(kicad_pcb
	(version 20260206)
	(generator "pcbnew")
	(generator_version "10.0")
	(general
		(thickness 1.6)
		(legacy_teardrops no)
	)
	(paper "A4")
	(layers
		(0 "F.Cu" signal "TOP")
		(4 "In1.Cu" signal "GND")
		(6 "In2.Cu" signal "IN1")
		(8 "In3.Cu" signal "GND1")
		(10 "In4.Cu" signal "IN2")
		(12 "In5.Cu" signal "GND2")
		(14 "In6.Cu" signal "IN3")
		(16 "In7.Cu" signal "GND3")
		(18 "In8.Cu" signal "VCC")
		(20 "In9.Cu" signal "VCC1")
		(22 "In10.Cu" signal "GND4")
		(24 "In11.Cu" signal "IN4")
		(26 "In12.Cu" signal "GND5")
		(28 "In13.Cu" signal "IN5")
		(30 "In14.Cu" signal "GND6")
		(32 "In15.Cu" signal "IN6")
		(34 "In16.Cu" signal "GND7")
		(2 "B.Cu" signal "BOTTOM")
		(9 "F.Adhes" user "F.Adhesive")
		(11 "B.Adhes" user "B.Adhesive")
		(13 "F.Paste" user "Package Geometry/Pastemask Top")
		(15 "B.Paste" user "Package Geometry/Pastemask Bottom")
		(5 "F.SilkS" user "Ref Des/Silkscreen Top")
		(7 "B.SilkS" user "Ref Des/Silkscreen Bottom")
		(1 "F.Mask" user "Board Geometry/Soldermask Top")
		(3 "B.Mask" user "Board Geometry/Soldermask Bottom")
		(17 "Dwgs.User" user "User.Drawings")
		(19 "Cmts.User" user "User.Comments")
		(21 "Eco1.User" user "User.Eco1")
		(23 "Eco2.User" user "User.Eco2")
		(25 "Edge.Cuts" user "Board Geometry/Outline")
		(27 "Margin" user)
		(31 "F.CrtYd" user "Package Geometry/Place Bound Top")
		(29 "B.CrtYd" user "Package Geometry/Place Bound Bottom")
		(35 "F.Fab" user "Ref Des/Assembly Top")
		(33 "B.Fab" user "Ref Des/Assembly Bottom")
	)
	(setup
		(pad_to_mask_clearance 0)
		(allow_soldermask_bridges_in_footprints no)
		(tenting
			(front yes)
			(back yes)
		)
		(covering
			(front no)
			(back no)
		)
		(plugging
			(front no)
			(back no)
		)
		(capping no)
		(filling no)
		(pcbplotparams
			(layerselection 0x00000000_00000000_55555555_5755f5ff)
			(plot_on_all_layers_selection 0x00000000_00000000_00000000_00000000)
			(disableapertmacros no)
			(usegerberextensions no)
			(usegerberattributes yes)
			(usegerberadvancedattributes yes)
			(creategerberjobfile yes)
			(dashed_line_dash_ratio 12)
			(dashed_line_gap_ratio 3)
			(svgprecision 4)
			(plotframeref no)
			(mode 1)
			(useauxorigin no)
			(pdf_front_fp_property_popups yes)
			(pdf_back_fp_property_popups yes)
			(pdf_metadata yes)
			(pdf_single_document no)
			(dxfpolygonmode yes)
			(dxfimperialunits yes)
			(dxfusepcbnewfont yes)
			(psnegative no)
			(psa4output no)
			(plot_black_and_white yes)
			(sketchpadsonfab no)
			(plotpadnumbers no)
			(hidednponfab no)
			(sketchdnponfab yes)
			(crossoutdnponfab yes)
			(subtractmaskfromsilk no)
			(outputformat 1)
			(mirror no)
			(drillshape 1)
			(scaleselection 1)
			(outputdirectory "")
		)
	)
	(gr_poly
		(pts
			(xy 102.494334 -267.735558) (xy 102.49634 -267.710864) (xy 102.506842 -267.662447) (xy 102.524496 -267.616156)
			(xy 102.5489 -267.573041) (xy 102.579502 -267.534079) (xy 102.615607 -267.500154) (xy 102.656397 -267.472035)
			(xy 102.700947 -267.45036) (xy 102.748246 -267.435621) (xy 102.797223 -267.428151) (xy 102.821994 -267.42771)
			(xy 102.844771 -267.428063) (xy 102.889893 -267.43431) (xy 102.91191 -267.440156) (xy 102.940612 -267.448284)
			(xy 104.158542 -266.230354) (xy 104.158542 -265.635994) (xy 104.124506 -265.62431) (xy 104.100664 -265.615551)
			(xy 104.055804 -265.591734) (xy 104.015149 -265.561291) (xy 103.979669 -265.524947) (xy 103.950212 -265.483572)
			(xy 103.927481 -265.438151) (xy 103.912019 -265.389772) (xy 103.904195 -265.339587) (xy 103.904196 -265.288797)
			(xy 103.912022 -265.238613) (xy 103.927487 -265.190234) (xy 103.95022 -265.144815) (xy 103.979679 -265.103441)
			(xy 104.01516 -265.067099) (xy 104.055817 -265.036657) (xy 104.100679 -265.012843) (xy 104.124506 -265.004042)
			(xy 104.158542 -264.992358) (xy 104.158542 -262.01751) (xy 104.15905 -261.995402) (xy 104.166757 -261.951861)
			(xy 104.181872 -261.910307) (xy 104.203939 -261.871989) (xy 104.217724 -261.854696) (xy 104.247442 -261.818882)
			(xy 104.111044 -261.682484) (xy 104.099727 -261.670367) (xy 104.083175 -261.641653) (xy 104.074572 -261.609646)
			(xy 104.07396 -261.593076) (xy 104.07396 -261.1628) (xy 104.074522 -261.146224) (xy 104.083128 -261.114207)
			(xy 104.099704 -261.085495) (xy 104.111044 -261.073392) (xy 104.501442 -260.682994) (xy 104.513555 -260.671666)
			(xy 104.542265 -260.65509) (xy 104.574276 -260.646466) (xy 104.59085 -260.64591) (xy 104.898698 -260.64591)
			(xy 104.913241 -260.645444) (xy 104.941149 -260.63725) (xy 104.965617 -260.621525) (xy 104.984664 -260.599542)
			(xy 104.996746 -260.573084) (xy 105.000884 -260.544294) (xy 104.999282 -260.529832) (xy 104.998079 -260.5208)
			(xy 104.996811 -260.502621) (xy 104.996742 -260.49351) (xy 104.996742 -257.093466) (xy 104.637586 -256.73431)
			(xy 103.672132 -256.73431) (xy 103.665274 -256.741422) (xy 103.345742 -257.060954) (xy 103.345742 -257.134868)
			(xy 103.345164 -257.159825) (xy 103.335412 -257.208778) (xy 103.316296 -257.254888) (xy 103.288551 -257.296382)
			(xy 103.27132 -257.314446) (xy 103.05288 -257.532886) (xy 103.05288 -258.060952) (xy 103.27132 -258.279392)
			(xy 103.288577 -258.297434) (xy 103.316329 -258.338928) (xy 103.335435 -258.385047) (xy 103.345159 -258.43401)
			(xy 103.345742 -258.45897) (xy 103.345742 -260.51891) (xy 103.34517 -260.54387) (xy 103.335427 -260.592829)
			(xy 103.316319 -260.638946) (xy 103.288579 -260.680448) (xy 103.27132 -260.698488) (xy 103.196136 -260.773672)
			(xy 103.197152 -260.796278) (xy 103.19766 -260.812534) (xy 103.197152 -260.83832) (xy 103.189079 -260.889255)
			(xy 103.173139 -260.938301) (xy 103.149722 -260.98425) (xy 103.119406 -261.025969) (xy 103.082937 -261.062434)
			(xy 103.041214 -261.092744) (xy 102.995262 -261.116155) (xy 102.946214 -261.132089) (xy 102.895278 -261.140155)
			(xy 102.869492 -261.140702) (xy 102.853236 -261.140194) (xy 102.83063 -261.139178) (xy 102.71252 -261.257288)
			(xy 102.694479 -261.274548) (xy 102.652986 -261.302305) (xy 102.606868 -261.321416) (xy 102.557903 -261.331144)
			(xy 102.532942 -261.33171) (xy 102.200456 -261.33171) (xy 102.18801 -261.363968) (xy 102.177999 -261.388246)
			(xy 102.15139 -261.433518) (xy 102.117912 -261.473975) (xy 102.078419 -261.508586) (xy 102.033919 -261.536466)
			(xy 101.985548 -261.556905) (xy 101.934539 -261.569381) (xy 101.882194 -261.573575) (xy 101.829849 -261.569381)
			(xy 101.77884 -261.556905) (xy 101.730469 -261.536466) (xy 101.685969 -261.508586) (xy 101.646476 -261.473975)
			(xy 101.612998 -261.433518) (xy 101.586389 -261.388246) (xy 101.576378 -261.363968) (xy 101.563932 -261.33171)
			(xy 101.260656 -261.33171) (xy 101.24821 -261.363968) (xy 101.238199 -261.388246) (xy 101.21159 -261.433518)
			(xy 101.178112 -261.473975) (xy 101.138619 -261.508586) (xy 101.094119 -261.536466) (xy 101.045748 -261.556905)
			(xy 100.994739 -261.569381) (xy 100.942394 -261.573575) (xy 100.890049 -261.569381) (xy 100.83904 -261.556905)
			(xy 100.790669 -261.536466) (xy 100.746169 -261.508586) (xy 100.706676 -261.473975) (xy 100.673198 -261.433518)
			(xy 100.646589 -261.388246) (xy 100.636578 -261.363968) (xy 100.624132 -261.33171) (xy 100.320856 -261.33171)
			(xy 100.30841 -261.363968) (xy 100.298399 -261.388246) (xy 100.27179 -261.433518) (xy 100.238312 -261.473975)
			(xy 100.198819 -261.508586) (xy 100.154319 -261.536466) (xy 100.105948 -261.556905) (xy 100.054939 -261.569381)
			(xy 100.002594 -261.573575) (xy 99.950249 -261.569381) (xy 99.89924 -261.556905) (xy 99.850869 -261.536466)
			(xy 99.806369 -261.508586) (xy 99.766876 -261.473975) (xy 99.733398 -261.433518) (xy 99.706789 -261.388246)
			(xy 99.696778 -261.363968) (xy 99.684332 -261.33171) (xy 99.381056 -261.33171) (xy 99.36861 -261.363968)
			(xy 99.358599 -261.388246) (xy 99.33199 -261.433518) (xy 99.298512 -261.473975) (xy 99.259019 -261.508586)
			(xy 99.214519 -261.536466) (xy 99.166148 -261.556905) (xy 99.115139 -261.569381) (xy 99.062794 -261.573575)
			(xy 99.010449 -261.569381) (xy 98.95944 -261.556905) (xy 98.911069 -261.536466) (xy 98.866569 -261.508586)
			(xy 98.827076 -261.473975) (xy 98.793598 -261.433518) (xy 98.766989 -261.388246) (xy 98.756978 -261.363968)
			(xy 98.744532 -261.33171) (xy 98.441256 -261.33171) (xy 98.42881 -261.363968) (xy 98.418799 -261.388246)
			(xy 98.39219 -261.433518) (xy 98.358712 -261.473975) (xy 98.319219 -261.508586) (xy 98.274719 -261.536466)
			(xy 98.226348 -261.556905) (xy 98.175339 -261.569381) (xy 98.122994 -261.573575) (xy 98.070649 -261.569381)
			(xy 98.01964 -261.556905) (xy 97.971269 -261.536466) (xy 97.926769 -261.508586) (xy 97.887276 -261.473975)
			(xy 97.853798 -261.433518) (xy 97.827189 -261.388246) (xy 97.817178 -261.363968) (xy 97.804732 -261.33171)
			(xy 97.501456 -261.33171) (xy 97.48901 -261.363968) (xy 97.479667 -261.386743) (xy 97.455149 -261.429429)
			(xy 97.424528 -261.467973) (xy 97.388493 -261.501509) (xy 97.347852 -261.529286) (xy 97.303517 -261.550679)
			(xy 97.256484 -261.565207) (xy 97.207807 -261.572546) (xy 97.183194 -261.57301) (xy 97.157406 -261.572504)
			(xy 97.106464 -261.564435) (xy 97.057411 -261.548498) (xy 97.011455 -261.525083) (xy 96.969727 -261.494769)
			(xy 96.933255 -261.4583) (xy 96.902935 -261.416576) (xy 96.879516 -261.370623) (xy 96.863573 -261.321571)
			(xy 96.855499 -261.27063) (xy 96.855026 -261.244842) (xy 96.855533 -261.218517) (xy 96.863896 -261.166535)
			(xy 96.880432 -261.116549) (xy 96.89211 -261.09295) (xy 96.909382 -261.05993) (xy 96.580706 -260.731254)
			(xy 96.572578 -260.727444) (xy 96.548896 -260.715613) (xy 96.505334 -260.685539) (xy 96.467157 -260.64887)
			(xy 96.435352 -260.606556) (xy 96.410741 -260.55969) (xy 96.393963 -260.509485) (xy 96.385449 -260.457239)
			(xy 96.384872 -260.430772) (xy 96.385353 -260.405326) (xy 96.393215 -260.355046) (xy 96.408745 -260.306582)
			(xy 96.431571 -260.261097) (xy 96.461147 -260.219681) (xy 96.478598 -260.201156) (xy 96.478598 -259.032248)
			(xy 96.461216 -259.013751) (xy 96.431791 -258.972396) (xy 96.409084 -258.927003) (xy 96.393637 -258.878656)
			(xy 96.385818 -258.828506) (xy 96.385813 -258.777751) (xy 96.393624 -258.7276) (xy 96.409062 -258.67925)
			(xy 96.431761 -258.633853) (xy 96.461179 -258.592493) (xy 96.478598 -258.574032) (xy 96.478598 -257.404362)
			(xy 96.461223 -257.385866) (xy 96.431811 -257.344512) (xy 96.409116 -257.299124) (xy 96.393681 -257.250782)
			(xy 96.385873 -257.20064) (xy 96.385878 -257.149894) (xy 96.393696 -257.099754) (xy 96.409141 -257.051415)
			(xy 96.431845 -257.006031) (xy 96.461265 -256.964684) (xy 96.478598 -256.946146) (xy 96.478598 -255.77673)
			(xy 96.461218 -255.758233) (xy 96.431795 -255.716879) (xy 96.409091 -255.671487) (xy 96.393646 -255.62314)
			(xy 96.385829 -255.572992) (xy 96.385827 -255.522239) (xy 96.393639 -255.47209) (xy 96.409079 -255.423743)
			(xy 96.431779 -255.378349) (xy 96.461197 -255.336991) (xy 96.478598 -255.318514) (xy 96.478598 -254.148844)
			(xy 96.461217 -254.130347) (xy 96.431792 -254.088992) (xy 96.409086 -254.0436) (xy 96.393639 -253.995252)
			(xy 96.38582 -253.945103) (xy 96.385816 -253.894348) (xy 96.393627 -253.844198) (xy 96.409066 -253.795848)
			(xy 96.431765 -253.750452) (xy 96.461183 -253.709092) (xy 96.478598 -253.690628) (xy 96.478598 -249.111262)
			(xy 96.45142 -249.097038) (xy 96.429016 -249.084767) (xy 96.387972 -249.05436) (xy 96.352134 -249.017963)
			(xy 96.322366 -248.976454) (xy 96.299388 -248.930835) (xy 96.283753 -248.882207) (xy 96.27584 -248.831744)
			(xy 96.27584 -248.780664) (xy 96.283752 -248.730201) (xy 96.299385 -248.681572) (xy 96.322362 -248.635952)
			(xy 96.352129 -248.594442) (xy 96.387967 -248.558044) (xy 96.42901 -248.527637) (xy 96.45142 -248.515378)
			(xy 96.478598 -248.501154) (xy 96.478598 -247.483376) (xy 96.45142 -247.469152) (xy 96.428998 -247.456894)
			(xy 96.387918 -247.426506) (xy 96.352045 -247.390118) (xy 96.322247 -247.348608) (xy 96.299243 -247.302981)
			(xy 96.283591 -247.254339) (xy 96.275668 -247.203859) (xy 96.275667 -247.152761) (xy 96.283586 -247.102281)
			(xy 96.299236 -247.053638) (xy 96.322236 -247.008009) (xy 96.352032 -246.966498) (xy 96.387903 -246.930107)
			(xy 96.428981 -246.899717) (xy 96.45142 -246.887492) (xy 96.478598 -246.873268) (xy 96.478598 -245.855744)
			(xy 96.45142 -245.84152) (xy 96.429017 -245.829249) (xy 96.387976 -245.798843) (xy 96.352141 -245.762447)
			(xy 96.322376 -245.720939) (xy 96.299399 -245.675321) (xy 96.283767 -245.626695) (xy 96.275856 -245.576234)
			(xy 96.275856 -245.525157) (xy 96.283769 -245.474696) (xy 96.299403 -245.42607) (xy 96.32238 -245.380453)
			(xy 96.352147 -245.338946) (xy 96.387983 -245.302551) (xy 96.429025 -245.272146) (xy 96.45142 -245.25986)
			(xy 96.478598 -245.245636) (xy 96.478598 -244.227858) (xy 96.45142 -244.213634) (xy 96.429016 -244.201363)
			(xy 96.387973 -244.170957) (xy 96.352135 -244.13456) (xy 96.322368 -244.093051) (xy 96.29939 -244.047432)
			(xy 96.283756 -243.998804) (xy 96.275844 -243.948341) (xy 96.275843 -243.897262) (xy 96.283755 -243.8468)
			(xy 96.299389 -243.798172) (xy 96.322366 -243.752552) (xy 96.352133 -243.711043) (xy 96.38797 -243.674646)
			(xy 96.429013 -243.644239) (xy 96.45142 -243.631974) (xy 96.478598 -243.61775) (xy 96.478598 -242.599972)
			(xy 96.45142 -242.585748) (xy 96.429015 -242.573477) (xy 96.38797 -242.54307) (xy 96.35213 -242.506673)
			(xy 96.322361 -242.465163) (xy 96.299381 -242.419542) (xy 96.283746 -242.370913) (xy 96.275832 -242.320449)
			(xy 96.27583 -242.269368) (xy 96.283742 -242.218903) (xy 96.299375 -242.170273) (xy 96.322352 -242.124652)
			(xy 96.352119 -242.08314) (xy 96.387957 -242.046741) (xy 96.429001 -242.016332) (xy 96.45142 -242.004088)
			(xy 96.478598 -241.989864) (xy 96.478598 -240.97234) (xy 96.45142 -240.958116) (xy 96.429018 -240.945845)
			(xy 96.387977 -240.915439) (xy 96.352142 -240.879043) (xy 96.322378 -240.837535) (xy 96.299402 -240.791918)
			(xy 96.28377 -240.743292) (xy 96.275859 -240.692832) (xy 96.27586 -240.641755) (xy 96.283773 -240.591295)
			(xy 96.299407 -240.54267) (xy 96.322384 -240.497054) (xy 96.352151 -240.455547) (xy 96.387987 -240.419152)
			(xy 96.429029 -240.388748) (xy 96.45142 -240.376456) (xy 96.478598 -240.362232) (xy 96.478598 -239.344454)
			(xy 96.45142 -239.33023) (xy 96.429017 -239.317959) (xy 96.387974 -239.287553) (xy 96.352137 -239.251156)
			(xy 96.32237 -239.209647) (xy 96.299393 -239.164029) (xy 96.283759 -239.115401) (xy 96.275847 -239.064939)
			(xy 96.275847 -239.013861) (xy 96.283759 -238.963399) (xy 96.299393 -238.914771) (xy 96.32237 -238.869153)
			(xy 96.352137 -238.827644) (xy 96.387974 -238.791247) (xy 96.429017 -238.760841) (xy 96.45142 -238.74857)
			(xy 96.478598 -238.734346) (xy 96.478598 -237.716568) (xy 96.45142 -237.702344) (xy 96.429016 -237.690073)
			(xy 96.387971 -237.659666) (xy 96.352132 -237.623269) (xy 96.322363 -237.581759) (xy 96.299384 -237.536139)
			(xy 96.283749 -237.487511) (xy 96.275835 -237.437047) (xy 96.275834 -237.385966) (xy 96.283746 -237.335502)
			(xy 96.299379 -237.286873) (xy 96.322356 -237.241252) (xy 96.352123 -237.199741) (xy 96.387961 -237.163342)
			(xy 96.429005 -237.132934) (xy 96.45142 -237.120684) (xy 96.478598 -237.10646) (xy 96.478598 -236.088936)
			(xy 96.45142 -236.074712) (xy 96.429018 -236.062441) (xy 96.387978 -236.032035) (xy 96.352144 -235.995639)
			(xy 96.32238 -235.954132) (xy 96.299404 -235.908515) (xy 96.283773 -235.85989) (xy 96.275862 -235.80943)
			(xy 96.275864 -235.758354) (xy 96.283777 -235.707894) (xy 96.299411 -235.65927) (xy 96.322388 -235.613654)
			(xy 96.352155 -235.572148) (xy 96.387991 -235.535754) (xy 96.429032 -235.50535) (xy 96.45142 -235.493052)
			(xy 96.478598 -235.478828) (xy 96.478598 -234.93857) (xy 96.479212 -234.913615) (xy 96.488955 -234.864664)
			(xy 96.508059 -234.818554) (xy 96.535792 -234.777057) (xy 96.55302 -234.758992) (xy 97.221548 -234.090464)
			(xy 97.22485 -234.076748) (xy 97.231451 -234.052238) (xy 97.251168 -234.005467) (xy 97.277848 -233.962287)
			(xy 97.310856 -233.923728) (xy 97.349405 -233.890708) (xy 97.392576 -233.864015) (xy 97.439341 -233.844283)
			(xy 97.463864 -233.837734) (xy 97.47758 -233.834432) (xy 97.758758 -233.553254) (xy 97.73666 -233.518964)
			(xy 97.724452 -233.499065) (xy 97.705171 -233.456551) (xy 97.692103 -233.411736) (xy 97.685511 -233.365521)
			(xy 97.685098 -233.34218) (xy 97.685605 -233.316392) (xy 97.693676 -233.265453) (xy 97.709615 -233.216402)
			(xy 97.73303 -233.170449) (xy 97.763345 -233.128724) (xy 97.799813 -233.092254) (xy 97.841537 -233.061937)
			(xy 97.887489 -233.03852) (xy 97.936539 -233.022579) (xy 97.987478 -233.014506) (xy 98.013266 -233.014012)
			(xy 98.03661 -233.014401) (xy 98.082831 -233.020978) (xy 98.127651 -233.034047) (xy 98.170164 -233.053343)
			(xy 98.19005 -233.065574) (xy 98.22434 -233.087672) (xy 99.565206 -231.746806) (xy 99.564698 -231.724708)
			(xy 99.564444 -231.714548) (xy 99.56492 -231.688756) (xy 99.572983 -231.637807) (xy 99.588917 -231.588746)
			(xy 99.612332 -231.542783) (xy 99.642649 -231.501049) (xy 99.679121 -231.464572) (xy 99.720852 -231.43425)
			(xy 99.766813 -231.410831) (xy 99.815872 -231.394891) (xy 99.86682 -231.386823) (xy 99.892612 -231.38638)
			(xy 99.902772 -231.386634) (xy 99.92487 -231.387142) (xy 101.931216 -229.380796) (xy 101.924104 -229.352856)
			(xy 101.919476 -229.333178) (xy 101.914507 -229.293059) (xy 101.914198 -229.272846) (xy 101.914674 -229.247053)
			(xy 101.922737 -229.196101) (xy 101.938671 -229.147038) (xy 101.962085 -229.101072) (xy 101.992401 -229.059334)
			(xy 102.028873 -229.022853) (xy 102.070603 -228.992526) (xy 102.116564 -228.969102) (xy 102.165623 -228.953155)
			(xy 102.216573 -228.94508) (xy 102.242366 -228.944678) (xy 102.26258 -228.944975) (xy 102.302701 -228.94994)
			(xy 102.322376 -228.954584) (xy 102.350316 -228.961696) (xy 102.429818 -228.882194) (xy 102.429818 -228.626924)
			(xy 102.423722 -228.615748) (xy 102.411171 -228.591553) (xy 102.393394 -228.54003) (xy 102.38438 -228.486278)
			(xy 102.384375 -228.431775) (xy 102.393381 -228.378021) (xy 102.411149 -228.326495) (xy 102.423722 -228.302312)
			(xy 102.429818 -228.291136) (xy 102.429818 -226.999038) (xy 102.423722 -226.987862) (xy 102.41117 -226.963667)
			(xy 102.393391 -226.912144) (xy 102.384374 -226.858391) (xy 102.384368 -226.803886) (xy 102.393372 -226.750131)
			(xy 102.411138 -226.698604) (xy 102.423722 -226.674426) (xy 102.429818 -226.66325) (xy 102.429818 -225.373946)
			(xy 102.423468 -225.362516) (xy 102.410549 -225.337978) (xy 102.392211 -225.285646) (xy 102.382889 -225.230983)
			(xy 102.38232 -225.203258) (xy 102.382911 -225.17554) (xy 102.392235 -225.120894) (xy 102.400862 -225.094546)
			(xy 102.408736 -225.072448) (xy 102.203758 -224.71761) (xy 102.180898 -224.713292) (xy 102.156095 -224.708095)
			(xy 102.108354 -224.691108) (xy 102.063773 -224.667016) (xy 102.023404 -224.636387) (xy 101.988196 -224.599942)
			(xy 101.958978 -224.55854) (xy 101.936439 -224.513155) (xy 101.921109 -224.464855) (xy 101.91335 -224.414779)
			(xy 101.912928 -224.389442) (xy 101.913406 -224.363549) (xy 101.921501 -224.312401) (xy 101.937497 -224.263148)
			(xy 101.961001 -224.217005) (xy 101.991435 -224.175106) (xy 102.028048 -224.138484) (xy 102.06994 -224.108041)
			(xy 102.116078 -224.084526) (xy 102.165327 -224.068518) (xy 102.216474 -224.060412) (xy 102.242366 -224.060004)
			(xy 102.258857 -224.060161) (xy 102.291685 -224.063338) (xy 102.307898 -224.066354) (xy 102.322715 -224.06883)
			(xy 102.35261 -224.066018) (xy 102.380396 -224.054639) (xy 102.403675 -224.035674) (xy 102.420436 -224.010761)
			(xy 102.429232 -223.982052) (xy 102.429818 -223.96704) (xy 102.429818 -223.743266) (xy 102.423722 -223.731836)
			(xy 102.411293 -223.70769) (xy 102.39365 -223.656333) (xy 102.38468 -223.602777) (xy 102.384098 -223.575626)
			(xy 102.384623 -223.548469) (xy 102.393568 -223.494897) (xy 102.411234 -223.443537) (xy 102.423722 -223.419416)
			(xy 102.429818 -223.407986) (xy 102.429818 -222.118428) (xy 102.423468 -222.106998) (xy 102.41055 -222.082459)
			(xy 102.392215 -222.030127) (xy 102.382896 -221.975465) (xy 102.38232 -221.94774) (xy 102.382913 -221.920023)
			(xy 102.392239 -221.865377) (xy 102.400862 -221.839028) (xy 102.408736 -221.81693) (xy 102.203758 -221.462092)
			(xy 102.180898 -221.457774) (xy 102.156096 -221.452577) (xy 102.108356 -221.435589) (xy 102.063777 -221.411497)
			(xy 102.023409 -221.380868) (xy 101.988203 -221.344423) (xy 101.958987 -221.30302) (xy 101.936451 -221.257635)
			(xy 101.921123 -221.209336) (xy 101.913367 -221.15926) (xy 101.912928 -221.133924) (xy 101.913418 -221.108253)
			(xy 101.921386 -221.057534) (xy 101.937131 -221.008666) (xy 101.960273 -220.962836) (xy 101.990249 -220.921154)
			(xy 102.007924 -220.90253) (xy 102.016926 -220.892782) (xy 102.030042 -220.869728) (xy 102.036776 -220.844073)
			(xy 102.036674 -220.817549) (xy 102.029743 -220.791947) (xy 102.016451 -220.768995) (xy 102.007416 -220.759274)
			(xy 101.88067 -220.632528) (xy 101.85273 -220.639386) (xy 101.83368 -220.643704) (xy 101.81082 -220.648022)
			(xy 101.605842 -221.003114) (xy 101.613716 -221.024958) (xy 101.622297 -221.051376) (xy 101.631497 -221.106152)
			(xy 101.632004 -221.133924) (xy 101.631496 -221.159811) (xy 101.623397 -221.210949) (xy 101.607398 -221.260189)
			(xy 101.583892 -221.306321) (xy 101.55346 -221.348208) (xy 101.51685 -221.384818) (xy 101.474963 -221.41525)
			(xy 101.428831 -221.438756) (xy 101.379591 -221.454755) (xy 101.328453 -221.462854) (xy 101.276679 -221.462854)
			(xy 101.225541 -221.454755) (xy 101.176301 -221.438756) (xy 101.130169 -221.41525) (xy 101.088282 -221.384818)
			(xy 101.051672 -221.348208) (xy 101.02124 -221.306321) (xy 100.997734 -221.260189) (xy 100.981735 -221.210949)
			(xy 100.973636 -221.159811) (xy 100.973128 -221.133924) (xy 100.97359 -221.108588) (xy 100.98134 -221.058511)
			(xy 100.996662 -221.01021) (xy 101.019194 -220.964822) (xy 101.048405 -220.923417) (xy 101.083609 -220.886969)
			(xy 101.123975 -220.856337) (xy 101.168553 -220.832242) (xy 101.216292 -220.815252) (xy 101.241098 -220.810074)
			(xy 101.263958 -220.805756) (xy 101.468936 -220.450664) (xy 101.461062 -220.42882) (xy 101.452419 -220.402411)
			(xy 101.443103 -220.347635) (xy 101.44252 -220.319854) (xy 101.442884 -220.299508) (xy 101.447983 -220.259136)
			(xy 101.45268 -220.239336) (xy 101.459538 -220.211396) (xy 100.714556 -219.466414) (xy 100.6973 -219.448372)
			(xy 100.669549 -219.406877) (xy 100.650444 -219.360759) (xy 100.640719 -219.311796) (xy 100.640134 -219.286836)
			(xy 100.640134 -218.959938) (xy 100.619248 -218.944349) (xy 100.582212 -218.907684) (xy 100.551412 -218.865645)
			(xy 100.527616 -218.81928) (xy 100.511419 -218.769746) (xy 100.503224 -218.71828) (xy 100.50272 -218.692222)
			(xy 100.503306 -218.664503) (xy 100.51262 -218.609853) (xy 100.521262 -218.58351) (xy 100.529136 -218.561412)
			(xy 100.324158 -218.206574) (xy 100.301298 -218.202256) (xy 100.276497 -218.197058) (xy 100.228758 -218.18007)
			(xy 100.18418 -218.155978) (xy 100.143814 -218.125348) (xy 100.10861 -218.088903) (xy 100.079396 -218.0475)
			(xy 100.056862 -218.002115) (xy 100.041537 -217.953817) (xy 100.033783 -217.903742) (xy 100.033328 -217.878406)
			(xy 100.033835 -217.852517) (xy 100.041934 -217.801377) (xy 100.057932 -217.752134) (xy 100.081436 -217.705999)
			(xy 100.111868 -217.664108) (xy 100.148478 -217.627494) (xy 100.190364 -217.597057) (xy 100.236497 -217.573547)
			(xy 100.285738 -217.557543) (xy 100.336877 -217.549438) (xy 100.362766 -217.548968) (xy 100.385834 -217.549363)
			(xy 100.431525 -217.555753) (xy 100.475889 -217.568415) (xy 100.497132 -217.577416) (xy 100.510548 -217.582841)
			(xy 100.53921 -217.586738) (xy 100.567814 -217.582443) (xy 100.594068 -217.570302) (xy 100.615865 -217.551287)
			(xy 100.631458 -217.526925) (xy 100.639596 -217.499168) (xy 100.640134 -217.484706) (xy 100.640134 -217.33002)
			(xy 100.619494 -217.314489) (xy 100.582909 -217.278024) (xy 100.552493 -217.236276) (xy 100.528997 -217.190276)
			(xy 100.513001 -217.141162) (xy 100.504901 -217.090148) (xy 100.504898 -217.038494) (xy 100.512991 -216.987479)
			(xy 100.52898 -216.938363) (xy 100.552471 -216.89236) (xy 100.582882 -216.850608) (xy 100.619461 -216.814139)
			(xy 100.640134 -216.798652) (xy 100.640134 -215.70442) (xy 100.619249 -215.688829) (xy 100.582214 -215.652162)
			(xy 100.551413 -215.610123) (xy 100.527613 -215.563759) (xy 100.511409 -215.514226) (xy 100.503205 -215.46276)
			(xy 100.503205 -215.410644) (xy 100.511408 -215.359179) (xy 100.527612 -215.309646) (xy 100.55141 -215.263281)
			(xy 100.582211 -215.221241) (xy 100.619246 -215.184574) (xy 100.640134 -215.168988) (xy 100.640134 -215.01608)
			(xy 100.639621 -215.00159) (xy 100.631477 -214.973778) (xy 100.615851 -214.949371) (xy 100.594001 -214.930335)
			(xy 100.567683 -214.918201) (xy 100.539017 -214.913945) (xy 100.51031 -214.91791) (xy 100.496878 -214.92337)
			(xy 100.475616 -214.932468) (xy 100.431178 -214.945274) (xy 100.385382 -214.951717) (xy 100.362258 -214.952072)
			(xy 100.336372 -214.951561) (xy 100.285238 -214.943457) (xy 100.236 -214.927454) (xy 100.189872 -214.903947)
			(xy 100.147988 -214.873515) (xy 100.11138 -214.836906) (xy 100.080948 -214.795021) (xy 100.057443 -214.748892)
			(xy 100.041441 -214.699655) (xy 100.033338 -214.64852) (xy 100.03282 -214.622634) (xy 100.033181 -214.599657)
			(xy 100.039493 -214.554141) (xy 100.052069 -214.509943) (xy 100.061014 -214.488776) (xy 100.07092 -214.466424)
			(xy 99.857306 -214.061294) (xy 99.833176 -214.056722) (xy 99.808255 -214.051631) (xy 99.760254 -214.034807)
			(xy 99.715406 -214.010813) (xy 99.674773 -213.980218) (xy 99.639318 -213.943748) (xy 99.609882 -213.902268)
			(xy 99.587163 -213.856761) (xy 99.571699 -213.808305) (xy 99.563858 -213.758049) (xy 99.563428 -213.732618)
			(xy 99.563936 -213.706731) (xy 99.572035 -213.655593) (xy 99.588034 -213.606353) (xy 99.61154 -213.560221)
			(xy 99.641972 -213.518334) (xy 99.678582 -213.481724) (xy 99.720469 -213.451292) (xy 99.766601 -213.427786)
			(xy 99.815841 -213.411787) (xy 99.866979 -213.403688) (xy 99.918753 -213.403688) (xy 99.969891 -213.411787)
			(xy 100.019131 -213.427786) (xy 100.065263 -213.451292) (xy 100.10715 -213.481724) (xy 100.14376 -213.518334)
			(xy 100.174192 -213.560221) (xy 100.197698 -213.606353) (xy 100.213697 -213.655593) (xy 100.221796 -213.706731)
			(xy 100.222304 -213.732618) (xy 100.221939 -213.755594) (xy 100.215621 -213.801108) (xy 100.20304 -213.845303)
			(xy 100.19411 -213.866476) (xy 100.184204 -213.888828) (xy 100.397818 -214.293958) (xy 100.421948 -214.29853)
			(xy 100.441244 -214.302388) (xy 100.478811 -214.314102) (xy 100.496878 -214.321898) (xy 100.510306 -214.327368)
			(xy 100.539014 -214.331335) (xy 100.56768 -214.327079) (xy 100.593997 -214.314943) (xy 100.615846 -214.295903)
			(xy 100.631468 -214.271493) (xy 100.639605 -214.243678) (xy 100.640134 -214.229188) (xy 100.640134 -213.998302)
			(xy 100.619495 -213.982774) (xy 100.582917 -213.946314) (xy 100.55251 -213.904567) (xy 100.529029 -213.858567)
			(xy 100.513053 -213.809453) (xy 100.50498 -213.758442) (xy 100.504498 -213.732618) (xy 100.504928 -213.708732)
			(xy 100.511856 -213.661464) (xy 100.525567 -213.615701) (xy 100.545772 -213.572411) (xy 100.572044 -213.532511)
			(xy 100.603826 -213.496843) (xy 100.621846 -213.481158) (xy 100.640134 -213.465918) (xy 100.640134 -213.38286)
			(xy 90.686382 -207.382872) (xy 90.658696 -207.417416) (xy 90.616807 -207.468784) (xy 90.527782 -207.567004)
			(xy 90.433063 -207.659746) (xy 90.332988 -207.746679) (xy 90.22791 -207.827496) (xy 90.118204 -207.901909)
			(xy 90.00426 -207.969653) (xy 89.886482 -208.030488) (xy 89.765288 -208.084198) (xy 89.64111 -208.130592)
			(xy 89.514389 -208.169505) (xy 89.385574 -208.200799) (xy 89.255123 -208.224363) (xy 89.1235 -208.240112)
			(xy 88.991173 -208.247992) (xy 88.924892 -208.248504) (xy 88.85772 -208.248007) (xy 88.72362 -208.239895)
			(xy 88.590255 -208.223701) (xy 88.458112 -208.199484) (xy 88.327671 -208.167333) (xy 88.19941 -208.127364)
			(xy 88.073796 -208.079724) (xy 87.951287 -208.024587) (xy 87.832331 -207.962154) (xy 87.717362 -207.892652)
			(xy 87.606799 -207.816335) (xy 87.501045 -207.733482) (xy 87.400487 -207.644394) (xy 87.305492 -207.549398)
			(xy 87.216406 -207.448839) (xy 87.133553 -207.343085) (xy 87.057237 -207.232521) (xy 86.987736 -207.117552)
			(xy 86.925304 -206.998595) (xy 86.870168 -206.876086) (xy 86.822529 -206.750471) (xy 86.782562 -206.62221)
			(xy 86.750412 -206.491769) (xy 86.726196 -206.359625) (xy 86.710004 -206.22626) (xy 86.701893 -206.09216)
			(xy 86.701376 -206.024988) (xy 86.701855 -205.959707) (xy 86.709517 -205.829369) (xy 86.724813 -205.699706)
			(xy 86.74769 -205.571163) (xy 86.778071 -205.444185) (xy 86.815849 -205.319207) (xy 86.860896 -205.196662)
			(xy 86.913056 -205.076971) (xy 86.972148 -204.960546) (xy 87.037971 -204.84779) (xy 87.110295 -204.73909)
			(xy 87.188873 -204.634821) (xy 87.273434 -204.535342) (xy 87.363686 -204.440996) (xy 87.459319 -204.352108)
			(xy 87.560002 -204.268985) (xy 87.665389 -204.191913) (xy 87.775116 -204.121157) (xy 87.888807 -204.056961)
			(xy 88.006068 -203.999547) (xy 88.066118 -203.973938) (xy 88.107012 -203.956666) (xy 86.495128 -197.951598)
			(xy 86.486746 -197.942454) (xy 86.469443 -197.922794) (xy 86.440226 -197.879329) (xy 86.417738 -197.832031)
			(xy 86.40247 -197.781934) (xy 86.394755 -197.730134) (xy 86.39429 -197.703948) (xy 86.394529 -197.684874)
			(xy 86.398597 -197.646945) (xy 86.402418 -197.628256) (xy 86.405212 -197.616064) (xy 85.700616 -194.991482)
			(xy 76.85659 -175.174656) (xy 74.874882 -173.192948) (xy 68.072 -173.192948) (xy 68.04704 -173.192377)
			(xy 67.998079 -173.182636) (xy 67.951961 -173.163529) (xy 67.910457 -173.13579) (xy 67.892422 -173.118526)
			(xy 65.579244 -170.805348) (xy 61.877956 -170.805348) (xy 61.39434 -171.288964) (xy 61.39434 -213.732618)
			(xy 90.165428 -213.732618) (xy 90.165936 -213.706731) (xy 90.174035 -213.655593) (xy 90.190034 -213.606353)
			(xy 90.21354 -213.560221) (xy 90.243972 -213.518334) (xy 90.280582 -213.481724) (xy 90.322469 -213.451292)
			(xy 90.368601 -213.427786) (xy 90.417841 -213.411787) (xy 90.468979 -213.403688) (xy 90.520753 -213.403688)
			(xy 90.571891 -213.411787) (xy 90.621131 -213.427786) (xy 90.667263 -213.451292) (xy 90.70915 -213.481724)
			(xy 90.74576 -213.518334) (xy 90.776192 -213.560221) (xy 90.799698 -213.606353) (xy 90.815697 -213.655593)
			(xy 90.823796 -213.706731) (xy 90.824304 -213.732618) (xy 92.045028 -213.732618) (xy 92.045536 -213.706731)
			(xy 92.053635 -213.655593) (xy 92.069634 -213.606353) (xy 92.09314 -213.560221) (xy 92.123572 -213.518334)
			(xy 92.160182 -213.481724) (xy 92.202069 -213.451292) (xy 92.248201 -213.427786) (xy 92.297441 -213.411787)
			(xy 92.348579 -213.403688) (xy 92.400353 -213.403688) (xy 92.451491 -213.411787) (xy 92.500731 -213.427786)
			(xy 92.546863 -213.451292) (xy 92.58875 -213.481724) (xy 92.62536 -213.518334) (xy 92.655792 -213.560221)
			(xy 92.679298 -213.606353) (xy 92.695297 -213.655593) (xy 92.703396 -213.706731) (xy 92.703904 -213.732618)
			(xy 93.924628 -213.732618) (xy 93.925136 -213.706731) (xy 93.933235 -213.655593) (xy 93.949234 -213.606353)
			(xy 93.97274 -213.560221) (xy 94.003172 -213.518334) (xy 94.039782 -213.481724) (xy 94.081669 -213.451292)
			(xy 94.127801 -213.427786) (xy 94.177041 -213.411787) (xy 94.228179 -213.403688) (xy 94.279953 -213.403688)
			(xy 94.331091 -213.411787) (xy 94.380331 -213.427786) (xy 94.426463 -213.451292) (xy 94.46835 -213.481724)
			(xy 94.50496 -213.518334) (xy 94.535392 -213.560221) (xy 94.558898 -213.606353) (xy 94.574897 -213.655593)
			(xy 94.582996 -213.706731) (xy 94.583504 -213.732618) (xy 95.804228 -213.732618) (xy 95.804736 -213.706731)
			(xy 95.812835 -213.655593) (xy 95.828834 -213.606353) (xy 95.85234 -213.560221) (xy 95.882772 -213.518334)
			(xy 95.919382 -213.481724) (xy 95.961269 -213.451292) (xy 96.007401 -213.427786) (xy 96.056641 -213.411787)
			(xy 96.107779 -213.403688) (xy 96.159553 -213.403688) (xy 96.210691 -213.411787) (xy 96.259931 -213.427786)
			(xy 96.306063 -213.451292) (xy 96.34795 -213.481724) (xy 96.38456 -213.518334) (xy 96.414992 -213.560221)
			(xy 96.438498 -213.606353) (xy 96.454497 -213.655593) (xy 96.462596 -213.706731) (xy 96.463104 -213.732618)
			(xy 97.683828 -213.732618) (xy 97.684336 -213.706731) (xy 97.692435 -213.655593) (xy 97.708434 -213.606353)
			(xy 97.73194 -213.560221) (xy 97.762372 -213.518334) (xy 97.798982 -213.481724) (xy 97.840869 -213.451292)
			(xy 97.887001 -213.427786) (xy 97.936241 -213.411787) (xy 97.987379 -213.403688) (xy 98.039153 -213.403688)
			(xy 98.090291 -213.411787) (xy 98.139531 -213.427786) (xy 98.185663 -213.451292) (xy 98.22755 -213.481724)
			(xy 98.26416 -213.518334) (xy 98.294592 -213.560221) (xy 98.318098 -213.606353) (xy 98.334097 -213.655593)
			(xy 98.342196 -213.706731) (xy 98.342704 -213.732618) (xy 98.342353 -213.755595) (xy 98.336032 -213.80111)
			(xy 98.323448 -213.845306) (xy 98.31451 -213.866476) (xy 98.304604 -213.888828) (xy 98.518218 -214.293958)
			(xy 98.542348 -214.29853) (xy 98.567267 -214.303641) (xy 98.615277 -214.320441) (xy 98.660136 -214.344419)
			(xy 98.700776 -214.375006) (xy 98.736234 -214.411476) (xy 98.765666 -214.452961) (xy 98.788373 -214.498476)
			(xy 98.803815 -214.54694) (xy 98.811627 -214.597201) (xy 98.812096 -214.622634) (xy 98.811588 -214.648521)
			(xy 98.803489 -214.699659) (xy 98.78749 -214.748899) (xy 98.763984 -214.795031) (xy 98.733552 -214.836918)
			(xy 98.696942 -214.873528) (xy 98.655055 -214.90396) (xy 98.608923 -214.927466) (xy 98.559683 -214.943465)
			(xy 98.508545 -214.951564) (xy 98.456771 -214.951564) (xy 98.405633 -214.943465) (xy 98.356393 -214.927466)
			(xy 98.310261 -214.90396) (xy 98.268374 -214.873528) (xy 98.231764 -214.836918) (xy 98.201332 -214.795031)
			(xy 98.177826 -214.748899) (xy 98.161827 -214.699659) (xy 98.153728 -214.648521) (xy 98.15322 -214.622634)
			(xy 98.153587 -214.599658) (xy 98.1599 -214.554143) (xy 98.172479 -214.509947) (xy 98.181414 -214.488776)
			(xy 98.19132 -214.466424) (xy 97.977706 -214.061294) (xy 97.953576 -214.056722) (xy 97.92865 -214.051639)
			(xy 97.880636 -214.034839) (xy 97.835775 -214.010859) (xy 97.795132 -213.980269) (xy 97.759674 -213.943796)
			(xy 97.730243 -213.902307) (xy 97.707538 -213.856787) (xy 97.6921 -213.808318) (xy 97.684294 -213.758052)
			(xy 97.683828 -213.732618) (xy 96.463104 -213.732618) (xy 96.462753 -213.755595) (xy 96.456432 -213.80111)
			(xy 96.443848 -213.845306) (xy 96.43491 -213.866476) (xy 96.425004 -213.888828) (xy 96.638618 -214.293958)
			(xy 96.662748 -214.29853) (xy 96.687667 -214.303641) (xy 96.735677 -214.320441) (xy 96.780536 -214.344419)
			(xy 96.821176 -214.375006) (xy 96.856634 -214.411476) (xy 96.886066 -214.452961) (xy 96.908773 -214.498476)
			(xy 96.924215 -214.54694) (xy 96.932027 -214.597201) (xy 96.932496 -214.622634) (xy 96.931988 -214.648521)
			(xy 96.923889 -214.699659) (xy 96.90789 -214.748899) (xy 96.884384 -214.795031) (xy 96.853952 -214.836918)
			(xy 96.817342 -214.873528) (xy 96.775455 -214.90396) (xy 96.729323 -214.927466) (xy 96.680083 -214.943465)
			(xy 96.628945 -214.951564) (xy 96.577171 -214.951564) (xy 96.526033 -214.943465) (xy 96.476793 -214.927466)
			(xy 96.430661 -214.90396) (xy 96.388774 -214.873528) (xy 96.352164 -214.836918) (xy 96.321732 -214.795031)
			(xy 96.298226 -214.748899) (xy 96.282227 -214.699659) (xy 96.274128 -214.648521) (xy 96.27362 -214.622634)
			(xy 96.273987 -214.599658) (xy 96.2803 -214.554143) (xy 96.292879 -214.509947) (xy 96.301814 -214.488776)
			(xy 96.31172 -214.466424) (xy 96.098106 -214.061294) (xy 96.073976 -214.056722) (xy 96.04905 -214.051639)
			(xy 96.001036 -214.034839) (xy 95.956175 -214.010859) (xy 95.915532 -213.980269) (xy 95.880074 -213.943796)
			(xy 95.850643 -213.902307) (xy 95.827938 -213.856787) (xy 95.8125 -213.808318) (xy 95.804694 -213.758052)
			(xy 95.804228 -213.732618) (xy 94.583504 -213.732618) (xy 94.583153 -213.755595) (xy 94.576832 -213.80111)
			(xy 94.564248 -213.845306) (xy 94.55531 -213.866476) (xy 94.545404 -213.888828) (xy 94.759018 -214.293958)
			(xy 94.783148 -214.29853) (xy 94.808067 -214.303641) (xy 94.856077 -214.320441) (xy 94.900936 -214.344419)
			(xy 94.941576 -214.375006) (xy 94.977034 -214.411476) (xy 95.006466 -214.452961) (xy 95.029173 -214.498476)
			(xy 95.044615 -214.54694) (xy 95.052427 -214.597201) (xy 95.052896 -214.622634) (xy 95.052388 -214.648521)
			(xy 95.044289 -214.699659) (xy 95.02829 -214.748899) (xy 95.004784 -214.795031) (xy 94.974352 -214.836918)
			(xy 94.937742 -214.873528) (xy 94.895855 -214.90396) (xy 94.849723 -214.927466) (xy 94.800483 -214.943465)
			(xy 94.749345 -214.951564) (xy 94.697571 -214.951564) (xy 94.646433 -214.943465) (xy 94.597193 -214.927466)
			(xy 94.551061 -214.90396) (xy 94.509174 -214.873528) (xy 94.472564 -214.836918) (xy 94.442132 -214.795031)
			(xy 94.418626 -214.748899) (xy 94.402627 -214.699659) (xy 94.394528 -214.648521) (xy 94.39402 -214.622634)
			(xy 94.394387 -214.599658) (xy 94.4007 -214.554143) (xy 94.413279 -214.509947) (xy 94.422214 -214.488776)
			(xy 94.43212 -214.466424) (xy 94.218506 -214.061294) (xy 94.194376 -214.056722) (xy 94.16945 -214.051639)
			(xy 94.121436 -214.034839) (xy 94.076575 -214.010859) (xy 94.035932 -213.980269) (xy 94.000474 -213.943796)
			(xy 93.971043 -213.902307) (xy 93.948338 -213.856787) (xy 93.9329 -213.808318) (xy 93.925094 -213.758052)
			(xy 93.924628 -213.732618) (xy 92.703904 -213.732618) (xy 92.703553 -213.755595) (xy 92.697232 -213.80111)
			(xy 92.684648 -213.845306) (xy 92.67571 -213.866476) (xy 92.665804 -213.888828) (xy 92.879418 -214.293958)
			(xy 92.903548 -214.29853) (xy 92.928467 -214.303641) (xy 92.976477 -214.320441) (xy 93.021336 -214.344419)
			(xy 93.061976 -214.375006) (xy 93.097434 -214.411476) (xy 93.126866 -214.452961) (xy 93.149573 -214.498476)
			(xy 93.165015 -214.54694) (xy 93.172827 -214.597201) (xy 93.173296 -214.622634) (xy 93.172788 -214.648521)
			(xy 93.164689 -214.699659) (xy 93.14869 -214.748899) (xy 93.125184 -214.795031) (xy 93.094752 -214.836918)
			(xy 93.058142 -214.873528) (xy 93.016255 -214.90396) (xy 92.970123 -214.927466) (xy 92.920883 -214.943465)
			(xy 92.869745 -214.951564) (xy 92.817971 -214.951564) (xy 92.766833 -214.943465) (xy 92.717593 -214.927466)
			(xy 92.671461 -214.90396) (xy 92.629574 -214.873528) (xy 92.592964 -214.836918) (xy 92.562532 -214.795031)
			(xy 92.539026 -214.748899) (xy 92.523027 -214.699659) (xy 92.514928 -214.648521) (xy 92.51442 -214.622634)
			(xy 92.514787 -214.599658) (xy 92.5211 -214.554143) (xy 92.533679 -214.509947) (xy 92.542614 -214.488776)
			(xy 92.55252 -214.466424) (xy 92.338906 -214.061294) (xy 92.314776 -214.056722) (xy 92.28985 -214.051639)
			(xy 92.241836 -214.034839) (xy 92.196975 -214.010859) (xy 92.156332 -213.980269) (xy 92.120874 -213.943796)
			(xy 92.091443 -213.902307) (xy 92.068738 -213.856787) (xy 92.0533 -213.808318) (xy 92.045494 -213.758052)
			(xy 92.045028 -213.732618) (xy 90.824304 -213.732618) (xy 90.823953 -213.755595) (xy 90.817632 -213.80111)
			(xy 90.805048 -213.845306) (xy 90.79611 -213.866476) (xy 90.786204 -213.888828) (xy 90.999818 -214.293958)
			(xy 91.023948 -214.29853) (xy 91.048867 -214.303641) (xy 91.096877 -214.320441) (xy 91.141736 -214.344419)
			(xy 91.182376 -214.375006) (xy 91.217834 -214.411476) (xy 91.247266 -214.452961) (xy 91.269973 -214.498476)
			(xy 91.285415 -214.54694) (xy 91.293227 -214.597201) (xy 91.293696 -214.622634) (xy 91.293188 -214.648521)
			(xy 91.285089 -214.699659) (xy 91.26909 -214.748899) (xy 91.245584 -214.795031) (xy 91.215152 -214.836918)
			(xy 91.178542 -214.873528) (xy 91.136655 -214.90396) (xy 91.090523 -214.927466) (xy 91.041283 -214.943465)
			(xy 90.990145 -214.951564) (xy 90.938371 -214.951564) (xy 90.887233 -214.943465) (xy 90.837993 -214.927466)
			(xy 90.791861 -214.90396) (xy 90.749974 -214.873528) (xy 90.713364 -214.836918) (xy 90.682932 -214.795031)
			(xy 90.659426 -214.748899) (xy 90.643427 -214.699659) (xy 90.635328 -214.648521) (xy 90.63482 -214.622634)
			(xy 90.635187 -214.599658) (xy 90.6415 -214.554143) (xy 90.654079 -214.509947) (xy 90.663014 -214.488776)
			(xy 90.67292 -214.466424) (xy 90.459306 -214.061294) (xy 90.435176 -214.056722) (xy 90.41025 -214.051639)
			(xy 90.362236 -214.034839) (xy 90.317375 -214.010859) (xy 90.276732 -213.980269) (xy 90.241274 -213.943796)
			(xy 90.211843 -213.902307) (xy 90.189138 -213.856787) (xy 90.1737 -213.808318) (xy 90.165894 -213.758052)
			(xy 90.165428 -213.732618) (xy 61.39434 -213.732618) (xy 61.39434 -215.436704) (xy 88.28532 -215.436704)
			(xy 88.285828 -215.410797) (xy 88.293934 -215.35962) (xy 88.309946 -215.310341) (xy 88.333469 -215.264174)
			(xy 88.363925 -215.222255) (xy 88.400563 -215.185617) (xy 88.442482 -215.155161) (xy 88.488649 -215.131638)
			(xy 88.537928 -215.115626) (xy 88.589105 -215.10752) (xy 88.640919 -215.10752) (xy 88.692096 -215.115626)
			(xy 88.741375 -215.131638) (xy 88.787542 -215.155161) (xy 88.829461 -215.185617) (xy 88.866099 -215.222255)
			(xy 88.896555 -215.264174) (xy 88.920078 -215.310341) (xy 88.93609 -215.35962) (xy 88.944196 -215.410797)
			(xy 88.944704 -215.436704) (xy 89.22512 -215.436704) (xy 89.225629 -215.41136) (xy 89.2334 -215.36127)
			(xy 89.248746 -215.31296) (xy 89.271303 -215.267567) (xy 89.300542 -215.226161) (xy 89.335773 -215.189717)
			(xy 89.376165 -215.159094) (xy 89.420769 -215.135013) (xy 89.468532 -215.118041) (xy 89.493344 -215.112854)
			(xy 89.516204 -215.108536) (xy 89.721182 -214.753444) (xy 89.713308 -214.7316) (xy 89.704729 -214.705181)
			(xy 89.695532 -214.650406) (xy 89.69502 -214.622634) (xy 89.695528 -214.596747) (xy 89.703627 -214.545609)
			(xy 89.719626 -214.496369) (xy 89.743132 -214.450237) (xy 89.773564 -214.40835) (xy 89.810174 -214.37174)
			(xy 89.852061 -214.341308) (xy 89.898193 -214.317802) (xy 89.947433 -214.301803) (xy 89.998571 -214.293704)
			(xy 90.050345 -214.293704) (xy 90.101483 -214.301803) (xy 90.150723 -214.317802) (xy 90.196855 -214.341308)
			(xy 90.238742 -214.37174) (xy 90.275352 -214.40835) (xy 90.305784 -214.450237) (xy 90.32929 -214.496369)
			(xy 90.345289 -214.545609) (xy 90.353388 -214.596747) (xy 90.353896 -214.622634) (xy 90.353447 -214.64797)
			(xy 90.34569 -214.698044) (xy 90.330363 -214.746341) (xy 90.307827 -214.791726) (xy 90.278612 -214.833128)
			(xy 90.243408 -214.869572) (xy 90.203042 -214.900202) (xy 90.158465 -214.924296) (xy 90.110727 -214.941286)
			(xy 90.085926 -214.946484) (xy 90.063066 -214.950802) (xy 89.858088 -215.305894) (xy 89.865962 -215.327738)
			(xy 89.87461 -215.354146) (xy 89.883929 -215.408922) (xy 89.884504 -215.436704) (xy 91.10472 -215.436704)
			(xy 91.105229 -215.41136) (xy 91.113 -215.36127) (xy 91.128346 -215.31296) (xy 91.150903 -215.267567)
			(xy 91.180142 -215.226161) (xy 91.215373 -215.189717) (xy 91.255765 -215.159094) (xy 91.300369 -215.135013)
			(xy 91.348132 -215.118041) (xy 91.372944 -215.112854) (xy 91.395804 -215.108536) (xy 91.600782 -214.753444)
			(xy 91.592908 -214.7316) (xy 91.584329 -214.705181) (xy 91.575132 -214.650406) (xy 91.57462 -214.622634)
			(xy 91.575128 -214.596747) (xy 91.583227 -214.545609) (xy 91.599226 -214.496369) (xy 91.622732 -214.450237)
			(xy 91.653164 -214.40835) (xy 91.689774 -214.37174) (xy 91.731661 -214.341308) (xy 91.777793 -214.317802)
			(xy 91.827033 -214.301803) (xy 91.878171 -214.293704) (xy 91.929945 -214.293704) (xy 91.981083 -214.301803)
			(xy 92.030323 -214.317802) (xy 92.076455 -214.341308) (xy 92.118342 -214.37174) (xy 92.154952 -214.40835)
			(xy 92.185384 -214.450237) (xy 92.20889 -214.496369) (xy 92.224889 -214.545609) (xy 92.232988 -214.596747)
			(xy 92.233496 -214.622634) (xy 92.233047 -214.64797) (xy 92.22529 -214.698044) (xy 92.209963 -214.746341)
			(xy 92.187427 -214.791726) (xy 92.158212 -214.833128) (xy 92.123008 -214.869572) (xy 92.082642 -214.900202)
			(xy 92.038065 -214.924296) (xy 91.990327 -214.941286) (xy 91.965526 -214.946484) (xy 91.942666 -214.950802)
			(xy 91.737688 -215.305894) (xy 91.745562 -215.327738) (xy 91.75421 -215.354146) (xy 91.763529 -215.408922)
			(xy 91.764104 -215.436704) (xy 92.98432 -215.436704) (xy 92.984829 -215.41136) (xy 92.9926 -215.36127)
			(xy 93.007946 -215.31296) (xy 93.030503 -215.267567) (xy 93.059742 -215.226161) (xy 93.094973 -215.189717)
			(xy 93.135365 -215.159094) (xy 93.179969 -215.135013) (xy 93.227732 -215.118041) (xy 93.252544 -215.112854)
			(xy 93.275404 -215.108536) (xy 93.480382 -214.753444) (xy 93.472508 -214.7316) (xy 93.463929 -214.705181)
			(xy 93.454732 -214.650406) (xy 93.45422 -214.622634) (xy 93.454728 -214.596747) (xy 93.462827 -214.545609)
			(xy 93.478826 -214.496369) (xy 93.502332 -214.450237) (xy 93.532764 -214.40835) (xy 93.569374 -214.37174)
			(xy 93.611261 -214.341308) (xy 93.657393 -214.317802) (xy 93.706633 -214.301803) (xy 93.757771 -214.293704)
			(xy 93.809545 -214.293704) (xy 93.860683 -214.301803) (xy 93.909923 -214.317802) (xy 93.956055 -214.341308)
			(xy 93.997942 -214.37174) (xy 94.034552 -214.40835) (xy 94.064984 -214.450237) (xy 94.08849 -214.496369)
			(xy 94.104489 -214.545609) (xy 94.112588 -214.596747) (xy 94.113096 -214.622634) (xy 94.112647 -214.64797)
			(xy 94.10489 -214.698044) (xy 94.089563 -214.746341) (xy 94.067027 -214.791726) (xy 94.037812 -214.833128)
			(xy 94.002608 -214.869572) (xy 93.962242 -214.900202) (xy 93.917665 -214.924296) (xy 93.869927 -214.941286)
			(xy 93.845126 -214.946484) (xy 93.822266 -214.950802) (xy 93.617288 -215.305894) (xy 93.625162 -215.327738)
			(xy 93.63381 -215.354146) (xy 93.643129 -215.408922) (xy 93.643704 -215.436704) (xy 94.86392 -215.436704)
			(xy 94.864429 -215.41136) (xy 94.8722 -215.36127) (xy 94.887546 -215.31296) (xy 94.910103 -215.267567)
			(xy 94.939342 -215.226161) (xy 94.974573 -215.189717) (xy 95.014965 -215.159094) (xy 95.059569 -215.135013)
			(xy 95.107332 -215.118041) (xy 95.132144 -215.112854) (xy 95.155004 -215.108536) (xy 95.359982 -214.753444)
			(xy 95.352108 -214.7316) (xy 95.343529 -214.705181) (xy 95.334332 -214.650406) (xy 95.33382 -214.622634)
			(xy 95.334328 -214.596747) (xy 95.342427 -214.545609) (xy 95.358426 -214.496369) (xy 95.381932 -214.450237)
			(xy 95.412364 -214.40835) (xy 95.448974 -214.37174) (xy 95.490861 -214.341308) (xy 95.536993 -214.317802)
			(xy 95.586233 -214.301803) (xy 95.637371 -214.293704) (xy 95.689145 -214.293704) (xy 95.740283 -214.301803)
			(xy 95.789523 -214.317802) (xy 95.835655 -214.341308) (xy 95.877542 -214.37174) (xy 95.914152 -214.40835)
			(xy 95.944584 -214.450237) (xy 95.96809 -214.496369) (xy 95.984089 -214.545609) (xy 95.992188 -214.596747)
			(xy 95.992696 -214.622634) (xy 95.992247 -214.64797) (xy 95.98449 -214.698044) (xy 95.969163 -214.746341)
			(xy 95.946627 -214.791726) (xy 95.917412 -214.833128) (xy 95.882208 -214.869572) (xy 95.841842 -214.900202)
			(xy 95.797265 -214.924296) (xy 95.749527 -214.941286) (xy 95.724726 -214.946484) (xy 95.701866 -214.950802)
			(xy 95.496888 -215.305894) (xy 95.504762 -215.327738) (xy 95.51341 -215.354146) (xy 95.522729 -215.408922)
			(xy 95.523304 -215.436704) (xy 96.74352 -215.436704) (xy 96.744029 -215.41136) (xy 96.7518 -215.36127)
			(xy 96.767146 -215.31296) (xy 96.789703 -215.267567) (xy 96.818942 -215.226161) (xy 96.854173 -215.189717)
			(xy 96.894565 -215.159094) (xy 96.939169 -215.135013) (xy 96.986932 -215.118041) (xy 97.011744 -215.112854)
			(xy 97.034604 -215.108536) (xy 97.239582 -214.753444) (xy 97.231708 -214.7316) (xy 97.223129 -214.705181)
			(xy 97.213932 -214.650406) (xy 97.21342 -214.622634) (xy 97.213928 -214.596747) (xy 97.222027 -214.545609)
			(xy 97.238026 -214.496369) (xy 97.261532 -214.450237) (xy 97.291964 -214.40835) (xy 97.328574 -214.37174)
			(xy 97.370461 -214.341308) (xy 97.416593 -214.317802) (xy 97.465833 -214.301803) (xy 97.516971 -214.293704)
			(xy 97.568745 -214.293704) (xy 97.619883 -214.301803) (xy 97.669123 -214.317802) (xy 97.715255 -214.341308)
			(xy 97.757142 -214.37174) (xy 97.793752 -214.40835) (xy 97.824184 -214.450237) (xy 97.84769 -214.496369)
			(xy 97.863689 -214.545609) (xy 97.871788 -214.596747) (xy 97.872296 -214.622634) (xy 97.871847 -214.64797)
			(xy 97.86409 -214.698044) (xy 97.848763 -214.746341) (xy 97.826227 -214.791726) (xy 97.797012 -214.833128)
			(xy 97.761808 -214.869572) (xy 97.721442 -214.900202) (xy 97.676865 -214.924296) (xy 97.629127 -214.941286)
			(xy 97.604326 -214.946484) (xy 97.581466 -214.950802) (xy 97.376488 -215.305894) (xy 97.384362 -215.327738)
			(xy 97.39301 -215.354146) (xy 97.402329 -215.408922) (xy 97.402904 -215.436704) (xy 98.62312 -215.436704)
			(xy 98.623629 -215.41136) (xy 98.6314 -215.36127) (xy 98.646746 -215.31296) (xy 98.669303 -215.267567)
			(xy 98.698542 -215.226161) (xy 98.733773 -215.189717) (xy 98.774165 -215.159094) (xy 98.818769 -215.135013)
			(xy 98.866532 -215.118041) (xy 98.891344 -215.112854) (xy 98.914204 -215.108536) (xy 99.119182 -214.753444)
			(xy 99.111308 -214.7316) (xy 99.102729 -214.705181) (xy 99.093532 -214.650406) (xy 99.09302 -214.622634)
			(xy 99.093528 -214.596747) (xy 99.101627 -214.545609) (xy 99.117626 -214.496369) (xy 99.141132 -214.450237)
			(xy 99.171564 -214.40835) (xy 99.208174 -214.37174) (xy 99.250061 -214.341308) (xy 99.296193 -214.317802)
			(xy 99.345433 -214.301803) (xy 99.396571 -214.293704) (xy 99.448345 -214.293704) (xy 99.499483 -214.301803)
			(xy 99.548723 -214.317802) (xy 99.594855 -214.341308) (xy 99.636742 -214.37174) (xy 99.673352 -214.40835)
			(xy 99.703784 -214.450237) (xy 99.72729 -214.496369) (xy 99.743289 -214.545609) (xy 99.751388 -214.596747)
			(xy 99.751896 -214.622634) (xy 99.751447 -214.64797) (xy 99.74369 -214.698044) (xy 99.728363 -214.746341)
			(xy 99.705827 -214.791726) (xy 99.676612 -214.833128) (xy 99.641408 -214.869572) (xy 99.601042 -214.900202)
			(xy 99.556465 -214.924296) (xy 99.508727 -214.941286) (xy 99.483926 -214.946484) (xy 99.461066 -214.950802)
			(xy 99.256088 -215.305894) (xy 99.263962 -215.327738) (xy 99.27261 -215.354146) (xy 99.281929 -215.408922)
			(xy 99.282504 -215.436704) (xy 99.281996 -215.462611) (xy 99.27389 -215.513788) (xy 99.257878 -215.563067)
			(xy 99.234355 -215.609234) (xy 99.203899 -215.651153) (xy 99.167261 -215.687791) (xy 99.125342 -215.718247)
			(xy 99.079175 -215.74177) (xy 99.029896 -215.757782) (xy 98.978719 -215.765888) (xy 98.926905 -215.765888)
			(xy 98.875728 -215.757782) (xy 98.826449 -215.74177) (xy 98.780282 -215.718247) (xy 98.738363 -215.687791)
			(xy 98.701725 -215.651153) (xy 98.671269 -215.609234) (xy 98.647746 -215.563067) (xy 98.631734 -215.513788)
			(xy 98.623628 -215.462611) (xy 98.62312 -215.436704) (xy 97.402904 -215.436704) (xy 97.402396 -215.462611)
			(xy 97.39429 -215.513788) (xy 97.378278 -215.563067) (xy 97.354755 -215.609234) (xy 97.324299 -215.651153)
			(xy 97.287661 -215.687791) (xy 97.245742 -215.718247) (xy 97.199575 -215.74177) (xy 97.150296 -215.757782)
			(xy 97.099119 -215.765888) (xy 97.047305 -215.765888) (xy 96.996128 -215.757782) (xy 96.946849 -215.74177)
			(xy 96.900682 -215.718247) (xy 96.858763 -215.687791) (xy 96.822125 -215.651153) (xy 96.791669 -215.609234)
			(xy 96.768146 -215.563067) (xy 96.752134 -215.513788) (xy 96.744028 -215.462611) (xy 96.74352 -215.436704)
			(xy 95.523304 -215.436704) (xy 95.522796 -215.462611) (xy 95.51469 -215.513788) (xy 95.498678 -215.563067)
			(xy 95.475155 -215.609234) (xy 95.444699 -215.651153) (xy 95.408061 -215.687791) (xy 95.366142 -215.718247)
			(xy 95.319975 -215.74177) (xy 95.270696 -215.757782) (xy 95.219519 -215.765888) (xy 95.167705 -215.765888)
			(xy 95.116528 -215.757782) (xy 95.067249 -215.74177) (xy 95.021082 -215.718247) (xy 94.979163 -215.687791)
			(xy 94.942525 -215.651153) (xy 94.912069 -215.609234) (xy 94.888546 -215.563067) (xy 94.872534 -215.513788)
			(xy 94.864428 -215.462611) (xy 94.86392 -215.436704) (xy 93.643704 -215.436704) (xy 93.643196 -215.462611)
			(xy 93.63509 -215.513788) (xy 93.619078 -215.563067) (xy 93.595555 -215.609234) (xy 93.565099 -215.651153)
			(xy 93.528461 -215.687791) (xy 93.486542 -215.718247) (xy 93.440375 -215.74177) (xy 93.391096 -215.757782)
			(xy 93.339919 -215.765888) (xy 93.288105 -215.765888) (xy 93.236928 -215.757782) (xy 93.187649 -215.74177)
			(xy 93.141482 -215.718247) (xy 93.099563 -215.687791) (xy 93.062925 -215.651153) (xy 93.032469 -215.609234)
			(xy 93.008946 -215.563067) (xy 92.992934 -215.513788) (xy 92.984828 -215.462611) (xy 92.98432 -215.436704)
			(xy 91.764104 -215.436704) (xy 91.763596 -215.462611) (xy 91.75549 -215.513788) (xy 91.739478 -215.563067)
			(xy 91.715955 -215.609234) (xy 91.685499 -215.651153) (xy 91.648861 -215.687791) (xy 91.606942 -215.718247)
			(xy 91.560775 -215.74177) (xy 91.511496 -215.757782) (xy 91.460319 -215.765888) (xy 91.408505 -215.765888)
			(xy 91.357328 -215.757782) (xy 91.308049 -215.74177) (xy 91.261882 -215.718247) (xy 91.219963 -215.687791)
			(xy 91.183325 -215.651153) (xy 91.152869 -215.609234) (xy 91.129346 -215.563067) (xy 91.113334 -215.513788)
			(xy 91.105228 -215.462611) (xy 91.10472 -215.436704) (xy 89.884504 -215.436704) (xy 89.883996 -215.462611)
			(xy 89.87589 -215.513788) (xy 89.859878 -215.563067) (xy 89.836355 -215.609234) (xy 89.805899 -215.651153)
			(xy 89.769261 -215.687791) (xy 89.727342 -215.718247) (xy 89.681175 -215.74177) (xy 89.631896 -215.757782)
			(xy 89.580719 -215.765888) (xy 89.528905 -215.765888) (xy 89.477728 -215.757782) (xy 89.428449 -215.74177)
			(xy 89.382282 -215.718247) (xy 89.340363 -215.687791) (xy 89.303725 -215.651153) (xy 89.273269 -215.609234)
			(xy 89.249746 -215.563067) (xy 89.233734 -215.513788) (xy 89.225628 -215.462611) (xy 89.22512 -215.436704)
			(xy 88.944704 -215.436704) (xy 88.944111 -215.464421) (xy 88.934787 -215.519068) (xy 88.926162 -215.545416)
			(xy 88.918288 -215.567514) (xy 89.123266 -215.922352) (xy 89.146126 -215.92667) (xy 89.170934 -215.931835)
			(xy 89.218674 -215.948828) (xy 89.263251 -215.972925) (xy 89.303616 -216.003559) (xy 89.338819 -216.040009)
			(xy 89.36803 -216.081415) (xy 89.390562 -216.126804) (xy 89.405883 -216.175106) (xy 89.413634 -216.225183)
			(xy 89.414096 -216.25052) (xy 89.413588 -216.276407) (xy 89.405489 -216.327545) (xy 89.38949 -216.376785)
			(xy 89.365984 -216.422917) (xy 89.335552 -216.464804) (xy 89.298942 -216.501414) (xy 89.257055 -216.531846)
			(xy 89.210923 -216.555352) (xy 89.161683 -216.571351) (xy 89.110545 -216.57945) (xy 89.058771 -216.57945)
			(xy 89.007633 -216.571351) (xy 88.958393 -216.555352) (xy 88.912261 -216.531846) (xy 88.870374 -216.501414)
			(xy 88.833764 -216.464804) (xy 88.803332 -216.422917) (xy 88.779826 -216.376785) (xy 88.763827 -216.327545)
			(xy 88.755728 -216.276407) (xy 88.75522 -216.25052) (xy 88.755754 -216.222812) (xy 88.764946 -216.168165)
			(xy 88.773508 -216.141808) (xy 88.781382 -216.11971) (xy 88.576404 -215.764872) (xy 88.553544 -215.760554)
			(xy 88.528711 -215.755439) (xy 88.480928 -215.73848) (xy 88.436306 -215.714403) (xy 88.395898 -215.683776)
			(xy 88.360658 -215.647323) (xy 88.331415 -215.605902) (xy 88.308862 -215.560492) (xy 88.293529 -215.512163)
			(xy 88.285778 -215.462056) (xy 88.28532 -215.436704) (xy 61.39434 -215.436704) (xy 61.39434 -217.585544)
			(xy 61.878718 -218.069922) (xy 74.355198 -218.069922) (xy 74.361294 -218.068398) (xy 74.376895 -218.064607)
			(xy 74.408741 -218.060533) (xy 74.424794 -218.06027) (xy 88.661494 -218.06027) (xy 88.676398 -218.059751)
			(xy 88.704938 -218.051147) (xy 88.729779 -218.034669) (xy 88.748804 -218.011721) (xy 88.760394 -217.984258)
			(xy 88.763562 -217.954618) (xy 88.761316 -217.939874) (xy 88.758653 -217.924648) (xy 88.755856 -217.893863)
			(xy 88.755728 -217.878406) (xy 88.756235 -217.852517) (xy 88.764334 -217.801377) (xy 88.780332 -217.752134)
			(xy 88.803836 -217.705999) (xy 88.834268 -217.664108) (xy 88.870878 -217.627494) (xy 88.912764 -217.597057)
			(xy 88.958897 -217.573547) (xy 89.008138 -217.557543) (xy 89.059277 -217.549438) (xy 89.085166 -217.548968)
			(xy 89.112663 -217.549501) (xy 89.166899 -217.558597) (xy 89.218871 -217.576575) (xy 89.267134 -217.602937)
			(xy 89.310349 -217.636949) (xy 89.32926 -217.656918) (xy 89.336191 -217.663877) (xy 89.353872 -217.672388)
			(xy 89.373454 -217.673647) (xy 89.39208 -217.667472) (xy 89.399872 -217.66149) (xy 89.417234 -217.647245)
			(xy 89.455946 -217.624489) (xy 89.498063 -217.608911) (xy 89.542265 -217.601) (xy 89.564718 -217.60053)
			(xy 89.847674 -217.60053) (xy 89.874515 -217.584284) (xy 89.93282 -217.561134) (xy 89.963498 -217.554556)
			(xy 89.986358 -217.550238) (xy 90.191336 -217.195146) (xy 90.183462 -217.173302) (xy 90.174812 -217.146894)
			(xy 90.165483 -217.092118) (xy 90.16492 -217.064336) (xy 90.165428 -217.038429) (xy 90.173534 -216.987252)
			(xy 90.189546 -216.937973) (xy 90.213069 -216.891806) (xy 90.243525 -216.849887) (xy 90.280163 -216.813249)
			(xy 90.322082 -216.782793) (xy 90.368249 -216.75927) (xy 90.417528 -216.743258) (xy 90.468705 -216.735152)
			(xy 90.520519 -216.735152) (xy 90.571696 -216.743258) (xy 90.620975 -216.75927) (xy 90.667142 -216.782793)
			(xy 90.709061 -216.813249) (xy 90.745699 -216.849887) (xy 90.776155 -216.891806) (xy 90.799678 -216.937973)
			(xy 90.81569 -216.987252) (xy 90.823796 -217.038429) (xy 90.824304 -217.064336) (xy 90.823844 -217.089687)
			(xy 90.816089 -217.139791) (xy 90.800754 -217.188117) (xy 90.778199 -217.233525) (xy 90.748956 -217.274944)
			(xy 90.713716 -217.311396) (xy 90.67331 -217.342021) (xy 90.62869 -217.366098) (xy 90.58091 -217.383058)
			(xy 90.55608 -217.388186) (xy 90.53322 -217.392504) (xy 90.500962 -217.44813) (xy 90.493787 -217.461591)
			(xy 90.48702 -217.49132) (xy 90.489318 -217.521722) (xy 90.500477 -217.550097) (xy 90.519505 -217.57392)
			(xy 90.544711 -217.591074) (xy 90.573855 -217.600034) (xy 90.5891 -217.60053) (xy 90.787474 -217.60053)
			(xy 90.807431 -217.588297) (xy 90.85007 -217.568983) (xy 90.895016 -217.55591) (xy 90.941361 -217.54934)
			(xy 90.964766 -217.548968) (xy 90.988167 -217.549367) (xy 91.034503 -217.555962) (xy 91.079441 -217.569039)
			(xy 91.12208 -217.588335) (xy 91.142058 -217.60053) (xy 91.727274 -217.60053) (xy 91.754115 -217.584284)
			(xy 91.81242 -217.561134) (xy 91.843098 -217.554556) (xy 91.865958 -217.550238) (xy 92.070936 -217.195146)
			(xy 92.063062 -217.173302) (xy 92.054412 -217.146894) (xy 92.045083 -217.092118) (xy 92.04452 -217.064336)
			(xy 92.045028 -217.038429) (xy 92.053134 -216.987252) (xy 92.069146 -216.937973) (xy 92.092669 -216.891806)
			(xy 92.123125 -216.849887) (xy 92.159763 -216.813249) (xy 92.201682 -216.782793) (xy 92.247849 -216.75927)
			(xy 92.297128 -216.743258) (xy 92.348305 -216.735152) (xy 92.400119 -216.735152) (xy 92.451296 -216.743258)
			(xy 92.500575 -216.75927) (xy 92.546742 -216.782793) (xy 92.588661 -216.813249) (xy 92.625299 -216.849887)
			(xy 92.655755 -216.891806) (xy 92.679278 -216.937973) (xy 92.69529 -216.987252) (xy 92.703396 -217.038429)
			(xy 92.703904 -217.064336) (xy 92.703444 -217.089687) (xy 92.695689 -217.139791) (xy 92.680354 -217.188117)
			(xy 92.657799 -217.233525) (xy 92.628556 -217.274944) (xy 92.593316 -217.311396) (xy 92.55291 -217.342021)
			(xy 92.50829 -217.366098) (xy 92.46051 -217.383058) (xy 92.43568 -217.388186) (xy 92.41282 -217.392504)
			(xy 92.380562 -217.44813) (xy 92.373387 -217.461591) (xy 92.36662 -217.49132) (xy 92.368918 -217.521722)
			(xy 92.380077 -217.550097) (xy 92.399105 -217.57392) (xy 92.424311 -217.591074) (xy 92.453455 -217.600034)
			(xy 92.4687 -217.60053) (xy 92.667074 -217.60053) (xy 92.687031 -217.588297) (xy 92.72967 -217.568983)
			(xy 92.774616 -217.55591) (xy 92.820961 -217.54934) (xy 92.844366 -217.548968) (xy 92.867767 -217.549367)
			(xy 92.914103 -217.555962) (xy 92.959041 -217.569039) (xy 93.00168 -217.588335) (xy 93.021658 -217.60053)
			(xy 93.606874 -217.60053) (xy 93.633715 -217.584284) (xy 93.69202 -217.561134) (xy 93.722698 -217.554556)
			(xy 93.745558 -217.550238) (xy 93.950536 -217.195146) (xy 93.942662 -217.173302) (xy 93.934012 -217.146894)
			(xy 93.924683 -217.092118) (xy 93.92412 -217.064336) (xy 93.924628 -217.038429) (xy 93.932734 -216.987252)
			(xy 93.948746 -216.937973) (xy 93.972269 -216.891806) (xy 94.002725 -216.849887) (xy 94.039363 -216.813249)
			(xy 94.081282 -216.782793) (xy 94.127449 -216.75927) (xy 94.176728 -216.743258) (xy 94.227905 -216.735152)
			(xy 94.279719 -216.735152) (xy 94.330896 -216.743258) (xy 94.380175 -216.75927) (xy 94.426342 -216.782793)
			(xy 94.468261 -216.813249) (xy 94.504899 -216.849887) (xy 94.535355 -216.891806) (xy 94.558878 -216.937973)
			(xy 94.57489 -216.987252) (xy 94.582996 -217.038429) (xy 94.583504 -217.064336) (xy 94.583044 -217.089687)
			(xy 94.575289 -217.139791) (xy 94.559954 -217.188117) (xy 94.537399 -217.233525) (xy 94.508156 -217.274944)
			(xy 94.472916 -217.311396) (xy 94.43251 -217.342021) (xy 94.38789 -217.366098) (xy 94.34011 -217.383058)
			(xy 94.31528 -217.388186) (xy 94.29242 -217.392504) (xy 94.260162 -217.44813) (xy 94.252987 -217.461591)
			(xy 94.24622 -217.49132) (xy 94.248518 -217.521722) (xy 94.259677 -217.550097) (xy 94.278705 -217.57392)
			(xy 94.303911 -217.591074) (xy 94.333055 -217.600034) (xy 94.3483 -217.60053) (xy 94.546674 -217.60053)
			(xy 94.566631 -217.588297) (xy 94.60927 -217.568983) (xy 94.654216 -217.55591) (xy 94.700561 -217.54934)
			(xy 94.723966 -217.548968) (xy 94.750058 -217.54946) (xy 94.801591 -217.55767) (xy 94.85119 -217.573888)
			(xy 94.897618 -217.597713) (xy 94.939716 -217.628548) (xy 94.958408 -217.646758) (xy 94.967313 -217.65316)
			(xy 94.9841 -217.667278) (xy 94.991936 -217.674952) (xy 95.171514 -217.85453) (xy 95.181408 -217.863826)
			(xy 95.20497 -217.877291) (xy 95.231247 -217.884074) (xy 95.258382 -217.883695) (xy 95.284459 -217.87618)
			(xy 95.307636 -217.862061) (xy 95.326274 -217.842335) (xy 95.339057 -217.818396) (xy 95.342456 -217.805254)
			(xy 95.34905 -217.77875) (xy 95.3698 -217.728234) (xy 95.398588 -217.681825) (xy 95.434628 -217.640793)
			(xy 95.476935 -217.606258) (xy 95.524352 -217.579163) (xy 95.575585 -217.56025) (xy 95.602298 -217.554556)
			(xy 95.625158 -217.550238) (xy 95.830136 -217.195146) (xy 95.822262 -217.173302) (xy 95.813612 -217.146894)
			(xy 95.804283 -217.092118) (xy 95.80372 -217.064336) (xy 95.804228 -217.038429) (xy 95.812334 -216.987252)
			(xy 95.828346 -216.937973) (xy 95.851869 -216.891806) (xy 95.882325 -216.849887) (xy 95.918963 -216.813249)
			(xy 95.960882 -216.782793) (xy 96.007049 -216.75927) (xy 96.056328 -216.743258) (xy 96.107505 -216.735152)
			(xy 96.159319 -216.735152) (xy 96.210496 -216.743258) (xy 96.259775 -216.75927) (xy 96.305942 -216.782793)
			(xy 96.347861 -216.813249) (xy 96.384499 -216.849887) (xy 96.414955 -216.891806) (xy 96.438478 -216.937973)
			(xy 96.45449 -216.987252) (xy 96.462596 -217.038429) (xy 96.463104 -217.064336) (xy 96.462644 -217.089687)
			(xy 96.454889 -217.139791) (xy 96.439554 -217.188117) (xy 96.416999 -217.233525) (xy 96.387756 -217.274944)
			(xy 96.352516 -217.311396) (xy 96.31211 -217.342021) (xy 96.26749 -217.366098) (xy 96.21971 -217.383058)
			(xy 96.19488 -217.388186) (xy 96.17202 -217.392504) (xy 95.967042 -217.747596) (xy 95.974916 -217.76944)
			(xy 95.983491 -217.795859) (xy 95.992677 -217.850635) (xy 95.993204 -217.878406) (xy 96.274128 -217.878406)
			(xy 96.274636 -217.852519) (xy 96.282735 -217.801381) (xy 96.298734 -217.752141) (xy 96.32224 -217.706009)
			(xy 96.352672 -217.664122) (xy 96.389282 -217.627512) (xy 96.431169 -217.59708) (xy 96.477301 -217.573574)
			(xy 96.526541 -217.557575) (xy 96.577679 -217.549476) (xy 96.629453 -217.549476) (xy 96.680591 -217.557575)
			(xy 96.729831 -217.573574) (xy 96.775963 -217.59708) (xy 96.81785 -217.627512) (xy 96.85446 -217.664122)
			(xy 96.884892 -217.706009) (xy 96.908398 -217.752141) (xy 96.924397 -217.801381) (xy 96.932496 -217.852519)
			(xy 96.933004 -217.878406) (xy 97.213928 -217.878406) (xy 97.214394 -217.853071) (xy 97.222146 -217.802996)
			(xy 97.237469 -217.754698) (xy 97.260002 -217.709313) (xy 97.289214 -217.66791) (xy 97.324417 -217.631464)
			(xy 97.364782 -217.600835) (xy 97.409359 -217.576742) (xy 97.457097 -217.559754) (xy 97.481898 -217.554556)
			(xy 97.504758 -217.550238) (xy 97.709736 -217.195146) (xy 97.701862 -217.173302) (xy 97.693224 -217.146891)
			(xy 97.683899 -217.092117) (xy 97.68332 -217.064336) (xy 97.683828 -217.038429) (xy 97.691934 -216.987252)
			(xy 97.707946 -216.937973) (xy 97.731469 -216.891806) (xy 97.761925 -216.849887) (xy 97.798563 -216.813249)
			(xy 97.840482 -216.782793) (xy 97.886649 -216.75927) (xy 97.935928 -216.743258) (xy 97.987105 -216.735152)
			(xy 98.038919 -216.735152) (xy 98.090096 -216.743258) (xy 98.139375 -216.75927) (xy 98.185542 -216.782793)
			(xy 98.227461 -216.813249) (xy 98.264099 -216.849887) (xy 98.294555 -216.891806) (xy 98.318078 -216.937973)
			(xy 98.33409 -216.987252) (xy 98.342196 -217.038429) (xy 98.342704 -217.064336) (xy 98.342212 -217.08968)
			(xy 98.334435 -217.13977) (xy 98.319086 -217.188079) (xy 98.296525 -217.233471) (xy 98.267284 -217.274876)
			(xy 98.232052 -217.311319) (xy 98.191659 -217.341943) (xy 98.147055 -217.366024) (xy 98.099292 -217.382998)
			(xy 98.07448 -217.388186) (xy 98.05162 -217.392504) (xy 97.846642 -217.747596) (xy 97.854516 -217.76944)
			(xy 97.863106 -217.795856) (xy 97.872295 -217.850633) (xy 97.872804 -217.878406) (xy 98.153728 -217.878406)
			(xy 98.154236 -217.852519) (xy 98.162335 -217.801381) (xy 98.178334 -217.752141) (xy 98.20184 -217.706009)
			(xy 98.232272 -217.664122) (xy 98.268882 -217.627512) (xy 98.310769 -217.59708) (xy 98.356901 -217.573574)
			(xy 98.406141 -217.557575) (xy 98.457279 -217.549476) (xy 98.509053 -217.549476) (xy 98.560191 -217.557575)
			(xy 98.609431 -217.573574) (xy 98.655563 -217.59708) (xy 98.69745 -217.627512) (xy 98.73406 -217.664122)
			(xy 98.764492 -217.706009) (xy 98.787998 -217.752141) (xy 98.803997 -217.801381) (xy 98.812096 -217.852519)
			(xy 98.812604 -217.878406) (xy 99.093528 -217.878406) (xy 99.093994 -217.853071) (xy 99.101746 -217.802996)
			(xy 99.117069 -217.754698) (xy 99.139602 -217.709313) (xy 99.168814 -217.66791) (xy 99.204017 -217.631464)
			(xy 99.244382 -217.600835) (xy 99.288959 -217.576742) (xy 99.336697 -217.559754) (xy 99.361498 -217.554556)
			(xy 99.384358 -217.550238) (xy 99.589336 -217.195146) (xy 99.581462 -217.173302) (xy 99.572824 -217.146891)
			(xy 99.563499 -217.092117) (xy 99.56292 -217.064336) (xy 99.563428 -217.038429) (xy 99.571534 -216.987252)
			(xy 99.587546 -216.937973) (xy 99.611069 -216.891806) (xy 99.641525 -216.849887) (xy 99.678163 -216.813249)
			(xy 99.720082 -216.782793) (xy 99.766249 -216.75927) (xy 99.815528 -216.743258) (xy 99.866705 -216.735152)
			(xy 99.918519 -216.735152) (xy 99.969696 -216.743258) (xy 100.018975 -216.75927) (xy 100.065142 -216.782793)
			(xy 100.107061 -216.813249) (xy 100.143699 -216.849887) (xy 100.174155 -216.891806) (xy 100.197678 -216.937973)
			(xy 100.21369 -216.987252) (xy 100.221796 -217.038429) (xy 100.222304 -217.064336) (xy 100.221812 -217.08968)
			(xy 100.214035 -217.13977) (xy 100.198686 -217.188079) (xy 100.176125 -217.233471) (xy 100.146884 -217.274876)
			(xy 100.111652 -217.311319) (xy 100.071259 -217.341943) (xy 100.026655 -217.366024) (xy 99.978892 -217.382998)
			(xy 99.95408 -217.388186) (xy 99.93122 -217.392504) (xy 99.726242 -217.747596) (xy 99.734116 -217.76944)
			(xy 99.742706 -217.795856) (xy 99.751895 -217.850633) (xy 99.752404 -217.878406) (xy 99.751896 -217.904293)
			(xy 99.743797 -217.955431) (xy 99.727798 -218.004671) (xy 99.704292 -218.050803) (xy 99.67386 -218.09269)
			(xy 99.63725 -218.1293) (xy 99.595363 -218.159732) (xy 99.549231 -218.183238) (xy 99.499991 -218.199237)
			(xy 99.448853 -218.207336) (xy 99.397079 -218.207336) (xy 99.345941 -218.199237) (xy 99.296701 -218.183238)
			(xy 99.250569 -218.159732) (xy 99.208682 -218.1293) (xy 99.172072 -218.09269) (xy 99.14164 -218.050803)
			(xy 99.118134 -218.004671) (xy 99.102135 -217.955431) (xy 99.094036 -217.904293) (xy 99.093528 -217.878406)
			(xy 98.812604 -217.878406) (xy 98.812076 -217.906114) (xy 98.80288 -217.960761) (xy 98.794316 -217.987118)
			(xy 98.786442 -218.009216) (xy 98.99142 -218.364054) (xy 99.01428 -218.368372) (xy 99.0391 -218.37354)
			(xy 99.086878 -218.390497) (xy 99.131495 -218.41457) (xy 99.1719 -218.44519) (xy 99.20714 -218.481637)
			(xy 99.236384 -218.52305) (xy 99.258942 -218.568452) (xy 99.274281 -218.616773) (xy 99.282041 -218.666873)
			(xy 99.282504 -218.692222) (xy 99.281996 -218.718129) (xy 99.27389 -218.769306) (xy 99.257878 -218.818585)
			(xy 99.234355 -218.864752) (xy 99.203899 -218.906671) (xy 99.167261 -218.943309) (xy 99.125342 -218.973765)
			(xy 99.079175 -218.997288) (xy 99.029896 -219.0133) (xy 98.978719 -219.021406) (xy 98.926905 -219.021406)
			(xy 98.875728 -219.0133) (xy 98.826449 -218.997288) (xy 98.780282 -218.973765) (xy 98.738363 -218.943309)
			(xy 98.701725 -218.906671) (xy 98.671269 -218.864752) (xy 98.647746 -218.818585) (xy 98.631734 -218.769306)
			(xy 98.623628 -218.718129) (xy 98.62312 -218.692222) (xy 98.623718 -218.664505) (xy 98.633039 -218.609858)
			(xy 98.641662 -218.58351) (xy 98.649536 -218.561412) (xy 98.444558 -218.206574) (xy 98.421698 -218.202256)
			(xy 98.396899 -218.197049) (xy 98.349162 -218.180062) (xy 98.304585 -218.15597) (xy 98.26422 -218.125341)
			(xy 98.229017 -218.088897) (xy 98.199804 -218.047495) (xy 98.177271 -218.002112) (xy 98.161946 -217.953814)
			(xy 98.154192 -217.903741) (xy 98.153728 -217.878406) (xy 97.872804 -217.878406) (xy 97.872296 -217.904293)
			(xy 97.864197 -217.955431) (xy 97.848198 -218.004671) (xy 97.824692 -218.050803) (xy 97.79426 -218.09269)
			(xy 97.75765 -218.1293) (xy 97.715763 -218.159732) (xy 97.669631 -218.183238) (xy 97.620391 -218.199237)
			(xy 97.569253 -218.207336) (xy 97.517479 -218.207336) (xy 97.466341 -218.199237) (xy 97.417101 -218.183238)
			(xy 97.370969 -218.159732) (xy 97.329082 -218.1293) (xy 97.292472 -218.09269) (xy 97.26204 -218.050803)
			(xy 97.238534 -218.004671) (xy 97.222535 -217.955431) (xy 97.214436 -217.904293) (xy 97.213928 -217.878406)
			(xy 96.933004 -217.878406) (xy 96.932476 -217.906114) (xy 96.92328 -217.960761) (xy 96.914716 -217.987118)
			(xy 96.906842 -218.009216) (xy 97.11182 -218.364054) (xy 97.13468 -218.368372) (xy 97.1595 -218.37354)
			(xy 97.207278 -218.390497) (xy 97.251895 -218.41457) (xy 97.2923 -218.44519) (xy 97.32754 -218.481637)
			(xy 97.356784 -218.52305) (xy 97.379342 -218.568452) (xy 97.394681 -218.616773) (xy 97.402441 -218.666873)
			(xy 97.402904 -218.692222) (xy 97.402396 -218.718129) (xy 97.39429 -218.769306) (xy 97.378278 -218.818585)
			(xy 97.354755 -218.864752) (xy 97.324299 -218.906671) (xy 97.287661 -218.943309) (xy 97.245742 -218.973765)
			(xy 97.199575 -218.997288) (xy 97.150296 -219.0133) (xy 97.099119 -219.021406) (xy 97.047305 -219.021406)
			(xy 96.996128 -219.0133) (xy 96.946849 -218.997288) (xy 96.900682 -218.973765) (xy 96.858763 -218.943309)
			(xy 96.822125 -218.906671) (xy 96.791669 -218.864752) (xy 96.768146 -218.818585) (xy 96.752134 -218.769306)
			(xy 96.744028 -218.718129) (xy 96.74352 -218.692222) (xy 96.744118 -218.664505) (xy 96.753439 -218.609858)
			(xy 96.762062 -218.58351) (xy 96.769936 -218.561412) (xy 96.564958 -218.206574) (xy 96.542098 -218.202256)
			(xy 96.517299 -218.197049) (xy 96.469562 -218.180062) (xy 96.424985 -218.15597) (xy 96.38462 -218.125341)
			(xy 96.349417 -218.088897) (xy 96.320204 -218.047495) (xy 96.297671 -218.002112) (xy 96.282346 -217.953814)
			(xy 96.274592 -217.903741) (xy 96.274128 -217.878406) (xy 95.993204 -217.878406) (xy 95.992722 -217.904294)
			(xy 95.984621 -217.955433) (xy 95.96862 -218.004675) (xy 95.945112 -218.050807) (xy 95.914676 -218.092693)
			(xy 95.878063 -218.129302) (xy 95.836173 -218.159733) (xy 95.790038 -218.183235) (xy 95.740794 -218.199231)
			(xy 95.689654 -218.207325) (xy 95.663766 -218.207844) (xy 95.63692 -218.207358) (xy 95.58393 -218.198725)
			(xy 95.533046 -218.181596) (xy 95.50908 -218.16949) (xy 95.499444 -218.165048) (xy 95.478298 -218.163627)
			(xy 95.458378 -218.170862) (xy 95.443072 -218.185521) (xy 95.434985 -218.20511) (xy 95.434658 -218.215718)
			(xy 95.434658 -218.467432) (xy 95.451221 -218.485832) (xy 95.479205 -218.52667) (xy 95.500766 -218.571234)
			(xy 95.515419 -218.618522) (xy 95.522835 -218.667469) (xy 95.523304 -218.692222) (xy 95.522796 -218.718796)
			(xy 95.514265 -218.771255) (xy 95.497427 -218.821665) (xy 95.47272 -218.868721) (xy 95.440782 -218.911202)
			(xy 95.421958 -218.929966) (xy 95.421958 -219.512134) (xy 95.952056 -220.042232) (xy 95.984822 -220.025722)
			(xy 96.007993 -220.01459) (xy 96.056927 -219.998849) (xy 96.10771 -219.99089) (xy 96.133412 -219.990416)
			(xy 96.159306 -219.990924) (xy 96.210456 -219.999024) (xy 96.259711 -220.015021) (xy 96.305859 -220.038523)
			(xy 96.347764 -220.068951) (xy 96.384397 -220.105558) (xy 96.414855 -220.147441) (xy 96.438389 -220.193573)
			(xy 96.454422 -220.242816) (xy 96.462557 -220.293961) (xy 96.463104 -220.319854) (xy 96.462595 -220.345566)
			(xy 96.454568 -220.396361) (xy 96.438733 -220.445288) (xy 96.427544 -220.468444) (xy 96.411034 -220.50121)
			(xy 96.746822 -220.836998) (xy 96.753934 -220.840554) (xy 96.776587 -220.852717) (xy 96.818148 -220.882987)
			(xy 96.854505 -220.919342) (xy 96.884776 -220.960901) (xy 96.896936 -220.983556) (xy 96.900492 -220.990668)
			(xy 97.046034 -221.13621) (xy 97.056218 -221.145723) (xy 97.080546 -221.159294) (xy 97.107636 -221.165791)
			(xy 97.135474 -221.16473) (xy 97.161991 -221.156191) (xy 97.185216 -221.140807) (xy 97.203424 -221.119722)
			(xy 97.21526 -221.094504) (xy 97.217992 -221.080838) (xy 97.222516 -221.056063) (xy 97.23809 -221.00817)
			(xy 97.260769 -220.963205) (xy 97.290023 -220.922212) (xy 97.325173 -220.886147) (xy 97.365401 -220.855848)
			(xy 97.409769 -220.832022) (xy 97.457245 -220.815222) (xy 97.481898 -220.810074) (xy 97.504758 -220.805756)
			(xy 97.709736 -220.450664) (xy 97.701862 -220.42882) (xy 97.693219 -220.402411) (xy 97.683903 -220.347635)
			(xy 97.68332 -220.319854) (xy 97.683828 -220.293947) (xy 97.691934 -220.24277) (xy 97.707946 -220.193491)
			(xy 97.731469 -220.147324) (xy 97.761925 -220.105405) (xy 97.798563 -220.068767) (xy 97.840482 -220.038311)
			(xy 97.886649 -220.014788) (xy 97.935928 -219.998776) (xy 97.987105 -219.99067) (xy 98.038919 -219.99067)
			(xy 98.090096 -219.998776) (xy 98.139375 -220.014788) (xy 98.185542 -220.038311) (xy 98.227461 -220.068767)
			(xy 98.264099 -220.105405) (xy 98.294555 -220.147324) (xy 98.318078 -220.193491) (xy 98.33409 -220.24277)
			(xy 98.342196 -220.293947) (xy 98.342704 -220.319854) (xy 98.342242 -220.345204) (xy 98.334486 -220.395306)
			(xy 98.319149 -220.44363) (xy 98.296592 -220.489036) (xy 98.26735 -220.530452) (xy 98.232109 -220.566902)
			(xy 98.191704 -220.597525) (xy 98.147085 -220.6216) (xy 98.099306 -220.638559) (xy 98.07448 -220.643704)
			(xy 98.05162 -220.648022) (xy 97.846642 -221.003114) (xy 97.854516 -221.024958) (xy 97.863097 -221.051376)
			(xy 97.872297 -221.106152) (xy 97.872804 -221.133924) (xy 98.153728 -221.133924) (xy 98.154236 -221.108037)
			(xy 98.162335 -221.056899) (xy 98.178334 -221.007659) (xy 98.20184 -220.961527) (xy 98.232272 -220.91964)
			(xy 98.268882 -220.88303) (xy 98.310769 -220.852598) (xy 98.356901 -220.829092) (xy 98.406141 -220.813093)
			(xy 98.457279 -220.804994) (xy 98.509053 -220.804994) (xy 98.560191 -220.813093) (xy 98.609431 -220.829092)
			(xy 98.655563 -220.852598) (xy 98.69745 -220.88303) (xy 98.73406 -220.91964) (xy 98.764492 -220.961527)
			(xy 98.787998 -221.007659) (xy 98.803997 -221.056899) (xy 98.812096 -221.108037) (xy 98.812604 -221.133924)
			(xy 99.093528 -221.133924) (xy 99.09401 -221.108589) (xy 99.10176 -221.058515) (xy 99.11708 -221.010217)
			(xy 99.139611 -220.964832) (xy 99.168821 -220.923429) (xy 99.204022 -220.886984) (xy 99.244386 -220.856354)
			(xy 99.288961 -220.83226) (xy 99.336698 -220.815272) (xy 99.361498 -220.810074) (xy 99.384358 -220.805756)
			(xy 99.589336 -220.450664) (xy 99.581462 -220.42882) (xy 99.572829 -220.402408) (xy 99.5635 -220.347635)
			(xy 99.56292 -220.319854) (xy 99.563428 -220.293947) (xy 99.571534 -220.24277) (xy 99.587546 -220.193491)
			(xy 99.611069 -220.147324) (xy 99.641525 -220.105405) (xy 99.678163 -220.068767) (xy 99.720082 -220.038311)
			(xy 99.766249 -220.014788) (xy 99.815528 -219.998776) (xy 99.866705 -219.99067) (xy 99.918519 -219.99067)
			(xy 99.969696 -219.998776) (xy 100.018975 -220.014788) (xy 100.065142 -220.038311) (xy 100.107061 -220.068767)
			(xy 100.143699 -220.105405) (xy 100.174155 -220.147324) (xy 100.197678 -220.193491) (xy 100.21369 -220.24277)
			(xy 100.221796 -220.293947) (xy 100.222304 -220.319854) (xy 100.221828 -220.345199) (xy 100.214049 -220.395289)
			(xy 100.198697 -220.443599) (xy 100.176134 -220.48899) (xy 100.146891 -220.530396) (xy 100.111657 -220.566839)
			(xy 100.071262 -220.597461) (xy 100.026657 -220.621543) (xy 99.978893 -220.638516) (xy 99.95408 -220.643704)
			(xy 99.93122 -220.648022) (xy 99.726242 -221.003114) (xy 99.734116 -221.024958) (xy 99.74271 -221.051373)
			(xy 99.751897 -221.106151) (xy 99.752404 -221.133924) (xy 100.033328 -221.133924) (xy 100.033836 -221.108037)
			(xy 100.041935 -221.056899) (xy 100.057934 -221.007659) (xy 100.08144 -220.961527) (xy 100.111872 -220.91964)
			(xy 100.148482 -220.88303) (xy 100.190369 -220.852598) (xy 100.236501 -220.829092) (xy 100.285741 -220.813093)
			(xy 100.336879 -220.804994) (xy 100.388653 -220.804994) (xy 100.439791 -220.813093) (xy 100.489031 -220.829092)
			(xy 100.535163 -220.852598) (xy 100.57705 -220.88303) (xy 100.61366 -220.91964) (xy 100.644092 -220.961527)
			(xy 100.667598 -221.007659) (xy 100.683597 -221.056899) (xy 100.691696 -221.108037) (xy 100.692204 -221.133924)
			(xy 100.69168 -221.161632) (xy 100.682481 -221.216279) (xy 100.673916 -221.242636) (xy 100.666042 -221.264734)
			(xy 100.87102 -221.619572) (xy 100.89388 -221.62389) (xy 100.918705 -221.629041) (xy 100.966483 -221.645999)
			(xy 101.011102 -221.670074) (xy 101.051507 -221.700696) (xy 101.086747 -221.737145) (xy 101.11599 -221.778561)
			(xy 101.138547 -221.823965) (xy 101.153885 -221.872289) (xy 101.161642 -221.92239) (xy 101.162104 -221.94774)
			(xy 101.161596 -221.973647) (xy 101.15349 -222.024824) (xy 101.137478 -222.074103) (xy 101.113955 -222.12027)
			(xy 101.083499 -222.162189) (xy 101.046861 -222.198827) (xy 101.004942 -222.229283) (xy 100.958775 -222.252806)
			(xy 100.909496 -222.268818) (xy 100.858319 -222.276924) (xy 100.806505 -222.276924) (xy 100.755328 -222.268818)
			(xy 100.706049 -222.252806) (xy 100.659882 -222.229283) (xy 100.617963 -222.198827) (xy 100.581325 -222.162189)
			(xy 100.550869 -222.12027) (xy 100.527346 -222.074103) (xy 100.511334 -222.024824) (xy 100.503228 -221.973647)
			(xy 100.50272 -221.94774) (xy 100.503323 -221.920023) (xy 100.51264 -221.865377) (xy 100.521262 -221.839028)
			(xy 100.529136 -221.81693) (xy 100.324158 -221.462092) (xy 100.301298 -221.457774) (xy 100.276503 -221.45255)
			(xy 100.228767 -221.435564) (xy 100.184192 -221.411474) (xy 100.143827 -221.380847) (xy 100.108624 -221.344405)
			(xy 100.079411 -221.303006) (xy 100.056876 -221.257625) (xy 100.04155 -221.20933) (xy 100.033794 -221.159258)
			(xy 100.033328 -221.133924) (xy 99.752404 -221.133924) (xy 99.751896 -221.159811) (xy 99.743797 -221.210949)
			(xy 99.727798 -221.260189) (xy 99.704292 -221.306321) (xy 99.67386 -221.348208) (xy 99.63725 -221.384818)
			(xy 99.595363 -221.41525) (xy 99.549231 -221.438756) (xy 99.499991 -221.454755) (xy 99.448853 -221.462854)
			(xy 99.397079 -221.462854) (xy 99.345941 -221.454755) (xy 99.296701 -221.438756) (xy 99.250569 -221.41525)
			(xy 99.208682 -221.384818) (xy 99.172072 -221.348208) (xy 99.14164 -221.306321) (xy 99.118134 -221.260189)
			(xy 99.102135 -221.210949) (xy 99.094036 -221.159811) (xy 99.093528 -221.133924) (xy 98.812604 -221.133924)
			(xy 98.81208 -221.161632) (xy 98.802881 -221.216279) (xy 98.794316 -221.242636) (xy 98.786442 -221.264734)
			(xy 98.99142 -221.619572) (xy 99.01428 -221.62389) (xy 99.039105 -221.629041) (xy 99.086883 -221.645999)
			(xy 99.131502 -221.670074) (xy 99.171907 -221.700696) (xy 99.207147 -221.737145) (xy 99.23639 -221.778561)
			(xy 99.258947 -221.823965) (xy 99.274285 -221.872289) (xy 99.282042 -221.92239) (xy 99.282504 -221.94774)
			(xy 99.281996 -221.973647) (xy 99.27389 -222.024824) (xy 99.257878 -222.074103) (xy 99.234355 -222.12027)
			(xy 99.203899 -222.162189) (xy 99.167261 -222.198827) (xy 99.125342 -222.229283) (xy 99.079175 -222.252806)
			(xy 99.029896 -222.268818) (xy 98.978719 -222.276924) (xy 98.926905 -222.276924) (xy 98.875728 -222.268818)
			(xy 98.826449 -222.252806) (xy 98.780282 -222.229283) (xy 98.738363 -222.198827) (xy 98.701725 -222.162189)
			(xy 98.671269 -222.12027) (xy 98.647746 -222.074103) (xy 98.631734 -222.024824) (xy 98.623628 -221.973647)
			(xy 98.62312 -221.94774) (xy 98.623723 -221.920023) (xy 98.63304 -221.865377) (xy 98.641662 -221.839028)
			(xy 98.649536 -221.81693) (xy 98.444558 -221.462092) (xy 98.421698 -221.457774) (xy 98.396903 -221.45255)
			(xy 98.349167 -221.435564) (xy 98.304592 -221.411474) (xy 98.264227 -221.380847) (xy 98.229024 -221.344405)
			(xy 98.199811 -221.303006) (xy 98.177276 -221.257625) (xy 98.16195 -221.20933) (xy 98.154194 -221.159258)
			(xy 98.153728 -221.133924) (xy 97.872804 -221.133924) (xy 97.872295 -221.159818) (xy 97.864195 -221.210968)
			(xy 97.848197 -221.260223) (xy 97.824694 -221.30637) (xy 97.794266 -221.348276) (xy 97.75766 -221.384909)
			(xy 97.715777 -221.415368) (xy 97.669646 -221.438904) (xy 97.620404 -221.454938) (xy 97.569259 -221.463076)
			(xy 97.543366 -221.463616) (xy 97.528095 -221.463398) (xy 97.497692 -221.460472) (xy 97.48266 -221.457774)
			(xy 97.467913 -221.455562) (xy 97.438285 -221.458805) (xy 97.410852 -221.470457) (xy 97.387947 -221.489528)
			(xy 97.371518 -221.514396) (xy 97.362961 -221.542947) (xy 97.362518 -221.55785) (xy 97.362518 -221.789498)
			(xy 97.367852 -221.800166) (xy 97.378867 -221.823193) (xy 97.394457 -221.871797) (xy 97.40239 -221.922219)
			(xy 97.402904 -221.94774) (xy 97.402411 -221.973263) (xy 97.3945 -222.023694) (xy 97.378891 -222.072296)
			(xy 97.367852 -222.095314) (xy 97.362518 -222.105982) (xy 97.362518 -223.41967) (xy 97.367852 -223.430338)
			(xy 97.378513 -223.453058) (xy 97.393575 -223.500928) (xy 97.401169 -223.550534) (xy 97.401634 -223.575626)
			(xy 97.401179 -223.600719) (xy 97.393581 -223.650326) (xy 97.37852 -223.698197) (xy 97.367852 -223.720914)
			(xy 97.362518 -223.731582) (xy 97.362518 -224.082864) (xy 97.422208 -224.082864) (xy 97.43059 -224.079816)
			(xy 97.443145 -224.075343) (xy 97.468831 -224.068219) (xy 97.481898 -224.065592) (xy 97.504758 -224.061274)
			(xy 97.709482 -223.706436) (xy 97.701862 -223.684338) (xy 97.693235 -223.65799) (xy 97.683906 -223.603344)
			(xy 97.68332 -223.575626) (xy 97.683828 -223.549719) (xy 97.691934 -223.498542) (xy 97.707946 -223.449263)
			(xy 97.731469 -223.403096) (xy 97.761925 -223.361177) (xy 97.798563 -223.324539) (xy 97.840482 -223.294083)
			(xy 97.886649 -223.27056) (xy 97.935928 -223.254548) (xy 97.987105 -223.246442) (xy 98.038919 -223.246442)
			(xy 98.090096 -223.254548) (xy 98.139375 -223.27056) (xy 98.185542 -223.294083) (xy 98.227461 -223.324539)
			(xy 98.264099 -223.361177) (xy 98.294555 -223.403096) (xy 98.318078 -223.449263) (xy 98.33409 -223.498542)
			(xy 98.342196 -223.549719) (xy 98.342704 -223.575626) (xy 98.342229 -223.600984) (xy 98.334444 -223.651099)
			(xy 98.319076 -223.699431) (xy 98.296488 -223.744839) (xy 98.267213 -223.786253) (xy 98.231942 -223.822696)
			(xy 98.191506 -223.853307) (xy 98.14686 -223.877366) (xy 98.099055 -223.894304) (xy 98.074226 -223.899476)
			(xy 98.051366 -223.903794) (xy 97.846642 -224.258632) (xy 97.854516 -224.280476) (xy 97.863096 -224.306895)
			(xy 97.872293 -224.36167) (xy 97.872804 -224.389442) (xy 98.153728 -224.389442) (xy 98.154236 -224.363555)
			(xy 98.162335 -224.312417) (xy 98.178334 -224.263177) (xy 98.20184 -224.217045) (xy 98.232272 -224.175158)
			(xy 98.268882 -224.138548) (xy 98.310769 -224.108116) (xy 98.356901 -224.08461) (xy 98.406141 -224.068611)
			(xy 98.457279 -224.060512) (xy 98.509053 -224.060512) (xy 98.560191 -224.068611) (xy 98.609431 -224.08461)
			(xy 98.655563 -224.108116) (xy 98.69745 -224.138548) (xy 98.73406 -224.175158) (xy 98.764492 -224.217045)
			(xy 98.787998 -224.263177) (xy 98.803997 -224.312417) (xy 98.812096 -224.363555) (xy 98.812604 -224.389442)
			(xy 99.093528 -224.389442) (xy 99.093935 -224.364105) (xy 99.101697 -224.314028) (xy 99.117029 -224.265728)
			(xy 99.13957 -224.220343) (xy 99.168789 -224.17894) (xy 99.203999 -224.142496) (xy 99.24437 -224.111867)
			(xy 99.288952 -224.087776) (xy 99.336695 -224.070789) (xy 99.361498 -224.065592) (xy 99.384358 -224.061274)
			(xy 99.589082 -223.706436) (xy 99.581462 -223.684338) (xy 99.572831 -223.657991) (xy 99.56351 -223.603344)
			(xy 99.56292 -223.575626) (xy 99.563428 -223.549719) (xy 99.571534 -223.498542) (xy 99.587546 -223.449263)
			(xy 99.611069 -223.403096) (xy 99.641525 -223.361177) (xy 99.678163 -223.324539) (xy 99.720082 -223.294083)
			(xy 99.766249 -223.27056) (xy 99.815528 -223.254548) (xy 99.866705 -223.246442) (xy 99.918519 -223.246442)
			(xy 99.969696 -223.254548) (xy 100.018975 -223.27056) (xy 100.065142 -223.294083) (xy 100.107061 -223.324539)
			(xy 100.143699 -223.361177) (xy 100.174155 -223.403096) (xy 100.197678 -223.449263) (xy 100.21369 -223.498542)
			(xy 100.221796 -223.549719) (xy 100.222304 -223.575626) (xy 100.221887 -223.600992) (xy 100.214134 -223.651127)
			(xy 100.198785 -223.69948) (xy 100.176203 -223.744908) (xy 100.146922 -223.786336) (xy 100.111634 -223.822783)
			(xy 100.071175 -223.853388) (xy 100.026501 -223.877427) (xy 99.978669 -223.894332) (xy 99.953826 -223.899476)
			(xy 99.930966 -223.903794) (xy 99.726242 -224.258632) (xy 99.734116 -224.280476) (xy 99.74269 -224.306896)
			(xy 99.75189 -224.36167) (xy 99.752404 -224.389442) (xy 100.033328 -224.389442) (xy 100.033836 -224.363555)
			(xy 100.041935 -224.312417) (xy 100.057934 -224.263177) (xy 100.08144 -224.217045) (xy 100.111872 -224.175158)
			(xy 100.148482 -224.138548) (xy 100.190369 -224.108116) (xy 100.236501 -224.08461) (xy 100.285741 -224.068611)
			(xy 100.336879 -224.060512) (xy 100.388653 -224.060512) (xy 100.439791 -224.068611) (xy 100.489031 -224.08461)
			(xy 100.535163 -224.108116) (xy 100.57705 -224.138548) (xy 100.61366 -224.175158) (xy 100.644092 -224.217045)
			(xy 100.667598 -224.263177) (xy 100.683597 -224.312417) (xy 100.691696 -224.363555) (xy 100.692204 -224.389442)
			(xy 100.973128 -224.389442) (xy 100.973535 -224.364105) (xy 100.981297 -224.314028) (xy 100.996629 -224.265728)
			(xy 101.01917 -224.220343) (xy 101.048389 -224.17894) (xy 101.083599 -224.142496) (xy 101.12397 -224.111867)
			(xy 101.168552 -224.087776) (xy 101.216295 -224.070789) (xy 101.241098 -224.065592) (xy 101.263958 -224.061274)
			(xy 101.468682 -223.706436) (xy 101.461062 -223.684338) (xy 101.452431 -223.657991) (xy 101.44311 -223.603344)
			(xy 101.44252 -223.575626) (xy 101.443028 -223.549719) (xy 101.451134 -223.498542) (xy 101.467146 -223.449263)
			(xy 101.490669 -223.403096) (xy 101.521125 -223.361177) (xy 101.557763 -223.324539) (xy 101.599682 -223.294083)
			(xy 101.645849 -223.27056) (xy 101.695128 -223.254548) (xy 101.746305 -223.246442) (xy 101.798119 -223.246442)
			(xy 101.849296 -223.254548) (xy 101.898575 -223.27056) (xy 101.944742 -223.294083) (xy 101.986661 -223.324539)
			(xy 102.023299 -223.361177) (xy 102.053755 -223.403096) (xy 102.077278 -223.449263) (xy 102.09329 -223.498542)
			(xy 102.101396 -223.549719) (xy 102.101904 -223.575626) (xy 102.101487 -223.600992) (xy 102.093734 -223.651127)
			(xy 102.078385 -223.69948) (xy 102.055803 -223.744908) (xy 102.026522 -223.786336) (xy 101.991234 -223.822783)
			(xy 101.950775 -223.853388) (xy 101.906101 -223.877427) (xy 101.858269 -223.894332) (xy 101.833426 -223.899476)
			(xy 101.810566 -223.903794) (xy 101.605842 -224.258632) (xy 101.613716 -224.280476) (xy 101.62229 -224.306896)
			(xy 101.63149 -224.36167) (xy 101.632004 -224.389442) (xy 101.631496 -224.415329) (xy 101.623397 -224.466467)
			(xy 101.607398 -224.515707) (xy 101.583892 -224.561839) (xy 101.55346 -224.603726) (xy 101.51685 -224.640336)
			(xy 101.474963 -224.670768) (xy 101.428831 -224.694274) (xy 101.379591 -224.710273) (xy 101.328453 -224.718372)
			(xy 101.276679 -224.718372) (xy 101.225541 -224.710273) (xy 101.176301 -224.694274) (xy 101.130169 -224.670768)
			(xy 101.088282 -224.640336) (xy 101.051672 -224.603726) (xy 101.02124 -224.561839) (xy 100.997734 -224.515707)
			(xy 100.981735 -224.466467) (xy 100.973636 -224.415329) (xy 100.973128 -224.389442) (xy 100.692204 -224.389442)
			(xy 100.69166 -224.417149) (xy 100.682474 -224.471796) (xy 100.673916 -224.498154) (xy 100.666042 -224.520252)
			(xy 100.87102 -224.87509) (xy 100.89388 -224.879408) (xy 100.918709 -224.884542) (xy 100.966488 -224.901501)
			(xy 101.011108 -224.925578) (xy 101.051514 -224.956202) (xy 101.086754 -224.992654) (xy 101.115997 -225.034071)
			(xy 101.138552 -225.079478) (xy 101.153888 -225.127804) (xy 101.161643 -225.177908) (xy 101.162104 -225.203258)
			(xy 101.161596 -225.229165) (xy 101.15349 -225.280342) (xy 101.137478 -225.329621) (xy 101.113955 -225.375788)
			(xy 101.083499 -225.417707) (xy 101.046861 -225.454345) (xy 101.004942 -225.484801) (xy 100.958775 -225.508324)
			(xy 100.909496 -225.524336) (xy 100.858319 -225.532442) (xy 100.806505 -225.532442) (xy 100.755328 -225.524336)
			(xy 100.706049 -225.508324) (xy 100.659882 -225.484801) (xy 100.617963 -225.454345) (xy 100.581325 -225.417707)
			(xy 100.550869 -225.375788) (xy 100.527346 -225.329621) (xy 100.511334 -225.280342) (xy 100.503228 -225.229165)
			(xy 100.50272 -225.203258) (xy 100.503327 -225.175541) (xy 100.512642 -225.120895) (xy 100.521262 -225.094546)
			(xy 100.529136 -225.072448) (xy 100.324158 -224.71761) (xy 100.301298 -224.713292) (xy 100.276485 -224.708145)
			(xy 100.228743 -224.691153) (xy 100.184163 -224.667056) (xy 100.143796 -224.63642) (xy 100.108593 -224.599968)
			(xy 100.079382 -224.558558) (xy 100.056852 -224.513166) (xy 100.041534 -224.46486) (xy 100.033788 -224.41478)
			(xy 100.033328 -224.389442) (xy 99.752404 -224.389442) (xy 99.751896 -224.415329) (xy 99.743797 -224.466467)
			(xy 99.727798 -224.515707) (xy 99.704292 -224.561839) (xy 99.67386 -224.603726) (xy 99.63725 -224.640336)
			(xy 99.595363 -224.670768) (xy 99.549231 -224.694274) (xy 99.499991 -224.710273) (xy 99.448853 -224.718372)
			(xy 99.397079 -224.718372) (xy 99.345941 -224.710273) (xy 99.296701 -224.694274) (xy 99.250569 -224.670768)
			(xy 99.208682 -224.640336) (xy 99.172072 -224.603726) (xy 99.14164 -224.561839) (xy 99.118134 -224.515707)
			(xy 99.102135 -224.466467) (xy 99.094036 -224.415329) (xy 99.093528 -224.389442) (xy 98.812604 -224.389442)
			(xy 98.81206 -224.417149) (xy 98.802874 -224.471796) (xy 98.794316 -224.498154) (xy 98.786442 -224.520252)
			(xy 98.99142 -224.87509) (xy 99.01428 -224.879408) (xy 99.039109 -224.884542) (xy 99.086888 -224.901501)
			(xy 99.131508 -224.925578) (xy 99.171914 -224.956202) (xy 99.207154 -224.992654) (xy 99.236397 -225.034071)
			(xy 99.258952 -225.079478) (xy 99.274288 -225.127804) (xy 99.282043 -225.177908) (xy 99.282504 -225.203258)
			(xy 99.281996 -225.229165) (xy 99.27389 -225.280342) (xy 99.257878 -225.329621) (xy 99.234355 -225.375788)
			(xy 99.203899 -225.417707) (xy 99.167261 -225.454345) (xy 99.125342 -225.484801) (xy 99.079175 -225.508324)
			(xy 99.029896 -225.524336) (xy 98.978719 -225.532442) (xy 98.926905 -225.532442) (xy 98.875728 -225.524336)
			(xy 98.826449 -225.508324) (xy 98.780282 -225.484801) (xy 98.738363 -225.454345) (xy 98.701725 -225.417707)
			(xy 98.671269 -225.375788) (xy 98.647746 -225.329621) (xy 98.631734 -225.280342) (xy 98.623628 -225.229165)
			(xy 98.62312 -225.203258) (xy 98.623727 -225.175541) (xy 98.633042 -225.120895) (xy 98.641662 -225.094546)
			(xy 98.649536 -225.072448) (xy 98.444558 -224.71761) (xy 98.421698 -224.713292) (xy 98.396885 -224.708145)
			(xy 98.349143 -224.691153) (xy 98.304563 -224.667056) (xy 98.264196 -224.63642) (xy 98.228993 -224.599968)
			(xy 98.199782 -224.558558) (xy 98.177252 -224.513166) (xy 98.161934 -224.46486) (xy 98.154188 -224.41478)
			(xy 98.153728 -224.389442) (xy 97.872804 -224.389442) (xy 97.872293 -224.415326) (xy 97.864188 -224.466457)
			(xy 97.848185 -224.515689) (xy 97.824677 -224.561813) (xy 97.794243 -224.603691) (xy 97.757633 -224.640293)
			(xy 97.715748 -224.670717) (xy 97.669619 -224.694214) (xy 97.620383 -224.710206) (xy 97.56925 -224.718299)
			(xy 97.543366 -224.71888) (xy 97.528101 -224.718716) (xy 97.497699 -224.715913) (xy 97.48266 -224.713292)
			(xy 97.467914 -224.71108) (xy 97.438288 -224.714322) (xy 97.410857 -224.725975) (xy 97.387954 -224.745047)
			(xy 97.371528 -224.769915) (xy 97.362977 -224.798465) (xy 97.362518 -224.813368) (xy 97.362518 -225.045016)
			(xy 97.367852 -225.055684) (xy 97.378865 -225.078711) (xy 97.394453 -225.127315) (xy 97.402383 -225.177738)
			(xy 97.402904 -225.203258) (xy 97.40241 -225.228781) (xy 97.394497 -225.279211) (xy 97.378885 -225.327811)
			(xy 97.367852 -225.350832) (xy 97.362518 -225.3615) (xy 97.362518 -226.085146) (xy 97.361902 -226.110101)
			(xy 97.352158 -226.159051) (xy 97.333052 -226.205159) (xy 97.305319 -226.246655) (xy 97.288096 -226.264724)
			(xy 95.98406 -227.56876) (xy 95.988124 -227.594414) (xy 95.989926 -227.606972) (xy 95.99183 -227.632273)
			(xy 95.991934 -227.64496) (xy 95.991457 -227.670751) (xy 95.983393 -227.721698) (xy 95.967457 -227.770756)
			(xy 95.944042 -227.816716) (xy 95.913725 -227.858447) (xy 95.877252 -227.894921) (xy 95.835521 -227.925239)
			(xy 95.789561 -227.948655) (xy 95.740504 -227.964592) (xy 95.689557 -227.972657) (xy 95.663766 -227.973128)
			(xy 95.651079 -227.97304) (xy 95.625777 -227.971134) (xy 95.61322 -227.969318) (xy 95.587566 -227.965254)
			(xy 93.61043 -229.94239) (xy 93.62186 -229.97287) (xy 93.631353 -230.000354) (xy 93.641567 -230.057591)
			(xy 93.64218 -230.086662) (xy 93.641704 -230.112454) (xy 93.63364 -230.163404) (xy 93.617704 -230.212464)
			(xy 93.59429 -230.258428) (xy 93.563973 -230.300163) (xy 93.527501 -230.336641) (xy 93.485771 -230.366964)
			(xy 93.439811 -230.390385) (xy 93.390752 -230.406328) (xy 93.339804 -230.4144) (xy 93.314012 -230.41483)
			(xy 93.284942 -230.414206) (xy 93.227707 -230.40399) (xy 93.20022 -230.39451) (xy 93.16974 -230.38308)
			(xy 91.750896 -231.801924) (xy 91.74734 -231.813608) (xy 91.738945 -231.838443) (xy 91.71539 -231.885274)
			(xy 91.68469 -231.927766) (xy 91.647627 -231.964838) (xy 91.605143 -231.995548) (xy 91.558318 -232.019115)
			(xy 91.533472 -232.027476) (xy 91.521788 -232.031032) (xy 91.226386 -232.326434) (xy 91.246706 -232.36047)
			(xy 91.261196 -232.386056) (xy 91.281816 -232.441114) (xy 91.292288 -232.498967) (xy 91.292934 -232.528364)
			(xy 91.292457 -232.554155) (xy 91.284392 -232.605101) (xy 91.268456 -232.654158) (xy 91.245041 -232.700118)
			(xy 91.214724 -232.741849) (xy 91.178251 -232.778322) (xy 91.13652 -232.80864) (xy 91.09056 -232.832056)
			(xy 91.041503 -232.847992) (xy 90.990556 -232.856057) (xy 90.964766 -232.856532) (xy 90.93537 -232.855875)
			(xy 90.87752 -232.845399) (xy 90.82246 -232.824787) (xy 90.796872 -232.810304) (xy 90.762836 -232.789984)
			(xy 89.782142 -233.770678) (xy 89.782142 -234.733338) (xy 89.800879 -234.752028) (xy 89.832677 -234.794331)
			(xy 89.857276 -234.841186) (xy 89.874039 -234.891382) (xy 89.882533 -234.943616) (xy 89.882537 -234.996537)
			(xy 89.87405 -235.048772) (xy 89.857294 -235.09897) (xy 89.832702 -235.145829) (xy 89.80091 -235.188137)
			(xy 89.782142 -235.206794) (xy 89.782142 -236.361224) (xy 89.80088 -236.379914) (xy 89.83268 -236.422217)
			(xy 89.857281 -236.469074) (xy 89.874047 -236.51927) (xy 89.882542 -236.571506) (xy 89.882547 -236.624428)
			(xy 89.874063 -236.676665) (xy 89.857307 -236.726865) (xy 89.832715 -236.773727) (xy 89.800924 -236.816036)
			(xy 89.782142 -236.83468) (xy 89.782142 -237.988856) (xy 89.800878 -238.007546) (xy 89.832672 -238.049848)
			(xy 89.857269 -238.096703) (xy 89.87403 -238.146897) (xy 89.882521 -238.19913) (xy 89.882523 -238.252048)
			(xy 89.874035 -238.304281) (xy 89.857277 -238.354477) (xy 89.832684 -238.401333) (xy 89.800892 -238.443637)
			(xy 89.782142 -238.462312) (xy 89.782142 -239.616488) (xy 89.800875 -239.635178) (xy 89.832665 -239.677479)
			(xy 89.857256 -239.724333) (xy 89.874012 -239.774524) (xy 89.8825 -239.826754) (xy 89.882498 -239.879668)
			(xy 89.874007 -239.931897) (xy 89.857247 -239.982088) (xy 89.832653 -240.028939) (xy 89.80086 -240.071239)
			(xy 89.782142 -240.089944) (xy 89.782142 -241.244374) (xy 89.800876 -241.263064) (xy 89.832668 -241.305366)
			(xy 89.857262 -241.35222) (xy 89.87402 -241.402412) (xy 89.882509 -241.454643) (xy 89.882509 -241.50756)
			(xy 89.874019 -241.55979) (xy 89.85726 -241.609983) (xy 89.832666 -241.656837) (xy 89.800874 -241.699138)
			(xy 89.782142 -241.71783) (xy 89.782142 -242.87226) (xy 89.800877 -242.89095) (xy 89.832671 -242.933252)
			(xy 89.857267 -242.980107) (xy 89.874027 -243.0303) (xy 89.882518 -243.082533) (xy 89.88252 -243.135451)
			(xy 89.874031 -243.187683) (xy 89.857274 -243.237878) (xy 89.83268 -243.284734) (xy 89.800888 -243.327037)
			(xy 89.782142 -243.345716) (xy 89.782142 -244.499892) (xy 89.800875 -244.518582) (xy 89.832664 -244.560883)
			(xy 89.857255 -244.607736) (xy 89.87401 -244.657927) (xy 89.882497 -244.710157) (xy 89.882495 -244.763071)
			(xy 89.874004 -244.815299) (xy 89.857244 -244.865489) (xy 89.832649 -244.91234) (xy 89.800856 -244.954639)
			(xy 89.782142 -244.973348) (xy 89.782142 -246.127778) (xy 89.800876 -246.146468) (xy 89.832667 -246.18877)
			(xy 89.85726 -246.235623) (xy 89.874018 -246.285816) (xy 89.882506 -246.338046) (xy 89.882506 -246.390962)
			(xy 89.874016 -246.443192) (xy 89.857257 -246.493384) (xy 89.832663 -246.540237) (xy 89.80087 -246.582538)
			(xy 89.782142 -246.601234) (xy 89.782142 -247.755156) (xy 89.800905 -247.77386) (xy 89.832748 -247.816198)
			(xy 89.857381 -247.8631) (xy 89.874166 -247.913347) (xy 89.882666 -247.965638) (xy 89.882662 -248.018615)
			(xy 89.874153 -248.070904) (xy 89.857361 -248.121149) (xy 89.83272 -248.168046) (xy 89.80087 -248.21038)
			(xy 89.782142 -248.22912) (xy 89.782142 -249.383296) (xy 89.800874 -249.401986) (xy 89.832663 -249.444287)
			(xy 89.857253 -249.49114) (xy 89.874008 -249.541331) (xy 89.882494 -249.59356) (xy 89.882492 -249.646473)
			(xy 89.874 -249.698701) (xy 89.85724 -249.748891) (xy 89.832645 -249.795741) (xy 89.800852 -249.838039)
			(xy 89.782142 -249.856752) (xy 89.782142 -254.42545) (xy 89.810336 -254.43942) (xy 89.833479 -254.451429)
			(xy 89.875967 -254.481644) (xy 89.913144 -254.518197) (xy 89.944075 -254.560168) (xy 89.967982 -254.6065)
			(xy 89.984262 -254.65603) (xy 89.992508 -254.70751) (xy 89.992512 -254.759647) (xy 89.984273 -254.811129)
			(xy 89.967998 -254.86066) (xy 89.944098 -254.906996) (xy 89.913172 -254.948971) (xy 89.876 -254.985528)
			(xy 89.833516 -255.01575) (xy 89.810336 -255.027684) (xy 89.782142 -255.041654) (xy 89.782142 -256.053336)
			(xy 89.810336 -256.067306) (xy 89.833472 -256.079315) (xy 89.875947 -256.109528) (xy 89.913111 -256.146077)
			(xy 89.944029 -256.188041) (xy 89.967925 -256.234366) (xy 89.984196 -256.283885) (xy 89.992434 -256.335355)
			(xy 89.992431 -256.387479) (xy 89.984188 -256.438948) (xy 89.967912 -256.488466) (xy 89.944012 -256.534788)
			(xy 89.913089 -256.576749) (xy 89.875921 -256.613293) (xy 89.833443 -256.643503) (xy 89.810336 -256.65557)
			(xy 89.782142 -256.66954) (xy 89.782142 -257.680968) (xy 89.810336 -257.694938) (xy 89.833478 -257.706946)
			(xy 89.875963 -257.737162) (xy 89.913138 -257.773714) (xy 89.944066 -257.815683) (xy 89.96797 -257.862014)
			(xy 89.984249 -257.911541) (xy 89.992493 -257.96302) (xy 89.992495 -258.015154) (xy 89.984255 -258.066633)
			(xy 89.96798 -258.116161) (xy 89.94408 -258.162494) (xy 89.913155 -258.204466) (xy 89.875984 -258.241021)
			(xy 89.833501 -258.27124) (xy 89.810336 -258.283202) (xy 89.782142 -258.297172) (xy 89.782142 -259.308854)
			(xy 89.810336 -259.322824) (xy 89.833479 -259.334832) (xy 89.875966 -259.365048) (xy 89.913143 -259.401601)
			(xy 89.944073 -259.443571) (xy 89.967979 -259.489903) (xy 89.984259 -259.539432) (xy 89.992505 -259.590912)
			(xy 89.992508 -259.643049) (xy 89.984269 -259.69453) (xy 89.967994 -259.744061) (xy 89.944094 -259.790396)
			(xy 89.913169 -259.83237) (xy 89.875996 -259.868927) (xy 89.833512 -259.899147) (xy 89.810336 -259.911088)
			(xy 89.782142 -259.925058) (xy 89.782142 -260.820154) (xy 91.507564 -262.545576) (xy 91.529916 -262.54456)
			(xy 91.544394 -262.544306) (xy 91.570183 -262.544811) (xy 91.621125 -262.552878) (xy 91.670178 -262.568815)
			(xy 91.716135 -262.592229) (xy 91.757863 -262.622544) (xy 91.794336 -262.659013) (xy 91.824654 -262.700738)
			(xy 91.848073 -262.746692) (xy 91.864014 -262.795744) (xy 91.872086 -262.846685) (xy 91.872562 -262.872474)
			(xy 91.872308 -262.886952) (xy 91.871292 -262.909304) (xy 93.210126 -264.248138) (xy 93.24467 -264.225532)
			(xy 93.26477 -264.212922) (xy 93.307832 -264.192994) (xy 93.353314 -264.179473) (xy 93.400269 -264.17264)
			(xy 93.423994 -264.172192) (xy 93.449783 -264.172697) (xy 93.500726 -264.180764) (xy 93.549781 -264.196701)
			(xy 93.595738 -264.220115) (xy 93.637467 -264.250429) (xy 93.673941 -264.286898) (xy 93.704261 -264.328623)
			(xy 93.727681 -264.374577) (xy 93.743625 -264.423629) (xy 93.751699 -264.474571) (xy 93.752162 -264.50036)
			(xy 93.751746 -264.524087) (xy 93.744915 -264.571046) (xy 93.731389 -264.616531) (xy 93.711451 -264.659593)
			(xy 93.698822 -264.679684) (xy 93.676216 -264.714228) (xy 93.953076 -264.991088) (xy 93.9673 -264.994136)
			(xy 93.992831 -265.000509) (xy 94.041598 -265.02027) (xy 94.086588 -265.047557) (xy 94.126651 -265.08167)
			(xy 94.16076 -265.121735) (xy 94.188043 -265.166728) (xy 94.2078 -265.215496) (xy 94.214188 -265.241024)
			(xy 94.217236 -265.255248) (xy 95.614744 -266.652756) (xy 95.64624 -266.639548) (xy 95.666496 -266.63138)
			(xy 95.708626 -266.619863) (xy 95.75191 -266.61403) (xy 95.773748 -266.61364) (xy 95.799533 -266.614149)
			(xy 95.850467 -266.622223) (xy 95.899511 -266.638165) (xy 95.945457 -266.661583) (xy 95.987175 -266.691899)
			(xy 96.023638 -266.728367) (xy 96.053947 -266.77009) (xy 96.077356 -266.816041) (xy 96.09329 -266.865088)
			(xy 96.101355 -266.916023) (xy 96.101916 -266.941808) (xy 96.101542 -266.963647) (xy 96.095714 -267.006934)
			(xy 96.08419 -267.049064) (xy 96.076008 -267.069316) (xy 96.0628 -267.100812) (xy 96.745298 -267.78331)
			(xy 102.49154 -267.78331)
		)
		(stroke
			(width 0)
			(type solid)
		)
		(fill yes)
		(layer "In8.Cu")
		(net "PVCCFA_EHV_CPU1")
	)
	(gr_poly
		(pts
			(xy 367.571274 -270.701262) (xy 367.59727 -270.692852) (xy 367.651146 -270.683782) (xy 367.678462 -270.683228)
			(xy 367.705781 -270.683767) (xy 367.759661 -270.692825) (xy 367.78565 -270.701262) (xy 367.793778 -270.704056)
			(xy 368.058192 -270.704056) (xy 368.069702 -270.685091) (xy 368.098216 -270.651111) (xy 368.132196 -270.622597)
			(xy 368.170611 -270.600416) (xy 368.212293 -270.585241) (xy 368.255977 -270.577532) (xy 368.278156 -270.577056)
			(xy 379.8824 -270.577056) (xy 380.086362 -270.373094) (xy 380.070614 -270.340582) (xy 380.06027 -270.318178)
			(xy 380.045671 -270.271042) (xy 380.038291 -270.222252) (xy 380.037848 -270.19758) (xy 380.038355 -270.171794)
			(xy 380.046426 -270.120857) (xy 380.062365 -270.07181) (xy 380.085781 -270.02586) (xy 380.116097 -269.984139)
			(xy 380.152566 -269.947674) (xy 380.194291 -269.917363) (xy 380.240243 -269.893952) (xy 380.289292 -269.878018)
			(xy 380.34023 -269.869952) (xy 380.366016 -269.869412) (xy 380.390688 -269.869856) (xy 380.439477 -269.877239)
			(xy 380.486613 -269.891837) (xy 380.509018 -269.902178) (xy 380.54153 -269.917926) (xy 381.91821 -268.541246)
			(xy 381.920496 -268.524228) (xy 381.924678 -268.498011) (xy 381.940396 -268.447304) (xy 381.964069 -268.399788)
			(xy 381.995079 -268.3567) (xy 382.032619 -268.319163) (xy 382.075709 -268.288156) (xy 382.123228 -268.264487)
			(xy 382.173935 -268.248773) (xy 382.20015 -268.244574) (xy 382.217168 -268.242288) (xy 382.477518 -267.981938)
			(xy 382.460642 -267.963544) (xy 382.432092 -267.922598) (xy 382.410082 -267.877797) (xy 382.39512 -267.830176)
			(xy 382.387554 -267.780836) (xy 382.387094 -267.755878) (xy 382.387601 -267.73009) (xy 382.395672 -267.679151)
			(xy 382.411611 -267.6301) (xy 382.435026 -267.584147) (xy 382.465341 -267.542421) (xy 382.501809 -267.505951)
			(xy 382.543533 -267.475635) (xy 382.589486 -267.452217) (xy 382.638535 -267.436276) (xy 382.689474 -267.428203)
			(xy 382.715262 -267.42771) (xy 382.740216 -267.428201) (xy 382.789542 -267.435801) (xy 382.837153 -267.45077)
			(xy 382.881953 -267.472765) (xy 382.922913 -267.501281) (xy 382.941322 -267.518134) (xy 387.197092 -263.262364)
			(xy 387.206494 -263.25235) (xy 387.220064 -263.22848) (xy 387.226784 -263.201858) (xy 387.226169 -263.174407)
			(xy 387.218263 -263.148112) (xy 387.203637 -263.124874) (xy 387.19379 -263.115298) (xy 387.173916 -263.096494)
			(xy 387.140096 -263.053491) (xy 387.113872 -263.005476) (xy 387.095972 -262.953778) (xy 387.086889 -262.899828)
			(xy 387.086348 -262.872474) (xy 387.086797 -262.847974) (xy 387.09407 -262.799518) (xy 387.108464 -262.752681)
			(xy 387.129662 -262.708504) (xy 387.15719 -262.667969) (xy 387.190439 -262.631977) (xy 387.228668 -262.601326)
			(xy 387.271029 -262.576699) (xy 387.316579 -262.558643) (xy 387.340348 -262.552688) (xy 387.379718 -262.543544)
			(xy 387.379718 -258.318) (xy 387.340348 -258.308856) (xy 387.315201 -258.302498) (xy 387.267164 -258.282939)
			(xy 387.222799 -258.256071) (xy 387.18321 -258.222561) (xy 387.149383 -258.183244) (xy 387.122159 -258.139096)
			(xy 387.102214 -258.091218) (xy 387.090046 -258.040798) (xy 387.085957 -257.989093) (xy 387.090048 -257.937388)
			(xy 387.102218 -257.886969) (xy 387.122165 -257.839092) (xy 387.149391 -257.794945) (xy 387.18322 -257.755629)
			(xy 387.22281 -257.722121) (xy 387.267176 -257.695255) (xy 387.315214 -257.675698) (xy 387.340348 -257.669284)
			(xy 387.379718 -257.66014) (xy 387.379718 -254.487172) (xy 387.345174 -254.475488) (xy 387.321159 -254.466817)
			(xy 387.275943 -254.443108) (xy 387.234941 -254.412686) (xy 387.199143 -254.376284) (xy 387.16941 -254.33478)
			(xy 387.14646 -254.289174) (xy 387.130845 -254.240565) (xy 387.122943 -254.190125) (xy 387.122943 -254.13907)
			(xy 387.130846 -254.08863) (xy 387.146462 -254.040021) (xy 387.169412 -253.994415) (xy 387.199146 -253.952912)
			(xy 387.234945 -253.916511) (xy 387.275947 -253.886089) (xy 387.321164 -253.862381) (xy 387.345174 -253.853696)
			(xy 387.379718 -253.842012) (xy 387.379718 -244.726968) (xy 387.358589 -244.711481) (xy 387.321077 -244.674918)
			(xy 387.289854 -244.632858) (xy 387.265713 -244.586369) (xy 387.249268 -244.536634) (xy 387.240938 -244.484917)
			(xy 387.240934 -244.432534) (xy 387.249256 -244.380816) (xy 387.265693 -244.331078) (xy 387.289827 -244.284585)
			(xy 387.321044 -244.24252) (xy 387.35855 -244.205951) (xy 387.379718 -244.19052) (xy 387.379718 -241.524282)
			(xy 387.345936 -241.51209) (xy 387.322399 -241.503164) (xy 387.278168 -241.479137) (xy 387.238124 -241.448637)
			(xy 387.203207 -241.41238) (xy 387.174237 -241.371216) (xy 387.151892 -241.326111) (xy 387.136697 -241.278123)
			(xy 387.129009 -241.228377) (xy 387.129008 -241.178041) (xy 387.136693 -241.128294) (xy 387.151885 -241.080305)
			(xy 387.174228 -241.035199) (xy 387.203196 -240.994033) (xy 387.238111 -240.957775) (xy 387.278153 -240.927273)
			(xy 387.322383 -240.903243) (xy 387.345936 -240.894362) (xy 387.379718 -240.88217) (xy 387.379718 -234.233974)
			(xy 383.560828 -230.415084) (xy 383.540254 -230.41483) (xy 383.51498 -230.413975) (xy 383.465136 -230.40545)
			(xy 383.417189 -230.389381) (xy 383.372275 -230.366147) (xy 383.331456 -230.336298) (xy 383.2957 -230.300541)
			(xy 383.265851 -230.259722) (xy 383.242618 -230.214807) (xy 383.226549 -230.16686) (xy 383.218025 -230.117016)
			(xy 383.217166 -230.091742) (xy 383.216912 -230.071168) (xy 381.866902 -228.721158) (xy 381.83312 -228.741224)
			(xy 381.80759 -228.75561) (xy 381.752689 -228.776085) (xy 381.695031 -228.786518) (xy 381.665734 -228.787198)
			(xy 381.639942 -228.786721) (xy 381.588992 -228.778657) (xy 381.53993 -228.762721) (xy 381.493966 -228.739307)
			(xy 381.45223 -228.708991) (xy 381.415751 -228.672519) (xy 381.385426 -228.630789) (xy 381.362003 -228.584829)
			(xy 381.346058 -228.535771) (xy 381.337984 -228.484822) (xy 381.337566 -228.45903) (xy 381.338076 -228.432191)
			(xy 381.346767 -228.379222) (xy 381.36397 -228.328376) (xy 381.389228 -228.281012) (xy 381.40513 -228.259386)
			(xy 381.10668 -227.960936) (xy 381.09525 -227.95738) (xy 381.070708 -227.948964) (xy 381.02444 -227.925496)
			(xy 380.98244 -227.89504) (xy 380.945756 -227.858354) (xy 380.9153 -227.816354) (xy 380.891833 -227.770085)
			(xy 380.883414 -227.745544) (xy 380.879858 -227.734114) (xy 380.4412 -227.295456) (xy 377.168156 -227.295456)
			(xy 377.143198 -227.29488) (xy 377.094242 -227.285133) (xy 377.048128 -227.266021) (xy 377.00663 -227.238279)
			(xy 376.988578 -227.221034) (xy 376.92457 -227.157026) (xy 376.908822 -227.154232) (xy 376.884305 -227.14938)
			(xy 376.837006 -227.133242) (xy 376.7927 -227.110119) (xy 376.752411 -227.080548) (xy 376.71707 -227.04521)
			(xy 376.687495 -227.004924) (xy 376.664369 -226.96062) (xy 376.648227 -226.913322) (xy 376.643392 -226.888802)
			(xy 376.640598 -226.873054) (xy 375.388378 -225.620834) (xy 375.374425 -225.60636) (xy 375.350818 -225.57382)
			(xy 375.341388 -225.556064) (xy 375.334027 -225.542763) (xy 375.312939 -225.52089) (xy 375.286348 -225.506191)
			(xy 375.256609 -225.499968) (xy 375.226355 -225.502772) (xy 375.212102 -225.508058) (xy 375.182077 -225.519537)
			(xy 375.119016 -225.53195) (xy 375.08688 -225.532696) (xy 375.060986 -225.532187) (xy 375.009836 -225.524087)
			(xy 374.960582 -225.508089) (xy 374.914434 -225.484587) (xy 374.872529 -225.454159) (xy 374.835896 -225.417553)
			(xy 374.805438 -225.375669) (xy 374.781902 -225.329539) (xy 374.765869 -225.280296) (xy 374.757732 -225.229151)
			(xy 374.757188 -225.203258) (xy 374.75778 -225.17554) (xy 374.767105 -225.120894) (xy 374.77573 -225.094546)
			(xy 374.783604 -225.072448) (xy 374.578626 -224.71761) (xy 374.555766 -224.713292) (xy 374.530965 -224.708093)
			(xy 374.483227 -224.691103) (xy 374.438651 -224.667009) (xy 374.398285 -224.636379) (xy 374.363081 -224.599934)
			(xy 374.333867 -224.558532) (xy 374.31133 -224.513149) (xy 374.296002 -224.464851) (xy 374.288244 -224.414778)
			(xy 374.287796 -224.389442) (xy 374.288304 -224.363555) (xy 374.296403 -224.312417) (xy 374.312402 -224.263177)
			(xy 374.335908 -224.217045) (xy 374.36634 -224.175158) (xy 374.40295 -224.138548) (xy 374.444837 -224.108116)
			(xy 374.490969 -224.08461) (xy 374.540209 -224.068611) (xy 374.591347 -224.060512) (xy 374.643121 -224.060512)
			(xy 374.694259 -224.068611) (xy 374.743499 -224.08461) (xy 374.789631 -224.108116) (xy 374.831518 -224.138548)
			(xy 374.868128 -224.175158) (xy 374.89856 -224.217045) (xy 374.922066 -224.263177) (xy 374.938065 -224.312417)
			(xy 374.946164 -224.363555) (xy 374.946672 -224.389442) (xy 374.946148 -224.417151) (xy 374.936958 -224.4718)
			(xy 374.928384 -224.498154) (xy 374.92051 -224.520252) (xy 375.125488 -224.87509) (xy 375.148348 -224.879408)
			(xy 375.182892 -224.888044) (xy 375.195998 -224.891574) (xy 375.223121 -224.892335) (xy 375.249486 -224.885926)
			(xy 375.273233 -224.872799) (xy 375.292683 -224.85388) (xy 375.306463 -224.830507) (xy 375.3136 -224.804329)
			(xy 375.313956 -224.790762) (xy 375.313956 -224.611946) (xy 375.2978 -224.593611) (xy 375.270518 -224.553068)
			(xy 375.249515 -224.508945) (xy 375.23525 -224.462207) (xy 375.228036 -224.413875) (xy 375.227596 -224.389442)
			(xy 375.228017 -224.365005) (xy 375.235199 -224.316663) (xy 375.249455 -224.269916) (xy 375.270472 -224.225793)
			(xy 375.297786 -224.185265) (xy 375.313956 -224.166938) (xy 375.313956 -222.982028) (xy 375.2963 -222.961759)
			(xy 375.267162 -222.916591) (xy 375.245776 -222.867278) (xy 375.232713 -222.815139) (xy 375.228323 -222.761567)
			(xy 375.232724 -222.707997) (xy 375.245797 -222.65586) (xy 375.267193 -222.606551) (xy 375.296339 -222.561389)
			(xy 375.313956 -222.541084) (xy 375.313956 -222.360236) (xy 375.313522 -222.346681) (xy 375.306373 -222.320531)
			(xy 375.292596 -222.297182) (xy 375.273162 -222.278281) (xy 375.24944 -222.265158) (xy 375.223101 -222.258739)
			(xy 375.196001 -222.259475) (xy 375.182892 -222.262954) (xy 375.159457 -222.269672) (xy 375.111254 -222.276948)
			(xy 375.08688 -222.277432) (xy 375.060973 -222.276923) (xy 375.009796 -222.268815) (xy 374.960517 -222.252802)
			(xy 374.91435 -222.229278) (xy 374.87243 -222.198823) (xy 374.83579 -222.162185) (xy 374.805332 -222.120267)
			(xy 374.781806 -222.074101) (xy 374.76579 -222.024824) (xy 374.757679 -221.973647) (xy 374.757188 -221.94774)
			(xy 374.75765 -221.922393) (xy 374.765408 -221.872295) (xy 374.780748 -221.823976) (xy 374.803307 -221.778577)
			(xy 374.832552 -221.737169) (xy 374.867795 -221.700729) (xy 374.908203 -221.670116) (xy 374.952823 -221.646053)
			(xy 375.000602 -221.629107) (xy 375.025412 -221.62389) (xy 375.048272 -221.619572) (xy 375.253504 -221.264226)
			(xy 375.24563 -221.242128) (xy 375.237167 -221.215884) (xy 375.228103 -221.161494) (xy 375.227596 -221.133924)
			(xy 375.228019 -221.109488) (xy 375.235203 -221.061147) (xy 375.249461 -221.014401) (xy 375.270479 -220.97028)
			(xy 375.297795 -220.929754) (xy 375.313956 -220.91142) (xy 375.313956 -219.72651) (xy 375.296293 -219.706241)
			(xy 375.267142 -219.661071) (xy 375.245743 -219.611753) (xy 375.232669 -219.559608) (xy 375.228268 -219.506028)
			(xy 375.23266 -219.452448) (xy 375.245725 -219.4003) (xy 375.267115 -219.350979) (xy 375.296259 -219.305804)
			(xy 375.313956 -219.285566) (xy 375.313956 -219.104718) (xy 375.313532 -219.091155) (xy 375.306396 -219.064986)
			(xy 375.292624 -219.041617) (xy 375.273186 -219.022698) (xy 375.249453 -219.009563) (xy 375.2231 -219.003139)
			(xy 375.195985 -219.003878) (xy 375.182892 -219.007436) (xy 375.159451 -219.0141) (xy 375.111246 -219.021246)
			(xy 375.08688 -219.02166) (xy 375.060987 -219.021151) (xy 375.009839 -219.013051) (xy 374.960587 -218.997052)
			(xy 374.914442 -218.97355) (xy 374.87254 -218.943121) (xy 374.835911 -218.906514) (xy 374.805456 -218.86463)
			(xy 374.781925 -218.8185) (xy 374.765897 -218.769257) (xy 374.757765 -218.718114) (xy 374.757188 -218.692222)
			(xy 374.757652 -218.666875) (xy 374.765412 -218.61678) (xy 374.780753 -218.568464) (xy 374.803313 -218.523067)
			(xy 374.832559 -218.481661) (xy 374.867802 -218.445223) (xy 374.908209 -218.414612) (xy 374.952828 -218.39055)
			(xy 375.000606 -218.373606) (xy 375.025412 -218.368372) (xy 375.048272 -218.364054) (xy 375.253504 -218.008708)
			(xy 375.24563 -217.98661) (xy 375.237169 -217.960365) (xy 375.228108 -217.905976) (xy 375.227596 -217.878406)
			(xy 375.22802 -217.85397) (xy 375.235206 -217.805631) (xy 375.249467 -217.758886) (xy 375.270486 -217.714767)
			(xy 375.297803 -217.674244) (xy 375.313956 -217.655902) (xy 375.313956 -216.470992) (xy 375.296294 -216.450723)
			(xy 375.267146 -216.405553) (xy 375.24575 -216.356237) (xy 375.232678 -216.304092) (xy 375.22828 -216.250515)
			(xy 375.232674 -216.196937) (xy 375.245741 -216.144791) (xy 375.267132 -216.095473) (xy 375.296276 -216.050301)
			(xy 375.313956 -216.030048) (xy 375.313956 -215.281256) (xy 375.314532 -215.256298) (xy 375.32428 -215.207342)
			(xy 375.343392 -215.161229) (xy 375.371135 -215.119732) (xy 375.388378 -215.101678) (xy 375.870978 -214.619078)
			(xy 375.88902 -214.60182) (xy 375.930514 -214.574066) (xy 375.976632 -214.554957) (xy 376.025595 -214.545231)
			(xy 376.050556 -214.544656) (xy 381.804418 -214.544656) (xy 381.810514 -214.500968) (xy 381.814651 -214.475175)
			(xy 381.830024 -214.425252) (xy 381.853107 -214.378394) (xy 381.883319 -214.335782) (xy 381.919897 -214.298491)
			(xy 381.961919 -214.267462) (xy 382.008323 -214.243478) (xy 382.057939 -214.227145) (xy 382.109516 -214.218874)
			(xy 382.161752 -214.218874) (xy 382.213329 -214.227145) (xy 382.262945 -214.243478) (xy 382.309349 -214.267462)
			(xy 382.351371 -214.298491) (xy 382.387949 -214.335782) (xy 382.418161 -214.378394) (xy 382.441244 -214.425252)
			(xy 382.456617 -214.475175) (xy 382.460754 -214.500968) (xy 382.46685 -214.544656) (xy 383.684018 -214.544656)
			(xy 383.690114 -214.500968) (xy 383.694251 -214.475175) (xy 383.709624 -214.425252) (xy 383.732707 -214.378394)
			(xy 383.762919 -214.335782) (xy 383.799497 -214.298491) (xy 383.841519 -214.267462) (xy 383.887923 -214.243478)
			(xy 383.937539 -214.227145) (xy 383.989116 -214.218874) (xy 384.041352 -214.218874) (xy 384.092929 -214.227145)
			(xy 384.142545 -214.243478) (xy 384.188949 -214.267462) (xy 384.230971 -214.298491) (xy 384.267549 -214.335782)
			(xy 384.297761 -214.378394) (xy 384.320844 -214.425252) (xy 384.336217 -214.475175) (xy 384.340354 -214.500968)
			(xy 384.34645 -214.544656) (xy 409.403296 -214.544656) (xy 409.966668 -213.981284) (xy 409.966668 -192.405762)
			(xy 409.943679 -192.392077) (xy 409.901423 -192.359266) (xy 409.864161 -192.320877) (xy 409.832624 -192.277661)
			(xy 409.80743 -192.230465) (xy 409.789072 -192.180213) (xy 409.77791 -192.127891) (xy 409.774163 -192.074523)
			(xy 409.777904 -192.021154) (xy 409.789059 -191.968831) (xy 409.807411 -191.918577) (xy 409.8326 -191.871378)
			(xy 409.864131 -191.828158) (xy 409.901388 -191.789764) (xy 409.943641 -191.756948) (xy 409.966668 -191.74333)
			(xy 409.966668 -168.08831) (xy 409.966414 -168.085008) (xy 409.964382 -168.05402) (xy 409.966414 -168.023032)
			(xy 409.966668 -168.01973) (xy 409.966668 -167.11295) (xy 409.637738 -166.78402) (xy 398.071086 -166.78402)
			(xy 363.553756 -201.30135) (xy 363.553756 -206.024988) (xy 380.650506 -206.024988) (xy 380.654487 -205.891968)
			(xy 380.666416 -205.759423) (xy 380.686251 -205.62783) (xy 380.71392 -205.497658) (xy 380.749324 -205.369373)
			(xy 380.792337 -205.243436) (xy 380.842804 -205.120297) (xy 380.900545 -205.000396) (xy 380.965354 -204.884163)
			(xy 381.036998 -204.772013) (xy 381.11522 -204.664349) (xy 381.199741 -204.561556) (xy 381.290259 -204.464001)
			(xy 381.386448 -204.372035) (xy 381.487966 -204.285985) (xy 381.594447 -204.206161) (xy 381.705512 -204.132848)
			(xy 381.820763 -204.066308) (xy 381.939787 -204.006779) (xy 382.062158 -203.954475) (xy 382.187437 -203.909583)
			(xy 382.315178 -203.872264) (xy 382.444921 -203.842651) (xy 382.576203 -203.82085) (xy 382.708554 -203.80694)
			(xy 382.8415 -203.800969) (xy 382.974565 -203.80296) (xy 383.107273 -203.812905) (xy 383.239149 -203.830769)
			(xy 383.36972 -203.856487) (xy 383.49852 -203.889968) (xy 383.625086 -203.931092) (xy 383.748967 -203.979712)
			(xy 383.869718 -204.035653) (xy 383.986908 -204.098715) (xy 384.100117 -204.168673) (xy 384.208939 -204.245277)
			(xy 384.312985 -204.328251) (xy 384.411883 -204.417299) (xy 384.505278 -204.512102) (xy 384.592836 -204.61232)
			(xy 384.674245 -204.717596) (xy 384.749211 -204.827552) (xy 384.817468 -204.941794) (xy 384.87877 -205.059914)
			(xy 384.932899 -205.181489) (xy 384.97966 -205.306083) (xy 385.018886 -205.433251) (xy 385.050436 -205.562537)
			(xy 385.074199 -205.693478) (xy 385.090088 -205.825606) (xy 385.098046 -205.958448) (xy 385.098544 -206.024988)
			(xy 385.098046 -206.091528) (xy 385.090088 -206.22437) (xy 385.074199 -206.356498) (xy 385.050436 -206.487439)
			(xy 385.018886 -206.616725) (xy 384.97966 -206.743893) (xy 384.932899 -206.868487) (xy 384.87877 -206.990062)
			(xy 384.817468 -207.108182) (xy 384.749211 -207.222424) (xy 384.674245 -207.33238) (xy 384.592836 -207.437656)
			(xy 384.505278 -207.537874) (xy 384.411883 -207.632677) (xy 384.312985 -207.721725) (xy 384.208939 -207.804699)
			(xy 384.100117 -207.881303) (xy 383.986908 -207.951261) (xy 383.869718 -208.014323) (xy 383.748967 -208.070264)
			(xy 383.625086 -208.118884) (xy 383.49852 -208.160008) (xy 383.36972 -208.193489) (xy 383.239149 -208.219207)
			(xy 383.107273 -208.237071) (xy 382.974565 -208.247016) (xy 382.8415 -208.249007) (xy 382.708554 -208.243036)
			(xy 382.576203 -208.229126) (xy 382.444921 -208.207325) (xy 382.315178 -208.177712) (xy 382.187437 -208.140393)
			(xy 382.062158 -208.095501) (xy 381.939787 -208.043197) (xy 381.820763 -207.983668) (xy 381.705512 -207.917128)
			(xy 381.594447 -207.843815) (xy 381.487966 -207.763991) (xy 381.386448 -207.677941) (xy 381.290259 -207.585975)
			(xy 381.199741 -207.48842) (xy 381.11522 -207.385627) (xy 381.036998 -207.277963) (xy 380.965354 -207.165813)
			(xy 380.900545 -207.04958) (xy 380.842804 -206.929679) (xy 380.792337 -206.80654) (xy 380.749324 -206.680603)
			(xy 380.71392 -206.552318) (xy 380.686251 -206.422146) (xy 380.666416 -206.290553) (xy 380.654487 -206.158008)
			(xy 380.650506 -206.024988) (xy 363.553756 -206.024988) (xy 363.553756 -216.002108) (xy 363.572838 -216.019227)
			(xy 363.605965 -216.058346) (xy 363.632606 -216.102141) (xy 363.652112 -216.149546) (xy 363.664007 -216.199408)
			(xy 363.668004 -216.250513) (xy 363.664003 -216.301618) (xy 363.652104 -216.351479) (xy 363.632594 -216.398883)
			(xy 363.60595 -216.442675) (xy 363.572819 -216.481792) (xy 363.553756 -216.498932) (xy 363.553756 -217.064336)
			(xy 364.419388 -217.064336) (xy 364.419896 -217.038429) (xy 364.428002 -216.987252) (xy 364.444014 -216.937973)
			(xy 364.467537 -216.891806) (xy 364.497993 -216.849887) (xy 364.534631 -216.813249) (xy 364.57655 -216.782793)
			(xy 364.622717 -216.75927) (xy 364.671996 -216.743258) (xy 364.723173 -216.735152) (xy 364.774987 -216.735152)
			(xy 364.826164 -216.743258) (xy 364.875443 -216.75927) (xy 364.92161 -216.782793) (xy 364.963529 -216.813249)
			(xy 365.000167 -216.849887) (xy 365.030623 -216.891806) (xy 365.054146 -216.937973) (xy 365.070158 -216.987252)
			(xy 365.078264 -217.038429) (xy 365.078772 -217.064336) (xy 366.298988 -217.064336) (xy 366.299496 -217.038429)
			(xy 366.307602 -216.987252) (xy 366.323614 -216.937973) (xy 366.347137 -216.891806) (xy 366.377593 -216.849887)
			(xy 366.414231 -216.813249) (xy 366.45615 -216.782793) (xy 366.502317 -216.75927) (xy 366.551596 -216.743258)
			(xy 366.602773 -216.735152) (xy 366.654587 -216.735152) (xy 366.705764 -216.743258) (xy 366.755043 -216.75927)
			(xy 366.80121 -216.782793) (xy 366.843129 -216.813249) (xy 366.879767 -216.849887) (xy 366.910223 -216.891806)
			(xy 366.933746 -216.937973) (xy 366.949758 -216.987252) (xy 366.957864 -217.038429) (xy 366.958372 -217.064336)
			(xy 368.178588 -217.064336) (xy 368.179096 -217.038429) (xy 368.187202 -216.987252) (xy 368.203214 -216.937973)
			(xy 368.226737 -216.891806) (xy 368.257193 -216.849887) (xy 368.293831 -216.813249) (xy 368.33575 -216.782793)
			(xy 368.381917 -216.75927) (xy 368.431196 -216.743258) (xy 368.482373 -216.735152) (xy 368.534187 -216.735152)
			(xy 368.585364 -216.743258) (xy 368.634643 -216.75927) (xy 368.68081 -216.782793) (xy 368.722729 -216.813249)
			(xy 368.759367 -216.849887) (xy 368.789823 -216.891806) (xy 368.813346 -216.937973) (xy 368.829358 -216.987252)
			(xy 368.837464 -217.038429) (xy 368.837972 -217.064336) (xy 370.058188 -217.064336) (xy 370.058696 -217.038429)
			(xy 370.066802 -216.987252) (xy 370.082814 -216.937973) (xy 370.106337 -216.891806) (xy 370.136793 -216.849887)
			(xy 370.173431 -216.813249) (xy 370.21535 -216.782793) (xy 370.261517 -216.75927) (xy 370.310796 -216.743258)
			(xy 370.361973 -216.735152) (xy 370.413787 -216.735152) (xy 370.464964 -216.743258) (xy 370.514243 -216.75927)
			(xy 370.56041 -216.782793) (xy 370.602329 -216.813249) (xy 370.638967 -216.849887) (xy 370.669423 -216.891806)
			(xy 370.692946 -216.937973) (xy 370.708958 -216.987252) (xy 370.717064 -217.038429) (xy 370.717572 -217.064336)
			(xy 371.937788 -217.064336) (xy 371.938296 -217.038429) (xy 371.946402 -216.987252) (xy 371.962414 -216.937973)
			(xy 371.985937 -216.891806) (xy 372.016393 -216.849887) (xy 372.053031 -216.813249) (xy 372.09495 -216.782793)
			(xy 372.141117 -216.75927) (xy 372.190396 -216.743258) (xy 372.241573 -216.735152) (xy 372.293387 -216.735152)
			(xy 372.344564 -216.743258) (xy 372.393843 -216.75927) (xy 372.44001 -216.782793) (xy 372.481929 -216.813249)
			(xy 372.518567 -216.849887) (xy 372.549023 -216.891806) (xy 372.572546 -216.937973) (xy 372.588558 -216.987252)
			(xy 372.596664 -217.038429) (xy 372.597172 -217.064336) (xy 373.817388 -217.064336) (xy 373.817896 -217.038429)
			(xy 373.826002 -216.987252) (xy 373.842014 -216.937973) (xy 373.865537 -216.891806) (xy 373.895993 -216.849887)
			(xy 373.932631 -216.813249) (xy 373.97455 -216.782793) (xy 374.020717 -216.75927) (xy 374.069996 -216.743258)
			(xy 374.121173 -216.735152) (xy 374.172987 -216.735152) (xy 374.224164 -216.743258) (xy 374.273443 -216.75927)
			(xy 374.31961 -216.782793) (xy 374.361529 -216.813249) (xy 374.398167 -216.849887) (xy 374.428623 -216.891806)
			(xy 374.452146 -216.937973) (xy 374.468158 -216.987252) (xy 374.476264 -217.038429) (xy 374.476772 -217.064336)
			(xy 374.476159 -217.091989) (xy 374.466838 -217.146507) (xy 374.45823 -217.172794) (xy 374.45061 -217.194892)
			(xy 374.655842 -217.550238) (xy 374.678702 -217.554556) (xy 374.703503 -217.559751) (xy 374.751242 -217.57674)
			(xy 374.795819 -217.600833) (xy 374.836184 -217.631463) (xy 374.871388 -217.667908) (xy 374.9006 -217.709312)
			(xy 374.923133 -217.754697) (xy 374.938456 -217.802996) (xy 374.946208 -217.85307) (xy 374.946672 -217.878406)
			(xy 374.946164 -217.904293) (xy 374.938065 -217.955431) (xy 374.922066 -218.004671) (xy 374.89856 -218.050803)
			(xy 374.868128 -218.09269) (xy 374.831518 -218.1293) (xy 374.789631 -218.159732) (xy 374.743499 -218.183238)
			(xy 374.694259 -218.199237) (xy 374.643121 -218.207336) (xy 374.591347 -218.207336) (xy 374.540209 -218.199237)
			(xy 374.490969 -218.183238) (xy 374.444837 -218.159732) (xy 374.40295 -218.1293) (xy 374.36634 -218.09269)
			(xy 374.335908 -218.050803) (xy 374.312402 -218.004671) (xy 374.296403 -217.955431) (xy 374.288304 -217.904293)
			(xy 374.287796 -217.878406) (xy 374.288327 -217.850698) (xy 374.297521 -217.796051) (xy 374.306084 -217.769694)
			(xy 374.313958 -217.747596) (xy 374.10898 -217.392504) (xy 374.08612 -217.388186) (xy 374.061275 -217.38302)
			(xy 374.013426 -217.366126) (xy 373.968733 -217.342096) (xy 373.928253 -217.311499) (xy 373.892941 -217.275058)
			(xy 373.863633 -217.233634) (xy 373.841022 -217.188207) (xy 373.825643 -217.13985) (xy 373.817858 -217.089708)
			(xy 373.817388 -217.064336) (xy 372.597172 -217.064336) (xy 372.596559 -217.091989) (xy 372.587238 -217.146507)
			(xy 372.57863 -217.172794) (xy 372.57101 -217.194892) (xy 372.776242 -217.550238) (xy 372.799102 -217.554556)
			(xy 372.823903 -217.559751) (xy 372.871642 -217.57674) (xy 372.916219 -217.600833) (xy 372.956584 -217.631463)
			(xy 372.991788 -217.667908) (xy 373.021 -217.709312) (xy 373.043533 -217.754697) (xy 373.058856 -217.802996)
			(xy 373.066608 -217.85307) (xy 373.067072 -217.878406) (xy 373.066564 -217.904293) (xy 373.058465 -217.955431)
			(xy 373.042466 -218.004671) (xy 373.01896 -218.050803) (xy 372.988528 -218.09269) (xy 372.951918 -218.1293)
			(xy 372.910031 -218.159732) (xy 372.863899 -218.183238) (xy 372.814659 -218.199237) (xy 372.763521 -218.207336)
			(xy 372.711747 -218.207336) (xy 372.660609 -218.199237) (xy 372.611369 -218.183238) (xy 372.565237 -218.159732)
			(xy 372.52335 -218.1293) (xy 372.48674 -218.09269) (xy 372.456308 -218.050803) (xy 372.432802 -218.004671)
			(xy 372.416803 -217.955431) (xy 372.408704 -217.904293) (xy 372.408196 -217.878406) (xy 372.408727 -217.850698)
			(xy 372.417921 -217.796051) (xy 372.426484 -217.769694) (xy 372.434358 -217.747596) (xy 372.22938 -217.392504)
			(xy 372.20652 -217.388186) (xy 372.181675 -217.38302) (xy 372.133826 -217.366126) (xy 372.089133 -217.342096)
			(xy 372.048653 -217.311499) (xy 372.013341 -217.275058) (xy 371.984033 -217.233634) (xy 371.961422 -217.188207)
			(xy 371.946043 -217.13985) (xy 371.938258 -217.089708) (xy 371.937788 -217.064336) (xy 370.717572 -217.064336)
			(xy 370.716959 -217.091989) (xy 370.707638 -217.146507) (xy 370.69903 -217.172794) (xy 370.69141 -217.194892)
			(xy 370.896642 -217.550238) (xy 370.919502 -217.554556) (xy 370.944303 -217.559751) (xy 370.992042 -217.57674)
			(xy 371.036619 -217.600833) (xy 371.076984 -217.631463) (xy 371.112188 -217.667908) (xy 371.1414 -217.709312)
			(xy 371.163933 -217.754697) (xy 371.179256 -217.802996) (xy 371.187008 -217.85307) (xy 371.187472 -217.878406)
			(xy 371.186964 -217.904293) (xy 371.178865 -217.955431) (xy 371.162866 -218.004671) (xy 371.13936 -218.050803)
			(xy 371.108928 -218.09269) (xy 371.072318 -218.1293) (xy 371.030431 -218.159732) (xy 370.984299 -218.183238)
			(xy 370.935059 -218.199237) (xy 370.883921 -218.207336) (xy 370.832147 -218.207336) (xy 370.781009 -218.199237)
			(xy 370.731769 -218.183238) (xy 370.685637 -218.159732) (xy 370.64375 -218.1293) (xy 370.60714 -218.09269)
			(xy 370.576708 -218.050803) (xy 370.553202 -218.004671) (xy 370.537203 -217.955431) (xy 370.529104 -217.904293)
			(xy 370.528596 -217.878406) (xy 370.529127 -217.850698) (xy 370.538321 -217.796051) (xy 370.546884 -217.769694)
			(xy 370.554758 -217.747596) (xy 370.34978 -217.392504) (xy 370.32692 -217.388186) (xy 370.302075 -217.38302)
			(xy 370.254226 -217.366126) (xy 370.209533 -217.342096) (xy 370.169053 -217.311499) (xy 370.133741 -217.275058)
			(xy 370.104433 -217.233634) (xy 370.081822 -217.188207) (xy 370.066443 -217.13985) (xy 370.058658 -217.089708)
			(xy 370.058188 -217.064336) (xy 368.837972 -217.064336) (xy 368.837359 -217.091989) (xy 368.828038 -217.146507)
			(xy 368.81943 -217.172794) (xy 368.81181 -217.194892) (xy 369.017042 -217.550238) (xy 369.039902 -217.554556)
			(xy 369.064703 -217.559751) (xy 369.112442 -217.57674) (xy 369.157019 -217.600833) (xy 369.197384 -217.631463)
			(xy 369.232588 -217.667908) (xy 369.2618 -217.709312) (xy 369.284333 -217.754697) (xy 369.299656 -217.802996)
			(xy 369.307408 -217.85307) (xy 369.307872 -217.878406) (xy 369.307364 -217.904293) (xy 369.299265 -217.955431)
			(xy 369.283266 -218.004671) (xy 369.25976 -218.050803) (xy 369.229328 -218.09269) (xy 369.192718 -218.1293)
			(xy 369.150831 -218.159732) (xy 369.104699 -218.183238) (xy 369.055459 -218.199237) (xy 369.004321 -218.207336)
			(xy 368.952547 -218.207336) (xy 368.901409 -218.199237) (xy 368.852169 -218.183238) (xy 368.806037 -218.159732)
			(xy 368.76415 -218.1293) (xy 368.72754 -218.09269) (xy 368.697108 -218.050803) (xy 368.673602 -218.004671)
			(xy 368.657603 -217.955431) (xy 368.649504 -217.904293) (xy 368.648996 -217.878406) (xy 368.649527 -217.850698)
			(xy 368.658721 -217.796051) (xy 368.667284 -217.769694) (xy 368.675158 -217.747596) (xy 368.47018 -217.392504)
			(xy 368.44732 -217.388186) (xy 368.422475 -217.38302) (xy 368.374626 -217.366126) (xy 368.329933 -217.342096)
			(xy 368.289453 -217.311499) (xy 368.254141 -217.275058) (xy 368.224833 -217.233634) (xy 368.202222 -217.188207)
			(xy 368.186843 -217.13985) (xy 368.179058 -217.089708) (xy 368.178588 -217.064336) (xy 366.958372 -217.064336)
			(xy 366.957759 -217.091989) (xy 366.948438 -217.146507) (xy 366.93983 -217.172794) (xy 366.93221 -217.194892)
			(xy 367.137442 -217.550238) (xy 367.160302 -217.554556) (xy 367.185103 -217.559751) (xy 367.232842 -217.57674)
			(xy 367.277419 -217.600833) (xy 367.317784 -217.631463) (xy 367.352988 -217.667908) (xy 367.3822 -217.709312)
			(xy 367.404733 -217.754697) (xy 367.420056 -217.802996) (xy 367.427808 -217.85307) (xy 367.428272 -217.878406)
			(xy 367.427764 -217.904293) (xy 367.419665 -217.955431) (xy 367.403666 -218.004671) (xy 367.38016 -218.050803)
			(xy 367.349728 -218.09269) (xy 367.313118 -218.1293) (xy 367.271231 -218.159732) (xy 367.225099 -218.183238)
			(xy 367.175859 -218.199237) (xy 367.124721 -218.207336) (xy 367.072947 -218.207336) (xy 367.021809 -218.199237)
			(xy 366.972569 -218.183238) (xy 366.926437 -218.159732) (xy 366.88455 -218.1293) (xy 366.84794 -218.09269)
			(xy 366.817508 -218.050803) (xy 366.794002 -218.004671) (xy 366.778003 -217.955431) (xy 366.769904 -217.904293)
			(xy 366.769396 -217.878406) (xy 366.769927 -217.850698) (xy 366.779121 -217.796051) (xy 366.787684 -217.769694)
			(xy 366.795558 -217.747596) (xy 366.59058 -217.392504) (xy 366.56772 -217.388186) (xy 366.542875 -217.38302)
			(xy 366.495026 -217.366126) (xy 366.450333 -217.342096) (xy 366.409853 -217.311499) (xy 366.374541 -217.275058)
			(xy 366.345233 -217.233634) (xy 366.322622 -217.188207) (xy 366.307243 -217.13985) (xy 366.299458 -217.089708)
			(xy 366.298988 -217.064336) (xy 365.078772 -217.064336) (xy 365.078159 -217.091989) (xy 365.068838 -217.146507)
			(xy 365.06023 -217.172794) (xy 365.05261 -217.194892) (xy 365.257842 -217.550238) (xy 365.280702 -217.554556)
			(xy 365.305503 -217.559751) (xy 365.353242 -217.57674) (xy 365.397819 -217.600833) (xy 365.438184 -217.631463)
			(xy 365.473388 -217.667908) (xy 365.5026 -217.709312) (xy 365.525133 -217.754697) (xy 365.540456 -217.802996)
			(xy 365.548208 -217.85307) (xy 365.548672 -217.878406) (xy 365.548164 -217.904293) (xy 365.540065 -217.955431)
			(xy 365.524066 -218.004671) (xy 365.50056 -218.050803) (xy 365.470128 -218.09269) (xy 365.433518 -218.1293)
			(xy 365.391631 -218.159732) (xy 365.345499 -218.183238) (xy 365.296259 -218.199237) (xy 365.245121 -218.207336)
			(xy 365.193347 -218.207336) (xy 365.142209 -218.199237) (xy 365.092969 -218.183238) (xy 365.046837 -218.159732)
			(xy 365.00495 -218.1293) (xy 364.96834 -218.09269) (xy 364.937908 -218.050803) (xy 364.914402 -218.004671)
			(xy 364.898403 -217.955431) (xy 364.890304 -217.904293) (xy 364.889796 -217.878406) (xy 364.890327 -217.850698)
			(xy 364.899521 -217.796051) (xy 364.908084 -217.769694) (xy 364.915958 -217.747596) (xy 364.71098 -217.392504)
			(xy 364.68812 -217.388186) (xy 364.663275 -217.38302) (xy 364.615426 -217.366126) (xy 364.570733 -217.342096)
			(xy 364.530253 -217.311499) (xy 364.494941 -217.275058) (xy 364.465633 -217.233634) (xy 364.443022 -217.188207)
			(xy 364.427643 -217.13985) (xy 364.419858 -217.089708) (xy 364.419388 -217.064336) (xy 363.553756 -217.064336)
			(xy 363.553756 -217.627962) (xy 363.573083 -217.64517) (xy 363.606654 -217.684546) (xy 363.63366 -217.728684)
			(xy 363.653439 -217.7765) (xy 363.665503 -217.826818) (xy 363.669557 -217.878404) (xy 363.665502 -217.929989)
			(xy 363.653436 -217.980308) (xy 363.633657 -218.028123) (xy 363.606649 -218.07226) (xy 363.573077 -218.111636)
			(xy 363.553756 -218.12885) (xy 363.553756 -218.289378) (xy 363.554218 -218.303458) (xy 363.561919 -218.330544)
			(xy 363.576715 -218.354503) (xy 363.597485 -218.373519) (xy 363.622654 -218.386149) (xy 363.650313 -218.391435)
			(xy 363.678365 -218.388978) (xy 363.691678 -218.384374) (xy 363.705378 -218.379283) (xy 363.733488 -218.371273)
			(xy 363.747812 -218.368372) (xy 363.770672 -218.364054) (xy 363.975904 -218.008708) (xy 363.96803 -217.98661)
			(xy 363.959569 -217.960365) (xy 363.950508 -217.905976) (xy 363.949996 -217.878406) (xy 363.950504 -217.852519)
			(xy 363.958603 -217.801381) (xy 363.974602 -217.752141) (xy 363.998108 -217.706009) (xy 364.02854 -217.664122)
			(xy 364.06515 -217.627512) (xy 364.107037 -217.59708) (xy 364.153169 -217.573574) (xy 364.202409 -217.557575)
			(xy 364.253547 -217.549476) (xy 364.305321 -217.549476) (xy 364.356459 -217.557575) (xy 364.405699 -217.573574)
			(xy 364.451831 -217.59708) (xy 364.493718 -217.627512) (xy 364.530328 -217.664122) (xy 364.56076 -217.706009)
			(xy 364.584266 -217.752141) (xy 364.600265 -217.801381) (xy 364.608364 -217.852519) (xy 364.608872 -217.878406)
			(xy 364.608404 -217.90378) (xy 364.600624 -217.953929) (xy 364.585248 -218.002293) (xy 364.562641 -218.047728)
			(xy 364.533336 -218.08916) (xy 364.498026 -218.12561) (xy 364.457545 -218.156217) (xy 364.412852 -218.180257)
			(xy 364.365001 -218.197162) (xy 364.34014 -218.202256) (xy 364.31728 -218.206574) (xy 364.112556 -218.561412)
			(xy 364.12043 -218.583256) (xy 364.129075 -218.609664) (xy 364.138395 -218.66444) (xy 364.138972 -218.692222)
			(xy 365.359188 -218.692222) (xy 365.359739 -218.66688) (xy 365.367507 -218.616793) (xy 365.382848 -218.568485)
			(xy 365.405401 -218.523094) (xy 365.434634 -218.481689) (xy 365.469859 -218.445245) (xy 365.510246 -218.41462)
			(xy 365.554844 -218.390537) (xy 365.602602 -218.373561) (xy 365.627412 -218.368372) (xy 365.650272 -218.364054)
			(xy 365.855504 -218.008708) (xy 365.84763 -217.98661) (xy 365.839161 -217.960367) (xy 365.830092 -217.905977)
			(xy 365.829596 -217.878406) (xy 365.830104 -217.852519) (xy 365.838203 -217.801381) (xy 365.854202 -217.752141)
			(xy 365.877708 -217.706009) (xy 365.90814 -217.664122) (xy 365.94475 -217.627512) (xy 365.986637 -217.59708)
			(xy 366.032769 -217.573574) (xy 366.082009 -217.557575) (xy 366.133147 -217.549476) (xy 366.184921 -217.549476)
			(xy 366.236059 -217.557575) (xy 366.285299 -217.573574) (xy 366.331431 -217.59708) (xy 366.373318 -217.627512)
			(xy 366.409928 -217.664122) (xy 366.44036 -217.706009) (xy 366.463866 -217.752141) (xy 366.479865 -217.801381)
			(xy 366.487964 -217.852519) (xy 366.488472 -217.878406) (xy 366.488025 -217.903782) (xy 366.480255 -217.953934)
			(xy 366.464885 -218.002302) (xy 366.442277 -218.047739) (xy 366.412967 -218.089171) (xy 366.37765 -218.125617)
			(xy 366.33716 -218.156215) (xy 366.292456 -218.18024) (xy 366.244596 -218.197124) (xy 366.21974 -218.202256)
			(xy 366.19688 -218.206574) (xy 365.992156 -218.561412) (xy 366.00003 -218.583256) (xy 366.008681 -218.609663)
			(xy 366.017998 -218.66444) (xy 366.018572 -218.692222) (xy 367.238788 -218.692222) (xy 367.239339 -218.66688)
			(xy 367.247107 -218.616793) (xy 367.262448 -218.568485) (xy 367.285001 -218.523094) (xy 367.314234 -218.481689)
			(xy 367.349459 -218.445245) (xy 367.389846 -218.41462) (xy 367.434444 -218.390537) (xy 367.482202 -218.373561)
			(xy 367.507012 -218.368372) (xy 367.529872 -218.364054) (xy 367.735104 -218.008708) (xy 367.72723 -217.98661)
			(xy 367.718761 -217.960367) (xy 367.709692 -217.905977) (xy 367.709196 -217.878406) (xy 367.709704 -217.852519)
			(xy 367.717803 -217.801381) (xy 367.733802 -217.752141) (xy 367.757308 -217.706009) (xy 367.78774 -217.664122)
			(xy 367.82435 -217.627512) (xy 367.866237 -217.59708) (xy 367.912369 -217.573574) (xy 367.961609 -217.557575)
			(xy 368.012747 -217.549476) (xy 368.064521 -217.549476) (xy 368.115659 -217.557575) (xy 368.164899 -217.573574)
			(xy 368.211031 -217.59708) (xy 368.252918 -217.627512) (xy 368.289528 -217.664122) (xy 368.31996 -217.706009)
			(xy 368.343466 -217.752141) (xy 368.359465 -217.801381) (xy 368.367564 -217.852519) (xy 368.368072 -217.878406)
			(xy 368.367625 -217.903782) (xy 368.359855 -217.953934) (xy 368.344485 -218.002302) (xy 368.321877 -218.047739)
			(xy 368.292567 -218.089171) (xy 368.25725 -218.125617) (xy 368.21676 -218.156215) (xy 368.172056 -218.18024)
			(xy 368.124196 -218.197124) (xy 368.09934 -218.202256) (xy 368.07648 -218.206574) (xy 367.871756 -218.561412)
			(xy 367.87963 -218.583256) (xy 367.888281 -218.609663) (xy 367.897598 -218.66444) (xy 367.898172 -218.692222)
			(xy 369.118388 -218.692222) (xy 369.118939 -218.66688) (xy 369.126707 -218.616793) (xy 369.142048 -218.568485)
			(xy 369.164601 -218.523094) (xy 369.193834 -218.481689) (xy 369.229059 -218.445245) (xy 369.269446 -218.41462)
			(xy 369.314044 -218.390537) (xy 369.361802 -218.373561) (xy 369.386612 -218.368372) (xy 369.409472 -218.364054)
			(xy 369.614704 -218.008708) (xy 369.60683 -217.98661) (xy 369.598361 -217.960367) (xy 369.589292 -217.905977)
			(xy 369.588796 -217.878406) (xy 369.589304 -217.852519) (xy 369.597403 -217.801381) (xy 369.613402 -217.752141)
			(xy 369.636908 -217.706009) (xy 369.66734 -217.664122) (xy 369.70395 -217.627512) (xy 369.745837 -217.59708)
			(xy 369.791969 -217.573574) (xy 369.841209 -217.557575) (xy 369.892347 -217.549476) (xy 369.944121 -217.549476)
			(xy 369.995259 -217.557575) (xy 370.044499 -217.573574) (xy 370.090631 -217.59708) (xy 370.132518 -217.627512)
			(xy 370.169128 -217.664122) (xy 370.19956 -217.706009) (xy 370.223066 -217.752141) (xy 370.239065 -217.801381)
			(xy 370.247164 -217.852519) (xy 370.247672 -217.878406) (xy 370.247225 -217.903782) (xy 370.239455 -217.953934)
			(xy 370.224085 -218.002302) (xy 370.201477 -218.047739) (xy 370.172167 -218.089171) (xy 370.13685 -218.125617)
			(xy 370.09636 -218.156215) (xy 370.051656 -218.18024) (xy 370.003796 -218.197124) (xy 369.97894 -218.202256)
			(xy 369.95608 -218.206574) (xy 369.751356 -218.561412) (xy 369.75923 -218.583256) (xy 369.767881 -218.609663)
			(xy 369.777198 -218.66444) (xy 369.777772 -218.692222) (xy 370.997988 -218.692222) (xy 370.998539 -218.66688)
			(xy 371.006307 -218.616793) (xy 371.021648 -218.568485) (xy 371.044201 -218.523094) (xy 371.073434 -218.481689)
			(xy 371.108659 -218.445245) (xy 371.149046 -218.41462) (xy 371.193644 -218.390537) (xy 371.241402 -218.373561)
			(xy 371.266212 -218.368372) (xy 371.289072 -218.364054) (xy 371.494304 -218.008708) (xy 371.48643 -217.98661)
			(xy 371.477961 -217.960367) (xy 371.468892 -217.905977) (xy 371.468396 -217.878406) (xy 371.468904 -217.852519)
			(xy 371.477003 -217.801381) (xy 371.493002 -217.752141) (xy 371.516508 -217.706009) (xy 371.54694 -217.664122)
			(xy 371.58355 -217.627512) (xy 371.625437 -217.59708) (xy 371.671569 -217.573574) (xy 371.720809 -217.557575)
			(xy 371.771947 -217.549476) (xy 371.823721 -217.549476) (xy 371.874859 -217.557575) (xy 371.924099 -217.573574)
			(xy 371.970231 -217.59708) (xy 372.012118 -217.627512) (xy 372.048728 -217.664122) (xy 372.07916 -217.706009)
			(xy 372.102666 -217.752141) (xy 372.118665 -217.801381) (xy 372.126764 -217.852519) (xy 372.127272 -217.878406)
			(xy 372.126825 -217.903782) (xy 372.119055 -217.953934) (xy 372.103685 -218.002302) (xy 372.081077 -218.047739)
			(xy 372.051767 -218.089171) (xy 372.01645 -218.125617) (xy 371.97596 -218.156215) (xy 371.931256 -218.18024)
			(xy 371.883396 -218.197124) (xy 371.85854 -218.202256) (xy 371.83568 -218.206574) (xy 371.630956 -218.561412)
			(xy 371.63883 -218.583256) (xy 371.647481 -218.609663) (xy 371.656798 -218.66444) (xy 371.657372 -218.692222)
			(xy 372.877588 -218.692222) (xy 372.878139 -218.66688) (xy 372.885907 -218.616793) (xy 372.901248 -218.568485)
			(xy 372.923801 -218.523094) (xy 372.953034 -218.481689) (xy 372.988259 -218.445245) (xy 373.028646 -218.41462)
			(xy 373.073244 -218.390537) (xy 373.121002 -218.373561) (xy 373.145812 -218.368372) (xy 373.168672 -218.364054)
			(xy 373.373904 -218.008708) (xy 373.36603 -217.98661) (xy 373.357561 -217.960367) (xy 373.348492 -217.905977)
			(xy 373.347996 -217.878406) (xy 373.348504 -217.852519) (xy 373.356603 -217.801381) (xy 373.372602 -217.752141)
			(xy 373.396108 -217.706009) (xy 373.42654 -217.664122) (xy 373.46315 -217.627512) (xy 373.505037 -217.59708)
			(xy 373.551169 -217.573574) (xy 373.600409 -217.557575) (xy 373.651547 -217.549476) (xy 373.703321 -217.549476)
			(xy 373.754459 -217.557575) (xy 373.803699 -217.573574) (xy 373.849831 -217.59708) (xy 373.891718 -217.627512)
			(xy 373.928328 -217.664122) (xy 373.95876 -217.706009) (xy 373.982266 -217.752141) (xy 373.998265 -217.801381)
			(xy 374.006364 -217.852519) (xy 374.006872 -217.878406) (xy 374.006425 -217.903782) (xy 373.998655 -217.953934)
			(xy 373.983285 -218.002302) (xy 373.960677 -218.047739) (xy 373.931367 -218.089171) (xy 373.89605 -218.125617)
			(xy 373.85556 -218.156215) (xy 373.810856 -218.18024) (xy 373.762996 -218.197124) (xy 373.73814 -218.202256)
			(xy 373.71528 -218.206574) (xy 373.510556 -218.561412) (xy 373.51843 -218.583256) (xy 373.527081 -218.609663)
			(xy 373.536398 -218.66444) (xy 373.536972 -218.692222) (xy 373.536464 -218.718129) (xy 373.528358 -218.769306)
			(xy 373.512346 -218.818585) (xy 373.488823 -218.864752) (xy 373.458367 -218.906671) (xy 373.421729 -218.943309)
			(xy 373.37981 -218.973765) (xy 373.333643 -218.997288) (xy 373.284364 -219.0133) (xy 373.233187 -219.021406)
			(xy 373.181373 -219.021406) (xy 373.130196 -219.0133) (xy 373.080917 -218.997288) (xy 373.03475 -218.973765)
			(xy 372.992831 -218.943309) (xy 372.956193 -218.906671) (xy 372.925737 -218.864752) (xy 372.902214 -218.818585)
			(xy 372.886202 -218.769306) (xy 372.878096 -218.718129) (xy 372.877588 -218.692222) (xy 371.657372 -218.692222)
			(xy 371.656864 -218.718129) (xy 371.648758 -218.769306) (xy 371.632746 -218.818585) (xy 371.609223 -218.864752)
			(xy 371.578767 -218.906671) (xy 371.542129 -218.943309) (xy 371.50021 -218.973765) (xy 371.454043 -218.997288)
			(xy 371.404764 -219.0133) (xy 371.353587 -219.021406) (xy 371.301773 -219.021406) (xy 371.250596 -219.0133)
			(xy 371.201317 -218.997288) (xy 371.15515 -218.973765) (xy 371.113231 -218.943309) (xy 371.076593 -218.906671)
			(xy 371.046137 -218.864752) (xy 371.022614 -218.818585) (xy 371.006602 -218.769306) (xy 370.998496 -218.718129)
			(xy 370.997988 -218.692222) (xy 369.777772 -218.692222) (xy 369.777264 -218.718129) (xy 369.769158 -218.769306)
			(xy 369.753146 -218.818585) (xy 369.729623 -218.864752) (xy 369.699167 -218.906671) (xy 369.662529 -218.943309)
			(xy 369.62061 -218.973765) (xy 369.574443 -218.997288) (xy 369.525164 -219.0133) (xy 369.473987 -219.021406)
			(xy 369.422173 -219.021406) (xy 369.370996 -219.0133) (xy 369.321717 -218.997288) (xy 369.27555 -218.973765)
			(xy 369.233631 -218.943309) (xy 369.196993 -218.906671) (xy 369.166537 -218.864752) (xy 369.143014 -218.818585)
			(xy 369.127002 -218.769306) (xy 369.118896 -218.718129) (xy 369.118388 -218.692222) (xy 367.898172 -218.692222)
			(xy 367.897664 -218.718129) (xy 367.889558 -218.769306) (xy 367.873546 -218.818585) (xy 367.850023 -218.864752)
			(xy 367.819567 -218.906671) (xy 367.782929 -218.943309) (xy 367.74101 -218.973765) (xy 367.694843 -218.997288)
			(xy 367.645564 -219.0133) (xy 367.594387 -219.021406) (xy 367.542573 -219.021406) (xy 367.491396 -219.0133)
			(xy 367.442117 -218.997288) (xy 367.39595 -218.973765) (xy 367.354031 -218.943309) (xy 367.317393 -218.906671)
			(xy 367.286937 -218.864752) (xy 367.263414 -218.818585) (xy 367.247402 -218.769306) (xy 367.239296 -218.718129)
			(xy 367.238788 -218.692222) (xy 366.018572 -218.692222) (xy 366.018064 -218.718129) (xy 366.009958 -218.769306)
			(xy 365.993946 -218.818585) (xy 365.970423 -218.864752) (xy 365.939967 -218.906671) (xy 365.903329 -218.943309)
			(xy 365.86141 -218.973765) (xy 365.815243 -218.997288) (xy 365.765964 -219.0133) (xy 365.714787 -219.021406)
			(xy 365.662973 -219.021406) (xy 365.611796 -219.0133) (xy 365.562517 -218.997288) (xy 365.51635 -218.973765)
			(xy 365.474431 -218.943309) (xy 365.437793 -218.906671) (xy 365.407337 -218.864752) (xy 365.383814 -218.818585)
			(xy 365.367802 -218.769306) (xy 365.359696 -218.718129) (xy 365.359188 -218.692222) (xy 364.138972 -218.692222)
			(xy 364.138488 -218.718124) (xy 364.130378 -218.769289) (xy 364.11436 -218.818555) (xy 364.09083 -218.864707)
			(xy 364.060368 -218.906608) (xy 364.023723 -218.943225) (xy 363.9818 -218.973657) (xy 363.935631 -218.997153)
			(xy 363.886353 -219.013134) (xy 363.835182 -219.021207) (xy 363.80928 -219.02166) (xy 363.779199 -219.021012)
			(xy 363.720029 -219.010145) (xy 363.691678 -219.00007) (xy 363.678357 -218.995448) (xy 363.650285 -218.992933)
			(xy 363.622595 -218.99819) (xy 363.597398 -219.010818) (xy 363.576613 -219.029855) (xy 363.561827 -219.05385)
			(xy 363.554164 -219.080973) (xy 363.553756 -219.095066) (xy 363.553756 -219.257372) (xy 363.572877 -219.274496)
			(xy 363.606076 -219.31364) (xy 363.632776 -219.357475) (xy 363.652326 -219.404932) (xy 363.664248 -219.454855)
			(xy 363.668252 -219.506025) (xy 363.66424 -219.557194) (xy 363.65231 -219.607115) (xy 363.632754 -219.65457)
			(xy 363.606047 -219.698401) (xy 363.572842 -219.737539) (xy 363.553756 -219.754704) (xy 363.553756 -220.319854)
			(xy 364.419388 -220.319854) (xy 364.419896 -220.293947) (xy 364.428002 -220.24277) (xy 364.444014 -220.193491)
			(xy 364.467537 -220.147324) (xy 364.497993 -220.105405) (xy 364.534631 -220.068767) (xy 364.57655 -220.038311)
			(xy 364.622717 -220.014788) (xy 364.671996 -219.998776) (xy 364.723173 -219.99067) (xy 364.774987 -219.99067)
			(xy 364.826164 -219.998776) (xy 364.875443 -220.014788) (xy 364.92161 -220.038311) (xy 364.963529 -220.068767)
			(xy 365.000167 -220.105405) (xy 365.030623 -220.147324) (xy 365.054146 -220.193491) (xy 365.070158 -220.24277)
			(xy 365.078264 -220.293947) (xy 365.078772 -220.319854) (xy 366.298988 -220.319854) (xy 366.299496 -220.293947)
			(xy 366.307602 -220.24277) (xy 366.323614 -220.193491) (xy 366.347137 -220.147324) (xy 366.377593 -220.105405)
			(xy 366.414231 -220.068767) (xy 366.45615 -220.038311) (xy 366.502317 -220.014788) (xy 366.551596 -219.998776)
			(xy 366.602773 -219.99067) (xy 366.654587 -219.99067) (xy 366.705764 -219.998776) (xy 366.755043 -220.014788)
			(xy 366.80121 -220.038311) (xy 366.843129 -220.068767) (xy 366.879767 -220.105405) (xy 366.910223 -220.147324)
			(xy 366.933746 -220.193491) (xy 366.949758 -220.24277) (xy 366.957864 -220.293947) (xy 366.958372 -220.319854)
			(xy 368.178588 -220.319854) (xy 368.179096 -220.293947) (xy 368.187202 -220.24277) (xy 368.203214 -220.193491)
			(xy 368.226737 -220.147324) (xy 368.257193 -220.105405) (xy 368.293831 -220.068767) (xy 368.33575 -220.038311)
			(xy 368.381917 -220.014788) (xy 368.431196 -219.998776) (xy 368.482373 -219.99067) (xy 368.534187 -219.99067)
			(xy 368.585364 -219.998776) (xy 368.634643 -220.014788) (xy 368.68081 -220.038311) (xy 368.722729 -220.068767)
			(xy 368.759367 -220.105405) (xy 368.789823 -220.147324) (xy 368.813346 -220.193491) (xy 368.829358 -220.24277)
			(xy 368.837464 -220.293947) (xy 368.837972 -220.319854) (xy 370.058188 -220.319854) (xy 370.058696 -220.293947)
			(xy 370.066802 -220.24277) (xy 370.082814 -220.193491) (xy 370.106337 -220.147324) (xy 370.136793 -220.105405)
			(xy 370.173431 -220.068767) (xy 370.21535 -220.038311) (xy 370.261517 -220.014788) (xy 370.310796 -219.998776)
			(xy 370.361973 -219.99067) (xy 370.413787 -219.99067) (xy 370.464964 -219.998776) (xy 370.514243 -220.014788)
			(xy 370.56041 -220.038311) (xy 370.602329 -220.068767) (xy 370.638967 -220.105405) (xy 370.669423 -220.147324)
			(xy 370.692946 -220.193491) (xy 370.708958 -220.24277) (xy 370.717064 -220.293947) (xy 370.717572 -220.319854)
			(xy 371.937788 -220.319854) (xy 371.938296 -220.293947) (xy 371.946402 -220.24277) (xy 371.962414 -220.193491)
			(xy 371.985937 -220.147324) (xy 372.016393 -220.105405) (xy 372.053031 -220.068767) (xy 372.09495 -220.038311)
			(xy 372.141117 -220.014788) (xy 372.190396 -219.998776) (xy 372.241573 -219.99067) (xy 372.293387 -219.99067)
			(xy 372.344564 -219.998776) (xy 372.393843 -220.014788) (xy 372.44001 -220.038311) (xy 372.481929 -220.068767)
			(xy 372.518567 -220.105405) (xy 372.549023 -220.147324) (xy 372.572546 -220.193491) (xy 372.588558 -220.24277)
			(xy 372.596664 -220.293947) (xy 372.597172 -220.319854) (xy 373.817388 -220.319854) (xy 373.817896 -220.293947)
			(xy 373.826002 -220.24277) (xy 373.842014 -220.193491) (xy 373.865537 -220.147324) (xy 373.895993 -220.105405)
			(xy 373.932631 -220.068767) (xy 373.97455 -220.038311) (xy 374.020717 -220.014788) (xy 374.069996 -219.998776)
			(xy 374.121173 -219.99067) (xy 374.172987 -219.99067) (xy 374.224164 -219.998776) (xy 374.273443 -220.014788)
			(xy 374.31961 -220.038311) (xy 374.361529 -220.068767) (xy 374.398167 -220.105405) (xy 374.428623 -220.147324)
			(xy 374.452146 -220.193491) (xy 374.468158 -220.24277) (xy 374.476264 -220.293947) (xy 374.476772 -220.319854)
			(xy 374.476163 -220.347508) (xy 374.466839 -220.402026) (xy 374.45823 -220.428312) (xy 374.45061 -220.45041)
			(xy 374.655842 -220.805756) (xy 374.678702 -220.810074) (xy 374.703508 -220.815252) (xy 374.751247 -220.832242)
			(xy 374.795825 -220.856337) (xy 374.836191 -220.886969) (xy 374.871395 -220.923417) (xy 374.900606 -220.964822)
			(xy 374.923138 -221.01021) (xy 374.93846 -221.058511) (xy 374.94621 -221.108588) (xy 374.946672 -221.133924)
			(xy 374.946164 -221.159811) (xy 374.938065 -221.210949) (xy 374.922066 -221.260189) (xy 374.89856 -221.306321)
			(xy 374.868128 -221.348208) (xy 374.831518 -221.384818) (xy 374.789631 -221.41525) (xy 374.743499 -221.438756)
			(xy 374.694259 -221.454755) (xy 374.643121 -221.462854) (xy 374.591347 -221.462854) (xy 374.540209 -221.454755)
			(xy 374.490969 -221.438756) (xy 374.444837 -221.41525) (xy 374.40295 -221.384818) (xy 374.36634 -221.348208)
			(xy 374.335908 -221.306321) (xy 374.312402 -221.260189) (xy 374.296403 -221.210949) (xy 374.288304 -221.159811)
			(xy 374.287796 -221.133924) (xy 374.288332 -221.106216) (xy 374.297523 -221.051569) (xy 374.306084 -221.025212)
			(xy 374.313958 -221.003114) (xy 374.10898 -220.648022) (xy 374.08612 -220.643704) (xy 374.061279 -220.638521)
			(xy 374.013432 -220.621628) (xy 373.96874 -220.5976) (xy 373.928259 -220.567005) (xy 373.892948 -220.530566)
			(xy 373.863639 -220.489145) (xy 373.841027 -220.44372) (xy 373.825646 -220.395365) (xy 373.817859 -220.345225)
			(xy 373.817388 -220.319854) (xy 372.597172 -220.319854) (xy 372.596563 -220.347508) (xy 372.587239 -220.402026)
			(xy 372.57863 -220.428312) (xy 372.57101 -220.45041) (xy 372.776242 -220.805756) (xy 372.799102 -220.810074)
			(xy 372.823908 -220.815252) (xy 372.871647 -220.832242) (xy 372.916225 -220.856337) (xy 372.956591 -220.886969)
			(xy 372.991795 -220.923417) (xy 373.021006 -220.964822) (xy 373.043538 -221.01021) (xy 373.05886 -221.058511)
			(xy 373.06661 -221.108588) (xy 373.067072 -221.133924) (xy 373.066564 -221.159811) (xy 373.058465 -221.210949)
			(xy 373.042466 -221.260189) (xy 373.01896 -221.306321) (xy 372.988528 -221.348208) (xy 372.951918 -221.384818)
			(xy 372.910031 -221.41525) (xy 372.863899 -221.438756) (xy 372.814659 -221.454755) (xy 372.763521 -221.462854)
			(xy 372.711747 -221.462854) (xy 372.660609 -221.454755) (xy 372.611369 -221.438756) (xy 372.565237 -221.41525)
			(xy 372.52335 -221.384818) (xy 372.48674 -221.348208) (xy 372.456308 -221.306321) (xy 372.432802 -221.260189)
			(xy 372.416803 -221.210949) (xy 372.408704 -221.159811) (xy 372.408196 -221.133924) (xy 372.408732 -221.106216)
			(xy 372.417923 -221.051569) (xy 372.426484 -221.025212) (xy 372.434358 -221.003114) (xy 372.22938 -220.648022)
			(xy 372.20652 -220.643704) (xy 372.181679 -220.638521) (xy 372.133832 -220.621628) (xy 372.08914 -220.5976)
			(xy 372.048659 -220.567005) (xy 372.013348 -220.530566) (xy 371.984039 -220.489145) (xy 371.961427 -220.44372)
			(xy 371.946046 -220.395365) (xy 371.938259 -220.345225) (xy 371.937788 -220.319854) (xy 370.717572 -220.319854)
			(xy 370.716963 -220.347508) (xy 370.707639 -220.402026) (xy 370.69903 -220.428312) (xy 370.69141 -220.45041)
			(xy 370.896642 -220.805756) (xy 370.919502 -220.810074) (xy 370.944308 -220.815252) (xy 370.992047 -220.832242)
			(xy 371.036625 -220.856337) (xy 371.076991 -220.886969) (xy 371.112195 -220.923417) (xy 371.141406 -220.964822)
			(xy 371.163938 -221.01021) (xy 371.17926 -221.058511) (xy 371.18701 -221.108588) (xy 371.187472 -221.133924)
			(xy 371.186964 -221.159811) (xy 371.178865 -221.210949) (xy 371.162866 -221.260189) (xy 371.13936 -221.306321)
			(xy 371.108928 -221.348208) (xy 371.072318 -221.384818) (xy 371.030431 -221.41525) (xy 370.984299 -221.438756)
			(xy 370.935059 -221.454755) (xy 370.883921 -221.462854) (xy 370.832147 -221.462854) (xy 370.781009 -221.454755)
			(xy 370.731769 -221.438756) (xy 370.685637 -221.41525) (xy 370.64375 -221.384818) (xy 370.60714 -221.348208)
			(xy 370.576708 -221.306321) (xy 370.553202 -221.260189) (xy 370.537203 -221.210949) (xy 370.529104 -221.159811)
			(xy 370.528596 -221.133924) (xy 370.529132 -221.106216) (xy 370.538323 -221.051569) (xy 370.546884 -221.025212)
			(xy 370.554758 -221.003114) (xy 370.34978 -220.648022) (xy 370.32692 -220.643704) (xy 370.302079 -220.638521)
			(xy 370.254232 -220.621628) (xy 370.20954 -220.5976) (xy 370.169059 -220.567005) (xy 370.133748 -220.530566)
			(xy 370.104439 -220.489145) (xy 370.081827 -220.44372) (xy 370.066446 -220.395365) (xy 370.058659 -220.345225)
			(xy 370.058188 -220.319854) (xy 368.837972 -220.319854) (xy 368.837363 -220.347508) (xy 368.828039 -220.402026)
			(xy 368.81943 -220.428312) (xy 368.81181 -220.45041) (xy 369.017042 -220.805756) (xy 369.039902 -220.810074)
			(xy 369.064708 -220.815252) (xy 369.112447 -220.832242) (xy 369.157025 -220.856337) (xy 369.197391 -220.886969)
			(xy 369.232595 -220.923417) (xy 369.261806 -220.964822) (xy 369.284338 -221.01021) (xy 369.29966 -221.058511)
			(xy 369.30741 -221.108588) (xy 369.307872 -221.133924) (xy 369.307364 -221.159811) (xy 369.299265 -221.210949)
			(xy 369.283266 -221.260189) (xy 369.25976 -221.306321) (xy 369.229328 -221.348208) (xy 369.192718 -221.384818)
			(xy 369.150831 -221.41525) (xy 369.104699 -221.438756) (xy 369.055459 -221.454755) (xy 369.004321 -221.462854)
			(xy 368.952547 -221.462854) (xy 368.901409 -221.454755) (xy 368.852169 -221.438756) (xy 368.806037 -221.41525)
			(xy 368.76415 -221.384818) (xy 368.72754 -221.348208) (xy 368.697108 -221.306321) (xy 368.673602 -221.260189)
			(xy 368.657603 -221.210949) (xy 368.649504 -221.159811) (xy 368.648996 -221.133924) (xy 368.649532 -221.106216)
			(xy 368.658723 -221.051569) (xy 368.667284 -221.025212) (xy 368.675158 -221.003114) (xy 368.47018 -220.648022)
			(xy 368.44732 -220.643704) (xy 368.422479 -220.638521) (xy 368.374632 -220.621628) (xy 368.32994 -220.5976)
			(xy 368.289459 -220.567005) (xy 368.254148 -220.530566) (xy 368.224839 -220.489145) (xy 368.202227 -220.44372)
			(xy 368.186846 -220.395365) (xy 368.179059 -220.345225) (xy 368.178588 -220.319854) (xy 366.958372 -220.319854)
			(xy 366.957763 -220.347508) (xy 366.948439 -220.402026) (xy 366.93983 -220.428312) (xy 366.93221 -220.45041)
			(xy 367.137442 -220.805756) (xy 367.160302 -220.810074) (xy 367.185108 -220.815252) (xy 367.232847 -220.832242)
			(xy 367.277425 -220.856337) (xy 367.317791 -220.886969) (xy 367.352995 -220.923417) (xy 367.382206 -220.964822)
			(xy 367.404738 -221.01021) (xy 367.42006 -221.058511) (xy 367.42781 -221.108588) (xy 367.428272 -221.133924)
			(xy 367.427764 -221.159811) (xy 367.419665 -221.210949) (xy 367.403666 -221.260189) (xy 367.38016 -221.306321)
			(xy 367.349728 -221.348208) (xy 367.313118 -221.384818) (xy 367.271231 -221.41525) (xy 367.225099 -221.438756)
			(xy 367.175859 -221.454755) (xy 367.124721 -221.462854) (xy 367.072947 -221.462854) (xy 367.021809 -221.454755)
			(xy 366.972569 -221.438756) (xy 366.926437 -221.41525) (xy 366.88455 -221.384818) (xy 366.84794 -221.348208)
			(xy 366.817508 -221.306321) (xy 366.794002 -221.260189) (xy 366.778003 -221.210949) (xy 366.769904 -221.159811)
			(xy 366.769396 -221.133924) (xy 366.769932 -221.106216) (xy 366.779123 -221.051569) (xy 366.787684 -221.025212)
			(xy 366.795558 -221.003114) (xy 366.59058 -220.648022) (xy 366.56772 -220.643704) (xy 366.542879 -220.638521)
			(xy 366.495032 -220.621628) (xy 366.45034 -220.5976) (xy 366.409859 -220.567005) (xy 366.374548 -220.530566)
			(xy 366.345239 -220.489145) (xy 366.322627 -220.44372) (xy 366.307246 -220.395365) (xy 366.299459 -220.345225)
			(xy 366.298988 -220.319854) (xy 365.078772 -220.319854) (xy 365.078163 -220.347508) (xy 365.068839 -220.402026)
			(xy 365.06023 -220.428312) (xy 365.05261 -220.45041) (xy 365.257842 -220.805756) (xy 365.280702 -220.810074)
			(xy 365.305508 -220.815252) (xy 365.353247 -220.832242) (xy 365.397825 -220.856337) (xy 365.438191 -220.886969)
			(xy 365.473395 -220.923417) (xy 365.502606 -220.964822) (xy 365.525138 -221.01021) (xy 365.54046 -221.058511)
			(xy 365.54821 -221.108588) (xy 365.548672 -221.133924) (xy 365.548164 -221.159811) (xy 365.540065 -221.210949)
			(xy 365.524066 -221.260189) (xy 365.50056 -221.306321) (xy 365.470128 -221.348208) (xy 365.433518 -221.384818)
			(xy 365.391631 -221.41525) (xy 365.345499 -221.438756) (xy 365.296259 -221.454755) (xy 365.245121 -221.462854)
			(xy 365.193347 -221.462854) (xy 365.142209 -221.454755) (xy 365.092969 -221.438756) (xy 365.046837 -221.41525)
			(xy 365.00495 -221.384818) (xy 364.96834 -221.348208) (xy 364.937908 -221.306321) (xy 364.914402 -221.260189)
			(xy 364.898403 -221.210949) (xy 364.890304 -221.159811) (xy 364.889796 -221.133924) (xy 364.890332 -221.106216)
			(xy 364.899523 -221.051569) (xy 364.908084 -221.025212) (xy 364.915958 -221.003114) (xy 364.71098 -220.648022)
			(xy 364.68812 -220.643704) (xy 364.663279 -220.638521) (xy 364.615432 -220.621628) (xy 364.57074 -220.5976)
			(xy 364.530259 -220.567005) (xy 364.494948 -220.530566) (xy 364.465639 -220.489145) (xy 364.443027 -220.44372)
			(xy 364.427646 -220.395365) (xy 364.419859 -220.345225) (xy 364.419388 -220.319854) (xy 363.553756 -220.319854)
			(xy 363.553756 -220.88348) (xy 363.573081 -220.900688) (xy 363.60665 -220.940064) (xy 363.633653 -220.984201)
			(xy 363.653429 -221.032015) (xy 363.665491 -221.082332) (xy 363.669544 -221.133916) (xy 363.665486 -221.185499)
			(xy 363.653419 -221.235815) (xy 363.633639 -221.283627) (xy 363.606631 -221.327762) (xy 363.573059 -221.367134)
			(xy 363.553756 -221.384368) (xy 363.553756 -221.544896) (xy 363.55422 -221.558974) (xy 363.561924 -221.586056)
			(xy 363.576721 -221.61001) (xy 363.59749 -221.629022) (xy 363.622656 -221.641649) (xy 363.650312 -221.646935)
			(xy 363.678361 -221.644479) (xy 363.691678 -221.639892) (xy 363.705378 -221.634803) (xy 363.733488 -221.626795)
			(xy 363.747812 -221.62389) (xy 363.770672 -221.619572) (xy 363.975904 -221.264226) (xy 363.96803 -221.242128)
			(xy 363.959567 -221.215884) (xy 363.950503 -221.161494) (xy 363.949996 -221.133924) (xy 363.950504 -221.108037)
			(xy 363.958603 -221.056899) (xy 363.974602 -221.007659) (xy 363.998108 -220.961527) (xy 364.02854 -220.91964)
			(xy 364.06515 -220.88303) (xy 364.107037 -220.852598) (xy 364.153169 -220.829092) (xy 364.202409 -220.813093)
			(xy 364.253547 -220.804994) (xy 364.305321 -220.804994) (xy 364.356459 -220.813093) (xy 364.405699 -220.829092)
			(xy 364.451831 -220.852598) (xy 364.493718 -220.88303) (xy 364.530328 -220.91964) (xy 364.56076 -220.961527)
			(xy 364.584266 -221.007659) (xy 364.600265 -221.056899) (xy 364.608364 -221.108037) (xy 364.608872 -221.133924)
			(xy 364.608403 -221.159298) (xy 364.60062 -221.209444) (xy 364.585243 -221.257806) (xy 364.562634 -221.303238)
			(xy 364.533329 -221.344668) (xy 364.498019 -221.381116) (xy 364.457539 -221.411721) (xy 364.412846 -221.435759)
			(xy 364.364997 -221.452663) (xy 364.34014 -221.457774) (xy 364.31728 -221.462092) (xy 364.112556 -221.81693)
			(xy 364.12043 -221.838774) (xy 364.129074 -221.865183) (xy 364.138391 -221.919959) (xy 364.138972 -221.94774)
			(xy 365.359188 -221.94774) (xy 365.359665 -221.922395) (xy 365.367445 -221.872306) (xy 365.382797 -221.823996)
			(xy 365.40536 -221.778605) (xy 365.434603 -221.7372) (xy 365.469837 -221.700757) (xy 365.510231 -221.670134)
			(xy 365.554836 -221.646052) (xy 365.602599 -221.629078) (xy 365.627412 -221.62389) (xy 365.650272 -221.619572)
			(xy 365.855504 -221.264226) (xy 365.84763 -221.242128) (xy 365.839165 -221.215883) (xy 365.830093 -221.161495)
			(xy 365.829596 -221.133924) (xy 365.830104 -221.108037) (xy 365.838203 -221.056899) (xy 365.854202 -221.007659)
			(xy 365.877708 -220.961527) (xy 365.90814 -220.91964) (xy 365.94475 -220.88303) (xy 365.986637 -220.852598)
			(xy 366.032769 -220.829092) (xy 366.082009 -220.813093) (xy 366.133147 -220.804994) (xy 366.184921 -220.804994)
			(xy 366.236059 -220.813093) (xy 366.285299 -220.829092) (xy 366.331431 -220.852598) (xy 366.373318 -220.88303)
			(xy 366.409928 -220.91964) (xy 366.44036 -220.961527) (xy 366.463866 -221.007659) (xy 366.479865 -221.056899)
			(xy 366.487964 -221.108037) (xy 366.488472 -221.133924) (xy 366.488042 -221.1593) (xy 366.480269 -221.209454)
			(xy 366.464896 -221.257821) (xy 366.442286 -221.303259) (xy 366.412974 -221.344691) (xy 366.377655 -221.381137)
			(xy 366.337163 -221.411734) (xy 366.292458 -221.435759) (xy 366.244596 -221.452643) (xy 366.21974 -221.457774)
			(xy 366.19688 -221.462092) (xy 365.992156 -221.81693) (xy 366.00003 -221.838774) (xy 366.008686 -221.865179)
			(xy 366.018 -221.919958) (xy 366.018572 -221.94774) (xy 369.118388 -221.94774) (xy 369.118865 -221.922395)
			(xy 369.126645 -221.872306) (xy 369.141997 -221.823996) (xy 369.16456 -221.778605) (xy 369.193803 -221.7372)
			(xy 369.229037 -221.700757) (xy 369.269431 -221.670134) (xy 369.314036 -221.646052) (xy 369.361799 -221.629078)
			(xy 369.386612 -221.62389) (xy 369.409472 -221.619572) (xy 369.614704 -221.264226) (xy 369.60683 -221.242128)
			(xy 369.598365 -221.215883) (xy 369.589293 -221.161495) (xy 369.588796 -221.133924) (xy 369.589304 -221.108037)
			(xy 369.597403 -221.056899) (xy 369.613402 -221.007659) (xy 369.636908 -220.961527) (xy 369.66734 -220.91964)
			(xy 369.70395 -220.88303) (xy 369.745837 -220.852598) (xy 369.791969 -220.829092) (xy 369.841209 -220.813093)
			(xy 369.892347 -220.804994) (xy 369.944121 -220.804994) (xy 369.995259 -220.813093) (xy 370.044499 -220.829092)
			(xy 370.090631 -220.852598) (xy 370.132518 -220.88303) (xy 370.169128 -220.91964) (xy 370.19956 -220.961527)
			(xy 370.223066 -221.007659) (xy 370.239065 -221.056899) (xy 370.247164 -221.108037) (xy 370.247672 -221.133924)
			(xy 370.247242 -221.1593) (xy 370.239469 -221.209454) (xy 370.224096 -221.257821) (xy 370.201486 -221.303259)
			(xy 370.172174 -221.344691) (xy 370.136855 -221.381137) (xy 370.096363 -221.411734) (xy 370.051658 -221.435759)
			(xy 370.003796 -221.452643) (xy 369.97894 -221.457774) (xy 369.95608 -221.462092) (xy 369.751356 -221.81693)
			(xy 369.75923 -221.838774) (xy 369.767886 -221.865179) (xy 369.7772 -221.919958) (xy 369.777772 -221.94774)
			(xy 370.997988 -221.94774) (xy 370.998465 -221.922395) (xy 371.006245 -221.872306) (xy 371.021597 -221.823996)
			(xy 371.04416 -221.778605) (xy 371.073403 -221.7372) (xy 371.108637 -221.700757) (xy 371.149031 -221.670134)
			(xy 371.193636 -221.646052) (xy 371.241399 -221.629078) (xy 371.266212 -221.62389) (xy 371.289072 -221.619572)
			(xy 371.494304 -221.264226) (xy 371.48643 -221.242128) (xy 371.477965 -221.215883) (xy 371.468893 -221.161495)
			(xy 371.468396 -221.133924) (xy 371.468904 -221.108037) (xy 371.477003 -221.056899) (xy 371.493002 -221.007659)
			(xy 371.516508 -220.961527) (xy 371.54694 -220.91964) (xy 371.58355 -220.88303) (xy 371.625437 -220.852598)
			(xy 371.671569 -220.829092) (xy 371.720809 -220.813093) (xy 371.771947 -220.804994) (xy 371.823721 -220.804994)
			(xy 371.874859 -220.813093) (xy 371.924099 -220.829092) (xy 371.970231 -220.852598) (xy 372.012118 -220.88303)
			(xy 372.048728 -220.91964) (xy 372.07916 -220.961527) (xy 372.102666 -221.007659) (xy 372.118665 -221.056899)
			(xy 372.126764 -221.108037) (xy 372.127272 -221.133924) (xy 372.126842 -221.1593) (xy 372.119069 -221.209454)
			(xy 372.103696 -221.257821) (xy 372.081086 -221.303259) (xy 372.051774 -221.344691) (xy 372.016455 -221.381137)
			(xy 371.975963 -221.411734) (xy 371.931258 -221.435759) (xy 371.883396 -221.452643) (xy 371.85854 -221.457774)
			(xy 371.83568 -221.462092) (xy 371.630956 -221.81693) (xy 371.63883 -221.838774) (xy 371.647486 -221.865179)
			(xy 371.6568 -221.919958) (xy 371.657372 -221.94774) (xy 372.877588 -221.94774) (xy 372.878065 -221.922395)
			(xy 372.885845 -221.872306) (xy 372.901197 -221.823996) (xy 372.92376 -221.778605) (xy 372.953003 -221.7372)
			(xy 372.988237 -221.700757) (xy 373.028631 -221.670134) (xy 373.073236 -221.646052) (xy 373.120999 -221.629078)
			(xy 373.145812 -221.62389) (xy 373.168672 -221.619572) (xy 373.373904 -221.264226) (xy 373.36603 -221.242128)
			(xy 373.357565 -221.215883) (xy 373.348493 -221.161495) (xy 373.347996 -221.133924) (xy 373.348504 -221.108037)
			(xy 373.356603 -221.056899) (xy 373.372602 -221.007659) (xy 373.396108 -220.961527) (xy 373.42654 -220.91964)
			(xy 373.46315 -220.88303) (xy 373.505037 -220.852598) (xy 373.551169 -220.829092) (xy 373.600409 -220.813093)
			(xy 373.651547 -220.804994) (xy 373.703321 -220.804994) (xy 373.754459 -220.813093) (xy 373.803699 -220.829092)
			(xy 373.849831 -220.852598) (xy 373.891718 -220.88303) (xy 373.928328 -220.91964) (xy 373.95876 -220.961527)
			(xy 373.982266 -221.007659) (xy 373.998265 -221.056899) (xy 374.006364 -221.108037) (xy 374.006872 -221.133924)
			(xy 374.006442 -221.1593) (xy 373.998669 -221.209454) (xy 373.983296 -221.257821) (xy 373.960686 -221.303259)
			(xy 373.931374 -221.344691) (xy 373.896055 -221.381137) (xy 373.855563 -221.411734) (xy 373.810858 -221.435759)
			(xy 373.762996 -221.452643) (xy 373.73814 -221.457774) (xy 373.71528 -221.462092) (xy 373.510556 -221.81693)
			(xy 373.51843 -221.838774) (xy 373.527086 -221.865179) (xy 373.5364 -221.919958) (xy 373.536972 -221.94774)
			(xy 373.536464 -221.973647) (xy 373.528358 -222.024824) (xy 373.512346 -222.074103) (xy 373.488823 -222.12027)
			(xy 373.458367 -222.162189) (xy 373.421729 -222.198827) (xy 373.37981 -222.229283) (xy 373.333643 -222.252806)
			(xy 373.284364 -222.268818) (xy 373.233187 -222.276924) (xy 373.181373 -222.276924) (xy 373.130196 -222.268818)
			(xy 373.080917 -222.252806) (xy 373.03475 -222.229283) (xy 372.992831 -222.198827) (xy 372.956193 -222.162189)
			(xy 372.925737 -222.12027) (xy 372.902214 -222.074103) (xy 372.886202 -222.024824) (xy 372.878096 -221.973647)
			(xy 372.877588 -221.94774) (xy 371.657372 -221.94774) (xy 371.656864 -221.973647) (xy 371.648758 -222.024824)
			(xy 371.632746 -222.074103) (xy 371.609223 -222.12027) (xy 371.578767 -222.162189) (xy 371.542129 -222.198827)
			(xy 371.50021 -222.229283) (xy 371.454043 -222.252806) (xy 371.404764 -222.268818) (xy 371.353587 -222.276924)
			(xy 371.301773 -222.276924) (xy 371.250596 -222.268818) (xy 371.201317 -222.252806) (xy 371.15515 -222.229283)
			(xy 371.113231 -222.198827) (xy 371.076593 -222.162189) (xy 371.046137 -222.12027) (xy 371.022614 -222.074103)
			(xy 371.006602 -222.024824) (xy 370.998496 -221.973647) (xy 370.997988 -221.94774) (xy 369.777772 -221.94774)
			(xy 369.777264 -221.973647) (xy 369.769158 -222.024824) (xy 369.753146 -222.074103) (xy 369.729623 -222.12027)
			(xy 369.699167 -222.162189) (xy 369.662529 -222.198827) (xy 369.62061 -222.229283) (xy 369.574443 -222.252806)
			(xy 369.525164 -222.268818) (xy 369.473987 -222.276924) (xy 369.422173 -222.276924) (xy 369.370996 -222.268818)
			(xy 369.321717 -222.252806) (xy 369.27555 -222.229283) (xy 369.233631 -222.198827) (xy 369.196993 -222.162189)
			(xy 369.166537 -222.12027) (xy 369.143014 -222.074103) (xy 369.127002 -222.024824) (xy 369.118896 -221.973647)
			(xy 369.118388 -221.94774) (xy 366.018572 -221.94774) (xy 366.018064 -221.973647) (xy 366.009958 -222.024824)
			(xy 365.993946 -222.074103) (xy 365.970423 -222.12027) (xy 365.939967 -222.162189) (xy 365.903329 -222.198827)
			(xy 365.86141 -222.229283) (xy 365.815243 -222.252806) (xy 365.765964 -222.268818) (xy 365.714787 -222.276924)
			(xy 365.662973 -222.276924) (xy 365.611796 -222.268818) (xy 365.562517 -222.252806) (xy 365.51635 -222.229283)
			(xy 365.474431 -222.198827) (xy 365.437793 -222.162189) (xy 365.407337 -222.12027) (xy 365.383814 -222.074103)
			(xy 365.367802 -222.024824) (xy 365.359696 -221.973647) (xy 365.359188 -221.94774) (xy 364.138972 -221.94774)
			(xy 364.138461 -221.973645) (xy 364.13035 -222.024815) (xy 364.114335 -222.074087) (xy 364.090809 -222.120248)
			(xy 364.060352 -222.162159) (xy 364.023714 -222.198791) (xy 363.981796 -222.22924) (xy 363.935632 -222.252758)
			(xy 363.886357 -222.268764) (xy 363.835185 -222.276865) (xy 363.80928 -222.277432) (xy 363.77919 -222.276715)
			(xy 363.72002 -222.265721) (xy 363.691678 -222.255588) (xy 363.678354 -222.250968) (xy 363.650276 -222.248456)
			(xy 363.62258 -222.253714) (xy 363.597376 -222.26634) (xy 363.576581 -222.285373) (xy 363.56178 -222.309365)
			(xy 363.554098 -222.336489) (xy 363.553756 -222.350584) (xy 363.553756 -222.51289) (xy 363.572883 -222.530015)
			(xy 363.606095 -222.56916) (xy 363.632807 -222.612999) (xy 363.652368 -222.660462) (xy 363.664301 -222.710392)
			(xy 363.668314 -222.761571) (xy 363.66431 -222.812751) (xy 363.652386 -222.862683) (xy 363.632833 -222.91015)
			(xy 363.606129 -222.953993) (xy 363.572924 -222.993145) (xy 363.553756 -223.010222) (xy 363.553756 -224.138998)
			(xy 363.571504 -224.154734) (xy 363.602743 -224.190424) (xy 363.628547 -224.230221) (xy 363.648383 -224.273305)
			(xy 363.661842 -224.318786) (xy 363.668646 -224.365727) (xy 363.669072 -224.389442) (xy 363.949996 -224.389442)
			(xy 363.950429 -224.364106) (xy 363.95819 -224.314032) (xy 363.97352 -224.265734) (xy 363.996059 -224.22035)
			(xy 364.025275 -224.178949) (xy 364.060481 -224.142504) (xy 364.100848 -224.111874) (xy 364.145426 -224.087781)
			(xy 364.193165 -224.070791) (xy 364.217966 -224.065592) (xy 364.240826 -224.061274) (xy 364.44555 -223.706436)
			(xy 364.43793 -223.684338) (xy 364.429302 -223.657991) (xy 364.419979 -223.603344) (xy 364.419388 -223.575626)
			(xy 364.419896 -223.549719) (xy 364.428002 -223.498542) (xy 364.444014 -223.449263) (xy 364.467537 -223.403096)
			(xy 364.497993 -223.361177) (xy 364.534631 -223.324539) (xy 364.57655 -223.294083) (xy 364.622717 -223.27056)
			(xy 364.671996 -223.254548) (xy 364.723173 -223.246442) (xy 364.774987 -223.246442) (xy 364.826164 -223.254548)
			(xy 364.875443 -223.27056) (xy 364.92161 -223.294083) (xy 364.963529 -223.324539) (xy 365.000167 -223.361177)
			(xy 365.030623 -223.403096) (xy 365.054146 -223.449263) (xy 365.070158 -223.498542) (xy 365.078264 -223.549719)
			(xy 365.078772 -223.575626) (xy 365.078381 -223.600993) (xy 365.070628 -223.651131) (xy 365.055277 -223.699486)
			(xy 365.032692 -223.744915) (xy 365.003407 -223.786344) (xy 364.968116 -223.822791) (xy 364.927652 -223.853396)
			(xy 364.882974 -223.877433) (xy 364.835139 -223.894334) (xy 364.810294 -223.899476) (xy 364.787434 -223.903794)
			(xy 364.58271 -224.258632) (xy 364.590584 -224.280476) (xy 364.599157 -224.306897) (xy 364.608358 -224.36167)
			(xy 364.608872 -224.389442) (xy 364.889796 -224.389442) (xy 364.890304 -224.363555) (xy 364.898403 -224.312417)
			(xy 364.914402 -224.263177) (xy 364.937908 -224.217045) (xy 364.96834 -224.175158) (xy 365.00495 -224.138548)
			(xy 365.046837 -224.108116) (xy 365.092969 -224.08461) (xy 365.142209 -224.068611) (xy 365.193347 -224.060512)
			(xy 365.245121 -224.060512) (xy 365.296259 -224.068611) (xy 365.345499 -224.08461) (xy 365.391631 -224.108116)
			(xy 365.433518 -224.138548) (xy 365.470128 -224.175158) (xy 365.50056 -224.217045) (xy 365.524066 -224.263177)
			(xy 365.540065 -224.312417) (xy 365.548164 -224.363555) (xy 365.548672 -224.389442) (xy 365.829596 -224.389442)
			(xy 365.830029 -224.364106) (xy 365.83779 -224.314032) (xy 365.85312 -224.265734) (xy 365.875659 -224.22035)
			(xy 365.904875 -224.178949) (xy 365.940081 -224.142504) (xy 365.980448 -224.111874) (xy 366.025026 -224.087781)
			(xy 366.072765 -224.070791) (xy 366.097566 -224.065592) (xy 366.120426 -224.061274) (xy 366.32515 -223.706436)
			(xy 366.31753 -223.684338) (xy 366.308902 -223.657991) (xy 366.299579 -223.603344) (xy 366.298988 -223.575626)
			(xy 366.299496 -223.549719) (xy 366.307602 -223.498542) (xy 366.323614 -223.449263) (xy 366.347137 -223.403096)
			(xy 366.377593 -223.361177) (xy 366.414231 -223.324539) (xy 366.45615 -223.294083) (xy 366.502317 -223.27056)
			(xy 366.551596 -223.254548) (xy 366.602773 -223.246442) (xy 366.654587 -223.246442) (xy 366.705764 -223.254548)
			(xy 366.755043 -223.27056) (xy 366.80121 -223.294083) (xy 366.843129 -223.324539) (xy 366.879767 -223.361177)
			(xy 366.910223 -223.403096) (xy 366.933746 -223.449263) (xy 366.949758 -223.498542) (xy 366.957864 -223.549719)
			(xy 366.958372 -223.575626) (xy 366.957981 -223.600993) (xy 366.950228 -223.651131) (xy 366.934877 -223.699486)
			(xy 366.912292 -223.744915) (xy 366.883007 -223.786344) (xy 366.847716 -223.822791) (xy 366.807252 -223.853396)
			(xy 366.762574 -223.877433) (xy 366.714739 -223.894334) (xy 366.689894 -223.899476) (xy 366.667034 -223.903794)
			(xy 366.46231 -224.258632) (xy 366.470184 -224.280476) (xy 366.478757 -224.306897) (xy 366.487958 -224.36167)
			(xy 366.488472 -224.389442) (xy 366.769396 -224.389442) (xy 366.769904 -224.363555) (xy 366.778003 -224.312417)
			(xy 366.794002 -224.263177) (xy 366.817508 -224.217045) (xy 366.84794 -224.175158) (xy 366.88455 -224.138548)
			(xy 366.926437 -224.108116) (xy 366.972569 -224.08461) (xy 367.021809 -224.068611) (xy 367.072947 -224.060512)
			(xy 367.124721 -224.060512) (xy 367.175859 -224.068611) (xy 367.225099 -224.08461) (xy 367.271231 -224.108116)
			(xy 367.313118 -224.138548) (xy 367.349728 -224.175158) (xy 367.38016 -224.217045) (xy 367.403666 -224.263177)
			(xy 367.419665 -224.312417) (xy 367.427764 -224.363555) (xy 367.428272 -224.389442) (xy 367.709196 -224.389442)
			(xy 367.709629 -224.364106) (xy 367.71739 -224.314032) (xy 367.73272 -224.265734) (xy 367.755259 -224.22035)
			(xy 367.784475 -224.178949) (xy 367.819681 -224.142504) (xy 367.860048 -224.111874) (xy 367.904626 -224.087781)
			(xy 367.952365 -224.070791) (xy 367.977166 -224.065592) (xy 368.000026 -224.061274) (xy 368.20475 -223.706436)
			(xy 368.19713 -223.684338) (xy 368.188502 -223.657991) (xy 368.179179 -223.603344) (xy 368.178588 -223.575626)
			(xy 368.179096 -223.549719) (xy 368.187202 -223.498542) (xy 368.203214 -223.449263) (xy 368.226737 -223.403096)
			(xy 368.257193 -223.361177) (xy 368.293831 -223.324539) (xy 368.33575 -223.294083) (xy 368.381917 -223.27056)
			(xy 368.431196 -223.254548) (xy 368.482373 -223.246442) (xy 368.534187 -223.246442) (xy 368.585364 -223.254548)
			(xy 368.634643 -223.27056) (xy 368.68081 -223.294083) (xy 368.722729 -223.324539) (xy 368.759367 -223.361177)
			(xy 368.789823 -223.403096) (xy 368.813346 -223.449263) (xy 368.829358 -223.498542) (xy 368.837464 -223.549719)
			(xy 368.837972 -223.575626) (xy 368.837581 -223.600993) (xy 368.829828 -223.651131) (xy 368.814477 -223.699486)
			(xy 368.791892 -223.744915) (xy 368.762607 -223.786344) (xy 368.727316 -223.822791) (xy 368.686852 -223.853396)
			(xy 368.642174 -223.877433) (xy 368.594339 -223.894334) (xy 368.569494 -223.899476) (xy 368.546634 -223.903794)
			(xy 368.34191 -224.258632) (xy 368.349784 -224.280476) (xy 368.358357 -224.306897) (xy 368.367558 -224.36167)
			(xy 368.368072 -224.389442) (xy 368.648996 -224.389442) (xy 368.649504 -224.363555) (xy 368.657603 -224.312417)
			(xy 368.673602 -224.263177) (xy 368.697108 -224.217045) (xy 368.72754 -224.175158) (xy 368.76415 -224.138548)
			(xy 368.806037 -224.108116) (xy 368.852169 -224.08461) (xy 368.901409 -224.068611) (xy 368.952547 -224.060512)
			(xy 369.004321 -224.060512) (xy 369.055459 -224.068611) (xy 369.104699 -224.08461) (xy 369.150831 -224.108116)
			(xy 369.192718 -224.138548) (xy 369.229328 -224.175158) (xy 369.25976 -224.217045) (xy 369.283266 -224.263177)
			(xy 369.299265 -224.312417) (xy 369.307364 -224.363555) (xy 369.307872 -224.389442) (xy 369.588796 -224.389442)
			(xy 369.589229 -224.364106) (xy 369.59699 -224.314032) (xy 369.61232 -224.265734) (xy 369.634859 -224.22035)
			(xy 369.664075 -224.178949) (xy 369.699281 -224.142504) (xy 369.739648 -224.111874) (xy 369.784226 -224.087781)
			(xy 369.831965 -224.070791) (xy 369.856766 -224.065592) (xy 369.879626 -224.061274) (xy 370.08435 -223.706436)
			(xy 370.07673 -223.684338) (xy 370.068102 -223.657991) (xy 370.058779 -223.603344) (xy 370.058188 -223.575626)
			(xy 370.058696 -223.549719) (xy 370.066802 -223.498542) (xy 370.082814 -223.449263) (xy 370.106337 -223.403096)
			(xy 370.136793 -223.361177) (xy 370.173431 -223.324539) (xy 370.21535 -223.294083) (xy 370.261517 -223.27056)
			(xy 370.310796 -223.254548) (xy 370.361973 -223.246442) (xy 370.413787 -223.246442) (xy 370.464964 -223.254548)
			(xy 370.514243 -223.27056) (xy 370.56041 -223.294083) (xy 370.602329 -223.324539) (xy 370.638967 -223.361177)
			(xy 370.669423 -223.403096) (xy 370.692946 -223.449263) (xy 370.708958 -223.498542) (xy 370.717064 -223.549719)
			(xy 370.717572 -223.575626) (xy 370.717181 -223.600993) (xy 370.709428 -223.651131) (xy 370.694077 -223.699486)
			(xy 370.671492 -223.744915) (xy 370.642207 -223.786344) (xy 370.606916 -223.822791) (xy 370.566452 -223.853396)
			(xy 370.521774 -223.877433) (xy 370.473939 -223.894334) (xy 370.449094 -223.899476) (xy 370.426234 -223.903794)
			(xy 370.22151 -224.258632) (xy 370.229384 -224.280476) (xy 370.237957 -224.306897) (xy 370.247158 -224.36167)
			(xy 370.247672 -224.389442) (xy 370.528596 -224.389442) (xy 370.529104 -224.363555) (xy 370.537203 -224.312417)
			(xy 370.553202 -224.263177) (xy 370.576708 -224.217045) (xy 370.60714 -224.175158) (xy 370.64375 -224.138548)
			(xy 370.685637 -224.108116) (xy 370.731769 -224.08461) (xy 370.781009 -224.068611) (xy 370.832147 -224.060512)
			(xy 370.883921 -224.060512) (xy 370.935059 -224.068611) (xy 370.984299 -224.08461) (xy 371.030431 -224.108116)
			(xy 371.072318 -224.138548) (xy 371.108928 -224.175158) (xy 371.13936 -224.217045) (xy 371.162866 -224.263177)
			(xy 371.178865 -224.312417) (xy 371.186964 -224.363555) (xy 371.187472 -224.389442) (xy 371.468396 -224.389442)
			(xy 371.468829 -224.364106) (xy 371.47659 -224.314032) (xy 371.49192 -224.265734) (xy 371.514459 -224.22035)
			(xy 371.543675 -224.178949) (xy 371.578881 -224.142504) (xy 371.619248 -224.111874) (xy 371.663826 -224.087781)
			(xy 371.711565 -224.070791) (xy 371.736366 -224.065592) (xy 371.759226 -224.061274) (xy 371.96395 -223.706436)
			(xy 371.95633 -223.684338) (xy 371.947702 -223.657991) (xy 371.938379 -223.603344) (xy 371.937788 -223.575626)
			(xy 371.938296 -223.549719) (xy 371.946402 -223.498542) (xy 371.962414 -223.449263) (xy 371.985937 -223.403096)
			(xy 372.016393 -223.361177) (xy 372.053031 -223.324539) (xy 372.09495 -223.294083) (xy 372.141117 -223.27056)
			(xy 372.190396 -223.254548) (xy 372.241573 -223.246442) (xy 372.293387 -223.246442) (xy 372.344564 -223.254548)
			(xy 372.393843 -223.27056) (xy 372.44001 -223.294083) (xy 372.481929 -223.324539) (xy 372.518567 -223.361177)
			(xy 372.549023 -223.403096) (xy 372.572546 -223.449263) (xy 372.588558 -223.498542) (xy 372.596664 -223.549719)
			(xy 372.597172 -223.575626) (xy 372.596781 -223.600993) (xy 372.589028 -223.651131) (xy 372.573677 -223.699486)
			(xy 372.551092 -223.744915) (xy 372.521807 -223.786344) (xy 372.486516 -223.822791) (xy 372.446052 -223.853396)
			(xy 372.401374 -223.877433) (xy 372.353539 -223.894334) (xy 372.328694 -223.899476) (xy 372.305834 -223.903794)
			(xy 372.10111 -224.258632) (xy 372.108984 -224.280476) (xy 372.117557 -224.306897) (xy 372.126758 -224.36167)
			(xy 372.127272 -224.389442) (xy 372.408196 -224.389442) (xy 372.408704 -224.363555) (xy 372.416803 -224.312417)
			(xy 372.432802 -224.263177) (xy 372.456308 -224.217045) (xy 372.48674 -224.175158) (xy 372.52335 -224.138548)
			(xy 372.565237 -224.108116) (xy 372.611369 -224.08461) (xy 372.660609 -224.068611) (xy 372.711747 -224.060512)
			(xy 372.763521 -224.060512) (xy 372.814659 -224.068611) (xy 372.863899 -224.08461) (xy 372.910031 -224.108116)
			(xy 372.951918 -224.138548) (xy 372.988528 -224.175158) (xy 373.01896 -224.217045) (xy 373.042466 -224.263177)
			(xy 373.058465 -224.312417) (xy 373.066564 -224.363555) (xy 373.067072 -224.389442) (xy 373.347996 -224.389442)
			(xy 373.348429 -224.364106) (xy 373.35619 -224.314032) (xy 373.37152 -224.265734) (xy 373.394059 -224.22035)
			(xy 373.423275 -224.178949) (xy 373.458481 -224.142504) (xy 373.498848 -224.111874) (xy 373.543426 -224.087781)
			(xy 373.591165 -224.070791) (xy 373.615966 -224.065592) (xy 373.638826 -224.061274) (xy 373.84355 -223.706436)
			(xy 373.83593 -223.684338) (xy 373.827302 -223.657991) (xy 373.817979 -223.603344) (xy 373.817388 -223.575626)
			(xy 373.817896 -223.549719) (xy 373.826002 -223.498542) (xy 373.842014 -223.449263) (xy 373.865537 -223.403096)
			(xy 373.895993 -223.361177) (xy 373.932631 -223.324539) (xy 373.97455 -223.294083) (xy 374.020717 -223.27056)
			(xy 374.069996 -223.254548) (xy 374.121173 -223.246442) (xy 374.172987 -223.246442) (xy 374.224164 -223.254548)
			(xy 374.273443 -223.27056) (xy 374.31961 -223.294083) (xy 374.361529 -223.324539) (xy 374.398167 -223.361177)
			(xy 374.428623 -223.403096) (xy 374.452146 -223.449263) (xy 374.468158 -223.498542) (xy 374.476264 -223.549719)
			(xy 374.476772 -223.575626) (xy 374.476381 -223.600993) (xy 374.468628 -223.651131) (xy 374.453277 -223.699486)
			(xy 374.430692 -223.744915) (xy 374.401407 -223.786344) (xy 374.366116 -223.822791) (xy 374.325652 -223.853396)
			(xy 374.280974 -223.877433) (xy 374.233139 -223.894334) (xy 374.208294 -223.899476) (xy 374.185434 -223.903794)
			(xy 373.98071 -224.258632) (xy 373.988584 -224.280476) (xy 373.997157 -224.306897) (xy 374.006358 -224.36167)
			(xy 374.006872 -224.389442) (xy 374.006364 -224.415329) (xy 373.998265 -224.466467) (xy 373.982266 -224.515707)
			(xy 373.95876 -224.561839) (xy 373.928328 -224.603726) (xy 373.891718 -224.640336) (xy 373.849831 -224.670768)
			(xy 373.803699 -224.694274) (xy 373.754459 -224.710273) (xy 373.703321 -224.718372) (xy 373.651547 -224.718372)
			(xy 373.600409 -224.710273) (xy 373.551169 -224.694274) (xy 373.505037 -224.670768) (xy 373.46315 -224.640336)
			(xy 373.42654 -224.603726) (xy 373.396108 -224.561839) (xy 373.372602 -224.515707) (xy 373.356603 -224.466467)
			(xy 373.348504 -224.415329) (xy 373.347996 -224.389442) (xy 373.067072 -224.389442) (xy 373.066525 -224.417149)
			(xy 373.057341 -224.471796) (xy 373.048784 -224.498154) (xy 373.04091 -224.520252) (xy 373.245888 -224.87509)
			(xy 373.268748 -224.879408) (xy 373.293571 -224.884565) (xy 373.341351 -224.90152) (xy 373.385971 -224.925592)
			(xy 373.426378 -224.956214) (xy 373.461619 -224.992662) (xy 373.490863 -225.034077) (xy 373.513419 -225.079482)
			(xy 373.528756 -225.127806) (xy 373.536511 -225.177908) (xy 373.536972 -225.203258) (xy 373.536464 -225.229165)
			(xy 373.528358 -225.280342) (xy 373.512346 -225.329621) (xy 373.488823 -225.375788) (xy 373.458367 -225.417707)
			(xy 373.421729 -225.454345) (xy 373.37981 -225.484801) (xy 373.333643 -225.508324) (xy 373.284364 -225.524336)
			(xy 373.233187 -225.532442) (xy 373.181373 -225.532442) (xy 373.130196 -225.524336) (xy 373.080917 -225.508324)
			(xy 373.03475 -225.484801) (xy 372.992831 -225.454345) (xy 372.956193 -225.417707) (xy 372.925737 -225.375788)
			(xy 372.902214 -225.329621) (xy 372.886202 -225.280342) (xy 372.878096 -225.229165) (xy 372.877588 -225.203258)
			(xy 372.878197 -225.175541) (xy 372.88751 -225.120895) (xy 372.89613 -225.094546) (xy 372.904004 -225.072448)
			(xy 372.699026 -224.71761) (xy 372.676166 -224.713292) (xy 372.651348 -224.708169) (xy 372.603605 -224.691172)
			(xy 372.559026 -224.667071) (xy 372.51866 -224.636431) (xy 372.483457 -224.599976) (xy 372.454248 -224.558564)
			(xy 372.431719 -224.51317) (xy 372.416401 -224.464863) (xy 372.408655 -224.414781) (xy 372.408196 -224.389442)
			(xy 372.127272 -224.389442) (xy 372.126764 -224.415329) (xy 372.118665 -224.466467) (xy 372.102666 -224.515707)
			(xy 372.07916 -224.561839) (xy 372.048728 -224.603726) (xy 372.012118 -224.640336) (xy 371.970231 -224.670768)
			(xy 371.924099 -224.694274) (xy 371.874859 -224.710273) (xy 371.823721 -224.718372) (xy 371.771947 -224.718372)
			(xy 371.720809 -224.710273) (xy 371.671569 -224.694274) (xy 371.625437 -224.670768) (xy 371.58355 -224.640336)
			(xy 371.54694 -224.603726) (xy 371.516508 -224.561839) (xy 371.493002 -224.515707) (xy 371.477003 -224.466467)
			(xy 371.468904 -224.415329) (xy 371.468396 -224.389442) (xy 371.187472 -224.389442) (xy 371.186925 -224.417149)
			(xy 371.177741 -224.471796) (xy 371.169184 -224.498154) (xy 371.16131 -224.520252) (xy 371.366288 -224.87509)
			(xy 371.389148 -224.879408) (xy 371.413971 -224.884565) (xy 371.461751 -224.90152) (xy 371.506371 -224.925592)
			(xy 371.546778 -224.956214) (xy 371.582019 -224.992662) (xy 371.611263 -225.034077) (xy 371.633819 -225.079482)
			(xy 371.649156 -225.127806) (xy 371.656911 -225.177908) (xy 371.657372 -225.203258) (xy 371.656864 -225.229165)
			(xy 371.648758 -225.280342) (xy 371.632746 -225.329621) (xy 371.609223 -225.375788) (xy 371.578767 -225.417707)
			(xy 371.542129 -225.454345) (xy 371.50021 -225.484801) (xy 371.454043 -225.508324) (xy 371.404764 -225.524336)
			(xy 371.353587 -225.532442) (xy 371.301773 -225.532442) (xy 371.250596 -225.524336) (xy 371.201317 -225.508324)
			(xy 371.15515 -225.484801) (xy 371.113231 -225.454345) (xy 371.076593 -225.417707) (xy 371.046137 -225.375788)
			(xy 371.022614 -225.329621) (xy 371.006602 -225.280342) (xy 370.998496 -225.229165) (xy 370.997988 -225.203258)
			(xy 370.998597 -225.175541) (xy 371.00791 -225.120895) (xy 371.01653 -225.094546) (xy 371.024404 -225.072448)
			(xy 370.819426 -224.71761) (xy 370.796566 -224.713292) (xy 370.771748 -224.708169) (xy 370.724005 -224.691172)
			(xy 370.679426 -224.667071) (xy 370.63906 -224.636431) (xy 370.603857 -224.599976) (xy 370.574648 -224.558564)
			(xy 370.552119 -224.51317) (xy 370.536801 -224.464863) (xy 370.529055 -224.414781) (xy 370.528596 -224.389442)
			(xy 370.247672 -224.389442) (xy 370.247164 -224.415329) (xy 370.239065 -224.466467) (xy 370.223066 -224.515707)
			(xy 370.19956 -224.561839) (xy 370.169128 -224.603726) (xy 370.132518 -224.640336) (xy 370.090631 -224.670768)
			(xy 370.044499 -224.694274) (xy 369.995259 -224.710273) (xy 369.944121 -224.718372) (xy 369.892347 -224.718372)
			(xy 369.841209 -224.710273) (xy 369.791969 -224.694274) (xy 369.745837 -224.670768) (xy 369.70395 -224.640336)
			(xy 369.66734 -224.603726) (xy 369.636908 -224.561839) (xy 369.613402 -224.515707) (xy 369.597403 -224.466467)
			(xy 369.589304 -224.415329) (xy 369.588796 -224.389442) (xy 369.307872 -224.389442) (xy 369.307325 -224.417149)
			(xy 369.298141 -224.471796) (xy 369.289584 -224.498154) (xy 369.28171 -224.520252) (xy 369.486688 -224.87509)
			(xy 369.509548 -224.879408) (xy 369.534371 -224.884565) (xy 369.582151 -224.90152) (xy 369.626771 -224.925592)
			(xy 369.667178 -224.956214) (xy 369.702419 -224.992662) (xy 369.731663 -225.034077) (xy 369.754219 -225.079482)
			(xy 369.769556 -225.127806) (xy 369.777311 -225.177908) (xy 369.777772 -225.203258) (xy 369.777264 -225.229165)
			(xy 369.769158 -225.280342) (xy 369.753146 -225.329621) (xy 369.729623 -225.375788) (xy 369.699167 -225.417707)
			(xy 369.662529 -225.454345) (xy 369.62061 -225.484801) (xy 369.574443 -225.508324) (xy 369.525164 -225.524336)
			(xy 369.473987 -225.532442) (xy 369.422173 -225.532442) (xy 369.370996 -225.524336) (xy 369.321717 -225.508324)
			(xy 369.27555 -225.484801) (xy 369.233631 -225.454345) (xy 369.196993 -225.417707) (xy 369.166537 -225.375788)
			(xy 369.143014 -225.329621) (xy 369.127002 -225.280342) (xy 369.118896 -225.229165) (xy 369.118388 -225.203258)
			(xy 369.118997 -225.175541) (xy 369.12831 -225.120895) (xy 369.13693 -225.094546) (xy 369.144804 -225.072448)
			(xy 368.939826 -224.71761) (xy 368.916966 -224.713292) (xy 368.892148 -224.708169) (xy 368.844405 -224.691172)
			(xy 368.799826 -224.667071) (xy 368.75946 -224.636431) (xy 368.724257 -224.599976) (xy 368.695048 -224.558564)
			(xy 368.672519 -224.51317) (xy 368.657201 -224.464863) (xy 368.649455 -224.414781) (xy 368.648996 -224.389442)
			(xy 368.368072 -224.389442) (xy 368.367564 -224.415329) (xy 368.359465 -224.466467) (xy 368.343466 -224.515707)
			(xy 368.31996 -224.561839) (xy 368.289528 -224.603726) (xy 368.252918 -224.640336) (xy 368.211031 -224.670768)
			(xy 368.164899 -224.694274) (xy 368.115659 -224.710273) (xy 368.064521 -224.718372) (xy 368.012747 -224.718372)
			(xy 367.961609 -224.710273) (xy 367.912369 -224.694274) (xy 367.866237 -224.670768) (xy 367.82435 -224.640336)
			(xy 367.78774 -224.603726) (xy 367.757308 -224.561839) (xy 367.733802 -224.515707) (xy 367.717803 -224.466467)
			(xy 367.709704 -224.415329) (xy 367.709196 -224.389442) (xy 367.428272 -224.389442) (xy 367.427725 -224.417149)
			(xy 367.418541 -224.471796) (xy 367.409984 -224.498154) (xy 367.40211 -224.520252) (xy 367.607088 -224.87509)
			(xy 367.629948 -224.879408) (xy 367.654771 -224.884565) (xy 367.702551 -224.90152) (xy 367.747171 -224.925592)
			(xy 367.787578 -224.956214) (xy 367.822819 -224.992662) (xy 367.852063 -225.034077) (xy 367.874619 -225.079482)
			(xy 367.889956 -225.127806) (xy 367.897711 -225.177908) (xy 367.898172 -225.203258) (xy 367.897664 -225.229165)
			(xy 367.889558 -225.280342) (xy 367.873546 -225.329621) (xy 367.850023 -225.375788) (xy 367.819567 -225.417707)
			(xy 367.782929 -225.454345) (xy 367.74101 -225.484801) (xy 367.694843 -225.508324) (xy 367.645564 -225.524336)
			(xy 367.594387 -225.532442) (xy 367.542573 -225.532442) (xy 367.491396 -225.524336) (xy 367.442117 -225.508324)
			(xy 367.39595 -225.484801) (xy 367.354031 -225.454345) (xy 367.317393 -225.417707) (xy 367.286937 -225.375788)
			(xy 367.263414 -225.329621) (xy 367.247402 -225.280342) (xy 367.239296 -225.229165) (xy 367.238788 -225.203258)
			(xy 367.239397 -225.175541) (xy 367.24871 -225.120895) (xy 367.25733 -225.094546) (xy 367.265204 -225.072448)
			(xy 367.060226 -224.71761) (xy 367.037366 -224.713292) (xy 367.012548 -224.708169) (xy 366.964805 -224.691172)
			(xy 366.920226 -224.667071) (xy 366.87986 -224.636431) (xy 366.844657 -224.599976) (xy 366.815448 -224.558564)
			(xy 366.792919 -224.51317) (xy 366.777601 -224.464863) (xy 366.769855 -224.414781) (xy 366.769396 -224.389442)
			(xy 366.488472 -224.389442) (xy 366.487964 -224.415329) (xy 366.479865 -224.466467) (xy 366.463866 -224.515707)
			(xy 366.44036 -224.561839) (xy 366.409928 -224.603726) (xy 366.373318 -224.640336) (xy 366.331431 -224.670768)
			(xy 366.285299 -224.694274) (xy 366.236059 -224.710273) (xy 366.184921 -224.718372) (xy 366.133147 -224.718372)
			(xy 366.082009 -224.710273) (xy 366.032769 -224.694274) (xy 365.986637 -224.670768) (xy 365.94475 -224.640336)
			(xy 365.90814 -224.603726) (xy 365.877708 -224.561839) (xy 365.854202 -224.515707) (xy 365.838203 -224.466467)
			(xy 365.830104 -224.415329) (xy 365.829596 -224.389442) (xy 365.548672 -224.389442) (xy 365.548125 -224.417149)
			(xy 365.538941 -224.471796) (xy 365.530384 -224.498154) (xy 365.52251 -224.520252) (xy 365.727488 -224.87509)
			(xy 365.750348 -224.879408) (xy 365.775171 -224.884565) (xy 365.822951 -224.90152) (xy 365.867571 -224.925592)
			(xy 365.907978 -224.956214) (xy 365.943219 -224.992662) (xy 365.972463 -225.034077) (xy 365.995019 -225.079482)
			(xy 366.010356 -225.127806) (xy 366.018111 -225.177908) (xy 366.018572 -225.203258) (xy 366.018064 -225.229165)
			(xy 366.009958 -225.280342) (xy 365.993946 -225.329621) (xy 365.970423 -225.375788) (xy 365.939967 -225.417707)
			(xy 365.903329 -225.454345) (xy 365.86141 -225.484801) (xy 365.815243 -225.508324) (xy 365.765964 -225.524336)
			(xy 365.714787 -225.532442) (xy 365.662973 -225.532442) (xy 365.611796 -225.524336) (xy 365.562517 -225.508324)
			(xy 365.51635 -225.484801) (xy 365.474431 -225.454345) (xy 365.437793 -225.417707) (xy 365.407337 -225.375788)
			(xy 365.383814 -225.329621) (xy 365.367802 -225.280342) (xy 365.359696 -225.229165) (xy 365.359188 -225.203258)
			(xy 365.359797 -225.175541) (xy 365.36911 -225.120895) (xy 365.37773 -225.094546) (xy 365.385604 -225.072448)
			(xy 365.180626 -224.71761) (xy 365.157766 -224.713292) (xy 365.132948 -224.708169) (xy 365.085205 -224.691172)
			(xy 365.040626 -224.667071) (xy 365.00026 -224.636431) (xy 364.965057 -224.599976) (xy 364.935848 -224.558564)
			(xy 364.913319 -224.51317) (xy 364.898001 -224.464863) (xy 364.890255 -224.414781) (xy 364.889796 -224.389442)
			(xy 364.608872 -224.389442) (xy 364.608364 -224.415329) (xy 364.600265 -224.466467) (xy 364.584266 -224.515707)
			(xy 364.56076 -224.561839) (xy 364.530328 -224.603726) (xy 364.493718 -224.640336) (xy 364.451831 -224.670768)
			(xy 364.405699 -224.694274) (xy 364.356459 -224.710273) (xy 364.305321 -224.718372) (xy 364.253547 -224.718372)
			(xy 364.202409 -224.710273) (xy 364.153169 -224.694274) (xy 364.107037 -224.670768) (xy 364.06515 -224.640336)
			(xy 364.02854 -224.603726) (xy 363.998108 -224.561839) (xy 363.974602 -224.515707) (xy 363.958603 -224.466467)
			(xy 363.950504 -224.415329) (xy 363.949996 -224.389442) (xy 363.669072 -224.389442) (xy 363.668548 -224.417151)
			(xy 363.659358 -224.4718) (xy 363.650784 -224.498154) (xy 363.64291 -224.520252) (xy 363.847888 -224.87509)
			(xy 363.870748 -224.879408) (xy 363.895562 -224.884594) (xy 363.94333 -224.901564) (xy 363.987938 -224.925644)
			(xy 364.028335 -224.956266) (xy 364.063572 -224.992709) (xy 364.092816 -225.034115) (xy 364.115381 -225.079509)
			(xy 364.130733 -225.12782) (xy 364.138511 -225.177912) (xy 364.138972 -225.203258) (xy 364.138493 -225.229163)
			(xy 364.13039 -225.280336) (xy 364.114379 -225.32961) (xy 364.090852 -225.375771) (xy 364.060391 -225.417681)
			(xy 364.023745 -225.454306) (xy 363.981819 -225.484745) (xy 363.935646 -225.508247) (xy 363.886363 -225.524232)
			(xy 363.835185 -225.532307) (xy 363.80928 -225.532696) (xy 363.779199 -225.532049) (xy 363.720028 -225.521182)
			(xy 363.691678 -225.511106) (xy 363.678355 -225.506485) (xy 363.650278 -225.503973) (xy 363.622583 -225.509231)
			(xy 363.59738 -225.521857) (xy 363.576588 -225.540891) (xy 363.56179 -225.564884) (xy 363.554113 -225.592007)
			(xy 363.553756 -225.606102) (xy 363.553756 -225.768662) (xy 363.572878 -225.785786) (xy 363.606078 -225.82493)
			(xy 363.63278 -225.868765) (xy 363.652331 -225.916224) (xy 363.664254 -225.966147) (xy 363.668259 -226.017318)
			(xy 363.664249 -226.068489) (xy 363.65232 -226.118411) (xy 363.632763 -226.165867) (xy 363.606057 -226.2097)
			(xy 363.572852 -226.24884) (xy 363.553756 -226.265994) (xy 363.553756 -227.396294) (xy 363.57132 -227.411952)
			(xy 363.602226 -227.447432) (xy 363.627749 -227.486961) (xy 363.647364 -227.529731) (xy 363.660671 -227.574863)
			(xy 363.667396 -227.621433) (xy 363.667802 -227.64496) (xy 363.66764 -227.659001) (xy 363.665219 -227.686978)
			(xy 363.662976 -227.70084) (xy 363.658404 -227.726748) (xy 365.689642 -229.757986) (xy 365.708692 -229.759002)
			(xy 365.735071 -229.761128) (xy 365.786699 -229.772751) (xy 365.835793 -229.792504) (xy 365.881083 -229.819877)
			(xy 365.921396 -229.854161) (xy 365.955687 -229.894467) (xy 365.983068 -229.939752) (xy 366.002831 -229.988843)
			(xy 366.014463 -230.040468) (xy 366.01654 -230.06685) (xy 366.017556 -230.0859) (xy 367.377218 -231.445562)
			(xy 367.410746 -231.42702) (xy 367.435145 -231.414243) (xy 367.487152 -231.396127) (xy 367.541452 -231.386939)
			(xy 367.568988 -231.38638) (xy 367.594777 -231.386859) (xy 367.64572 -231.394927) (xy 367.694773 -231.410865)
			(xy 367.740729 -231.434282) (xy 367.782455 -231.4646) (xy 367.818924 -231.501073) (xy 367.849237 -231.542802)
			(xy 367.872649 -231.58876) (xy 367.888582 -231.637815) (xy 367.896644 -231.688759) (xy 367.897156 -231.714548)
			(xy 367.896599 -231.742085) (xy 367.88742 -231.796388) (xy 367.869309 -231.848399) (xy 367.856516 -231.87279)
			(xy 367.837974 -231.906318) (xy 368.151918 -232.220262) (xy 368.16157 -232.224072) (xy 368.185777 -232.234432)
			(xy 368.230805 -232.261721) (xy 368.270901 -232.295848) (xy 368.305036 -232.335935) (xy 368.332335 -232.380957)
			(xy 368.342672 -232.405174) (xy 368.346482 -232.414826) (xy 369.7859 -233.854244) (xy 369.815618 -233.844592)
			(xy 369.84057 -233.836888) (xy 369.892125 -233.828598) (xy 369.918234 -233.828082) (xy 369.94402 -233.828564)
			(xy 369.994958 -233.836638) (xy 370.044005 -233.85258) (xy 370.089954 -233.875999) (xy 370.131673 -233.906318)
			(xy 370.168136 -233.942791) (xy 370.198445 -233.984518) (xy 370.221852 -234.030473) (xy 370.237782 -234.079524)
			(xy 370.245842 -234.130463) (xy 370.246402 -234.15625) (xy 370.245875 -234.182357) (xy 370.23758 -234.23391)
			(xy 370.229892 -234.258866) (xy 370.22024 -234.288584) (xy 372.206266 -236.27461) (xy 372.23065 -236.271816)
			(xy 372.239827 -236.27085) (xy 372.258253 -236.269833) (xy 372.26748 -236.269784) (xy 372.29327 -236.270288)
			(xy 372.344215 -236.278353) (xy 372.393272 -236.294289) (xy 372.439232 -236.317702) (xy 372.480964 -236.348015)
			(xy 372.51744 -236.384484) (xy 372.547763 -236.42621) (xy 372.571185 -236.472165) (xy 372.587131 -236.521218)
			(xy 372.595206 -236.572162) (xy 372.595648 -236.597952) (xy 372.595588 -236.607179) (xy 372.594571 -236.625604)
			(xy 372.593616 -236.634782) (xy 372.590822 -236.659166) (xy 373.918226 -237.98657) (xy 373.953278 -237.960916)
			(xy 373.974512 -237.94596) (xy 374.020713 -237.922235) (xy 374.070075 -237.906089) (xy 374.121366 -237.897924)
			(xy 374.147334 -237.897416) (xy 374.17312 -237.897924) (xy 374.224057 -237.905996) (xy 374.273105 -237.921937)
			(xy 374.319055 -237.945353) (xy 374.360777 -237.975669) (xy 374.397243 -238.012137) (xy 374.427556 -238.05386)
			(xy 374.45097 -238.099812) (xy 374.466908 -238.14886) (xy 374.474977 -238.199798) (xy 374.475502 -238.225584)
			(xy 374.475027 -238.250671) (xy 374.467393 -238.300261) (xy 374.4523 -238.348111) (xy 374.430099 -238.393106)
			(xy 374.401309 -238.434198) (xy 374.384316 -238.45266) (xy 374.643396 -238.71174) (xy 374.660414 -238.714026)
			(xy 374.686935 -238.718087) (xy 374.738262 -238.733705) (xy 374.786365 -238.757463) (xy 374.829964 -238.788727)
			(xy 374.867898 -238.826666) (xy 374.899157 -238.870268) (xy 374.922909 -238.918374) (xy 374.938521 -238.969702)
			(xy 374.942608 -238.99622) (xy 374.944894 -239.013238) (xy 375.36247 -239.430814) (xy 375.37973 -239.448855)
			(xy 375.40749 -239.490349) (xy 375.426606 -239.536466) (xy 375.436343 -239.58543) (xy 375.436892 -239.610392)
			(xy 375.436892 -254.509778) (xy 375.453374 -254.528099) (xy 375.481219 -254.568759) (xy 375.50267 -254.613125)
			(xy 375.517247 -254.6602) (xy 375.524621 -254.708925) (xy 375.524626 -254.758205) (xy 375.517263 -254.806932)
			(xy 375.502696 -254.85401) (xy 375.481254 -254.89838) (xy 375.453418 -254.939046) (xy 375.436892 -254.957326)
			(xy 375.436892 -256.137664) (xy 375.453368 -256.155985) (xy 375.481199 -256.196643) (xy 375.502639 -256.241005)
			(xy 375.517204 -256.288074) (xy 375.524567 -256.336792) (xy 375.524563 -256.386063) (xy 375.517191 -256.43478)
			(xy 375.502618 -256.481847) (xy 375.481172 -256.526205) (xy 375.453333 -256.566859) (xy 375.436892 -256.585212)
			(xy 375.436892 -257.765042) (xy 375.453412 -257.783374) (xy 375.481325 -257.824067) (xy 375.50283 -257.868482)
			(xy 375.517443 -257.915615) (xy 375.524834 -257.964405) (xy 375.524837 -258.013751) (xy 375.517452 -258.062542)
			(xy 375.502846 -258.109678) (xy 375.481347 -258.154095) (xy 375.45344 -258.194792) (xy 375.436892 -258.213098)
			(xy 375.436892 -259.393182) (xy 375.453374 -259.411503) (xy 375.481218 -259.452163) (xy 375.502669 -259.496529)
			(xy 375.517245 -259.543603) (xy 375.524618 -259.592328) (xy 375.524623 -259.641608) (xy 375.517259 -259.690334)
			(xy 375.502692 -259.737411) (xy 375.48125 -259.781782) (xy 375.453414 -259.822447) (xy 375.436892 -259.84073)
			(xy 375.436892 -261.021068) (xy 375.45337 -261.03939) (xy 375.481206 -261.08005) (xy 375.502652 -261.124413)
			(xy 375.517225 -261.171484) (xy 375.524599 -261.220204) (xy 375.52503 -261.244842) (xy 375.524521 -261.270626)
			(xy 375.516448 -261.321559) (xy 375.500506 -261.370602) (xy 375.477088 -261.416547) (xy 375.446772 -261.458264)
			(xy 375.410303 -261.494724) (xy 375.368579 -261.52503) (xy 375.322628 -261.548436) (xy 375.273581 -261.564366)
			(xy 375.222646 -261.572427) (xy 375.196862 -261.57301) (xy 375.172756 -261.572602) (xy 375.125058 -261.565577)
			(xy 375.078905 -261.551638) (xy 375.056908 -261.541768) (xy 375.02465 -261.526274) (xy 374.32869 -262.222234)
			(xy 374.31065 -262.239497) (xy 374.269158 -262.267261) (xy 374.22304 -262.286381) (xy 374.174074 -262.29612)
			(xy 374.149112 -262.296656) (xy 374.013222 -262.296656) (xy 373.994807 -262.31349) (xy 373.953837 -262.34196)
			(xy 373.909033 -262.363907) (xy 373.861424 -262.378825) (xy 373.812107 -262.386371) (xy 373.762217 -262.386371)
			(xy 373.7129 -262.378825) (xy 373.665291 -262.363907) (xy 373.620487 -262.34196) (xy 373.579517 -262.31349)
			(xy 373.561102 -262.296656) (xy 373.073676 -262.296656) (xy 373.055261 -262.31349) (xy 373.014291 -262.34196)
			(xy 372.969487 -262.363907) (xy 372.921878 -262.378825) (xy 372.872561 -262.386371) (xy 372.822671 -262.386371)
			(xy 372.773354 -262.378825) (xy 372.725745 -262.363907) (xy 372.680941 -262.34196) (xy 372.639971 -262.31349)
			(xy 372.621556 -262.296656) (xy 372.133876 -262.296656) (xy 372.115461 -262.31349) (xy 372.074491 -262.34196)
			(xy 372.029687 -262.363907) (xy 371.982078 -262.378825) (xy 371.932761 -262.386371) (xy 371.882871 -262.386371)
			(xy 371.833554 -262.378825) (xy 371.785945 -262.363907) (xy 371.741141 -262.34196) (xy 371.700171 -262.31349)
			(xy 371.681756 -262.296656) (xy 371.193822 -262.296656) (xy 371.175407 -262.31349) (xy 371.134437 -262.34196)
			(xy 371.089633 -262.363907) (xy 371.042024 -262.378825) (xy 370.992707 -262.386371) (xy 370.942817 -262.386371)
			(xy 370.8935 -262.378825) (xy 370.845891 -262.363907) (xy 370.801087 -262.34196) (xy 370.760117 -262.31349)
			(xy 370.741702 -262.296656) (xy 370.254276 -262.296656) (xy 370.235861 -262.313489) (xy 370.194892 -262.341957)
			(xy 370.150087 -262.363899) (xy 370.102478 -262.37881) (xy 370.053161 -262.386346) (xy 370.028216 -262.386826)
			(xy 370.003047 -262.386369) (xy 369.9533 -262.378681) (xy 369.905311 -262.363484) (xy 369.860207 -262.341134)
			(xy 369.819047 -262.312155) (xy 369.782797 -262.277229) (xy 369.752308 -262.237175) (xy 369.728296 -262.192933)
			(xy 369.719352 -262.169402) (xy 369.703844 -262.168181) (xy 369.674081 -262.159165) (xy 369.64738 -262.14322)
			(xy 369.63604 -262.132572) (xy 369.546632 -262.043164) (xy 369.546124 -262.043164) (xy 369.293648 -261.790688)
			(xy 369.293648 -261.582154) (xy 369.270459 -261.563305) (xy 369.22902 -261.520249) (xy 369.193961 -261.471857)
			(xy 369.165961 -261.419064) (xy 369.145564 -261.362896) (xy 369.133164 -261.304439) (xy 369.129001 -261.244826)
			(xy 369.133157 -261.185213) (xy 369.14555 -261.126754) (xy 369.16594 -261.070583) (xy 369.193933 -261.017788)
			(xy 369.228987 -260.969391) (xy 369.270421 -260.92633) (xy 369.293648 -260.90753) (xy 369.293648 -260.520434)
			(xy 369.205764 -260.43255) (xy 369.053618 -260.43255) (xy 368.787934 -260.698234) (xy 368.769893 -260.715493)
			(xy 368.728399 -260.743247) (xy 368.68228 -260.762357) (xy 368.633317 -260.772086) (xy 368.608356 -260.772656)
			(xy 366.874044 -260.772656) (xy 366.728756 -260.917944) (xy 366.728756 -263.053322) (xy 366.763554 -263.065006)
			(xy 366.78768 -263.073599) (xy 366.833129 -263.097199) (xy 366.87436 -263.127573) (xy 366.910373 -263.163984)
			(xy 366.940292 -263.205546) (xy 366.963392 -263.251252) (xy 366.979111 -263.299991) (xy 366.987069 -263.35058)
			(xy 366.987071 -263.401792) (xy 366.979118 -263.452382) (xy 366.963402 -263.501122) (xy 366.940307 -263.54683)
			(xy 366.910391 -263.588395) (xy 366.874381 -263.624808) (xy 366.833153 -263.655186) (xy 366.787706 -263.67879)
			(xy 366.763554 -263.687306) (xy 366.728756 -263.69899) (xy 366.728756 -270.016478) (xy 367.416334 -270.704056)
			(xy 367.563146 -270.704056)
		)
		(stroke
			(width 0)
			(type solid)
		)
		(fill yes)
		(layer "In8.Cu")
		(net "PVCCINFAON_CPU0")
	)
	(gr_poly
		(pts
			(xy 429.35144 -351.388172) (xy 429.334781 -351.368584) (xy 429.306689 -351.325514) (xy 429.285089 -351.27885)
			(xy 429.270431 -351.229562) (xy 429.26302 -351.178678) (xy 429.26254 -351.152968) (xy 429.263011 -351.125641)
			(xy 429.271316 -351.071622) (xy 429.287787 -351.01951) (xy 429.312036 -350.97053) (xy 429.343492 -350.925837)
			(xy 429.362108 -350.905826) (xy 429.372503 -350.894206) (xy 429.386324 -350.866275) (xy 429.391074 -350.835477)
			(xy 429.38631 -350.80468) (xy 429.372477 -350.776756) (xy 429.362108 -350.76511) (xy 429.343545 -350.745058)
			(xy 429.312118 -350.700359) (xy 429.287882 -350.651387) (xy 429.271404 -350.59929) (xy 429.26307 -350.545288)
			(xy 429.26254 -350.517968) (xy 429.263011 -350.490641) (xy 429.271316 -350.436622) (xy 429.287787 -350.38451)
			(xy 429.312036 -350.33553) (xy 429.343492 -350.290837) (xy 429.362108 -350.270826) (xy 429.372503 -350.259206)
			(xy 429.386324 -350.231275) (xy 429.391074 -350.200477) (xy 429.38631 -350.16968) (xy 429.372477 -350.141756)
			(xy 429.362108 -350.13011) (xy 429.343545 -350.110058) (xy 429.312118 -350.065359) (xy 429.287882 -350.016387)
			(xy 429.271404 -349.96429) (xy 429.26307 -349.910288) (xy 429.26254 -349.882968) (xy 429.263011 -349.855641)
			(xy 429.271316 -349.801622) (xy 429.287787 -349.74951) (xy 429.312036 -349.70053) (xy 429.343492 -349.655837)
			(xy 429.362108 -349.635826) (xy 429.372503 -349.624206) (xy 429.386324 -349.596275) (xy 429.391074 -349.565477)
			(xy 429.38631 -349.53468) (xy 429.372477 -349.506756) (xy 429.362108 -349.49511) (xy 429.343545 -349.475058)
			(xy 429.312118 -349.430359) (xy 429.287882 -349.381387) (xy 429.271404 -349.32929) (xy 429.26307 -349.275288)
			(xy 429.26254 -349.247968) (xy 429.263011 -349.220641) (xy 429.271316 -349.166622) (xy 429.287787 -349.11451)
			(xy 429.312036 -349.06553) (xy 429.343492 -349.020837) (xy 429.362108 -349.000826) (xy 429.372503 -348.989206)
			(xy 429.386324 -348.961275) (xy 429.391074 -348.930477) (xy 429.38631 -348.89968) (xy 429.372477 -348.871756)
			(xy 429.362108 -348.86011) (xy 429.343545 -348.840058) (xy 429.312118 -348.795359) (xy 429.287882 -348.746387)
			(xy 429.271404 -348.69429) (xy 429.26307 -348.640288) (xy 429.26254 -348.612968) (xy 429.263011 -348.585641)
			(xy 429.271316 -348.531622) (xy 429.287787 -348.47951) (xy 429.312036 -348.43053) (xy 429.343492 -348.385837)
			(xy 429.362108 -348.365826) (xy 429.372503 -348.354206) (xy 429.386324 -348.326275) (xy 429.391074 -348.295477)
			(xy 429.38631 -348.26468) (xy 429.372477 -348.236756) (xy 429.362108 -348.22511) (xy 429.343545 -348.205058)
			(xy 429.312118 -348.160359) (xy 429.287882 -348.111387) (xy 429.271404 -348.05929) (xy 429.26307 -348.005288)
			(xy 429.26254 -347.977968) (xy 429.263011 -347.950641) (xy 429.271316 -347.896622) (xy 429.287787 -347.84451)
			(xy 429.312036 -347.79553) (xy 429.343492 -347.750837) (xy 429.362108 -347.730826) (xy 429.372503 -347.719206)
			(xy 429.386324 -347.691275) (xy 429.391074 -347.660477) (xy 429.38631 -347.62968) (xy 429.372477 -347.601756)
			(xy 429.362108 -347.59011) (xy 429.343545 -347.570058) (xy 429.312118 -347.525359) (xy 429.287882 -347.476387)
			(xy 429.271404 -347.42429) (xy 429.26307 -347.370288) (xy 429.26254 -347.342968) (xy 429.262995 -347.316935)
			(xy 429.270585 -347.265424) (xy 429.285597 -347.215569) (xy 429.307712 -347.168432) (xy 429.336458 -347.12502)
			(xy 429.371221 -347.086258) (xy 429.41126 -347.052975) (xy 429.455721 -347.025879) (xy 429.503655 -347.005548)
			(xy 429.528732 -346.998544) (xy 429.566578 -346.988384) (xy 429.566578 -329.811634) (xy 428.931578 -329.176634)
			(xy 428.914319 -329.158593) (xy 428.886563 -329.117099) (xy 428.867452 -329.070981) (xy 428.857723 -329.022017)
			(xy 428.857156 -328.997056) (xy 428.857156 -323.726302) (xy 428.834906 -323.710964) (xy 428.794878 -323.67466)
			(xy 428.760794 -323.632724) (xy 428.733438 -323.586121) (xy 428.713437 -323.535919) (xy 428.701251 -323.483271)
			(xy 428.697159 -323.429387) (xy 428.701255 -323.375503) (xy 428.713445 -323.322856) (xy 428.73345 -323.272656)
			(xy 428.760809 -323.226054) (xy 428.794896 -323.184121) (xy 428.834927 -323.147819) (xy 428.857156 -323.13245)
			(xy 428.857156 -215.524334) (xy 428.385478 -215.052656) (xy 376.155712 -215.052656) (xy 375.821956 -215.386412)
			(xy 375.821956 -216.056718) (xy 375.836875 -216.07793) (xy 375.860534 -216.124076) (xy 375.876625 -216.173374)
			(xy 375.884747 -216.224591) (xy 375.885202 -216.25052) (xy 375.884706 -216.276444) (xy 375.876552 -216.327648)
			(xy 375.860466 -216.376938) (xy 375.836845 -216.423094) (xy 375.821956 -216.444322) (xy 375.821956 -216.645744)
			(xy 375.82248 -216.661136) (xy 375.831633 -216.690528) (xy 375.849124 -216.715859) (xy 375.873366 -216.734832)
			(xy 375.902158 -216.745723) (xy 375.932888 -216.747545) (xy 375.94794 -216.744296) (xy 375.967313 -216.739794)
			(xy 376.006793 -216.734957) (xy 376.02668 -216.734644) (xy 376.052589 -216.735125) (xy 376.10377 -216.743229)
			(xy 376.153053 -216.75924) (xy 376.199225 -216.782765) (xy 376.241147 -216.813223) (xy 376.277787 -216.849866)
			(xy 376.308244 -216.891789) (xy 376.331766 -216.937961) (xy 376.347775 -216.987245) (xy 376.355877 -217.038427)
			(xy 376.356372 -217.064336) (xy 377.576588 -217.064336) (xy 377.577096 -217.038429) (xy 377.585202 -216.987252)
			(xy 377.601214 -216.937973) (xy 377.624737 -216.891806) (xy 377.655193 -216.849887) (xy 377.691831 -216.813249)
			(xy 377.73375 -216.782793) (xy 377.779917 -216.75927) (xy 377.829196 -216.743258) (xy 377.880373 -216.735152)
			(xy 377.932187 -216.735152) (xy 377.983364 -216.743258) (xy 378.032643 -216.75927) (xy 378.07881 -216.782793)
			(xy 378.120729 -216.813249) (xy 378.157367 -216.849887) (xy 378.187823 -216.891806) (xy 378.211346 -216.937973)
			(xy 378.227358 -216.987252) (xy 378.235464 -217.038429) (xy 378.235972 -217.064336) (xy 379.456188 -217.064336)
			(xy 379.456696 -217.038429) (xy 379.464802 -216.987252) (xy 379.480814 -216.937973) (xy 379.504337 -216.891806)
			(xy 379.534793 -216.849887) (xy 379.571431 -216.813249) (xy 379.61335 -216.782793) (xy 379.659517 -216.75927)
			(xy 379.708796 -216.743258) (xy 379.759973 -216.735152) (xy 379.811787 -216.735152) (xy 379.862964 -216.743258)
			(xy 379.912243 -216.75927) (xy 379.95841 -216.782793) (xy 380.000329 -216.813249) (xy 380.036967 -216.849887)
			(xy 380.067423 -216.891806) (xy 380.090946 -216.937973) (xy 380.106958 -216.987252) (xy 380.115064 -217.038429)
			(xy 380.115572 -217.064336) (xy 381.335788 -217.064336) (xy 381.336296 -217.038429) (xy 381.344402 -216.987252)
			(xy 381.360414 -216.937973) (xy 381.383937 -216.891806) (xy 381.414393 -216.849887) (xy 381.451031 -216.813249)
			(xy 381.49295 -216.782793) (xy 381.539117 -216.75927) (xy 381.588396 -216.743258) (xy 381.639573 -216.735152)
			(xy 381.691387 -216.735152) (xy 381.742564 -216.743258) (xy 381.791843 -216.75927) (xy 381.83801 -216.782793)
			(xy 381.879929 -216.813249) (xy 381.916567 -216.849887) (xy 381.947023 -216.891806) (xy 381.970546 -216.937973)
			(xy 381.986558 -216.987252) (xy 381.994664 -217.038429) (xy 381.995172 -217.064336) (xy 381.994559 -217.091989)
			(xy 381.985238 -217.146507) (xy 381.97663 -217.172794) (xy 381.96901 -217.194892) (xy 382.174242 -217.550238)
			(xy 382.197102 -217.554556) (xy 382.221903 -217.559751) (xy 382.269642 -217.57674) (xy 382.314219 -217.600833)
			(xy 382.354584 -217.631463) (xy 382.389788 -217.667908) (xy 382.419 -217.709312) (xy 382.441533 -217.754697)
			(xy 382.456856 -217.802996) (xy 382.464608 -217.85307) (xy 382.465072 -217.878406) (xy 382.464564 -217.904293)
			(xy 382.456465 -217.955431) (xy 382.440466 -218.004671) (xy 382.41696 -218.050803) (xy 382.386528 -218.09269)
			(xy 382.349918 -218.1293) (xy 382.308031 -218.159732) (xy 382.261899 -218.183238) (xy 382.212659 -218.199237)
			(xy 382.161521 -218.207336) (xy 382.109747 -218.207336) (xy 382.058609 -218.199237) (xy 382.009369 -218.183238)
			(xy 381.963237 -218.159732) (xy 381.92135 -218.1293) (xy 381.88474 -218.09269) (xy 381.854308 -218.050803)
			(xy 381.830802 -218.004671) (xy 381.814803 -217.955431) (xy 381.806704 -217.904293) (xy 381.806196 -217.878406)
			(xy 381.806727 -217.850698) (xy 381.815921 -217.796051) (xy 381.824484 -217.769694) (xy 381.832358 -217.747596)
			(xy 381.62738 -217.392504) (xy 381.60452 -217.388186) (xy 381.579675 -217.38302) (xy 381.531826 -217.366126)
			(xy 381.487133 -217.342096) (xy 381.446653 -217.311499) (xy 381.411341 -217.275058) (xy 381.382033 -217.233634)
			(xy 381.359422 -217.188207) (xy 381.344043 -217.13985) (xy 381.336258 -217.089708) (xy 381.335788 -217.064336)
			(xy 380.115572 -217.064336) (xy 380.114959 -217.091989) (xy 380.105638 -217.146507) (xy 380.09703 -217.172794)
			(xy 380.08941 -217.194892) (xy 380.294642 -217.550238) (xy 380.317502 -217.554556) (xy 380.342303 -217.559751)
			(xy 380.390042 -217.57674) (xy 380.434619 -217.600833) (xy 380.474984 -217.631463) (xy 380.510188 -217.667908)
			(xy 380.5394 -217.709312) (xy 380.561933 -217.754697) (xy 380.577256 -217.802996) (xy 380.585008 -217.85307)
			(xy 380.585472 -217.878406) (xy 380.584964 -217.904293) (xy 380.576865 -217.955431) (xy 380.560866 -218.004671)
			(xy 380.53736 -218.050803) (xy 380.506928 -218.09269) (xy 380.470318 -218.1293) (xy 380.428431 -218.159732)
			(xy 380.382299 -218.183238) (xy 380.333059 -218.199237) (xy 380.281921 -218.207336) (xy 380.230147 -218.207336)
			(xy 380.179009 -218.199237) (xy 380.129769 -218.183238) (xy 380.083637 -218.159732) (xy 380.04175 -218.1293)
			(xy 380.00514 -218.09269) (xy 379.974708 -218.050803) (xy 379.951202 -218.004671) (xy 379.935203 -217.955431)
			(xy 379.927104 -217.904293) (xy 379.926596 -217.878406) (xy 379.927127 -217.850698) (xy 379.936321 -217.796051)
			(xy 379.944884 -217.769694) (xy 379.952758 -217.747596) (xy 379.74778 -217.392504) (xy 379.72492 -217.388186)
			(xy 379.700075 -217.38302) (xy 379.652226 -217.366126) (xy 379.607533 -217.342096) (xy 379.567053 -217.311499)
			(xy 379.531741 -217.275058) (xy 379.502433 -217.233634) (xy 379.479822 -217.188207) (xy 379.464443 -217.13985)
			(xy 379.456658 -217.089708) (xy 379.456188 -217.064336) (xy 378.235972 -217.064336) (xy 378.235359 -217.091989)
			(xy 378.226038 -217.146507) (xy 378.21743 -217.172794) (xy 378.20981 -217.194892) (xy 378.415042 -217.550238)
			(xy 378.437902 -217.554556) (xy 378.462703 -217.559751) (xy 378.510442 -217.57674) (xy 378.555019 -217.600833)
			(xy 378.595384 -217.631463) (xy 378.630588 -217.667908) (xy 378.6598 -217.709312) (xy 378.682333 -217.754697)
			(xy 378.697656 -217.802996) (xy 378.705408 -217.85307) (xy 378.705872 -217.878406) (xy 378.705364 -217.904293)
			(xy 378.697265 -217.955431) (xy 378.681266 -218.004671) (xy 378.65776 -218.050803) (xy 378.627328 -218.09269)
			(xy 378.590718 -218.1293) (xy 378.548831 -218.159732) (xy 378.502699 -218.183238) (xy 378.453459 -218.199237)
			(xy 378.402321 -218.207336) (xy 378.350547 -218.207336) (xy 378.299409 -218.199237) (xy 378.250169 -218.183238)
			(xy 378.204037 -218.159732) (xy 378.16215 -218.1293) (xy 378.12554 -218.09269) (xy 378.095108 -218.050803)
			(xy 378.071602 -218.004671) (xy 378.055603 -217.955431) (xy 378.047504 -217.904293) (xy 378.046996 -217.878406)
			(xy 378.047527 -217.850698) (xy 378.056721 -217.796051) (xy 378.065284 -217.769694) (xy 378.073158 -217.747596)
			(xy 377.86818 -217.392504) (xy 377.84532 -217.388186) (xy 377.820475 -217.38302) (xy 377.772626 -217.366126)
			(xy 377.727933 -217.342096) (xy 377.687453 -217.311499) (xy 377.652141 -217.275058) (xy 377.622833 -217.233634)
			(xy 377.600222 -217.188207) (xy 377.584843 -217.13985) (xy 377.577058 -217.089708) (xy 377.576588 -217.064336)
			(xy 376.356372 -217.064336) (xy 376.355769 -217.091991) (xy 376.346452 -217.146511) (xy 376.33783 -217.172794)
			(xy 376.33021 -217.194892) (xy 376.535442 -217.550238) (xy 376.558302 -217.554556) (xy 376.583103 -217.559754)
			(xy 376.630841 -217.576742) (xy 376.675418 -217.600835) (xy 376.715783 -217.631464) (xy 376.750986 -217.66791)
			(xy 376.780198 -217.709313) (xy 376.802731 -217.754698) (xy 376.818054 -217.802996) (xy 376.825806 -217.853071)
			(xy 376.826272 -217.878406) (xy 376.825764 -217.904293) (xy 376.817665 -217.955431) (xy 376.801666 -218.004671)
			(xy 376.77816 -218.050803) (xy 376.747728 -218.09269) (xy 376.711118 -218.1293) (xy 376.669231 -218.159732)
			(xy 376.623099 -218.183238) (xy 376.573859 -218.199237) (xy 376.522721 -218.207336) (xy 376.470947 -218.207336)
			(xy 376.419809 -218.199237) (xy 376.370569 -218.183238) (xy 376.324437 -218.159732) (xy 376.28255 -218.1293)
			(xy 376.24594 -218.09269) (xy 376.215508 -218.050803) (xy 376.192002 -218.004671) (xy 376.176003 -217.955431)
			(xy 376.167904 -217.904293) (xy 376.167396 -217.878406) (xy 376.167925 -217.850698) (xy 376.177125 -217.796052)
			(xy 376.185684 -217.769694) (xy 376.193558 -217.747596) (xy 375.98858 -217.392504) (xy 375.96572 -217.388186)
			(xy 375.94794 -217.384376) (xy 375.932884 -217.381206) (xy 375.902187 -217.383052) (xy 375.873428 -217.393945)
			(xy 375.84921 -217.412898) (xy 375.831726 -217.438197) (xy 375.822558 -217.467552) (xy 375.821956 -217.482928)
			(xy 375.821956 -217.682318) (xy 375.837155 -217.703739) (xy 375.861276 -217.750393) (xy 375.877688 -217.800283)
			(xy 375.885975 -217.852145) (xy 375.886472 -217.878406) (xy 375.885977 -217.904665) (xy 375.877676 -217.956523)
			(xy 375.861254 -218.006407) (xy 375.837127 -218.053054) (xy 375.821956 -218.074494) (xy 375.821956 -218.692222)
			(xy 376.636788 -218.692222) (xy 376.637339 -218.66688) (xy 376.645107 -218.616793) (xy 376.660448 -218.568485)
			(xy 376.683001 -218.523094) (xy 376.712234 -218.481689) (xy 376.747459 -218.445245) (xy 376.787846 -218.41462)
			(xy 376.832444 -218.390537) (xy 376.880202 -218.373561) (xy 376.905012 -218.368372) (xy 376.927872 -218.364054)
			(xy 377.133104 -218.008708) (xy 377.12523 -217.98661) (xy 377.116761 -217.960367) (xy 377.107692 -217.905977)
			(xy 377.107196 -217.878406) (xy 377.107704 -217.852519) (xy 377.115803 -217.801381) (xy 377.131802 -217.752141)
			(xy 377.155308 -217.706009) (xy 377.18574 -217.664122) (xy 377.22235 -217.627512) (xy 377.264237 -217.59708)
			(xy 377.310369 -217.573574) (xy 377.359609 -217.557575) (xy 377.410747 -217.549476) (xy 377.462521 -217.549476)
			(xy 377.513659 -217.557575) (xy 377.562899 -217.573574) (xy 377.609031 -217.59708) (xy 377.650918 -217.627512)
			(xy 377.687528 -217.664122) (xy 377.71796 -217.706009) (xy 377.741466 -217.752141) (xy 377.757465 -217.801381)
			(xy 377.765564 -217.852519) (xy 377.766072 -217.878406) (xy 377.765625 -217.903782) (xy 377.757855 -217.953934)
			(xy 377.742485 -218.002302) (xy 377.719877 -218.047739) (xy 377.690567 -218.089171) (xy 377.65525 -218.125617)
			(xy 377.61476 -218.156215) (xy 377.570056 -218.18024) (xy 377.522196 -218.197124) (xy 377.49734 -218.202256)
			(xy 377.47448 -218.206574) (xy 377.269756 -218.561412) (xy 377.27763 -218.583256) (xy 377.286281 -218.609663)
			(xy 377.295598 -218.66444) (xy 377.296172 -218.692222) (xy 378.516388 -218.692222) (xy 378.516939 -218.66688)
			(xy 378.524707 -218.616793) (xy 378.540048 -218.568485) (xy 378.562601 -218.523094) (xy 378.591834 -218.481689)
			(xy 378.627059 -218.445245) (xy 378.667446 -218.41462) (xy 378.712044 -218.390537) (xy 378.759802 -218.373561)
			(xy 378.784612 -218.368372) (xy 378.807472 -218.364054) (xy 379.012704 -218.008708) (xy 379.00483 -217.98661)
			(xy 378.996361 -217.960367) (xy 378.987292 -217.905977) (xy 378.986796 -217.878406) (xy 378.987304 -217.852519)
			(xy 378.995403 -217.801381) (xy 379.011402 -217.752141) (xy 379.034908 -217.706009) (xy 379.06534 -217.664122)
			(xy 379.10195 -217.627512) (xy 379.143837 -217.59708) (xy 379.189969 -217.573574) (xy 379.239209 -217.557575)
			(xy 379.290347 -217.549476) (xy 379.342121 -217.549476) (xy 379.393259 -217.557575) (xy 379.442499 -217.573574)
			(xy 379.488631 -217.59708) (xy 379.530518 -217.627512) (xy 379.567128 -217.664122) (xy 379.59756 -217.706009)
			(xy 379.621066 -217.752141) (xy 379.637065 -217.801381) (xy 379.645164 -217.852519) (xy 379.645672 -217.878406)
			(xy 379.645225 -217.903782) (xy 379.637455 -217.953934) (xy 379.622085 -218.002302) (xy 379.599477 -218.047739)
			(xy 379.570167 -218.089171) (xy 379.53485 -218.125617) (xy 379.49436 -218.156215) (xy 379.449656 -218.18024)
			(xy 379.401796 -218.197124) (xy 379.37694 -218.202256) (xy 379.35408 -218.206574) (xy 379.149356 -218.561412)
			(xy 379.15723 -218.583256) (xy 379.165881 -218.609663) (xy 379.175198 -218.66444) (xy 379.175772 -218.692222)
			(xy 380.395988 -218.692222) (xy 380.396539 -218.66688) (xy 380.404307 -218.616793) (xy 380.419648 -218.568485)
			(xy 380.442201 -218.523094) (xy 380.471434 -218.481689) (xy 380.506659 -218.445245) (xy 380.547046 -218.41462)
			(xy 380.591644 -218.390537) (xy 380.639402 -218.373561) (xy 380.664212 -218.368372) (xy 380.687072 -218.364054)
			(xy 380.892304 -218.008708) (xy 380.88443 -217.98661) (xy 380.875961 -217.960367) (xy 380.866892 -217.905977)
			(xy 380.866396 -217.878406) (xy 380.866904 -217.852519) (xy 380.875003 -217.801381) (xy 380.891002 -217.752141)
			(xy 380.914508 -217.706009) (xy 380.94494 -217.664122) (xy 380.98155 -217.627512) (xy 381.023437 -217.59708)
			(xy 381.069569 -217.573574) (xy 381.118809 -217.557575) (xy 381.169947 -217.549476) (xy 381.221721 -217.549476)
			(xy 381.272859 -217.557575) (xy 381.322099 -217.573574) (xy 381.368231 -217.59708) (xy 381.410118 -217.627512)
			(xy 381.446728 -217.664122) (xy 381.47716 -217.706009) (xy 381.500666 -217.752141) (xy 381.516665 -217.801381)
			(xy 381.524764 -217.852519) (xy 381.525272 -217.878406) (xy 381.524825 -217.903782) (xy 381.517055 -217.953934)
			(xy 381.501685 -218.002302) (xy 381.479077 -218.047739) (xy 381.449767 -218.089171) (xy 381.41445 -218.125617)
			(xy 381.37396 -218.156215) (xy 381.329256 -218.18024) (xy 381.281396 -218.197124) (xy 381.25654 -218.202256)
			(xy 381.23368 -218.206574) (xy 381.028956 -218.561412) (xy 381.03683 -218.583256) (xy 381.045481 -218.609663)
			(xy 381.054798 -218.66444) (xy 381.055372 -218.692222) (xy 381.054864 -218.718129) (xy 381.046758 -218.769306)
			(xy 381.030746 -218.818585) (xy 381.007223 -218.864752) (xy 380.976767 -218.906671) (xy 380.940129 -218.943309)
			(xy 380.89821 -218.973765) (xy 380.852043 -218.997288) (xy 380.802764 -219.0133) (xy 380.751587 -219.021406)
			(xy 380.699773 -219.021406) (xy 380.648596 -219.0133) (xy 380.599317 -218.997288) (xy 380.55315 -218.973765)
			(xy 380.511231 -218.943309) (xy 380.474593 -218.906671) (xy 380.444137 -218.864752) (xy 380.420614 -218.818585)
			(xy 380.404602 -218.769306) (xy 380.396496 -218.718129) (xy 380.395988 -218.692222) (xy 379.175772 -218.692222)
			(xy 379.175264 -218.718129) (xy 379.167158 -218.769306) (xy 379.151146 -218.818585) (xy 379.127623 -218.864752)
			(xy 379.097167 -218.906671) (xy 379.060529 -218.943309) (xy 379.01861 -218.973765) (xy 378.972443 -218.997288)
			(xy 378.923164 -219.0133) (xy 378.871987 -219.021406) (xy 378.820173 -219.021406) (xy 378.768996 -219.0133)
			(xy 378.719717 -218.997288) (xy 378.67355 -218.973765) (xy 378.631631 -218.943309) (xy 378.594993 -218.906671)
			(xy 378.564537 -218.864752) (xy 378.541014 -218.818585) (xy 378.525002 -218.769306) (xy 378.516896 -218.718129)
			(xy 378.516388 -218.692222) (xy 377.296172 -218.692222) (xy 377.295664 -218.718129) (xy 377.287558 -218.769306)
			(xy 377.271546 -218.818585) (xy 377.248023 -218.864752) (xy 377.217567 -218.906671) (xy 377.180929 -218.943309)
			(xy 377.13901 -218.973765) (xy 377.092843 -218.997288) (xy 377.043564 -219.0133) (xy 376.992387 -219.021406)
			(xy 376.940573 -219.021406) (xy 376.889396 -219.0133) (xy 376.840117 -218.997288) (xy 376.79395 -218.973765)
			(xy 376.752031 -218.943309) (xy 376.715393 -218.906671) (xy 376.684937 -218.864752) (xy 376.661414 -218.818585)
			(xy 376.645402 -218.769306) (xy 376.637296 -218.718129) (xy 376.636788 -218.692222) (xy 375.821956 -218.692222)
			(xy 375.821956 -219.312236) (xy 375.836874 -219.333449) (xy 375.86053 -219.379595) (xy 375.876619 -219.428892)
			(xy 375.884738 -219.480109) (xy 375.885202 -219.506038) (xy 375.884705 -219.531962) (xy 375.876548 -219.583164)
			(xy 375.86046 -219.632453) (xy 375.836837 -219.678607) (xy 375.821956 -219.69984) (xy 375.821956 -219.901262)
			(xy 375.822483 -219.916652) (xy 375.831638 -219.946039) (xy 375.84913 -219.971366) (xy 375.87337 -219.990334)
			(xy 375.902159 -220.001224) (xy 375.932885 -220.003045) (xy 375.94794 -219.999814) (xy 375.967319 -219.995369)
			(xy 376.006799 -219.990653) (xy 376.02668 -219.990416) (xy 376.052575 -219.990922) (xy 376.10373 -219.999017)
			(xy 376.152989 -220.015012) (xy 376.199141 -220.038512) (xy 376.241051 -220.06894) (xy 376.277687 -220.105547)
			(xy 376.308149 -220.147432) (xy 376.331686 -220.193565) (xy 376.347721 -220.242811) (xy 376.355857 -220.293959)
			(xy 376.356372 -220.319854) (xy 377.576588 -220.319854) (xy 377.577096 -220.293947) (xy 377.585202 -220.24277)
			(xy 377.601214 -220.193491) (xy 377.624737 -220.147324) (xy 377.655193 -220.105405) (xy 377.691831 -220.068767)
			(xy 377.73375 -220.038311) (xy 377.779917 -220.014788) (xy 377.829196 -219.998776) (xy 377.880373 -219.99067)
			(xy 377.932187 -219.99067) (xy 377.983364 -219.998776) (xy 378.032643 -220.014788) (xy 378.07881 -220.038311)
			(xy 378.120729 -220.068767) (xy 378.157367 -220.105405) (xy 378.187823 -220.147324) (xy 378.211346 -220.193491)
			(xy 378.227358 -220.24277) (xy 378.235464 -220.293947) (xy 378.235972 -220.319854) (xy 379.456188 -220.319854)
			(xy 379.456696 -220.293947) (xy 379.464802 -220.24277) (xy 379.480814 -220.193491) (xy 379.504337 -220.147324)
			(xy 379.534793 -220.105405) (xy 379.571431 -220.068767) (xy 379.61335 -220.038311) (xy 379.659517 -220.014788)
			(xy 379.708796 -219.998776) (xy 379.759973 -219.99067) (xy 379.811787 -219.99067) (xy 379.862964 -219.998776)
			(xy 379.912243 -220.014788) (xy 379.95841 -220.038311) (xy 380.000329 -220.068767) (xy 380.036967 -220.105405)
			(xy 380.067423 -220.147324) (xy 380.090946 -220.193491) (xy 380.106958 -220.24277) (xy 380.115064 -220.293947)
			(xy 380.115572 -220.319854) (xy 381.336296 -220.319854) (xy 381.336804 -220.293967) (xy 381.344903 -220.242829)
			(xy 381.360902 -220.193589) (xy 381.384408 -220.147457) (xy 381.41484 -220.10557) (xy 381.45145 -220.06896)
			(xy 381.493337 -220.038528) (xy 381.539469 -220.015022) (xy 381.588709 -219.999023) (xy 381.639847 -219.990924)
			(xy 381.691621 -219.990924) (xy 381.742759 -219.999023) (xy 381.791999 -220.015022) (xy 381.838131 -220.038528)
			(xy 381.880018 -220.06896) (xy 381.916628 -220.10557) (xy 381.94706 -220.147457) (xy 381.970566 -220.193589)
			(xy 381.986565 -220.242829) (xy 381.994664 -220.293967) (xy 381.995172 -220.319854) (xy 381.994628 -220.347561)
			(xy 381.985442 -220.402208) (xy 381.976884 -220.428566) (xy 381.969264 -220.450664) (xy 382.174242 -220.805756)
			(xy 382.197102 -220.810074) (xy 382.221908 -220.815252) (xy 382.269647 -220.832242) (xy 382.314225 -220.856337)
			(xy 382.354591 -220.886969) (xy 382.389795 -220.923417) (xy 382.419006 -220.964822) (xy 382.441538 -221.01021)
			(xy 382.45686 -221.058511) (xy 382.46461 -221.108588) (xy 382.465072 -221.133924) (xy 382.464564 -221.159811)
			(xy 382.456465 -221.210949) (xy 382.440466 -221.260189) (xy 382.41696 -221.306321) (xy 382.386528 -221.348208)
			(xy 382.349918 -221.384818) (xy 382.308031 -221.41525) (xy 382.261899 -221.438756) (xy 382.212659 -221.454755)
			(xy 382.161521 -221.462854) (xy 382.109747 -221.462854) (xy 382.058609 -221.454755) (xy 382.009369 -221.438756)
			(xy 381.963237 -221.41525) (xy 381.92135 -221.384818) (xy 381.88474 -221.348208) (xy 381.854308 -221.306321)
			(xy 381.830802 -221.260189) (xy 381.814803 -221.210949) (xy 381.806704 -221.159811) (xy 381.806196 -221.133924)
			(xy 381.806732 -221.106216) (xy 381.815923 -221.051569) (xy 381.824484 -221.025212) (xy 381.832358 -221.003114)
			(xy 381.62738 -220.648022) (xy 381.60452 -220.643704) (xy 381.579694 -220.638559) (xy 381.531915 -220.6216)
			(xy 381.487296 -220.597525) (xy 381.446891 -220.566902) (xy 381.41165 -220.530452) (xy 381.382408 -220.489036)
			(xy 381.359851 -220.44363) (xy 381.344514 -220.395306) (xy 381.336758 -220.345204) (xy 381.336296 -220.319854)
			(xy 380.115572 -220.319854) (xy 380.114963 -220.347508) (xy 380.105639 -220.402026) (xy 380.09703 -220.428312)
			(xy 380.08941 -220.45041) (xy 380.294642 -220.805756) (xy 380.317502 -220.810074) (xy 380.342308 -220.815252)
			(xy 380.390047 -220.832242) (xy 380.434625 -220.856337) (xy 380.474991 -220.886969) (xy 380.510195 -220.923417)
			(xy 380.539406 -220.964822) (xy 380.561938 -221.01021) (xy 380.57726 -221.058511) (xy 380.58501 -221.108588)
			(xy 380.585472 -221.133924) (xy 380.584964 -221.159811) (xy 380.576865 -221.210949) (xy 380.560866 -221.260189)
			(xy 380.53736 -221.306321) (xy 380.506928 -221.348208) (xy 380.470318 -221.384818) (xy 380.428431 -221.41525)
			(xy 380.382299 -221.438756) (xy 380.333059 -221.454755) (xy 380.281921 -221.462854) (xy 380.230147 -221.462854)
			(xy 380.179009 -221.454755) (xy 380.129769 -221.438756) (xy 380.083637 -221.41525) (xy 380.04175 -221.384818)
			(xy 380.00514 -221.348208) (xy 379.974708 -221.306321) (xy 379.951202 -221.260189) (xy 379.935203 -221.210949)
			(xy 379.927104 -221.159811) (xy 379.926596 -221.133924) (xy 379.927132 -221.106216) (xy 379.936323 -221.051569)
			(xy 379.944884 -221.025212) (xy 379.952758 -221.003114) (xy 379.74778 -220.648022) (xy 379.72492 -220.643704)
			(xy 379.700079 -220.638521) (xy 379.652232 -220.621628) (xy 379.60754 -220.5976) (xy 379.567059 -220.567005)
			(xy 379.531748 -220.530566) (xy 379.502439 -220.489145) (xy 379.479827 -220.44372) (xy 379.464446 -220.395365)
			(xy 379.456659 -220.345225) (xy 379.456188 -220.319854) (xy 378.235972 -220.319854) (xy 378.235363 -220.347508)
			(xy 378.226039 -220.402026) (xy 378.21743 -220.428312) (xy 378.20981 -220.45041) (xy 378.415042 -220.805756)
			(xy 378.437902 -220.810074) (xy 378.462708 -220.815252) (xy 378.510447 -220.832242) (xy 378.555025 -220.856337)
			(xy 378.595391 -220.886969) (xy 378.630595 -220.923417) (xy 378.659806 -220.964822) (xy 378.682338 -221.01021)
			(xy 378.69766 -221.058511) (xy 378.70541 -221.108588) (xy 378.705872 -221.133924) (xy 378.705364 -221.159811)
			(xy 378.697265 -221.210949) (xy 378.681266 -221.260189) (xy 378.65776 -221.306321) (xy 378.627328 -221.348208)
			(xy 378.590718 -221.384818) (xy 378.548831 -221.41525) (xy 378.502699 -221.438756) (xy 378.453459 -221.454755)
			(xy 378.402321 -221.462854) (xy 378.350547 -221.462854) (xy 378.299409 -221.454755) (xy 378.250169 -221.438756)
			(xy 378.204037 -221.41525) (xy 378.16215 -221.384818) (xy 378.12554 -221.348208) (xy 378.095108 -221.306321)
			(xy 378.071602 -221.260189) (xy 378.055603 -221.210949) (xy 378.047504 -221.159811) (xy 378.046996 -221.133924)
			(xy 378.047532 -221.106216) (xy 378.056723 -221.051569) (xy 378.065284 -221.025212) (xy 378.073158 -221.003114)
			(xy 377.86818 -220.648022) (xy 377.84532 -220.643704) (xy 377.820479 -220.638521) (xy 377.772632 -220.621628)
			(xy 377.72794 -220.5976) (xy 377.687459 -220.567005) (xy 377.652148 -220.530566) (xy 377.622839 -220.489145)
			(xy 377.600227 -220.44372) (xy 377.584846 -220.395365) (xy 377.577059 -220.345225) (xy 377.576588 -220.319854)
			(xy 376.356372 -220.319854) (xy 376.355767 -220.347508) (xy 376.346448 -220.402028) (xy 376.33783 -220.428312)
			(xy 376.33021 -220.45041) (xy 376.535442 -220.805756) (xy 376.558302 -220.810074) (xy 376.583102 -220.815272)
			(xy 376.630839 -220.83226) (xy 376.675414 -220.856354) (xy 376.715778 -220.886984) (xy 376.750979 -220.923429)
			(xy 376.780189 -220.964832) (xy 376.80272 -221.010217) (xy 376.81804 -221.058515) (xy 376.82579 -221.108589)
			(xy 376.826272 -221.133924) (xy 376.825764 -221.159811) (xy 376.817665 -221.210949) (xy 376.801666 -221.260189)
			(xy 376.77816 -221.306321) (xy 376.747728 -221.348208) (xy 376.711118 -221.384818) (xy 376.669231 -221.41525)
			(xy 376.623099 -221.438756) (xy 376.573859 -221.454755) (xy 376.522721 -221.462854) (xy 376.470947 -221.462854)
			(xy 376.419809 -221.454755) (xy 376.370569 -221.438756) (xy 376.324437 -221.41525) (xy 376.28255 -221.384818)
			(xy 376.24594 -221.348208) (xy 376.215508 -221.306321) (xy 376.192002 -221.260189) (xy 376.176003 -221.210949)
			(xy 376.167904 -221.159811) (xy 376.167396 -221.133924) (xy 376.167924 -221.106216) (xy 376.17712 -221.051569)
			(xy 376.185684 -221.025212) (xy 376.193558 -221.003114) (xy 375.98858 -220.648022) (xy 375.96572 -220.643704)
			(xy 375.94794 -220.639894) (xy 375.932881 -220.636726) (xy 375.902176 -220.638572) (xy 375.873408 -220.649464)
			(xy 375.849179 -220.668414) (xy 375.831679 -220.693711) (xy 375.82249 -220.723067) (xy 375.821956 -220.738446)
			(xy 375.821956 -220.937836) (xy 375.837153 -220.959257) (xy 375.861272 -221.005911) (xy 375.877682 -221.055802)
			(xy 375.885966 -221.107664) (xy 375.886472 -221.133924) (xy 375.885983 -221.160185) (xy 375.877694 -221.212049)
			(xy 375.861282 -221.26194) (xy 375.837163 -221.308596) (xy 375.821956 -221.330012) (xy 375.821956 -221.94774)
			(xy 376.636788 -221.94774) (xy 376.637265 -221.922395) (xy 376.645045 -221.872306) (xy 376.660397 -221.823996)
			(xy 376.68296 -221.778605) (xy 376.712203 -221.7372) (xy 376.747437 -221.700757) (xy 376.787831 -221.670134)
			(xy 376.832436 -221.646052) (xy 376.880199 -221.629078) (xy 376.905012 -221.62389) (xy 376.927872 -221.619572)
			(xy 377.133104 -221.264226) (xy 377.12523 -221.242128) (xy 377.116765 -221.215883) (xy 377.107693 -221.161495)
			(xy 377.107196 -221.133924) (xy 377.107704 -221.108037) (xy 377.115803 -221.056899) (xy 377.131802 -221.007659)
			(xy 377.155308 -220.961527) (xy 377.18574 -220.91964) (xy 377.22235 -220.88303) (xy 377.264237 -220.852598)
			(xy 377.310369 -220.829092) (xy 377.359609 -220.813093) (xy 377.410747 -220.804994) (xy 377.462521 -220.804994)
			(xy 377.513659 -220.813093) (xy 377.562899 -220.829092) (xy 377.609031 -220.852598) (xy 377.650918 -220.88303)
			(xy 377.687528 -220.91964) (xy 377.71796 -220.961527) (xy 377.741466 -221.007659) (xy 377.757465 -221.056899)
			(xy 377.765564 -221.108037) (xy 377.766072 -221.133924) (xy 377.765642 -221.1593) (xy 377.757869 -221.209454)
			(xy 377.742496 -221.257821) (xy 377.719886 -221.303259) (xy 377.690574 -221.344691) (xy 377.655255 -221.381137)
			(xy 377.614763 -221.411734) (xy 377.570058 -221.435759) (xy 377.522196 -221.452643) (xy 377.49734 -221.457774)
			(xy 377.47448 -221.462092) (xy 377.269756 -221.81693) (xy 377.27763 -221.838774) (xy 377.286286 -221.865179)
			(xy 377.2956 -221.919958) (xy 377.296172 -221.94774) (xy 378.516388 -221.94774) (xy 378.516865 -221.922395)
			(xy 378.524645 -221.872306) (xy 378.539997 -221.823996) (xy 378.56256 -221.778605) (xy 378.591803 -221.7372)
			(xy 378.627037 -221.700757) (xy 378.667431 -221.670134) (xy 378.712036 -221.646052) (xy 378.759799 -221.629078)
			(xy 378.784612 -221.62389) (xy 378.807472 -221.619572) (xy 379.012704 -221.264226) (xy 379.00483 -221.242128)
			(xy 378.996365 -221.215883) (xy 378.987293 -221.161495) (xy 378.986796 -221.133924) (xy 378.987304 -221.108037)
			(xy 378.995403 -221.056899) (xy 379.011402 -221.007659) (xy 379.034908 -220.961527) (xy 379.06534 -220.91964)
			(xy 379.10195 -220.88303) (xy 379.143837 -220.852598) (xy 379.189969 -220.829092) (xy 379.239209 -220.813093)
			(xy 379.290347 -220.804994) (xy 379.342121 -220.804994) (xy 379.393259 -220.813093) (xy 379.442499 -220.829092)
			(xy 379.488631 -220.852598) (xy 379.530518 -220.88303) (xy 379.567128 -220.91964) (xy 379.59756 -220.961527)
			(xy 379.621066 -221.007659) (xy 379.637065 -221.056899) (xy 379.645164 -221.108037) (xy 379.645672 -221.133924)
			(xy 379.645242 -221.1593) (xy 379.637469 -221.209454) (xy 379.622096 -221.257821) (xy 379.599486 -221.303259)
			(xy 379.570174 -221.344691) (xy 379.534855 -221.381137) (xy 379.494363 -221.411734) (xy 379.449658 -221.435759)
			(xy 379.401796 -221.452643) (xy 379.37694 -221.457774) (xy 379.35408 -221.462092) (xy 379.149356 -221.81693)
			(xy 379.15723 -221.838774) (xy 379.165886 -221.865179) (xy 379.1752 -221.919958) (xy 379.175772 -221.94774)
			(xy 380.395988 -221.94774) (xy 380.396465 -221.922395) (xy 380.404245 -221.872306) (xy 380.419597 -221.823996)
			(xy 380.44216 -221.778605) (xy 380.471403 -221.7372) (xy 380.506637 -221.700757) (xy 380.547031 -221.670134)
			(xy 380.591636 -221.646052) (xy 380.639399 -221.629078) (xy 380.664212 -221.62389) (xy 380.687072 -221.619572)
			(xy 380.89205 -221.263972) (xy 380.88443 -221.242128) (xy 380.875981 -221.215945) (xy 380.866909 -221.161685)
			(xy 380.866396 -221.134178) (xy 380.866396 -221.133924) (xy 380.866904 -221.108037) (xy 380.875003 -221.056899)
			(xy 380.891002 -221.007659) (xy 380.914508 -220.961527) (xy 380.94494 -220.91964) (xy 380.98155 -220.88303)
			(xy 381.023437 -220.852598) (xy 381.069569 -220.829092) (xy 381.118809 -220.813093) (xy 381.169947 -220.804994)
			(xy 381.221721 -220.804994) (xy 381.272859 -220.813093) (xy 381.322099 -220.829092) (xy 381.368231 -220.852598)
			(xy 381.410118 -220.88303) (xy 381.446728 -220.91964) (xy 381.47716 -220.961527) (xy 381.500666 -221.007659)
			(xy 381.516665 -221.056899) (xy 381.524764 -221.108037) (xy 381.525272 -221.133924) (xy 381.524879 -221.159291)
			(xy 381.517126 -221.209429) (xy 381.501775 -221.257784) (xy 381.479191 -221.303213) (xy 381.449906 -221.344642)
			(xy 381.414615 -221.381089) (xy 381.374152 -221.411694) (xy 381.329474 -221.435731) (xy 381.281638 -221.452632)
			(xy 381.256794 -221.457774) (xy 381.233934 -221.462092) (xy 381.02921 -221.81693) (xy 381.03683 -221.838774)
			(xy 381.045444 -221.865059) (xy 381.054766 -221.919578) (xy 381.055372 -221.947232) (xy 381.055372 -221.94774)
			(xy 382.275588 -221.94774) (xy 382.276065 -221.922395) (xy 382.283845 -221.872306) (xy 382.299197 -221.823996)
			(xy 382.32176 -221.778605) (xy 382.351003 -221.7372) (xy 382.386237 -221.700757) (xy 382.426631 -221.670134)
			(xy 382.471236 -221.646052) (xy 382.518999 -221.629078) (xy 382.543812 -221.62389) (xy 382.566672 -221.619572)
			(xy 382.77165 -221.263972) (xy 382.76403 -221.242128) (xy 382.755581 -221.215945) (xy 382.746509 -221.161685)
			(xy 382.745996 -221.134178) (xy 382.745996 -221.133924) (xy 382.746504 -221.108037) (xy 382.754603 -221.056899)
			(xy 382.770602 -221.007659) (xy 382.794108 -220.961527) (xy 382.82454 -220.91964) (xy 382.86115 -220.88303)
			(xy 382.903037 -220.852598) (xy 382.949169 -220.829092) (xy 382.998409 -220.813093) (xy 383.049547 -220.804994)
			(xy 383.101321 -220.804994) (xy 383.152459 -220.813093) (xy 383.201699 -220.829092) (xy 383.247831 -220.852598)
			(xy 383.289718 -220.88303) (xy 383.326328 -220.91964) (xy 383.35676 -220.961527) (xy 383.380266 -221.007659)
			(xy 383.396265 -221.056899) (xy 383.404364 -221.108037) (xy 383.404872 -221.133924) (xy 383.404479 -221.159291)
			(xy 383.396726 -221.209429) (xy 383.381375 -221.257784) (xy 383.358791 -221.303213) (xy 383.329506 -221.344642)
			(xy 383.294215 -221.381089) (xy 383.253752 -221.411694) (xy 383.209074 -221.435731) (xy 383.161238 -221.452632)
			(xy 383.136394 -221.457774) (xy 383.113534 -221.462092) (xy 382.90881 -221.81693) (xy 382.91643 -221.838774)
			(xy 382.925044 -221.865059) (xy 382.934366 -221.919578) (xy 382.934972 -221.947232) (xy 382.934972 -221.94774)
			(xy 382.934464 -221.973647) (xy 382.926358 -222.024824) (xy 382.910346 -222.074103) (xy 382.886823 -222.12027)
			(xy 382.856367 -222.162189) (xy 382.819729 -222.198827) (xy 382.77781 -222.229283) (xy 382.731643 -222.252806)
			(xy 382.682364 -222.268818) (xy 382.631187 -222.276924) (xy 382.579373 -222.276924) (xy 382.528196 -222.268818)
			(xy 382.478917 -222.252806) (xy 382.43275 -222.229283) (xy 382.390831 -222.198827) (xy 382.354193 -222.162189)
			(xy 382.323737 -222.12027) (xy 382.300214 -222.074103) (xy 382.284202 -222.024824) (xy 382.276096 -221.973647)
			(xy 382.275588 -221.94774) (xy 381.055372 -221.94774) (xy 381.054864 -221.973647) (xy 381.046758 -222.024824)
			(xy 381.030746 -222.074103) (xy 381.007223 -222.12027) (xy 380.976767 -222.162189) (xy 380.940129 -222.198827)
			(xy 380.89821 -222.229283) (xy 380.852043 -222.252806) (xy 380.802764 -222.268818) (xy 380.751587 -222.276924)
			(xy 380.699773 -222.276924) (xy 380.648596 -222.268818) (xy 380.599317 -222.252806) (xy 380.55315 -222.229283)
			(xy 380.511231 -222.198827) (xy 380.474593 -222.162189) (xy 380.444137 -222.12027) (xy 380.420614 -222.074103)
			(xy 380.404602 -222.024824) (xy 380.396496 -221.973647) (xy 380.395988 -221.94774) (xy 379.175772 -221.94774)
			(xy 379.175264 -221.973647) (xy 379.167158 -222.024824) (xy 379.151146 -222.074103) (xy 379.127623 -222.12027)
			(xy 379.097167 -222.162189) (xy 379.060529 -222.198827) (xy 379.01861 -222.229283) (xy 378.972443 -222.252806)
			(xy 378.923164 -222.268818) (xy 378.871987 -222.276924) (xy 378.820173 -222.276924) (xy 378.768996 -222.268818)
			(xy 378.719717 -222.252806) (xy 378.67355 -222.229283) (xy 378.631631 -222.198827) (xy 378.594993 -222.162189)
			(xy 378.564537 -222.12027) (xy 378.541014 -222.074103) (xy 378.525002 -222.024824) (xy 378.516896 -221.973647)
			(xy 378.516388 -221.94774) (xy 377.296172 -221.94774) (xy 377.295664 -221.973647) (xy 377.287558 -222.024824)
			(xy 377.271546 -222.074103) (xy 377.248023 -222.12027) (xy 377.217567 -222.162189) (xy 377.180929 -222.198827)
			(xy 377.13901 -222.229283) (xy 377.092843 -222.252806) (xy 377.043564 -222.268818) (xy 376.992387 -222.276924)
			(xy 376.940573 -222.276924) (xy 376.889396 -222.268818) (xy 376.840117 -222.252806) (xy 376.79395 -222.229283)
			(xy 376.752031 -222.198827) (xy 376.715393 -222.162189) (xy 376.684937 -222.12027) (xy 376.661414 -222.074103)
			(xy 376.645402 -222.024824) (xy 376.637296 -221.973647) (xy 376.636788 -221.94774) (xy 375.821956 -221.94774)
			(xy 375.821956 -222.567754) (xy 375.836873 -222.588967) (xy 375.860526 -222.635114) (xy 375.876612 -222.684411)
			(xy 375.884729 -222.735628) (xy 375.885202 -222.761556) (xy 375.884703 -222.787479) (xy 375.876544 -222.83868)
			(xy 375.860454 -222.887967) (xy 375.836829 -222.934119) (xy 375.821956 -222.955358) (xy 375.821956 -223.157034)
			(xy 375.822479 -223.172427) (xy 375.83163 -223.201821) (xy 375.84912 -223.227156) (xy 375.873363 -223.246131)
			(xy 375.902157 -223.257023) (xy 375.932889 -223.258845) (xy 375.94794 -223.255586) (xy 375.967319 -223.251141)
			(xy 376.006799 -223.246426) (xy 376.02668 -223.246188) (xy 376.052576 -223.246693) (xy 376.103732 -223.254788)
			(xy 376.152993 -223.270783) (xy 376.199148 -223.294282) (xy 376.24106 -223.32471) (xy 376.277699 -223.361316)
			(xy 376.308164 -223.403201) (xy 376.331705 -223.449335) (xy 376.347743 -223.498581) (xy 376.355883 -223.54973)
			(xy 376.356372 -223.575626) (xy 376.355897 -223.600983) (xy 376.348111 -223.651097) (xy 376.332743 -223.699427)
			(xy 376.310154 -223.744833) (xy 376.280878 -223.786244) (xy 376.245606 -223.822684) (xy 376.205169 -223.853292)
			(xy 376.160522 -223.877347) (xy 376.112718 -223.89428) (xy 376.087894 -223.899476) (xy 376.065034 -223.903794)
			(xy 375.86031 -224.258632) (xy 375.868184 -224.280476) (xy 375.876763 -224.306895) (xy 375.885958 -224.36167)
			(xy 375.886472 -224.389442) (xy 376.167396 -224.389442) (xy 376.167904 -224.363555) (xy 376.176003 -224.312417)
			(xy 376.192002 -224.263177) (xy 376.215508 -224.217045) (xy 376.24594 -224.175158) (xy 376.28255 -224.138548)
			(xy 376.324437 -224.108116) (xy 376.370569 -224.08461) (xy 376.419809 -224.068611) (xy 376.470947 -224.060512)
			(xy 376.522721 -224.060512) (xy 376.573859 -224.068611) (xy 376.623099 -224.08461) (xy 376.669231 -224.108116)
			(xy 376.711118 -224.138548) (xy 376.747728 -224.175158) (xy 376.77816 -224.217045) (xy 376.801666 -224.263177)
			(xy 376.817665 -224.312417) (xy 376.825764 -224.363555) (xy 376.826272 -224.389442) (xy 377.107196 -224.389442)
			(xy 377.107629 -224.364106) (xy 377.11539 -224.314032) (xy 377.13072 -224.265734) (xy 377.153259 -224.22035)
			(xy 377.182475 -224.178949) (xy 377.217681 -224.142504) (xy 377.258048 -224.111874) (xy 377.302626 -224.087781)
			(xy 377.350365 -224.070791) (xy 377.375166 -224.065592) (xy 377.398026 -224.061274) (xy 377.60275 -223.706436)
			(xy 377.59513 -223.684338) (xy 377.586502 -223.657991) (xy 377.577179 -223.603344) (xy 377.576588 -223.575626)
			(xy 377.577096 -223.549719) (xy 377.585202 -223.498542) (xy 377.601214 -223.449263) (xy 377.624737 -223.403096)
			(xy 377.655193 -223.361177) (xy 377.691831 -223.324539) (xy 377.73375 -223.294083) (xy 377.779917 -223.27056)
			(xy 377.829196 -223.254548) (xy 377.880373 -223.246442) (xy 377.932187 -223.246442) (xy 377.983364 -223.254548)
			(xy 378.032643 -223.27056) (xy 378.07881 -223.294083) (xy 378.120729 -223.324539) (xy 378.157367 -223.361177)
			(xy 378.187823 -223.403096) (xy 378.211346 -223.449263) (xy 378.227358 -223.498542) (xy 378.235464 -223.549719)
			(xy 378.235972 -223.575626) (xy 378.235581 -223.600993) (xy 378.227828 -223.651131) (xy 378.212477 -223.699486)
			(xy 378.189892 -223.744915) (xy 378.160607 -223.786344) (xy 378.125316 -223.822791) (xy 378.084852 -223.853396)
			(xy 378.040174 -223.877433) (xy 377.992339 -223.894334) (xy 377.967494 -223.899476) (xy 377.944634 -223.903794)
			(xy 377.73991 -224.258632) (xy 377.747784 -224.280476) (xy 377.756357 -224.306897) (xy 377.765558 -224.36167)
			(xy 377.766072 -224.389442) (xy 378.046996 -224.389442) (xy 378.047504 -224.363555) (xy 378.055603 -224.312417)
			(xy 378.071602 -224.263177) (xy 378.095108 -224.217045) (xy 378.12554 -224.175158) (xy 378.16215 -224.138548)
			(xy 378.204037 -224.108116) (xy 378.250169 -224.08461) (xy 378.299409 -224.068611) (xy 378.350547 -224.060512)
			(xy 378.402321 -224.060512) (xy 378.453459 -224.068611) (xy 378.502699 -224.08461) (xy 378.548831 -224.108116)
			(xy 378.590718 -224.138548) (xy 378.627328 -224.175158) (xy 378.65776 -224.217045) (xy 378.681266 -224.263177)
			(xy 378.697265 -224.312417) (xy 378.705364 -224.363555) (xy 378.705872 -224.389442) (xy 378.986796 -224.389442)
			(xy 378.987229 -224.364106) (xy 378.99499 -224.314032) (xy 379.01032 -224.265734) (xy 379.032859 -224.22035)
			(xy 379.062075 -224.178949) (xy 379.097281 -224.142504) (xy 379.137648 -224.111874) (xy 379.182226 -224.087781)
			(xy 379.229965 -224.070791) (xy 379.254766 -224.065592) (xy 379.277626 -224.061274) (xy 379.48235 -223.706182)
			(xy 379.47473 -223.684338) (xy 379.466087 -223.657995) (xy 379.456772 -223.603345) (xy 379.456188 -223.575626)
			(xy 379.456696 -223.549719) (xy 379.464802 -223.498542) (xy 379.480814 -223.449263) (xy 379.504337 -223.403096)
			(xy 379.534793 -223.361177) (xy 379.571431 -223.324539) (xy 379.61335 -223.294083) (xy 379.659517 -223.27056)
			(xy 379.708796 -223.254548) (xy 379.759973 -223.246442) (xy 379.811787 -223.246442) (xy 379.862964 -223.254548)
			(xy 379.912243 -223.27056) (xy 379.95841 -223.294083) (xy 380.000329 -223.324539) (xy 380.036967 -223.361177)
			(xy 380.067423 -223.403096) (xy 380.090946 -223.449263) (xy 380.106958 -223.498542) (xy 380.115064 -223.549719)
			(xy 380.115572 -223.575626) (xy 380.115097 -223.600971) (xy 380.107321 -223.651063) (xy 380.091971 -223.699374)
			(xy 380.069408 -223.744767) (xy 380.040166 -223.786173) (xy 380.004931 -223.822617) (xy 379.964535 -223.853239)
			(xy 379.919928 -223.877319) (xy 379.872162 -223.89429) (xy 379.847348 -223.899476) (xy 379.824488 -223.903794)
			(xy 379.619764 -224.258632) (xy 379.627384 -224.280476) (xy 379.635939 -224.306769) (xy 379.645132 -224.361289)
			(xy 379.645672 -224.388934) (xy 379.645672 -224.389442) (xy 379.926596 -224.389442) (xy 379.927104 -224.363555)
			(xy 379.935203 -224.312417) (xy 379.951202 -224.263177) (xy 379.974708 -224.217045) (xy 380.00514 -224.175158)
			(xy 380.04175 -224.138548) (xy 380.083637 -224.108116) (xy 380.129769 -224.08461) (xy 380.179009 -224.068611)
			(xy 380.230147 -224.060512) (xy 380.281921 -224.060512) (xy 380.333059 -224.068611) (xy 380.382299 -224.08461)
			(xy 380.428431 -224.108116) (xy 380.470318 -224.138548) (xy 380.506928 -224.175158) (xy 380.53736 -224.217045)
			(xy 380.560866 -224.263177) (xy 380.576865 -224.312417) (xy 380.584964 -224.363555) (xy 380.585472 -224.389442)
			(xy 380.866396 -224.389442) (xy 380.866829 -224.364106) (xy 380.87459 -224.314032) (xy 380.88992 -224.265734)
			(xy 380.912459 -224.22035) (xy 380.941675 -224.178949) (xy 380.976881 -224.142504) (xy 381.017248 -224.111874)
			(xy 381.061826 -224.087781) (xy 381.109565 -224.070791) (xy 381.134366 -224.065592) (xy 381.157226 -224.061274)
			(xy 381.362204 -223.705928) (xy 381.354584 -223.684084) (xy 381.346035 -223.657789) (xy 381.336839 -223.603271)
			(xy 381.336296 -223.575626) (xy 381.336804 -223.549739) (xy 381.344903 -223.498601) (xy 381.360902 -223.449361)
			(xy 381.384408 -223.403229) (xy 381.41484 -223.361342) (xy 381.45145 -223.324732) (xy 381.493337 -223.2943)
			(xy 381.539469 -223.270794) (xy 381.588709 -223.254795) (xy 381.639847 -223.246696) (xy 381.691621 -223.246696)
			(xy 381.742759 -223.254795) (xy 381.791999 -223.270794) (xy 381.838131 -223.2943) (xy 381.880018 -223.324732)
			(xy 381.916628 -223.361342) (xy 381.94706 -223.403229) (xy 381.970566 -223.449361) (xy 381.986565 -223.498601)
			(xy 381.994664 -223.549739) (xy 381.995172 -223.575626) (xy 381.994697 -223.600971) (xy 381.986921 -223.651063)
			(xy 381.971571 -223.699374) (xy 381.949008 -223.744767) (xy 381.919766 -223.786173) (xy 381.884531 -223.822617)
			(xy 381.844135 -223.853239) (xy 381.799528 -223.877319) (xy 381.751762 -223.89429) (xy 381.726948 -223.899476)
			(xy 381.704088 -223.903794) (xy 381.499364 -224.258632) (xy 381.506984 -224.280476) (xy 381.515539 -224.306769)
			(xy 381.524732 -224.361289) (xy 381.525272 -224.388934) (xy 381.525272 -224.389442) (xy 381.806196 -224.389442)
			(xy 381.806704 -224.363555) (xy 381.814803 -224.312417) (xy 381.830802 -224.263177) (xy 381.854308 -224.217045)
			(xy 381.88474 -224.175158) (xy 381.92135 -224.138548) (xy 381.963237 -224.108116) (xy 382.009369 -224.08461)
			(xy 382.058609 -224.068611) (xy 382.109747 -224.060512) (xy 382.161521 -224.060512) (xy 382.212659 -224.068611)
			(xy 382.261899 -224.08461) (xy 382.308031 -224.108116) (xy 382.349918 -224.138548) (xy 382.386528 -224.175158)
			(xy 382.41696 -224.217045) (xy 382.440466 -224.263177) (xy 382.456465 -224.312417) (xy 382.464564 -224.363555)
			(xy 382.465072 -224.389442) (xy 382.464539 -224.41715) (xy 382.455342 -224.471795) (xy 382.446784 -224.498154)
			(xy 382.439164 -224.519998) (xy 382.644142 -224.87509) (xy 382.667002 -224.879408) (xy 382.691815 -224.884555)
			(xy 382.739557 -224.901547) (xy 382.784137 -224.925644) (xy 382.824504 -224.95628) (xy 382.859707 -224.992732)
			(xy 382.888918 -225.034142) (xy 382.911448 -225.079534) (xy 382.926766 -225.12784) (xy 382.934512 -225.17792)
			(xy 382.934972 -225.203258) (xy 382.934464 -225.229145) (xy 382.926365 -225.280283) (xy 382.910366 -225.329523)
			(xy 382.88686 -225.375655) (xy 382.856428 -225.417542) (xy 382.819818 -225.454152) (xy 382.777931 -225.484584)
			(xy 382.731799 -225.50809) (xy 382.682559 -225.524089) (xy 382.631421 -225.532188) (xy 382.579647 -225.532188)
			(xy 382.528509 -225.524089) (xy 382.479269 -225.50809) (xy 382.433137 -225.484584) (xy 382.39125 -225.454152)
			(xy 382.35464 -225.417542) (xy 382.324208 -225.375655) (xy 382.300702 -225.329523) (xy 382.284703 -225.280283)
			(xy 382.276604 -225.229145) (xy 382.276096 -225.203258) (xy 382.276096 -225.20275) (xy 382.276653 -225.175107)
			(xy 382.285844 -225.120589) (xy 382.294384 -225.094292) (xy 382.302004 -225.072448) (xy 382.09728 -224.71761)
			(xy 382.07442 -224.713292) (xy 382.049591 -224.708158) (xy 382.001812 -224.691199) (xy 381.957192 -224.667122)
			(xy 381.916786 -224.636498) (xy 381.881546 -224.600046) (xy 381.852303 -224.558629) (xy 381.829748 -224.513222)
			(xy 381.814412 -224.464896) (xy 381.806657 -224.414792) (xy 381.806196 -224.389442) (xy 381.525272 -224.389442)
			(xy 381.524764 -224.415329) (xy 381.516665 -224.466467) (xy 381.500666 -224.515707) (xy 381.47716 -224.561839)
			(xy 381.446728 -224.603726) (xy 381.410118 -224.640336) (xy 381.368231 -224.670768) (xy 381.322099 -224.694274)
			(xy 381.272859 -224.710273) (xy 381.221721 -224.718372) (xy 381.169947 -224.718372) (xy 381.118809 -224.710273)
			(xy 381.069569 -224.694274) (xy 381.023437 -224.670768) (xy 380.98155 -224.640336) (xy 380.94494 -224.603726)
			(xy 380.914508 -224.561839) (xy 380.891002 -224.515707) (xy 380.875003 -224.466467) (xy 380.866904 -224.415329)
			(xy 380.866396 -224.389442) (xy 380.585472 -224.389442) (xy 380.584925 -224.417149) (xy 380.575741 -224.471796)
			(xy 380.567184 -224.498154) (xy 380.55931 -224.520252) (xy 380.764288 -224.87509) (xy 380.787148 -224.879408)
			(xy 380.811971 -224.884565) (xy 380.859751 -224.90152) (xy 380.904371 -224.925592) (xy 380.944778 -224.956214)
			(xy 380.980019 -224.992662) (xy 381.009263 -225.034077) (xy 381.031819 -225.079482) (xy 381.047156 -225.127806)
			(xy 381.054911 -225.177908) (xy 381.055372 -225.203258) (xy 381.054864 -225.229165) (xy 381.046758 -225.280342)
			(xy 381.030746 -225.329621) (xy 381.007223 -225.375788) (xy 380.976767 -225.417707) (xy 380.940129 -225.454345)
			(xy 380.89821 -225.484801) (xy 380.852043 -225.508324) (xy 380.802764 -225.524336) (xy 380.751587 -225.532442)
			(xy 380.699773 -225.532442) (xy 380.648596 -225.524336) (xy 380.599317 -225.508324) (xy 380.55315 -225.484801)
			(xy 380.511231 -225.454345) (xy 380.474593 -225.417707) (xy 380.444137 -225.375788) (xy 380.420614 -225.329621)
			(xy 380.404602 -225.280342) (xy 380.396496 -225.229165) (xy 380.395988 -225.203258) (xy 380.396597 -225.175541)
			(xy 380.40591 -225.120895) (xy 380.41453 -225.094546) (xy 380.422404 -225.072448) (xy 380.217426 -224.71761)
			(xy 380.194566 -224.713292) (xy 380.169748 -224.708169) (xy 380.122005 -224.691172) (xy 380.077426 -224.667071)
			(xy 380.03706 -224.636431) (xy 380.001857 -224.599976) (xy 379.972648 -224.558564) (xy 379.950119 -224.51317)
			(xy 379.934801 -224.464863) (xy 379.927055 -224.414781) (xy 379.926596 -224.389442) (xy 379.645672 -224.389442)
			(xy 379.645164 -224.415329) (xy 379.637065 -224.466467) (xy 379.621066 -224.515707) (xy 379.59756 -224.561839)
			(xy 379.567128 -224.603726) (xy 379.530518 -224.640336) (xy 379.488631 -224.670768) (xy 379.442499 -224.694274)
			(xy 379.393259 -224.710273) (xy 379.342121 -224.718372) (xy 379.290347 -224.718372) (xy 379.239209 -224.710273)
			(xy 379.189969 -224.694274) (xy 379.143837 -224.670768) (xy 379.10195 -224.640336) (xy 379.06534 -224.603726)
			(xy 379.034908 -224.561839) (xy 379.011402 -224.515707) (xy 378.995403 -224.466467) (xy 378.987304 -224.415329)
			(xy 378.986796 -224.389442) (xy 378.705872 -224.389442) (xy 378.705325 -224.417149) (xy 378.696141 -224.471796)
			(xy 378.687584 -224.498154) (xy 378.67971 -224.520252) (xy 378.884688 -224.87509) (xy 378.907548 -224.879408)
			(xy 378.932371 -224.884565) (xy 378.980151 -224.90152) (xy 379.024771 -224.925592) (xy 379.065178 -224.956214)
			(xy 379.100419 -224.992662) (xy 379.129663 -225.034077) (xy 379.152219 -225.079482) (xy 379.167556 -225.127806)
			(xy 379.175311 -225.177908) (xy 379.175772 -225.203258) (xy 379.175264 -225.229165) (xy 379.167158 -225.280342)
			(xy 379.151146 -225.329621) (xy 379.127623 -225.375788) (xy 379.097167 -225.417707) (xy 379.060529 -225.454345)
			(xy 379.01861 -225.484801) (xy 378.972443 -225.508324) (xy 378.923164 -225.524336) (xy 378.871987 -225.532442)
			(xy 378.820173 -225.532442) (xy 378.768996 -225.524336) (xy 378.719717 -225.508324) (xy 378.67355 -225.484801)
			(xy 378.631631 -225.454345) (xy 378.594993 -225.417707) (xy 378.564537 -225.375788) (xy 378.541014 -225.329621)
			(xy 378.525002 -225.280342) (xy 378.516896 -225.229165) (xy 378.516388 -225.203258) (xy 378.516997 -225.175541)
			(xy 378.52631 -225.120895) (xy 378.53493 -225.094546) (xy 378.542804 -225.072448) (xy 378.337826 -224.71761)
			(xy 378.314966 -224.713292) (xy 378.290148 -224.708169) (xy 378.242405 -224.691172) (xy 378.197826 -224.667071)
			(xy 378.15746 -224.636431) (xy 378.122257 -224.599976) (xy 378.093048 -224.558564) (xy 378.070519 -224.51317)
			(xy 378.055201 -224.464863) (xy 378.047455 -224.414781) (xy 378.046996 -224.389442) (xy 377.766072 -224.389442)
			(xy 377.765564 -224.415329) (xy 377.757465 -224.466467) (xy 377.741466 -224.515707) (xy 377.71796 -224.561839)
			(xy 377.687528 -224.603726) (xy 377.650918 -224.640336) (xy 377.609031 -224.670768) (xy 377.562899 -224.694274)
			(xy 377.513659 -224.710273) (xy 377.462521 -224.718372) (xy 377.410747 -224.718372) (xy 377.359609 -224.710273)
			(xy 377.310369 -224.694274) (xy 377.264237 -224.670768) (xy 377.22235 -224.640336) (xy 377.18574 -224.603726)
			(xy 377.155308 -224.561839) (xy 377.131802 -224.515707) (xy 377.115803 -224.466467) (xy 377.107704 -224.415329)
			(xy 377.107196 -224.389442) (xy 376.826272 -224.389442) (xy 376.825725 -224.417149) (xy 376.816541 -224.471796)
			(xy 376.807984 -224.498154) (xy 376.80011 -224.520252) (xy 377.005088 -224.87509) (xy 377.027948 -224.879408)
			(xy 377.052771 -224.884565) (xy 377.100551 -224.90152) (xy 377.145171 -224.925592) (xy 377.185578 -224.956214)
			(xy 377.220819 -224.992662) (xy 377.250063 -225.034077) (xy 377.272619 -225.079482) (xy 377.287956 -225.127806)
			(xy 377.295711 -225.177908) (xy 377.296172 -225.203258) (xy 377.295664 -225.229165) (xy 377.287558 -225.280342)
			(xy 377.271546 -225.329621) (xy 377.248023 -225.375788) (xy 377.217567 -225.417707) (xy 377.180929 -225.454345)
			(xy 377.13901 -225.484801) (xy 377.092843 -225.508324) (xy 377.043564 -225.524336) (xy 376.992387 -225.532442)
			(xy 376.940573 -225.532442) (xy 376.889396 -225.524336) (xy 376.840117 -225.508324) (xy 376.79395 -225.484801)
			(xy 376.752031 -225.454345) (xy 376.715393 -225.417707) (xy 376.684937 -225.375788) (xy 376.661414 -225.329621)
			(xy 376.645402 -225.280342) (xy 376.637296 -225.229165) (xy 376.636788 -225.203258) (xy 376.637397 -225.175541)
			(xy 376.64671 -225.120895) (xy 376.65533 -225.094546) (xy 376.663204 -225.072448) (xy 376.458226 -224.71761)
			(xy 376.435366 -224.713292) (xy 376.410548 -224.708169) (xy 376.362805 -224.691172) (xy 376.318226 -224.667071)
			(xy 376.27786 -224.636431) (xy 376.242657 -224.599976) (xy 376.213448 -224.558564) (xy 376.190919 -224.51317)
			(xy 376.175601 -224.464863) (xy 376.167855 -224.414781) (xy 376.167396 -224.389442) (xy 375.886472 -224.389442)
			(xy 375.885982 -224.415703) (xy 375.87769 -224.467565) (xy 375.861276 -224.517455) (xy 375.837155 -224.564109)
			(xy 375.821956 -224.58553) (xy 375.821956 -225.3361) (xy 376.265948 -225.780092) (xy 376.301 -225.75393)
			(xy 376.322374 -225.738698) (xy 376.368949 -225.714508) (xy 376.418778 -225.698033) (xy 376.470593 -225.689692)
			(xy 376.496834 -225.68916) (xy 376.522619 -225.689668) (xy 376.573553 -225.697741) (xy 376.622598 -225.713682)
			(xy 376.668545 -225.737099) (xy 376.710263 -225.767415) (xy 376.746725 -225.803884) (xy 376.777034 -225.845608)
			(xy 376.800442 -225.891559) (xy 376.816374 -225.940607) (xy 376.824437 -225.991543) (xy 376.825002 -226.017328)
			(xy 376.824485 -226.043569) (xy 376.816134 -226.095382) (xy 376.799649 -226.145207) (xy 376.775449 -226.191777)
			(xy 376.760232 -226.213162) (xy 376.73407 -226.248214) (xy 376.989086 -226.50323) (xy 377.006612 -226.505516)
			(xy 377.030915 -226.508971) (xy 377.078196 -226.522161) (xy 377.122985 -226.542248) (xy 377.164282 -226.568782)
			(xy 377.201166 -226.601171) (xy 377.232813 -226.638694) (xy 377.258518 -226.680512) (xy 377.277706 -226.725693)
			(xy 377.284234 -226.749356) (xy 377.29414 -226.787456) (xy 377.57862 -226.787456) (xy 377.588526 -226.749356)
			(xy 377.59534 -226.724811) (xy 377.615508 -226.678036) (xy 377.642663 -226.63494) (xy 377.676151 -226.596557)
			(xy 377.715169 -226.563812) (xy 377.758778 -226.537489) (xy 377.805931 -226.518222) (xy 377.855495 -226.506473)
			(xy 377.90628 -226.502525) (xy 377.957065 -226.506473) (xy 378.006629 -226.518222) (xy 378.053782 -226.537489)
			(xy 378.097391 -226.563812) (xy 378.136409 -226.596557) (xy 378.169897 -226.63494) (xy 378.197052 -226.678036)
			(xy 378.21722 -226.724811) (xy 378.224034 -226.749356) (xy 378.23394 -226.787456) (xy 378.518674 -226.787456)
			(xy 378.52858 -226.749356) (xy 378.535394 -226.724811) (xy 378.555562 -226.678036) (xy 378.582717 -226.63494)
			(xy 378.616205 -226.596557) (xy 378.655223 -226.563812) (xy 378.698832 -226.537489) (xy 378.745985 -226.518222)
			(xy 378.795549 -226.506473) (xy 378.846334 -226.502525) (xy 378.897119 -226.506473) (xy 378.946683 -226.518222)
			(xy 378.993836 -226.537489) (xy 379.037445 -226.563812) (xy 379.076463 -226.596557) (xy 379.109951 -226.63494)
			(xy 379.137106 -226.678036) (xy 379.157274 -226.724811) (xy 379.164088 -226.749356) (xy 379.173994 -226.787456)
			(xy 379.45822 -226.787456) (xy 379.468126 -226.749356) (xy 379.47494 -226.724811) (xy 379.495108 -226.678036)
			(xy 379.522263 -226.63494) (xy 379.555751 -226.596557) (xy 379.594769 -226.563812) (xy 379.638378 -226.537489)
			(xy 379.685531 -226.518222) (xy 379.735095 -226.506473) (xy 379.78588 -226.502525) (xy 379.836665 -226.506473)
			(xy 379.886229 -226.518222) (xy 379.933382 -226.537489) (xy 379.976991 -226.563812) (xy 380.016009 -226.596557)
			(xy 380.049497 -226.63494) (xy 380.076652 -226.678036) (xy 380.09682 -226.724811) (xy 380.103634 -226.749356)
			(xy 380.11354 -226.787456) (xy 380.546356 -226.787456) (xy 380.571314 -226.788033) (xy 380.620268 -226.797783)
			(xy 380.666379 -226.816897) (xy 380.707875 -226.844641) (xy 380.725934 -226.861878) (xy 381.180594 -227.316538)
			(xy 381.201168 -227.316792) (xy 381.226415 -227.317669) (xy 381.276201 -227.326224) (xy 381.324089 -227.342304)
			(xy 381.368948 -227.365532) (xy 381.409719 -227.395357) (xy 381.445439 -227.431077) (xy 381.475265 -227.471847)
			(xy 381.498493 -227.516706) (xy 381.514575 -227.564593) (xy 381.52313 -227.614379) (xy 381.524002 -227.639626)
			(xy 381.524256 -227.6602) (xy 382.87452 -229.010464) (xy 382.908302 -228.990398) (xy 382.933802 -228.976067)
			(xy 382.988626 -228.955686) (xy 383.04619 -228.945327) (xy 383.075434 -228.944678) (xy 383.101221 -228.94516)
			(xy 383.152158 -228.953234) (xy 383.201205 -228.969176) (xy 383.247155 -228.992595) (xy 383.288875 -229.022914)
			(xy 383.325338 -229.059386) (xy 383.355647 -229.101114) (xy 383.379055 -229.147069) (xy 383.394985 -229.19612)
			(xy 383.403046 -229.247059) (xy 383.403602 -229.272846) (xy 383.402968 -229.302092) (xy 383.392618 -229.359662)
			(xy 383.372236 -229.414489) (xy 383.357882 -229.439978) (xy 383.337816 -229.47376) (xy 383.634742 -229.770686)
			(xy 383.646426 -229.774496) (xy 383.670859 -229.782918) (xy 383.71692 -229.806352) (xy 383.758739 -229.836715)
			(xy 383.795282 -229.873257) (xy 383.825646 -229.915076) (xy 383.84908 -229.961136) (xy 383.8575 -229.98557)
			(xy 383.86131 -229.997254) (xy 387.813296 -233.94924) (xy 387.830559 -233.96728) (xy 387.858322 -234.008772)
			(xy 387.877439 -234.05489) (xy 387.887174 -234.103856) (xy 387.887718 -234.128818) (xy 387.887718 -244.381528)
			(xy 387.888988 -244.387116) (xy 387.892671 -244.404794) (xy 387.896612 -244.440689) (xy 387.896862 -244.458744)
			(xy 387.89664 -244.476801) (xy 387.892696 -244.512698) (xy 387.888988 -244.530372) (xy 387.887718 -244.53596)
			(xy 387.887718 -246.719598) (xy 387.922262 -246.731282) (xy 387.946381 -246.739875) (xy 387.991818 -246.763474)
			(xy 388.033037 -246.793845) (xy 388.069038 -246.83025) (xy 388.098947 -246.871806) (xy 388.122038 -246.917503)
			(xy 388.13775 -246.966232) (xy 388.145701 -247.01681) (xy 388.1457 -247.06801) (xy 388.137745 -247.118588)
			(xy 388.12203 -247.167316) (xy 388.098936 -247.213012) (xy 388.069025 -247.254565) (xy 388.033022 -247.290968)
			(xy 387.991801 -247.321336) (xy 387.946363 -247.344933) (xy 387.922262 -247.353582) (xy 387.887718 -247.365266)
			(xy 387.887718 -251.76988) (xy 391.655564 -251.76988) (xy 391.659545 -251.63686) (xy 391.671474 -251.504315)
			(xy 391.691309 -251.372722) (xy 391.718978 -251.24255) (xy 391.754382 -251.114265) (xy 391.797395 -250.988328)
			(xy 391.847862 -250.865189) (xy 391.905603 -250.745288) (xy 391.970412 -250.629055) (xy 392.042056 -250.516905)
			(xy 392.120278 -250.409241) (xy 392.204799 -250.306448) (xy 392.295317 -250.208893) (xy 392.391506 -250.116927)
			(xy 392.493024 -250.030877) (xy 392.599505 -249.951053) (xy 392.71057 -249.87774) (xy 392.825821 -249.8112)
			(xy 392.944845 -249.751671) (xy 393.067216 -249.699367) (xy 393.192495 -249.654475) (xy 393.320236 -249.617156)
			(xy 393.449979 -249.587543) (xy 393.581261 -249.565742) (xy 393.713612 -249.551832) (xy 393.846558 -249.545861)
			(xy 393.979623 -249.547852) (xy 394.112331 -249.557797) (xy 394.244207 -249.575661) (xy 394.374778 -249.601379)
			(xy 394.503578 -249.63486) (xy 394.630144 -249.675984) (xy 394.754025 -249.724604) (xy 394.874776 -249.780545)
			(xy 394.991966 -249.843607) (xy 395.105175 -249.913565) (xy 395.213997 -249.990169) (xy 395.318043 -250.073143)
			(xy 395.416941 -250.162191) (xy 395.510336 -250.256994) (xy 395.597894 -250.357212) (xy 395.679303 -250.462488)
			(xy 395.754269 -250.572444) (xy 395.822526 -250.686686) (xy 395.883828 -250.804806) (xy 395.937957 -250.926381)
			(xy 395.984718 -251.050975) (xy 396.023944 -251.178143) (xy 396.055494 -251.307429) (xy 396.079257 -251.43837)
			(xy 396.095146 -251.570498) (xy 396.103104 -251.70334) (xy 396.103602 -251.76988) (xy 396.103104 -251.83642)
			(xy 396.095146 -251.969262) (xy 396.079257 -252.10139) (xy 396.055494 -252.232331) (xy 396.023944 -252.361617)
			(xy 395.984718 -252.488785) (xy 395.937957 -252.613379) (xy 395.883828 -252.734954) (xy 395.822526 -252.853074)
			(xy 395.754269 -252.967316) (xy 395.679303 -253.077272) (xy 395.597894 -253.182548) (xy 395.510336 -253.282766)
			(xy 395.416941 -253.377569) (xy 395.318043 -253.466617) (xy 395.213997 -253.549591) (xy 395.105175 -253.626195)
			(xy 394.991966 -253.696153) (xy 394.874776 -253.759215) (xy 394.754025 -253.815156) (xy 394.630144 -253.863776)
			(xy 394.503578 -253.9049) (xy 394.374778 -253.938381) (xy 394.244207 -253.964099) (xy 394.112331 -253.981963)
			(xy 393.979623 -253.991908) (xy 393.846558 -253.993899) (xy 393.713612 -253.987928) (xy 393.581261 -253.974018)
			(xy 393.449979 -253.952217) (xy 393.320236 -253.922604) (xy 393.192495 -253.885285) (xy 393.067216 -253.840393)
			(xy 392.944845 -253.788089) (xy 392.825821 -253.72856) (xy 392.71057 -253.66202) (xy 392.599505 -253.588707)
			(xy 392.493024 -253.508883) (xy 392.391506 -253.422833) (xy 392.295317 -253.330867) (xy 392.204799 -253.233312)
			(xy 392.120278 -253.130519) (xy 392.042056 -253.022855) (xy 391.970412 -252.910705) (xy 391.905603 -252.794472)
			(xy 391.847862 -252.674571) (xy 391.797395 -252.551432) (xy 391.754382 -252.425495) (xy 391.718978 -252.29721)
			(xy 391.691309 -252.167038) (xy 391.671474 -252.035445) (xy 391.659545 -251.9029) (xy 391.655564 -251.76988)
			(xy 387.887718 -251.76988) (xy 387.887718 -261.727442) (xy 387.931152 -261.733538) (xy 387.956855 -261.737757)
			(xy 388.006579 -261.753254) (xy 388.053232 -261.776409) (xy 388.095644 -261.806642) (xy 388.132748 -261.843192)
			(xy 388.163615 -261.885144) (xy 388.18747 -261.931443) (xy 388.203713 -261.980929) (xy 388.211938 -262.032359)
			(xy 388.211938 -262.084442) (xy 388.203713 -262.135872) (xy 388.187469 -262.185358) (xy 388.163615 -262.231657)
			(xy 388.132747 -262.273609) (xy 388.095643 -262.310159) (xy 388.053231 -262.340391) (xy 388.006578 -262.363546)
			(xy 387.956853 -262.379043) (xy 387.931152 -262.38327) (xy 387.887718 -262.389366) (xy 387.887718 -263.184894)
			(xy 387.887098 -263.209847) (xy 387.877345 -263.258792) (xy 387.858233 -263.304894) (xy 387.830496 -263.346383)
			(xy 387.813296 -263.364472) (xy 384.407156 -266.770612) (xy 384.422142 -266.80287) (xy 384.431896 -266.824722)
			(xy 384.445682 -266.870544) (xy 384.452671 -266.917883) (xy 384.45313 -266.941808) (xy 384.45265 -266.967596)
			(xy 384.44458 -267.018537) (xy 384.42864 -267.067588) (xy 384.405222 -267.113542) (xy 384.374904 -267.155266)
			(xy 384.338431 -267.191734) (xy 384.296703 -267.222046) (xy 384.250746 -267.245457) (xy 384.201692 -267.26139)
			(xy 384.15075 -267.269453) (xy 384.124962 -267.269976) (xy 384.101036 -267.269525) (xy 384.053696 -267.262539)
			(xy 384.007873 -267.248749) (xy 383.986024 -267.238988) (xy 383.953766 -267.224002) (xy 382.57226 -268.605508)
			(xy 382.56972 -268.621764) (xy 382.565151 -268.647064) (xy 382.549185 -268.695931) (xy 382.525796 -268.741712)
			(xy 382.495557 -268.783287) (xy 382.459206 -268.81964) (xy 382.417633 -268.849883) (xy 382.371854 -268.873275)
			(xy 382.322989 -268.889245) (xy 382.297686 -268.893798) (xy 382.28143 -268.896338) (xy 382.016762 -269.161006)
			(xy 382.033 -269.179301) (xy 382.060436 -269.219797) (xy 382.081562 -269.263915) (xy 382.095911 -269.310678)
			(xy 382.103165 -269.359052) (xy 382.10363 -269.38351) (xy 382.103149 -269.409298) (xy 382.095079 -269.460239)
			(xy 382.079139 -269.50929) (xy 382.055721 -269.555243) (xy 382.025403 -269.596967) (xy 381.988931 -269.633434)
			(xy 381.947202 -269.663746) (xy 381.901245 -269.687157) (xy 381.852192 -269.70309) (xy 381.80125 -269.711153)
			(xy 381.775462 -269.711678) (xy 381.751005 -269.711225) (xy 381.702633 -269.703964) (xy 381.655873 -269.689607)
			(xy 381.611759 -269.668473) (xy 381.571269 -269.64103) (xy 381.552958 -269.62481) (xy 380.220474 -270.957294)
			(xy 380.222506 -270.98117) (xy 380.22403 -271.011396) (xy 380.22355 -271.037185) (xy 380.215482 -271.088127)
			(xy 380.199543 -271.13718) (xy 380.176126 -271.183135) (xy 380.145808 -271.224861) (xy 380.109335 -271.26133)
			(xy 380.067606 -271.291644) (xy 380.021649 -271.315056) (xy 379.972594 -271.33099) (xy 379.921651 -271.339053)
			(xy 379.895862 -271.339564) (xy 379.870494 -271.339087) (xy 379.820364 -271.331271) (xy 379.772035 -271.31583)
			(xy 379.72666 -271.293132) (xy 379.68532 -271.26372) (xy 379.649 -271.228294) (xy 379.618568 -271.187698)
			(xy 379.594748 -271.142902) (xy 379.585982 -271.119092) (xy 379.574044 -271.085056) (xy 379.27788 -271.085056)
			(xy 379.265942 -271.119092) (xy 379.257182 -271.142908) (xy 379.233374 -271.187719) (xy 379.202948 -271.228329)
			(xy 379.16663 -271.263768) (xy 379.125288 -271.29319) (xy 379.079907 -271.315894) (xy 379.031571 -271.331338)
			(xy 378.981434 -271.339153) (xy 378.93069 -271.339153) (xy 378.880553 -271.331338) (xy 378.832217 -271.315894)
			(xy 378.786836 -271.29319) (xy 378.745494 -271.263768) (xy 378.709176 -271.228329) (xy 378.67875 -271.187719)
			(xy 378.654942 -271.142908) (xy 378.646182 -271.119092) (xy 378.634244 -271.085056) (xy 378.33808 -271.085056)
			(xy 378.326142 -271.119092) (xy 378.317382 -271.142908) (xy 378.293574 -271.187719) (xy 378.263148 -271.228329)
			(xy 378.22683 -271.263768) (xy 378.185488 -271.29319) (xy 378.140107 -271.315894) (xy 378.091771 -271.331338)
			(xy 378.041634 -271.339153) (xy 377.99089 -271.339153) (xy 377.940753 -271.331338) (xy 377.892417 -271.315894)
			(xy 377.847036 -271.29319) (xy 377.805694 -271.263768) (xy 377.769376 -271.228329) (xy 377.73895 -271.187719)
			(xy 377.715142 -271.142908) (xy 377.706382 -271.119092) (xy 377.694444 -271.085056) (xy 377.39828 -271.085056)
			(xy 377.386342 -271.119092) (xy 377.377582 -271.142908) (xy 377.353774 -271.187719) (xy 377.323348 -271.228329)
			(xy 377.28703 -271.263768) (xy 377.245688 -271.29319) (xy 377.200307 -271.315894) (xy 377.151971 -271.331338)
			(xy 377.101834 -271.339153) (xy 377.05109 -271.339153) (xy 377.000953 -271.331338) (xy 376.952617 -271.315894)
			(xy 376.907236 -271.29319) (xy 376.865894 -271.263768) (xy 376.829576 -271.228329) (xy 376.79915 -271.187719)
			(xy 376.775342 -271.142908) (xy 376.766582 -271.119092) (xy 376.754644 -271.085056) (xy 376.45848 -271.085056)
			(xy 376.446542 -271.119092) (xy 376.437782 -271.142908) (xy 376.413974 -271.187719) (xy 376.383548 -271.228329)
			(xy 376.34723 -271.263768) (xy 376.305888 -271.29319) (xy 376.260507 -271.315894) (xy 376.212171 -271.331338)
			(xy 376.162034 -271.339153) (xy 376.11129 -271.339153) (xy 376.061153 -271.331338) (xy 376.012817 -271.315894)
			(xy 375.967436 -271.29319) (xy 375.926094 -271.263768) (xy 375.889776 -271.228329) (xy 375.85935 -271.187719)
			(xy 375.835542 -271.142908) (xy 375.826782 -271.119092) (xy 375.814844 -271.085056) (xy 375.51868 -271.085056)
			(xy 375.506742 -271.119092) (xy 375.497982 -271.142908) (xy 375.474174 -271.187719) (xy 375.443748 -271.228329)
			(xy 375.40743 -271.263768) (xy 375.366088 -271.29319) (xy 375.320707 -271.315894) (xy 375.272371 -271.331338)
			(xy 375.222234 -271.339153) (xy 375.17149 -271.339153) (xy 375.121353 -271.331338) (xy 375.073017 -271.315894)
			(xy 375.027636 -271.29319) (xy 374.986294 -271.263768) (xy 374.949976 -271.228329) (xy 374.91955 -271.187719)
			(xy 374.895742 -271.142908) (xy 374.886982 -271.119092) (xy 374.875044 -271.085056) (xy 374.57888 -271.085056)
			(xy 374.566942 -271.119092) (xy 374.558182 -271.142908) (xy 374.534374 -271.187719) (xy 374.503948 -271.228329)
			(xy 374.46763 -271.263768) (xy 374.426288 -271.29319) (xy 374.380907 -271.315894) (xy 374.332571 -271.331338)
			(xy 374.282434 -271.339153) (xy 374.23169 -271.339153) (xy 374.181553 -271.331338) (xy 374.133217 -271.315894)
			(xy 374.087836 -271.29319) (xy 374.046494 -271.263768) (xy 374.010176 -271.228329) (xy 373.97975 -271.187719)
			(xy 373.955942 -271.142908) (xy 373.947182 -271.119092) (xy 373.935244 -271.085056) (xy 373.63908 -271.085056)
			(xy 373.627142 -271.119092) (xy 373.618382 -271.142908) (xy 373.594574 -271.187719) (xy 373.564148 -271.228329)
			(xy 373.52783 -271.263768) (xy 373.486488 -271.29319) (xy 373.441107 -271.315894) (xy 373.392771 -271.331338)
			(xy 373.342634 -271.339153) (xy 373.29189 -271.339153) (xy 373.241753 -271.331338) (xy 373.193417 -271.315894)
			(xy 373.148036 -271.29319) (xy 373.106694 -271.263768) (xy 373.070376 -271.228329) (xy 373.03995 -271.187719)
			(xy 373.016142 -271.142908) (xy 373.007382 -271.119092) (xy 372.995444 -271.085056) (xy 372.69928 -271.085056)
			(xy 372.687342 -271.119092) (xy 372.678582 -271.142908) (xy 372.654774 -271.187719) (xy 372.624348 -271.228329)
			(xy 372.58803 -271.263768) (xy 372.546688 -271.29319) (xy 372.501307 -271.315894) (xy 372.452971 -271.331338)
			(xy 372.402834 -271.339153) (xy 372.35209 -271.339153) (xy 372.301953 -271.331338) (xy 372.253617 -271.315894)
			(xy 372.208236 -271.29319) (xy 372.166894 -271.263768) (xy 372.130576 -271.228329) (xy 372.10015 -271.187719)
			(xy 372.076342 -271.142908) (xy 372.067582 -271.119092) (xy 372.055644 -271.085056) (xy 371.75948 -271.085056)
			(xy 371.747542 -271.119092) (xy 371.738782 -271.142908) (xy 371.714974 -271.187719) (xy 371.684548 -271.228329)
			(xy 371.64823 -271.263768) (xy 371.606888 -271.29319) (xy 371.561507 -271.315894) (xy 371.513171 -271.331338)
			(xy 371.463034 -271.339153) (xy 371.41229 -271.339153) (xy 371.362153 -271.331338) (xy 371.313817 -271.315894)
			(xy 371.268436 -271.29319) (xy 371.227094 -271.263768) (xy 371.190776 -271.228329) (xy 371.16035 -271.187719)
			(xy 371.136542 -271.142908) (xy 371.127782 -271.119092) (xy 371.115844 -271.085056) (xy 370.819934 -271.085056)
			(xy 370.807996 -271.119092) (xy 370.799236 -271.142908) (xy 370.775428 -271.187719) (xy 370.745002 -271.228329)
			(xy 370.708684 -271.263768) (xy 370.667342 -271.29319) (xy 370.621961 -271.315894) (xy 370.573625 -271.331338)
			(xy 370.523488 -271.339153) (xy 370.472744 -271.339153) (xy 370.422607 -271.331338) (xy 370.374271 -271.315894)
			(xy 370.32889 -271.29319) (xy 370.287548 -271.263768) (xy 370.25123 -271.228329) (xy 370.220804 -271.187719)
			(xy 370.196996 -271.142908) (xy 370.188236 -271.119092) (xy 370.176298 -271.085056) (xy 369.87988 -271.085056)
			(xy 369.867942 -271.119092) (xy 369.859182 -271.142908) (xy 369.835374 -271.187719) (xy 369.804948 -271.228329)
			(xy 369.76863 -271.263768) (xy 369.727288 -271.29319) (xy 369.681907 -271.315894) (xy 369.633571 -271.331338)
			(xy 369.583434 -271.339153) (xy 369.53269 -271.339153) (xy 369.482553 -271.331338) (xy 369.434217 -271.315894)
			(xy 369.388836 -271.29319) (xy 369.347494 -271.263768) (xy 369.311176 -271.228329) (xy 369.28075 -271.187719)
			(xy 369.256942 -271.142908) (xy 369.248182 -271.119092) (xy 369.236244 -271.085056) (xy 368.94008 -271.085056)
			(xy 368.928142 -271.119092) (xy 368.919389 -271.142911) (xy 368.895588 -271.187729) (xy 368.865166 -271.228343)
			(xy 368.828848 -271.263784) (xy 368.787503 -271.293205) (xy 368.742118 -271.315902) (xy 368.693776 -271.331335)
			(xy 368.643635 -271.339134) (xy 368.618262 -271.339564) (xy 368.593693 -271.339103) (xy 368.545105 -271.331775)
			(xy 368.498151 -271.317288) (xy 368.45388 -271.295966) (xy 368.413281 -271.268285) (xy 368.37726 -271.234863)
			(xy 368.346622 -271.196447) (xy 368.32205 -271.153894) (xy 368.304094 -271.108154) (xy 368.298222 -271.084294)
			(xy 368.274442 -271.085634) (xy 368.227099 -271.08048) (xy 368.181545 -271.066599) (xy 368.139373 -271.044475)
			(xy 368.10206 -271.014884) (xy 368.070911 -270.978861) (xy 368.058446 -270.958564) (xy 367.310924 -270.958564)
			(xy 366.474248 -270.121888) (xy 366.474248 -269.720568) (xy 366.451102 -269.701719) (xy 366.409744 -269.658676)
			(xy 366.374756 -269.610313) (xy 366.346816 -269.557564) (xy 366.326463 -269.501449) (xy 366.314092 -269.443054)
			(xy 366.309941 -269.383506) (xy 366.31409 -269.323959) (xy 366.32646 -269.265563) (xy 366.346811 -269.209447)
			(xy 366.37475 -269.156697) (xy 366.409736 -269.108333) (xy 366.451093 -269.06529) (xy 366.474248 -269.046452)
			(xy 366.474248 -268.092936) (xy 366.451104 -268.074087) (xy 366.40975 -268.031045) (xy 366.374767 -267.982683)
			(xy 366.346831 -267.929936) (xy 366.326482 -267.873823) (xy 366.314114 -267.81543) (xy 366.309966 -267.755886)
			(xy 366.314118 -267.696343) (xy 366.32649 -267.63795) (xy 366.346842 -267.581839) (xy 366.374781 -267.529094)
			(xy 366.409768 -267.480734) (xy 366.451124 -267.437695) (xy 366.474248 -267.41882) (xy 366.474248 -266.323064)
			(xy 366.459233 -266.301782) (xy 366.435411 -266.255467) (xy 366.419196 -266.205973) (xy 366.410993 -266.154541)
			(xy 366.410494 -266.1285) (xy 366.410972 -266.102457) (xy 366.419161 -266.051019) (xy 366.435382 -266.001523)
			(xy 366.459225 -265.955215) (xy 366.474248 -265.933936) (xy 366.474248 -264.694924) (xy 366.459236 -264.673641)
			(xy 366.43542 -264.627325) (xy 366.41921 -264.577832) (xy 366.411014 -264.5264) (xy 366.410494 -264.50036)
			(xy 366.410967 -264.474315) (xy 366.419148 -264.422873) (xy 366.435361 -264.373372) (xy 366.459199 -264.327058)
			(xy 366.474248 -264.305796) (xy 366.474248 -263.647174) (xy 366.452605 -263.63174) (xy 366.414147 -263.595044)
			(xy 366.382102 -263.552633) (xy 366.357308 -263.505614) (xy 366.340411 -263.455216) (xy 366.331852 -263.402753)
			(xy 366.331856 -263.349597) (xy 366.340423 -263.297136) (xy 366.357327 -263.24674) (xy 366.382129 -263.199725)
			(xy 366.41418 -263.157319) (xy 366.452643 -263.120629) (xy 366.474248 -263.105138) (xy 366.474248 -260.90118)
			(xy 366.345978 -260.772656) (xy 364.725712 -260.772656) (xy 364.214156 -261.284212) (xy 364.214156 -264.356088)
			(xy 364.218728 -264.365994) (xy 364.227798 -264.38722) (xy 364.240576 -264.431575) (xy 364.247032 -264.477281)
			(xy 364.24743 -264.50036) (xy 364.247058 -264.523442) (xy 364.240618 -264.569153) (xy 364.227817 -264.613506)
			(xy 364.218728 -264.634726) (xy 364.214156 -264.644632) (xy 364.214156 -265.983974) (xy 364.218728 -265.99388)
			(xy 364.227799 -266.015106) (xy 364.240579 -266.059461) (xy 364.247036 -266.105166) (xy 364.24743 -266.128246)
			(xy 364.247059 -266.151328) (xy 364.24062 -266.19704) (xy 364.227821 -266.241393) (xy 364.218728 -266.262612)
			(xy 364.214156 -266.272518) (xy 364.214156 -267.611606) (xy 364.218728 -267.621512) (xy 364.227797 -267.642738)
			(xy 364.240573 -267.687094) (xy 364.247025 -267.732799) (xy 364.24743 -267.755878) (xy 364.247057 -267.77896)
			(xy 364.240614 -267.82467) (xy 364.227811 -267.869021) (xy 364.218728 -267.890244) (xy 364.214156 -267.90015)
			(xy 364.214156 -269.239238) (xy 364.218728 -269.249144) (xy 364.227802 -269.270369) (xy 364.240586 -269.314724)
			(xy 364.247048 -269.36043) (xy 364.24743 -269.38351) (xy 364.247061 -269.406593) (xy 364.240628 -269.452306)
			(xy 364.227833 -269.496662) (xy 364.218728 -269.517876) (xy 364.214156 -269.527782) (xy 364.214156 -270.867124)
			(xy 364.218728 -270.87703) (xy 364.227796 -270.898256) (xy 364.240569 -270.942612) (xy 364.247019 -270.988317)
			(xy 364.24743 -271.011396) (xy 364.247062 -271.034479) (xy 364.240631 -271.080193) (xy 364.227837 -271.12455)
			(xy 364.218728 -271.145762) (xy 364.214156 -271.155668) (xy 364.214156 -272.49501) (xy 364.218728 -272.504916)
			(xy 364.227797 -272.526142) (xy 364.240572 -272.570498) (xy 364.247024 -272.616203) (xy 364.24743 -272.639282)
			(xy 364.247056 -272.662363) (xy 364.240613 -272.708074) (xy 364.22781 -272.752425) (xy 364.218728 -272.773648)
			(xy 364.214156 -272.783554) (xy 364.214156 -274.12188) (xy 364.218728 -274.13204) (xy 364.227893 -274.15333)
			(xy 364.240808 -274.197846) (xy 364.247316 -274.243738) (xy 364.247684 -274.266914) (xy 364.24728 -274.290087)
			(xy 364.240759 -274.335972) (xy 364.227864 -274.380488) (xy 364.218728 -274.401788) (xy 364.214156 -274.411948)
			(xy 364.214156 -275.750528) (xy 364.218728 -275.760434) (xy 364.227796 -275.781661) (xy 364.240568 -275.826016)
			(xy 364.247018 -275.871721) (xy 364.24743 -275.8948) (xy 364.247062 -275.917883) (xy 364.24063 -275.963597)
			(xy 364.227836 -276.007953) (xy 364.218728 -276.029166) (xy 364.214156 -276.039072) (xy 364.214156 -277.377144)
			(xy 364.218728 -277.387304) (xy 364.227889 -277.408595) (xy 364.240795 -277.453111) (xy 364.247294 -277.499003)
			(xy 364.247684 -277.522178) (xy 364.247282 -277.545351) (xy 364.240767 -277.591238) (xy 364.227875 -277.635756)
			(xy 364.218728 -277.657052) (xy 364.214156 -277.667212) (xy 364.214156 -279.006046) (xy 364.218728 -279.015952)
			(xy 364.22965 -279.043638) (xy 364.231174 -279.04821) (xy 364.62589 -279.73655) (xy 364.629954 -279.740868)
			(xy 364.646567 -279.759445) (xy 364.674556 -279.800676) (xy 364.695985 -279.845667) (xy 364.703614 -279.869392)
			(xy 364.705392 -279.87498) (xy 365.088424 -280.543254) (xy 365.092996 -280.547826) (xy 365.112339 -280.568331)
			(xy 365.144425 -280.614673) (xy 365.168148 -280.665802) (xy 365.176054 -280.69286) (xy 365.177832 -280.69921)
			(xy 365.551212 -281.350212) (xy 365.556546 -281.355292) (xy 365.57311 -281.371794) (xy 365.601873 -281.408656)
			(xy 365.625116 -281.449224) (xy 365.642372 -281.492679) (xy 365.64824 -281.515312) (xy 365.650018 -281.522424)
			(xy 366.014508 -282.158186) (xy 366.02035 -282.16352) (xy 366.038854 -282.181025) (xy 366.070754 -282.220733)
			(xy 366.096129 -282.264897) (xy 366.114368 -282.312454) (xy 366.120172 -282.337256) (xy 366.121696 -282.34513)
			(xy 366.478312 -282.966922) (xy 366.484916 -282.972764) (xy 366.505095 -282.991111) (xy 366.539664 -283.033289)
			(xy 366.566778 -283.080606) (xy 366.58569 -283.131757) (xy 366.591342 -283.158438) (xy 366.59312 -283.16682)
			(xy 366.94237 -283.77642) (xy 366.949482 -283.782262) (xy 366.966963 -283.797444) (xy 366.997906 -283.831884)
			(xy 367.023711 -283.870325) (xy 367.043867 -283.912007) (xy 367.057974 -283.956105) (xy 367.062258 -283.978858)
			(xy 367.063782 -283.987748) (xy 367.40465 -284.582108) (xy 367.41227 -284.588204) (xy 367.431947 -284.604242)
			(xy 367.466607 -284.641329) (xy 367.495182 -284.683285) (xy 367.516999 -284.729119) (xy 367.531543 -284.777753)
			(xy 367.53546 -284.802834) (xy 367.53673 -284.81274) (xy 367.556676 -284.847538) (xy 368.758724 -284.847538)
			(xy 368.759232 -284.821631) (xy 368.767338 -284.770454) (xy 368.78335 -284.721175) (xy 368.806873 -284.675008)
			(xy 368.837329 -284.633089) (xy 368.873967 -284.596451) (xy 368.915886 -284.565995) (xy 368.962053 -284.542472)
			(xy 369.011332 -284.52646) (xy 369.062509 -284.518354) (xy 369.114323 -284.518354) (xy 369.1655 -284.52646)
			(xy 369.214779 -284.542472) (xy 369.260946 -284.565995) (xy 369.302865 -284.596451) (xy 369.339503 -284.633089)
			(xy 369.369959 -284.675008) (xy 369.393482 -284.721175) (xy 369.409494 -284.770454) (xy 369.4176 -284.821631)
			(xy 369.418108 -284.847538) (xy 370.638324 -284.847538) (xy 370.638832 -284.821631) (xy 370.646938 -284.770454)
			(xy 370.66295 -284.721175) (xy 370.686473 -284.675008) (xy 370.716929 -284.633089) (xy 370.753567 -284.596451)
			(xy 370.795486 -284.565995) (xy 370.841653 -284.542472) (xy 370.890932 -284.52646) (xy 370.942109 -284.518354)
			(xy 370.993923 -284.518354) (xy 371.0451 -284.52646) (xy 371.094379 -284.542472) (xy 371.140546 -284.565995)
			(xy 371.182465 -284.596451) (xy 371.219103 -284.633089) (xy 371.249559 -284.675008) (xy 371.273082 -284.721175)
			(xy 371.289094 -284.770454) (xy 371.2972 -284.821631) (xy 371.297708 -284.847538) (xy 372.517924 -284.847538)
			(xy 372.518432 -284.821631) (xy 372.526538 -284.770454) (xy 372.54255 -284.721175) (xy 372.566073 -284.675008)
			(xy 372.596529 -284.633089) (xy 372.633167 -284.596451) (xy 372.675086 -284.565995) (xy 372.721253 -284.542472)
			(xy 372.770532 -284.52646) (xy 372.821709 -284.518354) (xy 372.873523 -284.518354) (xy 372.9247 -284.52646)
			(xy 372.973979 -284.542472) (xy 373.020146 -284.565995) (xy 373.062065 -284.596451) (xy 373.098703 -284.633089)
			(xy 373.129159 -284.675008) (xy 373.152682 -284.721175) (xy 373.168694 -284.770454) (xy 373.1768 -284.821631)
			(xy 373.177308 -284.847538) (xy 374.397524 -284.847538) (xy 374.398032 -284.821631) (xy 374.406138 -284.770454)
			(xy 374.42215 -284.721175) (xy 374.445673 -284.675008) (xy 374.476129 -284.633089) (xy 374.512767 -284.596451)
			(xy 374.554686 -284.565995) (xy 374.600853 -284.542472) (xy 374.650132 -284.52646) (xy 374.701309 -284.518354)
			(xy 374.753123 -284.518354) (xy 374.8043 -284.52646) (xy 374.853579 -284.542472) (xy 374.899746 -284.565995)
			(xy 374.941665 -284.596451) (xy 374.978303 -284.633089) (xy 375.008759 -284.675008) (xy 375.032282 -284.721175)
			(xy 375.048294 -284.770454) (xy 375.0564 -284.821631) (xy 375.056908 -284.847538) (xy 376.277124 -284.847538)
			(xy 376.277632 -284.821631) (xy 376.285738 -284.770454) (xy 376.30175 -284.721175) (xy 376.325273 -284.675008)
			(xy 376.355729 -284.633089) (xy 376.392367 -284.596451) (xy 376.434286 -284.565995) (xy 376.480453 -284.542472)
			(xy 376.529732 -284.52646) (xy 376.580909 -284.518354) (xy 376.632723 -284.518354) (xy 376.6839 -284.52646)
			(xy 376.733179 -284.542472) (xy 376.779346 -284.565995) (xy 376.821265 -284.596451) (xy 376.857903 -284.633089)
			(xy 376.888359 -284.675008) (xy 376.911882 -284.721175) (xy 376.927894 -284.770454) (xy 376.936 -284.821631)
			(xy 376.936508 -284.847538) (xy 378.156724 -284.847538) (xy 378.157232 -284.821631) (xy 378.165338 -284.770454)
			(xy 378.18135 -284.721175) (xy 378.204873 -284.675008) (xy 378.235329 -284.633089) (xy 378.271967 -284.596451)
			(xy 378.313886 -284.565995) (xy 378.360053 -284.542472) (xy 378.409332 -284.52646) (xy 378.460509 -284.518354)
			(xy 378.512323 -284.518354) (xy 378.5635 -284.52646) (xy 378.612779 -284.542472) (xy 378.658946 -284.565995)
			(xy 378.700865 -284.596451) (xy 378.737503 -284.633089) (xy 378.767959 -284.675008) (xy 378.791482 -284.721175)
			(xy 378.807494 -284.770454) (xy 378.8156 -284.821631) (xy 378.816108 -284.847538) (xy 380.036324 -284.847538)
			(xy 380.036832 -284.821631) (xy 380.044938 -284.770454) (xy 380.06095 -284.721175) (xy 380.084473 -284.675008)
			(xy 380.114929 -284.633089) (xy 380.151567 -284.596451) (xy 380.193486 -284.565995) (xy 380.239653 -284.542472)
			(xy 380.288932 -284.52646) (xy 380.340109 -284.518354) (xy 380.391923 -284.518354) (xy 380.4431 -284.52646)
			(xy 380.492379 -284.542472) (xy 380.538546 -284.565995) (xy 380.580465 -284.596451) (xy 380.617103 -284.633089)
			(xy 380.647559 -284.675008) (xy 380.671082 -284.721175) (xy 380.687094 -284.770454) (xy 380.6952 -284.821631)
			(xy 380.695708 -284.847538) (xy 380.695098 -284.875255) (xy 380.685785 -284.929901) (xy 380.677166 -284.95625)
			(xy 380.669292 -284.978348) (xy 380.87427 -285.333186) (xy 380.89713 -285.337504) (xy 380.921947 -285.342634)
			(xy 380.969689 -285.35963) (xy 381.014267 -285.383731) (xy 381.054634 -285.414369) (xy 381.089836 -285.450823)
			(xy 381.119046 -285.492235) (xy 381.141576 -285.537628) (xy 381.156894 -285.585934) (xy 381.16464 -285.636016)
			(xy 381.1651 -285.661354) (xy 381.164592 -285.687241) (xy 381.156493 -285.738379) (xy 381.140494 -285.787619)
			(xy 381.116988 -285.833751) (xy 381.086556 -285.875638) (xy 381.049946 -285.912248) (xy 381.008059 -285.94268)
			(xy 380.961927 -285.966186) (xy 380.912687 -285.982185) (xy 380.861549 -285.990284) (xy 380.809775 -285.990284)
			(xy 380.758637 -285.982185) (xy 380.709397 -285.966186) (xy 380.663265 -285.94268) (xy 380.621378 -285.912248)
			(xy 380.584768 -285.875638) (xy 380.554336 -285.833751) (xy 380.53083 -285.787619) (xy 380.514831 -285.738379)
			(xy 380.506732 -285.687241) (xy 380.506224 -285.661354) (xy 380.506766 -285.633646) (xy 380.515953 -285.579)
			(xy 380.524512 -285.552642) (xy 380.532386 -285.530544) (xy 380.327408 -285.175706) (xy 380.304548 -285.171388)
			(xy 380.279723 -285.166238) (xy 380.231943 -285.149282) (xy 380.187323 -285.125209) (xy 380.146916 -285.094586)
			(xy 380.111675 -285.058137) (xy 380.082431 -285.016721) (xy 380.059876 -284.971315) (xy 380.044539 -284.922991)
			(xy 380.036785 -284.872888) (xy 380.036324 -284.847538) (xy 378.816108 -284.847538) (xy 378.815498 -284.875255)
			(xy 378.806185 -284.929901) (xy 378.797566 -284.95625) (xy 378.789692 -284.978348) (xy 378.99467 -285.333186)
			(xy 379.01753 -285.337504) (xy 379.042347 -285.342634) (xy 379.090089 -285.35963) (xy 379.134667 -285.383731)
			(xy 379.175034 -285.414369) (xy 379.210236 -285.450823) (xy 379.239446 -285.492235) (xy 379.261976 -285.537628)
			(xy 379.277294 -285.585934) (xy 379.28504 -285.636016) (xy 379.2855 -285.661354) (xy 379.284992 -285.687241)
			(xy 379.276893 -285.738379) (xy 379.260894 -285.787619) (xy 379.237388 -285.833751) (xy 379.206956 -285.875638)
			(xy 379.170346 -285.912248) (xy 379.128459 -285.94268) (xy 379.082327 -285.966186) (xy 379.033087 -285.982185)
			(xy 378.981949 -285.990284) (xy 378.930175 -285.990284) (xy 378.879037 -285.982185) (xy 378.829797 -285.966186)
			(xy 378.783665 -285.94268) (xy 378.741778 -285.912248) (xy 378.705168 -285.875638) (xy 378.674736 -285.833751)
			(xy 378.65123 -285.787619) (xy 378.635231 -285.738379) (xy 378.627132 -285.687241) (xy 378.626624 -285.661354)
			(xy 378.627166 -285.633646) (xy 378.636353 -285.579) (xy 378.644912 -285.552642) (xy 378.652786 -285.530544)
			(xy 378.447808 -285.175706) (xy 378.424948 -285.171388) (xy 378.400123 -285.166238) (xy 378.352343 -285.149282)
			(xy 378.307723 -285.125209) (xy 378.267316 -285.094586) (xy 378.232075 -285.058137) (xy 378.202831 -285.016721)
			(xy 378.180276 -284.971315) (xy 378.164939 -284.922991) (xy 378.157185 -284.872888) (xy 378.156724 -284.847538)
			(xy 376.936508 -284.847538) (xy 376.935898 -284.875255) (xy 376.926585 -284.929901) (xy 376.917966 -284.95625)
			(xy 376.910092 -284.978348) (xy 377.11507 -285.333186) (xy 377.13793 -285.337504) (xy 377.162747 -285.342634)
			(xy 377.210489 -285.35963) (xy 377.255067 -285.383731) (xy 377.295434 -285.414369) (xy 377.330636 -285.450823)
			(xy 377.359846 -285.492235) (xy 377.382376 -285.537628) (xy 377.397694 -285.585934) (xy 377.40544 -285.636016)
			(xy 377.4059 -285.661354) (xy 377.405392 -285.687241) (xy 377.397293 -285.738379) (xy 377.381294 -285.787619)
			(xy 377.357788 -285.833751) (xy 377.327356 -285.875638) (xy 377.290746 -285.912248) (xy 377.248859 -285.94268)
			(xy 377.202727 -285.966186) (xy 377.153487 -285.982185) (xy 377.102349 -285.990284) (xy 377.050575 -285.990284)
			(xy 376.999437 -285.982185) (xy 376.950197 -285.966186) (xy 376.904065 -285.94268) (xy 376.862178 -285.912248)
			(xy 376.825568 -285.875638) (xy 376.795136 -285.833751) (xy 376.77163 -285.787619) (xy 376.755631 -285.738379)
			(xy 376.747532 -285.687241) (xy 376.747024 -285.661354) (xy 376.747566 -285.633646) (xy 376.756753 -285.579)
			(xy 376.765312 -285.552642) (xy 376.773186 -285.530544) (xy 376.568208 -285.175706) (xy 376.545348 -285.171388)
			(xy 376.520523 -285.166238) (xy 376.472743 -285.149282) (xy 376.428123 -285.125209) (xy 376.387716 -285.094586)
			(xy 376.352475 -285.058137) (xy 376.323231 -285.016721) (xy 376.300676 -284.971315) (xy 376.285339 -284.922991)
			(xy 376.277585 -284.872888) (xy 376.277124 -284.847538) (xy 375.056908 -284.847538) (xy 375.056298 -284.875255)
			(xy 375.046985 -284.929901) (xy 375.038366 -284.95625) (xy 375.030492 -284.978348) (xy 375.23547 -285.333186)
			(xy 375.25833 -285.337504) (xy 375.283147 -285.342634) (xy 375.330889 -285.35963) (xy 375.375467 -285.383731)
			(xy 375.415834 -285.414369) (xy 375.451036 -285.450823) (xy 375.480246 -285.492235) (xy 375.502776 -285.537628)
			(xy 375.518094 -285.585934) (xy 375.52584 -285.636016) (xy 375.5263 -285.661354) (xy 375.525792 -285.687241)
			(xy 375.517693 -285.738379) (xy 375.501694 -285.787619) (xy 375.478188 -285.833751) (xy 375.447756 -285.875638)
			(xy 375.411146 -285.912248) (xy 375.369259 -285.94268) (xy 375.323127 -285.966186) (xy 375.273887 -285.982185)
			(xy 375.222749 -285.990284) (xy 375.170975 -285.990284) (xy 375.119837 -285.982185) (xy 375.070597 -285.966186)
			(xy 375.024465 -285.94268) (xy 374.982578 -285.912248) (xy 374.945968 -285.875638) (xy 374.915536 -285.833751)
			(xy 374.89203 -285.787619) (xy 374.876031 -285.738379) (xy 374.867932 -285.687241) (xy 374.867424 -285.661354)
			(xy 374.867966 -285.633646) (xy 374.877153 -285.579) (xy 374.885712 -285.552642) (xy 374.893586 -285.530544)
			(xy 374.688608 -285.175706) (xy 374.665748 -285.171388) (xy 374.640923 -285.166238) (xy 374.593143 -285.149282)
			(xy 374.548523 -285.125209) (xy 374.508116 -285.094586) (xy 374.472875 -285.058137) (xy 374.443631 -285.016721)
			(xy 374.421076 -284.971315) (xy 374.405739 -284.922991) (xy 374.397985 -284.872888) (xy 374.397524 -284.847538)
			(xy 373.177308 -284.847538) (xy 373.176698 -284.875255) (xy 373.167385 -284.929901) (xy 373.158766 -284.95625)
			(xy 373.150892 -284.978348) (xy 373.35587 -285.333186) (xy 373.37873 -285.337504) (xy 373.403547 -285.342634)
			(xy 373.451289 -285.35963) (xy 373.495867 -285.383731) (xy 373.536234 -285.414369) (xy 373.571436 -285.450823)
			(xy 373.600646 -285.492235) (xy 373.623176 -285.537628) (xy 373.638494 -285.585934) (xy 373.64624 -285.636016)
			(xy 373.6467 -285.661354) (xy 373.646192 -285.687241) (xy 373.638093 -285.738379) (xy 373.622094 -285.787619)
			(xy 373.598588 -285.833751) (xy 373.568156 -285.875638) (xy 373.531546 -285.912248) (xy 373.489659 -285.94268)
			(xy 373.443527 -285.966186) (xy 373.394287 -285.982185) (xy 373.343149 -285.990284) (xy 373.291375 -285.990284)
			(xy 373.240237 -285.982185) (xy 373.190997 -285.966186) (xy 373.144865 -285.94268) (xy 373.102978 -285.912248)
			(xy 373.066368 -285.875638) (xy 373.035936 -285.833751) (xy 373.01243 -285.787619) (xy 372.996431 -285.738379)
			(xy 372.988332 -285.687241) (xy 372.987824 -285.661354) (xy 372.988366 -285.633646) (xy 372.997553 -285.579)
			(xy 373.006112 -285.552642) (xy 373.013986 -285.530544) (xy 372.809008 -285.175706) (xy 372.786148 -285.171388)
			(xy 372.761323 -285.166238) (xy 372.713543 -285.149282) (xy 372.668923 -285.125209) (xy 372.628516 -285.094586)
			(xy 372.593275 -285.058137) (xy 372.564031 -285.016721) (xy 372.541476 -284.971315) (xy 372.526139 -284.922991)
			(xy 372.518385 -284.872888) (xy 372.517924 -284.847538) (xy 371.297708 -284.847538) (xy 371.297098 -284.875255)
			(xy 371.287785 -284.929901) (xy 371.279166 -284.95625) (xy 371.271292 -284.978348) (xy 371.47627 -285.333186)
			(xy 371.49913 -285.337504) (xy 371.523947 -285.342634) (xy 371.571689 -285.35963) (xy 371.616267 -285.383731)
			(xy 371.656634 -285.414369) (xy 371.691836 -285.450823) (xy 371.721046 -285.492235) (xy 371.743576 -285.537628)
			(xy 371.758894 -285.585934) (xy 371.76664 -285.636016) (xy 371.7671 -285.661354) (xy 371.766592 -285.687241)
			(xy 371.758493 -285.738379) (xy 371.742494 -285.787619) (xy 371.718988 -285.833751) (xy 371.688556 -285.875638)
			(xy 371.651946 -285.912248) (xy 371.610059 -285.94268) (xy 371.563927 -285.966186) (xy 371.514687 -285.982185)
			(xy 371.463549 -285.990284) (xy 371.411775 -285.990284) (xy 371.360637 -285.982185) (xy 371.311397 -285.966186)
			(xy 371.265265 -285.94268) (xy 371.223378 -285.912248) (xy 371.186768 -285.875638) (xy 371.156336 -285.833751)
			(xy 371.13283 -285.787619) (xy 371.116831 -285.738379) (xy 371.108732 -285.687241) (xy 371.108224 -285.661354)
			(xy 371.108766 -285.633646) (xy 371.117953 -285.579) (xy 371.126512 -285.552642) (xy 371.134386 -285.530544)
			(xy 370.929408 -285.175706) (xy 370.906548 -285.171388) (xy 370.881723 -285.166238) (xy 370.833943 -285.149282)
			(xy 370.789323 -285.125209) (xy 370.748916 -285.094586) (xy 370.713675 -285.058137) (xy 370.684431 -285.016721)
			(xy 370.661876 -284.971315) (xy 370.646539 -284.922991) (xy 370.638785 -284.872888) (xy 370.638324 -284.847538)
			(xy 369.418108 -284.847538) (xy 369.417498 -284.875255) (xy 369.408185 -284.929901) (xy 369.399566 -284.95625)
			(xy 369.391692 -284.978348) (xy 369.59667 -285.333186) (xy 369.61953 -285.337504) (xy 369.644347 -285.342634)
			(xy 369.692089 -285.35963) (xy 369.736667 -285.383731) (xy 369.777034 -285.414369) (xy 369.812236 -285.450823)
			(xy 369.841446 -285.492235) (xy 369.863976 -285.537628) (xy 369.879294 -285.585934) (xy 369.88704 -285.636016)
			(xy 369.8875 -285.661354) (xy 369.886992 -285.687241) (xy 369.878893 -285.738379) (xy 369.862894 -285.787619)
			(xy 369.839388 -285.833751) (xy 369.808956 -285.875638) (xy 369.772346 -285.912248) (xy 369.730459 -285.94268)
			(xy 369.684327 -285.966186) (xy 369.635087 -285.982185) (xy 369.583949 -285.990284) (xy 369.532175 -285.990284)
			(xy 369.481037 -285.982185) (xy 369.431797 -285.966186) (xy 369.385665 -285.94268) (xy 369.343778 -285.912248)
			(xy 369.307168 -285.875638) (xy 369.276736 -285.833751) (xy 369.25323 -285.787619) (xy 369.237231 -285.738379)
			(xy 369.229132 -285.687241) (xy 369.228624 -285.661354) (xy 369.229166 -285.633646) (xy 369.238353 -285.579)
			(xy 369.246912 -285.552642) (xy 369.254786 -285.530544) (xy 369.049808 -285.175706) (xy 369.026948 -285.171388)
			(xy 369.002123 -285.166238) (xy 368.954343 -285.149282) (xy 368.909723 -285.125209) (xy 368.869316 -285.094586)
			(xy 368.834075 -285.058137) (xy 368.804831 -285.016721) (xy 368.782276 -284.971315) (xy 368.766939 -284.922991)
			(xy 368.759185 -284.872888) (xy 368.758724 -284.847538) (xy 367.556676 -284.847538) (xy 367.868962 -285.392368)
			(xy 367.877344 -285.398464) (xy 367.898162 -285.414928) (xy 367.93476 -285.453362) (xy 367.964736 -285.497158)
			(xy 367.987319 -285.545185) (xy 368.001926 -285.596207) (xy 368.005614 -285.622492) (xy 368.006884 -285.632652)
			(xy 368.11839 -285.827216) (xy 368.126441 -285.840195) (xy 368.148786 -285.860999) (xy 368.176271 -285.874289)
			(xy 368.206453 -285.878884) (xy 368.236648 -285.874376) (xy 368.264172 -285.861164) (xy 368.286576 -285.840425)
			(xy 368.294666 -285.82747) (xy 368.314986 -285.792164) (xy 368.307112 -285.77032) (xy 368.298534 -285.743901)
			(xy 368.289339 -285.689126) (xy 368.288824 -285.661354) (xy 368.289332 -285.635467) (xy 368.297431 -285.584329)
			(xy 368.31343 -285.535089) (xy 368.336936 -285.488957) (xy 368.367368 -285.44707) (xy 368.403978 -285.41046)
			(xy 368.445865 -285.380028) (xy 368.491997 -285.356522) (xy 368.541237 -285.340523) (xy 368.592375 -285.332424)
			(xy 368.644149 -285.332424) (xy 368.695287 -285.340523) (xy 368.744527 -285.356522) (xy 368.790659 -285.380028)
			(xy 368.832546 -285.41046) (xy 368.869156 -285.44707) (xy 368.899588 -285.488957) (xy 368.923094 -285.535089)
			(xy 368.939093 -285.584329) (xy 368.947192 -285.635467) (xy 368.9477 -285.661354) (xy 368.947239 -285.686692)
			(xy 368.939492 -285.736772) (xy 368.924173 -285.785078) (xy 368.901644 -285.83047) (xy 368.872433 -285.87188)
			(xy 368.837231 -285.908334) (xy 368.796865 -285.938971) (xy 368.752286 -285.963071) (xy 368.704545 -285.980066)
			(xy 368.67973 -285.985204) (xy 368.65687 -285.989522) (xy 368.451892 -286.344614) (xy 368.459766 -286.366458)
			(xy 368.465943 -286.385017) (xy 368.474352 -286.423219) (xy 368.47653 -286.442658) (xy 368.477546 -286.45358)
			(xy 368.490082 -286.475424) (xy 369.698524 -286.475424) (xy 369.699048 -286.45008) (xy 369.706816 -286.399991)
			(xy 369.722159 -286.351681) (xy 369.744715 -286.306288) (xy 369.773951 -286.264882) (xy 369.80918 -286.228438)
			(xy 369.849572 -286.197814) (xy 369.894174 -286.173733) (xy 369.941936 -286.156761) (xy 369.966748 -286.151574)
			(xy 369.989608 -286.147256) (xy 370.194586 -285.792164) (xy 370.186712 -285.77032) (xy 370.178138 -285.7439)
			(xy 370.168938 -285.689126) (xy 370.168424 -285.661354) (xy 370.168932 -285.635467) (xy 370.177031 -285.584329)
			(xy 370.19303 -285.535089) (xy 370.216536 -285.488957) (xy 370.246968 -285.44707) (xy 370.283578 -285.41046)
			(xy 370.325465 -285.380028) (xy 370.371597 -285.356522) (xy 370.420837 -285.340523) (xy 370.471975 -285.332424)
			(xy 370.523749 -285.332424) (xy 370.574887 -285.340523) (xy 370.624127 -285.356522) (xy 370.670259 -285.380028)
			(xy 370.712146 -285.41046) (xy 370.748756 -285.44707) (xy 370.779188 -285.488957) (xy 370.802694 -285.535089)
			(xy 370.818693 -285.584329) (xy 370.826792 -285.635467) (xy 370.8273 -285.661354) (xy 370.826866 -285.68669)
			(xy 370.819106 -285.736765) (xy 370.803776 -285.785062) (xy 370.781238 -285.830446) (xy 370.752022 -285.871848)
			(xy 370.716816 -285.908293) (xy 370.676449 -285.938922) (xy 370.631871 -285.963016) (xy 370.584131 -285.980006)
			(xy 370.55933 -285.985204) (xy 370.53647 -285.989522) (xy 370.331492 -286.344614) (xy 370.339366 -286.366458)
			(xy 370.348019 -286.392864) (xy 370.357334 -286.447642) (xy 370.357908 -286.475424) (xy 371.578124 -286.475424)
			(xy 371.578648 -286.45008) (xy 371.586416 -286.399991) (xy 371.601759 -286.351681) (xy 371.624315 -286.306288)
			(xy 371.653551 -286.264882) (xy 371.68878 -286.228438) (xy 371.729172 -286.197814) (xy 371.773774 -286.173733)
			(xy 371.821536 -286.156761) (xy 371.846348 -286.151574) (xy 371.869208 -286.147256) (xy 372.074186 -285.792164)
			(xy 372.066312 -285.77032) (xy 372.057738 -285.7439) (xy 372.048538 -285.689126) (xy 372.048024 -285.661354)
			(xy 372.048532 -285.635467) (xy 372.056631 -285.584329) (xy 372.07263 -285.535089) (xy 372.096136 -285.488957)
			(xy 372.126568 -285.44707) (xy 372.163178 -285.41046) (xy 372.205065 -285.380028) (xy 372.251197 -285.356522)
			(xy 372.300437 -285.340523) (xy 372.351575 -285.332424) (xy 372.403349 -285.332424) (xy 372.454487 -285.340523)
			(xy 372.503727 -285.356522) (xy 372.549859 -285.380028) (xy 372.591746 -285.41046) (xy 372.628356 -285.44707)
			(xy 372.658788 -285.488957) (xy 372.682294 -285.535089) (xy 372.698293 -285.584329) (xy 372.706392 -285.635467)
			(xy 372.7069 -285.661354) (xy 372.706466 -285.68669) (xy 372.698706 -285.736765) (xy 372.683376 -285.785062)
			(xy 372.660838 -285.830446) (xy 372.631622 -285.871848) (xy 372.596416 -285.908293) (xy 372.556049 -285.938922)
			(xy 372.511471 -285.963016) (xy 372.463731 -285.980006) (xy 372.43893 -285.985204) (xy 372.41607 -285.989522)
			(xy 372.211092 -286.344614) (xy 372.218966 -286.366458) (xy 372.227619 -286.392864) (xy 372.236934 -286.447642)
			(xy 372.237508 -286.475424) (xy 373.457724 -286.475424) (xy 373.458248 -286.45008) (xy 373.466016 -286.399991)
			(xy 373.481359 -286.351681) (xy 373.503915 -286.306288) (xy 373.533151 -286.264882) (xy 373.56838 -286.228438)
			(xy 373.608772 -286.197814) (xy 373.653374 -286.173733) (xy 373.701136 -286.156761) (xy 373.725948 -286.151574)
			(xy 373.748808 -286.147256) (xy 373.953786 -285.792164) (xy 373.945912 -285.77032) (xy 373.937338 -285.7439)
			(xy 373.928138 -285.689126) (xy 373.927624 -285.661354) (xy 373.928132 -285.635467) (xy 373.936231 -285.584329)
			(xy 373.95223 -285.535089) (xy 373.975736 -285.488957) (xy 374.006168 -285.44707) (xy 374.042778 -285.41046)
			(xy 374.084665 -285.380028) (xy 374.130797 -285.356522) (xy 374.180037 -285.340523) (xy 374.231175 -285.332424)
			(xy 374.282949 -285.332424) (xy 374.334087 -285.340523) (xy 374.383327 -285.356522) (xy 374.429459 -285.380028)
			(xy 374.471346 -285.41046) (xy 374.507956 -285.44707) (xy 374.538388 -285.488957) (xy 374.561894 -285.535089)
			(xy 374.577893 -285.584329) (xy 374.585992 -285.635467) (xy 374.5865 -285.661354) (xy 374.586066 -285.68669)
			(xy 374.578306 -285.736765) (xy 374.562976 -285.785062) (xy 374.540438 -285.830446) (xy 374.511222 -285.871848)
			(xy 374.476016 -285.908293) (xy 374.435649 -285.938922) (xy 374.391071 -285.963016) (xy 374.343331 -285.980006)
			(xy 374.31853 -285.985204) (xy 374.29567 -285.989522) (xy 374.090692 -286.344614) (xy 374.098566 -286.366458)
			(xy 374.107219 -286.392864) (xy 374.116534 -286.447642) (xy 374.117108 -286.475424) (xy 375.337324 -286.475424)
			(xy 375.337848 -286.45008) (xy 375.345616 -286.399991) (xy 375.360959 -286.351681) (xy 375.383515 -286.306288)
			(xy 375.412751 -286.264882) (xy 375.44798 -286.228438) (xy 375.488372 -286.197814) (xy 375.532974 -286.173733)
			(xy 375.580736 -286.156761) (xy 375.605548 -286.151574) (xy 375.628408 -286.147256) (xy 375.833386 -285.792164)
			(xy 375.825512 -285.77032) (xy 375.816938 -285.7439) (xy 375.807738 -285.689126) (xy 375.807224 -285.661354)
			(xy 375.807732 -285.635467) (xy 375.815831 -285.584329) (xy 375.83183 -285.535089) (xy 375.855336 -285.488957)
			(xy 375.885768 -285.44707) (xy 375.922378 -285.41046) (xy 375.964265 -285.380028) (xy 376.010397 -285.356522)
			(xy 376.059637 -285.340523) (xy 376.110775 -285.332424) (xy 376.162549 -285.332424) (xy 376.213687 -285.340523)
			(xy 376.262927 -285.356522) (xy 376.309059 -285.380028) (xy 376.350946 -285.41046) (xy 376.387556 -285.44707)
			(xy 376.417988 -285.488957) (xy 376.441494 -285.535089) (xy 376.457493 -285.584329) (xy 376.465592 -285.635467)
			(xy 376.4661 -285.661354) (xy 376.465666 -285.68669) (xy 376.457906 -285.736765) (xy 376.442576 -285.785062)
			(xy 376.420038 -285.830446) (xy 376.390822 -285.871848) (xy 376.355616 -285.908293) (xy 376.315249 -285.938922)
			(xy 376.270671 -285.963016) (xy 376.222931 -285.980006) (xy 376.19813 -285.985204) (xy 376.17527 -285.989522)
			(xy 375.970292 -286.344614) (xy 375.978166 -286.366458) (xy 375.986819 -286.392864) (xy 375.996134 -286.447642)
			(xy 375.996708 -286.475424) (xy 377.216924 -286.475424) (xy 377.217448 -286.45008) (xy 377.225216 -286.399991)
			(xy 377.240559 -286.351681) (xy 377.263115 -286.306288) (xy 377.292351 -286.264882) (xy 377.32758 -286.228438)
			(xy 377.367972 -286.197814) (xy 377.412574 -286.173733) (xy 377.460336 -286.156761) (xy 377.485148 -286.151574)
			(xy 377.508008 -286.147256) (xy 377.712986 -285.792164) (xy 377.705112 -285.77032) (xy 377.696538 -285.7439)
			(xy 377.687338 -285.689126) (xy 377.686824 -285.661354) (xy 377.687332 -285.635467) (xy 377.695431 -285.584329)
			(xy 377.71143 -285.535089) (xy 377.734936 -285.488957) (xy 377.765368 -285.44707) (xy 377.801978 -285.41046)
			(xy 377.843865 -285.380028) (xy 377.889997 -285.356522) (xy 377.939237 -285.340523) (xy 377.990375 -285.332424)
			(xy 378.042149 -285.332424) (xy 378.093287 -285.340523) (xy 378.142527 -285.356522) (xy 378.188659 -285.380028)
			(xy 378.230546 -285.41046) (xy 378.267156 -285.44707) (xy 378.297588 -285.488957) (xy 378.321094 -285.535089)
			(xy 378.337093 -285.584329) (xy 378.345192 -285.635467) (xy 378.3457 -285.661354) (xy 378.345266 -285.68669)
			(xy 378.337506 -285.736765) (xy 378.322176 -285.785062) (xy 378.299638 -285.830446) (xy 378.270422 -285.871848)
			(xy 378.235216 -285.908293) (xy 378.194849 -285.938922) (xy 378.150271 -285.963016) (xy 378.102531 -285.980006)
			(xy 378.07773 -285.985204) (xy 378.05487 -285.989522) (xy 377.849892 -286.344614) (xy 377.857766 -286.366458)
			(xy 377.866419 -286.392864) (xy 377.875734 -286.447642) (xy 377.876308 -286.475424) (xy 379.096524 -286.475424)
			(xy 379.097048 -286.45008) (xy 379.104816 -286.399991) (xy 379.120159 -286.351681) (xy 379.142715 -286.306288)
			(xy 379.171951 -286.264882) (xy 379.20718 -286.228438) (xy 379.247572 -286.197814) (xy 379.292174 -286.173733)
			(xy 379.339936 -286.156761) (xy 379.364748 -286.151574) (xy 379.387608 -286.147256) (xy 379.592586 -285.792164)
			(xy 379.584712 -285.77032) (xy 379.576138 -285.7439) (xy 379.566938 -285.689126) (xy 379.566424 -285.661354)
			(xy 379.566932 -285.635467) (xy 379.575031 -285.584329) (xy 379.59103 -285.535089) (xy 379.614536 -285.488957)
			(xy 379.644968 -285.44707) (xy 379.681578 -285.41046) (xy 379.723465 -285.380028) (xy 379.769597 -285.356522)
			(xy 379.818837 -285.340523) (xy 379.869975 -285.332424) (xy 379.921749 -285.332424) (xy 379.972887 -285.340523)
			(xy 380.022127 -285.356522) (xy 380.068259 -285.380028) (xy 380.110146 -285.41046) (xy 380.146756 -285.44707)
			(xy 380.177188 -285.488957) (xy 380.200694 -285.535089) (xy 380.216693 -285.584329) (xy 380.224792 -285.635467)
			(xy 380.2253 -285.661354) (xy 380.224866 -285.68669) (xy 380.217106 -285.736765) (xy 380.201776 -285.785062)
			(xy 380.179238 -285.830446) (xy 380.150022 -285.871848) (xy 380.114816 -285.908293) (xy 380.074449 -285.938922)
			(xy 380.029871 -285.963016) (xy 379.982131 -285.980006) (xy 379.95733 -285.985204) (xy 379.93447 -285.989522)
			(xy 379.729492 -286.344614) (xy 379.737366 -286.366458) (xy 379.746019 -286.392864) (xy 379.755334 -286.447642)
			(xy 379.755908 -286.475424) (xy 380.976124 -286.475424) (xy 380.976648 -286.45008) (xy 380.984416 -286.399991)
			(xy 380.999759 -286.351681) (xy 381.022315 -286.306288) (xy 381.051551 -286.264882) (xy 381.08678 -286.228438)
			(xy 381.127172 -286.197814) (xy 381.171774 -286.173733) (xy 381.219536 -286.156761) (xy 381.244348 -286.151574)
			(xy 381.267208 -286.147256) (xy 381.472186 -285.792164) (xy 381.464312 -285.77032) (xy 381.455738 -285.7439)
			(xy 381.446538 -285.689126) (xy 381.446024 -285.661354) (xy 381.446532 -285.635467) (xy 381.454631 -285.584329)
			(xy 381.47063 -285.535089) (xy 381.494136 -285.488957) (xy 381.524568 -285.44707) (xy 381.561178 -285.41046)
			(xy 381.603065 -285.380028) (xy 381.649197 -285.356522) (xy 381.698437 -285.340523) (xy 381.749575 -285.332424)
			(xy 381.801349 -285.332424) (xy 381.852487 -285.340523) (xy 381.901727 -285.356522) (xy 381.947859 -285.380028)
			(xy 381.989746 -285.41046) (xy 382.026356 -285.44707) (xy 382.056788 -285.488957) (xy 382.080294 -285.535089)
			(xy 382.096293 -285.584329) (xy 382.104392 -285.635467) (xy 382.1049 -285.661354) (xy 382.104466 -285.68669)
			(xy 382.096706 -285.736765) (xy 382.081376 -285.785062) (xy 382.058838 -285.830446) (xy 382.029622 -285.871848)
			(xy 381.994416 -285.908293) (xy 381.954049 -285.938922) (xy 381.909471 -285.963016) (xy 381.861731 -285.980006)
			(xy 381.83693 -285.985204) (xy 381.81407 -285.989522) (xy 381.609092 -286.344614) (xy 381.616966 -286.366458)
			(xy 381.625619 -286.392864) (xy 381.634934 -286.447642) (xy 381.635508 -286.475424) (xy 381.635 -286.501331)
			(xy 381.626894 -286.552508) (xy 381.610882 -286.601787) (xy 381.587359 -286.647954) (xy 381.556903 -286.689873)
			(xy 381.520265 -286.726511) (xy 381.478346 -286.756967) (xy 381.432179 -286.78049) (xy 381.3829 -286.796502)
			(xy 381.331723 -286.804608) (xy 381.279909 -286.804608) (xy 381.228732 -286.796502) (xy 381.179453 -286.78049)
			(xy 381.133286 -286.756967) (xy 381.091367 -286.726511) (xy 381.054729 -286.689873) (xy 381.024273 -286.647954)
			(xy 381.00075 -286.601787) (xy 380.984738 -286.552508) (xy 380.976632 -286.501331) (xy 380.976124 -286.475424)
			(xy 379.755908 -286.475424) (xy 379.7554 -286.501331) (xy 379.747294 -286.552508) (xy 379.731282 -286.601787)
			(xy 379.707759 -286.647954) (xy 379.677303 -286.689873) (xy 379.640665 -286.726511) (xy 379.598746 -286.756967)
			(xy 379.552579 -286.78049) (xy 379.5033 -286.796502) (xy 379.452123 -286.804608) (xy 379.400309 -286.804608)
			(xy 379.349132 -286.796502) (xy 379.299853 -286.78049) (xy 379.253686 -286.756967) (xy 379.211767 -286.726511)
			(xy 379.175129 -286.689873) (xy 379.144673 -286.647954) (xy 379.12115 -286.601787) (xy 379.105138 -286.552508)
			(xy 379.097032 -286.501331) (xy 379.096524 -286.475424) (xy 377.876308 -286.475424) (xy 377.8758 -286.501331)
			(xy 377.867694 -286.552508) (xy 377.851682 -286.601787) (xy 377.828159 -286.647954) (xy 377.797703 -286.689873)
			(xy 377.761065 -286.726511) (xy 377.719146 -286.756967) (xy 377.672979 -286.78049) (xy 377.6237 -286.796502)
			(xy 377.572523 -286.804608) (xy 377.520709 -286.804608) (xy 377.469532 -286.796502) (xy 377.420253 -286.78049)
			(xy 377.374086 -286.756967) (xy 377.332167 -286.726511) (xy 377.295529 -286.689873) (xy 377.265073 -286.647954)
			(xy 377.24155 -286.601787) (xy 377.225538 -286.552508) (xy 377.217432 -286.501331) (xy 377.216924 -286.475424)
			(xy 375.996708 -286.475424) (xy 375.9962 -286.501331) (xy 375.988094 -286.552508) (xy 375.972082 -286.601787)
			(xy 375.948559 -286.647954) (xy 375.918103 -286.689873) (xy 375.881465 -286.726511) (xy 375.839546 -286.756967)
			(xy 375.793379 -286.78049) (xy 375.7441 -286.796502) (xy 375.692923 -286.804608) (xy 375.641109 -286.804608)
			(xy 375.589932 -286.796502) (xy 375.540653 -286.78049) (xy 375.494486 -286.756967) (xy 375.452567 -286.726511)
			(xy 375.415929 -286.689873) (xy 375.385473 -286.647954) (xy 375.36195 -286.601787) (xy 375.345938 -286.552508)
			(xy 375.337832 -286.501331) (xy 375.337324 -286.475424) (xy 374.117108 -286.475424) (xy 374.1166 -286.501331)
			(xy 374.108494 -286.552508) (xy 374.092482 -286.601787) (xy 374.068959 -286.647954) (xy 374.038503 -286.689873)
			(xy 374.001865 -286.726511) (xy 373.959946 -286.756967) (xy 373.913779 -286.78049) (xy 373.8645 -286.796502)
			(xy 373.813323 -286.804608) (xy 373.761509 -286.804608) (xy 373.710332 -286.796502) (xy 373.661053 -286.78049)
			(xy 373.614886 -286.756967) (xy 373.572967 -286.726511) (xy 373.536329 -286.689873) (xy 373.505873 -286.647954)
			(xy 373.48235 -286.601787) (xy 373.466338 -286.552508) (xy 373.458232 -286.501331) (xy 373.457724 -286.475424)
			(xy 372.237508 -286.475424) (xy 372.237 -286.501331) (xy 372.228894 -286.552508) (xy 372.212882 -286.601787)
			(xy 372.189359 -286.647954) (xy 372.158903 -286.689873) (xy 372.122265 -286.726511) (xy 372.080346 -286.756967)
			(xy 372.034179 -286.78049) (xy 371.9849 -286.796502) (xy 371.933723 -286.804608) (xy 371.881909 -286.804608)
			(xy 371.830732 -286.796502) (xy 371.781453 -286.78049) (xy 371.735286 -286.756967) (xy 371.693367 -286.726511)
			(xy 371.656729 -286.689873) (xy 371.626273 -286.647954) (xy 371.60275 -286.601787) (xy 371.586738 -286.552508)
			(xy 371.578632 -286.501331) (xy 371.578124 -286.475424) (xy 370.357908 -286.475424) (xy 370.3574 -286.501331)
			(xy 370.349294 -286.552508) (xy 370.333282 -286.601787) (xy 370.309759 -286.647954) (xy 370.279303 -286.689873)
			(xy 370.242665 -286.726511) (xy 370.200746 -286.756967) (xy 370.154579 -286.78049) (xy 370.1053 -286.796502)
			(xy 370.054123 -286.804608) (xy 370.002309 -286.804608) (xy 369.951132 -286.796502) (xy 369.901853 -286.78049)
			(xy 369.855686 -286.756967) (xy 369.813767 -286.726511) (xy 369.777129 -286.689873) (xy 369.746673 -286.647954)
			(xy 369.72315 -286.601787) (xy 369.707138 -286.552508) (xy 369.699032 -286.501331) (xy 369.698524 -286.475424)
			(xy 368.490082 -286.475424) (xy 368.800126 -287.015682) (xy 368.809016 -287.022286) (xy 368.827925 -287.036281)
			(xy 368.861916 -287.068802) (xy 368.890913 -287.105845) (xy 368.914323 -287.14665) (xy 368.931663 -287.19038)
			(xy 368.942581 -287.236138) (xy 368.94516 -287.259522) (xy 368.946176 -287.270444) (xy 369.263168 -287.823402)
			(xy 369.27282 -287.830006) (xy 369.293333 -287.844408) (xy 369.330157 -287.878407) (xy 369.361406 -287.917591)
			(xy 369.386359 -287.961057) (xy 369.40444 -288.007801) (xy 369.415231 -288.056745) (xy 369.417346 -288.08172)
			(xy 369.418108 -288.093658) (xy 369.728242 -288.634424) (xy 369.738402 -288.641028) (xy 369.758297 -288.654557)
			(xy 369.794312 -288.686455) (xy 369.825311 -288.723247) (xy 369.850637 -288.764152) (xy 369.860576 -288.786062)
			(xy 369.874038 -288.816542) (xy 370.182394 -288.816542) (xy 370.195856 -288.786062) (xy 370.206452 -288.762832)
			(xy 370.233746 -288.719684) (xy 370.26737 -288.681264) (xy 370.306518 -288.648491) (xy 370.350254 -288.622149)
			(xy 370.397529 -288.60287) (xy 370.447213 -288.591115) (xy 370.498116 -288.587165) (xy 370.549019 -288.591115)
			(xy 370.598703 -288.60287) (xy 370.645978 -288.622149) (xy 370.689714 -288.648491) (xy 370.728862 -288.681264)
			(xy 370.762486 -288.719684) (xy 370.78978 -288.762832) (xy 370.800376 -288.786062) (xy 370.813838 -288.816542)
			(xy 370.976144 -288.816542) (xy 370.991386 -288.81604) (xy 371.020518 -288.807064) (xy 371.045704 -288.789892)
			(xy 371.064705 -288.766055) (xy 371.075828 -288.737673) (xy 371.078082 -288.707274) (xy 371.071269 -288.677562)
			(xy 371.064028 -288.664142) (xy 370.929662 -288.431224) (xy 370.906802 -288.426906) (xy 370.88196 -288.421763)
			(xy 370.83413 -288.40486) (xy 370.789458 -288.380821) (xy 370.749001 -288.350216) (xy 370.713717 -288.313767)
			(xy 370.684441 -288.272338) (xy 370.661866 -288.226909) (xy 370.646525 -288.178556) (xy 370.638781 -288.128421)
			(xy 370.638324 -288.103056) (xy 370.638832 -288.077149) (xy 370.646938 -288.025972) (xy 370.66295 -287.976693)
			(xy 370.686473 -287.930526) (xy 370.716929 -287.888607) (xy 370.753567 -287.851969) (xy 370.795486 -287.821513)
			(xy 370.841653 -287.79799) (xy 370.890932 -287.781978) (xy 370.942109 -287.773872) (xy 370.993923 -287.773872)
			(xy 371.0451 -287.781978) (xy 371.094379 -287.79799) (xy 371.140546 -287.821513) (xy 371.182465 -287.851969)
			(xy 371.219103 -287.888607) (xy 371.249559 -287.930526) (xy 371.273082 -287.976693) (xy 371.289094 -288.025972)
			(xy 371.2972 -288.077149) (xy 371.297708 -288.103056) (xy 371.297115 -288.130773) (xy 371.287787 -288.185419)
			(xy 371.279166 -288.211768) (xy 371.271546 -288.233866) (xy 371.476524 -288.588958) (xy 371.499384 -288.593276)
			(xy 371.525582 -288.598796) (xy 371.575864 -288.617174) (xy 371.622517 -288.643435) (xy 371.664315 -288.676887)
			(xy 371.700159 -288.716652) (xy 371.72911 -288.761684) (xy 371.740176 -288.786062) (xy 371.753638 -288.816542)
			(xy 372.061994 -288.816542) (xy 372.075456 -288.786062) (xy 372.086052 -288.762832) (xy 372.113346 -288.719684)
			(xy 372.14697 -288.681264) (xy 372.186118 -288.648491) (xy 372.229854 -288.622149) (xy 372.277129 -288.60287)
			(xy 372.326813 -288.591115) (xy 372.377716 -288.587165) (xy 372.428619 -288.591115) (xy 372.478303 -288.60287)
			(xy 372.525578 -288.622149) (xy 372.569314 -288.648491) (xy 372.608462 -288.681264) (xy 372.642086 -288.719684)
			(xy 372.66938 -288.762832) (xy 372.679976 -288.786062) (xy 372.693438 -288.816542) (xy 372.855744 -288.816542)
			(xy 372.870986 -288.81604) (xy 372.900118 -288.807064) (xy 372.925304 -288.789892) (xy 372.944305 -288.766055)
			(xy 372.955428 -288.737673) (xy 372.957682 -288.707274) (xy 372.950869 -288.677562) (xy 372.943628 -288.664142)
			(xy 372.809262 -288.431224) (xy 372.786402 -288.426906) (xy 372.76156 -288.421763) (xy 372.71373 -288.40486)
			(xy 372.669058 -288.380821) (xy 372.628601 -288.350216) (xy 372.593317 -288.313767) (xy 372.564041 -288.272338)
			(xy 372.541466 -288.226909) (xy 372.526125 -288.178556) (xy 372.518381 -288.128421) (xy 372.517924 -288.103056)
			(xy 372.518432 -288.077149) (xy 372.526538 -288.025972) (xy 372.54255 -287.976693) (xy 372.566073 -287.930526)
			(xy 372.596529 -287.888607) (xy 372.633167 -287.851969) (xy 372.675086 -287.821513) (xy 372.721253 -287.79799)
			(xy 372.770532 -287.781978) (xy 372.821709 -287.773872) (xy 372.873523 -287.773872) (xy 372.9247 -287.781978)
			(xy 372.973979 -287.79799) (xy 373.020146 -287.821513) (xy 373.062065 -287.851969) (xy 373.098703 -287.888607)
			(xy 373.129159 -287.930526) (xy 373.152682 -287.976693) (xy 373.168694 -288.025972) (xy 373.1768 -288.077149)
			(xy 373.177308 -288.103056) (xy 373.176715 -288.130773) (xy 373.167387 -288.185419) (xy 373.158766 -288.211768)
			(xy 373.151146 -288.233866) (xy 373.356124 -288.588958) (xy 373.378984 -288.593276) (xy 373.405182 -288.598796)
			(xy 373.455464 -288.617174) (xy 373.502117 -288.643435) (xy 373.543915 -288.676887) (xy 373.579759 -288.716652)
			(xy 373.60871 -288.761684) (xy 373.619776 -288.786062) (xy 373.633238 -288.816542) (xy 373.941594 -288.816542)
			(xy 373.955056 -288.786062) (xy 373.965652 -288.762832) (xy 373.992946 -288.719684) (xy 374.02657 -288.681264)
			(xy 374.065718 -288.648491) (xy 374.109454 -288.622149) (xy 374.156729 -288.60287) (xy 374.206413 -288.591115)
			(xy 374.257316 -288.587165) (xy 374.308219 -288.591115) (xy 374.357903 -288.60287) (xy 374.405178 -288.622149)
			(xy 374.448914 -288.648491) (xy 374.488062 -288.681264) (xy 374.521686 -288.719684) (xy 374.54898 -288.762832)
			(xy 374.559576 -288.786062) (xy 374.573038 -288.816542) (xy 374.735344 -288.816542) (xy 374.750586 -288.81604)
			(xy 374.779718 -288.807064) (xy 374.804904 -288.789892) (xy 374.823905 -288.766055) (xy 374.835028 -288.737673)
			(xy 374.837282 -288.707274) (xy 374.830469 -288.677562) (xy 374.823228 -288.664142) (xy 374.688862 -288.431224)
			(xy 374.666002 -288.426906) (xy 374.64116 -288.421763) (xy 374.59333 -288.40486) (xy 374.548658 -288.380821)
			(xy 374.508201 -288.350216) (xy 374.472917 -288.313767) (xy 374.443641 -288.272338) (xy 374.421066 -288.226909)
			(xy 374.405725 -288.178556) (xy 374.397981 -288.128421) (xy 374.397524 -288.103056) (xy 374.398032 -288.077149)
			(xy 374.406138 -288.025972) (xy 374.42215 -287.976693) (xy 374.445673 -287.930526) (xy 374.476129 -287.888607)
			(xy 374.512767 -287.851969) (xy 374.554686 -287.821513) (xy 374.600853 -287.79799) (xy 374.650132 -287.781978)
			(xy 374.701309 -287.773872) (xy 374.753123 -287.773872) (xy 374.8043 -287.781978) (xy 374.853579 -287.79799)
			(xy 374.899746 -287.821513) (xy 374.941665 -287.851969) (xy 374.978303 -287.888607) (xy 375.008759 -287.930526)
			(xy 375.032282 -287.976693) (xy 375.048294 -288.025972) (xy 375.0564 -288.077149) (xy 375.056908 -288.103056)
			(xy 375.056315 -288.130773) (xy 375.046987 -288.185419) (xy 375.038366 -288.211768) (xy 375.030746 -288.233866)
			(xy 375.235724 -288.588958) (xy 375.258584 -288.593276) (xy 375.284782 -288.598796) (xy 375.335064 -288.617174)
			(xy 375.381717 -288.643435) (xy 375.423515 -288.676887) (xy 375.459359 -288.716652) (xy 375.48831 -288.761684)
			(xy 375.499376 -288.786062) (xy 375.512838 -288.816542) (xy 375.821194 -288.816542) (xy 375.834656 -288.786062)
			(xy 375.845252 -288.762832) (xy 375.872546 -288.719684) (xy 375.90617 -288.681264) (xy 375.945318 -288.648491)
			(xy 375.989054 -288.622149) (xy 376.036329 -288.60287) (xy 376.086013 -288.591115) (xy 376.136916 -288.587165)
			(xy 376.187819 -288.591115) (xy 376.237503 -288.60287) (xy 376.284778 -288.622149) (xy 376.328514 -288.648491)
			(xy 376.367662 -288.681264) (xy 376.401286 -288.719684) (xy 376.42858 -288.762832) (xy 376.439176 -288.786062)
			(xy 376.452638 -288.816542) (xy 376.614944 -288.816542) (xy 376.630186 -288.81604) (xy 376.659318 -288.807064)
			(xy 376.684504 -288.789892) (xy 376.703505 -288.766055) (xy 376.714628 -288.737673) (xy 376.716882 -288.707274)
			(xy 376.710069 -288.677562) (xy 376.702828 -288.664142) (xy 376.568462 -288.431224) (xy 376.545602 -288.426906)
			(xy 376.52076 -288.421763) (xy 376.47293 -288.40486) (xy 376.428258 -288.380821) (xy 376.387801 -288.350216)
			(xy 376.352517 -288.313767) (xy 376.323241 -288.272338) (xy 376.300666 -288.226909) (xy 376.285325 -288.178556)
			(xy 376.277581 -288.128421) (xy 376.277124 -288.103056) (xy 376.277632 -288.077149) (xy 376.285738 -288.025972)
			(xy 376.30175 -287.976693) (xy 376.325273 -287.930526) (xy 376.355729 -287.888607) (xy 376.392367 -287.851969)
			(xy 376.434286 -287.821513) (xy 376.480453 -287.79799) (xy 376.529732 -287.781978) (xy 376.580909 -287.773872)
			(xy 376.632723 -287.773872) (xy 376.6839 -287.781978) (xy 376.733179 -287.79799) (xy 376.779346 -287.821513)
			(xy 376.821265 -287.851969) (xy 376.857903 -287.888607) (xy 376.888359 -287.930526) (xy 376.911882 -287.976693)
			(xy 376.927894 -288.025972) (xy 376.936 -288.077149) (xy 376.936508 -288.103056) (xy 376.935915 -288.130773)
			(xy 376.926587 -288.185419) (xy 376.917966 -288.211768) (xy 376.910346 -288.233866) (xy 377.115324 -288.588958)
			(xy 377.138184 -288.593276) (xy 377.164382 -288.598796) (xy 377.214664 -288.617174) (xy 377.261317 -288.643435)
			(xy 377.303115 -288.676887) (xy 377.338959 -288.716652) (xy 377.36791 -288.761684) (xy 377.378976 -288.786062)
			(xy 377.392438 -288.816542) (xy 377.700794 -288.816542) (xy 377.714256 -288.786062) (xy 377.724852 -288.762832)
			(xy 377.752146 -288.719684) (xy 377.78577 -288.681264) (xy 377.824918 -288.648491) (xy 377.868654 -288.622149)
			(xy 377.915929 -288.60287) (xy 377.965613 -288.591115) (xy 378.016516 -288.587165) (xy 378.067419 -288.591115)
			(xy 378.117103 -288.60287) (xy 378.164378 -288.622149) (xy 378.208114 -288.648491) (xy 378.247262 -288.681264)
			(xy 378.280886 -288.719684) (xy 378.30818 -288.762832) (xy 378.318776 -288.786062) (xy 378.332238 -288.816542)
			(xy 378.494544 -288.816542) (xy 378.509786 -288.81604) (xy 378.538918 -288.807064) (xy 378.564104 -288.789892)
			(xy 378.583105 -288.766055) (xy 378.594228 -288.737673) (xy 378.596482 -288.707274) (xy 378.589669 -288.677562)
			(xy 378.582428 -288.664142) (xy 378.448062 -288.431224) (xy 378.425202 -288.426906) (xy 378.40036 -288.421763)
			(xy 378.35253 -288.40486) (xy 378.307858 -288.380821) (xy 378.267401 -288.350216) (xy 378.232117 -288.313767)
			(xy 378.202841 -288.272338) (xy 378.180266 -288.226909) (xy 378.164925 -288.178556) (xy 378.157181 -288.128421)
			(xy 378.156724 -288.103056) (xy 378.157232 -288.077149) (xy 378.165338 -288.025972) (xy 378.18135 -287.976693)
			(xy 378.204873 -287.930526) (xy 378.235329 -287.888607) (xy 378.271967 -287.851969) (xy 378.313886 -287.821513)
			(xy 378.360053 -287.79799) (xy 378.409332 -287.781978) (xy 378.460509 -287.773872) (xy 378.512323 -287.773872)
			(xy 378.5635 -287.781978) (xy 378.612779 -287.79799) (xy 378.658946 -287.821513) (xy 378.700865 -287.851969)
			(xy 378.737503 -287.888607) (xy 378.767959 -287.930526) (xy 378.791482 -287.976693) (xy 378.807494 -288.025972)
			(xy 378.8156 -288.077149) (xy 378.816108 -288.103056) (xy 378.815515 -288.130773) (xy 378.806187 -288.185419)
			(xy 378.797566 -288.211768) (xy 378.789946 -288.233866) (xy 378.994924 -288.588958) (xy 379.017784 -288.593276)
			(xy 379.043982 -288.598796) (xy 379.094264 -288.617174) (xy 379.140917 -288.643435) (xy 379.182715 -288.676887)
			(xy 379.218559 -288.716652) (xy 379.24751 -288.761684) (xy 379.258576 -288.786062) (xy 379.272038 -288.816542)
			(xy 379.580394 -288.816542) (xy 379.593856 -288.786062) (xy 379.604452 -288.762832) (xy 379.631746 -288.719684)
			(xy 379.66537 -288.681264) (xy 379.704518 -288.648491) (xy 379.748254 -288.622149) (xy 379.795529 -288.60287)
			(xy 379.845213 -288.591115) (xy 379.896116 -288.587165) (xy 379.947019 -288.591115) (xy 379.996703 -288.60287)
			(xy 380.043978 -288.622149) (xy 380.087714 -288.648491) (xy 380.126862 -288.681264) (xy 380.160486 -288.719684)
			(xy 380.18778 -288.762832) (xy 380.198376 -288.786062) (xy 380.211838 -288.816542) (xy 380.374144 -288.816542)
			(xy 380.389386 -288.81604) (xy 380.418518 -288.807064) (xy 380.443704 -288.789892) (xy 380.462705 -288.766055)
			(xy 380.473828 -288.737673) (xy 380.476082 -288.707274) (xy 380.469269 -288.677562) (xy 380.462028 -288.664142)
			(xy 380.327662 -288.431224) (xy 380.304802 -288.426906) (xy 380.27996 -288.421763) (xy 380.23213 -288.40486)
			(xy 380.187458 -288.380821) (xy 380.147001 -288.350216) (xy 380.111717 -288.313767) (xy 380.082441 -288.272338)
			(xy 380.059866 -288.226909) (xy 380.044525 -288.178556) (xy 380.036781 -288.128421) (xy 380.036324 -288.103056)
			(xy 380.036832 -288.077149) (xy 380.044938 -288.025972) (xy 380.06095 -287.976693) (xy 380.084473 -287.930526)
			(xy 380.114929 -287.888607) (xy 380.151567 -287.851969) (xy 380.193486 -287.821513) (xy 380.239653 -287.79799)
			(xy 380.288932 -287.781978) (xy 380.340109 -287.773872) (xy 380.391923 -287.773872) (xy 380.4431 -287.781978)
			(xy 380.492379 -287.79799) (xy 380.538546 -287.821513) (xy 380.580465 -287.851969) (xy 380.617103 -287.888607)
			(xy 380.647559 -287.930526) (xy 380.671082 -287.976693) (xy 380.687094 -288.025972) (xy 380.6952 -288.077149)
			(xy 380.695708 -288.103056) (xy 380.695115 -288.130773) (xy 380.685787 -288.185419) (xy 380.677166 -288.211768)
			(xy 380.669546 -288.233866) (xy 380.874524 -288.588958) (xy 380.897384 -288.593276) (xy 380.923582 -288.598796)
			(xy 380.973864 -288.617174) (xy 381.020517 -288.643435) (xy 381.062315 -288.676887) (xy 381.098159 -288.716652)
			(xy 381.12711 -288.761684) (xy 381.138176 -288.786062) (xy 381.151638 -288.816542) (xy 381.459994 -288.816542)
			(xy 381.473456 -288.786062) (xy 381.484052 -288.762832) (xy 381.511346 -288.719684) (xy 381.54497 -288.681264)
			(xy 381.584118 -288.648491) (xy 381.627854 -288.622149) (xy 381.675129 -288.60287) (xy 381.724813 -288.591115)
			(xy 381.775716 -288.587165) (xy 381.826619 -288.591115) (xy 381.876303 -288.60287) (xy 381.923578 -288.622149)
			(xy 381.967314 -288.648491) (xy 382.006462 -288.681264) (xy 382.040086 -288.719684) (xy 382.06738 -288.762832)
			(xy 382.077976 -288.786062) (xy 382.091438 -288.816542) (xy 382.401318 -288.816542) (xy 382.41478 -288.786062)
			(xy 382.425342 -288.762972) (xy 382.452528 -288.720089) (xy 382.485998 -288.681909) (xy 382.524952 -288.649344)
			(xy 382.56846 -288.623171) (xy 382.615482 -288.604016) (xy 382.664894 -288.592337) (xy 382.715516 -288.588412)
			(xy 382.766138 -288.592337) (xy 382.81555 -288.604016) (xy 382.862572 -288.623171) (xy 382.90608 -288.649344)
			(xy 382.945034 -288.681909) (xy 382.978504 -288.720089) (xy 383.00569 -288.762972) (xy 383.016252 -288.786062)
			(xy 383.029714 -288.816542) (xy 383.19329 -288.816542) (xy 383.208551 -288.816076) (xy 383.237737 -288.807151)
			(xy 383.262984 -288.790004) (xy 383.282041 -288.766166) (xy 383.293208 -288.737763) (xy 383.295487 -288.707328)
			(xy 383.288676 -288.677578) (xy 383.281428 -288.664142) (xy 383.146808 -288.431224) (xy 383.123948 -288.426906)
			(xy 383.099134 -288.42172) (xy 383.051366 -288.40475) (xy 383.006757 -288.38067) (xy 382.966358 -288.350048)
			(xy 382.931121 -288.313605) (xy 382.901875 -288.272199) (xy 382.87931 -288.226806) (xy 382.863956 -288.178494)
			(xy 382.856175 -288.128402) (xy 382.855724 -288.103056) (xy 382.856232 -288.077149) (xy 382.864338 -288.025972)
			(xy 382.88035 -287.976693) (xy 382.903873 -287.930526) (xy 382.934329 -287.888607) (xy 382.970967 -287.851969)
			(xy 383.012886 -287.821513) (xy 383.059053 -287.79799) (xy 383.108332 -287.781978) (xy 383.159509 -287.773872)
			(xy 383.211323 -287.773872) (xy 383.2625 -287.781978) (xy 383.311779 -287.79799) (xy 383.357946 -287.821513)
			(xy 383.399865 -287.851969) (xy 383.436503 -287.888607) (xy 383.466959 -287.930526) (xy 383.490482 -287.976693)
			(xy 383.506494 -288.025972) (xy 383.5146 -288.077149) (xy 383.515108 -288.103056) (xy 383.514515 -288.130773)
			(xy 383.505187 -288.185419) (xy 383.496566 -288.211768) (xy 383.488692 -288.233866) (xy 383.693924 -288.588958)
			(xy 383.716784 -288.593276) (xy 383.742982 -288.598796) (xy 383.793264 -288.617174) (xy 383.839917 -288.643435)
			(xy 383.881715 -288.676887) (xy 383.917559 -288.716652) (xy 383.94651 -288.761684) (xy 383.957576 -288.786062)
			(xy 383.971038 -288.816542) (xy 385.71805 -288.816542) (xy 385.743008 -288.817118) (xy 385.791964 -288.826867)
			(xy 385.838076 -288.845979) (xy 385.879574 -288.873722) (xy 385.897628 -288.890964) (xy 393.043156 -296.036492)
			(xy 393.060411 -296.054535) (xy 393.088159 -296.09603) (xy 393.107263 -296.142148) (xy 393.116985 -296.191111)
			(xy 393.117578 -296.21607) (xy 393.117578 -329.804014) (xy 393.466574 -330.15301) (xy 396.150338 -330.15301)
			(xy 396.175293 -330.153625) (xy 396.224243 -330.163369) (xy 396.270351 -330.182476) (xy 396.311846 -330.21021)
			(xy 396.329916 -330.227432) (xy 396.74419 -330.641706) (xy 396.761448 -330.659747) (xy 396.789201 -330.701241)
			(xy 396.808307 -330.74736) (xy 396.818029 -330.796324) (xy 396.818612 -330.821284) (xy 396.818612 -339.91931)
			(xy 408.390852 -351.49155) (xy 429.248062 -351.49155)
		)
		(stroke
			(width 0)
			(type solid)
		)
		(fill yes)
		(layer "In8.Cu")
		(net "PVCCFA_EHV_FIVRA_CPU0")
	)
	(gr_poly
		(pts
			(xy 350.434656 -267.735304) (xy 350.436665 -267.710632) (xy 350.447167 -267.662259) (xy 350.464812 -267.61601)
			(xy 350.4892 -267.572935) (xy 350.519779 -267.53401) (xy 350.555854 -267.500116) (xy 350.59661 -267.472023)
			(xy 350.641121 -267.450366) (xy 350.688379 -267.435638) (xy 350.737312 -267.428171) (xy 350.762062 -267.42771)
			(xy 350.784712 -267.428087) (xy 350.829579 -267.434329) (xy 350.85147 -267.440156) (xy 350.880172 -267.448284)
			(xy 352.098356 -266.2301) (xy 352.098356 -265.635994) (xy 352.06432 -265.624056) (xy 352.040508 -265.615294)
			(xy 351.995705 -265.591483) (xy 351.955104 -265.561057) (xy 351.919672 -265.52474) (xy 351.890256 -265.4834)
			(xy 351.867558 -265.438024) (xy 351.852118 -265.389693) (xy 351.844306 -265.339561) (xy 351.844307 -265.288824)
			(xy 351.852122 -265.238692) (xy 351.867564 -265.190362) (xy 351.890265 -265.144986) (xy 351.919682 -265.103648)
			(xy 351.955115 -265.067333) (xy 351.995718 -265.036908) (xy 352.040522 -265.013099) (xy 352.06432 -265.004296)
			(xy 352.098356 -264.992358) (xy 352.098356 -262.017256) (xy 352.098815 -261.995077) (xy 352.106526 -261.951393)
			(xy 352.121706 -261.909713) (xy 352.143894 -261.871302) (xy 352.172415 -261.837328) (xy 352.206403 -261.808823)
			(xy 352.225356 -261.797292) (xy 352.225356 -261.572502) (xy 352.207424 -261.545507) (xy 352.179033 -261.487253)
			(xy 352.159741 -261.425386) (xy 352.149991 -261.361319) (xy 352.14941 -261.328916) (xy 352.149918 -261.299177)
			(xy 352.158144 -261.240271) (xy 352.174439 -261.183069) (xy 352.198491 -261.128672) (xy 352.229837 -261.078124)
			(xy 352.267875 -261.032399) (xy 352.311871 -260.992376) (xy 352.360982 -260.958824) (xy 352.414262 -260.932388)
			(xy 352.470687 -260.913577) (xy 352.529171 -260.902753) (xy 352.558858 -260.900926) (xy 352.57867 -260.89991)
			(xy 352.79584 -260.68274) (xy 352.804222 -260.675374) (xy 352.806254 -260.673596) (xy 352.939604 -260.539992)
			(xy 352.937572 -260.51637) (xy 352.936556 -260.493256) (xy 352.936556 -257.093212) (xy 352.5774 -256.734056)
			(xy 351.611946 -256.734056) (xy 351.605088 -256.741168) (xy 351.285556 -257.0607) (xy 351.285556 -260.518656)
			(xy 351.284979 -260.543614) (xy 351.27523 -260.592569) (xy 351.256116 -260.63868) (xy 351.228373 -260.680177)
			(xy 351.211134 -260.698234) (xy 351.136204 -260.773164) (xy 351.13722 -260.79577) (xy 351.137728 -260.812534)
			(xy 351.137246 -260.838321) (xy 351.129172 -260.889258) (xy 351.11323 -260.938306) (xy 351.089811 -260.984256)
			(xy 351.059492 -261.025977) (xy 351.02302 -261.06244) (xy 350.981293 -261.09275) (xy 350.935338 -261.116158)
			(xy 350.886286 -261.13209) (xy 350.835347 -261.140151) (xy 350.80956 -261.140702) (xy 350.792796 -261.140194)
			(xy 350.77019 -261.139178) (xy 350.652334 -261.257034) (xy 350.634293 -261.274293) (xy 350.592799 -261.302047)
			(xy 350.54668 -261.321157) (xy 350.497717 -261.330886) (xy 350.472756 -261.331456) (xy 350.140778 -261.331456)
			(xy 350.128078 -261.363714) (xy 350.11808 -261.388007) (xy 350.091491 -261.43331) (xy 350.058024 -261.473798)
			(xy 350.018534 -261.508436) (xy 349.974029 -261.536341) (xy 349.925647 -261.556798) (xy 349.874623 -261.569285)
			(xy 349.822262 -261.573483) (xy 349.769901 -261.569285) (xy 349.718877 -261.556798) (xy 349.670495 -261.536341)
			(xy 349.62599 -261.508436) (xy 349.5865 -261.473798) (xy 349.553033 -261.43331) (xy 349.526444 -261.388007)
			(xy 349.516446 -261.363714) (xy 349.503746 -261.331456) (xy 349.200978 -261.331456) (xy 349.188278 -261.363714)
			(xy 349.17828 -261.388007) (xy 349.151691 -261.43331) (xy 349.118224 -261.473798) (xy 349.078734 -261.508436)
			(xy 349.034229 -261.536341) (xy 348.985847 -261.556798) (xy 348.934823 -261.569285) (xy 348.882462 -261.573483)
			(xy 348.830101 -261.569285) (xy 348.779077 -261.556798) (xy 348.730695 -261.536341) (xy 348.68619 -261.508436)
			(xy 348.6467 -261.473798) (xy 348.613233 -261.43331) (xy 348.586644 -261.388007) (xy 348.576646 -261.363714)
			(xy 348.563946 -261.331456) (xy 348.261178 -261.331456) (xy 348.248478 -261.363714) (xy 348.23848 -261.388007)
			(xy 348.211891 -261.43331) (xy 348.178424 -261.473798) (xy 348.138934 -261.508436) (xy 348.094429 -261.536341)
			(xy 348.046047 -261.556798) (xy 347.995023 -261.569285) (xy 347.942662 -261.573483) (xy 347.890301 -261.569285)
			(xy 347.839277 -261.556798) (xy 347.790895 -261.536341) (xy 347.74639 -261.508436) (xy 347.7069 -261.473798)
			(xy 347.673433 -261.43331) (xy 347.646844 -261.388007) (xy 347.636846 -261.363714) (xy 347.624146 -261.331456)
			(xy 347.321378 -261.331456) (xy 347.308678 -261.363714) (xy 347.29868 -261.388007) (xy 347.272091 -261.43331)
			(xy 347.238624 -261.473798) (xy 347.199134 -261.508436) (xy 347.154629 -261.536341) (xy 347.106247 -261.556798)
			(xy 347.055223 -261.569285) (xy 347.002862 -261.573483) (xy 346.950501 -261.569285) (xy 346.899477 -261.556798)
			(xy 346.851095 -261.536341) (xy 346.80659 -261.508436) (xy 346.7671 -261.473798) (xy 346.733633 -261.43331)
			(xy 346.707044 -261.388007) (xy 346.697046 -261.363714) (xy 346.684346 -261.331456) (xy 346.381578 -261.331456)
			(xy 346.368878 -261.363714) (xy 346.35888 -261.388007) (xy 346.332291 -261.43331) (xy 346.298824 -261.473798)
			(xy 346.259334 -261.508436) (xy 346.214829 -261.536341) (xy 346.166447 -261.556798) (xy 346.115423 -261.569285)
			(xy 346.063062 -261.573483) (xy 346.010701 -261.569285) (xy 345.959677 -261.556798) (xy 345.911295 -261.536341)
			(xy 345.86679 -261.508436) (xy 345.8273 -261.473798) (xy 345.793833 -261.43331) (xy 345.767244 -261.388007)
			(xy 345.757246 -261.363714) (xy 345.744546 -261.331456) (xy 345.441778 -261.331456) (xy 345.429078 -261.363714)
			(xy 345.419742 -261.386503) (xy 345.395235 -261.429218) (xy 345.364624 -261.467793) (xy 345.328594 -261.501364)
			(xy 345.287954 -261.529177) (xy 345.243616 -261.550609) (xy 345.196575 -261.565177) (xy 345.147885 -261.572557)
			(xy 345.123262 -261.57301) (xy 345.097475 -261.572502) (xy 345.046537 -261.564429) (xy 344.997489 -261.548488)
			(xy 344.951537 -261.525073) (xy 344.909814 -261.494757) (xy 344.873345 -261.45829) (xy 344.84303 -261.416566)
			(xy 344.819613 -261.370615) (xy 344.803672 -261.321567) (xy 344.795599 -261.270629) (xy 344.795094 -261.244842)
			(xy 344.795601 -261.218517) (xy 344.803963 -261.166535) (xy 344.820498 -261.116548) (xy 344.832178 -261.09295)
			(xy 344.84945 -261.05993) (xy 344.520774 -260.731254) (xy 344.512646 -260.727444) (xy 344.48896 -260.715616)
			(xy 344.44539 -260.685547) (xy 344.407205 -260.648881) (xy 344.375393 -260.606566) (xy 344.350777 -260.559699)
			(xy 344.333994 -260.509491) (xy 344.325479 -260.457241) (xy 344.32494 -260.430772) (xy 344.325418 -260.405362)
			(xy 344.333257 -260.35515) (xy 344.348743 -260.306747) (xy 344.371506 -260.261309) (xy 344.401001 -260.219924)
			(xy 344.418412 -260.20141) (xy 344.418412 -259.031994) (xy 344.401075 -259.013505) (xy 344.37173 -258.972181)
			(xy 344.349087 -258.926837) (xy 344.333684 -258.878551) (xy 344.325887 -258.82847) (xy 344.325883 -258.777787)
			(xy 344.333671 -258.727705) (xy 344.349065 -258.679416) (xy 344.3717 -258.634068) (xy 344.401038 -258.592739)
			(xy 344.418412 -258.574286) (xy 344.418412 -257.404108) (xy 344.401081 -257.385619) (xy 344.371749 -257.344297)
			(xy 344.349119 -257.298957) (xy 344.333728 -257.250677) (xy 344.325942 -257.200604) (xy 344.325947 -257.14993)
			(xy 344.333743 -257.099859) (xy 344.349144 -257.051582) (xy 344.371783 -257.006246) (xy 344.401124 -256.96493)
			(xy 344.418412 -256.9464) (xy 344.418412 -255.776476) (xy 344.401076 -255.757987) (xy 344.371734 -255.716663)
			(xy 344.349093 -255.67132) (xy 344.333693 -255.623035) (xy 344.325899 -255.572956) (xy 344.325896 -255.522275)
			(xy 344.333686 -255.472196) (xy 344.349081 -255.423909) (xy 344.371718 -255.378564) (xy 344.401056 -255.337237)
			(xy 344.418412 -255.318768) (xy 344.418412 -254.14859) (xy 344.401075 -254.130101) (xy 344.371731 -254.088777)
			(xy 344.349088 -254.043433) (xy 344.333686 -253.995147) (xy 344.32589 -253.945067) (xy 344.325886 -253.894384)
			(xy 344.333674 -253.844303) (xy 344.349069 -253.796015) (xy 344.371704 -253.750667) (xy 344.401042 -253.709339)
			(xy 344.418412 -253.690882) (xy 344.418412 -249.111008) (xy 344.391234 -249.096784) (xy 344.368867 -249.08451)
			(xy 344.327895 -249.05411) (xy 344.292123 -249.017735) (xy 344.262412 -248.976261) (xy 344.239478 -248.930689)
			(xy 344.223874 -248.882116) (xy 344.215977 -248.831713) (xy 344.215976 -248.780695) (xy 344.223872 -248.730292)
			(xy 344.239475 -248.681718) (xy 344.262408 -248.636145) (xy 344.292118 -248.594671) (xy 344.32789 -248.558295)
			(xy 344.368861 -248.527894) (xy 344.391234 -248.515632) (xy 344.418412 -248.501408) (xy 344.418412 -247.483376)
			(xy 344.391234 -247.469152) (xy 344.368828 -247.456881) (xy 344.327781 -247.426476) (xy 344.291939 -247.390078)
			(xy 344.262168 -247.348568) (xy 344.239186 -247.302947) (xy 344.22355 -247.254317) (xy 344.215635 -247.203851)
			(xy 344.215633 -247.152769) (xy 344.223545 -247.102303) (xy 344.239179 -247.053672) (xy 344.262157 -247.008049)
			(xy 344.291926 -246.966537) (xy 344.327765 -246.930138) (xy 344.368811 -246.89973) (xy 344.391234 -246.887492)
			(xy 344.418412 -246.873268) (xy 344.418412 -245.85549) (xy 344.391234 -245.841266) (xy 344.368869 -245.828992)
			(xy 344.3279 -245.798592) (xy 344.29213 -245.762218) (xy 344.262421 -245.720746) (xy 344.239489 -245.675175)
			(xy 344.223888 -245.626604) (xy 344.215992 -245.576203) (xy 344.215993 -245.525188) (xy 344.22389 -245.474787)
			(xy 344.239493 -245.426217) (xy 344.262426 -245.380646) (xy 344.292136 -245.339175) (xy 344.327907 -245.302802)
			(xy 344.368876 -245.272404) (xy 344.391234 -245.260114) (xy 344.418412 -245.24589) (xy 344.418412 -244.227604)
			(xy 344.391234 -244.21338) (xy 344.368867 -244.201106) (xy 344.327896 -244.170706) (xy 344.292124 -244.134331)
			(xy 344.262414 -244.092858) (xy 344.23948 -244.047286) (xy 344.223877 -243.998713) (xy 344.21598 -243.94831)
			(xy 344.21598 -243.897293) (xy 344.223876 -243.846891) (xy 344.239479 -243.798318) (xy 344.262412 -243.752745)
			(xy 344.292122 -243.711272) (xy 344.327894 -243.674896) (xy 344.368864 -243.644496) (xy 344.391234 -243.632228)
			(xy 344.418412 -243.618004) (xy 344.418412 -242.599718) (xy 344.391234 -242.585494) (xy 344.368866 -242.573219)
			(xy 344.327893 -242.54282) (xy 344.292119 -242.506444) (xy 344.262406 -242.46497) (xy 344.239471 -242.419396)
			(xy 344.223867 -242.370822) (xy 344.215968 -242.320418) (xy 344.215967 -242.269399) (xy 344.223863 -242.218994)
			(xy 344.239465 -242.170419) (xy 344.262398 -242.124845) (xy 344.292108 -242.083369) (xy 344.327881 -242.046991)
			(xy 344.368852 -242.016589) (xy 344.391234 -242.004342) (xy 344.418412 -241.990118) (xy 344.418412 -240.972086)
			(xy 344.391234 -240.957862) (xy 344.368869 -240.945588) (xy 344.327901 -240.915188) (xy 344.292131 -240.878814)
			(xy 344.262423 -240.837342) (xy 344.239492 -240.791772) (xy 344.223891 -240.743201) (xy 344.215996 -240.692801)
			(xy 344.215997 -240.641786) (xy 344.223894 -240.591386) (xy 344.239497 -240.542816) (xy 344.26243 -240.497246)
			(xy 344.29214 -240.455776) (xy 344.32791 -240.419403) (xy 344.36888 -240.389006) (xy 344.391234 -240.37671)
			(xy 344.418412 -240.362486) (xy 344.418412 -239.3442) (xy 344.391234 -239.329976) (xy 344.368868 -239.317702)
			(xy 344.327897 -239.287302) (xy 344.292126 -239.250927) (xy 344.262416 -239.209454) (xy 344.239483 -239.163883)
			(xy 344.22388 -239.11531) (xy 344.215984 -239.064908) (xy 344.215984 -239.013892) (xy 344.22388 -238.96349)
			(xy 344.239483 -238.914917) (xy 344.262416 -238.869346) (xy 344.292126 -238.827873) (xy 344.327897 -238.791498)
			(xy 344.368868 -238.761098) (xy 344.391234 -238.748824) (xy 344.418412 -238.7346) (xy 344.418412 -237.716314)
			(xy 344.391234 -237.70209) (xy 344.368867 -237.689815) (xy 344.327894 -237.659416) (xy 344.292121 -237.62304)
			(xy 344.262408 -237.581566) (xy 344.239474 -237.535993) (xy 344.22387 -237.487419) (xy 344.215972 -237.437016)
			(xy 344.215971 -237.385997) (xy 344.223867 -237.335593) (xy 344.239469 -237.287019) (xy 344.262402 -237.241445)
			(xy 344.292112 -237.19997) (xy 344.327884 -237.163593) (xy 344.368856 -237.133191) (xy 344.391234 -237.120938)
			(xy 344.418412 -237.106714) (xy 344.418412 -236.088682) (xy 344.391234 -236.074458) (xy 344.368869 -236.062184)
			(xy 344.327901 -236.031785) (xy 344.292133 -235.995411) (xy 344.262425 -235.953939) (xy 344.239495 -235.908369)
			(xy 344.223894 -235.859798) (xy 344.215999 -235.809399) (xy 344.216 -235.758385) (xy 344.223898 -235.707985)
			(xy 344.239501 -235.659416) (xy 344.262434 -235.613847) (xy 344.292143 -235.572376) (xy 344.327914 -235.536004)
			(xy 344.368883 -235.505608) (xy 344.391234 -235.493306) (xy 344.418412 -235.479082) (xy 344.418412 -234.938316)
			(xy 344.419032 -234.913363) (xy 344.428783 -234.864418) (xy 344.447896 -234.818316) (xy 344.475634 -234.776828)
			(xy 344.492834 -234.758738) (xy 345.16187 -234.089702) (xy 345.165172 -234.07624) (xy 345.171787 -234.051828)
			(xy 345.191494 -234.005247) (xy 345.218114 -233.962243) (xy 345.251018 -233.923832) (xy 345.289427 -233.890926)
			(xy 345.33243 -233.864303) (xy 345.379009 -233.844594) (xy 345.403424 -233.837988) (xy 345.416886 -233.834686)
			(xy 345.698572 -233.553) (xy 345.676728 -233.51871) (xy 345.664523 -233.498845) (xy 345.645241 -233.456396)
			(xy 345.632167 -233.411644) (xy 345.625564 -233.365491) (xy 345.625166 -233.34218) (xy 345.625647 -233.316392)
			(xy 345.633719 -233.265453) (xy 345.64966 -233.216403) (xy 345.673078 -233.17045) (xy 345.703396 -233.128728)
			(xy 345.739869 -233.092261) (xy 345.781597 -233.06195) (xy 345.827553 -233.038539) (xy 345.876605 -233.022606)
			(xy 345.927546 -233.014543) (xy 345.953334 -233.014012) (xy 345.976644 -233.014424) (xy 346.022794 -233.02103)
			(xy 346.067544 -233.034105) (xy 346.109991 -233.053384) (xy 346.129864 -233.065574) (xy 346.164154 -233.087418)
			(xy 347.505274 -231.746298) (xy 347.504766 -231.724454) (xy 347.504512 -231.714548) (xy 347.504988 -231.688755)
			(xy 347.51305 -231.637804) (xy 347.528985 -231.588741) (xy 347.552398 -231.542776) (xy 347.582715 -231.501039)
			(xy 347.619187 -231.464559) (xy 347.660918 -231.434234) (xy 347.706879 -231.410811) (xy 347.755938 -231.394866)
			(xy 347.806887 -231.386793) (xy 347.83268 -231.38638) (xy 347.842586 -231.386634) (xy 347.86443 -231.387142)
			(xy 349.87103 -229.380542) (xy 349.864172 -229.352602) (xy 349.859555 -229.332986) (xy 349.854582 -229.292995)
			(xy 349.854266 -229.272846) (xy 349.854742 -229.247055) (xy 349.862806 -229.196107) (xy 349.878741 -229.147048)
			(xy 349.902155 -229.101087) (xy 349.932473 -229.059355) (xy 349.968946 -229.022881) (xy 350.010677 -228.992562)
			(xy 350.056637 -228.969145) (xy 350.105696 -228.953208) (xy 350.156643 -228.945143) (xy 350.182434 -228.944678)
			(xy 350.202583 -228.945) (xy 350.242575 -228.949965) (xy 350.26219 -228.954584) (xy 350.29013 -228.961442)
			(xy 351.782634 -227.468938) (xy 351.782634 -226.190048) (xy 351.77603 -226.178364) (xy 351.762751 -226.153625)
			(xy 351.74393 -226.10073) (xy 351.734404 -226.0454) (xy 351.733866 -226.017328) (xy 351.734441 -225.989259)
			(xy 351.743978 -225.933936) (xy 351.762764 -225.881034) (xy 351.77603 -225.856292) (xy 351.782634 -225.844608)
			(xy 351.782634 -224.564702) (xy 351.77603 -224.553018) (xy 351.764276 -224.531557) (xy 351.746541 -224.485954)
			(xy 351.735739 -224.438232) (xy 351.732108 -224.389437) (xy 351.735728 -224.340641) (xy 351.746519 -224.292916)
			(xy 351.764245 -224.247309) (xy 351.77603 -224.225866) (xy 351.782634 -224.214182) (xy 351.782634 -223.99752)
			(xy 351.782129 -223.982395) (xy 351.773359 -223.953448) (xy 351.756494 -223.92834) (xy 351.733013 -223.909274)
			(xy 351.704977 -223.897923) (xy 351.674846 -223.895284) (xy 351.659952 -223.897952) (xy 351.653094 -223.899476)
			(xy 351.630234 -223.903794) (xy 351.42551 -224.258632) (xy 351.433384 -224.280476) (xy 351.441963 -224.306895)
			(xy 351.451158 -224.36167) (xy 351.451672 -224.389442) (xy 351.451164 -224.415329) (xy 351.443065 -224.466467)
			(xy 351.427066 -224.515707) (xy 351.40356 -224.561839) (xy 351.373128 -224.603726) (xy 351.336518 -224.640336)
			(xy 351.294631 -224.670768) (xy 351.248499 -224.694274) (xy 351.199259 -224.710273) (xy 351.148121 -224.718372)
			(xy 351.096347 -224.718372) (xy 351.045209 -224.710273) (xy 350.995969 -224.694274) (xy 350.949837 -224.670768)
			(xy 350.90795 -224.640336) (xy 350.87134 -224.603726) (xy 350.840908 -224.561839) (xy 350.817402 -224.515707)
			(xy 350.801403 -224.466467) (xy 350.793304 -224.415329) (xy 350.792796 -224.389442) (xy 350.793256 -224.364104)
			(xy 350.801004 -224.314024) (xy 350.816323 -224.265719) (xy 350.838853 -224.220327) (xy 350.868064 -224.178916)
			(xy 350.903266 -224.142463) (xy 350.943632 -224.111826) (xy 350.98821 -224.087725) (xy 351.035951 -224.07073)
			(xy 351.060766 -224.065592) (xy 351.083626 -224.061274) (xy 351.28835 -223.706436) (xy 351.28073 -223.684338)
			(xy 351.272104 -223.65799) (xy 351.262776 -223.603344) (xy 351.262188 -223.575626) (xy 351.262668 -223.549723)
			(xy 351.270773 -223.498556) (xy 351.286787 -223.449288) (xy 351.310316 -223.403133) (xy 351.340778 -223.361231)
			(xy 351.377424 -223.324613) (xy 351.41935 -223.294183) (xy 351.465523 -223.27069) (xy 351.514803 -223.254714)
			(xy 351.565977 -223.246648) (xy 351.59188 -223.246188) (xy 351.609026 -223.246407) (xy 351.643131 -223.24997)
			(xy 351.659952 -223.2533) (xy 351.674848 -223.255893) (xy 351.704952 -223.253231) (xy 351.732959 -223.24188)
			(xy 351.756422 -223.222834) (xy 351.773287 -223.197757) (xy 351.782079 -223.168843) (xy 351.782634 -223.153732)
			(xy 351.782634 -222.934276) (xy 351.77603 -222.922592) (xy 351.762757 -222.897851) (xy 351.743947 -222.844955)
			(xy 351.734433 -222.789627) (xy 351.733866 -222.761556) (xy 351.734447 -222.733489) (xy 351.743995 -222.678171)
			(xy 351.76279 -222.625276) (xy 351.77603 -222.60052) (xy 351.782634 -222.588836) (xy 351.782634 -222.088202)
			(xy 351.156778 -221.462346) (xy 351.13468 -221.463362) (xy 351.122234 -221.463616) (xy 351.096331 -221.463136)
			(xy 351.045162 -221.455032) (xy 350.995893 -221.439019) (xy 350.949737 -221.415491) (xy 350.907833 -221.385029)
			(xy 350.871214 -221.348383) (xy 350.840782 -221.306456) (xy 350.817288 -221.260283) (xy 350.801311 -221.211002)
			(xy 350.793245 -221.159828) (xy 350.792796 -221.133924) (xy 350.792796 -221.121478) (xy 350.793812 -221.09938)
			(xy 350.157796 -220.463364) (xy 350.148087 -220.454209) (xy 350.124986 -220.440865) (xy 350.099217 -220.43396)
			(xy 350.072539 -220.433966) (xy 350.046773 -220.440882) (xy 350.023678 -220.454235) (xy 350.00483 -220.473116)
			(xy 349.997776 -220.484446) (xy 349.985613 -220.504717) (xy 349.956387 -220.541873) (xy 349.922159 -220.57448)
			(xy 349.88363 -220.60187) (xy 349.841586 -220.623482) (xy 349.79689 -220.638875) (xy 349.773748 -220.643704)
			(xy 349.750888 -220.648022) (xy 349.54591 -221.003114) (xy 349.553784 -221.024958) (xy 349.562364 -221.051377)
			(xy 349.571562 -221.106152) (xy 349.572072 -221.133924) (xy 349.852996 -221.133924) (xy 349.853504 -221.108037)
			(xy 349.861603 -221.056899) (xy 349.877602 -221.007659) (xy 349.901108 -220.961527) (xy 349.93154 -220.91964)
			(xy 349.96815 -220.88303) (xy 350.010037 -220.852598) (xy 350.056169 -220.829092) (xy 350.105409 -220.813093)
			(xy 350.156547 -220.804994) (xy 350.208321 -220.804994) (xy 350.259459 -220.813093) (xy 350.308699 -220.829092)
			(xy 350.354831 -220.852598) (xy 350.396718 -220.88303) (xy 350.433328 -220.91964) (xy 350.46376 -220.961527)
			(xy 350.487266 -221.007659) (xy 350.503265 -221.056899) (xy 350.511364 -221.108037) (xy 350.511872 -221.133924)
			(xy 350.511345 -221.161632) (xy 350.502148 -221.216279) (xy 350.493584 -221.242636) (xy 350.48571 -221.264734)
			(xy 350.690688 -221.619572) (xy 350.713548 -221.62389) (xy 350.738367 -221.629064) (xy 350.786146 -221.646018)
			(xy 350.830765 -221.670088) (xy 350.871172 -221.700708) (xy 350.906413 -221.737154) (xy 350.935657 -221.778566)
			(xy 350.958214 -221.823969) (xy 350.973552 -221.872291) (xy 350.98131 -221.922391) (xy 350.981772 -221.94774)
			(xy 350.981264 -221.973647) (xy 350.973158 -222.024824) (xy 350.957146 -222.074103) (xy 350.933623 -222.12027)
			(xy 350.903167 -222.162189) (xy 350.866529 -222.198827) (xy 350.82461 -222.229283) (xy 350.778443 -222.252806)
			(xy 350.729164 -222.268818) (xy 350.677987 -222.276924) (xy 350.626173 -222.276924) (xy 350.574996 -222.268818)
			(xy 350.525717 -222.252806) (xy 350.47955 -222.229283) (xy 350.437631 -222.198827) (xy 350.400993 -222.162189)
			(xy 350.370537 -222.12027) (xy 350.347014 -222.074103) (xy 350.331002 -222.024824) (xy 350.322896 -221.973647)
			(xy 350.322388 -221.94774) (xy 350.322992 -221.920023) (xy 350.332309 -221.865377) (xy 350.34093 -221.839028)
			(xy 350.348804 -221.81693) (xy 350.143826 -221.462092) (xy 350.120966 -221.457774) (xy 350.096166 -221.452574)
			(xy 350.04843 -221.435583) (xy 350.003855 -221.411489) (xy 349.963491 -221.380859) (xy 349.928289 -221.344414)
			(xy 349.899076 -221.303012) (xy 349.876542 -221.257629) (xy 349.861217 -221.209332) (xy 349.853461 -221.159259)
			(xy 349.852996 -221.133924) (xy 349.572072 -221.133924) (xy 349.571564 -221.159811) (xy 349.563465 -221.210949)
			(xy 349.547466 -221.260189) (xy 349.52396 -221.306321) (xy 349.493528 -221.348208) (xy 349.456918 -221.384818)
			(xy 349.415031 -221.41525) (xy 349.368899 -221.438756) (xy 349.319659 -221.454755) (xy 349.268521 -221.462854)
			(xy 349.216747 -221.462854) (xy 349.165609 -221.454755) (xy 349.116369 -221.438756) (xy 349.070237 -221.41525)
			(xy 349.02835 -221.384818) (xy 348.99174 -221.348208) (xy 348.961308 -221.306321) (xy 348.937802 -221.260189)
			(xy 348.921803 -221.210949) (xy 348.913704 -221.159811) (xy 348.913196 -221.133924) (xy 348.913658 -221.108587)
			(xy 348.921408 -221.058509) (xy 348.936728 -221.010206) (xy 348.95926 -220.964816) (xy 348.98847 -220.923408)
			(xy 349.023673 -220.886957) (xy 349.064038 -220.856322) (xy 349.108616 -220.832223) (xy 349.156355 -220.815229)
			(xy 349.181166 -220.810074) (xy 349.204026 -220.805756) (xy 349.409004 -220.450664) (xy 349.40113 -220.42882)
			(xy 349.392487 -220.402411) (xy 349.383173 -220.347635) (xy 349.382588 -220.319854) (xy 349.383025 -220.295168)
			(xy 349.390387 -220.246348) (xy 349.404955 -220.199175) (xy 349.426402 -220.154704) (xy 349.454247 -220.113934)
			(xy 349.487867 -220.077778) (xy 349.526507 -220.047045) (xy 349.547688 -220.034358) (xy 349.559082 -220.027375)
			(xy 349.578025 -220.008538) (xy 349.591424 -219.985426) (xy 349.598357 -219.959627) (xy 349.598349 -219.932912)
			(xy 349.5914 -219.907116) (xy 349.577987 -219.884013) (xy 349.56877 -219.874338) (xy 349.45447 -219.760038)
			(xy 349.419926 -219.782136) (xy 349.399994 -219.794449) (xy 349.35738 -219.813911) (xy 349.312429 -219.827111)
			(xy 349.266058 -219.833782) (xy 349.242634 -219.834206) (xy 349.216844 -219.833703) (xy 349.165897 -219.825639)
			(xy 349.116839 -219.809705) (xy 349.070878 -219.786293) (xy 349.029145 -219.755979) (xy 348.992668 -219.71951)
			(xy 348.962345 -219.677784) (xy 348.938923 -219.631827) (xy 348.922978 -219.582773) (xy 348.914903 -219.531828)
			(xy 348.914466 -219.506038) (xy 348.914862 -219.482611) (xy 348.921527 -219.436234) (xy 348.934726 -219.391278)
			(xy 348.954191 -219.34866) (xy 348.966536 -219.328746) (xy 348.988634 -219.294202) (xy 348.95409 -219.259658)
			(xy 348.936828 -219.241618) (xy 348.909067 -219.200125) (xy 348.889951 -219.154007) (xy 348.880217 -219.105042)
			(xy 348.879668 -219.08008) (xy 348.879668 -219.017596) (xy 348.825058 -219.017596) (xy 348.821248 -219.018104)
			(xy 348.809127 -219.019787) (xy 348.784717 -219.02157) (xy 348.77248 -219.02166) (xy 348.746587 -219.021151)
			(xy 348.695439 -219.013051) (xy 348.646187 -218.997052) (xy 348.600042 -218.97355) (xy 348.55814 -218.943121)
			(xy 348.521511 -218.906514) (xy 348.491056 -218.86463) (xy 348.467525 -218.8185) (xy 348.451497 -218.769257)
			(xy 348.443365 -218.718114) (xy 348.442788 -218.692222) (xy 348.443375 -218.664503) (xy 348.45269 -218.609854)
			(xy 348.46133 -218.58351) (xy 348.469204 -218.561412) (xy 348.264226 -218.206574) (xy 348.241366 -218.202256)
			(xy 348.216566 -218.197056) (xy 348.168831 -218.180065) (xy 348.124258 -218.155971) (xy 348.083896 -218.12534)
			(xy 348.048695 -218.088895) (xy 348.019485 -218.047493) (xy 347.996953 -218.002109) (xy 347.98163 -217.953813)
			(xy 347.973877 -217.90374) (xy 347.973396 -217.878406) (xy 347.973904 -217.852519) (xy 347.982003 -217.801381)
			(xy 347.998002 -217.752141) (xy 348.021508 -217.706009) (xy 348.05194 -217.664122) (xy 348.08855 -217.627512)
			(xy 348.130437 -217.59708) (xy 348.176569 -217.573574) (xy 348.225809 -217.557575) (xy 348.276947 -217.549476)
			(xy 348.328721 -217.549476) (xy 348.379859 -217.557575) (xy 348.429099 -217.573574) (xy 348.475231 -217.59708)
			(xy 348.517118 -217.627512) (xy 348.553728 -217.664122) (xy 348.58416 -217.706009) (xy 348.607666 -217.752141)
			(xy 348.623665 -217.801381) (xy 348.631764 -217.852519) (xy 348.632272 -217.878406) (xy 348.631742 -217.906114)
			(xy 348.622542 -217.960759) (xy 348.613984 -217.987118) (xy 348.60611 -218.009216) (xy 348.690184 -218.154504)
			(xy 348.698032 -218.167055) (xy 348.719574 -218.187338) (xy 348.746025 -218.200597) (xy 348.775165 -218.205721)
			(xy 348.804552 -218.202279) (xy 348.831721 -218.19056) (xy 348.854392 -218.171548) (xy 348.870663 -218.146836)
			(xy 348.879171 -218.118497) (xy 348.879668 -218.103704) (xy 348.879668 -215.867742) (xy 348.879263 -215.854311)
			(xy 348.872264 -215.828376) (xy 348.85874 -215.805167) (xy 348.839628 -215.78629) (xy 348.816253 -215.773055)
			(xy 348.790233 -215.766378) (xy 348.776798 -215.766142) (xy 348.77248 -215.766396) (xy 348.746574 -215.765886)
			(xy 348.695399 -215.757778) (xy 348.646123 -215.741765) (xy 348.599958 -215.71824) (xy 348.558042 -215.687784)
			(xy 348.521405 -215.651146) (xy 348.490951 -215.609228) (xy 348.467429 -215.563062) (xy 348.451418 -215.513785)
			(xy 348.443313 -215.46261) (xy 348.442788 -215.436704) (xy 348.443253 -215.411358) (xy 348.451016 -215.361265)
			(xy 348.466358 -215.312951) (xy 348.488919 -215.267556) (xy 348.518166 -215.226153) (xy 348.553409 -215.189717)
			(xy 348.593816 -215.159108) (xy 348.638434 -215.135048) (xy 348.68621 -215.118105) (xy 348.711012 -215.112854)
			(xy 348.733872 -215.108536) (xy 348.879668 -214.855806) (xy 348.879668 -189.34938) (xy 348.880281 -189.324424)
			(xy 348.890021 -189.275471) (xy 348.909123 -189.229359) (xy 348.936852 -189.187858) (xy 348.95409 -189.169802)
			(xy 349.522542 -188.60135) (xy 349.540583 -188.584091) (xy 349.582077 -188.556334) (xy 349.628195 -188.537221)
			(xy 349.677159 -188.527488) (xy 349.70212 -188.526928) (xy 355.093524 -188.526928) (xy 355.58476 -188.035692)
			(xy 355.58476 -174.508668) (xy 355.585334 -174.483709) (xy 355.595081 -174.434752) (xy 355.614192 -174.388638)
			(xy 355.641934 -174.347139) (xy 355.659182 -174.32909) (xy 372.891304 -157.096968) (xy 372.909347 -157.079712)
			(xy 372.950842 -157.051964) (xy 372.99696 -157.032861) (xy 373.045922 -157.023139) (xy 373.070882 -157.022546)
			(xy 409.505912 -157.022546) (xy 409.966668 -156.56179) (xy 409.966668 -149.101302) (xy 409.53309 -148.667724)
			(xy 409.521526 -148.655773) (xy 409.501268 -148.629401) (xy 409.492704 -148.615146) (xy 408.43708 -148.615146)
			(xy 408.414203 -148.630996) (xy 408.364557 -148.656147) (xy 408.311601 -148.673263) (xy 408.256627 -148.681927)
			(xy 408.200973 -148.681927) (xy 408.145999 -148.673263) (xy 408.093043 -148.656147) (xy 408.043397 -148.630996)
			(xy 408.02052 -148.615146) (xy 396.941294 -148.615146) (xy 396.926195 -148.637975) (xy 396.890496 -148.679464)
			(xy 396.849236 -148.715427) (xy 396.80326 -148.745125) (xy 396.753513 -148.767948) (xy 396.701014 -148.783429)
			(xy 396.646843 -148.79125) (xy 396.592109 -148.79125) (xy 396.537938 -148.783429) (xy 396.485439 -148.767948)
			(xy 396.435692 -148.745125) (xy 396.389716 -148.715427) (xy 396.348456 -148.679464) (xy 396.312757 -148.637975)
			(xy 396.297658 -148.615146) (xy 356.031038 -148.615146) (xy 337.080352 -167.565832) (xy 348.657164 -167.565832)
			(xy 348.657658 -167.532531) (xy 348.666337 -167.466499) (xy 348.683566 -167.402165) (xy 348.709048 -167.340632)
			(xy 348.742347 -167.282953) (xy 348.782893 -167.230117) (xy 348.829992 -167.183027) (xy 348.882836 -167.142492)
			(xy 348.911418 -167.125396) (xy 349.83547 -166.591742) (xy 349.864533 -166.575642) (xy 349.925937 -166.550271)
			(xy 349.990123 -166.533114) (xy 350.055996 -166.524463) (xy 350.089216 -166.523924) (xy 350.089724 -166.523924)
			(xy 350.120458 -166.524315) (xy 350.181477 -166.531727) (xy 350.241158 -166.54644) (xy 350.29863 -166.56824)
			(xy 350.353056 -166.596808) (xy 350.403641 -166.631729) (xy 350.449648 -166.672492) (xy 350.490406 -166.718503)
			(xy 350.525321 -166.769092) (xy 350.553883 -166.823521) (xy 350.575676 -166.880996) (xy 350.590383 -166.940678)
			(xy 350.597788 -167.001698) (xy 350.598232 -167.032432) (xy 350.597712 -167.065732) (xy 350.589036 -167.131763)
			(xy 350.571812 -167.196097) (xy 350.546334 -167.25763) (xy 350.513038 -167.315309) (xy 350.472496 -167.368145)
			(xy 350.4254 -167.415235) (xy 350.372559 -167.455772) (xy 350.343978 -167.472868) (xy 349.419926 -168.006522)
			(xy 349.390862 -168.02262) (xy 349.329459 -168.047992) (xy 349.265273 -168.06515) (xy 349.1994 -168.073802)
			(xy 349.16618 -168.07434) (xy 349.165672 -168.07434) (xy 349.134942 -168.07387) (xy 349.073929 -168.066459)
			(xy 349.014255 -168.051748) (xy 348.956789 -168.029953) (xy 348.902369 -168.001389) (xy 348.851788 -167.966475)
			(xy 348.805784 -167.925719) (xy 348.765027 -167.879715) (xy 348.730113 -167.829135) (xy 348.701549 -167.774715)
			(xy 348.679753 -167.717249) (xy 348.665041 -167.657575) (xy 348.65763 -167.596562) (xy 348.657164 -167.565832)
			(xy 337.080352 -167.565832) (xy 336.343752 -168.302432) (xy 352.441764 -168.302432) (xy 352.442268 -168.271702)
			(xy 352.449672 -168.210689) (xy 352.464377 -168.151013) (xy 352.486168 -168.093545) (xy 352.514727 -168.039122)
			(xy 352.549637 -167.988539) (xy 352.59039 -167.942533) (xy 352.636392 -167.901774) (xy 352.686971 -167.866858)
			(xy 352.74139 -167.838292) (xy 352.798856 -167.816495) (xy 352.85853 -167.801783) (xy 352.919542 -167.794371)
			(xy 352.950272 -167.793924) (xy 352.95078 -167.793924) (xy 352.983998 -167.794489) (xy 353.049869 -167.803142)
			(xy 353.114055 -167.820291) (xy 353.175463 -167.845645) (xy 353.204526 -167.861742) (xy 354.128578 -168.395396)
			(xy 354.157139 -168.412518) (xy 354.209962 -168.453067) (xy 354.257042 -168.500162) (xy 354.297574 -168.552998)
			(xy 354.330866 -168.61067) (xy 354.356349 -168.672193) (xy 354.373586 -168.736515) (xy 354.382284 -168.802536)
			(xy 354.382832 -168.835832) (xy 354.382374 -168.866563) (xy 354.374962 -168.927576) (xy 354.360251 -168.987251)
			(xy 354.338454 -169.044717) (xy 354.30989 -169.099138) (xy 354.274975 -169.149719) (xy 354.234218 -169.195723)
			(xy 354.188213 -169.23648) (xy 354.137631 -169.271394) (xy 354.08321 -169.299957) (xy 354.025743 -169.321753)
			(xy 353.966068 -169.336464) (xy 353.905055 -169.343875) (xy 353.874324 -169.34434) (xy 353.873816 -169.34434)
			(xy 353.840597 -169.343782) (xy 353.774726 -169.335127) (xy 353.710541 -169.317976) (xy 353.649132 -169.292621)
			(xy 353.62007 -169.276522) (xy 352.696018 -168.742868) (xy 352.667463 -168.725735) (xy 352.614637 -168.685191)
			(xy 352.567553 -168.638099) (xy 352.527018 -168.585266) (xy 352.493724 -168.527595) (xy 352.468241 -168.466072)
			(xy 352.451005 -168.40175) (xy 352.44231 -168.335728) (xy 352.441764 -168.302432) (xy 336.343752 -168.302432)
			(xy 334.032352 -170.613832) (xy 348.657164 -170.613832) (xy 348.657658 -170.580531) (xy 348.666337 -170.514499)
			(xy 348.683566 -170.450165) (xy 348.709048 -170.388632) (xy 348.742347 -170.330953) (xy 348.782893 -170.278117)
			(xy 348.829992 -170.231027) (xy 348.882836 -170.190492) (xy 348.911418 -170.173396) (xy 349.83547 -169.639742)
			(xy 349.864533 -169.623642) (xy 349.925937 -169.598271) (xy 349.990123 -169.581114) (xy 350.055996 -169.572463)
			(xy 350.089216 -169.571924) (xy 350.089724 -169.571924) (xy 350.120458 -169.572315) (xy 350.181477 -169.579727)
			(xy 350.241158 -169.59444) (xy 350.29863 -169.61624) (xy 350.353056 -169.644808) (xy 350.403641 -169.679729)
			(xy 350.449648 -169.720492) (xy 350.490406 -169.766503) (xy 350.525321 -169.817092) (xy 350.553883 -169.871521)
			(xy 350.575676 -169.928996) (xy 350.590383 -169.988678) (xy 350.597788 -170.049698) (xy 350.598232 -170.080432)
			(xy 350.597712 -170.113732) (xy 350.589036 -170.179763) (xy 350.571812 -170.244097) (xy 350.546334 -170.30563)
			(xy 350.513038 -170.363309) (xy 350.472496 -170.416145) (xy 350.4254 -170.463235) (xy 350.372559 -170.503772)
			(xy 350.343978 -170.520868) (xy 349.419926 -171.054522) (xy 349.390862 -171.07062) (xy 349.329459 -171.095992)
			(xy 349.265273 -171.11315) (xy 349.1994 -171.121802) (xy 349.16618 -171.12234) (xy 349.165672 -171.12234)
			(xy 349.134942 -171.12187) (xy 349.073929 -171.114459) (xy 349.014255 -171.099748) (xy 348.956789 -171.077953)
			(xy 348.902369 -171.049389) (xy 348.851788 -171.014475) (xy 348.805784 -170.973719) (xy 348.765027 -170.927715)
			(xy 348.730113 -170.877135) (xy 348.701549 -170.822715) (xy 348.679753 -170.765249) (xy 348.665041 -170.705575)
			(xy 348.65763 -170.644562) (xy 348.657164 -170.613832) (xy 334.032352 -170.613832) (xy 332.660752 -171.985432)
			(xy 352.441764 -171.985432) (xy 352.442268 -171.954702) (xy 352.449672 -171.893689) (xy 352.464377 -171.834013)
			(xy 352.486168 -171.776545) (xy 352.514727 -171.722122) (xy 352.549637 -171.671539) (xy 352.59039 -171.625533)
			(xy 352.636392 -171.584774) (xy 352.686971 -171.549858) (xy 352.74139 -171.521292) (xy 352.798856 -171.499495)
			(xy 352.85853 -171.484783) (xy 352.919542 -171.477371) (xy 352.950272 -171.476924) (xy 352.95078 -171.476924)
			(xy 352.983998 -171.477489) (xy 353.049869 -171.486142) (xy 353.114055 -171.503291) (xy 353.175463 -171.528645)
			(xy 353.204526 -171.544742) (xy 354.128578 -172.078396) (xy 354.157139 -172.095518) (xy 354.209962 -172.136067)
			(xy 354.257042 -172.183162) (xy 354.297574 -172.235998) (xy 354.330866 -172.29367) (xy 354.356349 -172.355193)
			(xy 354.373586 -172.419515) (xy 354.382284 -172.485536) (xy 354.382832 -172.518832) (xy 354.382374 -172.549563)
			(xy 354.374962 -172.610576) (xy 354.360251 -172.670251) (xy 354.338454 -172.727717) (xy 354.30989 -172.782138)
			(xy 354.274975 -172.832719) (xy 354.234218 -172.878723) (xy 354.188213 -172.91948) (xy 354.137631 -172.954394)
			(xy 354.08321 -172.982957) (xy 354.025743 -173.004753) (xy 353.966068 -173.019464) (xy 353.905055 -173.026875)
			(xy 353.874324 -173.02734) (xy 353.873816 -173.02734) (xy 353.840597 -173.026782) (xy 353.774726 -173.018127)
			(xy 353.710541 -173.000976) (xy 353.649132 -172.975621) (xy 353.62007 -172.959522) (xy 352.696018 -172.425868)
			(xy 352.667463 -172.408735) (xy 352.614637 -172.368191) (xy 352.567553 -172.321099) (xy 352.527018 -172.268266)
			(xy 352.493724 -172.210595) (xy 352.468241 -172.149072) (xy 352.451005 -172.08475) (xy 352.44231 -172.018728)
			(xy 352.441764 -171.985432) (xy 332.660752 -171.985432) (xy 330.984352 -173.661832) (xy 348.657164 -173.661832)
			(xy 348.657658 -173.628531) (xy 348.666337 -173.562499) (xy 348.683566 -173.498165) (xy 348.709048 -173.436632)
			(xy 348.742347 -173.378953) (xy 348.782893 -173.326117) (xy 348.829992 -173.279027) (xy 348.882836 -173.238492)
			(xy 348.911418 -173.221396) (xy 349.83547 -172.687742) (xy 349.864533 -172.671642) (xy 349.925937 -172.646271)
			(xy 349.990123 -172.629114) (xy 350.055996 -172.620463) (xy 350.089216 -172.619924) (xy 350.089724 -172.619924)
			(xy 350.120458 -172.620315) (xy 350.181477 -172.627727) (xy 350.241158 -172.64244) (xy 350.29863 -172.66424)
			(xy 350.353056 -172.692808) (xy 350.403641 -172.727729) (xy 350.449648 -172.768492) (xy 350.490406 -172.814503)
			(xy 350.525321 -172.865092) (xy 350.553883 -172.919521) (xy 350.575676 -172.976996) (xy 350.590383 -173.036678)
			(xy 350.597788 -173.097698) (xy 350.598232 -173.128432) (xy 350.597712 -173.161732) (xy 350.589036 -173.227763)
			(xy 350.571812 -173.292097) (xy 350.546334 -173.35363) (xy 350.513038 -173.411309) (xy 350.472496 -173.464145)
			(xy 350.4254 -173.511235) (xy 350.372559 -173.551772) (xy 350.343978 -173.568868) (xy 349.419926 -174.102522)
			(xy 349.390862 -174.11862) (xy 349.329459 -174.143992) (xy 349.265273 -174.16115) (xy 349.1994 -174.169802)
			(xy 349.16618 -174.17034) (xy 349.165672 -174.17034) (xy 349.134942 -174.16987) (xy 349.073929 -174.162459)
			(xy 349.014255 -174.147748) (xy 348.956789 -174.125953) (xy 348.902369 -174.097389) (xy 348.851788 -174.062475)
			(xy 348.805784 -174.021719) (xy 348.765027 -173.975715) (xy 348.730113 -173.925135) (xy 348.701549 -173.870715)
			(xy 348.679753 -173.813249) (xy 348.665041 -173.753575) (xy 348.65763 -173.692562) (xy 348.657164 -173.661832)
			(xy 330.984352 -173.661832) (xy 327.936352 -176.709832) (xy 348.657164 -176.709832) (xy 348.657658 -176.676531)
			(xy 348.666337 -176.610499) (xy 348.683566 -176.546165) (xy 348.709048 -176.484632) (xy 348.742347 -176.426953)
			(xy 348.782893 -176.374117) (xy 348.829992 -176.327027) (xy 348.882836 -176.286492) (xy 348.911418 -176.269396)
			(xy 349.83547 -175.735742) (xy 349.864533 -175.719642) (xy 349.925937 -175.694271) (xy 349.990123 -175.677114)
			(xy 350.055996 -175.668463) (xy 350.089216 -175.667924) (xy 350.089724 -175.667924) (xy 350.120458 -175.668315)
			(xy 350.121421 -175.668432) (xy 352.441764 -175.668432) (xy 352.442268 -175.637702) (xy 352.449672 -175.576689)
			(xy 352.464377 -175.517013) (xy 352.486168 -175.459545) (xy 352.514727 -175.405122) (xy 352.549637 -175.354539)
			(xy 352.59039 -175.308533) (xy 352.636392 -175.267774) (xy 352.686971 -175.232858) (xy 352.74139 -175.204292)
			(xy 352.798856 -175.182495) (xy 352.85853 -175.167783) (xy 352.919542 -175.160371) (xy 352.950272 -175.159924)
			(xy 352.95078 -175.159924) (xy 352.983998 -175.160489) (xy 353.049869 -175.169142) (xy 353.114055 -175.186291)
			(xy 353.175463 -175.211645) (xy 353.204526 -175.227742) (xy 354.128578 -175.761396) (xy 354.157139 -175.778518)
			(xy 354.209962 -175.819067) (xy 354.257042 -175.866162) (xy 354.297574 -175.918998) (xy 354.330866 -175.97667)
			(xy 354.356349 -176.038193) (xy 354.373586 -176.102515) (xy 354.382284 -176.168536) (xy 354.382832 -176.201832)
			(xy 354.382374 -176.232563) (xy 354.374962 -176.293576) (xy 354.360251 -176.353251) (xy 354.338454 -176.410717)
			(xy 354.30989 -176.465138) (xy 354.274975 -176.515719) (xy 354.234218 -176.561723) (xy 354.188213 -176.60248)
			(xy 354.137631 -176.637394) (xy 354.08321 -176.665957) (xy 354.025743 -176.687753) (xy 353.966068 -176.702464)
			(xy 353.905055 -176.709875) (xy 353.874324 -176.71034) (xy 353.873816 -176.71034) (xy 353.840597 -176.709782)
			(xy 353.774726 -176.701127) (xy 353.710541 -176.683976) (xy 353.649132 -176.658621) (xy 353.62007 -176.642522)
			(xy 352.696018 -176.108868) (xy 352.667463 -176.091735) (xy 352.614637 -176.051191) (xy 352.567553 -176.004099)
			(xy 352.527018 -175.951266) (xy 352.493724 -175.893595) (xy 352.468241 -175.832072) (xy 352.451005 -175.76775)
			(xy 352.44231 -175.701728) (xy 352.441764 -175.668432) (xy 350.121421 -175.668432) (xy 350.181477 -175.675727)
			(xy 350.241158 -175.69044) (xy 350.29863 -175.71224) (xy 350.353056 -175.740808) (xy 350.403641 -175.775729)
			(xy 350.449648 -175.816492) (xy 350.490406 -175.862503) (xy 350.525321 -175.913092) (xy 350.553883 -175.967521)
			(xy 350.575676 -176.024996) (xy 350.590383 -176.084678) (xy 350.597788 -176.145698) (xy 350.598232 -176.176432)
			(xy 350.597712 -176.209732) (xy 350.589036 -176.275763) (xy 350.571812 -176.340097) (xy 350.546334 -176.40163)
			(xy 350.513038 -176.459309) (xy 350.472496 -176.512145) (xy 350.4254 -176.559235) (xy 350.372559 -176.599772)
			(xy 350.343978 -176.616868) (xy 349.419926 -177.150522) (xy 349.390862 -177.16662) (xy 349.329459 -177.191992)
			(xy 349.265273 -177.20915) (xy 349.1994 -177.217802) (xy 349.16618 -177.21834) (xy 349.165672 -177.21834)
			(xy 349.134942 -177.21787) (xy 349.073929 -177.210459) (xy 349.014255 -177.195748) (xy 348.956789 -177.173953)
			(xy 348.902369 -177.145389) (xy 348.851788 -177.110475) (xy 348.805784 -177.069719) (xy 348.765027 -177.023715)
			(xy 348.730113 -176.973135) (xy 348.701549 -176.918715) (xy 348.679753 -176.861249) (xy 348.665041 -176.801575)
			(xy 348.65763 -176.740562) (xy 348.657164 -176.709832) (xy 327.936352 -176.709832) (xy 324.888352 -179.757832)
			(xy 348.657164 -179.757832) (xy 348.657658 -179.724531) (xy 348.666337 -179.658499) (xy 348.683566 -179.594165)
			(xy 348.709048 -179.532632) (xy 348.742347 -179.474953) (xy 348.782893 -179.422117) (xy 348.829992 -179.375027)
			(xy 348.882836 -179.334492) (xy 348.911418 -179.317396) (xy 349.83547 -178.783742) (xy 349.864533 -178.767642)
			(xy 349.925937 -178.742271) (xy 349.990123 -178.725114) (xy 350.055996 -178.716463) (xy 350.089216 -178.715924)
			(xy 350.089724 -178.715924) (xy 350.120458 -178.716315) (xy 350.181477 -178.723727) (xy 350.241158 -178.73844)
			(xy 350.29863 -178.76024) (xy 350.353056 -178.788808) (xy 350.403641 -178.823729) (xy 350.449648 -178.864492)
			(xy 350.490406 -178.910503) (xy 350.525321 -178.961092) (xy 350.553883 -179.015521) (xy 350.575676 -179.072996)
			(xy 350.590383 -179.132678) (xy 350.597788 -179.193698) (xy 350.598232 -179.224432) (xy 350.597712 -179.257732)
			(xy 350.589036 -179.323763) (xy 350.581628 -179.351432) (xy 352.441764 -179.351432) (xy 352.442268 -179.320702)
			(xy 352.449672 -179.259689) (xy 352.464377 -179.200013) (xy 352.486168 -179.142545) (xy 352.514727 -179.088122)
			(xy 352.549637 -179.037539) (xy 352.59039 -178.991533) (xy 352.636392 -178.950774) (xy 352.686971 -178.915858)
			(xy 352.74139 -178.887292) (xy 352.798856 -178.865495) (xy 352.85853 -178.850783) (xy 352.919542 -178.843371)
			(xy 352.950272 -178.842924) (xy 352.95078 -178.842924) (xy 352.983998 -178.843489) (xy 353.049869 -178.852142)
			(xy 353.114055 -178.869291) (xy 353.175463 -178.894645) (xy 353.204526 -178.910742) (xy 354.128578 -179.444396)
			(xy 354.157139 -179.461518) (xy 354.209962 -179.502067) (xy 354.257042 -179.549162) (xy 354.297574 -179.601998)
			(xy 354.330866 -179.65967) (xy 354.356349 -179.721193) (xy 354.373586 -179.785515) (xy 354.382284 -179.851536)
			(xy 354.382832 -179.884832) (xy 354.382374 -179.915563) (xy 354.374962 -179.976576) (xy 354.360251 -180.036251)
			(xy 354.338454 -180.093717) (xy 354.30989 -180.148138) (xy 354.274975 -180.198719) (xy 354.234218 -180.244723)
			(xy 354.188213 -180.28548) (xy 354.137631 -180.320394) (xy 354.08321 -180.348957) (xy 354.025743 -180.370753)
			(xy 353.966068 -180.385464) (xy 353.905055 -180.392875) (xy 353.874324 -180.39334) (xy 353.873816 -180.39334)
			(xy 353.840597 -180.392782) (xy 353.774726 -180.384127) (xy 353.710541 -180.366976) (xy 353.649132 -180.341621)
			(xy 353.62007 -180.325522) (xy 352.696018 -179.791868) (xy 352.667463 -179.774735) (xy 352.614637 -179.734191)
			(xy 352.567553 -179.687099) (xy 352.527018 -179.634266) (xy 352.493724 -179.576595) (xy 352.468241 -179.515072)
			(xy 352.451005 -179.45075) (xy 352.44231 -179.384728) (xy 352.441764 -179.351432) (xy 350.581628 -179.351432)
			(xy 350.571812 -179.388097) (xy 350.546334 -179.44963) (xy 350.513038 -179.507309) (xy 350.472496 -179.560145)
			(xy 350.4254 -179.607235) (xy 350.372559 -179.647772) (xy 350.343978 -179.664868) (xy 349.419926 -180.198522)
			(xy 349.390862 -180.21462) (xy 349.329459 -180.239992) (xy 349.265273 -180.25715) (xy 349.1994 -180.265802)
			(xy 349.16618 -180.26634) (xy 349.165672 -180.26634) (xy 349.134942 -180.26587) (xy 349.073929 -180.258459)
			(xy 349.014255 -180.243748) (xy 348.956789 -180.221953) (xy 348.902369 -180.193389) (xy 348.851788 -180.158475)
			(xy 348.805784 -180.117719) (xy 348.765027 -180.071715) (xy 348.730113 -180.021135) (xy 348.701549 -179.966715)
			(xy 348.679753 -179.909249) (xy 348.665041 -179.849575) (xy 348.65763 -179.788562) (xy 348.657164 -179.757832)
			(xy 324.888352 -179.757832) (xy 321.840352 -182.805832) (xy 348.657164 -182.805832) (xy 348.657658 -182.772531)
			(xy 348.666337 -182.706499) (xy 348.683566 -182.642165) (xy 348.709048 -182.580632) (xy 348.742347 -182.522953)
			(xy 348.782893 -182.470117) (xy 348.829992 -182.423027) (xy 348.882836 -182.382492) (xy 348.911418 -182.365396)
			(xy 349.83547 -181.831742) (xy 349.864533 -181.815642) (xy 349.925937 -181.790271) (xy 349.990123 -181.773114)
			(xy 350.055996 -181.764463) (xy 350.089216 -181.763924) (xy 350.089724 -181.763924) (xy 350.120458 -181.764315)
			(xy 350.181477 -181.771727) (xy 350.241158 -181.78644) (xy 350.29863 -181.80824) (xy 350.353056 -181.836808)
			(xy 350.403641 -181.871729) (xy 350.449648 -181.912492) (xy 350.490406 -181.958503) (xy 350.525321 -182.009092)
			(xy 350.553883 -182.063521) (xy 350.575676 -182.120996) (xy 350.590383 -182.180678) (xy 350.597788 -182.241698)
			(xy 350.598232 -182.272432) (xy 350.597712 -182.305732) (xy 350.589036 -182.371763) (xy 350.571812 -182.436097)
			(xy 350.546334 -182.49763) (xy 350.513038 -182.555309) (xy 350.472496 -182.608145) (xy 350.4254 -182.655235)
			(xy 350.372559 -182.695772) (xy 350.343978 -182.712868) (xy 349.775297 -183.04129) (xy 352.441764 -183.04129)
			(xy 352.442192 -183.010552) (xy 352.449601 -182.949525) (xy 352.46431 -182.889835) (xy 352.486105 -182.832352)
			(xy 352.514667 -182.777914) (xy 352.549581 -182.727315) (xy 352.590338 -182.681292) (xy 352.636344 -182.640516)
			(xy 352.686928 -182.60558) (xy 352.741353 -182.576994) (xy 352.798826 -182.555175) (xy 352.85851 -182.540441)
			(xy 352.919534 -182.533005) (xy 352.950272 -182.532528) (xy 352.95078 -182.532528) (xy 352.984007 -182.533118)
			(xy 353.049889 -182.541823) (xy 353.114077 -182.559036) (xy 353.175475 -182.584464) (xy 353.204526 -182.6006)
			(xy 354.128578 -183.134254) (xy 354.157165 -183.151335) (xy 354.209988 -183.19189) (xy 354.257067 -183.238991)
			(xy 354.297597 -183.291832) (xy 354.330886 -183.34951) (xy 354.356365 -183.411039) (xy 354.373597 -183.475367)
			(xy 354.382288 -183.541392) (xy 354.382832 -183.57469) (xy 354.382389 -183.605428) (xy 354.374982 -183.666455)
			(xy 354.360275 -183.726145) (xy 354.338483 -183.783627) (xy 354.309922 -183.838065) (xy 354.275009 -183.888665)
			(xy 354.234254 -183.934688) (xy 354.188249 -183.975465) (xy 354.137666 -184.010401) (xy 354.083241 -184.038987)
			(xy 354.025768 -184.060806) (xy 353.966085 -184.07554) (xy 353.905061 -184.082975) (xy 353.874324 -184.083452)
			(xy 353.873816 -184.083452) (xy 353.840589 -184.082867) (xy 353.774706 -184.07416) (xy 353.710519 -184.056946)
			(xy 353.649121 -184.031517) (xy 353.62007 -184.01538) (xy 352.696018 -183.481726) (xy 352.667489 -183.464552)
			(xy 352.614663 -183.424014) (xy 352.567578 -183.376928) (xy 352.527041 -183.324101) (xy 352.493744 -183.266436)
			(xy 352.468257 -183.204918) (xy 352.451015 -183.140601) (xy 352.442314 -183.074584) (xy 352.441764 -183.04129)
			(xy 349.775297 -183.04129) (xy 349.419926 -183.246522) (xy 349.390862 -183.26262) (xy 349.329459 -183.287992)
			(xy 349.265273 -183.30515) (xy 349.1994 -183.313802) (xy 349.16618 -183.31434) (xy 349.165672 -183.31434)
			(xy 349.134942 -183.31387) (xy 349.073929 -183.306459) (xy 349.014255 -183.291748) (xy 348.956789 -183.269953)
			(xy 348.902369 -183.241389) (xy 348.851788 -183.206475) (xy 348.805784 -183.165719) (xy 348.765027 -183.119715)
			(xy 348.730113 -183.069135) (xy 348.701549 -183.014715) (xy 348.679753 -182.957249) (xy 348.665041 -182.897575)
			(xy 348.65763 -182.836562) (xy 348.657164 -182.805832) (xy 321.840352 -182.805832) (xy 318.57188 -186.074304)
			(xy 318.57188 -186.714892) (xy 351.367344 -186.714892) (xy 351.367848 -186.684163) (xy 351.375257 -186.623152)
			(xy 351.389965 -186.563479) (xy 351.411758 -186.506014) (xy 351.440318 -186.451595) (xy 351.475229 -186.401014)
			(xy 351.515982 -186.355011) (xy 351.561983 -186.314254) (xy 351.612561 -186.279339) (xy 351.666978 -186.250774)
			(xy 351.724441 -186.228977) (xy 351.784113 -186.214264) (xy 351.845123 -186.206851) (xy 351.875852 -186.206384)
			(xy 351.87636 -186.206384) (xy 351.90958 -186.206906) (xy 351.975453 -186.215571) (xy 352.039638 -186.232732)
			(xy 352.101045 -186.258098) (xy 352.130106 -186.274202) (xy 353.054158 -186.807856) (xy 353.082741 -186.824943)
			(xy 353.135565 -186.865496) (xy 353.182645 -186.912596) (xy 353.223176 -186.965436) (xy 353.256466 -187.023114)
			(xy 353.281945 -187.084642) (xy 353.299177 -187.148969) (xy 353.307868 -187.214995) (xy 353.308412 -187.248292)
			(xy 353.307955 -187.279024) (xy 353.300547 -187.340039) (xy 353.285839 -187.399717) (xy 353.264044 -187.457187)
			(xy 353.235482 -187.51161) (xy 353.200567 -187.562194) (xy 353.15981 -187.608201) (xy 353.113804 -187.648959)
			(xy 353.063221 -187.683875) (xy 353.008798 -187.712439) (xy 352.951329 -187.734235) (xy 352.891651 -187.748945)
			(xy 352.830636 -187.756354) (xy 352.799904 -187.7568) (xy 352.799396 -187.7568) (xy 352.766177 -187.756256)
			(xy 352.700305 -187.747598) (xy 352.636119 -187.730443) (xy 352.574711 -187.705083) (xy 352.54565 -187.688982)
			(xy 351.621598 -187.155328) (xy 351.593065 -187.13816) (xy 351.54024 -187.09762) (xy 351.493156 -187.050533)
			(xy 351.45262 -186.997705) (xy 351.419323 -186.940039) (xy 351.393837 -186.878521) (xy 351.376595 -186.814204)
			(xy 351.367894 -186.748186) (xy 351.367344 -186.714892) (xy 318.57188 -186.714892) (xy 318.57188 -193.87947)
			(xy 318.817498 -193.87947) (xy 318.839683 -193.879925) (xy 318.883379 -193.887629) (xy 318.925073 -193.902805)
			(xy 318.963499 -193.924989) (xy 318.997489 -193.95351) (xy 319.026009 -193.987499) (xy 319.048195 -194.025925)
			(xy 319.06337 -194.067619) (xy 319.071075 -194.111315) (xy 319.071075 -194.155685) (xy 319.06337 -194.199381)
			(xy 319.048195 -194.241075) (xy 319.026009 -194.279501) (xy 318.997489 -194.31349) (xy 318.963499 -194.342011)
			(xy 318.925073 -194.364195) (xy 318.883379 -194.379371) (xy 318.839683 -194.387075) (xy 318.817498 -194.38747)
			(xy 318.57188 -194.38747) (xy 318.57188 -194.639692) (xy 318.575182 -194.648328) (xy 318.582787 -194.669958)
			(xy 318.590971 -194.715067) (xy 318.591438 -194.73799) (xy 318.590974 -194.760914) (xy 318.582797 -194.806025)
			(xy 318.575182 -194.827652) (xy 318.57188 -194.836288) (xy 318.57188 -206.024988) (xy 334.640692 -206.024988)
			(xy 334.644673 -205.891968) (xy 334.656602 -205.759423) (xy 334.676437 -205.62783) (xy 334.704106 -205.497658)
			(xy 334.73951 -205.369373) (xy 334.782523 -205.243436) (xy 334.83299 -205.120297) (xy 334.890731 -205.000396)
			(xy 334.95554 -204.884163) (xy 335.027184 -204.772013) (xy 335.105406 -204.664349) (xy 335.189927 -204.561556)
			(xy 335.280445 -204.464001) (xy 335.376634 -204.372035) (xy 335.478152 -204.285985) (xy 335.584633 -204.206161)
			(xy 335.695698 -204.132848) (xy 335.810949 -204.066308) (xy 335.929973 -204.006779) (xy 336.052344 -203.954475)
			(xy 336.177623 -203.909583) (xy 336.305364 -203.872264) (xy 336.435107 -203.842651) (xy 336.566389 -203.82085)
			(xy 336.69874 -203.80694) (xy 336.831686 -203.800969) (xy 336.964751 -203.80296) (xy 337.097459 -203.812905)
			(xy 337.229335 -203.830769) (xy 337.359906 -203.856487) (xy 337.488706 -203.889968) (xy 337.615272 -203.931092)
			(xy 337.739153 -203.979712) (xy 337.859904 -204.035653) (xy 337.977094 -204.098715) (xy 338.090303 -204.168673)
			(xy 338.199125 -204.245277) (xy 338.303171 -204.328251) (xy 338.402069 -204.417299) (xy 338.495464 -204.512102)
			(xy 338.583022 -204.61232) (xy 338.664431 -204.717596) (xy 338.739397 -204.827552) (xy 338.807654 -204.941794)
			(xy 338.868956 -205.059914) (xy 338.923085 -205.181489) (xy 338.969846 -205.306083) (xy 339.009072 -205.433251)
			(xy 339.040622 -205.562537) (xy 339.064385 -205.693478) (xy 339.080274 -205.825606) (xy 339.088232 -205.958448)
			(xy 339.08873 -206.024988) (xy 339.088232 -206.091528) (xy 339.080274 -206.22437) (xy 339.064385 -206.356498)
			(xy 339.040622 -206.487439) (xy 339.009072 -206.616725) (xy 338.969846 -206.743893) (xy 338.923085 -206.868487)
			(xy 338.868956 -206.990062) (xy 338.807654 -207.108182) (xy 338.739397 -207.222424) (xy 338.664431 -207.33238)
			(xy 338.583022 -207.437656) (xy 338.495464 -207.537874) (xy 338.402069 -207.632677) (xy 338.303171 -207.721725)
			(xy 338.199125 -207.804699) (xy 338.090303 -207.881303) (xy 337.977094 -207.951261) (xy 337.859904 -208.014323)
			(xy 337.739153 -208.070264) (xy 337.615272 -208.118884) (xy 337.488706 -208.160008) (xy 337.359906 -208.193489)
			(xy 337.229335 -208.219207) (xy 337.097459 -208.237071) (xy 336.964751 -208.247016) (xy 336.831686 -208.249007)
			(xy 336.69874 -208.243036) (xy 336.566389 -208.229126) (xy 336.435107 -208.207325) (xy 336.305364 -208.177712)
			(xy 336.177623 -208.140393) (xy 336.052344 -208.095501) (xy 335.929973 -208.043197) (xy 335.810949 -207.983668)
			(xy 335.695698 -207.917128) (xy 335.584633 -207.843815) (xy 335.478152 -207.763991) (xy 335.376634 -207.677941)
			(xy 335.280445 -207.585975) (xy 335.189927 -207.48842) (xy 335.105406 -207.385627) (xy 335.027184 -207.277963)
			(xy 334.95554 -207.165813) (xy 334.890731 -207.04958) (xy 334.83299 -206.929679) (xy 334.782523 -206.80654)
			(xy 334.73951 -206.680603) (xy 334.704106 -206.552318) (xy 334.676437 -206.422146) (xy 334.656602 -206.290553)
			(xy 334.644673 -206.158008) (xy 334.640692 -206.024988) (xy 318.57188 -206.024988) (xy 318.57188 -213.732618)
			(xy 338.105496 -213.732618) (xy 338.106004 -213.706731) (xy 338.114103 -213.655593) (xy 338.130102 -213.606353)
			(xy 338.153608 -213.560221) (xy 338.18404 -213.518334) (xy 338.22065 -213.481724) (xy 338.262537 -213.451292)
			(xy 338.308669 -213.427786) (xy 338.357909 -213.411787) (xy 338.409047 -213.403688) (xy 338.460821 -213.403688)
			(xy 338.511959 -213.411787) (xy 338.561199 -213.427786) (xy 338.607331 -213.451292) (xy 338.649218 -213.481724)
			(xy 338.685828 -213.518334) (xy 338.71626 -213.560221) (xy 338.739766 -213.606353) (xy 338.755765 -213.655593)
			(xy 338.763864 -213.706731) (xy 338.764372 -213.732618) (xy 339.985096 -213.732618) (xy 339.985604 -213.706731)
			(xy 339.993703 -213.655593) (xy 340.009702 -213.606353) (xy 340.033208 -213.560221) (xy 340.06364 -213.518334)
			(xy 340.10025 -213.481724) (xy 340.142137 -213.451292) (xy 340.188269 -213.427786) (xy 340.237509 -213.411787)
			(xy 340.288647 -213.403688) (xy 340.340421 -213.403688) (xy 340.391559 -213.411787) (xy 340.440799 -213.427786)
			(xy 340.486931 -213.451292) (xy 340.528818 -213.481724) (xy 340.565428 -213.518334) (xy 340.59586 -213.560221)
			(xy 340.619366 -213.606353) (xy 340.635365 -213.655593) (xy 340.643464 -213.706731) (xy 340.643972 -213.732618)
			(xy 341.864696 -213.732618) (xy 341.865204 -213.706731) (xy 341.873303 -213.655593) (xy 341.889302 -213.606353)
			(xy 341.912808 -213.560221) (xy 341.94324 -213.518334) (xy 341.97985 -213.481724) (xy 342.021737 -213.451292)
			(xy 342.067869 -213.427786) (xy 342.117109 -213.411787) (xy 342.168247 -213.403688) (xy 342.220021 -213.403688)
			(xy 342.271159 -213.411787) (xy 342.320399 -213.427786) (xy 342.366531 -213.451292) (xy 342.408418 -213.481724)
			(xy 342.445028 -213.518334) (xy 342.47546 -213.560221) (xy 342.498966 -213.606353) (xy 342.514965 -213.655593)
			(xy 342.523064 -213.706731) (xy 342.523572 -213.732618) (xy 343.744296 -213.732618) (xy 343.744804 -213.706731)
			(xy 343.752903 -213.655593) (xy 343.768902 -213.606353) (xy 343.792408 -213.560221) (xy 343.82284 -213.518334)
			(xy 343.85945 -213.481724) (xy 343.901337 -213.451292) (xy 343.947469 -213.427786) (xy 343.996709 -213.411787)
			(xy 344.047847 -213.403688) (xy 344.099621 -213.403688) (xy 344.150759 -213.411787) (xy 344.199999 -213.427786)
			(xy 344.246131 -213.451292) (xy 344.288018 -213.481724) (xy 344.324628 -213.518334) (xy 344.35506 -213.560221)
			(xy 344.378566 -213.606353) (xy 344.394565 -213.655593) (xy 344.402664 -213.706731) (xy 344.403172 -213.732618)
			(xy 345.623896 -213.732618) (xy 345.624404 -213.706731) (xy 345.632503 -213.655593) (xy 345.648502 -213.606353)
			(xy 345.672008 -213.560221) (xy 345.70244 -213.518334) (xy 345.73905 -213.481724) (xy 345.780937 -213.451292)
			(xy 345.827069 -213.427786) (xy 345.876309 -213.411787) (xy 345.927447 -213.403688) (xy 345.979221 -213.403688)
			(xy 346.030359 -213.411787) (xy 346.079599 -213.427786) (xy 346.125731 -213.451292) (xy 346.167618 -213.481724)
			(xy 346.204228 -213.518334) (xy 346.23466 -213.560221) (xy 346.258166 -213.606353) (xy 346.274165 -213.655593)
			(xy 346.282264 -213.706731) (xy 346.282772 -213.732618) (xy 347.503496 -213.732618) (xy 347.504004 -213.706731)
			(xy 347.512103 -213.655593) (xy 347.528102 -213.606353) (xy 347.551608 -213.560221) (xy 347.58204 -213.518334)
			(xy 347.61865 -213.481724) (xy 347.660537 -213.451292) (xy 347.706669 -213.427786) (xy 347.755909 -213.411787)
			(xy 347.807047 -213.403688) (xy 347.858821 -213.403688) (xy 347.909959 -213.411787) (xy 347.959199 -213.427786)
			(xy 348.005331 -213.451292) (xy 348.047218 -213.481724) (xy 348.083828 -213.518334) (xy 348.11426 -213.560221)
			(xy 348.137766 -213.606353) (xy 348.153765 -213.655593) (xy 348.161864 -213.706731) (xy 348.162372 -213.732618)
			(xy 348.162023 -213.755595) (xy 348.155702 -213.801111) (xy 348.143116 -213.845306) (xy 348.134178 -213.866476)
			(xy 348.124272 -213.888828) (xy 348.337886 -214.293958) (xy 348.362016 -214.29853) (xy 348.38693 -214.303664)
			(xy 348.43494 -214.320459) (xy 348.479799 -214.344434) (xy 348.520441 -214.375017) (xy 348.555899 -214.411484)
			(xy 348.585332 -214.452967) (xy 348.60804 -214.49848) (xy 348.623483 -214.546942) (xy 348.631295 -214.597202)
			(xy 348.631764 -214.622634) (xy 348.631256 -214.648521) (xy 348.623157 -214.699659) (xy 348.607158 -214.748899)
			(xy 348.583652 -214.795031) (xy 348.55322 -214.836918) (xy 348.51661 -214.873528) (xy 348.474723 -214.90396)
			(xy 348.428591 -214.927466) (xy 348.379351 -214.943465) (xy 348.328213 -214.951564) (xy 348.276439 -214.951564)
			(xy 348.225301 -214.943465) (xy 348.176061 -214.927466) (xy 348.129929 -214.90396) (xy 348.088042 -214.873528)
			(xy 348.051432 -214.836918) (xy 348.021 -214.795031) (xy 347.997494 -214.748899) (xy 347.981495 -214.699659)
			(xy 347.973396 -214.648521) (xy 347.972888 -214.622634) (xy 347.973258 -214.599658) (xy 347.97957 -214.554143)
			(xy 347.992148 -214.509947) (xy 348.001082 -214.488776) (xy 348.010988 -214.466424) (xy 347.797374 -214.061294)
			(xy 347.773244 -214.056722) (xy 347.748313 -214.051663) (xy 347.700299 -214.034858) (xy 347.655439 -214.010874)
			(xy 347.614797 -213.980281) (xy 347.579339 -213.943805) (xy 347.549909 -213.902313) (xy 347.527205 -213.856791)
			(xy 347.511767 -213.80832) (xy 347.503962 -213.758053) (xy 347.503496 -213.732618) (xy 346.282772 -213.732618)
			(xy 346.282423 -213.755595) (xy 346.276102 -213.801111) (xy 346.263516 -213.845306) (xy 346.254578 -213.866476)
			(xy 346.244672 -213.888828) (xy 346.458286 -214.293958) (xy 346.482416 -214.29853) (xy 346.50733 -214.303664)
			(xy 346.55534 -214.320459) (xy 346.600199 -214.344434) (xy 346.640841 -214.375017) (xy 346.676299 -214.411484)
			(xy 346.705732 -214.452967) (xy 346.72844 -214.49848) (xy 346.743883 -214.546942) (xy 346.751695 -214.597202)
			(xy 346.752164 -214.622634) (xy 346.751656 -214.648521) (xy 346.743557 -214.699659) (xy 346.727558 -214.748899)
			(xy 346.704052 -214.795031) (xy 346.67362 -214.836918) (xy 346.63701 -214.873528) (xy 346.595123 -214.90396)
			(xy 346.548991 -214.927466) (xy 346.499751 -214.943465) (xy 346.448613 -214.951564) (xy 346.396839 -214.951564)
			(xy 346.345701 -214.943465) (xy 346.296461 -214.927466) (xy 346.250329 -214.90396) (xy 346.208442 -214.873528)
			(xy 346.171832 -214.836918) (xy 346.1414 -214.795031) (xy 346.117894 -214.748899) (xy 346.101895 -214.699659)
			(xy 346.093796 -214.648521) (xy 346.093288 -214.622634) (xy 346.093658 -214.599658) (xy 346.09997 -214.554143)
			(xy 346.112548 -214.509947) (xy 346.121482 -214.488776) (xy 346.131388 -214.466424) (xy 345.917774 -214.061294)
			(xy 345.893644 -214.056722) (xy 345.868713 -214.051663) (xy 345.820699 -214.034858) (xy 345.775839 -214.010874)
			(xy 345.735197 -213.980281) (xy 345.699739 -213.943805) (xy 345.670309 -213.902313) (xy 345.647605 -213.856791)
			(xy 345.632167 -213.80832) (xy 345.624362 -213.758053) (xy 345.623896 -213.732618) (xy 344.403172 -213.732618)
			(xy 344.402823 -213.755595) (xy 344.396502 -213.801111) (xy 344.383916 -213.845306) (xy 344.374978 -213.866476)
			(xy 344.365072 -213.888828) (xy 344.578686 -214.293958) (xy 344.602816 -214.29853) (xy 344.62773 -214.303664)
			(xy 344.67574 -214.320459) (xy 344.720599 -214.344434) (xy 344.761241 -214.375017) (xy 344.796699 -214.411484)
			(xy 344.826132 -214.452967) (xy 344.84884 -214.49848) (xy 344.864283 -214.546942) (xy 344.872095 -214.597202)
			(xy 344.872564 -214.622634) (xy 344.872056 -214.648521) (xy 344.863957 -214.699659) (xy 344.847958 -214.748899)
			(xy 344.824452 -214.795031) (xy 344.79402 -214.836918) (xy 344.75741 -214.873528) (xy 344.715523 -214.90396)
			(xy 344.669391 -214.927466) (xy 344.620151 -214.943465) (xy 344.569013 -214.951564) (xy 344.517239 -214.951564)
			(xy 344.466101 -214.943465) (xy 344.416861 -214.927466) (xy 344.370729 -214.90396) (xy 344.328842 -214.873528)
			(xy 344.292232 -214.836918) (xy 344.2618 -214.795031) (xy 344.238294 -214.748899) (xy 344.222295 -214.699659)
			(xy 344.214196 -214.648521) (xy 344.213688 -214.622634) (xy 344.214058 -214.599658) (xy 344.22037 -214.554143)
			(xy 344.232948 -214.509947) (xy 344.241882 -214.488776) (xy 344.251788 -214.466424) (xy 344.038174 -214.061294)
			(xy 344.014044 -214.056722) (xy 343.989113 -214.051663) (xy 343.941099 -214.034858) (xy 343.896239 -214.010874)
			(xy 343.855597 -213.980281) (xy 343.820139 -213.943805) (xy 343.790709 -213.902313) (xy 343.768005 -213.856791)
			(xy 343.752567 -213.80832) (xy 343.744762 -213.758053) (xy 343.744296 -213.732618) (xy 342.523572 -213.732618)
			(xy 342.523223 -213.755595) (xy 342.516902 -213.801111) (xy 342.504316 -213.845306) (xy 342.495378 -213.866476)
			(xy 342.485472 -213.888828) (xy 342.699086 -214.293958) (xy 342.723216 -214.29853) (xy 342.74813 -214.303664)
			(xy 342.79614 -214.320459) (xy 342.840999 -214.344434) (xy 342.881641 -214.375017) (xy 342.917099 -214.411484)
			(xy 342.946532 -214.452967) (xy 342.96924 -214.49848) (xy 342.984683 -214.546942) (xy 342.992495 -214.597202)
			(xy 342.992964 -214.622634) (xy 342.992456 -214.648521) (xy 342.984357 -214.699659) (xy 342.968358 -214.748899)
			(xy 342.944852 -214.795031) (xy 342.91442 -214.836918) (xy 342.87781 -214.873528) (xy 342.835923 -214.90396)
			(xy 342.789791 -214.927466) (xy 342.740551 -214.943465) (xy 342.689413 -214.951564) (xy 342.637639 -214.951564)
			(xy 342.586501 -214.943465) (xy 342.537261 -214.927466) (xy 342.491129 -214.90396) (xy 342.449242 -214.873528)
			(xy 342.412632 -214.836918) (xy 342.3822 -214.795031) (xy 342.358694 -214.748899) (xy 342.342695 -214.699659)
			(xy 342.334596 -214.648521) (xy 342.334088 -214.622634) (xy 342.334458 -214.599658) (xy 342.34077 -214.554143)
			(xy 342.353348 -214.509947) (xy 342.362282 -214.488776) (xy 342.372188 -214.466424) (xy 342.158574 -214.061294)
			(xy 342.134444 -214.056722) (xy 342.109513 -214.051663) (xy 342.061499 -214.034858) (xy 342.016639 -214.010874)
			(xy 341.975997 -213.980281) (xy 341.940539 -213.943805) (xy 341.911109 -213.902313) (xy 341.888405 -213.856791)
			(xy 341.872967 -213.80832) (xy 341.865162 -213.758053) (xy 341.864696 -213.732618) (xy 340.643972 -213.732618)
			(xy 340.643623 -213.755595) (xy 340.637302 -213.801111) (xy 340.624716 -213.845306) (xy 340.615778 -213.866476)
			(xy 340.605872 -213.888828) (xy 340.819486 -214.293958) (xy 340.843616 -214.29853) (xy 340.86853 -214.303664)
			(xy 340.91654 -214.320459) (xy 340.961399 -214.344434) (xy 341.002041 -214.375017) (xy 341.037499 -214.411484)
			(xy 341.066932 -214.452967) (xy 341.08964 -214.49848) (xy 341.105083 -214.546942) (xy 341.112895 -214.597202)
			(xy 341.113364 -214.622634) (xy 341.112856 -214.648521) (xy 341.104757 -214.699659) (xy 341.088758 -214.748899)
			(xy 341.065252 -214.795031) (xy 341.03482 -214.836918) (xy 340.99821 -214.873528) (xy 340.956323 -214.90396)
			(xy 340.910191 -214.927466) (xy 340.860951 -214.943465) (xy 340.809813 -214.951564) (xy 340.758039 -214.951564)
			(xy 340.706901 -214.943465) (xy 340.657661 -214.927466) (xy 340.611529 -214.90396) (xy 340.569642 -214.873528)
			(xy 340.533032 -214.836918) (xy 340.5026 -214.795031) (xy 340.479094 -214.748899) (xy 340.463095 -214.699659)
			(xy 340.454996 -214.648521) (xy 340.454488 -214.622634) (xy 340.454858 -214.599658) (xy 340.46117 -214.554143)
			(xy 340.473748 -214.509947) (xy 340.482682 -214.488776) (xy 340.492588 -214.466424) (xy 340.278974 -214.061294)
			(xy 340.254844 -214.056722) (xy 340.229913 -214.051663) (xy 340.181899 -214.034858) (xy 340.137039 -214.010874)
			(xy 340.096397 -213.980281) (xy 340.060939 -213.943805) (xy 340.031509 -213.902313) (xy 340.008805 -213.856791)
			(xy 339.993367 -213.80832) (xy 339.985562 -213.758053) (xy 339.985096 -213.732618) (xy 338.764372 -213.732618)
			(xy 338.764023 -213.755595) (xy 338.757702 -213.801111) (xy 338.745116 -213.845306) (xy 338.736178 -213.866476)
			(xy 338.726272 -213.888828) (xy 338.939886 -214.293958) (xy 338.964016 -214.29853) (xy 338.98893 -214.303664)
			(xy 339.03694 -214.320459) (xy 339.081799 -214.344434) (xy 339.122441 -214.375017) (xy 339.157899 -214.411484)
			(xy 339.187332 -214.452967) (xy 339.21004 -214.49848) (xy 339.225483 -214.546942) (xy 339.233295 -214.597202)
			(xy 339.233764 -214.622634) (xy 339.233256 -214.648521) (xy 339.225157 -214.699659) (xy 339.209158 -214.748899)
			(xy 339.185652 -214.795031) (xy 339.15522 -214.836918) (xy 339.11861 -214.873528) (xy 339.076723 -214.90396)
			(xy 339.030591 -214.927466) (xy 338.981351 -214.943465) (xy 338.930213 -214.951564) (xy 338.878439 -214.951564)
			(xy 338.827301 -214.943465) (xy 338.778061 -214.927466) (xy 338.731929 -214.90396) (xy 338.690042 -214.873528)
			(xy 338.653432 -214.836918) (xy 338.623 -214.795031) (xy 338.599494 -214.748899) (xy 338.583495 -214.699659)
			(xy 338.575396 -214.648521) (xy 338.574888 -214.622634) (xy 338.575258 -214.599658) (xy 338.58157 -214.554143)
			(xy 338.594148 -214.509947) (xy 338.603082 -214.488776) (xy 338.612988 -214.466424) (xy 338.399374 -214.061294)
			(xy 338.375244 -214.056722) (xy 338.350313 -214.051663) (xy 338.302299 -214.034858) (xy 338.257439 -214.010874)
			(xy 338.216797 -213.980281) (xy 338.181339 -213.943805) (xy 338.151909 -213.902313) (xy 338.129205 -213.856791)
			(xy 338.113767 -213.80832) (xy 338.105962 -213.758053) (xy 338.105496 -213.732618) (xy 318.57188 -213.732618)
			(xy 318.57188 -215.436704) (xy 336.225388 -215.436704) (xy 336.225896 -215.410797) (xy 336.234002 -215.35962)
			(xy 336.250014 -215.310341) (xy 336.273537 -215.264174) (xy 336.303993 -215.222255) (xy 336.340631 -215.185617)
			(xy 336.38255 -215.155161) (xy 336.428717 -215.131638) (xy 336.477996 -215.115626) (xy 336.529173 -215.10752)
			(xy 336.580987 -215.10752) (xy 336.632164 -215.115626) (xy 336.681443 -215.131638) (xy 336.72761 -215.155161)
			(xy 336.769529 -215.185617) (xy 336.806167 -215.222255) (xy 336.836623 -215.264174) (xy 336.860146 -215.310341)
			(xy 336.876158 -215.35962) (xy 336.884264 -215.410797) (xy 336.884772 -215.436704) (xy 337.165188 -215.436704)
			(xy 337.165723 -215.411361) (xy 337.173493 -215.361274) (xy 337.188837 -215.312966) (xy 337.211392 -215.267575)
			(xy 337.240627 -215.226169) (xy 337.275854 -215.189725) (xy 337.316243 -215.159101) (xy 337.360842 -215.135018)
			(xy 337.408601 -215.118043) (xy 337.433412 -215.112854) (xy 337.456272 -215.108536) (xy 337.66125 -214.753444)
			(xy 337.653376 -214.7316) (xy 337.644799 -214.705181) (xy 337.6356 -214.650406) (xy 337.635088 -214.622634)
			(xy 337.635596 -214.596747) (xy 337.643695 -214.545609) (xy 337.659694 -214.496369) (xy 337.6832 -214.450237)
			(xy 337.713632 -214.40835) (xy 337.750242 -214.37174) (xy 337.792129 -214.341308) (xy 337.838261 -214.317802)
			(xy 337.887501 -214.301803) (xy 337.938639 -214.293704) (xy 337.990413 -214.293704) (xy 338.041551 -214.301803)
			(xy 338.090791 -214.317802) (xy 338.136923 -214.341308) (xy 338.17881 -214.37174) (xy 338.21542 -214.40835)
			(xy 338.245852 -214.450237) (xy 338.269358 -214.496369) (xy 338.285357 -214.545609) (xy 338.293456 -214.596747)
			(xy 338.293964 -214.622634) (xy 338.293541 -214.647971) (xy 338.285783 -214.698047) (xy 338.270454 -214.746347)
			(xy 338.247915 -214.791733) (xy 338.218698 -214.833136) (xy 338.18349 -214.869581) (xy 338.14312 -214.90021)
			(xy 338.098539 -214.924301) (xy 338.050797 -214.941288) (xy 338.025994 -214.946484) (xy 338.003134 -214.950802)
			(xy 337.798156 -215.305894) (xy 337.80603 -215.327738) (xy 337.814677 -215.354146) (xy 337.823997 -215.408922)
			(xy 337.824572 -215.436704) (xy 339.044788 -215.436704) (xy 339.045323 -215.411361) (xy 339.053093 -215.361274)
			(xy 339.068437 -215.312966) (xy 339.090992 -215.267575) (xy 339.120227 -215.226169) (xy 339.155454 -215.189725)
			(xy 339.195843 -215.159101) (xy 339.240442 -215.135018) (xy 339.288201 -215.118043) (xy 339.313012 -215.112854)
			(xy 339.335872 -215.108536) (xy 339.54085 -214.753444) (xy 339.532976 -214.7316) (xy 339.524399 -214.705181)
			(xy 339.5152 -214.650406) (xy 339.514688 -214.622634) (xy 339.515196 -214.596747) (xy 339.523295 -214.545609)
			(xy 339.539294 -214.496369) (xy 339.5628 -214.450237) (xy 339.593232 -214.40835) (xy 339.629842 -214.37174)
			(xy 339.671729 -214.341308) (xy 339.717861 -214.317802) (xy 339.767101 -214.301803) (xy 339.818239 -214.293704)
			(xy 339.870013 -214.293704) (xy 339.921151 -214.301803) (xy 339.970391 -214.317802) (xy 340.016523 -214.341308)
			(xy 340.05841 -214.37174) (xy 340.09502 -214.40835) (xy 340.125452 -214.450237) (xy 340.148958 -214.496369)
			(xy 340.164957 -214.545609) (xy 340.173056 -214.596747) (xy 340.173564 -214.622634) (xy 340.173141 -214.647971)
			(xy 340.165383 -214.698047) (xy 340.150054 -214.746347) (xy 340.127515 -214.791733) (xy 340.098298 -214.833136)
			(xy 340.06309 -214.869581) (xy 340.02272 -214.90021) (xy 339.978139 -214.924301) (xy 339.930397 -214.941288)
			(xy 339.905594 -214.946484) (xy 339.882734 -214.950802) (xy 339.677756 -215.305894) (xy 339.68563 -215.327738)
			(xy 339.694277 -215.354146) (xy 339.703597 -215.408922) (xy 339.704172 -215.436704) (xy 340.924388 -215.436704)
			(xy 340.924923 -215.411361) (xy 340.932693 -215.361274) (xy 340.948037 -215.312966) (xy 340.970592 -215.267575)
			(xy 340.999827 -215.226169) (xy 341.035054 -215.189725) (xy 341.075443 -215.159101) (xy 341.120042 -215.135018)
			(xy 341.167801 -215.118043) (xy 341.192612 -215.112854) (xy 341.215472 -215.108536) (xy 341.42045 -214.753444)
			(xy 341.412576 -214.7316) (xy 341.403999 -214.705181) (xy 341.3948 -214.650406) (xy 341.394288 -214.622634)
			(xy 341.394796 -214.596747) (xy 341.402895 -214.545609) (xy 341.418894 -214.496369) (xy 341.4424 -214.450237)
			(xy 341.472832 -214.40835) (xy 341.509442 -214.37174) (xy 341.551329 -214.341308) (xy 341.597461 -214.317802)
			(xy 341.646701 -214.301803) (xy 341.697839 -214.293704) (xy 341.749613 -214.293704) (xy 341.800751 -214.301803)
			(xy 341.849991 -214.317802) (xy 341.896123 -214.341308) (xy 341.93801 -214.37174) (xy 341.97462 -214.40835)
			(xy 342.005052 -214.450237) (xy 342.028558 -214.496369) (xy 342.044557 -214.545609) (xy 342.052656 -214.596747)
			(xy 342.053164 -214.622634) (xy 342.052741 -214.647971) (xy 342.044983 -214.698047) (xy 342.029654 -214.746347)
			(xy 342.007115 -214.791733) (xy 341.977898 -214.833136) (xy 341.94269 -214.869581) (xy 341.90232 -214.90021)
			(xy 341.857739 -214.924301) (xy 341.809997 -214.941288) (xy 341.785194 -214.946484) (xy 341.762334 -214.950802)
			(xy 341.557356 -215.305894) (xy 341.56523 -215.327738) (xy 341.573877 -215.354146) (xy 341.583197 -215.408922)
			(xy 341.583772 -215.436704) (xy 342.803988 -215.436704) (xy 342.804523 -215.411361) (xy 342.812293 -215.361274)
			(xy 342.827637 -215.312966) (xy 342.850192 -215.267575) (xy 342.879427 -215.226169) (xy 342.914654 -215.189725)
			(xy 342.955043 -215.159101) (xy 342.999642 -215.135018) (xy 343.047401 -215.118043) (xy 343.072212 -215.112854)
			(xy 343.095072 -215.108536) (xy 343.30005 -214.753444) (xy 343.292176 -214.7316) (xy 343.283599 -214.705181)
			(xy 343.2744 -214.650406) (xy 343.273888 -214.622634) (xy 343.274396 -214.596747) (xy 343.282495 -214.545609)
			(xy 343.298494 -214.496369) (xy 343.322 -214.450237) (xy 343.352432 -214.40835) (xy 343.389042 -214.37174)
			(xy 343.430929 -214.341308) (xy 343.477061 -214.317802) (xy 343.526301 -214.301803) (xy 343.577439 -214.293704)
			(xy 343.629213 -214.293704) (xy 343.680351 -214.301803) (xy 343.729591 -214.317802) (xy 343.775723 -214.341308)
			(xy 343.81761 -214.37174) (xy 343.85422 -214.40835) (xy 343.884652 -214.450237) (xy 343.908158 -214.496369)
			(xy 343.924157 -214.545609) (xy 343.932256 -214.596747) (xy 343.932764 -214.622634) (xy 343.932341 -214.647971)
			(xy 343.924583 -214.698047) (xy 343.909254 -214.746347) (xy 343.886715 -214.791733) (xy 343.857498 -214.833136)
			(xy 343.82229 -214.869581) (xy 343.78192 -214.90021) (xy 343.737339 -214.924301) (xy 343.689597 -214.941288)
			(xy 343.664794 -214.946484) (xy 343.641934 -214.950802) (xy 343.436956 -215.305894) (xy 343.44483 -215.327738)
			(xy 343.453477 -215.354146) (xy 343.462797 -215.408922) (xy 343.463372 -215.436704) (xy 344.683588 -215.436704)
			(xy 344.684123 -215.411361) (xy 344.691893 -215.361274) (xy 344.707237 -215.312966) (xy 344.729792 -215.267575)
			(xy 344.759027 -215.226169) (xy 344.794254 -215.189725) (xy 344.834643 -215.159101) (xy 344.879242 -215.135018)
			(xy 344.927001 -215.118043) (xy 344.951812 -215.112854) (xy 344.974672 -215.108536) (xy 345.17965 -214.753444)
			(xy 345.171776 -214.7316) (xy 345.163199 -214.705181) (xy 345.154 -214.650406) (xy 345.153488 -214.622634)
			(xy 345.153996 -214.596747) (xy 345.162095 -214.545609) (xy 345.178094 -214.496369) (xy 345.2016 -214.450237)
			(xy 345.232032 -214.40835) (xy 345.268642 -214.37174) (xy 345.310529 -214.341308) (xy 345.356661 -214.317802)
			(xy 345.405901 -214.301803) (xy 345.457039 -214.293704) (xy 345.508813 -214.293704) (xy 345.559951 -214.301803)
			(xy 345.609191 -214.317802) (xy 345.655323 -214.341308) (xy 345.69721 -214.37174) (xy 345.73382 -214.40835)
			(xy 345.764252 -214.450237) (xy 345.787758 -214.496369) (xy 345.803757 -214.545609) (xy 345.811856 -214.596747)
			(xy 345.812364 -214.622634) (xy 345.811941 -214.647971) (xy 345.804183 -214.698047) (xy 345.788854 -214.746347)
			(xy 345.766315 -214.791733) (xy 345.737098 -214.833136) (xy 345.70189 -214.869581) (xy 345.66152 -214.90021)
			(xy 345.616939 -214.924301) (xy 345.569197 -214.941288) (xy 345.544394 -214.946484) (xy 345.521534 -214.950802)
			(xy 345.316556 -215.305894) (xy 345.32443 -215.327738) (xy 345.333077 -215.354146) (xy 345.342397 -215.408922)
			(xy 345.342972 -215.436704) (xy 346.563188 -215.436704) (xy 346.563723 -215.411361) (xy 346.571493 -215.361274)
			(xy 346.586837 -215.312966) (xy 346.609392 -215.267575) (xy 346.638627 -215.226169) (xy 346.673854 -215.189725)
			(xy 346.714243 -215.159101) (xy 346.758842 -215.135018) (xy 346.806601 -215.118043) (xy 346.831412 -215.112854)
			(xy 346.854272 -215.108536) (xy 347.05925 -214.753444) (xy 347.051376 -214.7316) (xy 347.042799 -214.705181)
			(xy 347.0336 -214.650406) (xy 347.033088 -214.622634) (xy 347.033596 -214.596747) (xy 347.041695 -214.545609)
			(xy 347.057694 -214.496369) (xy 347.0812 -214.450237) (xy 347.111632 -214.40835) (xy 347.148242 -214.37174)
			(xy 347.190129 -214.341308) (xy 347.236261 -214.317802) (xy 347.285501 -214.301803) (xy 347.336639 -214.293704)
			(xy 347.388413 -214.293704) (xy 347.439551 -214.301803) (xy 347.488791 -214.317802) (xy 347.534923 -214.341308)
			(xy 347.57681 -214.37174) (xy 347.61342 -214.40835) (xy 347.643852 -214.450237) (xy 347.667358 -214.496369)
			(xy 347.683357 -214.545609) (xy 347.691456 -214.596747) (xy 347.691964 -214.622634) (xy 347.691541 -214.647971)
			(xy 347.683783 -214.698047) (xy 347.668454 -214.746347) (xy 347.645915 -214.791733) (xy 347.616698 -214.833136)
			(xy 347.58149 -214.869581) (xy 347.54112 -214.90021) (xy 347.496539 -214.924301) (xy 347.448797 -214.941288)
			(xy 347.423994 -214.946484) (xy 347.401134 -214.950802) (xy 347.196156 -215.305894) (xy 347.20403 -215.327738)
			(xy 347.212677 -215.354146) (xy 347.221997 -215.408922) (xy 347.222572 -215.436704) (xy 347.222064 -215.462611)
			(xy 347.213958 -215.513788) (xy 347.197946 -215.563067) (xy 347.174423 -215.609234) (xy 347.143967 -215.651153)
			(xy 347.107329 -215.687791) (xy 347.06541 -215.718247) (xy 347.019243 -215.74177) (xy 346.969964 -215.757782)
			(xy 346.918787 -215.765888) (xy 346.866973 -215.765888) (xy 346.815796 -215.757782) (xy 346.766517 -215.74177)
			(xy 346.72035 -215.718247) (xy 346.678431 -215.687791) (xy 346.641793 -215.651153) (xy 346.611337 -215.609234)
			(xy 346.587814 -215.563067) (xy 346.571802 -215.513788) (xy 346.563696 -215.462611) (xy 346.563188 -215.436704)
			(xy 345.342972 -215.436704) (xy 345.342464 -215.462611) (xy 345.334358 -215.513788) (xy 345.318346 -215.563067)
			(xy 345.294823 -215.609234) (xy 345.264367 -215.651153) (xy 345.227729 -215.687791) (xy 345.18581 -215.718247)
			(xy 345.139643 -215.74177) (xy 345.090364 -215.757782) (xy 345.039187 -215.765888) (xy 344.987373 -215.765888)
			(xy 344.936196 -215.757782) (xy 344.886917 -215.74177) (xy 344.84075 -215.718247) (xy 344.798831 -215.687791)
			(xy 344.762193 -215.651153) (xy 344.731737 -215.609234) (xy 344.708214 -215.563067) (xy 344.692202 -215.513788)
			(xy 344.684096 -215.462611) (xy 344.683588 -215.436704) (xy 343.463372 -215.436704) (xy 343.462864 -215.462611)
			(xy 343.454758 -215.513788) (xy 343.438746 -215.563067) (xy 343.415223 -215.609234) (xy 343.384767 -215.651153)
			(xy 343.348129 -215.687791) (xy 343.30621 -215.718247) (xy 343.260043 -215.74177) (xy 343.210764 -215.757782)
			(xy 343.159587 -215.765888) (xy 343.107773 -215.765888) (xy 343.056596 -215.757782) (xy 343.007317 -215.74177)
			(xy 342.96115 -215.718247) (xy 342.919231 -215.687791) (xy 342.882593 -215.651153) (xy 342.852137 -215.609234)
			(xy 342.828614 -215.563067) (xy 342.812602 -215.513788) (xy 342.804496 -215.462611) (xy 342.803988 -215.436704)
			(xy 341.583772 -215.436704) (xy 341.583264 -215.462611) (xy 341.575158 -215.513788) (xy 341.559146 -215.563067)
			(xy 341.535623 -215.609234) (xy 341.505167 -215.651153) (xy 341.468529 -215.687791) (xy 341.42661 -215.718247)
			(xy 341.380443 -215.74177) (xy 341.331164 -215.757782) (xy 341.279987 -215.765888) (xy 341.228173 -215.765888)
			(xy 341.176996 -215.757782) (xy 341.127717 -215.74177) (xy 341.08155 -215.718247) (xy 341.039631 -215.687791)
			(xy 341.002993 -215.651153) (xy 340.972537 -215.609234) (xy 340.949014 -215.563067) (xy 340.933002 -215.513788)
			(xy 340.924896 -215.462611) (xy 340.924388 -215.436704) (xy 339.704172 -215.436704) (xy 339.703664 -215.462611)
			(xy 339.695558 -215.513788) (xy 339.679546 -215.563067) (xy 339.656023 -215.609234) (xy 339.625567 -215.651153)
			(xy 339.588929 -215.687791) (xy 339.54701 -215.718247) (xy 339.500843 -215.74177) (xy 339.451564 -215.757782)
			(xy 339.400387 -215.765888) (xy 339.348573 -215.765888) (xy 339.297396 -215.757782) (xy 339.248117 -215.74177)
			(xy 339.20195 -215.718247) (xy 339.160031 -215.687791) (xy 339.123393 -215.651153) (xy 339.092937 -215.609234)
			(xy 339.069414 -215.563067) (xy 339.053402 -215.513788) (xy 339.045296 -215.462611) (xy 339.044788 -215.436704)
			(xy 337.824572 -215.436704) (xy 337.824064 -215.462611) (xy 337.815958 -215.513788) (xy 337.799946 -215.563067)
			(xy 337.776423 -215.609234) (xy 337.745967 -215.651153) (xy 337.709329 -215.687791) (xy 337.66741 -215.718247)
			(xy 337.621243 -215.74177) (xy 337.571964 -215.757782) (xy 337.520787 -215.765888) (xy 337.468973 -215.765888)
			(xy 337.417796 -215.757782) (xy 337.368517 -215.74177) (xy 337.32235 -215.718247) (xy 337.280431 -215.687791)
			(xy 337.243793 -215.651153) (xy 337.213337 -215.609234) (xy 337.189814 -215.563067) (xy 337.173802 -215.513788)
			(xy 337.165696 -215.462611) (xy 337.165188 -215.436704) (xy 336.884772 -215.436704) (xy 336.884181 -215.464421)
			(xy 336.874856 -215.519068) (xy 336.86623 -215.545416) (xy 336.858356 -215.567514) (xy 337.063334 -215.922352)
			(xy 337.086194 -215.92667) (xy 337.110997 -215.931858) (xy 337.158737 -215.948846) (xy 337.203315 -215.972939)
			(xy 337.243681 -216.00357) (xy 337.278884 -216.040017) (xy 337.308096 -216.081421) (xy 337.330629 -216.126808)
			(xy 337.345951 -216.175108) (xy 337.353702 -216.225184) (xy 337.354164 -216.25052) (xy 337.353656 -216.276407)
			(xy 337.345557 -216.327545) (xy 337.329558 -216.376785) (xy 337.306052 -216.422917) (xy 337.27562 -216.464804)
			(xy 337.23901 -216.501414) (xy 337.197123 -216.531846) (xy 337.150991 -216.555352) (xy 337.101751 -216.571351)
			(xy 337.050613 -216.57945) (xy 336.998839 -216.57945) (xy 336.947701 -216.571351) (xy 336.898461 -216.555352)
			(xy 336.852329 -216.531846) (xy 336.810442 -216.501414) (xy 336.773832 -216.464804) (xy 336.7434 -216.422917)
			(xy 336.719894 -216.376785) (xy 336.703895 -216.327545) (xy 336.695796 -216.276407) (xy 336.695288 -216.25052)
			(xy 336.695823 -216.222812) (xy 336.705015 -216.168165) (xy 336.713576 -216.141808) (xy 336.72145 -216.11971)
			(xy 336.516472 -215.764872) (xy 336.493612 -215.760554) (xy 336.46879 -215.755389) (xy 336.421007 -215.73844)
			(xy 336.376384 -215.714372) (xy 336.335974 -215.683753) (xy 336.300731 -215.647305) (xy 336.271487 -215.60589)
			(xy 336.248932 -215.560483) (xy 336.233597 -215.512158) (xy 336.225846 -215.462054) (xy 336.225388 -215.436704)
			(xy 318.57188 -215.436704) (xy 318.57188 -217.425016) (xy 319.078102 -217.931238) (xy 336.695796 -217.931238)
			(xy 336.695796 -217.880184) (xy 336.695796 -217.878406) (xy 336.696304 -217.852519) (xy 336.704403 -217.801381)
			(xy 336.720402 -217.752141) (xy 336.743908 -217.706009) (xy 336.77434 -217.664122) (xy 336.81095 -217.627512)
			(xy 336.852837 -217.59708) (xy 336.898969 -217.573574) (xy 336.948209 -217.557575) (xy 336.999347 -217.549476)
			(xy 337.051121 -217.549476) (xy 337.102259 -217.557575) (xy 337.151499 -217.573574) (xy 337.197631 -217.59708)
			(xy 337.239518 -217.627512) (xy 337.276128 -217.664122) (xy 337.30656 -217.706009) (xy 337.330066 -217.752141)
			(xy 337.346065 -217.801381) (xy 337.354164 -217.852519) (xy 337.354672 -217.878406) (xy 337.354672 -217.880184)
			(xy 337.354672 -217.931238) (xy 337.635596 -217.931238) (xy 337.635596 -217.880184) (xy 337.635596 -217.878406)
			(xy 337.636059 -217.85307) (xy 337.643811 -217.802993) (xy 337.659134 -217.754693) (xy 337.681666 -217.709305)
			(xy 337.710877 -217.6679) (xy 337.74608 -217.631451) (xy 337.786444 -217.600818) (xy 337.831021 -217.576721)
			(xy 337.878759 -217.559728) (xy 337.903566 -217.554556) (xy 337.926426 -217.550238) (xy 338.131404 -217.195146)
			(xy 338.12353 -217.173302) (xy 338.114881 -217.146894) (xy 338.105553 -217.092118) (xy 338.104988 -217.064336)
			(xy 338.105496 -217.038429) (xy 338.113602 -216.987252) (xy 338.129614 -216.937973) (xy 338.153137 -216.891806)
			(xy 338.183593 -216.849887) (xy 338.220231 -216.813249) (xy 338.26215 -216.782793) (xy 338.308317 -216.75927)
			(xy 338.357596 -216.743258) (xy 338.408773 -216.735152) (xy 338.460587 -216.735152) (xy 338.511764 -216.743258)
			(xy 338.561043 -216.75927) (xy 338.60721 -216.782793) (xy 338.649129 -216.813249) (xy 338.685767 -216.849887)
			(xy 338.716223 -216.891806) (xy 338.739746 -216.937973) (xy 338.755758 -216.987252) (xy 338.763864 -217.038429)
			(xy 338.764372 -217.064336) (xy 338.763912 -217.089686) (xy 338.756157 -217.139789) (xy 338.740821 -217.188114)
			(xy 338.718265 -217.233519) (xy 338.689022 -217.274935) (xy 338.653781 -217.311384) (xy 338.613373 -217.342006)
			(xy 338.568753 -217.366079) (xy 338.520973 -217.383035) (xy 338.496148 -217.388186) (xy 338.473288 -217.392504)
			(xy 338.26831 -217.747596) (xy 338.276184 -217.76944) (xy 338.284758 -217.79586) (xy 338.293942 -217.850635)
			(xy 338.294472 -217.878406) (xy 338.294472 -217.880184) (xy 338.294472 -217.931238) (xy 338.575396 -217.931238)
			(xy 338.575396 -217.880184) (xy 338.575396 -217.878406) (xy 338.575904 -217.852519) (xy 338.584003 -217.801381)
			(xy 338.600002 -217.752141) (xy 338.623508 -217.706009) (xy 338.65394 -217.664122) (xy 338.69055 -217.627512)
			(xy 338.732437 -217.59708) (xy 338.778569 -217.573574) (xy 338.827809 -217.557575) (xy 338.878947 -217.549476)
			(xy 338.930721 -217.549476) (xy 338.981859 -217.557575) (xy 339.031099 -217.573574) (xy 339.077231 -217.59708)
			(xy 339.119118 -217.627512) (xy 339.155728 -217.664122) (xy 339.18616 -217.706009) (xy 339.209666 -217.752141)
			(xy 339.225665 -217.801381) (xy 339.233764 -217.852519) (xy 339.234272 -217.878406) (xy 339.234272 -217.880184)
			(xy 339.234272 -217.931238) (xy 339.515196 -217.931238) (xy 339.515196 -217.880184) (xy 339.515196 -217.878406)
			(xy 339.515659 -217.85307) (xy 339.523411 -217.802993) (xy 339.538734 -217.754693) (xy 339.561266 -217.709305)
			(xy 339.590477 -217.6679) (xy 339.62568 -217.631451) (xy 339.666044 -217.600818) (xy 339.710621 -217.576721)
			(xy 339.758359 -217.559728) (xy 339.783166 -217.554556) (xy 339.806026 -217.550238) (xy 340.011004 -217.195146)
			(xy 340.00313 -217.173302) (xy 339.994481 -217.146894) (xy 339.985153 -217.092118) (xy 339.984588 -217.064336)
			(xy 339.985096 -217.038429) (xy 339.993202 -216.987252) (xy 340.009214 -216.937973) (xy 340.032737 -216.891806)
			(xy 340.063193 -216.849887) (xy 340.099831 -216.813249) (xy 340.14175 -216.782793) (xy 340.187917 -216.75927)
			(xy 340.237196 -216.743258) (xy 340.288373 -216.735152) (xy 340.340187 -216.735152) (xy 340.391364 -216.743258)
			(xy 340.440643 -216.75927) (xy 340.48681 -216.782793) (xy 340.528729 -216.813249) (xy 340.565367 -216.849887)
			(xy 340.595823 -216.891806) (xy 340.619346 -216.937973) (xy 340.635358 -216.987252) (xy 340.643464 -217.038429)
			(xy 340.643972 -217.064336) (xy 340.643512 -217.089686) (xy 340.635757 -217.139789) (xy 340.620421 -217.188114)
			(xy 340.597865 -217.233519) (xy 340.568622 -217.274935) (xy 340.533381 -217.311384) (xy 340.492973 -217.342006)
			(xy 340.448353 -217.366079) (xy 340.400573 -217.383035) (xy 340.375748 -217.388186) (xy 340.352888 -217.392504)
			(xy 340.14791 -217.747596) (xy 340.155784 -217.76944) (xy 340.164358 -217.79586) (xy 340.173542 -217.850635)
			(xy 340.174072 -217.878406) (xy 340.174072 -217.880184) (xy 340.174072 -217.931238) (xy 340.454996 -217.931238)
			(xy 340.454996 -217.880184) (xy 340.454996 -217.878406) (xy 340.455504 -217.852519) (xy 340.463603 -217.801381)
			(xy 340.479602 -217.752141) (xy 340.503108 -217.706009) (xy 340.53354 -217.664122) (xy 340.57015 -217.627512)
			(xy 340.612037 -217.59708) (xy 340.658169 -217.573574) (xy 340.707409 -217.557575) (xy 340.758547 -217.549476)
			(xy 340.810321 -217.549476) (xy 340.861459 -217.557575) (xy 340.910699 -217.573574) (xy 340.956831 -217.59708)
			(xy 340.998718 -217.627512) (xy 341.035328 -217.664122) (xy 341.06576 -217.706009) (xy 341.089266 -217.752141)
			(xy 341.105265 -217.801381) (xy 341.113364 -217.852519) (xy 341.113872 -217.878406) (xy 341.113872 -217.880184)
			(xy 341.113872 -217.931238) (xy 341.394796 -217.931238) (xy 341.394796 -217.880184) (xy 341.394796 -217.878406)
			(xy 341.395259 -217.85307) (xy 341.403011 -217.802993) (xy 341.418334 -217.754693) (xy 341.440866 -217.709305)
			(xy 341.470077 -217.6679) (xy 341.50528 -217.631451) (xy 341.545644 -217.600818) (xy 341.590221 -217.576721)
			(xy 341.637959 -217.559728) (xy 341.662766 -217.554556) (xy 341.685626 -217.550238) (xy 341.890604 -217.195146)
			(xy 341.88273 -217.173302) (xy 341.874081 -217.146894) (xy 341.864753 -217.092118) (xy 341.864188 -217.064336)
			(xy 341.864696 -217.038429) (xy 341.872802 -216.987252) (xy 341.888814 -216.937973) (xy 341.912337 -216.891806)
			(xy 341.942793 -216.849887) (xy 341.979431 -216.813249) (xy 342.02135 -216.782793) (xy 342.067517 -216.75927)
			(xy 342.116796 -216.743258) (xy 342.167973 -216.735152) (xy 342.219787 -216.735152) (xy 342.270964 -216.743258)
			(xy 342.320243 -216.75927) (xy 342.36641 -216.782793) (xy 342.408329 -216.813249) (xy 342.444967 -216.849887)
			(xy 342.475423 -216.891806) (xy 342.498946 -216.937973) (xy 342.514958 -216.987252) (xy 342.523064 -217.038429)
			(xy 342.523572 -217.064336) (xy 342.523112 -217.089686) (xy 342.515357 -217.139789) (xy 342.500021 -217.188114)
			(xy 342.477465 -217.233519) (xy 342.448222 -217.274935) (xy 342.412981 -217.311384) (xy 342.372573 -217.342006)
			(xy 342.327953 -217.366079) (xy 342.280173 -217.383035) (xy 342.255348 -217.388186) (xy 342.232488 -217.392504)
			(xy 342.02751 -217.747596) (xy 342.035384 -217.76944) (xy 342.043958 -217.79586) (xy 342.053142 -217.850635)
			(xy 342.053672 -217.878406) (xy 342.053672 -217.880184) (xy 342.053672 -217.931238) (xy 342.334596 -217.931238)
			(xy 342.334596 -217.880184) (xy 342.334596 -217.878406) (xy 342.335104 -217.852519) (xy 342.343203 -217.801381)
			(xy 342.359202 -217.752141) (xy 342.382708 -217.706009) (xy 342.41314 -217.664122) (xy 342.44975 -217.627512)
			(xy 342.491637 -217.59708) (xy 342.537769 -217.573574) (xy 342.587009 -217.557575) (xy 342.638147 -217.549476)
			(xy 342.689921 -217.549476) (xy 342.741059 -217.557575) (xy 342.790299 -217.573574) (xy 342.836431 -217.59708)
			(xy 342.878318 -217.627512) (xy 342.914928 -217.664122) (xy 342.94536 -217.706009) (xy 342.968866 -217.752141)
			(xy 342.984865 -217.801381) (xy 342.992964 -217.852519) (xy 342.993472 -217.878406) (xy 343.274396 -217.878406)
			(xy 343.274888 -217.853072) (xy 343.282639 -217.803) (xy 343.29796 -217.754704) (xy 343.320491 -217.70932)
			(xy 343.349699 -217.667918) (xy 343.384899 -217.631473) (xy 343.42526 -217.600842) (xy 343.469833 -217.576747)
			(xy 343.517567 -217.559756) (xy 343.542366 -217.554556) (xy 343.565226 -217.550238) (xy 343.770204 -217.195146)
			(xy 343.76233 -217.173302) (xy 343.753691 -217.146892) (xy 343.744367 -217.092117) (xy 343.743788 -217.064336)
			(xy 343.744296 -217.038429) (xy 343.752402 -216.987252) (xy 343.768414 -216.937973) (xy 343.791937 -216.891806)
			(xy 343.822393 -216.849887) (xy 343.859031 -216.813249) (xy 343.90095 -216.782793) (xy 343.947117 -216.75927)
			(xy 343.996396 -216.743258) (xy 344.047573 -216.735152) (xy 344.099387 -216.735152) (xy 344.150564 -216.743258)
			(xy 344.199843 -216.75927) (xy 344.24601 -216.782793) (xy 344.287929 -216.813249) (xy 344.324567 -216.849887)
			(xy 344.355023 -216.891806) (xy 344.378546 -216.937973) (xy 344.394558 -216.987252) (xy 344.402664 -217.038429)
			(xy 344.403172 -217.064336) (xy 344.402706 -217.089682) (xy 344.394928 -217.139773) (xy 344.379577 -217.188085)
			(xy 344.357013 -217.233478) (xy 344.327769 -217.274884) (xy 344.292534 -217.311328) (xy 344.252136 -217.34195)
			(xy 344.207529 -217.36603) (xy 344.159762 -217.383) (xy 344.134948 -217.388186) (xy 344.112088 -217.392504)
			(xy 343.90711 -217.747596) (xy 343.914984 -217.76944) (xy 343.923573 -217.795856) (xy 343.932763 -217.850633)
			(xy 343.933272 -217.878406) (xy 344.214196 -217.878406) (xy 344.214704 -217.852519) (xy 344.222803 -217.801381)
			(xy 344.238802 -217.752141) (xy 344.262308 -217.706009) (xy 344.29274 -217.664122) (xy 344.32935 -217.627512)
			(xy 344.371237 -217.59708) (xy 344.417369 -217.573574) (xy 344.466609 -217.557575) (xy 344.517747 -217.549476)
			(xy 344.569521 -217.549476) (xy 344.620659 -217.557575) (xy 344.669899 -217.573574) (xy 344.716031 -217.59708)
			(xy 344.757918 -217.627512) (xy 344.794528 -217.664122) (xy 344.82496 -217.706009) (xy 344.848466 -217.752141)
			(xy 344.864465 -217.801381) (xy 344.872564 -217.852519) (xy 344.873072 -217.878406) (xy 345.153996 -217.878406)
			(xy 345.154488 -217.853072) (xy 345.162239 -217.803) (xy 345.17756 -217.754704) (xy 345.200091 -217.70932)
			(xy 345.229299 -217.667918) (xy 345.264499 -217.631473) (xy 345.30486 -217.600842) (xy 345.349433 -217.576747)
			(xy 345.397167 -217.559756) (xy 345.421966 -217.554556) (xy 345.444826 -217.550238) (xy 345.649804 -217.195146)
			(xy 345.64193 -217.173302) (xy 345.633291 -217.146892) (xy 345.623967 -217.092117) (xy 345.623388 -217.064336)
			(xy 345.623896 -217.038429) (xy 345.632002 -216.987252) (xy 345.648014 -216.937973) (xy 345.671537 -216.891806)
			(xy 345.701993 -216.849887) (xy 345.738631 -216.813249) (xy 345.78055 -216.782793) (xy 345.826717 -216.75927)
			(xy 345.875996 -216.743258) (xy 345.927173 -216.735152) (xy 345.978987 -216.735152) (xy 346.030164 -216.743258)
			(xy 346.079443 -216.75927) (xy 346.12561 -216.782793) (xy 346.167529 -216.813249) (xy 346.204167 -216.849887)
			(xy 346.234623 -216.891806) (xy 346.258146 -216.937973) (xy 346.274158 -216.987252) (xy 346.282264 -217.038429)
			(xy 346.282772 -217.064336) (xy 346.282306 -217.089682) (xy 346.274528 -217.139773) (xy 346.259177 -217.188085)
			(xy 346.236613 -217.233478) (xy 346.207369 -217.274884) (xy 346.172134 -217.311328) (xy 346.131736 -217.34195)
			(xy 346.087129 -217.36603) (xy 346.039362 -217.383) (xy 346.014548 -217.388186) (xy 345.991688 -217.392504)
			(xy 345.78671 -217.747596) (xy 345.794584 -217.76944) (xy 345.803173 -217.795856) (xy 345.812363 -217.850633)
			(xy 345.812872 -217.878406) (xy 346.093796 -217.878406) (xy 346.094304 -217.852519) (xy 346.102403 -217.801381)
			(xy 346.118402 -217.752141) (xy 346.141908 -217.706009) (xy 346.17234 -217.664122) (xy 346.20895 -217.627512)
			(xy 346.250837 -217.59708) (xy 346.296969 -217.573574) (xy 346.346209 -217.557575) (xy 346.397347 -217.549476)
			(xy 346.449121 -217.549476) (xy 346.500259 -217.557575) (xy 346.549499 -217.573574) (xy 346.595631 -217.59708)
			(xy 346.637518 -217.627512) (xy 346.674128 -217.664122) (xy 346.70456 -217.706009) (xy 346.728066 -217.752141)
			(xy 346.744065 -217.801381) (xy 346.752164 -217.852519) (xy 346.752672 -217.878406) (xy 347.033596 -217.878406)
			(xy 347.034088 -217.853072) (xy 347.041839 -217.803) (xy 347.05716 -217.754704) (xy 347.079691 -217.70932)
			(xy 347.108899 -217.667918) (xy 347.144099 -217.631473) (xy 347.18446 -217.600842) (xy 347.229033 -217.576747)
			(xy 347.276767 -217.559756) (xy 347.301566 -217.554556) (xy 347.324426 -217.550238) (xy 347.529404 -217.195146)
			(xy 347.52153 -217.173302) (xy 347.512891 -217.146892) (xy 347.503567 -217.092117) (xy 347.502988 -217.064336)
			(xy 347.503496 -217.038429) (xy 347.511602 -216.987252) (xy 347.527614 -216.937973) (xy 347.551137 -216.891806)
			(xy 347.581593 -216.849887) (xy 347.618231 -216.813249) (xy 347.66015 -216.782793) (xy 347.706317 -216.75927)
			(xy 347.755596 -216.743258) (xy 347.806773 -216.735152) (xy 347.858587 -216.735152) (xy 347.909764 -216.743258)
			(xy 347.959043 -216.75927) (xy 348.00521 -216.782793) (xy 348.047129 -216.813249) (xy 348.083767 -216.849887)
			(xy 348.114223 -216.891806) (xy 348.137746 -216.937973) (xy 348.153758 -216.987252) (xy 348.161864 -217.038429)
			(xy 348.162372 -217.064336) (xy 348.161906 -217.089682) (xy 348.154128 -217.139773) (xy 348.138777 -217.188085)
			(xy 348.116213 -217.233478) (xy 348.086969 -217.274884) (xy 348.051734 -217.311328) (xy 348.011336 -217.34195)
			(xy 347.966729 -217.36603) (xy 347.918962 -217.383) (xy 347.894148 -217.388186) (xy 347.871288 -217.392504)
			(xy 347.66631 -217.747596) (xy 347.674184 -217.76944) (xy 347.682773 -217.795856) (xy 347.691963 -217.850633)
			(xy 347.692472 -217.878406) (xy 347.691964 -217.904293) (xy 347.683865 -217.955431) (xy 347.667866 -218.004671)
			(xy 347.64436 -218.050803) (xy 347.613928 -218.09269) (xy 347.577318 -218.1293) (xy 347.535431 -218.159732)
			(xy 347.489299 -218.183238) (xy 347.440059 -218.199237) (xy 347.388921 -218.207336) (xy 347.337147 -218.207336)
			(xy 347.286009 -218.199237) (xy 347.236769 -218.183238) (xy 347.190637 -218.159732) (xy 347.14875 -218.1293)
			(xy 347.11214 -218.09269) (xy 347.081708 -218.050803) (xy 347.058202 -218.004671) (xy 347.042203 -217.955431)
			(xy 347.034104 -217.904293) (xy 347.033596 -217.878406) (xy 346.752672 -217.878406) (xy 346.752141 -217.906114)
			(xy 346.742946 -217.960761) (xy 346.734384 -217.987118) (xy 346.72651 -218.009216) (xy 346.931488 -218.364054)
			(xy 346.954348 -218.368372) (xy 346.979163 -218.373563) (xy 347.026941 -218.390515) (xy 347.071559 -218.414584)
			(xy 347.111965 -218.445202) (xy 347.147206 -218.481645) (xy 347.17645 -218.523056) (xy 347.199009 -218.568456)
			(xy 347.214349 -218.616776) (xy 347.222108 -218.666874) (xy 347.222572 -218.692222) (xy 347.222064 -218.718129)
			(xy 347.213958 -218.769306) (xy 347.197946 -218.818585) (xy 347.174423 -218.864752) (xy 347.143967 -218.906671)
			(xy 347.107329 -218.943309) (xy 347.06541 -218.973765) (xy 347.019243 -218.997288) (xy 346.969964 -219.0133)
			(xy 346.918787 -219.021406) (xy 346.866973 -219.021406) (xy 346.815796 -219.0133) (xy 346.766517 -218.997288)
			(xy 346.72035 -218.973765) (xy 346.678431 -218.943309) (xy 346.641793 -218.906671) (xy 346.611337 -218.864752)
			(xy 346.587814 -218.818585) (xy 346.571802 -218.769306) (xy 346.563696 -218.718129) (xy 346.563188 -218.692222)
			(xy 346.563788 -218.664505) (xy 346.573107 -218.609859) (xy 346.58173 -218.58351) (xy 346.589604 -218.561412)
			(xy 346.384626 -218.206574) (xy 346.361766 -218.202256) (xy 346.336962 -218.197073) (xy 346.289224 -218.180081)
			(xy 346.244649 -218.155985) (xy 346.204284 -218.125353) (xy 346.169082 -218.088906) (xy 346.13987 -218.047502)
			(xy 346.117337 -218.002116) (xy 346.102013 -217.953817) (xy 346.09426 -217.903742) (xy 346.093796 -217.878406)
			(xy 345.812872 -217.878406) (xy 345.812364 -217.904293) (xy 345.804265 -217.955431) (xy 345.788266 -218.004671)
			(xy 345.76476 -218.050803) (xy 345.734328 -218.09269) (xy 345.697718 -218.1293) (xy 345.655831 -218.159732)
			(xy 345.609699 -218.183238) (xy 345.560459 -218.199237) (xy 345.509321 -218.207336) (xy 345.457547 -218.207336)
			(xy 345.406409 -218.199237) (xy 345.357169 -218.183238) (xy 345.311037 -218.159732) (xy 345.26915 -218.1293)
			(xy 345.23254 -218.09269) (xy 345.202108 -218.050803) (xy 345.178602 -218.004671) (xy 345.162603 -217.955431)
			(xy 345.154504 -217.904293) (xy 345.153996 -217.878406) (xy 344.873072 -217.878406) (xy 344.872541 -217.906114)
			(xy 344.863346 -217.960761) (xy 344.854784 -217.987118) (xy 344.84691 -218.009216) (xy 345.051888 -218.364054)
			(xy 345.074748 -218.368372) (xy 345.099563 -218.373563) (xy 345.147341 -218.390515) (xy 345.191959 -218.414584)
			(xy 345.232365 -218.445202) (xy 345.267606 -218.481645) (xy 345.29685 -218.523056) (xy 345.319409 -218.568456)
			(xy 345.334749 -218.616776) (xy 345.342508 -218.666874) (xy 345.342972 -218.692222) (xy 345.342464 -218.718129)
			(xy 345.334358 -218.769306) (xy 345.318346 -218.818585) (xy 345.294823 -218.864752) (xy 345.264367 -218.906671)
			(xy 345.227729 -218.943309) (xy 345.18581 -218.973765) (xy 345.139643 -218.997288) (xy 345.090364 -219.0133)
			(xy 345.039187 -219.021406) (xy 344.987373 -219.021406) (xy 344.936196 -219.0133) (xy 344.886917 -218.997288)
			(xy 344.84075 -218.973765) (xy 344.798831 -218.943309) (xy 344.762193 -218.906671) (xy 344.731737 -218.864752)
			(xy 344.708214 -218.818585) (xy 344.692202 -218.769306) (xy 344.684096 -218.718129) (xy 344.683588 -218.692222)
			(xy 344.684188 -218.664505) (xy 344.693507 -218.609859) (xy 344.70213 -218.58351) (xy 344.710004 -218.561412)
			(xy 344.505026 -218.206574) (xy 344.482166 -218.202256) (xy 344.457362 -218.197073) (xy 344.409624 -218.180081)
			(xy 344.365049 -218.155985) (xy 344.324684 -218.125353) (xy 344.289482 -218.088906) (xy 344.26027 -218.047502)
			(xy 344.237737 -218.002116) (xy 344.222413 -217.953817) (xy 344.21466 -217.903742) (xy 344.214196 -217.878406)
			(xy 343.933272 -217.878406) (xy 343.932764 -217.904293) (xy 343.924665 -217.955431) (xy 343.908666 -218.004671)
			(xy 343.88516 -218.050803) (xy 343.854728 -218.09269) (xy 343.818118 -218.1293) (xy 343.776231 -218.159732)
			(xy 343.730099 -218.183238) (xy 343.680859 -218.199237) (xy 343.629721 -218.207336) (xy 343.577947 -218.207336)
			(xy 343.526809 -218.199237) (xy 343.477569 -218.183238) (xy 343.431437 -218.159732) (xy 343.38955 -218.1293)
			(xy 343.35294 -218.09269) (xy 343.322508 -218.050803) (xy 343.299002 -218.004671) (xy 343.283003 -217.955431)
			(xy 343.274904 -217.904293) (xy 343.274396 -217.878406) (xy 342.993472 -217.878406) (xy 342.992942 -217.906114)
			(xy 342.983742 -217.960759) (xy 342.975184 -217.987118) (xy 342.96731 -218.009216) (xy 343.172288 -218.364054)
			(xy 343.195148 -218.368372) (xy 343.21996 -218.373559) (xy 343.267723 -218.39053) (xy 343.312326 -218.414611)
			(xy 343.352718 -218.445234) (xy 343.387948 -218.481679) (xy 343.417185 -218.523085) (xy 343.439741 -218.568478)
			(xy 343.455084 -218.616789) (xy 343.462853 -218.666878) (xy 343.463372 -218.692222) (xy 343.46261 -218.712288)
			(xy 343.46134 -218.735148) (xy 344.796364 -220.070172) (xy 344.831162 -220.047058) (xy 344.851501 -220.033962)
			(xy 344.895215 -220.013251) (xy 344.941499 -219.99919) (xy 344.989348 -219.992085) (xy 345.013534 -219.991686)
			(xy 345.039321 -219.992194) (xy 345.09026 -220.000266) (xy 345.139309 -220.016206) (xy 345.185262 -220.039622)
			(xy 345.226986 -220.069937) (xy 345.263455 -220.106405) (xy 345.293772 -220.148128) (xy 345.317189 -220.19408)
			(xy 345.333131 -220.243128) (xy 345.341205 -220.294067) (xy 345.341702 -220.319854) (xy 345.341168 -220.347112)
			(xy 345.332173 -220.400882) (xy 345.314422 -220.452427) (xy 345.288403 -220.500334) (xy 345.25483 -220.543286)
			(xy 345.214625 -220.580104) (xy 345.168892 -220.609778) (xy 345.14409 -220.621098) (xy 345.113356 -220.634306)
			(xy 345.113356 -220.796612) (xy 345.113837 -220.810874) (xy 345.121733 -220.838283) (xy 345.136906 -220.862436)
			(xy 345.15817 -220.881448) (xy 345.183864 -220.893833) (xy 345.211983 -220.898624) (xy 345.240329 -220.895448)
			(xy 345.266689 -220.884551) (xy 345.278202 -220.876114) (xy 345.299356 -220.859905) (xy 345.345826 -220.833822)
			(xy 345.395886 -220.815553) (xy 345.421966 -220.810074) (xy 345.444826 -220.805756) (xy 345.649804 -220.450664)
			(xy 345.64193 -220.42882) (xy 345.633287 -220.402411) (xy 345.623973 -220.347635) (xy 345.623388 -220.319854)
			(xy 345.623896 -220.293947) (xy 345.632002 -220.24277) (xy 345.648014 -220.193491) (xy 345.671537 -220.147324)
			(xy 345.701993 -220.105405) (xy 345.738631 -220.068767) (xy 345.78055 -220.038311) (xy 345.826717 -220.014788)
			(xy 345.875996 -219.998776) (xy 345.927173 -219.99067) (xy 345.978987 -219.99067) (xy 346.030164 -219.998776)
			(xy 346.079443 -220.014788) (xy 346.12561 -220.038311) (xy 346.167529 -220.068767) (xy 346.204167 -220.105405)
			(xy 346.234623 -220.147324) (xy 346.258146 -220.193491) (xy 346.274158 -220.24277) (xy 346.282264 -220.293947)
			(xy 346.282772 -220.319854) (xy 346.28231 -220.345203) (xy 346.274553 -220.395304) (xy 346.259216 -220.443627)
			(xy 346.236659 -220.48903) (xy 346.207415 -220.530444) (xy 346.172174 -220.56689) (xy 346.131767 -220.59751)
			(xy 346.087148 -220.621582) (xy 346.039369 -220.638536) (xy 346.014548 -220.643704) (xy 345.991688 -220.648022)
			(xy 345.78671 -221.003114) (xy 345.794584 -221.024958) (xy 345.803164 -221.051377) (xy 345.812362 -221.106152)
			(xy 345.812872 -221.133924) (xy 346.093796 -221.133924) (xy 346.094304 -221.108037) (xy 346.102403 -221.056899)
			(xy 346.118402 -221.007659) (xy 346.141908 -220.961527) (xy 346.17234 -220.91964) (xy 346.20895 -220.88303)
			(xy 346.250837 -220.852598) (xy 346.296969 -220.829092) (xy 346.346209 -220.813093) (xy 346.397347 -220.804994)
			(xy 346.449121 -220.804994) (xy 346.500259 -220.813093) (xy 346.549499 -220.829092) (xy 346.595631 -220.852598)
			(xy 346.637518 -220.88303) (xy 346.674128 -220.91964) (xy 346.70456 -220.961527) (xy 346.728066 -221.007659)
			(xy 346.744065 -221.056899) (xy 346.752164 -221.108037) (xy 346.752672 -221.133924) (xy 347.033596 -221.133924)
			(xy 347.034104 -221.10859) (xy 347.041853 -221.058519) (xy 347.057172 -221.010223) (xy 347.0797 -220.96484)
			(xy 347.108906 -220.923438) (xy 347.144104 -220.886992) (xy 347.184463 -220.856361) (xy 347.229034 -220.832266)
			(xy 347.276767 -220.815274) (xy 347.301566 -220.810074) (xy 347.324426 -220.805756) (xy 347.529404 -220.450664)
			(xy 347.52153 -220.42882) (xy 347.512896 -220.402408) (xy 347.503568 -220.347635) (xy 347.502988 -220.319854)
			(xy 347.503496 -220.293947) (xy 347.511602 -220.24277) (xy 347.527614 -220.193491) (xy 347.551137 -220.147324)
			(xy 347.581593 -220.105405) (xy 347.618231 -220.068767) (xy 347.66015 -220.038311) (xy 347.706317 -220.014788)
			(xy 347.755596 -219.998776) (xy 347.806773 -219.99067) (xy 347.858587 -219.99067) (xy 347.909764 -219.998776)
			(xy 347.959043 -220.014788) (xy 348.00521 -220.038311) (xy 348.047129 -220.068767) (xy 348.083767 -220.105405)
			(xy 348.114223 -220.147324) (xy 348.137746 -220.193491) (xy 348.153758 -220.24277) (xy 348.161864 -220.293947)
			(xy 348.162372 -220.319854) (xy 348.161922 -220.3452) (xy 348.154142 -220.395293) (xy 348.138788 -220.443604)
			(xy 348.116222 -220.488998) (xy 348.086976 -220.530404) (xy 348.051739 -220.566847) (xy 348.01134 -220.597469)
			(xy 347.966731 -220.621548) (xy 347.918963 -220.638518) (xy 347.894148 -220.643704) (xy 347.871288 -220.648022)
			(xy 347.66631 -221.003114) (xy 347.674184 -221.024958) (xy 347.682777 -221.051373) (xy 347.691965 -221.106151)
			(xy 347.692472 -221.133924) (xy 347.973396 -221.133924) (xy 347.973904 -221.108037) (xy 347.982003 -221.056899)
			(xy 347.998002 -221.007659) (xy 348.021508 -220.961527) (xy 348.05194 -220.91964) (xy 348.08855 -220.88303)
			(xy 348.130437 -220.852598) (xy 348.176569 -220.829092) (xy 348.225809 -220.813093) (xy 348.276947 -220.804994)
			(xy 348.328721 -220.804994) (xy 348.379859 -220.813093) (xy 348.429099 -220.829092) (xy 348.475231 -220.852598)
			(xy 348.517118 -220.88303) (xy 348.553728 -220.91964) (xy 348.58416 -220.961527) (xy 348.607666 -221.007659)
			(xy 348.623665 -221.056899) (xy 348.631764 -221.108037) (xy 348.632272 -221.133924) (xy 348.631745 -221.161632)
			(xy 348.622548 -221.216279) (xy 348.613984 -221.242636) (xy 348.60611 -221.264734) (xy 348.811088 -221.619572)
			(xy 348.833948 -221.62389) (xy 348.858767 -221.629064) (xy 348.906546 -221.646018) (xy 348.951165 -221.670088)
			(xy 348.991572 -221.700708) (xy 349.026813 -221.737154) (xy 349.056057 -221.778566) (xy 349.078614 -221.823969)
			(xy 349.093952 -221.872291) (xy 349.10171 -221.922391) (xy 349.102172 -221.94774) (xy 349.101664 -221.973647)
			(xy 349.093558 -222.024824) (xy 349.077546 -222.074103) (xy 349.054023 -222.12027) (xy 349.023567 -222.162189)
			(xy 348.986929 -222.198827) (xy 348.94501 -222.229283) (xy 348.898843 -222.252806) (xy 348.849564 -222.268818)
			(xy 348.798387 -222.276924) (xy 348.746573 -222.276924) (xy 348.695396 -222.268818) (xy 348.646117 -222.252806)
			(xy 348.59995 -222.229283) (xy 348.558031 -222.198827) (xy 348.521393 -222.162189) (xy 348.490937 -222.12027)
			(xy 348.467414 -222.074103) (xy 348.451402 -222.024824) (xy 348.443296 -221.973647) (xy 348.442788 -221.94774)
			(xy 348.443392 -221.920023) (xy 348.452709 -221.865377) (xy 348.46133 -221.839028) (xy 348.469204 -221.81693)
			(xy 348.264226 -221.462092) (xy 348.241366 -221.457774) (xy 348.216566 -221.452574) (xy 348.16883 -221.435583)
			(xy 348.124255 -221.411489) (xy 348.083891 -221.380859) (xy 348.048689 -221.344414) (xy 348.019476 -221.303012)
			(xy 347.996942 -221.257629) (xy 347.981617 -221.209332) (xy 347.973861 -221.159259) (xy 347.973396 -221.133924)
			(xy 347.692472 -221.133924) (xy 347.691964 -221.159811) (xy 347.683865 -221.210949) (xy 347.667866 -221.260189)
			(xy 347.64436 -221.306321) (xy 347.613928 -221.348208) (xy 347.577318 -221.384818) (xy 347.535431 -221.41525)
			(xy 347.489299 -221.438756) (xy 347.440059 -221.454755) (xy 347.388921 -221.462854) (xy 347.337147 -221.462854)
			(xy 347.286009 -221.454755) (xy 347.236769 -221.438756) (xy 347.190637 -221.41525) (xy 347.14875 -221.384818)
			(xy 347.11214 -221.348208) (xy 347.081708 -221.306321) (xy 347.058202 -221.260189) (xy 347.042203 -221.210949)
			(xy 347.034104 -221.159811) (xy 347.033596 -221.133924) (xy 346.752672 -221.133924) (xy 346.752145 -221.161632)
			(xy 346.742948 -221.216279) (xy 346.734384 -221.242636) (xy 346.72651 -221.264734) (xy 346.931488 -221.619572)
			(xy 346.954348 -221.62389) (xy 346.979167 -221.629064) (xy 347.026946 -221.646018) (xy 347.071565 -221.670088)
			(xy 347.111972 -221.700708) (xy 347.147213 -221.737154) (xy 347.176457 -221.778566) (xy 347.199014 -221.823969)
			(xy 347.214352 -221.872291) (xy 347.22211 -221.922391) (xy 347.222572 -221.94774) (xy 347.222064 -221.973647)
			(xy 347.213958 -222.024824) (xy 347.197946 -222.074103) (xy 347.174423 -222.12027) (xy 347.143967 -222.162189)
			(xy 347.107329 -222.198827) (xy 347.06541 -222.229283) (xy 347.019243 -222.252806) (xy 346.969964 -222.268818)
			(xy 346.918787 -222.276924) (xy 346.866973 -222.276924) (xy 346.815796 -222.268818) (xy 346.766517 -222.252806)
			(xy 346.72035 -222.229283) (xy 346.678431 -222.198827) (xy 346.641793 -222.162189) (xy 346.611337 -222.12027)
			(xy 346.587814 -222.074103) (xy 346.571802 -222.024824) (xy 346.563696 -221.973647) (xy 346.563188 -221.94774)
			(xy 346.563792 -221.920023) (xy 346.573109 -221.865377) (xy 346.58173 -221.839028) (xy 346.589604 -221.81693)
			(xy 346.384626 -221.462092) (xy 346.361766 -221.457774) (xy 346.336966 -221.452574) (xy 346.28923 -221.435583)
			(xy 346.244655 -221.411489) (xy 346.204291 -221.380859) (xy 346.169089 -221.344414) (xy 346.139876 -221.303012)
			(xy 346.117342 -221.257629) (xy 346.102017 -221.209332) (xy 346.094261 -221.159259) (xy 346.093796 -221.133924)
			(xy 345.812872 -221.133924) (xy 345.812363 -221.159817) (xy 345.804262 -221.210965) (xy 345.788263 -221.260218)
			(xy 345.764761 -221.306363) (xy 345.734332 -221.348266) (xy 345.697725 -221.384895) (xy 345.655842 -221.415351)
			(xy 345.609712 -221.438883) (xy 345.560469 -221.454913) (xy 345.509326 -221.463046) (xy 345.483434 -221.463616)
			(xy 345.455717 -221.463024) (xy 345.40107 -221.453707) (xy 345.348753 -221.435379) (xy 345.300238 -221.408557)
			(xy 345.278202 -221.391734) (xy 345.266743 -221.383232) (xy 345.24038 -221.372349) (xy 345.212035 -221.369186)
			(xy 345.183921 -221.37399) (xy 345.158235 -221.386387) (xy 345.136982 -221.405407) (xy 345.121822 -221.429565)
			(xy 345.113939 -221.456975) (xy 345.113356 -221.471236) (xy 345.113356 -221.632018) (xy 345.14409 -221.645226)
			(xy 345.167369 -221.655802) (xy 345.210615 -221.683076) (xy 345.249129 -221.716704) (xy 345.281985 -221.755877)
			(xy 345.308395 -221.799656) (xy 345.327726 -221.84699) (xy 345.339511 -221.896741) (xy 345.34347 -221.947716)
			(xy 345.339506 -221.99869) (xy 345.327716 -222.048441) (xy 345.308381 -222.095772) (xy 345.281967 -222.139549)
			(xy 345.249106 -222.178719) (xy 345.21059 -222.212343) (xy 345.167341 -222.239613) (xy 345.14409 -222.250254)
			(xy 345.113356 -222.263462) (xy 345.113356 -223.261174) (xy 345.14409 -223.274382) (xy 345.167231 -223.28495)
			(xy 345.21021 -223.312164) (xy 345.248478 -223.34568) (xy 345.28112 -223.384696) (xy 345.307355 -223.42828)
			(xy 345.326556 -223.475387) (xy 345.338262 -223.524892) (xy 345.342195 -223.57561) (xy 345.338259 -223.626328)
			(xy 345.32655 -223.675832) (xy 345.307346 -223.722939) (xy 345.281108 -223.766521) (xy 345.248464 -223.805535)
			(xy 345.210193 -223.839048) (xy 345.167212 -223.866259) (xy 345.14409 -223.87687) (xy 345.113356 -223.890078)
			(xy 345.113356 -224.05213) (xy 345.113839 -224.06639) (xy 345.121738 -224.093794) (xy 345.136912 -224.117943)
			(xy 345.158174 -224.136951) (xy 345.183866 -224.149334) (xy 345.211981 -224.154124) (xy 345.240323 -224.150949)
			(xy 345.266681 -224.140056) (xy 345.278202 -224.131632) (xy 345.299355 -224.115422) (xy 345.345825 -224.089338)
			(xy 345.395885 -224.071068) (xy 345.421966 -224.065592) (xy 345.444826 -224.061274) (xy 345.64955 -223.706436)
			(xy 345.64193 -223.684338) (xy 345.633304 -223.65799) (xy 345.623976 -223.603344) (xy 345.623388 -223.575626)
			(xy 345.623896 -223.549719) (xy 345.632002 -223.498542) (xy 345.648014 -223.449263) (xy 345.671537 -223.403096)
			(xy 345.701993 -223.361177) (xy 345.738631 -223.324539) (xy 345.78055 -223.294083) (xy 345.826717 -223.27056)
			(xy 345.875996 -223.254548) (xy 345.927173 -223.246442) (xy 345.978987 -223.246442) (xy 346.030164 -223.254548)
			(xy 346.079443 -223.27056) (xy 346.12561 -223.294083) (xy 346.167529 -223.324539) (xy 346.204167 -223.361177)
			(xy 346.234623 -223.403096) (xy 346.258146 -223.449263) (xy 346.274158 -223.498542) (xy 346.282264 -223.549719)
			(xy 346.282772 -223.575626) (xy 346.282297 -223.600983) (xy 346.274511 -223.651097) (xy 346.259143 -223.699427)
			(xy 346.236554 -223.744833) (xy 346.207278 -223.786244) (xy 346.172006 -223.822684) (xy 346.131569 -223.853292)
			(xy 346.086922 -223.877347) (xy 346.039118 -223.89428) (xy 346.014294 -223.899476) (xy 345.991434 -223.903794)
			(xy 345.78671 -224.258632) (xy 345.794584 -224.280476) (xy 345.803163 -224.306895) (xy 345.812358 -224.36167)
			(xy 345.812872 -224.389442) (xy 346.093796 -224.389442) (xy 346.094304 -224.363555) (xy 346.102403 -224.312417)
			(xy 346.118402 -224.263177) (xy 346.141908 -224.217045) (xy 346.17234 -224.175158) (xy 346.20895 -224.138548)
			(xy 346.250837 -224.108116) (xy 346.296969 -224.08461) (xy 346.346209 -224.068611) (xy 346.397347 -224.060512)
			(xy 346.449121 -224.060512) (xy 346.500259 -224.068611) (xy 346.549499 -224.08461) (xy 346.595631 -224.108116)
			(xy 346.637518 -224.138548) (xy 346.674128 -224.175158) (xy 346.70456 -224.217045) (xy 346.728066 -224.263177)
			(xy 346.744065 -224.312417) (xy 346.752164 -224.363555) (xy 346.752672 -224.389442) (xy 347.033596 -224.389442)
			(xy 347.034029 -224.364106) (xy 347.04179 -224.314032) (xy 347.05712 -224.265734) (xy 347.079659 -224.22035)
			(xy 347.108875 -224.178949) (xy 347.144081 -224.142504) (xy 347.184448 -224.111874) (xy 347.229026 -224.087781)
			(xy 347.276765 -224.070791) (xy 347.301566 -224.065592) (xy 347.324426 -224.061274) (xy 347.52915 -223.706436)
			(xy 347.52153 -223.684338) (xy 347.512902 -223.657991) (xy 347.503579 -223.603344) (xy 347.502988 -223.575626)
			(xy 347.503496 -223.549719) (xy 347.511602 -223.498542) (xy 347.527614 -223.449263) (xy 347.551137 -223.403096)
			(xy 347.581593 -223.361177) (xy 347.618231 -223.324539) (xy 347.66015 -223.294083) (xy 347.706317 -223.27056)
			(xy 347.755596 -223.254548) (xy 347.806773 -223.246442) (xy 347.858587 -223.246442) (xy 347.909764 -223.254548)
			(xy 347.959043 -223.27056) (xy 348.00521 -223.294083) (xy 348.047129 -223.324539) (xy 348.083767 -223.361177)
			(xy 348.114223 -223.403096) (xy 348.137746 -223.449263) (xy 348.153758 -223.498542) (xy 348.161864 -223.549719)
			(xy 348.162372 -223.575626) (xy 348.161981 -223.600993) (xy 348.154228 -223.651131) (xy 348.138877 -223.699486)
			(xy 348.116292 -223.744915) (xy 348.087007 -223.786344) (xy 348.051716 -223.822791) (xy 348.011252 -223.853396)
			(xy 347.966574 -223.877433) (xy 347.918739 -223.894334) (xy 347.893894 -223.899476) (xy 347.871034 -223.903794)
			(xy 347.66631 -224.258632) (xy 347.674184 -224.280476) (xy 347.682757 -224.306897) (xy 347.691958 -224.36167)
			(xy 347.692472 -224.389442) (xy 347.973396 -224.389442) (xy 347.973904 -224.363555) (xy 347.982003 -224.312417)
			(xy 347.998002 -224.263177) (xy 348.021508 -224.217045) (xy 348.05194 -224.175158) (xy 348.08855 -224.138548)
			(xy 348.130437 -224.108116) (xy 348.176569 -224.08461) (xy 348.225809 -224.068611) (xy 348.276947 -224.060512)
			(xy 348.328721 -224.060512) (xy 348.379859 -224.068611) (xy 348.429099 -224.08461) (xy 348.475231 -224.108116)
			(xy 348.517118 -224.138548) (xy 348.553728 -224.175158) (xy 348.58416 -224.217045) (xy 348.607666 -224.263177)
			(xy 348.623665 -224.312417) (xy 348.631764 -224.363555) (xy 348.632272 -224.389442) (xy 348.913196 -224.389442)
			(xy 348.913629 -224.364106) (xy 348.92139 -224.314032) (xy 348.93672 -224.265734) (xy 348.959259 -224.22035)
			(xy 348.988475 -224.178949) (xy 349.023681 -224.142504) (xy 349.064048 -224.111874) (xy 349.108626 -224.087781)
			(xy 349.156365 -224.070791) (xy 349.181166 -224.065592) (xy 349.204026 -224.061274) (xy 349.40875 -223.706436)
			(xy 349.40113 -223.684338) (xy 349.392502 -223.657991) (xy 349.383179 -223.603344) (xy 349.382588 -223.575626)
			(xy 349.383096 -223.549719) (xy 349.391202 -223.498542) (xy 349.407214 -223.449263) (xy 349.430737 -223.403096)
			(xy 349.461193 -223.361177) (xy 349.497831 -223.324539) (xy 349.53975 -223.294083) (xy 349.585917 -223.27056)
			(xy 349.635196 -223.254548) (xy 349.686373 -223.246442) (xy 349.738187 -223.246442) (xy 349.789364 -223.254548)
			(xy 349.838643 -223.27056) (xy 349.88481 -223.294083) (xy 349.926729 -223.324539) (xy 349.963367 -223.361177)
			(xy 349.993823 -223.403096) (xy 350.017346 -223.449263) (xy 350.033358 -223.498542) (xy 350.041464 -223.549719)
			(xy 350.041972 -223.575626) (xy 350.041581 -223.600993) (xy 350.033828 -223.651131) (xy 350.018477 -223.699486)
			(xy 349.995892 -223.744915) (xy 349.966607 -223.786344) (xy 349.931316 -223.822791) (xy 349.890852 -223.853396)
			(xy 349.846174 -223.877433) (xy 349.798339 -223.894334) (xy 349.773494 -223.899476) (xy 349.750634 -223.903794)
			(xy 349.54591 -224.258632) (xy 349.553784 -224.280476) (xy 349.562357 -224.306897) (xy 349.571558 -224.36167)
			(xy 349.572072 -224.389442) (xy 349.852996 -224.389442) (xy 349.853504 -224.363555) (xy 349.861603 -224.312417)
			(xy 349.877602 -224.263177) (xy 349.901108 -224.217045) (xy 349.93154 -224.175158) (xy 349.96815 -224.138548)
			(xy 350.010037 -224.108116) (xy 350.056169 -224.08461) (xy 350.105409 -224.068611) (xy 350.156547 -224.060512)
			(xy 350.208321 -224.060512) (xy 350.259459 -224.068611) (xy 350.308699 -224.08461) (xy 350.354831 -224.108116)
			(xy 350.396718 -224.138548) (xy 350.433328 -224.175158) (xy 350.46376 -224.217045) (xy 350.487266 -224.263177)
			(xy 350.503265 -224.312417) (xy 350.511364 -224.363555) (xy 350.511872 -224.389442) (xy 350.511325 -224.417149)
			(xy 350.502141 -224.471796) (xy 350.493584 -224.498154) (xy 350.48571 -224.520252) (xy 350.690688 -224.87509)
			(xy 350.713548 -224.879408) (xy 350.738371 -224.884565) (xy 350.786151 -224.90152) (xy 350.830771 -224.925592)
			(xy 350.871178 -224.956214) (xy 350.906419 -224.992662) (xy 350.935663 -225.034077) (xy 350.958219 -225.079482)
			(xy 350.973556 -225.127806) (xy 350.981311 -225.177908) (xy 350.981772 -225.203258) (xy 350.981264 -225.229165)
			(xy 350.973158 -225.280342) (xy 350.957146 -225.329621) (xy 350.933623 -225.375788) (xy 350.903167 -225.417707)
			(xy 350.866529 -225.454345) (xy 350.82461 -225.484801) (xy 350.778443 -225.508324) (xy 350.729164 -225.524336)
			(xy 350.677987 -225.532442) (xy 350.626173 -225.532442) (xy 350.574996 -225.524336) (xy 350.525717 -225.508324)
			(xy 350.47955 -225.484801) (xy 350.437631 -225.454345) (xy 350.400993 -225.417707) (xy 350.370537 -225.375788)
			(xy 350.347014 -225.329621) (xy 350.331002 -225.280342) (xy 350.322896 -225.229165) (xy 350.322388 -225.203258)
			(xy 350.322997 -225.175541) (xy 350.33231 -225.120895) (xy 350.34093 -225.094546) (xy 350.348804 -225.072448)
			(xy 350.143826 -224.71761) (xy 350.120966 -224.713292) (xy 350.096148 -224.708169) (xy 350.048405 -224.691172)
			(xy 350.003826 -224.667071) (xy 349.96346 -224.636431) (xy 349.928257 -224.599976) (xy 349.899048 -224.558564)
			(xy 349.876519 -224.51317) (xy 349.861201 -224.464863) (xy 349.853455 -224.414781) (xy 349.852996 -224.389442)
			(xy 349.572072 -224.389442) (xy 349.571564 -224.415329) (xy 349.563465 -224.466467) (xy 349.547466 -224.515707)
			(xy 349.52396 -224.561839) (xy 349.493528 -224.603726) (xy 349.456918 -224.640336) (xy 349.415031 -224.670768)
			(xy 349.368899 -224.694274) (xy 349.319659 -224.710273) (xy 349.268521 -224.718372) (xy 349.216747 -224.718372)
			(xy 349.165609 -224.710273) (xy 349.116369 -224.694274) (xy 349.070237 -224.670768) (xy 349.02835 -224.640336)
			(xy 348.99174 -224.603726) (xy 348.961308 -224.561839) (xy 348.937802 -224.515707) (xy 348.921803 -224.466467)
			(xy 348.913704 -224.415329) (xy 348.913196 -224.389442) (xy 348.632272 -224.389442) (xy 348.631725 -224.417149)
			(xy 348.622541 -224.471796) (xy 348.613984 -224.498154) (xy 348.60611 -224.520252) (xy 348.811088 -224.87509)
			(xy 348.833948 -224.879408) (xy 348.858771 -224.884565) (xy 348.906551 -224.90152) (xy 348.951171 -224.925592)
			(xy 348.991578 -224.956214) (xy 349.026819 -224.992662) (xy 349.056063 -225.034077) (xy 349.078619 -225.079482)
			(xy 349.093956 -225.127806) (xy 349.101711 -225.177908) (xy 349.102172 -225.203258) (xy 349.101664 -225.229165)
			(xy 349.093558 -225.280342) (xy 349.077546 -225.329621) (xy 349.054023 -225.375788) (xy 349.023567 -225.417707)
			(xy 348.986929 -225.454345) (xy 348.94501 -225.484801) (xy 348.898843 -225.508324) (xy 348.849564 -225.524336)
			(xy 348.798387 -225.532442) (xy 348.746573 -225.532442) (xy 348.695396 -225.524336) (xy 348.646117 -225.508324)
			(xy 348.59995 -225.484801) (xy 348.558031 -225.454345) (xy 348.521393 -225.417707) (xy 348.490937 -225.375788)
			(xy 348.467414 -225.329621) (xy 348.451402 -225.280342) (xy 348.443296 -225.229165) (xy 348.442788 -225.203258)
			(xy 348.443397 -225.175541) (xy 348.45271 -225.120895) (xy 348.46133 -225.094546) (xy 348.469204 -225.072448)
			(xy 348.264226 -224.71761) (xy 348.241366 -224.713292) (xy 348.216548 -224.708169) (xy 348.168805 -224.691172)
			(xy 348.124226 -224.667071) (xy 348.08386 -224.636431) (xy 348.048657 -224.599976) (xy 348.019448 -224.558564)
			(xy 347.996919 -224.51317) (xy 347.981601 -224.464863) (xy 347.973855 -224.414781) (xy 347.973396 -224.389442)
			(xy 347.692472 -224.389442) (xy 347.691964 -224.415329) (xy 347.683865 -224.466467) (xy 347.667866 -224.515707)
			(xy 347.64436 -224.561839) (xy 347.613928 -224.603726) (xy 347.577318 -224.640336) (xy 347.535431 -224.670768)
			(xy 347.489299 -224.694274) (xy 347.440059 -224.710273) (xy 347.388921 -224.718372) (xy 347.337147 -224.718372)
			(xy 347.286009 -224.710273) (xy 347.236769 -224.694274) (xy 347.190637 -224.670768) (xy 347.14875 -224.640336)
			(xy 347.11214 -224.603726) (xy 347.081708 -224.561839) (xy 347.058202 -224.515707) (xy 347.042203 -224.466467)
			(xy 347.034104 -224.415329) (xy 347.033596 -224.389442) (xy 346.752672 -224.389442) (xy 346.752125 -224.417149)
			(xy 346.742941 -224.471796) (xy 346.734384 -224.498154) (xy 346.72651 -224.520252) (xy 346.931488 -224.87509)
			(xy 346.954348 -224.879408) (xy 346.979171 -224.884565) (xy 347.026951 -224.90152) (xy 347.071571 -224.925592)
			(xy 347.111978 -224.956214) (xy 347.147219 -224.992662) (xy 347.176463 -225.034077) (xy 347.199019 -225.079482)
			(xy 347.214356 -225.127806) (xy 347.222111 -225.177908) (xy 347.222572 -225.203258) (xy 347.222064 -225.229165)
			(xy 347.213958 -225.280342) (xy 347.197946 -225.329621) (xy 347.174423 -225.375788) (xy 347.143967 -225.417707)
			(xy 347.107329 -225.454345) (xy 347.06541 -225.484801) (xy 347.019243 -225.508324) (xy 346.969964 -225.524336)
			(xy 346.918787 -225.532442) (xy 346.866973 -225.532442) (xy 346.815796 -225.524336) (xy 346.766517 -225.508324)
			(xy 346.72035 -225.484801) (xy 346.678431 -225.454345) (xy 346.641793 -225.417707) (xy 346.611337 -225.375788)
			(xy 346.587814 -225.329621) (xy 346.571802 -225.280342) (xy 346.563696 -225.229165) (xy 346.563188 -225.203258)
			(xy 346.563797 -225.175541) (xy 346.57311 -225.120895) (xy 346.58173 -225.094546) (xy 346.589604 -225.072448)
			(xy 346.384626 -224.71761) (xy 346.361766 -224.713292) (xy 346.336948 -224.708169) (xy 346.289205 -224.691172)
			(xy 346.244626 -224.667071) (xy 346.20426 -224.636431) (xy 346.169057 -224.599976) (xy 346.139848 -224.558564)
			(xy 346.117319 -224.51317) (xy 346.102001 -224.464863) (xy 346.094255 -224.414781) (xy 346.093796 -224.389442)
			(xy 345.812872 -224.389442) (xy 345.812361 -224.415328) (xy 345.804257 -224.466462) (xy 345.788254 -224.5157)
			(xy 345.764747 -224.561828) (xy 345.734315 -224.603712) (xy 345.697706 -224.64032) (xy 345.655821 -224.670752)
			(xy 345.609692 -224.694257) (xy 345.560455 -224.710259) (xy 345.50932 -224.718362) (xy 345.483434 -224.71888)
			(xy 345.45573 -224.718301) (xy 345.401104 -224.709025) (xy 345.348792 -224.69076) (xy 345.300263 -224.66402)
			(xy 345.278202 -224.647252) (xy 345.266738 -224.638755) (xy 345.24037 -224.62788) (xy 345.212023 -224.624722)
			(xy 345.183908 -224.629527) (xy 345.158219 -224.64192) (xy 345.136958 -224.660934) (xy 345.121786 -224.685086)
			(xy 345.113886 -224.712493) (xy 345.113356 -224.726754) (xy 345.113356 -224.887536) (xy 345.14409 -224.900744)
			(xy 345.169026 -224.912098) (xy 345.215044 -224.941834) (xy 345.255505 -224.978776) (xy 345.289294 -225.021904)
			(xy 345.31548 -225.07003) (xy 345.33334 -225.121826) (xy 345.342382 -225.175863) (xy 345.342972 -225.203258)
			(xy 345.342493 -225.229163) (xy 345.33439 -225.280336) (xy 345.318379 -225.32961) (xy 345.294852 -225.375771)
			(xy 345.264391 -225.417681) (xy 345.227745 -225.454306) (xy 345.185819 -225.484745) (xy 345.139646 -225.508247)
			(xy 345.090363 -225.524232) (xy 345.039185 -225.532307) (xy 345.01328 -225.532696) (xy 344.990306 -225.532294)
			(xy 344.944804 -225.525916) (xy 344.922602 -225.519996) (xy 344.8939 -225.511868) (xy 343.426796 -226.978972)
			(xy 343.42324 -226.985576) (xy 343.411441 -227.006766) (xy 343.382562 -227.04573) (xy 343.348264 -227.080019)
			(xy 343.309292 -227.108887) (xy 343.288112 -227.120704) (xy 343.281508 -227.12426) (xy 342.940894 -227.464874)
			(xy 342.957404 -227.49764) (xy 342.968388 -227.520627) (xy 342.983903 -227.56915) (xy 342.991735 -227.619488)
			(xy 342.992202 -227.64496) (xy 342.991726 -227.670753) (xy 342.983662 -227.721704) (xy 342.967727 -227.770766)
			(xy 342.944313 -227.816732) (xy 342.913997 -227.858469) (xy 342.877525 -227.894949) (xy 342.835795 -227.925275)
			(xy 342.789835 -227.948699) (xy 342.740776 -227.964645) (xy 342.689827 -227.97272) (xy 342.664034 -227.973128)
			(xy 342.638562 -227.972665) (xy 342.588224 -227.96483) (xy 342.539702 -227.949312) (xy 342.516714 -227.93833)
			(xy 342.483948 -227.92182) (xy 341.112348 -229.29342) (xy 341.110316 -229.310946) (xy 341.107035 -229.335129)
			(xy 341.094247 -229.382223) (xy 341.074624 -229.426905) (xy 341.048601 -229.468187) (xy 341.016751 -229.505161)
			(xy 340.979777 -229.537009) (xy 340.938493 -229.563031) (xy 340.893811 -229.582651) (xy 340.846716 -229.595438)
			(xy 340.822534 -229.598728) (xy 340.805008 -229.60076) (xy 340.550754 -229.855014) (xy 340.57717 -229.890066)
			(xy 340.592514 -229.911502) (xy 340.616891 -229.958239) (xy 340.633495 -230.008268) (xy 340.6419 -230.060306)
			(xy 340.642448 -230.086662) (xy 340.641972 -230.112453) (xy 340.633907 -230.163401) (xy 340.617972 -230.212459)
			(xy 340.594557 -230.258421) (xy 340.564239 -230.300153) (xy 340.527767 -230.336628) (xy 340.486036 -230.366947)
			(xy 340.440076 -230.390365) (xy 340.391018 -230.406303) (xy 340.340071 -230.41437) (xy 340.31428 -230.41483)
			(xy 340.287918 -230.414333) (xy 340.235867 -230.405951) (xy 340.18583 -230.389341) (xy 340.139099 -230.364933)
			(xy 340.117684 -230.349552) (xy 340.082632 -230.323136) (xy 338.757006 -231.648762) (xy 338.760308 -231.6734)
			(xy 338.761504 -231.683645) (xy 338.762777 -231.704234) (xy 338.762848 -231.714548) (xy 338.762339 -231.740333)
			(xy 338.754264 -231.791266) (xy 338.738322 -231.840309) (xy 338.714905 -231.886255) (xy 338.684589 -231.927972)
			(xy 338.64812 -231.964433) (xy 338.606397 -231.99474) (xy 338.560446 -232.018148) (xy 338.5114 -232.03408)
			(xy 338.460465 -232.042144) (xy 338.43468 -232.042716) (xy 338.424366 -232.042654) (xy 338.403776 -232.041381)
			(xy 338.393532 -232.040176) (xy 338.368894 -232.036874) (xy 337.721956 -232.683812) (xy 337.721956 -233.105198)
			(xy 337.740724 -233.123902) (xy 337.772574 -233.166243) (xy 337.797216 -233.213147) (xy 337.814008 -233.263399)
			(xy 337.822515 -233.315695) (xy 337.822517 -233.368678) (xy 337.814014 -233.420974) (xy 337.797226 -233.471227)
			(xy 337.772589 -233.518134) (xy 337.740742 -233.560477) (xy 337.721956 -233.579162) (xy 337.721956 -234.733084)
			(xy 337.740725 -234.751788) (xy 337.772578 -234.794129) (xy 337.797221 -234.841034) (xy 337.814015 -234.891287)
			(xy 337.822524 -234.943584) (xy 337.822528 -234.996569) (xy 337.814026 -235.048867) (xy 337.79724 -235.099122)
			(xy 337.772603 -235.146031) (xy 337.740756 -235.188377) (xy 337.721956 -235.207048) (xy 337.721956 -236.36097)
			(xy 337.740726 -236.379674) (xy 337.772581 -236.422015) (xy 337.797227 -236.468921) (xy 337.814023 -236.519175)
			(xy 337.822534 -236.571474) (xy 337.822539 -236.62446) (xy 337.814039 -236.67676) (xy 337.797253 -236.727017)
			(xy 337.772617 -236.773928) (xy 337.74077 -236.816276) (xy 337.721956 -236.834934) (xy 337.721956 -237.988602)
			(xy 337.740723 -238.007306) (xy 337.772574 -238.049647) (xy 337.797214 -238.096551) (xy 337.814005 -238.146802)
			(xy 337.822512 -238.199098) (xy 337.822514 -238.25208) (xy 337.814011 -238.304376) (xy 337.797223 -238.354629)
			(xy 337.772585 -238.401535) (xy 337.740738 -238.443877) (xy 337.721956 -238.462566) (xy 337.721956 -239.616234)
			(xy 337.74072 -239.634938) (xy 337.772565 -239.677278) (xy 337.797201 -239.72418) (xy 337.813988 -239.77443)
			(xy 337.822491 -239.826722) (xy 337.822489 -239.879701) (xy 337.813983 -239.931992) (xy 337.797192 -239.98224)
			(xy 337.772554 -240.029141) (xy 337.740706 -240.071478) (xy 337.721956 -240.090198) (xy 337.721956 -241.24412)
			(xy 337.740722 -241.262824) (xy 337.772569 -241.305164) (xy 337.797207 -241.352067) (xy 337.813996 -241.402318)
			(xy 337.8225 -241.454611) (xy 337.8225 -241.507592) (xy 337.813995 -241.559885) (xy 337.797206 -241.610135)
			(xy 337.772568 -241.657038) (xy 337.74072 -241.699378) (xy 337.721956 -241.718084) (xy 337.721956 -242.872006)
			(xy 337.740723 -242.89071) (xy 337.772573 -242.93305) (xy 337.797212 -242.979955) (xy 337.814003 -243.030206)
			(xy 337.82251 -243.082501) (xy 337.822511 -243.135483) (xy 337.814007 -243.187778) (xy 337.797219 -243.23803)
			(xy 337.772581 -243.284936) (xy 337.740734 -243.327278) (xy 337.721956 -243.34597) (xy 337.721956 -244.499638)
			(xy 337.74072 -244.518342) (xy 337.772565 -244.560682) (xy 337.797199 -244.607584) (xy 337.813986 -244.657833)
			(xy 337.822488 -244.710125) (xy 337.822486 -244.763103) (xy 337.813979 -244.815394) (xy 337.797189 -244.865641)
			(xy 337.77255 -244.912542) (xy 337.740702 -244.954879) (xy 337.721956 -244.973602) (xy 337.721956 -246.127524)
			(xy 337.740721 -246.146228) (xy 337.772568 -246.188568) (xy 337.797205 -246.235471) (xy 337.813994 -246.285721)
			(xy 337.822498 -246.338014) (xy 337.822497 -246.390994) (xy 337.813992 -246.443287) (xy 337.797202 -246.493537)
			(xy 337.772564 -246.540439) (xy 337.740716 -246.582778) (xy 337.721956 -246.601488) (xy 337.721956 -247.754902)
			(xy 337.740766 -247.773612) (xy 337.772693 -247.81598) (xy 337.797393 -247.862929) (xy 337.814224 -247.913239)
			(xy 337.822749 -247.965601) (xy 337.822745 -248.018652) (xy 337.814212 -248.071012) (xy 337.797372 -248.121319)
			(xy 337.772664 -248.168265) (xy 337.740731 -248.210628) (xy 337.721956 -248.229374) (xy 337.721956 -249.383042)
			(xy 337.74072 -249.401746) (xy 337.772564 -249.444086) (xy 337.797198 -249.490988) (xy 337.813984 -249.541236)
			(xy 337.822485 -249.593528) (xy 337.822483 -249.646506) (xy 337.813976 -249.698796) (xy 337.797185 -249.749043)
			(xy 337.772546 -249.795942) (xy 337.740698 -249.838279) (xy 337.721956 -249.857006) (xy 337.721956 -254.42545)
			(xy 337.75015 -254.43942) (xy 337.773321 -254.451406) (xy 337.815866 -254.481589) (xy 337.853098 -254.518127)
			(xy 337.884077 -254.560096) (xy 337.908022 -254.60644) (xy 337.924331 -254.65599) (xy 337.932591 -254.707496)
			(xy 337.932594 -254.759661) (xy 337.924341 -254.811169) (xy 337.908039 -254.860721) (xy 337.884099 -254.907068)
			(xy 337.853126 -254.949041) (xy 337.815899 -254.985583) (xy 337.773357 -255.015772) (xy 337.75015 -255.027684)
			(xy 337.721956 -255.041654) (xy 337.721956 -256.053336) (xy 337.75015 -256.067306) (xy 337.773314 -256.079292)
			(xy 337.815846 -256.109473) (xy 337.853064 -256.146006) (xy 337.884031 -256.187969) (xy 337.907966 -256.234305)
			(xy 337.924265 -256.283845) (xy 337.932517 -256.335341) (xy 337.932514 -256.387493) (xy 337.924257 -256.438988)
			(xy 337.907953 -256.488526) (xy 337.884014 -256.534859) (xy 337.853042 -256.57682) (xy 337.81582 -256.613349)
			(xy 337.773285 -256.643525) (xy 337.75015 -256.65557) (xy 337.721956 -256.66954) (xy 337.721956 -257.680968)
			(xy 337.75015 -257.694938) (xy 337.773319 -257.706924) (xy 337.815862 -257.737107) (xy 337.853091 -257.773643)
			(xy 337.884067 -257.815611) (xy 337.908011 -257.861954) (xy 337.924317 -257.911501) (xy 337.932575 -257.963006)
			(xy 337.932577 -258.015168) (xy 337.924323 -258.066673) (xy 337.908021 -258.116222) (xy 337.884081 -258.162566)
			(xy 337.853108 -258.204537) (xy 337.815882 -258.241076) (xy 337.773342 -258.271262) (xy 337.75015 -258.283202)
			(xy 337.721956 -258.297172) (xy 337.721956 -259.308854) (xy 337.75015 -259.322824) (xy 337.77332 -259.33481)
			(xy 337.815865 -259.364993) (xy 337.853096 -259.40153) (xy 337.884075 -259.4435) (xy 337.90802 -259.489843)
			(xy 337.924328 -259.539392) (xy 337.932587 -259.590899) (xy 337.93259 -259.643063) (xy 337.924337 -259.69457)
			(xy 337.908035 -259.744121) (xy 337.884095 -259.790467) (xy 337.853122 -259.83244) (xy 337.815895 -259.868982)
			(xy 337.773354 -259.89917) (xy 337.75015 -259.911088) (xy 337.721956 -259.925058) (xy 337.721956 -260.8199)
			(xy 339.447632 -262.545576) (xy 339.469984 -262.54456) (xy 339.484462 -262.544306) (xy 339.510254 -262.544782)
			(xy 339.561205 -262.552846) (xy 339.610266 -262.568782) (xy 339.656231 -262.592196) (xy 339.697967 -262.622512)
			(xy 339.734446 -262.658984) (xy 339.764771 -262.700714) (xy 339.788194 -262.746674) (xy 339.804139 -262.795733)
			(xy 339.812213 -262.846682) (xy 339.81263 -262.872474) (xy 339.812376 -262.886952) (xy 339.81136 -262.909304)
			(xy 341.150194 -264.248138) (xy 341.184738 -264.225532) (xy 341.204838 -264.21292) (xy 341.247899 -264.192988)
			(xy 341.293381 -264.179462) (xy 341.340337 -264.172625) (xy 341.364062 -264.172192) (xy 341.389853 -264.172695)
			(xy 341.4408 -264.180758) (xy 341.489858 -264.196692) (xy 341.53582 -264.220104) (xy 341.577554 -264.250417)
			(xy 341.614032 -264.286887) (xy 341.644355 -264.328613) (xy 341.667778 -264.374569) (xy 341.683724 -264.423624)
			(xy 341.691799 -264.474569) (xy 341.69223 -264.50036) (xy 341.691813 -264.524087) (xy 341.684981 -264.571046)
			(xy 341.671455 -264.61653) (xy 341.651515 -264.659591) (xy 341.63889 -264.679684) (xy 341.616284 -264.714228)
			(xy 341.893144 -264.991088) (xy 341.907368 -264.994136) (xy 341.932901 -265.000507) (xy 341.981671 -265.020265)
			(xy 342.026665 -265.047549) (xy 342.066732 -265.081661) (xy 342.100845 -265.121727) (xy 342.128131 -265.16672)
			(xy 342.147891 -265.21549) (xy 342.154256 -265.241024) (xy 342.157304 -265.255248) (xy 343.554812 -266.652756)
			(xy 343.586308 -266.639548) (xy 343.606563 -266.631378) (xy 343.648693 -266.619857) (xy 343.691978 -266.61402)
			(xy 343.713816 -266.61364) (xy 343.739603 -266.614147) (xy 343.79054 -266.622217) (xy 343.839589 -266.638156)
			(xy 343.88554 -266.661572) (xy 343.927262 -266.691887) (xy 343.963728 -266.728356) (xy 343.994041 -266.770081)
			(xy 344.017453 -266.816034) (xy 344.033389 -266.865083) (xy 344.041455 -266.916021) (xy 344.041984 -266.941808)
			(xy 344.04161 -266.963647) (xy 344.035781 -267.006934) (xy 344.024256 -267.049064) (xy 344.016076 -267.069316)
			(xy 344.002868 -267.100812) (xy 344.685112 -267.783056) (xy 350.431608 -267.783056)
		)
		(stroke
			(width 0)
			(type solid)
		)
		(fill yes)
		(layer "In8.Cu")
		(net "PVCCFA_EHV_CPU0")
	)
	(gr_poly
		(pts
			(xy 168.62425 -341.767668) (xy 168.641221 -341.746414) (xy 168.680523 -341.708819) (xy 168.725085 -341.677639)
			(xy 168.773872 -341.653601) (xy 168.825747 -341.637263) (xy 168.879504 -341.629005) (xy 168.906698 -341.628476)
			(xy 168.932022 -341.628922) (xy 168.982159 -341.636102) (xy 169.030771 -341.650316) (xy 169.076878 -341.671278)
			(xy 169.119547 -341.698565) (xy 169.157917 -341.731624) (xy 169.174922 -341.750396) (xy 169.190162 -341.767668)
			(xy 169.258234 -341.767668) (xy 169.273474 -341.750396) (xy 169.292038 -341.729927) (xy 169.334373 -341.694417)
			(xy 169.381686 -341.665873) (xy 169.43284 -341.644981) (xy 169.486608 -341.632241) (xy 169.541698 -341.627961)
			(xy 169.596788 -341.632241) (xy 169.650556 -341.644981) (xy 169.70171 -341.665873) (xy 169.749023 -341.694417)
			(xy 169.791358 -341.729927) (xy 169.809922 -341.750396) (xy 169.825162 -341.767668) (xy 169.905934 -341.767668)
			(xy 169.921174 -341.750396) (xy 169.938166 -341.731614) (xy 169.976546 -341.698567) (xy 170.019221 -341.671289)
			(xy 170.065328 -341.650331) (xy 170.11394 -341.636114) (xy 170.164074 -341.628926) (xy 170.189398 -341.628476)
			(xy 170.216592 -341.62899) (xy 170.270349 -341.637257) (xy 170.322224 -341.6536) (xy 170.371012 -341.677639)
			(xy 170.415578 -341.708815) (xy 170.454888 -341.746403) (xy 170.471846 -341.767668) (xy 173.594522 -341.767668)
			(xy 173.611493 -341.746412) (xy 173.650793 -341.708814) (xy 173.695355 -341.677631) (xy 173.744142 -341.653589)
			(xy 173.796018 -341.637247) (xy 173.849775 -341.628985) (xy 173.87697 -341.628476) (xy 173.902295 -341.62892)
			(xy 173.952434 -341.636096) (xy 174.001049 -341.650308) (xy 174.047158 -341.671268) (xy 174.08983 -341.698552)
			(xy 174.128204 -341.731611) (xy 174.145194 -341.750396) (xy 174.160434 -341.767668) (xy 174.241206 -341.767668)
			(xy 174.256446 -341.750396) (xy 174.27501 -341.729927) (xy 174.317345 -341.694417) (xy 174.364658 -341.665873)
			(xy 174.415812 -341.644981) (xy 174.46958 -341.632241) (xy 174.52467 -341.627961) (xy 174.57976 -341.632241)
			(xy 174.633528 -341.644981) (xy 174.684682 -341.665873) (xy 174.731995 -341.694417) (xy 174.77433 -341.729927)
			(xy 174.792894 -341.750396) (xy 174.808134 -341.767668) (xy 174.876206 -341.767668) (xy 174.891446 -341.750396)
			(xy 174.908437 -341.731612) (xy 174.946817 -341.698562) (xy 174.989491 -341.671281) (xy 175.035598 -341.650319)
			(xy 175.08421 -341.636099) (xy 175.134346 -341.628907) (xy 175.15967 -341.628476) (xy 175.186862 -341.628995)
			(xy 175.240612 -341.637272) (xy 175.29248 -341.653623) (xy 175.34126 -341.677668) (xy 175.385818 -341.708847)
			(xy 175.425119 -341.746438) (xy 175.442118 -341.767668) (xy 178.30165 -341.767668) (xy 178.318621 -341.746414)
			(xy 178.357923 -341.708819) (xy 178.402485 -341.677639) (xy 178.451272 -341.653601) (xy 178.503147 -341.637263)
			(xy 178.556904 -341.629005) (xy 178.584098 -341.628476) (xy 178.609422 -341.628922) (xy 178.659559 -341.636102)
			(xy 178.708171 -341.650316) (xy 178.754278 -341.671278) (xy 178.796947 -341.698565) (xy 178.835317 -341.731624)
			(xy 178.852322 -341.750396) (xy 178.867562 -341.767668) (xy 178.935634 -341.767668) (xy 178.950874 -341.750396)
			(xy 178.969438 -341.729927) (xy 179.011773 -341.694417) (xy 179.059086 -341.665873) (xy 179.11024 -341.644981)
			(xy 179.164008 -341.632241) (xy 179.219098 -341.627961) (xy 179.274188 -341.632241) (xy 179.327956 -341.644981)
			(xy 179.37911 -341.665873) (xy 179.426423 -341.694417) (xy 179.468758 -341.729927) (xy 179.487322 -341.750396)
			(xy 179.502562 -341.767668) (xy 179.583334 -341.767668) (xy 179.598574 -341.750396) (xy 179.615566 -341.731614)
			(xy 179.653946 -341.698567) (xy 179.696621 -341.671289) (xy 179.742728 -341.650331) (xy 179.79134 -341.636114)
			(xy 179.841474 -341.628926) (xy 179.866798 -341.628476) (xy 179.893992 -341.62899) (xy 179.947749 -341.637257)
			(xy 179.999624 -341.6536) (xy 180.048412 -341.677639) (xy 180.092978 -341.708815) (xy 180.132288 -341.746403)
			(xy 180.149246 -341.767668) (xy 183.373268 -341.767668) (xy 183.390239 -341.746415) (xy 183.429542 -341.708822)
			(xy 183.474105 -341.677645) (xy 183.522891 -341.653608) (xy 183.574766 -341.637273) (xy 183.628523 -341.629018)
			(xy 183.655716 -341.628476) (xy 183.681042 -341.628917) (xy 183.731185 -341.636086) (xy 183.779805 -341.650292)
			(xy 183.82592 -341.671247) (xy 183.868598 -341.698528) (xy 183.906977 -341.731585) (xy 183.92394 -341.750396)
			(xy 183.93918 -341.767668) (xy 184.019952 -341.767668) (xy 184.035192 -341.750396) (xy 184.053756 -341.729927)
			(xy 184.096091 -341.694417) (xy 184.143404 -341.665873) (xy 184.194558 -341.644981) (xy 184.248326 -341.632241)
			(xy 184.303416 -341.627961) (xy 184.358506 -341.632241) (xy 184.412274 -341.644981) (xy 184.463428 -341.665873)
			(xy 184.510741 -341.694417) (xy 184.553076 -341.729927) (xy 184.57164 -341.750396) (xy 184.58688 -341.767668)
			(xy 184.654952 -341.767668) (xy 184.670192 -341.750396) (xy 184.687184 -341.731615) (xy 184.725565 -341.69857)
			(xy 184.76824 -341.671294) (xy 184.814347 -341.650338) (xy 184.862958 -341.636124) (xy 184.913093 -341.628938)
			(xy 184.938416 -341.628476) (xy 184.96766 -341.629049) (xy 185.02537 -341.638563) (xy 185.080753 -341.657366)
			(xy 185.106818 -341.67064) (xy 185.139838 -341.688674) (xy 186.0804 -340.748112) (xy 186.0804 -329.188064)
			(xy 185.495184 -328.602848) (xy 182.02148 -328.602848) (xy 181.996521 -328.602275) (xy 181.947562 -328.592531)
			(xy 181.901446 -328.573421) (xy 181.859945 -328.545681) (xy 181.841902 -328.528426) (xy 180.991764 -327.678288)
			(xy 180.974502 -327.660248) (xy 180.946738 -327.618755) (xy 180.927619 -327.572637) (xy 180.91788 -327.523672)
			(xy 180.917342 -327.49871) (xy 180.917342 -323.731636) (xy 180.895061 -323.716294) (xy 180.854975 -323.679972)
			(xy 180.820841 -323.638007) (xy 180.793444 -323.591363) (xy 180.773412 -323.541114) (xy 180.761208 -323.488415)
			(xy 180.757111 -323.434476) (xy 180.761215 -323.380537) (xy 180.773427 -323.327839) (xy 180.793465 -323.277593)
			(xy 180.820869 -323.230953) (xy 180.855009 -323.188993) (xy 180.8951 -323.152676) (xy 180.917342 -323.137276)
			(xy 180.917342 -215.48852) (xy 180.476652 -215.04783) (xy 152.668478 -215.04783) (xy 152.663906 -215.048592)
			(xy 152.652455 -215.050601) (xy 152.629304 -215.05276) (xy 152.617678 -215.05291) (xy 135.930894 -215.05291)
			(xy 135.916351 -215.053378) (xy 135.888444 -215.061576) (xy 135.863979 -215.077306) (xy 135.844937 -215.099293)
			(xy 135.832864 -215.125755) (xy 135.828737 -215.154546) (xy 135.83289 -215.183334) (xy 135.844988 -215.209785)
			(xy 135.854186 -215.221058) (xy 135.869275 -215.23911) (xy 135.894716 -215.278686) (xy 135.914271 -215.321477)
			(xy 135.927543 -215.366615) (xy 135.934261 -215.41318) (xy 135.934704 -215.436704) (xy 135.934196 -215.462611)
			(xy 135.92609 -215.513788) (xy 135.910078 -215.563067) (xy 135.886555 -215.609234) (xy 135.856099 -215.651153)
			(xy 135.819461 -215.687791) (xy 135.777542 -215.718247) (xy 135.731375 -215.74177) (xy 135.682096 -215.757782)
			(xy 135.630919 -215.765888) (xy 135.579105 -215.765888) (xy 135.527928 -215.757782) (xy 135.478649 -215.74177)
			(xy 135.432482 -215.718247) (xy 135.390563 -215.687791) (xy 135.353925 -215.651153) (xy 135.323469 -215.609234)
			(xy 135.299946 -215.563067) (xy 135.283934 -215.513788) (xy 135.275828 -215.462611) (xy 135.27532 -215.436704)
			(xy 135.276038 -215.405864) (xy 135.287546 -215.345266) (xy 135.29818 -215.316308) (xy 135.306816 -215.294464)
			(xy 135.179308 -215.05291) (xy 134.991094 -215.05291) (xy 134.976551 -215.053378) (xy 134.948644 -215.061576)
			(xy 134.924179 -215.077306) (xy 134.905137 -215.099293) (xy 134.893064 -215.125755) (xy 134.888937 -215.154546)
			(xy 134.89309 -215.183334) (xy 134.905188 -215.209785) (xy 134.914386 -215.221058) (xy 134.929475 -215.23911)
			(xy 134.954916 -215.278686) (xy 134.974471 -215.321477) (xy 134.987743 -215.366615) (xy 134.994461 -215.41318)
			(xy 134.994904 -215.436704) (xy 134.994396 -215.462611) (xy 134.98629 -215.513788) (xy 134.970278 -215.563067)
			(xy 134.946755 -215.609235) (xy 134.916299 -215.651154) (xy 134.87966 -215.687794) (xy 134.837742 -215.71825)
			(xy 134.791575 -215.741775) (xy 134.742296 -215.757788) (xy 134.691119 -215.765895) (xy 134.665212 -215.766396)
			(xy 134.6397 -215.765919) (xy 134.589284 -215.75806) (xy 134.540681 -215.742528) (xy 134.495051 -215.719693)
			(xy 134.453484 -215.6901) (xy 134.416972 -215.654458) (xy 134.401306 -215.634316) (xy 133.989318 -215.634316)
			(xy 133.973645 -215.654452) (xy 133.937135 -215.690096) (xy 133.89557 -215.719691) (xy 133.849941 -215.742528)
			(xy 133.801339 -215.758064) (xy 133.750924 -215.765926) (xy 133.725412 -215.766396) (xy 133.699502 -215.765915)
			(xy 133.648319 -215.757811) (xy 133.599035 -215.741799) (xy 133.552862 -215.718274) (xy 133.510938 -215.687816)
			(xy 133.474294 -215.651175) (xy 133.443834 -215.609252) (xy 133.420307 -215.56308) (xy 133.404293 -215.513796)
			(xy 133.396186 -215.462614) (xy 133.39572 -215.436704) (xy 133.396159 -215.413181) (xy 133.402887 -215.366618)
			(xy 133.416164 -215.321484) (xy 133.435721 -215.278694) (xy 133.46116 -215.239119) (xy 133.476238 -215.221058)
			(xy 133.485412 -215.209769) (xy 133.497504 -215.183324) (xy 133.501654 -215.154543) (xy 133.497528 -215.125759)
			(xy 133.485458 -215.099303) (xy 133.466424 -215.07732) (xy 133.441967 -215.061591) (xy 133.414069 -215.05339)
			(xy 133.39953 -215.05291) (xy 133.234938 -215.05291) (xy 133.088888 -215.305894) (xy 133.096762 -215.327738)
			(xy 133.105408 -215.354146) (xy 133.11473 -215.408922) (xy 133.115304 -215.436704) (xy 133.114796 -215.462611)
			(xy 133.10669 -215.513788) (xy 133.090678 -215.563067) (xy 133.067155 -215.609234) (xy 133.036699 -215.651153)
			(xy 133.000061 -215.687791) (xy 132.958142 -215.718247) (xy 132.911975 -215.74177) (xy 132.862696 -215.757782)
			(xy 132.811519 -215.765888) (xy 132.759705 -215.765888) (xy 132.708528 -215.757782) (xy 132.659249 -215.74177)
			(xy 132.613082 -215.718247) (xy 132.571163 -215.687791) (xy 132.534525 -215.651153) (xy 132.504069 -215.609234)
			(xy 132.480546 -215.563067) (xy 132.464534 -215.513788) (xy 132.456428 -215.462611) (xy 132.45592 -215.436704)
			(xy 132.456359 -215.413181) (xy 132.463087 -215.366618) (xy 132.476364 -215.321484) (xy 132.495921 -215.278694)
			(xy 132.52136 -215.239119) (xy 132.536438 -215.221058) (xy 132.545612 -215.209769) (xy 132.557704 -215.183324)
			(xy 132.561854 -215.154543) (xy 132.557728 -215.125759) (xy 132.545658 -215.099303) (xy 132.526624 -215.07732)
			(xy 132.502167 -215.061591) (xy 132.474269 -215.05339) (xy 132.45973 -215.05291) (xy 131.355338 -215.05291)
			(xy 131.209288 -215.305894) (xy 131.217162 -215.327738) (xy 131.225808 -215.354146) (xy 131.23513 -215.408922)
			(xy 131.235704 -215.436704) (xy 131.235196 -215.462611) (xy 131.22709 -215.513788) (xy 131.211078 -215.563067)
			(xy 131.187555 -215.609234) (xy 131.157099 -215.651153) (xy 131.120461 -215.687791) (xy 131.078542 -215.718247)
			(xy 131.032375 -215.74177) (xy 130.983096 -215.757782) (xy 130.931919 -215.765888) (xy 130.880105 -215.765888)
			(xy 130.828928 -215.757782) (xy 130.779649 -215.74177) (xy 130.733482 -215.718247) (xy 130.691563 -215.687791)
			(xy 130.654925 -215.651153) (xy 130.624469 -215.609234) (xy 130.600946 -215.563067) (xy 130.584934 -215.513788)
			(xy 130.576828 -215.462611) (xy 130.57632 -215.436704) (xy 130.576759 -215.413181) (xy 130.583487 -215.366618)
			(xy 130.596764 -215.321484) (xy 130.616321 -215.278694) (xy 130.64176 -215.239119) (xy 130.656838 -215.221058)
			(xy 130.666012 -215.209769) (xy 130.678104 -215.183324) (xy 130.682254 -215.154543) (xy 130.678128 -215.125759)
			(xy 130.666058 -215.099303) (xy 130.647024 -215.07732) (xy 130.622567 -215.061591) (xy 130.594669 -215.05339)
			(xy 130.58013 -215.05291) (xy 129.475738 -215.05291) (xy 129.329688 -215.305894) (xy 129.337562 -215.327738)
			(xy 129.346208 -215.354146) (xy 129.35553 -215.408922) (xy 129.356104 -215.436704) (xy 129.355596 -215.462611)
			(xy 129.34749 -215.513788) (xy 129.331478 -215.563067) (xy 129.307955 -215.609234) (xy 129.277499 -215.651153)
			(xy 129.240861 -215.687791) (xy 129.198942 -215.718247) (xy 129.152775 -215.74177) (xy 129.103496 -215.757782)
			(xy 129.052319 -215.765888) (xy 129.000505 -215.765888) (xy 128.949328 -215.757782) (xy 128.900049 -215.74177)
			(xy 128.853882 -215.718247) (xy 128.811963 -215.687791) (xy 128.775325 -215.651153) (xy 128.744869 -215.609234)
			(xy 128.721346 -215.563067) (xy 128.705334 -215.513788) (xy 128.697228 -215.462611) (xy 128.69672 -215.436704)
			(xy 128.697159 -215.413181) (xy 128.703887 -215.366618) (xy 128.717164 -215.321484) (xy 128.736721 -215.278694)
			(xy 128.76216 -215.239119) (xy 128.777238 -215.221058) (xy 128.786412 -215.209769) (xy 128.798504 -215.183324)
			(xy 128.802654 -215.154543) (xy 128.798528 -215.125759) (xy 128.786458 -215.099303) (xy 128.767424 -215.07732)
			(xy 128.742967 -215.061591) (xy 128.715069 -215.05339) (xy 128.70053 -215.05291) (xy 128.215898 -215.05291)
			(xy 127.882142 -215.386666) (xy 127.882142 -216.057226) (xy 127.896978 -216.078402) (xy 127.920504 -216.124442)
			(xy 127.936519 -216.173602) (xy 127.944625 -216.224665) (xy 127.944622 -216.276367) (xy 127.936511 -216.32743)
			(xy 127.920492 -216.376588) (xy 127.896961 -216.422626) (xy 127.882142 -216.443814) (xy 127.882142 -216.645744)
			(xy 127.882664 -216.66111) (xy 127.891793 -216.690453) (xy 127.90924 -216.71575) (xy 127.933425 -216.73471)
			(xy 127.962156 -216.745613) (xy 127.99283 -216.747472) (xy 128.007872 -216.744296) (xy 128.027245 -216.739796)
			(xy 128.066725 -216.734962) (xy 128.086612 -216.734644) (xy 128.11252 -216.735127) (xy 128.163697 -216.743235)
			(xy 128.212976 -216.759249) (xy 128.259142 -216.782776) (xy 128.30106 -216.813235) (xy 128.337696 -216.849877)
			(xy 128.368149 -216.891799) (xy 128.391669 -216.937969) (xy 128.407676 -216.98725) (xy 128.415777 -217.038428)
			(xy 128.416304 -217.064336) (xy 129.63652 -217.064336) (xy 129.637028 -217.038429) (xy 129.645134 -216.987252)
			(xy 129.661146 -216.937973) (xy 129.684669 -216.891806) (xy 129.715125 -216.849887) (xy 129.751763 -216.813249)
			(xy 129.793682 -216.782793) (xy 129.839849 -216.75927) (xy 129.889128 -216.743258) (xy 129.940305 -216.735152)
			(xy 129.992119 -216.735152) (xy 130.043296 -216.743258) (xy 130.092575 -216.75927) (xy 130.138742 -216.782793)
			(xy 130.180661 -216.813249) (xy 130.217299 -216.849887) (xy 130.247755 -216.891806) (xy 130.271278 -216.937973)
			(xy 130.28729 -216.987252) (xy 130.295396 -217.038429) (xy 130.295904 -217.064336) (xy 131.51612 -217.064336)
			(xy 131.516628 -217.038429) (xy 131.524734 -216.987252) (xy 131.540746 -216.937973) (xy 131.564269 -216.891806)
			(xy 131.594725 -216.849887) (xy 131.631363 -216.813249) (xy 131.673282 -216.782793) (xy 131.719449 -216.75927)
			(xy 131.768728 -216.743258) (xy 131.819905 -216.735152) (xy 131.871719 -216.735152) (xy 131.922896 -216.743258)
			(xy 131.972175 -216.75927) (xy 132.018342 -216.782793) (xy 132.060261 -216.813249) (xy 132.096899 -216.849887)
			(xy 132.127355 -216.891806) (xy 132.150878 -216.937973) (xy 132.16689 -216.987252) (xy 132.174996 -217.038429)
			(xy 132.175504 -217.064336) (xy 133.39572 -217.064336) (xy 133.396228 -217.038429) (xy 133.404334 -216.987252)
			(xy 133.420346 -216.937973) (xy 133.443869 -216.891806) (xy 133.474325 -216.849887) (xy 133.510963 -216.813249)
			(xy 133.552882 -216.782793) (xy 133.599049 -216.75927) (xy 133.648328 -216.743258) (xy 133.699505 -216.735152)
			(xy 133.751319 -216.735152) (xy 133.802496 -216.743258) (xy 133.851775 -216.75927) (xy 133.897942 -216.782793)
			(xy 133.939861 -216.813249) (xy 133.976499 -216.849887) (xy 134.006955 -216.891806) (xy 134.030478 -216.937973)
			(xy 134.04649 -216.987252) (xy 134.054596 -217.038429) (xy 134.055104 -217.064336) (xy 134.054489 -217.091989)
			(xy 134.045169 -217.146507) (xy 134.036562 -217.172794) (xy 134.028942 -217.194892) (xy 134.234174 -217.550238)
			(xy 134.257034 -217.554556) (xy 134.281841 -217.559728) (xy 134.329579 -217.576721) (xy 134.374156 -217.600818)
			(xy 134.41452 -217.631451) (xy 134.449723 -217.6679) (xy 134.478934 -217.709305) (xy 134.501466 -217.754693)
			(xy 134.516789 -217.802993) (xy 134.524541 -217.85307) (xy 134.525004 -217.878406) (xy 134.524496 -217.904293)
			(xy 134.516397 -217.955431) (xy 134.500398 -218.004671) (xy 134.476892 -218.050803) (xy 134.44646 -218.09269)
			(xy 134.40985 -218.1293) (xy 134.367963 -218.159732) (xy 134.321831 -218.183238) (xy 134.272591 -218.199237)
			(xy 134.221453 -218.207336) (xy 134.169679 -218.207336) (xy 134.118541 -218.199237) (xy 134.069301 -218.183238)
			(xy 134.023169 -218.159732) (xy 133.981282 -218.1293) (xy 133.944672 -218.09269) (xy 133.91424 -218.050803)
			(xy 133.890734 -218.004671) (xy 133.874735 -217.955431) (xy 133.866636 -217.904293) (xy 133.866128 -217.878406)
			(xy 133.866662 -217.850698) (xy 133.875855 -217.796051) (xy 133.884416 -217.769694) (xy 133.89229 -217.747596)
			(xy 133.687312 -217.392504) (xy 133.664452 -217.388186) (xy 133.639596 -217.383069) (xy 133.591748 -217.366166)
			(xy 133.547056 -217.342128) (xy 133.506577 -217.311523) (xy 133.471267 -217.275076) (xy 133.441961 -217.233647)
			(xy 133.419352 -217.188215) (xy 133.403974 -217.139855) (xy 133.39619 -217.089709) (xy 133.39572 -217.064336)
			(xy 132.175504 -217.064336) (xy 132.174889 -217.091989) (xy 132.165569 -217.146507) (xy 132.156962 -217.172794)
			(xy 132.149342 -217.194892) (xy 132.354574 -217.550238) (xy 132.377434 -217.554556) (xy 132.402241 -217.559728)
			(xy 132.449979 -217.576721) (xy 132.494556 -217.600818) (xy 132.53492 -217.631451) (xy 132.570123 -217.6679)
			(xy 132.599334 -217.709305) (xy 132.621866 -217.754693) (xy 132.637189 -217.802993) (xy 132.644941 -217.85307)
			(xy 132.645404 -217.878406) (xy 132.644896 -217.904293) (xy 132.636797 -217.955431) (xy 132.620798 -218.004671)
			(xy 132.597292 -218.050803) (xy 132.56686 -218.09269) (xy 132.53025 -218.1293) (xy 132.488363 -218.159732)
			(xy 132.442231 -218.183238) (xy 132.392991 -218.199237) (xy 132.341853 -218.207336) (xy 132.290079 -218.207336)
			(xy 132.238941 -218.199237) (xy 132.189701 -218.183238) (xy 132.143569 -218.159732) (xy 132.101682 -218.1293)
			(xy 132.065072 -218.09269) (xy 132.03464 -218.050803) (xy 132.011134 -218.004671) (xy 131.995135 -217.955431)
			(xy 131.987036 -217.904293) (xy 131.986528 -217.878406) (xy 131.987062 -217.850698) (xy 131.996255 -217.796051)
			(xy 132.004816 -217.769694) (xy 132.01269 -217.747596) (xy 131.807712 -217.392504) (xy 131.784852 -217.388186)
			(xy 131.759996 -217.383069) (xy 131.712148 -217.366166) (xy 131.667456 -217.342128) (xy 131.626977 -217.311523)
			(xy 131.591667 -217.275076) (xy 131.562361 -217.233647) (xy 131.539752 -217.188215) (xy 131.524374 -217.139855)
			(xy 131.51659 -217.089709) (xy 131.51612 -217.064336) (xy 130.295904 -217.064336) (xy 130.295289 -217.091989)
			(xy 130.285969 -217.146507) (xy 130.277362 -217.172794) (xy 130.269742 -217.194892) (xy 130.474974 -217.550238)
			(xy 130.497834 -217.554556) (xy 130.522641 -217.559728) (xy 130.570379 -217.576721) (xy 130.614956 -217.600818)
			(xy 130.65532 -217.631451) (xy 130.690523 -217.6679) (xy 130.719734 -217.709305) (xy 130.742266 -217.754693)
			(xy 130.757589 -217.802993) (xy 130.765341 -217.85307) (xy 130.765804 -217.878406) (xy 130.765296 -217.904293)
			(xy 130.757197 -217.955431) (xy 130.741198 -218.004671) (xy 130.717692 -218.050803) (xy 130.68726 -218.09269)
			(xy 130.65065 -218.1293) (xy 130.608763 -218.159732) (xy 130.562631 -218.183238) (xy 130.513391 -218.199237)
			(xy 130.462253 -218.207336) (xy 130.410479 -218.207336) (xy 130.359341 -218.199237) (xy 130.310101 -218.183238)
			(xy 130.263969 -218.159732) (xy 130.222082 -218.1293) (xy 130.185472 -218.09269) (xy 130.15504 -218.050803)
			(xy 130.131534 -218.004671) (xy 130.115535 -217.955431) (xy 130.107436 -217.904293) (xy 130.106928 -217.878406)
			(xy 130.107462 -217.850698) (xy 130.116655 -217.796051) (xy 130.125216 -217.769694) (xy 130.13309 -217.747596)
			(xy 129.928112 -217.392504) (xy 129.905252 -217.388186) (xy 129.880396 -217.383069) (xy 129.832548 -217.366166)
			(xy 129.787856 -217.342128) (xy 129.747377 -217.311523) (xy 129.712067 -217.275076) (xy 129.682761 -217.233647)
			(xy 129.660152 -217.188215) (xy 129.644774 -217.139855) (xy 129.63699 -217.089709) (xy 129.63652 -217.064336)
			(xy 128.416304 -217.064336) (xy 128.415701 -217.091991) (xy 128.406385 -217.146511) (xy 128.397762 -217.172794)
			(xy 128.390142 -217.194892) (xy 128.595374 -217.550238) (xy 128.618234 -217.554556) (xy 128.643033 -217.559756)
			(xy 128.690767 -217.576747) (xy 128.73534 -217.600842) (xy 128.775701 -217.631473) (xy 128.810901 -217.667918)
			(xy 128.840109 -217.70932) (xy 128.86264 -217.754704) (xy 128.877961 -217.803) (xy 128.885712 -217.853072)
			(xy 128.886204 -217.878406) (xy 128.885696 -217.904293) (xy 128.877597 -217.955431) (xy 128.861598 -218.004671)
			(xy 128.838092 -218.050803) (xy 128.80766 -218.09269) (xy 128.77105 -218.1293) (xy 128.729163 -218.159732)
			(xy 128.683031 -218.183238) (xy 128.633791 -218.199237) (xy 128.582653 -218.207336) (xy 128.530879 -218.207336)
			(xy 128.479741 -218.199237) (xy 128.430501 -218.183238) (xy 128.384369 -218.159732) (xy 128.342482 -218.1293)
			(xy 128.305872 -218.09269) (xy 128.27544 -218.050803) (xy 128.251934 -218.004671) (xy 128.235935 -217.955431)
			(xy 128.227836 -217.904293) (xy 128.227328 -217.878406) (xy 128.227857 -217.850698) (xy 128.237055 -217.796052)
			(xy 128.245616 -217.769694) (xy 128.25349 -217.747596) (xy 128.048512 -217.392504) (xy 128.025652 -217.388186)
			(xy 128.007872 -217.384376) (xy 127.992835 -217.38125) (xy 127.962195 -217.383159) (xy 127.933502 -217.394076)
			(xy 127.909344 -217.413019) (xy 127.891897 -217.438279) (xy 127.882735 -217.467579) (xy 127.882142 -217.482928)
			(xy 127.882142 -217.682826) (xy 127.89727 -217.704206) (xy 127.921279 -217.750751) (xy 127.937629 -217.800505)
			(xy 127.945907 -217.852219) (xy 127.945906 -217.904591) (xy 127.937626 -217.956304) (xy 127.921275 -218.006058)
			(xy 127.897264 -218.052602) (xy 127.882142 -218.073986) (xy 127.882142 -218.692222) (xy 128.69672 -218.692222)
			(xy 128.697245 -218.666878) (xy 128.705014 -218.616789) (xy 128.720357 -218.56848) (xy 128.742912 -218.523087)
			(xy 128.772149 -218.481681) (xy 128.807378 -218.445236) (xy 128.847769 -218.414613) (xy 128.89237 -218.390531)
			(xy 128.940132 -218.373559) (xy 128.964944 -218.368372) (xy 128.987804 -218.364054) (xy 129.193036 -218.008708)
			(xy 129.185162 -217.98661) (xy 129.176694 -217.960366) (xy 129.167624 -217.905977) (xy 129.167128 -217.878406)
			(xy 129.167636 -217.852519) (xy 129.175735 -217.801381) (xy 129.191734 -217.752141) (xy 129.21524 -217.706009)
			(xy 129.245672 -217.664122) (xy 129.282282 -217.627512) (xy 129.324169 -217.59708) (xy 129.370301 -217.573574)
			(xy 129.419541 -217.557575) (xy 129.470679 -217.549476) (xy 129.522453 -217.549476) (xy 129.573591 -217.557575)
			(xy 129.622831 -217.573574) (xy 129.668963 -217.59708) (xy 129.71085 -217.627512) (xy 129.74746 -217.664122)
			(xy 129.777892 -217.706009) (xy 129.801398 -217.752141) (xy 129.817397 -217.801381) (xy 129.825496 -217.852519)
			(xy 129.826004 -217.878406) (xy 129.825531 -217.90378) (xy 129.817762 -217.953931) (xy 129.802393 -218.002296)
			(xy 129.779788 -218.047732) (xy 129.750482 -218.089163) (xy 129.715168 -218.125609) (xy 129.674682 -218.156208)
			(xy 129.629982 -218.180235) (xy 129.582126 -218.197122) (xy 129.557272 -218.202256) (xy 129.534412 -218.206574)
			(xy 129.329688 -218.561412) (xy 129.337562 -218.583256) (xy 129.346214 -218.609662) (xy 129.35553 -218.66444)
			(xy 129.356104 -218.692222) (xy 130.57632 -218.692222) (xy 130.576845 -218.666878) (xy 130.584614 -218.616789)
			(xy 130.599957 -218.56848) (xy 130.622512 -218.523087) (xy 130.651749 -218.481681) (xy 130.686978 -218.445236)
			(xy 130.727369 -218.414613) (xy 130.77197 -218.390531) (xy 130.819732 -218.373559) (xy 130.844544 -218.368372)
			(xy 130.867404 -218.364054) (xy 131.072636 -218.008708) (xy 131.064762 -217.98661) (xy 131.056294 -217.960366)
			(xy 131.047224 -217.905977) (xy 131.046728 -217.878406) (xy 131.047236 -217.852519) (xy 131.055335 -217.801381)
			(xy 131.071334 -217.752141) (xy 131.09484 -217.706009) (xy 131.125272 -217.664122) (xy 131.161882 -217.627512)
			(xy 131.203769 -217.59708) (xy 131.249901 -217.573574) (xy 131.299141 -217.557575) (xy 131.350279 -217.549476)
			(xy 131.402053 -217.549476) (xy 131.453191 -217.557575) (xy 131.502431 -217.573574) (xy 131.548563 -217.59708)
			(xy 131.59045 -217.627512) (xy 131.62706 -217.664122) (xy 131.657492 -217.706009) (xy 131.680998 -217.752141)
			(xy 131.696997 -217.801381) (xy 131.705096 -217.852519) (xy 131.705604 -217.878406) (xy 131.705131 -217.90378)
			(xy 131.697362 -217.953931) (xy 131.681993 -218.002296) (xy 131.659388 -218.047732) (xy 131.630082 -218.089163)
			(xy 131.594768 -218.125609) (xy 131.554282 -218.156208) (xy 131.509582 -218.180235) (xy 131.461726 -218.197122)
			(xy 131.436872 -218.202256) (xy 131.414012 -218.206574) (xy 131.209288 -218.561412) (xy 131.217162 -218.583256)
			(xy 131.225814 -218.609662) (xy 131.23513 -218.66444) (xy 131.235704 -218.692222) (xy 132.45592 -218.692222)
			(xy 132.456445 -218.666878) (xy 132.464214 -218.616789) (xy 132.479557 -218.56848) (xy 132.502112 -218.523087)
			(xy 132.531349 -218.481681) (xy 132.566578 -218.445236) (xy 132.606969 -218.414613) (xy 132.65157 -218.390531)
			(xy 132.699332 -218.373559) (xy 132.724144 -218.368372) (xy 132.747004 -218.364054) (xy 132.952236 -218.008708)
			(xy 132.944362 -217.98661) (xy 132.935894 -217.960366) (xy 132.926824 -217.905977) (xy 132.926328 -217.878406)
			(xy 132.926836 -217.852519) (xy 132.934935 -217.801381) (xy 132.950934 -217.752141) (xy 132.97444 -217.706009)
			(xy 133.004872 -217.664122) (xy 133.041482 -217.627512) (xy 133.083369 -217.59708) (xy 133.129501 -217.573574)
			(xy 133.178741 -217.557575) (xy 133.229879 -217.549476) (xy 133.281653 -217.549476) (xy 133.332791 -217.557575)
			(xy 133.382031 -217.573574) (xy 133.428163 -217.59708) (xy 133.47005 -217.627512) (xy 133.50666 -217.664122)
			(xy 133.537092 -217.706009) (xy 133.560598 -217.752141) (xy 133.576597 -217.801381) (xy 133.584696 -217.852519)
			(xy 133.585204 -217.878406) (xy 133.584731 -217.90378) (xy 133.576962 -217.953931) (xy 133.561593 -218.002296)
			(xy 133.538988 -218.047732) (xy 133.509682 -218.089163) (xy 133.474368 -218.125609) (xy 133.433882 -218.156208)
			(xy 133.389182 -218.180235) (xy 133.341326 -218.197122) (xy 133.316472 -218.202256) (xy 133.293612 -218.206574)
			(xy 133.088888 -218.561412) (xy 133.096762 -218.583256) (xy 133.105414 -218.609662) (xy 133.11473 -218.66444)
			(xy 133.115304 -218.692222) (xy 133.114796 -218.718129) (xy 133.10669 -218.769306) (xy 133.090678 -218.818585)
			(xy 133.067155 -218.864752) (xy 133.036699 -218.906671) (xy 133.000061 -218.943309) (xy 132.958142 -218.973765)
			(xy 132.911975 -218.997288) (xy 132.862696 -219.0133) (xy 132.811519 -219.021406) (xy 132.759705 -219.021406)
			(xy 132.708528 -219.0133) (xy 132.659249 -218.997288) (xy 132.613082 -218.973765) (xy 132.571163 -218.943309)
			(xy 132.534525 -218.906671) (xy 132.504069 -218.864752) (xy 132.480546 -218.818585) (xy 132.464534 -218.769306)
			(xy 132.456428 -218.718129) (xy 132.45592 -218.692222) (xy 131.235704 -218.692222) (xy 131.235196 -218.718129)
			(xy 131.22709 -218.769306) (xy 131.211078 -218.818585) (xy 131.187555 -218.864752) (xy 131.157099 -218.906671)
			(xy 131.120461 -218.943309) (xy 131.078542 -218.973765) (xy 131.032375 -218.997288) (xy 130.983096 -219.0133)
			(xy 130.931919 -219.021406) (xy 130.880105 -219.021406) (xy 130.828928 -219.0133) (xy 130.779649 -218.997288)
			(xy 130.733482 -218.973765) (xy 130.691563 -218.943309) (xy 130.654925 -218.906671) (xy 130.624469 -218.864752)
			(xy 130.600946 -218.818585) (xy 130.584934 -218.769306) (xy 130.576828 -218.718129) (xy 130.57632 -218.692222)
			(xy 129.356104 -218.692222) (xy 129.355596 -218.718129) (xy 129.34749 -218.769306) (xy 129.331478 -218.818585)
			(xy 129.307955 -218.864752) (xy 129.277499 -218.906671) (xy 129.240861 -218.943309) (xy 129.198942 -218.973765)
			(xy 129.152775 -218.997288) (xy 129.103496 -219.0133) (xy 129.052319 -219.021406) (xy 129.000505 -219.021406)
			(xy 128.949328 -219.0133) (xy 128.900049 -218.997288) (xy 128.853882 -218.973765) (xy 128.811963 -218.943309)
			(xy 128.775325 -218.906671) (xy 128.744869 -218.864752) (xy 128.721346 -218.818585) (xy 128.705334 -218.769306)
			(xy 128.697228 -218.718129) (xy 128.69672 -218.692222) (xy 127.882142 -218.692222) (xy 127.882142 -219.312744)
			(xy 127.896977 -219.33392) (xy 127.9205 -219.379959) (xy 127.936512 -219.429118) (xy 127.944615 -219.48018)
			(xy 127.944611 -219.531881) (xy 127.936497 -219.582941) (xy 127.920476 -219.632098) (xy 127.896944 -219.678133)
			(xy 127.882142 -219.699332) (xy 127.882142 -219.901262) (xy 127.882666 -219.916626) (xy 127.891798 -219.945964)
			(xy 127.909246 -219.971257) (xy 127.933429 -219.990212) (xy 127.962157 -220.001113) (xy 127.992827 -220.002973)
			(xy 128.007872 -219.999814) (xy 128.027251 -219.995371) (xy 128.066731 -219.990659) (xy 128.086612 -219.990416)
			(xy 128.112506 -219.990924) (xy 128.163656 -219.999024) (xy 128.212911 -220.015021) (xy 128.259059 -220.038523)
			(xy 128.300964 -220.068951) (xy 128.337597 -220.105558) (xy 128.368055 -220.147441) (xy 128.391589 -220.193573)
			(xy 128.407622 -220.242816) (xy 128.415757 -220.293961) (xy 128.416304 -220.319854) (xy 129.63652 -220.319854)
			(xy 129.637028 -220.293947) (xy 129.645134 -220.24277) (xy 129.661146 -220.193491) (xy 129.684669 -220.147324)
			(xy 129.715125 -220.105405) (xy 129.751763 -220.068767) (xy 129.793682 -220.038311) (xy 129.839849 -220.014788)
			(xy 129.889128 -219.998776) (xy 129.940305 -219.99067) (xy 129.992119 -219.99067) (xy 130.043296 -219.998776)
			(xy 130.092575 -220.014788) (xy 130.138742 -220.038311) (xy 130.180661 -220.068767) (xy 130.217299 -220.105405)
			(xy 130.247755 -220.147324) (xy 130.271278 -220.193491) (xy 130.28729 -220.24277) (xy 130.295396 -220.293947)
			(xy 130.295904 -220.319854) (xy 131.51612 -220.319854) (xy 131.516628 -220.293947) (xy 131.524734 -220.24277)
			(xy 131.540746 -220.193491) (xy 131.564269 -220.147324) (xy 131.594725 -220.105405) (xy 131.631363 -220.068767)
			(xy 131.673282 -220.038311) (xy 131.719449 -220.014788) (xy 131.768728 -219.998776) (xy 131.819905 -219.99067)
			(xy 131.871719 -219.99067) (xy 131.922896 -219.998776) (xy 131.972175 -220.014788) (xy 132.018342 -220.038311)
			(xy 132.060261 -220.068767) (xy 132.096899 -220.105405) (xy 132.127355 -220.147324) (xy 132.150878 -220.193491)
			(xy 132.16689 -220.24277) (xy 132.174996 -220.293947) (xy 132.175504 -220.319854) (xy 133.396228 -220.319854)
			(xy 133.396736 -220.293967) (xy 133.404835 -220.242829) (xy 133.420834 -220.193589) (xy 133.44434 -220.147457)
			(xy 133.474772 -220.10557) (xy 133.511382 -220.06896) (xy 133.553269 -220.038528) (xy 133.599401 -220.015022)
			(xy 133.648641 -219.999023) (xy 133.699779 -219.990924) (xy 133.751553 -219.990924) (xy 133.802691 -219.999023)
			(xy 133.851931 -220.015022) (xy 133.898063 -220.038528) (xy 133.93995 -220.06896) (xy 133.97656 -220.10557)
			(xy 134.006992 -220.147457) (xy 134.030498 -220.193589) (xy 134.046497 -220.242829) (xy 134.054596 -220.293967)
			(xy 134.055104 -220.319854) (xy 134.054563 -220.347562) (xy 134.045375 -220.402208) (xy 134.036816 -220.428566)
			(xy 134.029196 -220.450664) (xy 134.234174 -220.805756) (xy 134.257034 -220.810074) (xy 134.281845 -220.815229)
			(xy 134.329584 -220.832223) (xy 134.374162 -220.856322) (xy 134.414527 -220.886957) (xy 134.44973 -220.923408)
			(xy 134.47894 -220.964816) (xy 134.501472 -221.010206) (xy 134.516792 -221.058509) (xy 134.524542 -221.108587)
			(xy 134.525004 -221.133924) (xy 134.524496 -221.159811) (xy 134.516397 -221.210949) (xy 134.500398 -221.260189)
			(xy 134.476892 -221.306321) (xy 134.44646 -221.348208) (xy 134.40985 -221.384818) (xy 134.367963 -221.41525)
			(xy 134.321831 -221.438756) (xy 134.272591 -221.454755) (xy 134.221453 -221.462854) (xy 134.169679 -221.462854)
			(xy 134.118541 -221.454755) (xy 134.069301 -221.438756) (xy 134.023169 -221.41525) (xy 133.981282 -221.384818)
			(xy 133.944672 -221.348208) (xy 133.91424 -221.306321) (xy 133.890734 -221.260189) (xy 133.874735 -221.210949)
			(xy 133.866636 -221.159811) (xy 133.866128 -221.133924) (xy 133.866667 -221.106216) (xy 133.875856 -221.05157)
			(xy 133.884416 -221.025212) (xy 133.89229 -221.003114) (xy 133.687312 -220.648022) (xy 133.664452 -220.643704)
			(xy 133.639631 -220.638536) (xy 133.591852 -220.621582) (xy 133.547233 -220.59751) (xy 133.506826 -220.56689)
			(xy 133.471585 -220.530444) (xy 133.442341 -220.48903) (xy 133.419784 -220.443627) (xy 133.404447 -220.395304)
			(xy 133.39669 -220.345203) (xy 133.396228 -220.319854) (xy 132.175504 -220.319854) (xy 132.174894 -220.347507)
			(xy 132.165571 -220.402025) (xy 132.156962 -220.428312) (xy 132.149342 -220.45041) (xy 132.354574 -220.805756)
			(xy 132.377434 -220.810074) (xy 132.402245 -220.815229) (xy 132.449984 -220.832223) (xy 132.494562 -220.856322)
			(xy 132.534927 -220.886957) (xy 132.57013 -220.923408) (xy 132.59934 -220.964816) (xy 132.621872 -221.010206)
			(xy 132.637192 -221.058509) (xy 132.644942 -221.108587) (xy 132.645404 -221.133924) (xy 132.644896 -221.159811)
			(xy 132.636797 -221.210949) (xy 132.620798 -221.260189) (xy 132.597292 -221.306321) (xy 132.56686 -221.348208)
			(xy 132.53025 -221.384818) (xy 132.488363 -221.41525) (xy 132.442231 -221.438756) (xy 132.392991 -221.454755)
			(xy 132.341853 -221.462854) (xy 132.290079 -221.462854) (xy 132.238941 -221.454755) (xy 132.189701 -221.438756)
			(xy 132.143569 -221.41525) (xy 132.101682 -221.384818) (xy 132.065072 -221.348208) (xy 132.03464 -221.306321)
			(xy 132.011134 -221.260189) (xy 131.995135 -221.210949) (xy 131.987036 -221.159811) (xy 131.986528 -221.133924)
			(xy 131.987067 -221.106216) (xy 131.996256 -221.05157) (xy 132.004816 -221.025212) (xy 132.01269 -221.003114)
			(xy 131.807712 -220.648022) (xy 131.784852 -220.643704) (xy 131.76 -220.63857) (xy 131.712153 -220.621668)
			(xy 131.667462 -220.597632) (xy 131.626984 -220.567029) (xy 131.591674 -220.530584) (xy 131.562368 -220.489157)
			(xy 131.539757 -220.443728) (xy 131.524377 -220.39537) (xy 131.516591 -220.345226) (xy 131.51612 -220.319854)
			(xy 130.295904 -220.319854) (xy 130.295294 -220.347507) (xy 130.285971 -220.402025) (xy 130.277362 -220.428312)
			(xy 130.269742 -220.45041) (xy 130.474974 -220.805756) (xy 130.497834 -220.810074) (xy 130.522645 -220.815229)
			(xy 130.570384 -220.832223) (xy 130.614962 -220.856322) (xy 130.655327 -220.886957) (xy 130.69053 -220.923408)
			(xy 130.71974 -220.964816) (xy 130.742272 -221.010206) (xy 130.757592 -221.058509) (xy 130.765342 -221.108587)
			(xy 130.765804 -221.133924) (xy 130.765296 -221.159811) (xy 130.757197 -221.210949) (xy 130.741198 -221.260189)
			(xy 130.717692 -221.306321) (xy 130.68726 -221.348208) (xy 130.65065 -221.384818) (xy 130.608763 -221.41525)
			(xy 130.562631 -221.438756) (xy 130.513391 -221.454755) (xy 130.462253 -221.462854) (xy 130.410479 -221.462854)
			(xy 130.359341 -221.454755) (xy 130.310101 -221.438756) (xy 130.263969 -221.41525) (xy 130.222082 -221.384818)
			(xy 130.185472 -221.348208) (xy 130.15504 -221.306321) (xy 130.131534 -221.260189) (xy 130.115535 -221.210949)
			(xy 130.107436 -221.159811) (xy 130.106928 -221.133924) (xy 130.107467 -221.106216) (xy 130.116656 -221.05157)
			(xy 130.125216 -221.025212) (xy 130.13309 -221.003114) (xy 129.928112 -220.648022) (xy 129.905252 -220.643704)
			(xy 129.8804 -220.63857) (xy 129.832553 -220.621668) (xy 129.787862 -220.597632) (xy 129.747384 -220.567029)
			(xy 129.712074 -220.530584) (xy 129.682768 -220.489157) (xy 129.660157 -220.443728) (xy 129.644777 -220.39537)
			(xy 129.636991 -220.345226) (xy 129.63652 -220.319854) (xy 128.416304 -220.319854) (xy 128.415699 -220.347508)
			(xy 128.406381 -220.402028) (xy 128.397762 -220.428312) (xy 128.390142 -220.45041) (xy 128.595374 -220.805756)
			(xy 128.618234 -220.810074) (xy 128.643033 -220.815274) (xy 128.690766 -220.832266) (xy 128.735337 -220.856361)
			(xy 128.775696 -220.886992) (xy 128.810894 -220.923438) (xy 128.8401 -220.96484) (xy 128.862628 -221.010223)
			(xy 128.877947 -221.058519) (xy 128.885696 -221.10859) (xy 128.886204 -221.133924) (xy 128.885696 -221.159811)
			(xy 128.877597 -221.210949) (xy 128.861598 -221.260189) (xy 128.838092 -221.306321) (xy 128.80766 -221.348208)
			(xy 128.77105 -221.384818) (xy 128.729163 -221.41525) (xy 128.683031 -221.438756) (xy 128.633791 -221.454755)
			(xy 128.582653 -221.462854) (xy 128.530879 -221.462854) (xy 128.479741 -221.454755) (xy 128.430501 -221.438756)
			(xy 128.384369 -221.41525) (xy 128.342482 -221.384818) (xy 128.305872 -221.348208) (xy 128.27544 -221.306321)
			(xy 128.251934 -221.260189) (xy 128.235935 -221.210949) (xy 128.227836 -221.159811) (xy 128.227328 -221.133924)
			(xy 128.227855 -221.106216) (xy 128.23705 -221.051569) (xy 128.245616 -221.025212) (xy 128.25349 -221.003114)
			(xy 128.048512 -220.648022) (xy 128.025652 -220.643704) (xy 128.007872 -220.639894) (xy 127.992836 -220.636768)
			(xy 127.962197 -220.638677) (xy 127.933507 -220.649595) (xy 127.909351 -220.668538) (xy 127.891908 -220.693798)
			(xy 127.88275 -220.723098) (xy 127.882142 -220.738446) (xy 127.882142 -220.938344) (xy 127.897268 -220.959724)
			(xy 127.921275 -221.006268) (xy 127.937622 -221.056022) (xy 127.945898 -221.107734) (xy 127.945894 -221.160104)
			(xy 127.937612 -221.211816) (xy 127.92126 -221.261568) (xy 127.897248 -221.308109) (xy 127.882142 -221.329504)
			(xy 127.882142 -221.94774) (xy 128.69672 -221.94774) (xy 128.697171 -221.922394) (xy 128.704952 -221.872302)
			(xy 128.720306 -221.82399) (xy 128.742872 -221.778597) (xy 128.772118 -221.737192) (xy 128.807355 -221.700749)
			(xy 128.847754 -221.670127) (xy 128.892362 -221.646047) (xy 128.94013 -221.629076) (xy 128.964944 -221.62389)
			(xy 128.987804 -221.619572) (xy 129.193036 -221.264226) (xy 129.185162 -221.242128) (xy 129.176698 -221.215883)
			(xy 129.167625 -221.161495) (xy 129.167128 -221.133924) (xy 129.167636 -221.108037) (xy 129.175735 -221.056899)
			(xy 129.191734 -221.007659) (xy 129.21524 -220.961527) (xy 129.245672 -220.91964) (xy 129.282282 -220.88303)
			(xy 129.324169 -220.852598) (xy 129.370301 -220.829092) (xy 129.419541 -220.813093) (xy 129.470679 -220.804994)
			(xy 129.522453 -220.804994) (xy 129.573591 -220.813093) (xy 129.622831 -220.829092) (xy 129.668963 -220.852598)
			(xy 129.71085 -220.88303) (xy 129.74746 -220.91964) (xy 129.777892 -220.961527) (xy 129.801398 -221.007659)
			(xy 129.817397 -221.056899) (xy 129.825496 -221.108037) (xy 129.826004 -221.133924) (xy 129.825548 -221.159299)
			(xy 129.817776 -221.20945) (xy 129.802404 -221.257815) (xy 129.779797 -221.303251) (xy 129.750489 -221.344682)
			(xy 129.715173 -221.381128) (xy 129.674685 -221.411727) (xy 129.629984 -221.435754) (xy 129.582126 -221.452641)
			(xy 129.557272 -221.457774) (xy 129.534412 -221.462092) (xy 129.329688 -221.81693) (xy 129.337562 -221.838774)
			(xy 129.346219 -221.865179) (xy 129.355532 -221.919958) (xy 129.356104 -221.94774) (xy 130.57632 -221.94774)
			(xy 130.576771 -221.922394) (xy 130.584552 -221.872302) (xy 130.599906 -221.82399) (xy 130.622472 -221.778597)
			(xy 130.651718 -221.737192) (xy 130.686955 -221.700749) (xy 130.727354 -221.670127) (xy 130.771962 -221.646047)
			(xy 130.81973 -221.629076) (xy 130.844544 -221.62389) (xy 130.867404 -221.619572) (xy 131.072636 -221.264226)
			(xy 131.064762 -221.242128) (xy 131.056298 -221.215883) (xy 131.047225 -221.161495) (xy 131.046728 -221.133924)
			(xy 131.047236 -221.108037) (xy 131.055335 -221.056899) (xy 131.071334 -221.007659) (xy 131.09484 -220.961527)
			(xy 131.125272 -220.91964) (xy 131.161882 -220.88303) (xy 131.203769 -220.852598) (xy 131.249901 -220.829092)
			(xy 131.299141 -220.813093) (xy 131.350279 -220.804994) (xy 131.402053 -220.804994) (xy 131.453191 -220.813093)
			(xy 131.502431 -220.829092) (xy 131.548563 -220.852598) (xy 131.59045 -220.88303) (xy 131.62706 -220.91964)
			(xy 131.657492 -220.961527) (xy 131.680998 -221.007659) (xy 131.696997 -221.056899) (xy 131.705096 -221.108037)
			(xy 131.705604 -221.133924) (xy 131.705148 -221.159299) (xy 131.697376 -221.20945) (xy 131.682004 -221.257815)
			(xy 131.659397 -221.303251) (xy 131.630089 -221.344682) (xy 131.594773 -221.381128) (xy 131.554285 -221.411727)
			(xy 131.509584 -221.435754) (xy 131.461726 -221.452641) (xy 131.436872 -221.457774) (xy 131.414012 -221.462092)
			(xy 131.209288 -221.81693) (xy 131.217162 -221.838774) (xy 131.225819 -221.865179) (xy 131.235132 -221.919958)
			(xy 131.235704 -221.94774) (xy 132.45592 -221.94774) (xy 132.456371 -221.922394) (xy 132.464152 -221.872302)
			(xy 132.479506 -221.82399) (xy 132.502072 -221.778597) (xy 132.531318 -221.737192) (xy 132.566555 -221.700749)
			(xy 132.606954 -221.670127) (xy 132.651562 -221.646047) (xy 132.69933 -221.629076) (xy 132.724144 -221.62389)
			(xy 132.747004 -221.619572) (xy 132.951982 -221.263972) (xy 132.944362 -221.242128) (xy 132.935911 -221.215946)
			(xy 132.92684 -221.161685) (xy 132.926328 -221.134178) (xy 132.926328 -221.133924) (xy 132.926836 -221.108037)
			(xy 132.934935 -221.056899) (xy 132.950934 -221.007659) (xy 132.97444 -220.961527) (xy 133.004872 -220.91964)
			(xy 133.041482 -220.88303) (xy 133.083369 -220.852598) (xy 133.129501 -220.829092) (xy 133.178741 -220.813093)
			(xy 133.229879 -220.804994) (xy 133.281653 -220.804994) (xy 133.332791 -220.813093) (xy 133.382031 -220.829092)
			(xy 133.428163 -220.852598) (xy 133.47005 -220.88303) (xy 133.50666 -220.91964) (xy 133.537092 -220.961527)
			(xy 133.560598 -221.007659) (xy 133.576597 -221.056899) (xy 133.584696 -221.108037) (xy 133.585204 -221.133924)
			(xy 133.584785 -221.15929) (xy 133.577033 -221.209425) (xy 133.561684 -221.257778) (xy 133.539102 -221.303206)
			(xy 133.509821 -221.344633) (xy 133.474533 -221.381081) (xy 133.434074 -221.411686) (xy 133.3894 -221.435725)
			(xy 133.341569 -221.45263) (xy 133.316726 -221.457774) (xy 133.293866 -221.462092) (xy 133.089142 -221.81693)
			(xy 133.096762 -221.838774) (xy 133.105377 -221.865059) (xy 133.114698 -221.919578) (xy 133.115304 -221.947232)
			(xy 133.115304 -221.94774) (xy 134.33552 -221.94774) (xy 134.335971 -221.922394) (xy 134.343752 -221.872302)
			(xy 134.359106 -221.82399) (xy 134.381672 -221.778597) (xy 134.410918 -221.737192) (xy 134.446155 -221.700749)
			(xy 134.486554 -221.670127) (xy 134.531162 -221.646047) (xy 134.57893 -221.629076) (xy 134.603744 -221.62389)
			(xy 134.626604 -221.619572) (xy 134.831582 -221.263972) (xy 134.823962 -221.242128) (xy 134.815511 -221.215946)
			(xy 134.80644 -221.161685) (xy 134.805928 -221.134178) (xy 134.805928 -221.133924) (xy 134.806436 -221.108037)
			(xy 134.814535 -221.056899) (xy 134.830534 -221.007659) (xy 134.85404 -220.961527) (xy 134.884472 -220.91964)
			(xy 134.921082 -220.88303) (xy 134.962969 -220.852598) (xy 135.009101 -220.829092) (xy 135.058341 -220.813093)
			(xy 135.109479 -220.804994) (xy 135.161253 -220.804994) (xy 135.212391 -220.813093) (xy 135.261631 -220.829092)
			(xy 135.307763 -220.852598) (xy 135.34965 -220.88303) (xy 135.38626 -220.91964) (xy 135.416692 -220.961527)
			(xy 135.440198 -221.007659) (xy 135.456197 -221.056899) (xy 135.464296 -221.108037) (xy 135.464804 -221.133924)
			(xy 135.464385 -221.15929) (xy 135.456633 -221.209425) (xy 135.441284 -221.257778) (xy 135.418702 -221.303206)
			(xy 135.389421 -221.344633) (xy 135.354133 -221.381081) (xy 135.313674 -221.411686) (xy 135.269 -221.435725)
			(xy 135.221169 -221.45263) (xy 135.196326 -221.457774) (xy 135.173466 -221.462092) (xy 134.968742 -221.81693)
			(xy 134.976362 -221.838774) (xy 134.984977 -221.865059) (xy 134.994298 -221.919578) (xy 134.994904 -221.947232)
			(xy 134.994904 -221.94774) (xy 134.994396 -221.973647) (xy 134.98629 -222.024824) (xy 134.970278 -222.074103)
			(xy 134.946755 -222.12027) (xy 134.916299 -222.162189) (xy 134.879661 -222.198827) (xy 134.837742 -222.229283)
			(xy 134.791575 -222.252806) (xy 134.742296 -222.268818) (xy 134.691119 -222.276924) (xy 134.639305 -222.276924)
			(xy 134.588128 -222.268818) (xy 134.538849 -222.252806) (xy 134.492682 -222.229283) (xy 134.450763 -222.198827)
			(xy 134.414125 -222.162189) (xy 134.383669 -222.12027) (xy 134.360146 -222.074103) (xy 134.344134 -222.024824)
			(xy 134.336028 -221.973647) (xy 134.33552 -221.94774) (xy 133.115304 -221.94774) (xy 133.114796 -221.973647)
			(xy 133.10669 -222.024824) (xy 133.090678 -222.074103) (xy 133.067155 -222.12027) (xy 133.036699 -222.162189)
			(xy 133.000061 -222.198827) (xy 132.958142 -222.229283) (xy 132.911975 -222.252806) (xy 132.862696 -222.268818)
			(xy 132.811519 -222.276924) (xy 132.759705 -222.276924) (xy 132.708528 -222.268818) (xy 132.659249 -222.252806)
			(xy 132.613082 -222.229283) (xy 132.571163 -222.198827) (xy 132.534525 -222.162189) (xy 132.504069 -222.12027)
			(xy 132.480546 -222.074103) (xy 132.464534 -222.024824) (xy 132.456428 -221.973647) (xy 132.45592 -221.94774)
			(xy 131.235704 -221.94774) (xy 131.235196 -221.973647) (xy 131.22709 -222.024824) (xy 131.211078 -222.074103)
			(xy 131.187555 -222.12027) (xy 131.157099 -222.162189) (xy 131.120461 -222.198827) (xy 131.078542 -222.229283)
			(xy 131.032375 -222.252806) (xy 130.983096 -222.268818) (xy 130.931919 -222.276924) (xy 130.880105 -222.276924)
			(xy 130.828928 -222.268818) (xy 130.779649 -222.252806) (xy 130.733482 -222.229283) (xy 130.691563 -222.198827)
			(xy 130.654925 -222.162189) (xy 130.624469 -222.12027) (xy 130.600946 -222.074103) (xy 130.584934 -222.024824)
			(xy 130.576828 -221.973647) (xy 130.57632 -221.94774) (xy 129.356104 -221.94774) (xy 129.355596 -221.973647)
			(xy 129.34749 -222.024824) (xy 129.331478 -222.074103) (xy 129.307955 -222.12027) (xy 129.277499 -222.162189)
			(xy 129.240861 -222.198827) (xy 129.198942 -222.229283) (xy 129.152775 -222.252806) (xy 129.103496 -222.268818)
			(xy 129.052319 -222.276924) (xy 129.000505 -222.276924) (xy 128.949328 -222.268818) (xy 128.900049 -222.252806)
			(xy 128.853882 -222.229283) (xy 128.811963 -222.198827) (xy 128.775325 -222.162189) (xy 128.744869 -222.12027)
			(xy 128.721346 -222.074103) (xy 128.705334 -222.024824) (xy 128.697228 -221.973647) (xy 128.69672 -221.94774)
			(xy 127.882142 -221.94774) (xy 127.882142 -222.568262) (xy 127.896983 -222.589438) (xy 127.92052 -222.635479)
			(xy 127.936544 -222.684642) (xy 127.944659 -222.73571) (xy 127.944664 -222.787419) (xy 127.93656 -222.838488)
			(xy 127.920547 -222.887655) (xy 127.897021 -222.933702) (xy 127.882142 -222.95485) (xy 127.882142 -223.157034)
			(xy 127.882663 -223.172401) (xy 127.89179 -223.201747) (xy 127.909236 -223.227047) (xy 127.933422 -223.246008)
			(xy 127.962155 -223.256913) (xy 127.992831 -223.258772) (xy 128.007872 -223.255586) (xy 128.027251 -223.251143)
			(xy 128.066731 -223.246432) (xy 128.086612 -223.246188) (xy 128.112507 -223.246696) (xy 128.163659 -223.254795)
			(xy 128.212915 -223.270792) (xy 128.259065 -223.294293) (xy 128.300973 -223.324721) (xy 128.337608 -223.361327)
			(xy 128.368069 -223.403211) (xy 128.391608 -223.449342) (xy 128.407644 -223.498586) (xy 128.415784 -223.549732)
			(xy 128.416304 -223.575626) (xy 128.415829 -223.600984) (xy 128.408044 -223.651099) (xy 128.392676 -223.699431)
			(xy 128.370088 -223.744839) (xy 128.340813 -223.786253) (xy 128.305542 -223.822696) (xy 128.265106 -223.853307)
			(xy 128.22046 -223.877366) (xy 128.172655 -223.894304) (xy 128.147826 -223.899476) (xy 128.124966 -223.903794)
			(xy 127.920242 -224.258632) (xy 127.928116 -224.280476) (xy 127.936696 -224.306895) (xy 127.945893 -224.36167)
			(xy 127.946404 -224.389442) (xy 128.227328 -224.389442) (xy 128.227836 -224.363555) (xy 128.235935 -224.312417)
			(xy 128.251934 -224.263177) (xy 128.27544 -224.217045) (xy 128.305872 -224.175158) (xy 128.342482 -224.138548)
			(xy 128.384369 -224.108116) (xy 128.430501 -224.08461) (xy 128.479741 -224.068611) (xy 128.530879 -224.060512)
			(xy 128.582653 -224.060512) (xy 128.633791 -224.068611) (xy 128.683031 -224.08461) (xy 128.729163 -224.108116)
			(xy 128.77105 -224.138548) (xy 128.80766 -224.175158) (xy 128.838092 -224.217045) (xy 128.861598 -224.263177)
			(xy 128.877597 -224.312417) (xy 128.885696 -224.363555) (xy 128.886204 -224.389442) (xy 129.167128 -224.389442)
			(xy 129.167535 -224.364105) (xy 129.175297 -224.314028) (xy 129.190629 -224.265728) (xy 129.21317 -224.220343)
			(xy 129.242389 -224.17894) (xy 129.277599 -224.142496) (xy 129.31797 -224.111867) (xy 129.362552 -224.087776)
			(xy 129.410295 -224.070789) (xy 129.435098 -224.065592) (xy 129.457958 -224.061274) (xy 129.662682 -223.706436)
			(xy 129.655062 -223.684338) (xy 129.646431 -223.657991) (xy 129.63711 -223.603344) (xy 129.63652 -223.575626)
			(xy 129.637028 -223.549719) (xy 129.645134 -223.498542) (xy 129.661146 -223.449263) (xy 129.684669 -223.403096)
			(xy 129.715125 -223.361177) (xy 129.751763 -223.324539) (xy 129.793682 -223.294083) (xy 129.839849 -223.27056)
			(xy 129.889128 -223.254548) (xy 129.940305 -223.246442) (xy 129.992119 -223.246442) (xy 130.043296 -223.254548)
			(xy 130.092575 -223.27056) (xy 130.138742 -223.294083) (xy 130.180661 -223.324539) (xy 130.217299 -223.361177)
			(xy 130.247755 -223.403096) (xy 130.271278 -223.449263) (xy 130.28729 -223.498542) (xy 130.295396 -223.549719)
			(xy 130.295904 -223.575626) (xy 130.295487 -223.600992) (xy 130.287734 -223.651127) (xy 130.272385 -223.69948)
			(xy 130.249803 -223.744908) (xy 130.220522 -223.786336) (xy 130.185234 -223.822783) (xy 130.144775 -223.853388)
			(xy 130.100101 -223.877427) (xy 130.052269 -223.894332) (xy 130.027426 -223.899476) (xy 130.004566 -223.903794)
			(xy 129.799842 -224.258632) (xy 129.807716 -224.280476) (xy 129.81629 -224.306896) (xy 129.82549 -224.36167)
			(xy 129.826004 -224.389442) (xy 130.106928 -224.389442) (xy 130.107436 -224.363555) (xy 130.115535 -224.312417)
			(xy 130.131534 -224.263177) (xy 130.15504 -224.217045) (xy 130.185472 -224.175158) (xy 130.222082 -224.138548)
			(xy 130.263969 -224.108116) (xy 130.310101 -224.08461) (xy 130.359341 -224.068611) (xy 130.410479 -224.060512)
			(xy 130.462253 -224.060512) (xy 130.513391 -224.068611) (xy 130.562631 -224.08461) (xy 130.608763 -224.108116)
			(xy 130.65065 -224.138548) (xy 130.68726 -224.175158) (xy 130.717692 -224.217045) (xy 130.741198 -224.263177)
			(xy 130.757197 -224.312417) (xy 130.765296 -224.363555) (xy 130.765804 -224.389442) (xy 131.046728 -224.389442)
			(xy 131.047135 -224.364105) (xy 131.054897 -224.314028) (xy 131.070229 -224.265728) (xy 131.09277 -224.220343)
			(xy 131.121989 -224.17894) (xy 131.157199 -224.142496) (xy 131.19757 -224.111867) (xy 131.242152 -224.087776)
			(xy 131.289895 -224.070789) (xy 131.314698 -224.065592) (xy 131.337558 -224.061274) (xy 131.542282 -223.706182)
			(xy 131.534662 -223.684338) (xy 131.526017 -223.657995) (xy 131.516704 -223.603345) (xy 131.51612 -223.575626)
			(xy 131.516628 -223.549719) (xy 131.524734 -223.498542) (xy 131.540746 -223.449263) (xy 131.564269 -223.403096)
			(xy 131.594725 -223.361177) (xy 131.631363 -223.324539) (xy 131.673282 -223.294083) (xy 131.719449 -223.27056)
			(xy 131.768728 -223.254548) (xy 131.819905 -223.246442) (xy 131.871719 -223.246442) (xy 131.922896 -223.254548)
			(xy 131.972175 -223.27056) (xy 132.018342 -223.294083) (xy 132.060261 -223.324539) (xy 132.096899 -223.361177)
			(xy 132.127355 -223.403096) (xy 132.150878 -223.449263) (xy 132.16689 -223.498542) (xy 132.174996 -223.549719)
			(xy 132.175504 -223.575626) (xy 132.175003 -223.60097) (xy 132.167228 -223.651059) (xy 132.151879 -223.699368)
			(xy 132.12932 -223.74476) (xy 132.10008 -223.786165) (xy 132.064849 -223.822609) (xy 132.024457 -223.853232)
			(xy 131.979854 -223.877314) (xy 131.932092 -223.894288) (xy 131.90728 -223.899476) (xy 131.88442 -223.903794)
			(xy 131.679696 -224.258632) (xy 131.687316 -224.280476) (xy 131.695872 -224.306769) (xy 131.705065 -224.361289)
			(xy 131.705604 -224.388934) (xy 131.705604 -224.389442) (xy 131.986528 -224.389442) (xy 131.987036 -224.363555)
			(xy 131.995135 -224.312417) (xy 132.011134 -224.263177) (xy 132.03464 -224.217045) (xy 132.065072 -224.175158)
			(xy 132.101682 -224.138548) (xy 132.143569 -224.108116) (xy 132.189701 -224.08461) (xy 132.238941 -224.068611)
			(xy 132.290079 -224.060512) (xy 132.341853 -224.060512) (xy 132.392991 -224.068611) (xy 132.442231 -224.08461)
			(xy 132.488363 -224.108116) (xy 132.53025 -224.138548) (xy 132.56686 -224.175158) (xy 132.597292 -224.217045)
			(xy 132.620798 -224.263177) (xy 132.636797 -224.312417) (xy 132.644896 -224.363555) (xy 132.645404 -224.389442)
			(xy 132.926328 -224.389442) (xy 132.926735 -224.364105) (xy 132.934497 -224.314028) (xy 132.949829 -224.265728)
			(xy 132.97237 -224.220343) (xy 133.001589 -224.17894) (xy 133.036799 -224.142496) (xy 133.07717 -224.111867)
			(xy 133.121752 -224.087776) (xy 133.169495 -224.070789) (xy 133.194298 -224.065592) (xy 133.217158 -224.061274)
			(xy 133.422136 -223.705928) (xy 133.414516 -223.684084) (xy 133.405965 -223.657789) (xy 133.396771 -223.603271)
			(xy 133.396228 -223.575626) (xy 133.396736 -223.549739) (xy 133.404835 -223.498601) (xy 133.420834 -223.449361)
			(xy 133.44434 -223.403229) (xy 133.474772 -223.361342) (xy 133.511382 -223.324732) (xy 133.553269 -223.2943)
			(xy 133.599401 -223.270794) (xy 133.648641 -223.254795) (xy 133.699779 -223.246696) (xy 133.751553 -223.246696)
			(xy 133.802691 -223.254795) (xy 133.851931 -223.270794) (xy 133.898063 -223.2943) (xy 133.93995 -223.324732)
			(xy 133.97656 -223.361342) (xy 134.006992 -223.403229) (xy 134.030498 -223.449361) (xy 134.046497 -223.498601)
			(xy 134.054596 -223.549739) (xy 134.055104 -223.575626) (xy 134.054603 -223.60097) (xy 134.046828 -223.651059)
			(xy 134.031479 -223.699368) (xy 134.00892 -223.74476) (xy 133.97968 -223.786165) (xy 133.944449 -223.822609)
			(xy 133.904057 -223.853232) (xy 133.859454 -223.877314) (xy 133.811692 -223.894288) (xy 133.78688 -223.899476)
			(xy 133.76402 -223.903794) (xy 133.559296 -224.258632) (xy 133.566916 -224.280476) (xy 133.575472 -224.306769)
			(xy 133.584665 -224.361289) (xy 133.585204 -224.388934) (xy 133.585204 -224.389442) (xy 133.866128 -224.389442)
			(xy 133.866636 -224.363555) (xy 133.874735 -224.312417) (xy 133.890734 -224.263177) (xy 133.91424 -224.217045)
			(xy 133.944672 -224.175158) (xy 133.981282 -224.138548) (xy 134.023169 -224.108116) (xy 134.069301 -224.08461)
			(xy 134.118541 -224.068611) (xy 134.169679 -224.060512) (xy 134.221453 -224.060512) (xy 134.272591 -224.068611)
			(xy 134.321831 -224.08461) (xy 134.367963 -224.108116) (xy 134.40985 -224.138548) (xy 134.44646 -224.175158)
			(xy 134.476892 -224.217045) (xy 134.500398 -224.263177) (xy 134.516397 -224.312417) (xy 134.524496 -224.363555)
			(xy 134.525004 -224.389442) (xy 134.524474 -224.41715) (xy 134.515275 -224.471796) (xy 134.506716 -224.498154)
			(xy 134.499096 -224.519998) (xy 134.704074 -224.87509) (xy 134.726934 -224.879408) (xy 134.751752 -224.884531)
			(xy 134.799495 -224.901528) (xy 134.844074 -224.925629) (xy 134.88444 -224.956269) (xy 134.919643 -224.992724)
			(xy 134.948852 -225.034136) (xy 134.971381 -225.07953) (xy 134.986699 -225.127837) (xy 134.994445 -225.177919)
			(xy 134.994904 -225.203258) (xy 134.994396 -225.229145) (xy 134.986297 -225.280283) (xy 134.970298 -225.329523)
			(xy 134.946792 -225.375655) (xy 134.91636 -225.417542) (xy 134.87975 -225.454152) (xy 134.837863 -225.484584)
			(xy 134.791731 -225.50809) (xy 134.742491 -225.524089) (xy 134.691353 -225.532188) (xy 134.639579 -225.532188)
			(xy 134.588441 -225.524089) (xy 134.539201 -225.50809) (xy 134.493069 -225.484584) (xy 134.451182 -225.454152)
			(xy 134.414572 -225.417542) (xy 134.38414 -225.375655) (xy 134.360634 -225.329523) (xy 134.344635 -225.280283)
			(xy 134.336536 -225.229145) (xy 134.336028 -225.203258) (xy 134.336028 -225.20275) (xy 134.336589 -225.175107)
			(xy 134.345778 -225.120589) (xy 134.354316 -225.094292) (xy 134.361936 -225.072448) (xy 134.157212 -224.71761)
			(xy 134.134352 -224.713292) (xy 134.109529 -224.708135) (xy 134.061749 -224.69118) (xy 134.017129 -224.667108)
			(xy 133.976722 -224.636486) (xy 133.941481 -224.600038) (xy 133.912237 -224.558623) (xy 133.889681 -224.513218)
			(xy 133.874344 -224.464894) (xy 133.866589 -224.414792) (xy 133.866128 -224.389442) (xy 133.585204 -224.389442)
			(xy 133.584696 -224.415329) (xy 133.576597 -224.466467) (xy 133.560598 -224.515707) (xy 133.537092 -224.561839)
			(xy 133.50666 -224.603726) (xy 133.47005 -224.640336) (xy 133.428163 -224.670768) (xy 133.382031 -224.694274)
			(xy 133.332791 -224.710273) (xy 133.281653 -224.718372) (xy 133.229879 -224.718372) (xy 133.178741 -224.710273)
			(xy 133.129501 -224.694274) (xy 133.083369 -224.670768) (xy 133.041482 -224.640336) (xy 133.004872 -224.603726)
			(xy 132.97444 -224.561839) (xy 132.950934 -224.515707) (xy 132.934935 -224.466467) (xy 132.926836 -224.415329)
			(xy 132.926328 -224.389442) (xy 132.645404 -224.389442) (xy 132.64486 -224.417149) (xy 132.635674 -224.471796)
			(xy 132.627116 -224.498154) (xy 132.619242 -224.520252) (xy 132.82422 -224.87509) (xy 132.84708 -224.879408)
			(xy 132.871909 -224.884542) (xy 132.919688 -224.901501) (xy 132.964308 -224.925578) (xy 133.004714 -224.956202)
			(xy 133.039954 -224.992654) (xy 133.069197 -225.034071) (xy 133.091752 -225.079478) (xy 133.107088 -225.127804)
			(xy 133.114843 -225.177908) (xy 133.115304 -225.203258) (xy 133.114796 -225.229165) (xy 133.10669 -225.280342)
			(xy 133.090678 -225.329621) (xy 133.067155 -225.375788) (xy 133.036699 -225.417707) (xy 133.000061 -225.454345)
			(xy 132.958142 -225.484801) (xy 132.911975 -225.508324) (xy 132.862696 -225.524336) (xy 132.811519 -225.532442)
			(xy 132.759705 -225.532442) (xy 132.708528 -225.524336) (xy 132.659249 -225.508324) (xy 132.613082 -225.484801)
			(xy 132.571163 -225.454345) (xy 132.534525 -225.417707) (xy 132.504069 -225.375788) (xy 132.480546 -225.329621)
			(xy 132.464534 -225.280342) (xy 132.456428 -225.229165) (xy 132.45592 -225.203258) (xy 132.456527 -225.175541)
			(xy 132.465842 -225.120895) (xy 132.474462 -225.094546) (xy 132.482336 -225.072448) (xy 132.277358 -224.71761)
			(xy 132.254498 -224.713292) (xy 132.229685 -224.708145) (xy 132.181943 -224.691153) (xy 132.137363 -224.667056)
			(xy 132.096996 -224.63642) (xy 132.061793 -224.599968) (xy 132.032582 -224.558558) (xy 132.010052 -224.513166)
			(xy 131.994734 -224.46486) (xy 131.986988 -224.41478) (xy 131.986528 -224.389442) (xy 131.705604 -224.389442)
			(xy 131.705096 -224.415329) (xy 131.696997 -224.466467) (xy 131.680998 -224.515707) (xy 131.657492 -224.561839)
			(xy 131.62706 -224.603726) (xy 131.59045 -224.640336) (xy 131.548563 -224.670768) (xy 131.502431 -224.694274)
			(xy 131.453191 -224.710273) (xy 131.402053 -224.718372) (xy 131.350279 -224.718372) (xy 131.299141 -224.710273)
			(xy 131.249901 -224.694274) (xy 131.203769 -224.670768) (xy 131.161882 -224.640336) (xy 131.125272 -224.603726)
			(xy 131.09484 -224.561839) (xy 131.071334 -224.515707) (xy 131.055335 -224.466467) (xy 131.047236 -224.415329)
			(xy 131.046728 -224.389442) (xy 130.765804 -224.389442) (xy 130.76526 -224.417149) (xy 130.756074 -224.471796)
			(xy 130.747516 -224.498154) (xy 130.739642 -224.520252) (xy 130.94462 -224.87509) (xy 130.96748 -224.879408)
			(xy 130.992309 -224.884542) (xy 131.040088 -224.901501) (xy 131.084708 -224.925578) (xy 131.125114 -224.956202)
			(xy 131.160354 -224.992654) (xy 131.189597 -225.034071) (xy 131.212152 -225.079478) (xy 131.227488 -225.127804)
			(xy 131.235243 -225.177908) (xy 131.235704 -225.203258) (xy 131.235196 -225.229165) (xy 131.22709 -225.280342)
			(xy 131.211078 -225.329621) (xy 131.187555 -225.375788) (xy 131.157099 -225.417707) (xy 131.120461 -225.454345)
			(xy 131.078542 -225.484801) (xy 131.032375 -225.508324) (xy 130.983096 -225.524336) (xy 130.931919 -225.532442)
			(xy 130.880105 -225.532442) (xy 130.828928 -225.524336) (xy 130.779649 -225.508324) (xy 130.733482 -225.484801)
			(xy 130.691563 -225.454345) (xy 130.654925 -225.417707) (xy 130.624469 -225.375788) (xy 130.600946 -225.329621)
			(xy 130.584934 -225.280342) (xy 130.576828 -225.229165) (xy 130.57632 -225.203258) (xy 130.576927 -225.175541)
			(xy 130.586242 -225.120895) (xy 130.594862 -225.094546) (xy 130.602736 -225.072448) (xy 130.397758 -224.71761)
			(xy 130.374898 -224.713292) (xy 130.350085 -224.708145) (xy 130.302343 -224.691153) (xy 130.257763 -224.667056)
			(xy 130.217396 -224.63642) (xy 130.182193 -224.599968) (xy 130.152982 -224.558558) (xy 130.130452 -224.513166)
			(xy 130.115134 -224.46486) (xy 130.107388 -224.41478) (xy 130.106928 -224.389442) (xy 129.826004 -224.389442)
			(xy 129.825496 -224.415329) (xy 129.817397 -224.466467) (xy 129.801398 -224.515707) (xy 129.777892 -224.561839)
			(xy 129.74746 -224.603726) (xy 129.71085 -224.640336) (xy 129.668963 -224.670768) (xy 129.622831 -224.694274)
			(xy 129.573591 -224.710273) (xy 129.522453 -224.718372) (xy 129.470679 -224.718372) (xy 129.419541 -224.710273)
			(xy 129.370301 -224.694274) (xy 129.324169 -224.670768) (xy 129.282282 -224.640336) (xy 129.245672 -224.603726)
			(xy 129.21524 -224.561839) (xy 129.191734 -224.515707) (xy 129.175735 -224.466467) (xy 129.167636 -224.415329)
			(xy 129.167128 -224.389442) (xy 128.886204 -224.389442) (xy 128.88566 -224.417149) (xy 128.876474 -224.471796)
			(xy 128.867916 -224.498154) (xy 128.860042 -224.520252) (xy 129.06502 -224.87509) (xy 129.08788 -224.879408)
			(xy 129.112709 -224.884542) (xy 129.160488 -224.901501) (xy 129.205108 -224.925578) (xy 129.245514 -224.956202)
			(xy 129.280754 -224.992654) (xy 129.309997 -225.034071) (xy 129.332552 -225.079478) (xy 129.347888 -225.127804)
			(xy 129.355643 -225.177908) (xy 129.356104 -225.203258) (xy 129.355596 -225.229165) (xy 129.34749 -225.280342)
			(xy 129.331478 -225.329621) (xy 129.307955 -225.375788) (xy 129.277499 -225.417707) (xy 129.240861 -225.454345)
			(xy 129.198942 -225.484801) (xy 129.152775 -225.508324) (xy 129.103496 -225.524336) (xy 129.052319 -225.532442)
			(xy 129.000505 -225.532442) (xy 128.949328 -225.524336) (xy 128.900049 -225.508324) (xy 128.853882 -225.484801)
			(xy 128.811963 -225.454345) (xy 128.775325 -225.417707) (xy 128.744869 -225.375788) (xy 128.721346 -225.329621)
			(xy 128.705334 -225.280342) (xy 128.697228 -225.229165) (xy 128.69672 -225.203258) (xy 128.697327 -225.175541)
			(xy 128.706642 -225.120895) (xy 128.715262 -225.094546) (xy 128.723136 -225.072448) (xy 128.518158 -224.71761)
			(xy 128.495298 -224.713292) (xy 128.470485 -224.708145) (xy 128.422743 -224.691153) (xy 128.378163 -224.667056)
			(xy 128.337796 -224.63642) (xy 128.302593 -224.599968) (xy 128.273382 -224.558558) (xy 128.250852 -224.513166)
			(xy 128.235534 -224.46486) (xy 128.227788 -224.41478) (xy 128.227328 -224.389442) (xy 127.946404 -224.389442)
			(xy 127.945898 -224.415627) (xy 127.937615 -224.467338) (xy 127.921264 -224.51709) (xy 127.897256 -224.563633)
			(xy 127.882142 -224.585022) (xy 127.882142 -225.336354) (xy 128.32588 -225.780092) (xy 128.360932 -225.75393)
			(xy 128.382307 -225.7387) (xy 128.428882 -225.714515) (xy 128.478711 -225.698044) (xy 128.530526 -225.689708)
			(xy 128.556766 -225.68916) (xy 128.582557 -225.689637) (xy 128.633503 -225.697702) (xy 128.682561 -225.713638)
			(xy 128.728521 -225.737053) (xy 128.770252 -225.76737) (xy 128.806726 -225.803843) (xy 128.837044 -225.845574)
			(xy 128.86046 -225.891533) (xy 128.876397 -225.940591) (xy 128.884463 -225.991537) (xy 128.884934 -226.017328)
			(xy 128.884417 -226.043569) (xy 128.876067 -226.095383) (xy 128.859583 -226.145209) (xy 128.835385 -226.19178)
			(xy 128.820164 -226.213162) (xy 128.794002 -226.248214) (xy 129.049018 -226.50323) (xy 129.066544 -226.505516)
			(xy 129.090865 -226.508949) (xy 129.138175 -226.522149) (xy 129.182988 -226.542258) (xy 129.2243 -226.568826)
			(xy 129.261188 -226.601257) (xy 129.292826 -226.638827) (xy 129.318508 -226.680695) (xy 129.337658 -226.725926)
			(xy 129.344166 -226.74961) (xy 129.354072 -226.78771) (xy 129.638552 -226.78771) (xy 129.648458 -226.74961)
			(xy 129.655243 -226.725037) (xy 129.675364 -226.6782) (xy 129.702489 -226.63504) (xy 129.735965 -226.596597)
			(xy 129.774986 -226.563796) (xy 129.818611 -226.537426) (xy 129.865791 -226.518124) (xy 129.91539 -226.506353)
			(xy 129.966212 -226.502398) (xy 130.017034 -226.506353) (xy 130.066633 -226.518124) (xy 130.113813 -226.537426)
			(xy 130.157438 -226.563796) (xy 130.196459 -226.596597) (xy 130.229935 -226.63504) (xy 130.25706 -226.6782)
			(xy 130.277181 -226.725037) (xy 130.283966 -226.74961) (xy 130.293872 -226.78771) (xy 130.578606 -226.78771)
			(xy 130.588512 -226.74961) (xy 130.595297 -226.725037) (xy 130.615418 -226.6782) (xy 130.642543 -226.63504)
			(xy 130.676019 -226.596597) (xy 130.71504 -226.563796) (xy 130.758665 -226.537426) (xy 130.805845 -226.518124)
			(xy 130.855444 -226.506353) (xy 130.906266 -226.502398) (xy 130.957088 -226.506353) (xy 131.006687 -226.518124)
			(xy 131.053867 -226.537426) (xy 131.097492 -226.563796) (xy 131.136513 -226.596597) (xy 131.169989 -226.63504)
			(xy 131.197114 -226.6782) (xy 131.217235 -226.725037) (xy 131.22402 -226.74961) (xy 131.233926 -226.78771)
			(xy 131.518152 -226.78771) (xy 131.528058 -226.74961) (xy 131.534843 -226.725037) (xy 131.554964 -226.6782)
			(xy 131.582089 -226.63504) (xy 131.615565 -226.596597) (xy 131.654586 -226.563796) (xy 131.698211 -226.537426)
			(xy 131.745391 -226.518124) (xy 131.79499 -226.506353) (xy 131.845812 -226.502398) (xy 131.896634 -226.506353)
			(xy 131.946233 -226.518124) (xy 131.993413 -226.537426) (xy 132.037038 -226.563796) (xy 132.076059 -226.596597)
			(xy 132.109535 -226.63504) (xy 132.13666 -226.6782) (xy 132.156781 -226.725037) (xy 132.163566 -226.74961)
			(xy 132.173472 -226.78771) (xy 132.606542 -226.78771) (xy 132.631497 -226.788326) (xy 132.680446 -226.79807)
			(xy 132.726554 -226.817177) (xy 132.768048 -226.844912) (xy 132.78612 -226.862132) (xy 133.240526 -227.316538)
			(xy 133.2611 -227.316792) (xy 133.28635 -227.317664) (xy 133.336144 -227.32621) (xy 133.384041 -227.342285)
			(xy 133.428909 -227.365509) (xy 133.469689 -227.395333) (xy 133.505418 -227.431054) (xy 133.535251 -227.471827)
			(xy 133.558485 -227.51669) (xy 133.574571 -227.564583) (xy 133.583129 -227.614375) (xy 133.583934 -227.639626)
			(xy 133.584188 -227.6602) (xy 134.934452 -229.010464) (xy 134.968234 -228.990398) (xy 134.993735 -228.97607)
			(xy 135.048559 -228.955694) (xy 135.106122 -228.94534) (xy 135.135366 -228.944678) (xy 135.161156 -228.945155)
			(xy 135.212102 -228.95322) (xy 135.261158 -228.969157) (xy 135.307117 -228.992572) (xy 135.348846 -229.02289)
			(xy 135.385318 -229.059363) (xy 135.415634 -229.101093) (xy 135.439048 -229.147053) (xy 135.454983 -229.19611)
			(xy 135.463046 -229.247056) (xy 135.463534 -229.272846) (xy 135.462899 -229.302092) (xy 135.452548 -229.359661)
			(xy 135.432162 -229.414486) (xy 135.417814 -229.439978) (xy 135.397748 -229.47376) (xy 135.694674 -229.770686)
			(xy 135.706358 -229.774496) (xy 135.730795 -229.782914) (xy 135.776863 -229.806342) (xy 135.81869 -229.836701)
			(xy 135.85524 -229.873241) (xy 135.885611 -229.915059) (xy 135.909051 -229.961121) (xy 135.917432 -229.98557)
			(xy 135.921242 -229.997254) (xy 135.987536 -230.063548) (xy 136.21512 -230.063548) (xy 136.223248 -230.022654)
			(xy 136.228603 -229.998161) (xy 136.24575 -229.951049) (xy 136.269864 -229.907094) (xy 136.300384 -229.867318)
			(xy 136.336599 -229.832649) (xy 136.377667 -229.803892) (xy 136.422632 -229.781718) (xy 136.470447 -229.766642)
			(xy 136.519998 -229.759015) (xy 136.570134 -229.759015) (xy 136.619685 -229.766642) (xy 136.6675 -229.781718)
			(xy 136.712465 -229.803892) (xy 136.753533 -229.832649) (xy 136.789748 -229.867318) (xy 136.820268 -229.907094)
			(xy 136.844382 -229.951049) (xy 136.861529 -229.998161) (xy 136.866884 -230.022654) (xy 136.875012 -230.063548)
			(xy 139.03452 -230.063548) (xy 139.042648 -230.022654) (xy 139.048003 -229.998161) (xy 139.06515 -229.951049)
			(xy 139.089264 -229.907094) (xy 139.119784 -229.867318) (xy 139.155999 -229.832649) (xy 139.197067 -229.803892)
			(xy 139.242032 -229.781718) (xy 139.289847 -229.766642) (xy 139.339398 -229.759015) (xy 139.389534 -229.759015)
			(xy 139.439085 -229.766642) (xy 139.4869 -229.781718) (xy 139.531865 -229.803892) (xy 139.572933 -229.832649)
			(xy 139.609148 -229.867318) (xy 139.639668 -229.907094) (xy 139.663782 -229.951049) (xy 139.680929 -229.998161)
			(xy 139.686284 -230.022654) (xy 139.694412 -230.063548) (xy 140.813536 -230.063548) (xy 140.838495 -230.064123)
			(xy 140.887451 -230.073869) (xy 140.933566 -230.092981) (xy 140.975065 -230.120722) (xy 140.993114 -230.13797)
			(xy 141.816836 -230.961692) (xy 141.834092 -230.979734) (xy 141.861842 -231.021229) (xy 141.880947 -231.067347)
			(xy 141.890671 -231.11631) (xy 141.891258 -231.14127) (xy 141.891258 -251.76988) (xy 143.715496 -251.76988)
			(xy 143.719477 -251.63686) (xy 143.731406 -251.504315) (xy 143.751241 -251.372722) (xy 143.77891 -251.24255)
			(xy 143.814314 -251.114265) (xy 143.857327 -250.988328) (xy 143.907794 -250.865189) (xy 143.965535 -250.745288)
			(xy 144.030344 -250.629055) (xy 144.101988 -250.516905) (xy 144.18021 -250.409241) (xy 144.264731 -250.306448)
			(xy 144.355249 -250.208893) (xy 144.451438 -250.116927) (xy 144.552956 -250.030877) (xy 144.659437 -249.951053)
			(xy 144.770502 -249.87774) (xy 144.885753 -249.8112) (xy 145.004777 -249.751671) (xy 145.127148 -249.699367)
			(xy 145.252427 -249.654475) (xy 145.380168 -249.617156) (xy 145.509911 -249.587543) (xy 145.641193 -249.565742)
			(xy 145.773544 -249.551832) (xy 145.90649 -249.545861) (xy 146.039555 -249.547852) (xy 146.172263 -249.557797)
			(xy 146.304139 -249.575661) (xy 146.43471 -249.601379) (xy 146.56351 -249.63486) (xy 146.690076 -249.675984)
			(xy 146.813957 -249.724604) (xy 146.934708 -249.780545) (xy 147.051898 -249.843607) (xy 147.165107 -249.913565)
			(xy 147.273929 -249.990169) (xy 147.377975 -250.073143) (xy 147.476873 -250.162191) (xy 147.570268 -250.256994)
			(xy 147.657826 -250.357212) (xy 147.739235 -250.462488) (xy 147.814201 -250.572444) (xy 147.882458 -250.686686)
			(xy 147.94376 -250.804806) (xy 147.997889 -250.926381) (xy 148.04465 -251.050975) (xy 148.083876 -251.178143)
			(xy 148.115426 -251.307429) (xy 148.139189 -251.43837) (xy 148.155078 -251.570498) (xy 148.163036 -251.70334)
			(xy 148.163534 -251.76988) (xy 148.163036 -251.83642) (xy 148.155078 -251.969262) (xy 148.139189 -252.10139)
			(xy 148.115426 -252.232331) (xy 148.083876 -252.361617) (xy 148.04465 -252.488785) (xy 147.997889 -252.613379)
			(xy 147.94376 -252.734954) (xy 147.882458 -252.853074) (xy 147.814201 -252.967316) (xy 147.739235 -253.077272)
			(xy 147.657826 -253.182548) (xy 147.570268 -253.282766) (xy 147.476873 -253.377569) (xy 147.377975 -253.466617)
			(xy 147.273929 -253.549591) (xy 147.165107 -253.626195) (xy 147.051898 -253.696153) (xy 146.934708 -253.759215)
			(xy 146.813957 -253.815156) (xy 146.690076 -253.863776) (xy 146.56351 -253.9049) (xy 146.43471 -253.938381)
			(xy 146.304139 -253.964099) (xy 146.172263 -253.981963) (xy 146.039555 -253.991908) (xy 145.90649 -253.993899)
			(xy 145.773544 -253.987928) (xy 145.641193 -253.974018) (xy 145.509911 -253.952217) (xy 145.380168 -253.922604)
			(xy 145.252427 -253.885285) (xy 145.127148 -253.840393) (xy 145.004777 -253.788089) (xy 144.885753 -253.72856)
			(xy 144.770502 -253.66202) (xy 144.659437 -253.588707) (xy 144.552956 -253.508883) (xy 144.451438 -253.422833)
			(xy 144.355249 -253.330867) (xy 144.264731 -253.233312) (xy 144.18021 -253.130519) (xy 144.101988 -253.022855)
			(xy 144.030344 -252.910705) (xy 143.965535 -252.794472) (xy 143.907794 -252.674571) (xy 143.857327 -252.551432)
			(xy 143.814314 -252.425495) (xy 143.77891 -252.29721) (xy 143.751241 -252.167038) (xy 143.731406 -252.035445)
			(xy 143.719477 -251.9029) (xy 143.715496 -251.76988) (xy 141.891258 -251.76988) (xy 141.891258 -265.97229)
			(xy 141.890678 -265.997247) (xy 141.880923 -266.046198) (xy 141.861805 -266.092305) (xy 141.834059 -266.133797)
			(xy 141.816836 -266.151868) (xy 140.683996 -267.284708) (xy 140.665954 -267.301965) (xy 140.62446 -267.329716)
			(xy 140.578341 -267.348821) (xy 140.529378 -267.358543) (xy 140.504418 -267.35913) (xy 135.879078 -267.35913)
			(xy 134.632192 -268.606016) (xy 134.629398 -268.622272) (xy 134.624806 -268.647487) (xy 134.60883 -268.696182)
			(xy 134.585479 -268.741802) (xy 134.555319 -268.783236) (xy 134.519083 -268.819478) (xy 134.477655 -268.849646)
			(xy 134.432039 -268.873007) (xy 134.383347 -268.888991) (xy 134.358126 -268.893544) (xy 134.34187 -268.896338)
			(xy 134.07898 -269.159228) (xy 134.103618 -269.19428) (xy 134.117759 -269.215166) (xy 134.14015 -269.260361)
			(xy 134.155376 -269.308445) (xy 134.163078 -269.358291) (xy 134.163562 -269.38351) (xy 134.163056 -269.409297)
			(xy 134.154986 -269.460236) (xy 134.139048 -269.509285) (xy 134.115632 -269.555237) (xy 134.085317 -269.59696)
			(xy 134.048848 -269.633427) (xy 134.007123 -269.663741) (xy 133.96117 -269.687154) (xy 133.91212 -269.70309)
			(xy 133.861181 -269.711157) (xy 133.835394 -269.711678) (xy 133.81017 -269.711244) (xy 133.760309 -269.70357)
			(xy 133.712215 -269.688342) (xy 133.667024 -269.665922) (xy 133.646164 -269.651734) (xy 133.611112 -269.627096)
			(xy 132.280406 -270.957802) (xy 132.282692 -270.981424) (xy 132.283962 -271.011396) (xy 132.283483 -271.037186)
			(xy 132.275415 -271.08813) (xy 132.259476 -271.137185) (xy 132.23606 -271.183143) (xy 132.205742 -271.224871)
			(xy 132.16927 -271.261343) (xy 132.127541 -271.291661) (xy 132.081583 -271.315077) (xy 132.032528 -271.331015)
			(xy 131.981584 -271.339083) (xy 131.955794 -271.339564) (xy 131.93044 -271.339091) (xy 131.880335 -271.331287)
			(xy 131.832028 -271.315867) (xy 131.786669 -271.293198) (xy 131.745339 -271.263819) (xy 131.709021 -271.228431)
			(xy 131.67858 -271.187875) (xy 131.654743 -271.143119) (xy 131.645914 -271.119346) (xy 131.633976 -271.08531)
			(xy 131.337812 -271.08531) (xy 131.325874 -271.119346) (xy 131.317087 -271.143134) (xy 131.293238 -271.187885)
			(xy 131.262788 -271.228434) (xy 131.226462 -271.263816) (xy 131.185126 -271.293188) (xy 131.139763 -271.315852)
			(xy 131.091454 -271.331268) (xy 131.041349 -271.339069) (xy 130.990639 -271.339069) (xy 130.940534 -271.331268)
			(xy 130.892225 -271.315852) (xy 130.846862 -271.293188) (xy 130.805526 -271.263816) (xy 130.7692 -271.228434)
			(xy 130.73875 -271.187885) (xy 130.714901 -271.143134) (xy 130.706114 -271.119346) (xy 130.694176 -271.08531)
			(xy 130.398012 -271.08531) (xy 130.386074 -271.119346) (xy 130.377287 -271.143134) (xy 130.353438 -271.187885)
			(xy 130.322988 -271.228434) (xy 130.286662 -271.263816) (xy 130.245326 -271.293188) (xy 130.199963 -271.315852)
			(xy 130.151654 -271.331268) (xy 130.101549 -271.339069) (xy 130.050839 -271.339069) (xy 130.000734 -271.331268)
			(xy 129.952425 -271.315852) (xy 129.907062 -271.293188) (xy 129.865726 -271.263816) (xy 129.8294 -271.228434)
			(xy 129.79895 -271.187885) (xy 129.775101 -271.143134) (xy 129.766314 -271.119346) (xy 129.754376 -271.08531)
			(xy 129.458212 -271.08531) (xy 129.446274 -271.119346) (xy 129.437487 -271.143134) (xy 129.413638 -271.187885)
			(xy 129.383188 -271.228434) (xy 129.346862 -271.263816) (xy 129.305526 -271.293188) (xy 129.260163 -271.315852)
			(xy 129.211854 -271.331268) (xy 129.161749 -271.339069) (xy 129.111039 -271.339069) (xy 129.060934 -271.331268)
			(xy 129.012625 -271.315852) (xy 128.967262 -271.293188) (xy 128.925926 -271.263816) (xy 128.8896 -271.228434)
			(xy 128.85915 -271.187885) (xy 128.835301 -271.143134) (xy 128.826514 -271.119346) (xy 128.814576 -271.08531)
			(xy 128.518412 -271.08531) (xy 128.506474 -271.119346) (xy 128.497687 -271.143134) (xy 128.473838 -271.187885)
			(xy 128.443388 -271.228434) (xy 128.407062 -271.263816) (xy 128.365726 -271.293188) (xy 128.320363 -271.315852)
			(xy 128.272054 -271.331268) (xy 128.221949 -271.339069) (xy 128.171239 -271.339069) (xy 128.121134 -271.331268)
			(xy 128.072825 -271.315852) (xy 128.027462 -271.293188) (xy 127.986126 -271.263816) (xy 127.9498 -271.228434)
			(xy 127.91935 -271.187885) (xy 127.895501 -271.143134) (xy 127.886714 -271.119346) (xy 127.874776 -271.08531)
			(xy 127.578612 -271.08531) (xy 127.566674 -271.119346) (xy 127.557887 -271.143134) (xy 127.534038 -271.187885)
			(xy 127.503588 -271.228434) (xy 127.467262 -271.263816) (xy 127.425926 -271.293188) (xy 127.380563 -271.315852)
			(xy 127.332254 -271.331268) (xy 127.282149 -271.339069) (xy 127.231439 -271.339069) (xy 127.181334 -271.331268)
			(xy 127.133025 -271.315852) (xy 127.087662 -271.293188) (xy 127.046326 -271.263816) (xy 127.01 -271.228434)
			(xy 126.97955 -271.187885) (xy 126.955701 -271.143134) (xy 126.946914 -271.119346) (xy 126.934976 -271.08531)
			(xy 126.638812 -271.08531) (xy 126.626874 -271.119346) (xy 126.618087 -271.143134) (xy 126.594238 -271.187885)
			(xy 126.563788 -271.228434) (xy 126.527462 -271.263816) (xy 126.486126 -271.293188) (xy 126.440763 -271.315852)
			(xy 126.392454 -271.331268) (xy 126.342349 -271.339069) (xy 126.291639 -271.339069) (xy 126.241534 -271.331268)
			(xy 126.193225 -271.315852) (xy 126.147862 -271.293188) (xy 126.106526 -271.263816) (xy 126.0702 -271.228434)
			(xy 126.03975 -271.187885) (xy 126.015901 -271.143134) (xy 126.007114 -271.119346) (xy 125.995176 -271.08531)
			(xy 125.699012 -271.08531) (xy 125.687074 -271.119346) (xy 125.678287 -271.143134) (xy 125.654438 -271.187885)
			(xy 125.623988 -271.228434) (xy 125.587662 -271.263816) (xy 125.546326 -271.293188) (xy 125.500963 -271.315852)
			(xy 125.452654 -271.331268) (xy 125.402549 -271.339069) (xy 125.351839 -271.339069) (xy 125.301734 -271.331268)
			(xy 125.253425 -271.315852) (xy 125.208062 -271.293188) (xy 125.166726 -271.263816) (xy 125.1304 -271.228434)
			(xy 125.09995 -271.187885) (xy 125.076101 -271.143134) (xy 125.067314 -271.119346) (xy 125.055376 -271.08531)
			(xy 124.759212 -271.08531) (xy 124.747274 -271.119346) (xy 124.738487 -271.143134) (xy 124.714638 -271.187885)
			(xy 124.684188 -271.228434) (xy 124.647862 -271.263816) (xy 124.606526 -271.293188) (xy 124.561163 -271.315852)
			(xy 124.512854 -271.331268) (xy 124.462749 -271.339069) (xy 124.412039 -271.339069) (xy 124.361934 -271.331268)
			(xy 124.313625 -271.315852) (xy 124.268262 -271.293188) (xy 124.226926 -271.263816) (xy 124.1906 -271.228434)
			(xy 124.16015 -271.187885) (xy 124.136301 -271.143134) (xy 124.127514 -271.119346) (xy 124.115576 -271.08531)
			(xy 123.819412 -271.08531) (xy 123.807474 -271.119346) (xy 123.798687 -271.143134) (xy 123.774838 -271.187885)
			(xy 123.744388 -271.228434) (xy 123.708062 -271.263816) (xy 123.666726 -271.293188) (xy 123.621363 -271.315852)
			(xy 123.573054 -271.331268) (xy 123.522949 -271.339069) (xy 123.472239 -271.339069) (xy 123.422134 -271.331268)
			(xy 123.373825 -271.315852) (xy 123.328462 -271.293188) (xy 123.287126 -271.263816) (xy 123.2508 -271.228434)
			(xy 123.22035 -271.187885) (xy 123.196501 -271.143134) (xy 123.187714 -271.119346) (xy 123.175776 -271.08531)
			(xy 122.879866 -271.08531) (xy 122.867928 -271.119346) (xy 122.859141 -271.143134) (xy 122.835292 -271.187885)
			(xy 122.804842 -271.228434) (xy 122.768516 -271.263816) (xy 122.72718 -271.293188) (xy 122.681817 -271.315852)
			(xy 122.633508 -271.331268) (xy 122.583403 -271.339069) (xy 122.532693 -271.339069) (xy 122.482588 -271.331268)
			(xy 122.434279 -271.315852) (xy 122.388916 -271.293188) (xy 122.34758 -271.263816) (xy 122.311254 -271.228434)
			(xy 122.280804 -271.187885) (xy 122.256955 -271.143134) (xy 122.248168 -271.119346) (xy 122.23623 -271.08531)
			(xy 121.939812 -271.08531) (xy 121.927874 -271.119346) (xy 121.919087 -271.143134) (xy 121.895238 -271.187885)
			(xy 121.864788 -271.228434) (xy 121.828462 -271.263816) (xy 121.787126 -271.293188) (xy 121.741763 -271.315852)
			(xy 121.693454 -271.331268) (xy 121.643349 -271.339069) (xy 121.592639 -271.339069) (xy 121.542534 -271.331268)
			(xy 121.494225 -271.315852) (xy 121.448862 -271.293188) (xy 121.407526 -271.263816) (xy 121.3712 -271.228434)
			(xy 121.34075 -271.187885) (xy 121.316901 -271.143134) (xy 121.308114 -271.119346) (xy 121.296176 -271.08531)
			(xy 121.000012 -271.08531) (xy 120.988074 -271.119346) (xy 120.979289 -271.143138) (xy 120.955442 -271.187897)
			(xy 120.924994 -271.228455) (xy 120.88867 -271.263847) (xy 120.847335 -271.293232) (xy 120.801972 -271.315908)
			(xy 120.753661 -271.331338) (xy 120.703552 -271.339153) (xy 120.678194 -271.339564) (xy 120.653635 -271.339112)
			(xy 120.605064 -271.331808) (xy 120.558123 -271.317347) (xy 120.513861 -271.296054) (xy 120.473266 -271.268404)
			(xy 120.437243 -271.235013) (xy 120.406599 -271.196628) (xy 120.382015 -271.154105) (xy 120.364042 -271.108394)
			(xy 120.358154 -271.084548) (xy 120.334379 -271.085873) (xy 120.287051 -271.080684) (xy 120.241522 -271.06676)
			(xy 120.199387 -271.044591) (xy 120.162125 -271.014953) (xy 120.131043 -270.978887) (xy 120.118632 -270.958564)
			(xy 119.37111 -270.958564) (xy 118.534688 -270.122142) (xy 118.534688 -269.720822) (xy 118.511467 -269.701994)
			(xy 118.469965 -269.658969) (xy 118.434849 -269.610589) (xy 118.406803 -269.557796) (xy 118.386371 -269.501616)
			(xy 118.373951 -269.443141) (xy 118.369783 -269.383506) (xy 118.373949 -269.323871) (xy 118.386368 -269.265395)
			(xy 118.406798 -269.209215) (xy 118.434843 -269.156421) (xy 118.469957 -269.108041) (xy 118.511458 -269.065014)
			(xy 118.534688 -269.046198) (xy 118.534688 -268.09319) (xy 118.511469 -268.074362) (xy 118.469972 -268.031337)
			(xy 118.43486 -267.982959) (xy 118.406818 -267.930168) (xy 118.38639 -267.87399) (xy 118.373973 -267.815518)
			(xy 118.369808 -267.755886) (xy 118.373977 -267.696255) (xy 118.386398 -267.637783) (xy 118.406829 -267.581607)
			(xy 118.434875 -267.528818) (xy 118.469989 -267.480442) (xy 118.51149 -267.437419) (xy 118.534688 -267.418566)
			(xy 118.534688 -266.323318) (xy 118.519582 -266.302034) (xy 118.495593 -266.255684) (xy 118.479246 -266.206121)
			(xy 118.470952 -266.154595) (xy 118.470426 -266.1285) (xy 118.470953 -266.102407) (xy 118.479257 -266.050884)
			(xy 118.495608 -266.001323) (xy 118.519595 -265.954974) (xy 118.534688 -265.933682) (xy 118.534688 -264.695178)
			(xy 118.519578 -264.673896) (xy 118.495581 -264.627547) (xy 118.479225 -264.577983) (xy 118.470921 -264.526456)
			(xy 118.470426 -264.50036) (xy 118.470948 -264.474265) (xy 118.479244 -264.422738) (xy 118.495588 -264.373172)
			(xy 118.519569 -264.326817) (xy 118.534688 -264.305542) (xy 118.534688 -263.64184) (xy 118.513745 -263.627791)
			(xy 118.476038 -263.594307) (xy 118.443897 -263.555449) (xy 118.418079 -263.512131) (xy 118.39919 -263.465374)
			(xy 118.387676 -263.416278) (xy 118.383808 -263.365998) (xy 118.387677 -263.315718) (xy 118.399192 -263.266622)
			(xy 118.418081 -263.219865) (xy 118.4439 -263.176548) (xy 118.476041 -263.13769) (xy 118.513749 -263.104206)
			(xy 118.534688 -263.090152) (xy 118.534688 -260.901434) (xy 118.406164 -260.77291) (xy 116.785898 -260.77291)
			(xy 116.274342 -261.284466) (xy 116.274342 -264.356596) (xy 116.27866 -264.366502) (xy 116.287702 -264.387648)
			(xy 116.300458 -264.431834) (xy 116.306937 -264.477366) (xy 116.307362 -264.50036) (xy 116.306961 -264.523357)
			(xy 116.300497 -264.568894) (xy 116.287718 -264.613077) (xy 116.27866 -264.634218) (xy 116.274342 -264.644124)
			(xy 116.274342 -265.984482) (xy 116.27866 -265.994388) (xy 116.287703 -266.015534) (xy 116.300461 -266.05972)
			(xy 116.306941 -266.105251) (xy 116.307362 -266.128246) (xy 116.306962 -266.151243) (xy 116.300499 -266.196781)
			(xy 116.287723 -266.240964) (xy 116.27866 -266.262104) (xy 116.274342 -266.27201) (xy 116.274342 -267.612114)
			(xy 116.27866 -267.62202) (xy 116.287701 -267.643166) (xy 116.300454 -267.687352) (xy 116.306931 -267.732884)
			(xy 116.307362 -267.755878) (xy 116.306959 -267.778874) (xy 116.300493 -267.824411) (xy 116.287713 -267.868592)
			(xy 116.27866 -267.889736) (xy 116.274342 -267.899642) (xy 116.274342 -269.239746) (xy 116.27866 -269.249652)
			(xy 116.287706 -269.270797) (xy 116.300468 -269.314983) (xy 116.306953 -269.360515) (xy 116.307362 -269.38351)
			(xy 116.306964 -269.406507) (xy 116.300507 -269.452047) (xy 116.287734 -269.496233) (xy 116.27866 -269.517368)
			(xy 116.274342 -269.527274) (xy 116.274342 -270.867632) (xy 116.27866 -270.877538) (xy 116.287707 -270.898683)
			(xy 116.300471 -270.942869) (xy 116.306958 -270.988401) (xy 116.307362 -271.011396) (xy 116.306958 -271.034392)
			(xy 116.300489 -271.079927) (xy 116.287707 -271.124108) (xy 116.27866 -271.145254) (xy 116.274342 -271.15516)
			(xy 116.274342 -272.495518) (xy 116.27866 -272.505424) (xy 116.287701 -272.52657) (xy 116.300454 -272.570756)
			(xy 116.306929 -272.616288) (xy 116.307362 -272.639282) (xy 116.306959 -272.662278) (xy 116.300492 -272.707814)
			(xy 116.287711 -272.751996) (xy 116.27866 -272.77314) (xy 116.274342 -272.783046) (xy 116.274342 -274.122642)
			(xy 116.278914 -274.132548) (xy 116.287988 -274.153773) (xy 116.300772 -274.198128) (xy 116.307234 -274.243834)
			(xy 116.307616 -274.266914) (xy 116.307247 -274.289997) (xy 116.300813 -274.33571) (xy 116.288017 -274.380065)
			(xy 116.278914 -274.40128) (xy 116.274342 -274.411186) (xy 116.274342 -275.751036) (xy 116.27866 -275.760942)
			(xy 116.287706 -275.782087) (xy 116.30047 -275.826273) (xy 116.306957 -275.871805) (xy 116.307362 -275.8948)
			(xy 116.306965 -275.917798) (xy 116.300509 -275.963338) (xy 116.287738 -276.007524) (xy 116.27866 -276.028658)
			(xy 116.274342 -276.038564) (xy 116.274342 -277.377906) (xy 116.278914 -277.387812) (xy 116.287984 -277.409038)
			(xy 116.30076 -277.453393) (xy 116.307213 -277.499099) (xy 116.307616 -277.522178) (xy 116.307243 -277.545259)
			(xy 116.3008 -277.59097) (xy 116.287996 -277.635321) (xy 116.278914 -277.656544) (xy 116.274342 -277.66645)
			(xy 116.274342 -279.006554) (xy 116.27866 -279.01646) (xy 116.289328 -279.04313) (xy 116.290852 -279.047702)
			(xy 116.686076 -279.736804) (xy 116.69014 -279.741122) (xy 116.706668 -279.759642) (xy 116.734534 -279.80072)
			(xy 116.755916 -279.845517) (xy 116.763546 -279.869138) (xy 116.76507 -279.874726) (xy 117.14861 -280.543508)
			(xy 117.153182 -280.54808) (xy 117.172444 -280.568478) (xy 117.204416 -280.614574) (xy 117.228094 -280.66543)
			(xy 117.235986 -280.692352) (xy 117.237764 -280.698702) (xy 117.611398 -281.350466) (xy 117.616732 -281.355546)
			(xy 117.633241 -281.372) (xy 117.661911 -281.408748) (xy 117.685089 -281.449187) (xy 117.702306 -281.4925)
			(xy 117.708172 -281.515058) (xy 117.70995 -281.52217) (xy 118.074694 -282.158186) (xy 118.080536 -282.163774)
			(xy 118.098939 -282.181253) (xy 118.130662 -282.22087) (xy 118.155909 -282.264897) (xy 118.174076 -282.312287)
			(xy 118.17985 -282.337002) (xy 118.181628 -282.344876) (xy 118.538498 -282.967176) (xy 118.544848 -282.972764)
			(xy 118.565031 -282.991108) (xy 118.599606 -283.033284) (xy 118.626726 -283.080601) (xy 118.645642 -283.131752)
			(xy 118.651274 -283.158438) (xy 118.652798 -283.166566) (xy 119.002556 -283.77642) (xy 119.009414 -283.782262)
			(xy 119.026893 -283.797414) (xy 119.057836 -283.831797) (xy 119.083642 -283.870186) (xy 119.103801 -283.911819)
			(xy 119.117911 -283.955871) (xy 119.12219 -283.978604) (xy 119.123714 -283.987494) (xy 119.464582 -284.582362)
			(xy 119.472456 -284.588458) (xy 119.492074 -284.604459) (xy 119.526623 -284.641461) (xy 119.555095 -284.683319)
			(xy 119.576816 -284.729046) (xy 119.591274 -284.777561) (xy 119.595138 -284.80258) (xy 119.596662 -284.812486)
			(xy 119.61676 -284.847538) (xy 120.818656 -284.847538) (xy 120.819164 -284.821631) (xy 120.82727 -284.770454)
			(xy 120.843282 -284.721175) (xy 120.866805 -284.675008) (xy 120.897261 -284.633089) (xy 120.933899 -284.596451)
			(xy 120.975818 -284.565995) (xy 121.021985 -284.542472) (xy 121.071264 -284.52646) (xy 121.122441 -284.518354)
			(xy 121.174255 -284.518354) (xy 121.225432 -284.52646) (xy 121.274711 -284.542472) (xy 121.320878 -284.565995)
			(xy 121.362797 -284.596451) (xy 121.399435 -284.633089) (xy 121.429891 -284.675008) (xy 121.453414 -284.721175)
			(xy 121.469426 -284.770454) (xy 121.477532 -284.821631) (xy 121.47804 -284.847538) (xy 122.698256 -284.847538)
			(xy 122.698764 -284.821631) (xy 122.70687 -284.770454) (xy 122.722882 -284.721175) (xy 122.746405 -284.675008)
			(xy 122.776861 -284.633089) (xy 122.813499 -284.596451) (xy 122.855418 -284.565995) (xy 122.901585 -284.542472)
			(xy 122.950864 -284.52646) (xy 123.002041 -284.518354) (xy 123.053855 -284.518354) (xy 123.105032 -284.52646)
			(xy 123.154311 -284.542472) (xy 123.200478 -284.565995) (xy 123.242397 -284.596451) (xy 123.279035 -284.633089)
			(xy 123.309491 -284.675008) (xy 123.333014 -284.721175) (xy 123.349026 -284.770454) (xy 123.357132 -284.821631)
			(xy 123.35764 -284.847538) (xy 124.577856 -284.847538) (xy 124.578364 -284.821631) (xy 124.58647 -284.770454)
			(xy 124.602482 -284.721175) (xy 124.626005 -284.675008) (xy 124.656461 -284.633089) (xy 124.693099 -284.596451)
			(xy 124.735018 -284.565995) (xy 124.781185 -284.542472) (xy 124.830464 -284.52646) (xy 124.881641 -284.518354)
			(xy 124.933455 -284.518354) (xy 124.984632 -284.52646) (xy 125.033911 -284.542472) (xy 125.080078 -284.565995)
			(xy 125.121997 -284.596451) (xy 125.158635 -284.633089) (xy 125.189091 -284.675008) (xy 125.212614 -284.721175)
			(xy 125.228626 -284.770454) (xy 125.236732 -284.821631) (xy 125.23724 -284.847538) (xy 126.457456 -284.847538)
			(xy 126.457964 -284.821631) (xy 126.46607 -284.770454) (xy 126.482082 -284.721175) (xy 126.505605 -284.675008)
			(xy 126.536061 -284.633089) (xy 126.572699 -284.596451) (xy 126.614618 -284.565995) (xy 126.660785 -284.542472)
			(xy 126.710064 -284.52646) (xy 126.761241 -284.518354) (xy 126.813055 -284.518354) (xy 126.864232 -284.52646)
			(xy 126.913511 -284.542472) (xy 126.959678 -284.565995) (xy 127.001597 -284.596451) (xy 127.038235 -284.633089)
			(xy 127.068691 -284.675008) (xy 127.092214 -284.721175) (xy 127.108226 -284.770454) (xy 127.116332 -284.821631)
			(xy 127.11684 -284.847538) (xy 128.337056 -284.847538) (xy 128.337564 -284.821631) (xy 128.34567 -284.770454)
			(xy 128.361682 -284.721175) (xy 128.385205 -284.675008) (xy 128.415661 -284.633089) (xy 128.452299 -284.596451)
			(xy 128.494218 -284.565995) (xy 128.540385 -284.542472) (xy 128.589664 -284.52646) (xy 128.640841 -284.518354)
			(xy 128.692655 -284.518354) (xy 128.743832 -284.52646) (xy 128.793111 -284.542472) (xy 128.839278 -284.565995)
			(xy 128.881197 -284.596451) (xy 128.917835 -284.633089) (xy 128.948291 -284.675008) (xy 128.971814 -284.721175)
			(xy 128.987826 -284.770454) (xy 128.995932 -284.821631) (xy 128.99644 -284.847538) (xy 130.216656 -284.847538)
			(xy 130.217164 -284.821631) (xy 130.22527 -284.770454) (xy 130.241282 -284.721175) (xy 130.264805 -284.675008)
			(xy 130.295261 -284.633089) (xy 130.331899 -284.596451) (xy 130.373818 -284.565995) (xy 130.419985 -284.542472)
			(xy 130.469264 -284.52646) (xy 130.520441 -284.518354) (xy 130.572255 -284.518354) (xy 130.623432 -284.52646)
			(xy 130.672711 -284.542472) (xy 130.718878 -284.565995) (xy 130.760797 -284.596451) (xy 130.797435 -284.633089)
			(xy 130.827891 -284.675008) (xy 130.851414 -284.721175) (xy 130.867426 -284.770454) (xy 130.875532 -284.821631)
			(xy 130.87604 -284.847538) (xy 132.096256 -284.847538) (xy 132.096764 -284.821631) (xy 132.10487 -284.770454)
			(xy 132.120882 -284.721175) (xy 132.144405 -284.675008) (xy 132.174861 -284.633089) (xy 132.211499 -284.596451)
			(xy 132.253418 -284.565995) (xy 132.299585 -284.542472) (xy 132.348864 -284.52646) (xy 132.400041 -284.518354)
			(xy 132.451855 -284.518354) (xy 132.503032 -284.52646) (xy 132.552311 -284.542472) (xy 132.598478 -284.565995)
			(xy 132.640397 -284.596451) (xy 132.677035 -284.633089) (xy 132.707491 -284.675008) (xy 132.731014 -284.721175)
			(xy 132.747026 -284.770454) (xy 132.755132 -284.821631) (xy 132.75564 -284.847538) (xy 132.755034 -284.875255)
			(xy 132.745719 -284.929901) (xy 132.737098 -284.95625) (xy 132.729224 -284.978348) (xy 132.934202 -285.333186)
			(xy 132.957062 -285.337504) (xy 132.981868 -285.342683) (xy 133.02961 -285.359669) (xy 133.07419 -285.383762)
			(xy 133.114558 -285.414393) (xy 133.149763 -285.450841) (xy 133.178975 -285.492247) (xy 133.201506 -285.537636)
			(xy 133.216825 -285.585939) (xy 133.224572 -285.636017) (xy 133.225032 -285.661354) (xy 133.224524 -285.687241)
			(xy 133.216425 -285.738379) (xy 133.200426 -285.787619) (xy 133.17692 -285.833751) (xy 133.146488 -285.875638)
			(xy 133.109878 -285.912248) (xy 133.067991 -285.94268) (xy 133.021859 -285.966186) (xy 132.972619 -285.982185)
			(xy 132.921481 -285.990284) (xy 132.869707 -285.990284) (xy 132.818569 -285.982185) (xy 132.769329 -285.966186)
			(xy 132.723197 -285.94268) (xy 132.68131 -285.912248) (xy 132.6447 -285.875638) (xy 132.614268 -285.833751)
			(xy 132.590762 -285.787619) (xy 132.574763 -285.738379) (xy 132.566664 -285.687241) (xy 132.566156 -285.661354)
			(xy 132.566701 -285.633647) (xy 132.575886 -285.579) (xy 132.584444 -285.552642) (xy 132.592318 -285.530544)
			(xy 132.38734 -285.175706) (xy 132.36448 -285.171388) (xy 132.33966 -285.166215) (xy 132.29188 -285.149263)
			(xy 132.247259 -285.125194) (xy 132.206851 -285.094575) (xy 132.171609 -285.058129) (xy 132.142365 -285.016715)
			(xy 132.119809 -284.971312) (xy 132.104472 -284.922989) (xy 132.096717 -284.872887) (xy 132.096256 -284.847538)
			(xy 130.87604 -284.847538) (xy 130.875434 -284.875255) (xy 130.866119 -284.929901) (xy 130.857498 -284.95625)
			(xy 130.849624 -284.978348) (xy 131.054602 -285.333186) (xy 131.077462 -285.337504) (xy 131.102268 -285.342683)
			(xy 131.15001 -285.359669) (xy 131.19459 -285.383762) (xy 131.234958 -285.414393) (xy 131.270163 -285.450841)
			(xy 131.299375 -285.492247) (xy 131.321906 -285.537636) (xy 131.337225 -285.585939) (xy 131.344972 -285.636017)
			(xy 131.345432 -285.661354) (xy 131.344924 -285.687241) (xy 131.336825 -285.738379) (xy 131.320826 -285.787619)
			(xy 131.29732 -285.833751) (xy 131.266888 -285.875638) (xy 131.230278 -285.912248) (xy 131.188391 -285.94268)
			(xy 131.142259 -285.966186) (xy 131.093019 -285.982185) (xy 131.041881 -285.990284) (xy 130.990107 -285.990284)
			(xy 130.938969 -285.982185) (xy 130.889729 -285.966186) (xy 130.843597 -285.94268) (xy 130.80171 -285.912248)
			(xy 130.7651 -285.875638) (xy 130.734668 -285.833751) (xy 130.711162 -285.787619) (xy 130.695163 -285.738379)
			(xy 130.687064 -285.687241) (xy 130.686556 -285.661354) (xy 130.687101 -285.633647) (xy 130.696286 -285.579)
			(xy 130.704844 -285.552642) (xy 130.712718 -285.530544) (xy 130.50774 -285.175706) (xy 130.48488 -285.171388)
			(xy 130.46006 -285.166215) (xy 130.41228 -285.149263) (xy 130.367659 -285.125194) (xy 130.327251 -285.094575)
			(xy 130.292009 -285.058129) (xy 130.262765 -285.016715) (xy 130.240209 -284.971312) (xy 130.224872 -284.922989)
			(xy 130.217117 -284.872887) (xy 130.216656 -284.847538) (xy 128.99644 -284.847538) (xy 128.995834 -284.875255)
			(xy 128.986519 -284.929901) (xy 128.977898 -284.95625) (xy 128.970024 -284.978348) (xy 129.175002 -285.333186)
			(xy 129.197862 -285.337504) (xy 129.222668 -285.342683) (xy 129.27041 -285.359669) (xy 129.31499 -285.383762)
			(xy 129.355358 -285.414393) (xy 129.390563 -285.450841) (xy 129.419775 -285.492247) (xy 129.442306 -285.537636)
			(xy 129.457625 -285.585939) (xy 129.465372 -285.636017) (xy 129.465832 -285.661354) (xy 129.465324 -285.687241)
			(xy 129.457225 -285.738379) (xy 129.441226 -285.787619) (xy 129.41772 -285.833751) (xy 129.387288 -285.875638)
			(xy 129.350678 -285.912248) (xy 129.308791 -285.94268) (xy 129.262659 -285.966186) (xy 129.213419 -285.982185)
			(xy 129.162281 -285.990284) (xy 129.110507 -285.990284) (xy 129.059369 -285.982185) (xy 129.010129 -285.966186)
			(xy 128.963997 -285.94268) (xy 128.92211 -285.912248) (xy 128.8855 -285.875638) (xy 128.855068 -285.833751)
			(xy 128.831562 -285.787619) (xy 128.815563 -285.738379) (xy 128.807464 -285.687241) (xy 128.806956 -285.661354)
			(xy 128.807501 -285.633647) (xy 128.816686 -285.579) (xy 128.825244 -285.552642) (xy 128.833118 -285.530544)
			(xy 128.62814 -285.175706) (xy 128.60528 -285.171388) (xy 128.58046 -285.166215) (xy 128.53268 -285.149263)
			(xy 128.488059 -285.125194) (xy 128.447651 -285.094575) (xy 128.412409 -285.058129) (xy 128.383165 -285.016715)
			(xy 128.360609 -284.971312) (xy 128.345272 -284.922989) (xy 128.337517 -284.872887) (xy 128.337056 -284.847538)
			(xy 127.11684 -284.847538) (xy 127.116234 -284.875255) (xy 127.106919 -284.929901) (xy 127.098298 -284.95625)
			(xy 127.090424 -284.978348) (xy 127.295402 -285.333186) (xy 127.318262 -285.337504) (xy 127.343068 -285.342683)
			(xy 127.39081 -285.359669) (xy 127.43539 -285.383762) (xy 127.475758 -285.414393) (xy 127.510963 -285.450841)
			(xy 127.540175 -285.492247) (xy 127.562706 -285.537636) (xy 127.578025 -285.585939) (xy 127.585772 -285.636017)
			(xy 127.586232 -285.661354) (xy 127.585724 -285.687241) (xy 127.577625 -285.738379) (xy 127.561626 -285.787619)
			(xy 127.53812 -285.833751) (xy 127.507688 -285.875638) (xy 127.471078 -285.912248) (xy 127.429191 -285.94268)
			(xy 127.383059 -285.966186) (xy 127.333819 -285.982185) (xy 127.282681 -285.990284) (xy 127.230907 -285.990284)
			(xy 127.179769 -285.982185) (xy 127.130529 -285.966186) (xy 127.084397 -285.94268) (xy 127.04251 -285.912248)
			(xy 127.0059 -285.875638) (xy 126.975468 -285.833751) (xy 126.951962 -285.787619) (xy 126.935963 -285.738379)
			(xy 126.927864 -285.687241) (xy 126.927356 -285.661354) (xy 126.927901 -285.633647) (xy 126.937086 -285.579)
			(xy 126.945644 -285.552642) (xy 126.953518 -285.530544) (xy 126.74854 -285.175706) (xy 126.72568 -285.171388)
			(xy 126.70086 -285.166215) (xy 126.65308 -285.149263) (xy 126.608459 -285.125194) (xy 126.568051 -285.094575)
			(xy 126.532809 -285.058129) (xy 126.503565 -285.016715) (xy 126.481009 -284.971312) (xy 126.465672 -284.922989)
			(xy 126.457917 -284.872887) (xy 126.457456 -284.847538) (xy 125.23724 -284.847538) (xy 125.236634 -284.875255)
			(xy 125.227319 -284.929901) (xy 125.218698 -284.95625) (xy 125.210824 -284.978348) (xy 125.415802 -285.333186)
			(xy 125.438662 -285.337504) (xy 125.463468 -285.342683) (xy 125.51121 -285.359669) (xy 125.55579 -285.383762)
			(xy 125.596158 -285.414393) (xy 125.631363 -285.450841) (xy 125.660575 -285.492247) (xy 125.683106 -285.537636)
			(xy 125.698425 -285.585939) (xy 125.706172 -285.636017) (xy 125.706632 -285.661354) (xy 125.706124 -285.687241)
			(xy 125.698025 -285.738379) (xy 125.682026 -285.787619) (xy 125.65852 -285.833751) (xy 125.628088 -285.875638)
			(xy 125.591478 -285.912248) (xy 125.549591 -285.94268) (xy 125.503459 -285.966186) (xy 125.454219 -285.982185)
			(xy 125.403081 -285.990284) (xy 125.351307 -285.990284) (xy 125.300169 -285.982185) (xy 125.250929 -285.966186)
			(xy 125.204797 -285.94268) (xy 125.16291 -285.912248) (xy 125.1263 -285.875638) (xy 125.095868 -285.833751)
			(xy 125.072362 -285.787619) (xy 125.056363 -285.738379) (xy 125.048264 -285.687241) (xy 125.047756 -285.661354)
			(xy 125.048301 -285.633647) (xy 125.057486 -285.579) (xy 125.066044 -285.552642) (xy 125.073918 -285.530544)
			(xy 124.86894 -285.175706) (xy 124.84608 -285.171388) (xy 124.82126 -285.166215) (xy 124.77348 -285.149263)
			(xy 124.728859 -285.125194) (xy 124.688451 -285.094575) (xy 124.653209 -285.058129) (xy 124.623965 -285.016715)
			(xy 124.601409 -284.971312) (xy 124.586072 -284.922989) (xy 124.578317 -284.872887) (xy 124.577856 -284.847538)
			(xy 123.35764 -284.847538) (xy 123.357034 -284.875255) (xy 123.347719 -284.929901) (xy 123.339098 -284.95625)
			(xy 123.331224 -284.978348) (xy 123.536202 -285.333186) (xy 123.559062 -285.337504) (xy 123.583868 -285.342683)
			(xy 123.63161 -285.359669) (xy 123.67619 -285.383762) (xy 123.716558 -285.414393) (xy 123.751763 -285.450841)
			(xy 123.780975 -285.492247) (xy 123.803506 -285.537636) (xy 123.818825 -285.585939) (xy 123.826572 -285.636017)
			(xy 123.827032 -285.661354) (xy 123.826524 -285.687241) (xy 123.818425 -285.738379) (xy 123.802426 -285.787619)
			(xy 123.77892 -285.833751) (xy 123.748488 -285.875638) (xy 123.711878 -285.912248) (xy 123.669991 -285.94268)
			(xy 123.623859 -285.966186) (xy 123.574619 -285.982185) (xy 123.523481 -285.990284) (xy 123.471707 -285.990284)
			(xy 123.420569 -285.982185) (xy 123.371329 -285.966186) (xy 123.325197 -285.94268) (xy 123.28331 -285.912248)
			(xy 123.2467 -285.875638) (xy 123.216268 -285.833751) (xy 123.192762 -285.787619) (xy 123.176763 -285.738379)
			(xy 123.168664 -285.687241) (xy 123.168156 -285.661354) (xy 123.168701 -285.633647) (xy 123.177886 -285.579)
			(xy 123.186444 -285.552642) (xy 123.194318 -285.530544) (xy 122.98934 -285.175706) (xy 122.96648 -285.171388)
			(xy 122.94166 -285.166215) (xy 122.89388 -285.149263) (xy 122.849259 -285.125194) (xy 122.808851 -285.094575)
			(xy 122.773609 -285.058129) (xy 122.744365 -285.016715) (xy 122.721809 -284.971312) (xy 122.706472 -284.922989)
			(xy 122.698717 -284.872887) (xy 122.698256 -284.847538) (xy 121.47804 -284.847538) (xy 121.477434 -284.875255)
			(xy 121.468119 -284.929901) (xy 121.459498 -284.95625) (xy 121.451624 -284.978348) (xy 121.656602 -285.333186)
			(xy 121.679462 -285.337504) (xy 121.704268 -285.342683) (xy 121.75201 -285.359669) (xy 121.79659 -285.383762)
			(xy 121.836958 -285.414393) (xy 121.872163 -285.450841) (xy 121.901375 -285.492247) (xy 121.923906 -285.537636)
			(xy 121.939225 -285.585939) (xy 121.946972 -285.636017) (xy 121.947432 -285.661354) (xy 121.946924 -285.687241)
			(xy 121.938825 -285.738379) (xy 121.922826 -285.787619) (xy 121.89932 -285.833751) (xy 121.868888 -285.875638)
			(xy 121.832278 -285.912248) (xy 121.790391 -285.94268) (xy 121.744259 -285.966186) (xy 121.695019 -285.982185)
			(xy 121.643881 -285.990284) (xy 121.592107 -285.990284) (xy 121.540969 -285.982185) (xy 121.491729 -285.966186)
			(xy 121.445597 -285.94268) (xy 121.40371 -285.912248) (xy 121.3671 -285.875638) (xy 121.336668 -285.833751)
			(xy 121.313162 -285.787619) (xy 121.297163 -285.738379) (xy 121.289064 -285.687241) (xy 121.288556 -285.661354)
			(xy 121.289101 -285.633647) (xy 121.298286 -285.579) (xy 121.306844 -285.552642) (xy 121.314718 -285.530544)
			(xy 121.10974 -285.175706) (xy 121.08688 -285.171388) (xy 121.06206 -285.166215) (xy 121.01428 -285.149263)
			(xy 120.969659 -285.125194) (xy 120.929251 -285.094575) (xy 120.894009 -285.058129) (xy 120.864765 -285.016715)
			(xy 120.842209 -284.971312) (xy 120.826872 -284.922989) (xy 120.819117 -284.872887) (xy 120.818656 -284.847538)
			(xy 119.61676 -284.847538) (xy 119.929148 -285.392368) (xy 119.93753 -285.398718) (xy 119.958317 -285.415132)
			(xy 119.994862 -285.453466) (xy 120.024793 -285.49716) (xy 120.047335 -285.545085) (xy 120.061908 -285.596003)
			(xy 120.065546 -285.622238) (xy 120.066816 -285.632398) (xy 120.178322 -285.827216) (xy 120.18637 -285.840214)
			(xy 120.208728 -285.861046) (xy 120.236244 -285.874339) (xy 120.26646 -285.878906) (xy 120.296676 -285.874339)
			(xy 120.324192 -285.861046) (xy 120.34655 -285.840214) (xy 120.354598 -285.827216) (xy 120.374918 -285.792164)
			(xy 120.367044 -285.77032) (xy 120.358465 -285.743901) (xy 120.34927 -285.689126) (xy 120.348756 -285.661354)
			(xy 120.349264 -285.635467) (xy 120.357363 -285.584329) (xy 120.373362 -285.535089) (xy 120.396868 -285.488957)
			(xy 120.4273 -285.44707) (xy 120.46391 -285.41046) (xy 120.505797 -285.380028) (xy 120.551929 -285.356522)
			(xy 120.601169 -285.340523) (xy 120.652307 -285.332424) (xy 120.704081 -285.332424) (xy 120.755219 -285.340523)
			(xy 120.804459 -285.356522) (xy 120.850591 -285.380028) (xy 120.892478 -285.41046) (xy 120.929088 -285.44707)
			(xy 120.95952 -285.488957) (xy 120.983026 -285.535089) (xy 120.999025 -285.584329) (xy 121.007124 -285.635467)
			(xy 121.007632 -285.661354) (xy 121.007171 -285.686691) (xy 120.999424 -285.736768) (xy 120.984103 -285.785069)
			(xy 120.961572 -285.830458) (xy 120.93236 -285.871863) (xy 120.897155 -285.90831) (xy 120.856787 -285.93894)
			(xy 120.812208 -285.963032) (xy 120.764466 -285.980017) (xy 120.739662 -285.985204) (xy 120.716802 -285.989522)
			(xy 120.511824 -286.344614) (xy 120.519698 -286.366458) (xy 120.525875 -286.385017) (xy 120.534286 -286.423219)
			(xy 120.536462 -286.442658) (xy 120.537478 -286.453326) (xy 120.550148 -286.475424) (xy 121.758456 -286.475424)
			(xy 121.758954 -286.450079) (xy 121.766723 -286.399987) (xy 121.782068 -286.351675) (xy 121.804626 -286.306281)
			(xy 121.833866 -286.264873) (xy 121.869099 -286.228429) (xy 121.909494 -286.197807) (xy 121.9541 -286.173728)
			(xy 122.001866 -286.156759) (xy 122.02668 -286.151574) (xy 122.04954 -286.147256) (xy 122.254518 -285.792164)
			(xy 122.246644 -285.77032) (xy 122.238071 -285.743899) (xy 122.22887 -285.689126) (xy 122.228356 -285.661354)
			(xy 122.228864 -285.635467) (xy 122.236963 -285.584329) (xy 122.252962 -285.535089) (xy 122.276468 -285.488957)
			(xy 122.3069 -285.44707) (xy 122.34351 -285.41046) (xy 122.385397 -285.380028) (xy 122.431529 -285.356522)
			(xy 122.480769 -285.340523) (xy 122.531907 -285.332424) (xy 122.583681 -285.332424) (xy 122.634819 -285.340523)
			(xy 122.684059 -285.356522) (xy 122.730191 -285.380028) (xy 122.772078 -285.41046) (xy 122.808688 -285.44707)
			(xy 122.83912 -285.488957) (xy 122.862626 -285.535089) (xy 122.878625 -285.584329) (xy 122.886724 -285.635467)
			(xy 122.887232 -285.661354) (xy 122.886772 -285.686689) (xy 122.879013 -285.736761) (xy 122.863685 -285.785057)
			(xy 122.841149 -285.830439) (xy 122.811936 -285.87184) (xy 122.776734 -285.908285) (xy 122.736371 -285.938915)
			(xy 122.691797 -285.963011) (xy 122.644062 -285.980004) (xy 122.619262 -285.985204) (xy 122.596402 -285.989522)
			(xy 122.391424 -286.344614) (xy 122.399298 -286.366458) (xy 122.407949 -286.392865) (xy 122.417266 -286.447642)
			(xy 122.41784 -286.475424) (xy 123.638056 -286.475424) (xy 123.638554 -286.450079) (xy 123.646323 -286.399987)
			(xy 123.661668 -286.351675) (xy 123.684226 -286.306281) (xy 123.713466 -286.264873) (xy 123.748699 -286.228429)
			(xy 123.789094 -286.197807) (xy 123.8337 -286.173728) (xy 123.881466 -286.156759) (xy 123.90628 -286.151574)
			(xy 123.92914 -286.147256) (xy 124.134118 -285.792164) (xy 124.126244 -285.77032) (xy 124.117671 -285.743899)
			(xy 124.10847 -285.689126) (xy 124.107956 -285.661354) (xy 124.108464 -285.635467) (xy 124.116563 -285.584329)
			(xy 124.132562 -285.535089) (xy 124.156068 -285.488957) (xy 124.1865 -285.44707) (xy 124.22311 -285.41046)
			(xy 124.264997 -285.380028) (xy 124.311129 -285.356522) (xy 124.360369 -285.340523) (xy 124.411507 -285.332424)
			(xy 124.463281 -285.332424) (xy 124.514419 -285.340523) (xy 124.563659 -285.356522) (xy 124.609791 -285.380028)
			(xy 124.651678 -285.41046) (xy 124.688288 -285.44707) (xy 124.71872 -285.488957) (xy 124.742226 -285.535089)
			(xy 124.758225 -285.584329) (xy 124.766324 -285.635467) (xy 124.766832 -285.661354) (xy 124.766372 -285.686689)
			(xy 124.758613 -285.736761) (xy 124.743285 -285.785057) (xy 124.720749 -285.830439) (xy 124.691536 -285.87184)
			(xy 124.656334 -285.908285) (xy 124.615971 -285.938915) (xy 124.571397 -285.963011) (xy 124.523662 -285.980004)
			(xy 124.498862 -285.985204) (xy 124.476002 -285.989522) (xy 124.271024 -286.344614) (xy 124.278898 -286.366458)
			(xy 124.287549 -286.392865) (xy 124.296866 -286.447642) (xy 124.29744 -286.475424) (xy 125.517656 -286.475424)
			(xy 125.518154 -286.450079) (xy 125.525923 -286.399987) (xy 125.541268 -286.351675) (xy 125.563826 -286.306281)
			(xy 125.593066 -286.264873) (xy 125.628299 -286.228429) (xy 125.668694 -286.197807) (xy 125.7133 -286.173728)
			(xy 125.761066 -286.156759) (xy 125.78588 -286.151574) (xy 125.80874 -286.147256) (xy 126.013718 -285.792164)
			(xy 126.005844 -285.77032) (xy 125.997271 -285.743899) (xy 125.98807 -285.689126) (xy 125.987556 -285.661354)
			(xy 125.988064 -285.635467) (xy 125.996163 -285.584329) (xy 126.012162 -285.535089) (xy 126.035668 -285.488957)
			(xy 126.0661 -285.44707) (xy 126.10271 -285.41046) (xy 126.144597 -285.380028) (xy 126.190729 -285.356522)
			(xy 126.239969 -285.340523) (xy 126.291107 -285.332424) (xy 126.342881 -285.332424) (xy 126.394019 -285.340523)
			(xy 126.443259 -285.356522) (xy 126.489391 -285.380028) (xy 126.531278 -285.41046) (xy 126.567888 -285.44707)
			(xy 126.59832 -285.488957) (xy 126.621826 -285.535089) (xy 126.637825 -285.584329) (xy 126.645924 -285.635467)
			(xy 126.646432 -285.661354) (xy 126.645972 -285.686689) (xy 126.638213 -285.736761) (xy 126.622885 -285.785057)
			(xy 126.600349 -285.830439) (xy 126.571136 -285.87184) (xy 126.535934 -285.908285) (xy 126.495571 -285.938915)
			(xy 126.450997 -285.963011) (xy 126.403262 -285.980004) (xy 126.378462 -285.985204) (xy 126.355602 -285.989522)
			(xy 126.150624 -286.344614) (xy 126.158498 -286.366458) (xy 126.167149 -286.392865) (xy 126.176466 -286.447642)
			(xy 126.17704 -286.475424) (xy 127.397256 -286.475424) (xy 127.397754 -286.450079) (xy 127.405523 -286.399987)
			(xy 127.420868 -286.351675) (xy 127.443426 -286.306281) (xy 127.472666 -286.264873) (xy 127.507899 -286.228429)
			(xy 127.548294 -286.197807) (xy 127.5929 -286.173728) (xy 127.640666 -286.156759) (xy 127.66548 -286.151574)
			(xy 127.68834 -286.147256) (xy 127.893318 -285.792164) (xy 127.885444 -285.77032) (xy 127.876871 -285.743899)
			(xy 127.86767 -285.689126) (xy 127.867156 -285.661354) (xy 127.867664 -285.635467) (xy 127.875763 -285.584329)
			(xy 127.891762 -285.535089) (xy 127.915268 -285.488957) (xy 127.9457 -285.44707) (xy 127.98231 -285.41046)
			(xy 128.024197 -285.380028) (xy 128.070329 -285.356522) (xy 128.119569 -285.340523) (xy 128.170707 -285.332424)
			(xy 128.222481 -285.332424) (xy 128.273619 -285.340523) (xy 128.322859 -285.356522) (xy 128.368991 -285.380028)
			(xy 128.410878 -285.41046) (xy 128.447488 -285.44707) (xy 128.47792 -285.488957) (xy 128.501426 -285.535089)
			(xy 128.517425 -285.584329) (xy 128.525524 -285.635467) (xy 128.526032 -285.661354) (xy 128.525572 -285.686689)
			(xy 128.517813 -285.736761) (xy 128.502485 -285.785057) (xy 128.479949 -285.830439) (xy 128.450736 -285.87184)
			(xy 128.415534 -285.908285) (xy 128.375171 -285.938915) (xy 128.330597 -285.963011) (xy 128.282862 -285.980004)
			(xy 128.258062 -285.985204) (xy 128.235202 -285.989522) (xy 128.030224 -286.344614) (xy 128.038098 -286.366458)
			(xy 128.046749 -286.392865) (xy 128.056066 -286.447642) (xy 128.05664 -286.475424) (xy 129.276856 -286.475424)
			(xy 129.277354 -286.450079) (xy 129.285123 -286.399987) (xy 129.300468 -286.351675) (xy 129.323026 -286.306281)
			(xy 129.352266 -286.264873) (xy 129.387499 -286.228429) (xy 129.427894 -286.197807) (xy 129.4725 -286.173728)
			(xy 129.520266 -286.156759) (xy 129.54508 -286.151574) (xy 129.56794 -286.147256) (xy 129.772918 -285.792164)
			(xy 129.765044 -285.77032) (xy 129.756471 -285.743899) (xy 129.74727 -285.689126) (xy 129.746756 -285.661354)
			(xy 129.747264 -285.635467) (xy 129.755363 -285.584329) (xy 129.771362 -285.535089) (xy 129.794868 -285.488957)
			(xy 129.8253 -285.44707) (xy 129.86191 -285.41046) (xy 129.903797 -285.380028) (xy 129.949929 -285.356522)
			(xy 129.999169 -285.340523) (xy 130.050307 -285.332424) (xy 130.102081 -285.332424) (xy 130.153219 -285.340523)
			(xy 130.202459 -285.356522) (xy 130.248591 -285.380028) (xy 130.290478 -285.41046) (xy 130.327088 -285.44707)
			(xy 130.35752 -285.488957) (xy 130.381026 -285.535089) (xy 130.397025 -285.584329) (xy 130.405124 -285.635467)
			(xy 130.405632 -285.661354) (xy 130.405172 -285.686689) (xy 130.397413 -285.736761) (xy 130.382085 -285.785057)
			(xy 130.359549 -285.830439) (xy 130.330336 -285.87184) (xy 130.295134 -285.908285) (xy 130.254771 -285.938915)
			(xy 130.210197 -285.963011) (xy 130.162462 -285.980004) (xy 130.137662 -285.985204) (xy 130.114802 -285.989522)
			(xy 129.909824 -286.344614) (xy 129.917698 -286.366458) (xy 129.926349 -286.392865) (xy 129.935666 -286.447642)
			(xy 129.93624 -286.475424) (xy 131.156456 -286.475424) (xy 131.156954 -286.450079) (xy 131.164723 -286.399987)
			(xy 131.180068 -286.351675) (xy 131.202626 -286.306281) (xy 131.231866 -286.264873) (xy 131.267099 -286.228429)
			(xy 131.307494 -286.197807) (xy 131.3521 -286.173728) (xy 131.399866 -286.156759) (xy 131.42468 -286.151574)
			(xy 131.44754 -286.147256) (xy 131.652518 -285.792164) (xy 131.644644 -285.77032) (xy 131.636071 -285.743899)
			(xy 131.62687 -285.689126) (xy 131.626356 -285.661354) (xy 131.626864 -285.635467) (xy 131.634963 -285.584329)
			(xy 131.650962 -285.535089) (xy 131.674468 -285.488957) (xy 131.7049 -285.44707) (xy 131.74151 -285.41046)
			(xy 131.783397 -285.380028) (xy 131.829529 -285.356522) (xy 131.878769 -285.340523) (xy 131.929907 -285.332424)
			(xy 131.981681 -285.332424) (xy 132.032819 -285.340523) (xy 132.082059 -285.356522) (xy 132.128191 -285.380028)
			(xy 132.170078 -285.41046) (xy 132.206688 -285.44707) (xy 132.23712 -285.488957) (xy 132.260626 -285.535089)
			(xy 132.276625 -285.584329) (xy 132.284724 -285.635467) (xy 132.285232 -285.661354) (xy 132.284772 -285.686689)
			(xy 132.277013 -285.736761) (xy 132.261685 -285.785057) (xy 132.239149 -285.830439) (xy 132.209936 -285.87184)
			(xy 132.174734 -285.908285) (xy 132.134371 -285.938915) (xy 132.089797 -285.963011) (xy 132.042062 -285.980004)
			(xy 132.017262 -285.985204) (xy 131.994402 -285.989522) (xy 131.789424 -286.344614) (xy 131.797298 -286.366458)
			(xy 131.805949 -286.392865) (xy 131.815266 -286.447642) (xy 131.81584 -286.475424) (xy 133.036056 -286.475424)
			(xy 133.036554 -286.450079) (xy 133.044323 -286.399987) (xy 133.059668 -286.351675) (xy 133.082226 -286.306281)
			(xy 133.111466 -286.264873) (xy 133.146699 -286.228429) (xy 133.187094 -286.197807) (xy 133.2317 -286.173728)
			(xy 133.279466 -286.156759) (xy 133.30428 -286.151574) (xy 133.32714 -286.147256) (xy 133.532118 -285.792164)
			(xy 133.524244 -285.77032) (xy 133.515671 -285.743899) (xy 133.50647 -285.689126) (xy 133.505956 -285.661354)
			(xy 133.506464 -285.635467) (xy 133.514563 -285.584329) (xy 133.530562 -285.535089) (xy 133.554068 -285.488957)
			(xy 133.5845 -285.44707) (xy 133.62111 -285.41046) (xy 133.662997 -285.380028) (xy 133.709129 -285.356522)
			(xy 133.758369 -285.340523) (xy 133.809507 -285.332424) (xy 133.861281 -285.332424) (xy 133.912419 -285.340523)
			(xy 133.961659 -285.356522) (xy 134.007791 -285.380028) (xy 134.049678 -285.41046) (xy 134.086288 -285.44707)
			(xy 134.11672 -285.488957) (xy 134.140226 -285.535089) (xy 134.156225 -285.584329) (xy 134.164324 -285.635467)
			(xy 134.164832 -285.661354) (xy 134.164372 -285.686689) (xy 134.156613 -285.736761) (xy 134.141285 -285.785057)
			(xy 134.118749 -285.830439) (xy 134.089536 -285.87184) (xy 134.054334 -285.908285) (xy 134.013971 -285.938915)
			(xy 133.969397 -285.963011) (xy 133.921662 -285.980004) (xy 133.896862 -285.985204) (xy 133.874002 -285.989522)
			(xy 133.669024 -286.344614) (xy 133.676898 -286.366458) (xy 133.685549 -286.392865) (xy 133.694866 -286.447642)
			(xy 133.69544 -286.475424) (xy 133.694932 -286.501331) (xy 133.686826 -286.552508) (xy 133.670814 -286.601787)
			(xy 133.647291 -286.647954) (xy 133.616835 -286.689873) (xy 133.580197 -286.726511) (xy 133.538278 -286.756967)
			(xy 133.492111 -286.78049) (xy 133.442832 -286.796502) (xy 133.391655 -286.804608) (xy 133.339841 -286.804608)
			(xy 133.288664 -286.796502) (xy 133.239385 -286.78049) (xy 133.193218 -286.756967) (xy 133.151299 -286.726511)
			(xy 133.114661 -286.689873) (xy 133.084205 -286.647954) (xy 133.060682 -286.601787) (xy 133.04467 -286.552508)
			(xy 133.036564 -286.501331) (xy 133.036056 -286.475424) (xy 131.81584 -286.475424) (xy 131.815332 -286.501331)
			(xy 131.807226 -286.552508) (xy 131.791214 -286.601787) (xy 131.767691 -286.647954) (xy 131.737235 -286.689873)
			(xy 131.700597 -286.726511) (xy 131.658678 -286.756967) (xy 131.612511 -286.78049) (xy 131.563232 -286.796502)
			(xy 131.512055 -286.804608) (xy 131.460241 -286.804608) (xy 131.409064 -286.796502) (xy 131.359785 -286.78049)
			(xy 131.313618 -286.756967) (xy 131.271699 -286.726511) (xy 131.235061 -286.689873) (xy 131.204605 -286.647954)
			(xy 131.181082 -286.601787) (xy 131.16507 -286.552508) (xy 131.156964 -286.501331) (xy 131.156456 -286.475424)
			(xy 129.93624 -286.475424) (xy 129.935732 -286.501331) (xy 129.927626 -286.552508) (xy 129.911614 -286.601787)
			(xy 129.888091 -286.647954) (xy 129.857635 -286.689873) (xy 129.820997 -286.726511) (xy 129.779078 -286.756967)
			(xy 129.732911 -286.78049) (xy 129.683632 -286.796502) (xy 129.632455 -286.804608) (xy 129.580641 -286.804608)
			(xy 129.529464 -286.796502) (xy 129.480185 -286.78049) (xy 129.434018 -286.756967) (xy 129.392099 -286.726511)
			(xy 129.355461 -286.689873) (xy 129.325005 -286.647954) (xy 129.301482 -286.601787) (xy 129.28547 -286.552508)
			(xy 129.277364 -286.501331) (xy 129.276856 -286.475424) (xy 128.05664 -286.475424) (xy 128.056132 -286.501331)
			(xy 128.048026 -286.552508) (xy 128.032014 -286.601787) (xy 128.008491 -286.647954) (xy 127.978035 -286.689873)
			(xy 127.941397 -286.726511) (xy 127.899478 -286.756967) (xy 127.853311 -286.78049) (xy 127.804032 -286.796502)
			(xy 127.752855 -286.804608) (xy 127.701041 -286.804608) (xy 127.649864 -286.796502) (xy 127.600585 -286.78049)
			(xy 127.554418 -286.756967) (xy 127.512499 -286.726511) (xy 127.475861 -286.689873) (xy 127.445405 -286.647954)
			(xy 127.421882 -286.601787) (xy 127.40587 -286.552508) (xy 127.397764 -286.501331) (xy 127.397256 -286.475424)
			(xy 126.17704 -286.475424) (xy 126.176532 -286.501331) (xy 126.168426 -286.552508) (xy 126.152414 -286.601787)
			(xy 126.128891 -286.647954) (xy 126.098435 -286.689873) (xy 126.061797 -286.726511) (xy 126.019878 -286.756967)
			(xy 125.973711 -286.78049) (xy 125.924432 -286.796502) (xy 125.873255 -286.804608) (xy 125.821441 -286.804608)
			(xy 125.770264 -286.796502) (xy 125.720985 -286.78049) (xy 125.674818 -286.756967) (xy 125.632899 -286.726511)
			(xy 125.596261 -286.689873) (xy 125.565805 -286.647954) (xy 125.542282 -286.601787) (xy 125.52627 -286.552508)
			(xy 125.518164 -286.501331) (xy 125.517656 -286.475424) (xy 124.29744 -286.475424) (xy 124.296932 -286.501331)
			(xy 124.288826 -286.552508) (xy 124.272814 -286.601787) (xy 124.249291 -286.647954) (xy 124.218835 -286.689873)
			(xy 124.182197 -286.726511) (xy 124.140278 -286.756967) (xy 124.094111 -286.78049) (xy 124.044832 -286.796502)
			(xy 123.993655 -286.804608) (xy 123.941841 -286.804608) (xy 123.890664 -286.796502) (xy 123.841385 -286.78049)
			(xy 123.795218 -286.756967) (xy 123.753299 -286.726511) (xy 123.716661 -286.689873) (xy 123.686205 -286.647954)
			(xy 123.662682 -286.601787) (xy 123.64667 -286.552508) (xy 123.638564 -286.501331) (xy 123.638056 -286.475424)
			(xy 122.41784 -286.475424) (xy 122.417332 -286.501331) (xy 122.409226 -286.552508) (xy 122.393214 -286.601787)
			(xy 122.369691 -286.647954) (xy 122.339235 -286.689873) (xy 122.302597 -286.726511) (xy 122.260678 -286.756967)
			(xy 122.214511 -286.78049) (xy 122.165232 -286.796502) (xy 122.114055 -286.804608) (xy 122.062241 -286.804608)
			(xy 122.011064 -286.796502) (xy 121.961785 -286.78049) (xy 121.915618 -286.756967) (xy 121.873699 -286.726511)
			(xy 121.837061 -286.689873) (xy 121.806605 -286.647954) (xy 121.783082 -286.601787) (xy 121.76707 -286.552508)
			(xy 121.758964 -286.501331) (xy 121.758456 -286.475424) (xy 120.550148 -286.475424) (xy 120.860058 -287.015936)
			(xy 120.869202 -287.022286) (xy 120.891789 -287.039168) (xy 120.931363 -287.079333) (xy 120.963498 -287.125665)
			(xy 120.987249 -287.176804) (xy 121.001919 -287.231248) (xy 121.005092 -287.259268) (xy 121.006108 -287.27019)
			(xy 121.3231 -287.823402) (xy 121.333006 -287.830006) (xy 121.353493 -287.844424) (xy 121.390266 -287.878443)
			(xy 121.421466 -287.917635) (xy 121.446375 -287.961098) (xy 121.464419 -288.007831) (xy 121.475182 -288.056756)
			(xy 121.477278 -288.08172) (xy 121.47804 -288.093404) (xy 121.788428 -288.634678) (xy 121.798588 -288.641282)
			(xy 121.818496 -288.654752) (xy 121.854515 -288.686579) (xy 121.885514 -288.723314) (xy 121.910831 -288.764173)
			(xy 121.920762 -288.786062) (xy 121.93397 -288.816796) (xy 122.242326 -288.816796) (xy 122.255534 -288.786062)
			(xy 122.266919 -288.761162) (xy 122.296698 -288.715223) (xy 122.333662 -288.674838) (xy 122.376793 -288.64112)
			(xy 122.424905 -288.614995) (xy 122.476673 -288.597183) (xy 122.530674 -288.588174) (xy 122.558048 -288.587688)
			(xy 122.585421 -288.588208) (xy 122.63942 -288.597215) (xy 122.691188 -288.615022) (xy 122.739301 -288.641139)
			(xy 122.782437 -288.674849) (xy 122.819407 -288.715225) (xy 122.849197 -288.761155) (xy 122.860562 -288.786062)
			(xy 122.87377 -288.816796) (xy 123.036076 -288.816796) (xy 123.051299 -288.81622) (xy 123.08039 -288.807235)
			(xy 123.105546 -288.790084) (xy 123.124539 -288.766287) (xy 123.135684 -288.737954) (xy 123.137995 -288.707595)
			(xy 123.131266 -288.677902) (xy 123.124214 -288.664396) (xy 122.989594 -288.431224) (xy 122.966734 -288.426906)
			(xy 122.941896 -288.421758) (xy 122.894074 -288.404849) (xy 122.84941 -288.380806) (xy 122.808962 -288.350198)
			(xy 122.773686 -288.313749) (xy 122.744417 -288.272322) (xy 122.721847 -288.226897) (xy 122.70651 -288.178548)
			(xy 122.698769 -288.128418) (xy 122.698256 -288.103056) (xy 122.698764 -288.077149) (xy 122.70687 -288.025972)
			(xy 122.722882 -287.976693) (xy 122.746405 -287.930526) (xy 122.776861 -287.888607) (xy 122.813499 -287.851969)
			(xy 122.855418 -287.821513) (xy 122.901585 -287.79799) (xy 122.950864 -287.781978) (xy 123.002041 -287.773872)
			(xy 123.053855 -287.773872) (xy 123.105032 -287.781978) (xy 123.154311 -287.79799) (xy 123.200478 -287.821513)
			(xy 123.242397 -287.851969) (xy 123.279035 -287.888607) (xy 123.309491 -287.930526) (xy 123.333014 -287.976693)
			(xy 123.349026 -288.025972) (xy 123.357132 -288.077149) (xy 123.35764 -288.103056) (xy 123.357047 -288.130773)
			(xy 123.34772 -288.185419) (xy 123.339098 -288.211768) (xy 123.331478 -288.233866) (xy 123.536456 -288.588958)
			(xy 123.559316 -288.593276) (xy 123.585527 -288.598792) (xy 123.635837 -288.617168) (xy 123.682517 -288.643432)
			(xy 123.72434 -288.676893) (xy 123.760206 -288.716672) (xy 123.789174 -288.761724) (xy 123.800362 -288.786062)
			(xy 123.81357 -288.816796) (xy 124.121926 -288.816796) (xy 124.135134 -288.786062) (xy 124.146519 -288.761162)
			(xy 124.176298 -288.715223) (xy 124.213262 -288.674838) (xy 124.256393 -288.64112) (xy 124.304505 -288.614995)
			(xy 124.356273 -288.597183) (xy 124.410274 -288.588174) (xy 124.437648 -288.587688) (xy 124.465021 -288.588208)
			(xy 124.51902 -288.597215) (xy 124.570788 -288.615022) (xy 124.618901 -288.641139) (xy 124.662037 -288.674849)
			(xy 124.699007 -288.715225) (xy 124.728797 -288.761155) (xy 124.740162 -288.786062) (xy 124.75337 -288.816796)
			(xy 124.915676 -288.816796) (xy 124.930899 -288.81622) (xy 124.95999 -288.807235) (xy 124.985146 -288.790084)
			(xy 125.004139 -288.766287) (xy 125.015284 -288.737954) (xy 125.017595 -288.707595) (xy 125.010866 -288.677902)
			(xy 125.003814 -288.664396) (xy 124.869194 -288.431224) (xy 124.846334 -288.426906) (xy 124.821496 -288.421758)
			(xy 124.773674 -288.404849) (xy 124.72901 -288.380806) (xy 124.688562 -288.350198) (xy 124.653286 -288.313749)
			(xy 124.624017 -288.272322) (xy 124.601447 -288.226897) (xy 124.58611 -288.178548) (xy 124.578369 -288.128418)
			(xy 124.577856 -288.103056) (xy 124.578364 -288.077149) (xy 124.58647 -288.025972) (xy 124.602482 -287.976693)
			(xy 124.626005 -287.930526) (xy 124.656461 -287.888607) (xy 124.693099 -287.851969) (xy 124.735018 -287.821513)
			(xy 124.781185 -287.79799) (xy 124.830464 -287.781978) (xy 124.881641 -287.773872) (xy 124.933455 -287.773872)
			(xy 124.984632 -287.781978) (xy 125.033911 -287.79799) (xy 125.080078 -287.821513) (xy 125.121997 -287.851969)
			(xy 125.158635 -287.888607) (xy 125.189091 -287.930526) (xy 125.212614 -287.976693) (xy 125.228626 -288.025972)
			(xy 125.236732 -288.077149) (xy 125.23724 -288.103056) (xy 125.236647 -288.130773) (xy 125.22732 -288.185419)
			(xy 125.218698 -288.211768) (xy 125.211078 -288.233866) (xy 125.416056 -288.588958) (xy 125.438916 -288.593276)
			(xy 125.465127 -288.598792) (xy 125.515437 -288.617168) (xy 125.562117 -288.643432) (xy 125.60394 -288.676893)
			(xy 125.639806 -288.716672) (xy 125.668774 -288.761724) (xy 125.679962 -288.786062) (xy 125.69317 -288.816796)
			(xy 126.001526 -288.816796) (xy 126.014734 -288.786062) (xy 126.026119 -288.761162) (xy 126.055898 -288.715223)
			(xy 126.092862 -288.674838) (xy 126.135993 -288.64112) (xy 126.184105 -288.614995) (xy 126.235873 -288.597183)
			(xy 126.289874 -288.588174) (xy 126.317248 -288.587688) (xy 126.344621 -288.588208) (xy 126.39862 -288.597215)
			(xy 126.450388 -288.615022) (xy 126.498501 -288.641139) (xy 126.541637 -288.674849) (xy 126.578607 -288.715225)
			(xy 126.608397 -288.761155) (xy 126.619762 -288.786062) (xy 126.63297 -288.816796) (xy 126.795276 -288.816796)
			(xy 126.810499 -288.81622) (xy 126.83959 -288.807235) (xy 126.864746 -288.790084) (xy 126.883739 -288.766287)
			(xy 126.894884 -288.737954) (xy 126.897195 -288.707595) (xy 126.890466 -288.677902) (xy 126.883414 -288.664396)
			(xy 126.748794 -288.431224) (xy 126.725934 -288.426906) (xy 126.701096 -288.421758) (xy 126.653274 -288.404849)
			(xy 126.60861 -288.380806) (xy 126.568162 -288.350198) (xy 126.532886 -288.313749) (xy 126.503617 -288.272322)
			(xy 126.481047 -288.226897) (xy 126.46571 -288.178548) (xy 126.457969 -288.128418) (xy 126.457456 -288.103056)
			(xy 126.457964 -288.077149) (xy 126.46607 -288.025972) (xy 126.482082 -287.976693) (xy 126.505605 -287.930526)
			(xy 126.536061 -287.888607) (xy 126.572699 -287.851969) (xy 126.614618 -287.821513) (xy 126.660785 -287.79799)
			(xy 126.710064 -287.781978) (xy 126.761241 -287.773872) (xy 126.813055 -287.773872) (xy 126.864232 -287.781978)
			(xy 126.913511 -287.79799) (xy 126.959678 -287.821513) (xy 127.001597 -287.851969) (xy 127.038235 -287.888607)
			(xy 127.068691 -287.930526) (xy 127.092214 -287.976693) (xy 127.108226 -288.025972) (xy 127.116332 -288.077149)
			(xy 127.11684 -288.103056) (xy 127.116247 -288.130773) (xy 127.10692 -288.185419) (xy 127.098298 -288.211768)
			(xy 127.090678 -288.233866) (xy 127.295656 -288.588958) (xy 127.318516 -288.593276) (xy 127.344727 -288.598792)
			(xy 127.395037 -288.617168) (xy 127.441717 -288.643432) (xy 127.48354 -288.676893) (xy 127.519406 -288.716672)
			(xy 127.548374 -288.761724) (xy 127.559562 -288.786062) (xy 127.57277 -288.816796) (xy 127.881126 -288.816796)
			(xy 127.894334 -288.786062) (xy 127.905719 -288.761162) (xy 127.935498 -288.715223) (xy 127.972462 -288.674838)
			(xy 128.015593 -288.64112) (xy 128.063705 -288.614995) (xy 128.115473 -288.597183) (xy 128.169474 -288.588174)
			(xy 128.196848 -288.587688) (xy 128.224221 -288.588208) (xy 128.27822 -288.597215) (xy 128.329988 -288.615022)
			(xy 128.378101 -288.641139) (xy 128.421237 -288.674849) (xy 128.458207 -288.715225) (xy 128.487997 -288.761155)
			(xy 128.499362 -288.786062) (xy 128.51257 -288.816796) (xy 128.674876 -288.816796) (xy 128.690099 -288.81622)
			(xy 128.71919 -288.807235) (xy 128.744346 -288.790084) (xy 128.763339 -288.766287) (xy 128.774484 -288.737954)
			(xy 128.776795 -288.707595) (xy 128.770066 -288.677902) (xy 128.763014 -288.664396) (xy 128.628394 -288.431224)
			(xy 128.605534 -288.426906) (xy 128.580696 -288.421758) (xy 128.532874 -288.404849) (xy 128.48821 -288.380806)
			(xy 128.447762 -288.350198) (xy 128.412486 -288.313749) (xy 128.383217 -288.272322) (xy 128.360647 -288.226897)
			(xy 128.34531 -288.178548) (xy 128.337569 -288.128418) (xy 128.337056 -288.103056) (xy 128.337564 -288.077149)
			(xy 128.34567 -288.025972) (xy 128.361682 -287.976693) (xy 128.385205 -287.930526) (xy 128.415661 -287.888607)
			(xy 128.452299 -287.851969) (xy 128.494218 -287.821513) (xy 128.540385 -287.79799) (xy 128.589664 -287.781978)
			(xy 128.640841 -287.773872) (xy 128.692655 -287.773872) (xy 128.743832 -287.781978) (xy 128.793111 -287.79799)
			(xy 128.839278 -287.821513) (xy 128.881197 -287.851969) (xy 128.917835 -287.888607) (xy 128.948291 -287.930526)
			(xy 128.971814 -287.976693) (xy 128.987826 -288.025972) (xy 128.995932 -288.077149) (xy 128.99644 -288.103056)
			(xy 128.995847 -288.130773) (xy 128.98652 -288.185419) (xy 128.977898 -288.211768) (xy 128.970278 -288.233866)
			(xy 129.175256 -288.588958) (xy 129.198116 -288.593276) (xy 129.224327 -288.598792) (xy 129.274637 -288.617168)
			(xy 129.321317 -288.643432) (xy 129.36314 -288.676893) (xy 129.399006 -288.716672) (xy 129.427974 -288.761724)
			(xy 129.439162 -288.786062) (xy 129.45237 -288.816796) (xy 129.760726 -288.816796) (xy 129.773934 -288.786062)
			(xy 129.785319 -288.761162) (xy 129.815098 -288.715223) (xy 129.852062 -288.674838) (xy 129.895193 -288.64112)
			(xy 129.943305 -288.614995) (xy 129.995073 -288.597183) (xy 130.049074 -288.588174) (xy 130.076448 -288.587688)
			(xy 130.103821 -288.588208) (xy 130.15782 -288.597215) (xy 130.209588 -288.615022) (xy 130.257701 -288.641139)
			(xy 130.300837 -288.674849) (xy 130.337807 -288.715225) (xy 130.367597 -288.761155) (xy 130.378962 -288.786062)
			(xy 130.39217 -288.816796) (xy 130.554476 -288.816796) (xy 130.569699 -288.81622) (xy 130.59879 -288.807235)
			(xy 130.623946 -288.790084) (xy 130.642939 -288.766287) (xy 130.654084 -288.737954) (xy 130.656395 -288.707595)
			(xy 130.649666 -288.677902) (xy 130.642614 -288.664396) (xy 130.507994 -288.431224) (xy 130.485134 -288.426906)
			(xy 130.460296 -288.421758) (xy 130.412474 -288.404849) (xy 130.36781 -288.380806) (xy 130.327362 -288.350198)
			(xy 130.292086 -288.313749) (xy 130.262817 -288.272322) (xy 130.240247 -288.226897) (xy 130.22491 -288.178548)
			(xy 130.217169 -288.128418) (xy 130.216656 -288.103056) (xy 130.217164 -288.077149) (xy 130.22527 -288.025972)
			(xy 130.241282 -287.976693) (xy 130.264805 -287.930526) (xy 130.295261 -287.888607) (xy 130.331899 -287.851969)
			(xy 130.373818 -287.821513) (xy 130.419985 -287.79799) (xy 130.469264 -287.781978) (xy 130.520441 -287.773872)
			(xy 130.572255 -287.773872) (xy 130.623432 -287.781978) (xy 130.672711 -287.79799) (xy 130.718878 -287.821513)
			(xy 130.760797 -287.851969) (xy 130.797435 -287.888607) (xy 130.827891 -287.930526) (xy 130.851414 -287.976693)
			(xy 130.867426 -288.025972) (xy 130.875532 -288.077149) (xy 130.87604 -288.103056) (xy 130.875447 -288.130773)
			(xy 130.86612 -288.185419) (xy 130.857498 -288.211768) (xy 130.849878 -288.233866) (xy 131.054856 -288.588958)
			(xy 131.077716 -288.593276) (xy 131.103927 -288.598792) (xy 131.154237 -288.617168) (xy 131.200917 -288.643432)
			(xy 131.24274 -288.676893) (xy 131.278606 -288.716672) (xy 131.307574 -288.761724) (xy 131.318762 -288.786062)
			(xy 131.33197 -288.816796) (xy 131.640326 -288.816796) (xy 131.653534 -288.786062) (xy 131.664919 -288.761162)
			(xy 131.694698 -288.715223) (xy 131.731662 -288.674838) (xy 131.774793 -288.64112) (xy 131.822905 -288.614995)
			(xy 131.874673 -288.597183) (xy 131.928674 -288.588174) (xy 131.956048 -288.587688) (xy 131.983421 -288.588208)
			(xy 132.03742 -288.597215) (xy 132.089188 -288.615022) (xy 132.137301 -288.641139) (xy 132.180437 -288.674849)
			(xy 132.217407 -288.715225) (xy 132.247197 -288.761155) (xy 132.258562 -288.786062) (xy 132.27177 -288.816796)
			(xy 132.434076 -288.816796) (xy 132.449299 -288.81622) (xy 132.47839 -288.807235) (xy 132.503546 -288.790084)
			(xy 132.522539 -288.766287) (xy 132.533684 -288.737954) (xy 132.535995 -288.707595) (xy 132.529266 -288.677902)
			(xy 132.522214 -288.664396) (xy 132.387594 -288.431224) (xy 132.364734 -288.426906) (xy 132.339896 -288.421758)
			(xy 132.292074 -288.404849) (xy 132.24741 -288.380806) (xy 132.206962 -288.350198) (xy 132.171686 -288.313749)
			(xy 132.142417 -288.272322) (xy 132.119847 -288.226897) (xy 132.10451 -288.178548) (xy 132.096769 -288.128418)
			(xy 132.096256 -288.103056) (xy 132.096764 -288.077149) (xy 132.10487 -288.025972) (xy 132.120882 -287.976693)
			(xy 132.144405 -287.930526) (xy 132.174861 -287.888607) (xy 132.211499 -287.851969) (xy 132.253418 -287.821513)
			(xy 132.299585 -287.79799) (xy 132.348864 -287.781978) (xy 132.400041 -287.773872) (xy 132.451855 -287.773872)
			(xy 132.503032 -287.781978) (xy 132.552311 -287.79799) (xy 132.598478 -287.821513) (xy 132.640397 -287.851969)
			(xy 132.677035 -287.888607) (xy 132.707491 -287.930526) (xy 132.731014 -287.976693) (xy 132.747026 -288.025972)
			(xy 132.755132 -288.077149) (xy 132.75564 -288.103056) (xy 132.755047 -288.130773) (xy 132.74572 -288.185419)
			(xy 132.737098 -288.211768) (xy 132.729478 -288.233866) (xy 132.934456 -288.588958) (xy 132.957316 -288.593276)
			(xy 132.983527 -288.598792) (xy 133.033837 -288.617168) (xy 133.080517 -288.643432) (xy 133.12234 -288.676893)
			(xy 133.158206 -288.716672) (xy 133.187174 -288.761724) (xy 133.198362 -288.786062) (xy 133.21157 -288.816796)
			(xy 133.519926 -288.816796) (xy 133.533134 -288.786062) (xy 133.544519 -288.761162) (xy 133.574298 -288.715223)
			(xy 133.611262 -288.674838) (xy 133.654393 -288.64112) (xy 133.702505 -288.614995) (xy 133.754273 -288.597183)
			(xy 133.808274 -288.588174) (xy 133.835648 -288.587688) (xy 133.863021 -288.588208) (xy 133.91702 -288.597215)
			(xy 133.968788 -288.615022) (xy 134.016901 -288.641139) (xy 134.060037 -288.674849) (xy 134.097007 -288.715225)
			(xy 134.126797 -288.761155) (xy 134.138162 -288.786062) (xy 134.15137 -288.816796) (xy 134.46125 -288.816796)
			(xy 134.474458 -288.786316) (xy 134.485023 -288.7632) (xy 134.512224 -288.720268) (xy 134.545718 -288.682043)
			(xy 134.584705 -288.649439) (xy 134.628251 -288.623234) (xy 134.675317 -288.604055) (xy 134.724777 -288.592361)
			(xy 134.775448 -288.588432) (xy 134.826119 -288.592361) (xy 134.875579 -288.604055) (xy 134.922645 -288.623234)
			(xy 134.966191 -288.649439) (xy 135.005178 -288.682043) (xy 135.038672 -288.720268) (xy 135.065873 -288.7632)
			(xy 135.076438 -288.786316) (xy 135.089646 -288.816796) (xy 135.253476 -288.816796) (xy 135.26871 -288.81629)
			(xy 135.297825 -288.807308) (xy 135.322994 -288.790138) (xy 135.341979 -288.766308) (xy 135.353088 -288.737937)
			(xy 135.355334 -288.707552) (xy 135.348517 -288.677856) (xy 135.34136 -288.664396) (xy 135.20674 -288.431224)
			(xy 135.18388 -288.426906) (xy 135.159064 -288.421722) (xy 135.111292 -288.404755) (xy 135.066679 -288.380677)
			(xy 135.026277 -288.350056) (xy 134.991036 -288.313613) (xy 134.961787 -288.272207) (xy 134.939218 -288.226812)
			(xy 134.923863 -288.178498) (xy 134.916081 -288.128403) (xy 134.915656 -288.103056) (xy 134.916164 -288.077149)
			(xy 134.92427 -288.025972) (xy 134.940282 -287.976693) (xy 134.963805 -287.930526) (xy 134.994261 -287.888607)
			(xy 135.030899 -287.851969) (xy 135.072818 -287.821513) (xy 135.118985 -287.79799) (xy 135.168264 -287.781978)
			(xy 135.219441 -287.773872) (xy 135.271255 -287.773872) (xy 135.322432 -287.781978) (xy 135.371711 -287.79799)
			(xy 135.417878 -287.821513) (xy 135.459797 -287.851969) (xy 135.496435 -287.888607) (xy 135.526891 -287.930526)
			(xy 135.550414 -287.976693) (xy 135.566426 -288.025972) (xy 135.574532 -288.077149) (xy 135.57504 -288.103056)
			(xy 135.574447 -288.130773) (xy 135.56512 -288.185419) (xy 135.556498 -288.211768) (xy 135.548624 -288.233866)
			(xy 135.753856 -288.588958) (xy 135.776716 -288.593276) (xy 135.802927 -288.598792) (xy 135.853237 -288.617168)
			(xy 135.899917 -288.643432) (xy 135.94174 -288.676893) (xy 135.977606 -288.716672) (xy 136.006574 -288.761724)
			(xy 136.017762 -288.786062) (xy 136.03097 -288.816796) (xy 137.448544 -288.816796) (xy 137.473499 -288.817412)
			(xy 137.522448 -288.827156) (xy 137.568557 -288.846263) (xy 137.610052 -288.873996) (xy 137.628122 -288.891218)
			(xy 145.060416 -296.323512) (xy 145.07768 -296.341551) (xy 145.105445 -296.383043) (xy 145.124566 -296.429162)
			(xy 145.134306 -296.478127) (xy 145.134838 -296.50309) (xy 145.134838 -331.043534) (xy 145.501614 -331.41031)
			(xy 148.007578 -331.41031) (xy 148.032531 -331.410929) (xy 148.081477 -331.42068) (xy 148.12758 -331.439791)
			(xy 148.169069 -331.467529) (xy 148.187156 -331.484732) (xy 148.804376 -332.101952) (xy 148.821639 -332.119992)
			(xy 148.849402 -332.161484) (xy 148.868519 -332.207602) (xy 148.878252 -332.256568) (xy 148.878798 -332.28153)
			(xy 148.878798 -340.70417) (xy 149.942296 -341.767668)
		)
		(stroke
			(width 0)
			(type solid)
		)
		(fill yes)
		(layer "In8.Cu")
		(net "PVCCFA_EHV_FIVRA_CPU1")
	)
	(gr_poly
		(pts
			(xy 119.630444 -270.701516) (xy 119.656615 -270.692994) (xy 119.710877 -270.683802) (xy 119.738394 -270.683228)
			(xy 119.765913 -270.683784) (xy 119.82018 -270.69297) (xy 119.846344 -270.701516) (xy 119.854472 -270.70431)
			(xy 120.118378 -270.70431) (xy 120.129885 -270.685341) (xy 120.158395 -270.651352) (xy 120.192374 -270.622831)
			(xy 120.230789 -270.600643) (xy 120.272474 -270.585462) (xy 120.316161 -270.577749) (xy 120.338342 -270.57731)
			(xy 131.942586 -270.57731) (xy 132.146548 -270.373348) (xy 132.1308 -270.340836) (xy 132.120393 -270.318404)
			(xy 132.105696 -270.27119) (xy 132.098257 -270.222304) (xy 132.09778 -270.19758) (xy 132.098261 -270.171793)
			(xy 132.106333 -270.120854) (xy 132.122274 -270.071805) (xy 132.145692 -270.025854) (xy 132.176011 -269.984132)
			(xy 132.212484 -269.947667) (xy 132.254212 -269.917357) (xy 132.300168 -269.893948) (xy 132.34922 -269.878017)
			(xy 132.400161 -269.869956) (xy 132.425948 -269.869412) (xy 132.450671 -269.869885) (xy 132.499552 -269.877346)
			(xy 132.546763 -269.892046) (xy 132.569204 -269.902432) (xy 132.601716 -269.91818) (xy 133.978142 -268.541754)
			(xy 133.980428 -268.524736) (xy 133.984583 -268.498458) (xy 134.000277 -268.447626) (xy 134.023965 -268.399991)
			(xy 134.055026 -268.356801) (xy 134.092647 -268.319187) (xy 134.135843 -268.288134) (xy 134.183482 -268.264455)
			(xy 134.234317 -268.24877) (xy 134.26059 -268.244574) (xy 134.277608 -268.242288) (xy 134.535672 -267.984224)
			(xy 134.510018 -267.949172) (xy 134.495185 -267.927994) (xy 134.471662 -267.881952) (xy 134.455645 -267.832792)
			(xy 134.44753 -267.781729) (xy 134.447026 -267.755878) (xy 134.447533 -267.730091) (xy 134.455604 -267.679153)
			(xy 134.471544 -267.630105) (xy 134.494959 -267.584154) (xy 134.525275 -267.542431) (xy 134.561743 -267.505964)
			(xy 134.603468 -267.475651) (xy 134.64942 -267.452238) (xy 134.698469 -267.4363) (xy 134.749407 -267.428232)
			(xy 134.775194 -267.42771) (xy 134.800185 -267.428199) (xy 134.849584 -267.435813) (xy 134.89726 -267.450821)
			(xy 134.942113 -267.472876) (xy 134.983109 -267.50147) (xy 135.001508 -267.518388) (xy 135.594344 -266.925552)
			(xy 135.612385 -266.908293) (xy 135.653879 -266.880536) (xy 135.699997 -266.861423) (xy 135.748961 -266.851691)
			(xy 135.773922 -266.85113) (xy 135.867648 -266.85113) (xy 135.880348 -266.81938) (xy 135.890516 -266.79542)
			(xy 135.917307 -266.750798) (xy 135.950804 -266.710963) (xy 135.990168 -266.676913) (xy 136.034412 -266.649502)
			(xy 136.082427 -266.629417) (xy 136.13301 -266.617161) (xy 136.184894 -266.613041) (xy 136.236778 -266.617161)
			(xy 136.287361 -266.629417) (xy 136.335376 -266.649502) (xy 136.37962 -266.676913) (xy 136.418984 -266.710963)
			(xy 136.452481 -266.750798) (xy 136.479272 -266.79542) (xy 136.48944 -266.81938) (xy 136.50214 -266.85113)
			(xy 140.399262 -266.85113) (xy 141.383258 -265.867134) (xy 141.383258 -231.246426) (xy 140.70838 -230.571548)
			(xy 135.88238 -230.571548) (xy 135.857421 -230.570975) (xy 135.808462 -230.561231) (xy 135.762346 -230.542121)
			(xy 135.720845 -230.514381) (xy 135.702802 -230.497126) (xy 135.62076 -230.415084) (xy 135.600186 -230.41483)
			(xy 135.574916 -230.41397) (xy 135.525079 -230.405437) (xy 135.477142 -230.389362) (xy 135.432236 -230.366124)
			(xy 135.391427 -230.336274) (xy 135.355679 -230.300518) (xy 135.325837 -230.259701) (xy 135.30261 -230.214791)
			(xy 135.286545 -230.16685) (xy 135.278023 -230.117011) (xy 135.277098 -230.091742) (xy 135.276844 -230.071168)
			(xy 133.92531 -228.719634) (xy 133.903669 -228.73551) (xy 133.856301 -228.760744) (xy 133.805461 -228.777942)
			(xy 133.752501 -228.786645) (xy 133.725666 -228.787198) (xy 133.699879 -228.78669) (xy 133.648941 -228.778618)
			(xy 133.599893 -228.762677) (xy 133.553942 -228.739261) (xy 133.512219 -228.708946) (xy 133.475751 -228.672478)
			(xy 133.445436 -228.630755) (xy 133.422021 -228.584803) (xy 133.406081 -228.535755) (xy 133.39801 -228.484817)
			(xy 133.397498 -228.45903) (xy 133.398008 -228.432191) (xy 133.4067 -228.379223) (xy 133.423905 -228.328378)
			(xy 133.449164 -228.281016) (xy 133.465062 -228.259386) (xy 133.166612 -227.960936) (xy 133.155182 -227.95738)
			(xy 133.130644 -227.94896) (xy 133.084383 -227.925486) (xy 133.042391 -227.895025) (xy 133.005714 -227.858338)
			(xy 132.975266 -227.816338) (xy 132.951804 -227.77007) (xy 132.943346 -227.745544) (xy 132.93979 -227.734114)
			(xy 132.501386 -227.29571) (xy 129.228342 -227.29571) (xy 129.203388 -227.295093) (xy 129.154439 -227.285346)
			(xy 129.108333 -227.266238) (xy 129.066839 -227.238504) (xy 129.048764 -227.221288) (xy 128.984502 -227.157026)
			(xy 128.968754 -227.154232) (xy 128.944235 -227.149382) (xy 128.896932 -227.133247) (xy 128.852622 -227.110127)
			(xy 128.81233 -227.080557) (xy 128.776986 -227.04522) (xy 128.747407 -227.004933) (xy 128.724279 -226.960627)
			(xy 128.708134 -226.913328) (xy 128.703324 -226.888802) (xy 128.70053 -226.873054) (xy 127.448564 -225.621088)
			(xy 127.4346 -225.606553) (xy 127.410999 -225.573881) (xy 127.401574 -225.556064) (xy 127.394213 -225.542764)
			(xy 127.373125 -225.520895) (xy 127.346534 -225.506199) (xy 127.316797 -225.49998) (xy 127.286546 -225.502787)
			(xy 127.272288 -225.508058) (xy 127.252305 -225.515878) (xy 127.210824 -225.526866) (xy 127.168268 -225.532382)
			(xy 127.146812 -225.532696) (xy 127.120917 -225.532189) (xy 127.069763 -225.524093) (xy 127.020504 -225.508098)
			(xy 126.974352 -225.484598) (xy 126.932442 -225.45417) (xy 126.895806 -225.417563) (xy 126.865344 -225.375679)
			(xy 126.841805 -225.329546) (xy 126.82577 -225.2803) (xy 126.817632 -225.229153) (xy 126.81712 -225.203258)
			(xy 126.817711 -225.17554) (xy 126.827035 -225.120894) (xy 126.835662 -225.094546) (xy 126.843536 -225.072448)
			(xy 126.638558 -224.71761) (xy 126.615698 -224.713292) (xy 126.590895 -224.708095) (xy 126.543154 -224.691108)
			(xy 126.498573 -224.667016) (xy 126.458204 -224.636387) (xy 126.422996 -224.599942) (xy 126.393778 -224.55854)
			(xy 126.371239 -224.513155) (xy 126.355909 -224.464855) (xy 126.34815 -224.414779) (xy 126.347728 -224.389442)
			(xy 126.348236 -224.363555) (xy 126.356335 -224.312417) (xy 126.372334 -224.263177) (xy 126.39584 -224.217045)
			(xy 126.426272 -224.175158) (xy 126.462882 -224.138548) (xy 126.504769 -224.108116) (xy 126.550901 -224.08461)
			(xy 126.600141 -224.068611) (xy 126.651279 -224.060512) (xy 126.703053 -224.060512) (xy 126.754191 -224.068611)
			(xy 126.803431 -224.08461) (xy 126.849563 -224.108116) (xy 126.89145 -224.138548) (xy 126.92806 -224.175158)
			(xy 126.958492 -224.217045) (xy 126.981998 -224.263177) (xy 126.997997 -224.312417) (xy 127.006096 -224.363555)
			(xy 127.006604 -224.389442) (xy 127.006079 -224.417151) (xy 126.996888 -224.471799) (xy 126.988316 -224.498154)
			(xy 126.980442 -224.520252) (xy 127.18542 -224.87509) (xy 127.20828 -224.879408) (xy 127.242824 -224.888044)
			(xy 127.255945 -224.891615) (xy 127.283116 -224.892439) (xy 127.309542 -224.886064) (xy 127.333347 -224.87294)
			(xy 127.352845 -224.853999) (xy 127.366653 -224.830584) (xy 127.373792 -224.804354) (xy 127.374142 -224.790762)
			(xy 127.374142 -224.6122) (xy 127.357934 -224.593859) (xy 127.330558 -224.553287) (xy 127.309481 -224.509113)
			(xy 127.295165 -224.462309) (xy 127.287925 -224.413903) (xy 127.287921 -224.364959) (xy 127.295151 -224.316551)
			(xy 127.309458 -224.269745) (xy 127.330528 -224.225567) (xy 127.357896 -224.18499) (xy 127.374142 -224.166684)
			(xy 127.374142 -222.982282) (xy 127.356443 -222.962) (xy 127.327232 -222.916791) (xy 127.305789 -222.867421)
			(xy 127.292692 -222.815213) (xy 127.28829 -222.761567) (xy 127.292703 -222.707923) (xy 127.30581 -222.655718)
			(xy 127.327262 -222.606351) (xy 127.356483 -222.561148) (xy 127.374142 -222.54083) (xy 127.374142 -222.360236)
			(xy 127.373706 -222.346658) (xy 127.366539 -222.320465) (xy 127.352729 -222.297084) (xy 127.333249 -222.278163)
			(xy 127.309475 -222.26504) (xy 127.283084 -222.258639) (xy 127.255939 -222.259414) (xy 127.242824 -222.262954)
			(xy 127.219389 -222.269667) (xy 127.171185 -222.276933) (xy 127.146812 -222.277432) (xy 127.120903 -222.276925)
			(xy 127.069722 -222.268821) (xy 127.020439 -222.252811) (xy 126.974268 -222.229289) (xy 126.932344 -222.198834)
			(xy 126.8957 -222.162196) (xy 126.865238 -222.120277) (xy 126.841709 -222.074109) (xy 126.825691 -222.024828)
			(xy 126.817579 -221.973649) (xy 126.81712 -221.94774) (xy 126.817582 -221.922391) (xy 126.82534 -221.87229)
			(xy 126.840678 -221.823968) (xy 126.863235 -221.778565) (xy 126.892479 -221.737152) (xy 126.927719 -221.700705)
			(xy 126.968126 -221.670085) (xy 127.012745 -221.646013) (xy 127.060523 -221.629058) (xy 127.085344 -221.62389)
			(xy 127.108204 -221.619572) (xy 127.313436 -221.264226) (xy 127.305562 -221.242128) (xy 127.297099 -221.215884)
			(xy 127.288034 -221.161495) (xy 127.287528 -221.133924) (xy 127.287972 -221.109454) (xy 127.295201 -221.061052)
			(xy 127.309504 -221.014249) (xy 127.330567 -220.970074) (xy 127.357927 -220.929497) (xy 127.374142 -220.911166)
			(xy 127.374142 -219.726764) (xy 127.356437 -219.706482) (xy 127.327212 -219.661271) (xy 127.305757 -219.611896)
			(xy 127.292647 -219.559682) (xy 127.288235 -219.506028) (xy 127.292638 -219.452374) (xy 127.305739 -219.400157)
			(xy 127.327185 -219.350779) (xy 127.356402 -219.305563) (xy 127.374142 -219.285312) (xy 127.374142 -219.104718)
			(xy 127.373704 -219.091142) (xy 127.366534 -219.064953) (xy 127.352723 -219.041576) (xy 127.333244 -219.022659)
			(xy 127.309472 -219.009539) (xy 127.283084 -219.003139) (xy 127.255943 -219.003913) (xy 127.242824 -219.007436)
			(xy 127.219382 -219.014095) (xy 127.171178 -219.021231) (xy 127.146812 -219.02166) (xy 127.120918 -219.021153)
			(xy 127.069766 -219.013057) (xy 127.020509 -218.997062) (xy 126.97436 -218.973561) (xy 126.932453 -218.943132)
			(xy 126.89582 -218.906525) (xy 126.865362 -218.86464) (xy 126.841828 -218.818507) (xy 126.825798 -218.769262)
			(xy 126.817665 -218.718116) (xy 126.81712 -218.692222) (xy 126.817584 -218.666874) (xy 126.825343 -218.616775)
			(xy 126.840683 -218.568455) (xy 126.863241 -218.523054) (xy 126.892486 -218.481643) (xy 126.927726 -218.445199)
			(xy 126.968132 -218.414581) (xy 127.01275 -218.390511) (xy 127.060527 -218.373557) (xy 127.085344 -218.368372)
			(xy 127.108204 -218.364054) (xy 127.313436 -218.008708) (xy 127.305562 -217.98661) (xy 127.2971 -217.960365)
			(xy 127.288038 -217.905976) (xy 127.287528 -217.878406) (xy 127.287973 -217.853937) (xy 127.295204 -217.805535)
			(xy 127.30951 -217.758734) (xy 127.330574 -217.714561) (xy 127.357936 -217.673986) (xy 127.374142 -217.655648)
			(xy 127.374142 -216.471246) (xy 127.356438 -216.450964) (xy 127.327216 -216.405753) (xy 127.305764 -216.356379)
			(xy 127.292657 -216.304167) (xy 127.288247 -216.250515) (xy 127.292652 -216.196863) (xy 127.305754 -216.144649)
			(xy 127.327202 -216.095273) (xy 127.35642 -216.050059) (xy 127.374142 -216.029794) (xy 127.374142 -215.8492)
			(xy 127.373702 -215.835626) (xy 127.366529 -215.809441) (xy 127.352717 -215.786068) (xy 127.333239 -215.767156)
			(xy 127.309469 -215.754038) (xy 127.283084 -215.747639) (xy 127.255946 -215.748412) (xy 127.242824 -215.751918)
			(xy 127.219389 -215.758632) (xy 127.171185 -215.765898) (xy 127.146812 -215.766396) (xy 127.120902 -215.765915)
			(xy 127.069719 -215.757811) (xy 127.020435 -215.741799) (xy 126.974262 -215.718274) (xy 126.932338 -215.687816)
			(xy 126.895694 -215.651175) (xy 126.865234 -215.609252) (xy 126.841707 -215.56308) (xy 126.825693 -215.513796)
			(xy 126.817586 -215.462614) (xy 126.81712 -215.436704) (xy 126.817585 -215.411357) (xy 126.825347 -215.36126)
			(xy 126.840688 -215.312942) (xy 126.863248 -215.267544) (xy 126.892492 -215.226135) (xy 126.927733 -215.189693)
			(xy 126.968138 -215.159077) (xy 127.012755 -215.135008) (xy 127.060531 -215.118056) (xy 127.085344 -215.112854)
			(xy 127.108204 -215.108536) (xy 127.313182 -214.753444) (xy 127.305308 -214.7316) (xy 127.296731 -214.705181)
			(xy 127.287541 -214.650406) (xy 127.28702 -214.622634) (xy 127.287525 -214.596744) (xy 127.29562 -214.5456)
			(xy 127.311616 -214.496352) (xy 127.335118 -214.450212) (xy 127.36555 -214.408318) (xy 127.40216 -214.371699)
			(xy 127.444047 -214.341258) (xy 127.490181 -214.317745) (xy 127.539426 -214.301738) (xy 127.590568 -214.293631)
			(xy 127.616458 -214.293196) (xy 127.640666 -214.293627) (xy 127.68856 -214.300718) (xy 127.734901 -214.31474)
			(xy 127.778693 -214.33539) (xy 127.818992 -214.362224) (xy 127.854933 -214.394665) (xy 127.885741 -214.432014)
			(xy 127.910753 -214.473469) (xy 127.920496 -214.495634) (xy 127.926655 -214.509067) (xy 127.945367 -214.531924)
			(xy 127.969832 -214.548477) (xy 127.998009 -214.557346) (xy 128.027545 -214.557791) (xy 128.041908 -214.554308)
			(xy 128.058776 -214.549913) (xy 128.093313 -214.5452) (xy 128.110742 -214.54491) (xy 128.233932 -214.54491)
			(xy 128.246124 -214.511382) (xy 128.255014 -214.488776) (xy 128.26492 -214.466424) (xy 128.051306 -214.061294)
			(xy 128.027176 -214.056722) (xy 128.002255 -214.051631) (xy 127.954254 -214.034807) (xy 127.909406 -214.010813)
			(xy 127.868773 -213.980218) (xy 127.833318 -213.943748) (xy 127.803882 -213.902268) (xy 127.781163 -213.856761)
			(xy 127.765699 -213.808305) (xy 127.757858 -213.758049) (xy 127.757428 -213.732618) (xy 127.757936 -213.706731)
			(xy 127.766035 -213.655593) (xy 127.782034 -213.606353) (xy 127.80554 -213.560221) (xy 127.835972 -213.518334)
			(xy 127.872582 -213.481724) (xy 127.914469 -213.451292) (xy 127.960601 -213.427786) (xy 128.009841 -213.411787)
			(xy 128.060979 -213.403688) (xy 128.112753 -213.403688) (xy 128.163891 -213.411787) (xy 128.213131 -213.427786)
			(xy 128.259263 -213.451292) (xy 128.30115 -213.481724) (xy 128.33776 -213.518334) (xy 128.368192 -213.560221)
			(xy 128.391698 -213.606353) (xy 128.407697 -213.655593) (xy 128.415796 -213.706731) (xy 128.416304 -213.732618)
			(xy 128.415939 -213.755594) (xy 128.409621 -213.801108) (xy 128.39704 -213.845303) (xy 128.38811 -213.866476)
			(xy 128.378204 -213.888828) (xy 128.591818 -214.293958) (xy 128.615948 -214.29853) (xy 128.640053 -214.303426)
			(xy 128.686567 -214.319417) (xy 128.730185 -214.342149) (xy 128.769936 -214.371115) (xy 128.804937 -214.405672)
			(xy 128.834409 -214.44505) (xy 128.857695 -214.488374) (xy 128.866392 -214.511382) (xy 128.878584 -214.54491)
			(xy 129.173732 -214.54491) (xy 129.185924 -214.511382) (xy 129.194888 -214.487752) (xy 129.219016 -214.443346)
			(xy 129.249642 -214.403145) (xy 129.286046 -214.368092) (xy 129.327377 -214.339009) (xy 129.372664 -214.316578)
			(xy 129.420844 -214.301325) (xy 129.470789 -214.293608) (xy 129.521327 -214.293608) (xy 129.571272 -214.301325)
			(xy 129.619452 -214.316578) (xy 129.664739 -214.339009) (xy 129.70607 -214.368092) (xy 129.742474 -214.403145)
			(xy 129.7731 -214.443346) (xy 129.797228 -214.487752) (xy 129.806192 -214.511382) (xy 129.818384 -214.54491)
			(xy 130.113532 -214.54491) (xy 130.125724 -214.511382) (xy 130.134614 -214.488776) (xy 130.14452 -214.466424)
			(xy 129.930906 -214.061294) (xy 129.906776 -214.056722) (xy 129.881855 -214.051631) (xy 129.833854 -214.034807)
			(xy 129.789006 -214.010813) (xy 129.748373 -213.980218) (xy 129.712918 -213.943748) (xy 129.683482 -213.902268)
			(xy 129.660763 -213.856761) (xy 129.645299 -213.808305) (xy 129.637458 -213.758049) (xy 129.637028 -213.732618)
			(xy 129.637536 -213.706731) (xy 129.645635 -213.655593) (xy 129.661634 -213.606353) (xy 129.68514 -213.560221)
			(xy 129.715572 -213.518334) (xy 129.752182 -213.481724) (xy 129.794069 -213.451292) (xy 129.840201 -213.427786)
			(xy 129.889441 -213.411787) (xy 129.940579 -213.403688) (xy 129.992353 -213.403688) (xy 130.043491 -213.411787)
			(xy 130.092731 -213.427786) (xy 130.138863 -213.451292) (xy 130.18075 -213.481724) (xy 130.21736 -213.518334)
			(xy 130.247792 -213.560221) (xy 130.271298 -213.606353) (xy 130.287297 -213.655593) (xy 130.295396 -213.706731)
			(xy 130.295904 -213.732618) (xy 130.295539 -213.755594) (xy 130.289221 -213.801108) (xy 130.27664 -213.845303)
			(xy 130.26771 -213.866476) (xy 130.257804 -213.888828) (xy 130.471418 -214.293958) (xy 130.495548 -214.29853)
			(xy 130.519653 -214.303426) (xy 130.566167 -214.319417) (xy 130.609785 -214.342149) (xy 130.649536 -214.371115)
			(xy 130.684537 -214.405672) (xy 130.714009 -214.44505) (xy 130.737295 -214.488374) (xy 130.745992 -214.511382)
			(xy 130.758184 -214.54491) (xy 131.053332 -214.54491) (xy 131.065524 -214.511382) (xy 131.074488 -214.487752)
			(xy 131.098616 -214.443346) (xy 131.129242 -214.403145) (xy 131.165646 -214.368092) (xy 131.206977 -214.339009)
			(xy 131.252264 -214.316578) (xy 131.300444 -214.301325) (xy 131.350389 -214.293608) (xy 131.400927 -214.293608)
			(xy 131.450872 -214.301325) (xy 131.499052 -214.316578) (xy 131.544339 -214.339009) (xy 131.58567 -214.368092)
			(xy 131.622074 -214.403145) (xy 131.6527 -214.443346) (xy 131.676828 -214.487752) (xy 131.685792 -214.511382)
			(xy 131.697984 -214.54491) (xy 131.993132 -214.54491) (xy 132.005324 -214.511382) (xy 132.014214 -214.488776)
			(xy 132.02412 -214.466424) (xy 131.810506 -214.061294) (xy 131.786376 -214.056722) (xy 131.761455 -214.051631)
			(xy 131.713454 -214.034807) (xy 131.668606 -214.010813) (xy 131.627973 -213.980218) (xy 131.592518 -213.943748)
			(xy 131.563082 -213.902268) (xy 131.540363 -213.856761) (xy 131.524899 -213.808305) (xy 131.517058 -213.758049)
			(xy 131.516628 -213.732618) (xy 131.517136 -213.706731) (xy 131.525235 -213.655593) (xy 131.541234 -213.606353)
			(xy 131.56474 -213.560221) (xy 131.595172 -213.518334) (xy 131.631782 -213.481724) (xy 131.673669 -213.451292)
			(xy 131.719801 -213.427786) (xy 131.769041 -213.411787) (xy 131.820179 -213.403688) (xy 131.871953 -213.403688)
			(xy 131.923091 -213.411787) (xy 131.972331 -213.427786) (xy 132.018463 -213.451292) (xy 132.06035 -213.481724)
			(xy 132.09696 -213.518334) (xy 132.127392 -213.560221) (xy 132.150898 -213.606353) (xy 132.166897 -213.655593)
			(xy 132.174996 -213.706731) (xy 132.175504 -213.732618) (xy 132.175139 -213.755594) (xy 132.168821 -213.801108)
			(xy 132.15624 -213.845303) (xy 132.14731 -213.866476) (xy 132.137404 -213.888828) (xy 132.351018 -214.293958)
			(xy 132.375148 -214.29853) (xy 132.399253 -214.303426) (xy 132.445767 -214.319417) (xy 132.489385 -214.342149)
			(xy 132.529136 -214.371115) (xy 132.564137 -214.405672) (xy 132.593609 -214.44505) (xy 132.616895 -214.488374)
			(xy 132.625592 -214.511382) (xy 132.637784 -214.54491) (xy 132.932932 -214.54491) (xy 132.945124 -214.511382)
			(xy 132.954088 -214.487752) (xy 132.978216 -214.443346) (xy 133.008842 -214.403145) (xy 133.045246 -214.368092)
			(xy 133.086577 -214.339009) (xy 133.131864 -214.316578) (xy 133.180044 -214.301325) (xy 133.229989 -214.293608)
			(xy 133.280527 -214.293608) (xy 133.330472 -214.301325) (xy 133.378652 -214.316578) (xy 133.423939 -214.339009)
			(xy 133.46527 -214.368092) (xy 133.501674 -214.403145) (xy 133.5323 -214.443346) (xy 133.556428 -214.487752)
			(xy 133.565392 -214.511382) (xy 133.577584 -214.54491) (xy 133.86435 -214.54491) (xy 133.870446 -214.501222)
			(xy 133.874548 -214.475401) (xy 133.889866 -214.425415) (xy 133.912914 -214.378489) (xy 133.943108 -214.335809)
			(xy 133.979685 -214.298455) (xy 134.021721 -214.267371) (xy 134.068153 -214.243343) (xy 134.117806 -214.226979)
			(xy 134.169426 -214.218692) (xy 134.221706 -214.218692) (xy 134.273326 -214.226979) (xy 134.322979 -214.243343)
			(xy 134.369411 -214.267371) (xy 134.411447 -214.298455) (xy 134.448024 -214.335809) (xy 134.478218 -214.378489)
			(xy 134.501266 -214.425415) (xy 134.516584 -214.475401) (xy 134.520686 -214.501222) (xy 134.526782 -214.54491)
			(xy 134.802626 -214.54491) (xy 134.808722 -214.501222) (xy 134.812828 -214.47529) (xy 134.828187 -214.425087)
			(xy 134.851312 -214.377954) (xy 134.881618 -214.335084) (xy 134.918338 -214.297562) (xy 134.960543 -214.266337)
			(xy 135.007166 -214.2422) (xy 135.057026 -214.225761) (xy 135.108862 -214.217436) (xy 135.161362 -214.217436)
			(xy 135.213198 -214.225761) (xy 135.263058 -214.2422) (xy 135.309681 -214.266337) (xy 135.351886 -214.297562)
			(xy 135.388606 -214.335084) (xy 135.418912 -214.377954) (xy 135.442037 -214.425087) (xy 135.457396 -214.47529)
			(xy 135.461502 -214.501222) (xy 135.467598 -214.54491) (xy 135.74395 -214.54491) (xy 135.750046 -214.501222)
			(xy 135.754148 -214.475401) (xy 135.769466 -214.425415) (xy 135.792514 -214.378489) (xy 135.822708 -214.335809)
			(xy 135.859285 -214.298455) (xy 135.901321 -214.267371) (xy 135.947753 -214.243343) (xy 135.997406 -214.226979)
			(xy 136.049026 -214.218692) (xy 136.101306 -214.218692) (xy 136.152926 -214.226979) (xy 136.202579 -214.243343)
			(xy 136.249011 -214.267371) (xy 136.291047 -214.298455) (xy 136.327624 -214.335809) (xy 136.357818 -214.378489)
			(xy 136.380866 -214.425415) (xy 136.396184 -214.475401) (xy 136.400286 -214.501222) (xy 136.406382 -214.54491)
			(xy 150.941278 -214.54491) (xy 150.94585 -214.544148) (xy 150.957301 -214.542136) (xy 150.980452 -214.539974)
			(xy 150.992078 -214.53983) (xy 151.246078 -214.53983) (xy 151.257703 -214.539987) (xy 151.280853 -214.542147)
			(xy 151.292306 -214.544148) (xy 151.296878 -214.54491) (xy 151.449278 -214.54491) (xy 151.45385 -214.544148)
			(xy 151.465301 -214.542136) (xy 151.488452 -214.539974) (xy 151.500078 -214.53983) (xy 153.741882 -214.53983)
			(xy 154.144218 -214.137494) (xy 154.144218 -196.352922) (xy 152.499822 -194.708526) (xy 152.482561 -194.690486)
			(xy 152.454802 -194.648993) (xy 152.435689 -194.602874) (xy 152.42596 -194.553909) (xy 152.4254 -194.528948)
			(xy 152.4254 -193.135504) (xy 98.043746 -138.75385) (xy 64.694816 -138.75385) (xy 64.677036 -138.773408)
			(xy 64.665352 -138.785092) (xy 64.647312 -138.802354) (xy 64.60582 -138.830116) (xy 64.559701 -138.849233)
			(xy 64.510736 -138.858966) (xy 64.485774 -138.859514) (xy 64.461692 -138.858949) (xy 64.41439 -138.84988)
			(xy 64.36964 -138.832073) (xy 64.32904 -138.806161) (xy 64.294042 -138.773073) (xy 64.279526 -138.75385)
			(xy 61.927994 -138.75385) (xy 61.39434 -139.287504) (xy 61.39434 -144.56918) (xy 61.418119 -144.582628)
			(xy 61.461913 -144.615281) (xy 61.500604 -144.653845) (xy 61.533399 -144.697533) (xy 61.55963 -144.745451)
			(xy 61.57876 -144.79662) (xy 61.590398 -144.849993) (xy 61.594305 -144.904481) (xy 61.590403 -144.958969)
			(xy 61.578771 -145.012344) (xy 61.559646 -145.063514) (xy 61.53342 -145.111435) (xy 61.500629 -145.155126)
			(xy 61.461942 -145.193694) (xy 61.418151 -145.226352) (xy 61.39434 -145.23974) (xy 61.39434 -150.5966)
			(xy 61.419803 -150.611035) (xy 61.466366 -150.646496) (xy 61.506966 -150.688655) (xy 61.54065 -150.73652)
			(xy 61.566626 -150.788969) (xy 61.584286 -150.844771) (xy 61.593215 -150.902615) (xy 61.59373 -150.93188)
			(xy 61.59321 -150.960619) (xy 61.584589 -151.017447) (xy 61.567538 -151.072338) (xy 61.542445 -151.12405)
			(xy 61.509877 -151.171411) (xy 61.490606 -151.192738) (xy 61.480533 -151.204273) (xy 61.467188 -151.231821)
			(xy 61.4626 -151.262085) (xy 61.46718 -151.292351) (xy 61.480517 -151.319903) (xy 61.490606 -151.331422)
			(xy 61.509877 -151.352749) (xy 61.542442 -151.400112) (xy 61.567534 -151.451823) (xy 61.584586 -151.506714)
			(xy 61.59321 -151.563541) (xy 61.59373 -151.59228) (xy 61.593192 -151.621541) (xy 61.584246 -151.679374)
			(xy 61.566576 -151.735164) (xy 61.540597 -151.787602) (xy 61.506916 -151.83546) (xy 61.466325 -151.877616)
			(xy 61.419773 -151.91308) (xy 61.39434 -151.92756) (xy 61.39434 -153.20518) (xy 61.418119 -153.218628)
			(xy 61.461913 -153.251281) (xy 61.500604 -153.289845) (xy 61.533399 -153.333533) (xy 61.55963 -153.381451)
			(xy 61.57876 -153.43262) (xy 61.590398 -153.485993) (xy 61.594305 -153.540481) (xy 61.590403 -153.594969)
			(xy 61.578771 -153.648344) (xy 61.559646 -153.699514) (xy 61.53342 -153.747435) (xy 61.500629 -153.791126)
			(xy 61.461942 -153.829694) (xy 61.418151 -153.862352) (xy 61.39434 -153.87574) (xy 61.39434 -159.2326)
			(xy 61.419803 -159.247035) (xy 61.466366 -159.282496) (xy 61.506966 -159.324655) (xy 61.54065 -159.37252)
			(xy 61.566626 -159.424969) (xy 61.584286 -159.480771) (xy 61.593215 -159.538615) (xy 61.59373 -159.56788)
			(xy 61.59321 -159.596619) (xy 61.584589 -159.653447) (xy 61.567538 -159.708338) (xy 61.542445 -159.76005)
			(xy 61.509877 -159.807411) (xy 61.490606 -159.828738) (xy 61.480533 -159.840273) (xy 61.467188 -159.867821)
			(xy 61.4626 -159.898085) (xy 61.46718 -159.928351) (xy 61.480517 -159.955903) (xy 61.490606 -159.967422)
			(xy 61.509877 -159.988749) (xy 61.542442 -160.036112) (xy 61.567534 -160.087823) (xy 61.584586 -160.142714)
			(xy 61.59321 -160.199541) (xy 61.59373 -160.22828) (xy 61.59324 -160.255522) (xy 61.585481 -160.309452)
			(xy 61.570134 -160.361731) (xy 61.547508 -160.411297) (xy 61.518065 -160.457141) (xy 61.482403 -160.498334)
			(xy 61.462158 -160.51657) (xy 61.45196 -160.526056) (xy 61.436646 -160.549307) (xy 61.428172 -160.575826)
			(xy 61.427165 -160.603648) (xy 61.4337 -160.63071) (xy 61.447293 -160.655006) (xy 61.456824 -160.66516)
			(xy 62.005972 -161.214308) (xy 70.633844 -161.214308) (xy 71.788782 -160.05937) (xy 71.806824 -160.042113)
			(xy 71.848318 -160.01436) (xy 71.894437 -159.995253) (xy 71.9434 -159.985527) (xy 71.96836 -159.984948)
			(xy 72.485504 -159.984948) (xy 72.502195 -159.963249) (xy 72.540767 -159.924404) (xy 72.584497 -159.891472)
			(xy 72.632485 -159.865129) (xy 72.683745 -159.845916) (xy 72.737226 -159.834229) (xy 72.791828 -159.830306)
			(xy 72.84643 -159.834229) (xy 72.899911 -159.845916) (xy 72.951171 -159.865129) (xy 72.999159 -159.891472)
			(xy 73.042889 -159.924404) (xy 73.081461 -159.963249) (xy 73.098152 -159.984948) (xy 74.975974 -159.984948)
			(xy 74.992571 -159.96242) (xy 75.031284 -159.92202) (xy 75.075485 -159.887711) (xy 75.124227 -159.860231)
			(xy 75.176461 -159.840169) (xy 75.231066 -159.827957) (xy 75.28687 -159.823857) (xy 75.342674 -159.827957)
			(xy 75.397279 -159.840169) (xy 75.449513 -159.860231) (xy 75.498255 -159.887711) (xy 75.542456 -159.92202)
			(xy 75.581169 -159.96242) (xy 75.597766 -159.984948) (xy 80.00365 -159.984948) (xy 80.028608 -159.985524)
			(xy 80.077563 -159.995273) (xy 80.123676 -160.014386) (xy 80.165173 -160.042129) (xy 80.183228 -160.05937)
			(xy 115.53952 -195.415662) (xy 115.55678 -195.433703) (xy 115.584536 -195.475196) (xy 115.603648 -195.521315)
			(xy 115.613378 -195.570279) (xy 115.613942 -195.59524) (xy 115.613942 -206.024988) (xy 132.710692 -206.024988)
			(xy 132.714673 -205.891968) (xy 132.726602 -205.759423) (xy 132.746437 -205.62783) (xy 132.774106 -205.497658)
			(xy 132.80951 -205.369373) (xy 132.852523 -205.243436) (xy 132.90299 -205.120297) (xy 132.960731 -205.000396)
			(xy 133.02554 -204.884163) (xy 133.097184 -204.772013) (xy 133.175406 -204.664349) (xy 133.259927 -204.561556)
			(xy 133.350445 -204.464001) (xy 133.446634 -204.372035) (xy 133.548152 -204.285985) (xy 133.654633 -204.206161)
			(xy 133.765698 -204.132848) (xy 133.880949 -204.066308) (xy 133.999973 -204.006779) (xy 134.122344 -203.954475)
			(xy 134.247623 -203.909583) (xy 134.375364 -203.872264) (xy 134.505107 -203.842651) (xy 134.636389 -203.82085)
			(xy 134.76874 -203.80694) (xy 134.901686 -203.800969) (xy 135.034751 -203.80296) (xy 135.167459 -203.812905)
			(xy 135.299335 -203.830769) (xy 135.429906 -203.856487) (xy 135.558706 -203.889968) (xy 135.685272 -203.931092)
			(xy 135.809153 -203.979712) (xy 135.929904 -204.035653) (xy 136.047094 -204.098715) (xy 136.160303 -204.168673)
			(xy 136.269125 -204.245277) (xy 136.373171 -204.328251) (xy 136.472069 -204.417299) (xy 136.565464 -204.512102)
			(xy 136.653022 -204.61232) (xy 136.734431 -204.717596) (xy 136.809397 -204.827552) (xy 136.877654 -204.941794)
			(xy 136.938956 -205.059914) (xy 136.993085 -205.181489) (xy 137.039846 -205.306083) (xy 137.079072 -205.433251)
			(xy 137.110622 -205.562537) (xy 137.134385 -205.693478) (xy 137.150274 -205.825606) (xy 137.158232 -205.958448)
			(xy 137.15873 -206.024988) (xy 137.158232 -206.091528) (xy 137.150274 -206.22437) (xy 137.134385 -206.356498)
			(xy 137.110622 -206.487439) (xy 137.079072 -206.616725) (xy 137.039846 -206.743893) (xy 136.993085 -206.868487)
			(xy 136.938956 -206.990062) (xy 136.877654 -207.108182) (xy 136.809397 -207.222424) (xy 136.734431 -207.33238)
			(xy 136.653022 -207.437656) (xy 136.565464 -207.537874) (xy 136.472069 -207.632677) (xy 136.373171 -207.721725)
			(xy 136.269125 -207.804699) (xy 136.160303 -207.881303) (xy 136.047094 -207.951261) (xy 135.929904 -208.014323)
			(xy 135.809153 -208.070264) (xy 135.685272 -208.118884) (xy 135.558706 -208.160008) (xy 135.429906 -208.193489)
			(xy 135.299335 -208.219207) (xy 135.167459 -208.237071) (xy 135.034751 -208.247016) (xy 134.901686 -208.249007)
			(xy 134.76874 -208.243036) (xy 134.636389 -208.229126) (xy 134.505107 -208.207325) (xy 134.375364 -208.177712)
			(xy 134.247623 -208.140393) (xy 134.122344 -208.095501) (xy 133.999973 -208.043197) (xy 133.880949 -207.983668)
			(xy 133.765698 -207.917128) (xy 133.654633 -207.843815) (xy 133.548152 -207.763991) (xy 133.446634 -207.677941)
			(xy 133.350445 -207.585975) (xy 133.259927 -207.48842) (xy 133.175406 -207.385627) (xy 133.097184 -207.277963)
			(xy 133.02554 -207.165813) (xy 132.960731 -207.04958) (xy 132.90299 -206.929679) (xy 132.852523 -206.80654)
			(xy 132.80951 -206.680603) (xy 132.774106 -206.552318) (xy 132.746437 -206.422146) (xy 132.726602 -206.290553)
			(xy 132.714673 -206.158008) (xy 132.710692 -206.024988) (xy 115.613942 -206.024988) (xy 115.613942 -213.732618)
			(xy 116.479828 -213.732618) (xy 116.480336 -213.706731) (xy 116.488435 -213.655593) (xy 116.504434 -213.606353)
			(xy 116.52794 -213.560221) (xy 116.558372 -213.518334) (xy 116.594982 -213.481724) (xy 116.636869 -213.451292)
			(xy 116.683001 -213.427786) (xy 116.732241 -213.411787) (xy 116.783379 -213.403688) (xy 116.835153 -213.403688)
			(xy 116.886291 -213.411787) (xy 116.935531 -213.427786) (xy 116.981663 -213.451292) (xy 117.02355 -213.481724)
			(xy 117.06016 -213.518334) (xy 117.090592 -213.560221) (xy 117.114098 -213.606353) (xy 117.130097 -213.655593)
			(xy 117.138196 -213.706731) (xy 117.138704 -213.732618) (xy 118.359428 -213.732618) (xy 118.359936 -213.706731)
			(xy 118.368035 -213.655593) (xy 118.384034 -213.606353) (xy 118.40754 -213.560221) (xy 118.437972 -213.518334)
			(xy 118.474582 -213.481724) (xy 118.516469 -213.451292) (xy 118.562601 -213.427786) (xy 118.611841 -213.411787)
			(xy 118.662979 -213.403688) (xy 118.714753 -213.403688) (xy 118.765891 -213.411787) (xy 118.815131 -213.427786)
			(xy 118.861263 -213.451292) (xy 118.90315 -213.481724) (xy 118.93976 -213.518334) (xy 118.970192 -213.560221)
			(xy 118.993698 -213.606353) (xy 119.009697 -213.655593) (xy 119.017796 -213.706731) (xy 119.018304 -213.732618)
			(xy 120.239028 -213.732618) (xy 120.239536 -213.706731) (xy 120.247635 -213.655593) (xy 120.263634 -213.606353)
			(xy 120.28714 -213.560221) (xy 120.317572 -213.518334) (xy 120.354182 -213.481724) (xy 120.396069 -213.451292)
			(xy 120.442201 -213.427786) (xy 120.491441 -213.411787) (xy 120.542579 -213.403688) (xy 120.594353 -213.403688)
			(xy 120.645491 -213.411787) (xy 120.694731 -213.427786) (xy 120.740863 -213.451292) (xy 120.78275 -213.481724)
			(xy 120.81936 -213.518334) (xy 120.849792 -213.560221) (xy 120.873298 -213.606353) (xy 120.889297 -213.655593)
			(xy 120.897396 -213.706731) (xy 120.897904 -213.732618) (xy 122.118628 -213.732618) (xy 122.119136 -213.706731)
			(xy 122.127235 -213.655593) (xy 122.143234 -213.606353) (xy 122.16674 -213.560221) (xy 122.197172 -213.518334)
			(xy 122.233782 -213.481724) (xy 122.275669 -213.451292) (xy 122.321801 -213.427786) (xy 122.371041 -213.411787)
			(xy 122.422179 -213.403688) (xy 122.473953 -213.403688) (xy 122.525091 -213.411787) (xy 122.574331 -213.427786)
			(xy 122.620463 -213.451292) (xy 122.66235 -213.481724) (xy 122.69896 -213.518334) (xy 122.729392 -213.560221)
			(xy 122.752898 -213.606353) (xy 122.768897 -213.655593) (xy 122.776996 -213.706731) (xy 122.777504 -213.732618)
			(xy 123.99772 -213.732618) (xy 123.998228 -213.706711) (xy 124.006334 -213.655534) (xy 124.022346 -213.606255)
			(xy 124.045869 -213.560088) (xy 124.076325 -213.518169) (xy 124.112963 -213.481531) (xy 124.154882 -213.451075)
			(xy 124.201049 -213.427552) (xy 124.250328 -213.41154) (xy 124.301505 -213.403434) (xy 124.353319 -213.403434)
			(xy 124.404496 -213.41154) (xy 124.453775 -213.427552) (xy 124.499942 -213.451075) (xy 124.541861 -213.481531)
			(xy 124.578499 -213.518169) (xy 124.608955 -213.560088) (xy 124.632478 -213.606255) (xy 124.64849 -213.655534)
			(xy 124.656596 -213.706711) (xy 124.657104 -213.732618) (xy 125.87732 -213.732618) (xy 125.877828 -213.706711)
			(xy 125.885934 -213.655534) (xy 125.901946 -213.606255) (xy 125.925469 -213.560088) (xy 125.955925 -213.518169)
			(xy 125.992563 -213.481531) (xy 126.034482 -213.451075) (xy 126.080649 -213.427552) (xy 126.129928 -213.41154)
			(xy 126.181105 -213.403434) (xy 126.232919 -213.403434) (xy 126.284096 -213.41154) (xy 126.333375 -213.427552)
			(xy 126.379542 -213.451075) (xy 126.421461 -213.481531) (xy 126.458099 -213.518169) (xy 126.488555 -213.560088)
			(xy 126.512078 -213.606255) (xy 126.52809 -213.655534) (xy 126.536196 -213.706711) (xy 126.536704 -213.732618)
			(xy 126.536283 -213.755559) (xy 126.529855 -213.80099) (xy 126.517209 -213.845096) (xy 126.508256 -213.866222)
			(xy 126.49835 -213.888574) (xy 126.712218 -214.293958) (xy 126.736348 -214.29853) (xy 126.761267 -214.303641)
			(xy 126.809277 -214.320441) (xy 126.854136 -214.344419) (xy 126.894776 -214.375006) (xy 126.930234 -214.411476)
			(xy 126.959666 -214.452961) (xy 126.982373 -214.498476) (xy 126.997815 -214.54694) (xy 127.005627 -214.597201)
			(xy 127.006096 -214.622634) (xy 127.005588 -214.648521) (xy 126.997489 -214.699659) (xy 126.98149 -214.748899)
			(xy 126.957984 -214.795031) (xy 126.927552 -214.836918) (xy 126.890942 -214.873528) (xy 126.849055 -214.90396)
			(xy 126.802923 -214.927466) (xy 126.753683 -214.943465) (xy 126.702545 -214.951564) (xy 126.650771 -214.951564)
			(xy 126.599633 -214.943465) (xy 126.550393 -214.927466) (xy 126.504261 -214.90396) (xy 126.462374 -214.873528)
			(xy 126.425764 -214.836918) (xy 126.395332 -214.795031) (xy 126.371826 -214.748899) (xy 126.355827 -214.699659)
			(xy 126.347728 -214.648521) (xy 126.34722 -214.622634) (xy 126.347587 -214.599658) (xy 126.3539 -214.554143)
			(xy 126.366479 -214.509947) (xy 126.375414 -214.488776) (xy 126.38532 -214.466424) (xy 126.171706 -214.061294)
			(xy 126.147576 -214.056722) (xy 126.12262 -214.051672) (xy 126.074538 -214.034924) (xy 126.029605 -214.010979)
			(xy 125.98889 -213.980407) (xy 125.953363 -213.943936) (xy 125.92387 -213.902434) (xy 125.901111 -213.856888)
			(xy 125.88563 -213.808384) (xy 125.877795 -213.758075) (xy 125.87732 -213.732618) (xy 124.657104 -213.732618)
			(xy 124.656681 -213.756953) (xy 124.649527 -213.805095) (xy 124.635379 -213.851663) (xy 124.625354 -213.873842)
			(xy 124.614432 -213.896448) (xy 124.820172 -214.292942) (xy 124.845826 -214.296752) (xy 124.87151 -214.301109)
			(xy 124.921167 -214.316849) (xy 124.967731 -214.340204) (xy 125.010041 -214.370592) (xy 125.047044 -214.407258)
			(xy 125.077819 -214.449288) (xy 125.101599 -214.495635) (xy 125.117793 -214.545146) (xy 125.125998 -214.596588)
			(xy 125.126496 -214.622634) (xy 125.125988 -214.648521) (xy 125.117889 -214.699659) (xy 125.10189 -214.748899)
			(xy 125.078384 -214.795031) (xy 125.047952 -214.836918) (xy 125.011342 -214.873528) (xy 124.969455 -214.90396)
			(xy 124.923323 -214.927466) (xy 124.874083 -214.943465) (xy 124.822945 -214.951564) (xy 124.771171 -214.951564)
			(xy 124.720033 -214.943465) (xy 124.670793 -214.927466) (xy 124.624661 -214.90396) (xy 124.582774 -214.873528)
			(xy 124.546164 -214.836918) (xy 124.515732 -214.795031) (xy 124.492226 -214.748899) (xy 124.476227 -214.699659)
			(xy 124.468128 -214.648521) (xy 124.46762 -214.622634) (xy 124.468099 -214.597068) (xy 124.476002 -214.546552)
			(xy 124.491623 -214.497866) (xy 124.502672 -214.474806) (xy 124.514102 -214.451438) (xy 124.31268 -214.062818)
			(xy 124.28601 -214.059516) (xy 124.259814 -214.055663) (xy 124.20902 -214.04073) (xy 124.161267 -214.017866)
			(xy 124.117785 -213.987661) (xy 124.079693 -213.950891) (xy 124.047971 -213.908503) (xy 124.023436 -213.861587)
			(xy 124.006718 -213.811352) (xy 123.998249 -213.75909) (xy 123.99772 -213.732618) (xy 122.777504 -213.732618)
			(xy 122.777153 -213.755595) (xy 122.770832 -213.80111) (xy 122.758248 -213.845306) (xy 122.74931 -213.866476)
			(xy 122.739404 -213.888828) (xy 122.953018 -214.293958) (xy 122.977148 -214.29853) (xy 123.002067 -214.303641)
			(xy 123.050077 -214.320441) (xy 123.094936 -214.344419) (xy 123.135576 -214.375006) (xy 123.171034 -214.411476)
			(xy 123.200466 -214.452961) (xy 123.223173 -214.498476) (xy 123.238615 -214.54694) (xy 123.246427 -214.597201)
			(xy 123.246896 -214.622634) (xy 123.246388 -214.648521) (xy 123.238289 -214.699659) (xy 123.22229 -214.748899)
			(xy 123.198784 -214.795031) (xy 123.168352 -214.836918) (xy 123.131742 -214.873528) (xy 123.089855 -214.90396)
			(xy 123.043723 -214.927466) (xy 122.994483 -214.943465) (xy 122.943345 -214.951564) (xy 122.891571 -214.951564)
			(xy 122.840433 -214.943465) (xy 122.791193 -214.927466) (xy 122.745061 -214.90396) (xy 122.703174 -214.873528)
			(xy 122.666564 -214.836918) (xy 122.636132 -214.795031) (xy 122.612626 -214.748899) (xy 122.596627 -214.699659)
			(xy 122.588528 -214.648521) (xy 122.58802 -214.622634) (xy 122.588387 -214.599658) (xy 122.5947 -214.554143)
			(xy 122.607279 -214.509947) (xy 122.616214 -214.488776) (xy 122.62612 -214.466424) (xy 122.412506 -214.061294)
			(xy 122.388376 -214.056722) (xy 122.36345 -214.051639) (xy 122.315436 -214.034839) (xy 122.270575 -214.010859)
			(xy 122.229932 -213.980269) (xy 122.194474 -213.943796) (xy 122.165043 -213.902307) (xy 122.142338 -213.856787)
			(xy 122.1269 -213.808318) (xy 122.119094 -213.758052) (xy 122.118628 -213.732618) (xy 120.897904 -213.732618)
			(xy 120.897553 -213.755595) (xy 120.891232 -213.80111) (xy 120.878648 -213.845306) (xy 120.86971 -213.866476)
			(xy 120.859804 -213.888828) (xy 121.073418 -214.293958) (xy 121.097548 -214.29853) (xy 121.122467 -214.303641)
			(xy 121.170477 -214.320441) (xy 121.215336 -214.344419) (xy 121.255976 -214.375006) (xy 121.291434 -214.411476)
			(xy 121.320866 -214.452961) (xy 121.343573 -214.498476) (xy 121.359015 -214.54694) (xy 121.366827 -214.597201)
			(xy 121.367296 -214.622634) (xy 121.366788 -214.648521) (xy 121.358689 -214.699659) (xy 121.34269 -214.748899)
			(xy 121.319184 -214.795031) (xy 121.288752 -214.836918) (xy 121.252142 -214.873528) (xy 121.210255 -214.90396)
			(xy 121.164123 -214.927466) (xy 121.114883 -214.943465) (xy 121.063745 -214.951564) (xy 121.011971 -214.951564)
			(xy 120.960833 -214.943465) (xy 120.911593 -214.927466) (xy 120.865461 -214.90396) (xy 120.823574 -214.873528)
			(xy 120.786964 -214.836918) (xy 120.756532 -214.795031) (xy 120.733026 -214.748899) (xy 120.717027 -214.699659)
			(xy 120.708928 -214.648521) (xy 120.70842 -214.622634) (xy 120.708787 -214.599658) (xy 120.7151 -214.554143)
			(xy 120.727679 -214.509947) (xy 120.736614 -214.488776) (xy 120.74652 -214.466424) (xy 120.532906 -214.061294)
			(xy 120.508776 -214.056722) (xy 120.48385 -214.051639) (xy 120.435836 -214.034839) (xy 120.390975 -214.010859)
			(xy 120.350332 -213.980269) (xy 120.314874 -213.943796) (xy 120.285443 -213.902307) (xy 120.262738 -213.856787)
			(xy 120.2473 -213.808318) (xy 120.239494 -213.758052) (xy 120.239028 -213.732618) (xy 119.018304 -213.732618)
			(xy 119.017953 -213.755595) (xy 119.011632 -213.80111) (xy 118.999048 -213.845306) (xy 118.99011 -213.866476)
			(xy 118.980204 -213.888828) (xy 119.193818 -214.293958) (xy 119.217948 -214.29853) (xy 119.242867 -214.303641)
			(xy 119.290877 -214.320441) (xy 119.335736 -214.344419) (xy 119.376376 -214.375006) (xy 119.411834 -214.411476)
			(xy 119.441266 -214.452961) (xy 119.463973 -214.498476) (xy 119.479415 -214.54694) (xy 119.487227 -214.597201)
			(xy 119.487696 -214.622634) (xy 119.487188 -214.648521) (xy 119.479089 -214.699659) (xy 119.46309 -214.748899)
			(xy 119.439584 -214.795031) (xy 119.409152 -214.836918) (xy 119.372542 -214.873528) (xy 119.330655 -214.90396)
			(xy 119.284523 -214.927466) (xy 119.235283 -214.943465) (xy 119.184145 -214.951564) (xy 119.132371 -214.951564)
			(xy 119.081233 -214.943465) (xy 119.031993 -214.927466) (xy 118.985861 -214.90396) (xy 118.943974 -214.873528)
			(xy 118.907364 -214.836918) (xy 118.876932 -214.795031) (xy 118.853426 -214.748899) (xy 118.837427 -214.699659)
			(xy 118.829328 -214.648521) (xy 118.82882 -214.622634) (xy 118.829187 -214.599658) (xy 118.8355 -214.554143)
			(xy 118.848079 -214.509947) (xy 118.857014 -214.488776) (xy 118.86692 -214.466424) (xy 118.653306 -214.061294)
			(xy 118.629176 -214.056722) (xy 118.60425 -214.051639) (xy 118.556236 -214.034839) (xy 118.511375 -214.010859)
			(xy 118.470732 -213.980269) (xy 118.435274 -213.943796) (xy 118.405843 -213.902307) (xy 118.383138 -213.856787)
			(xy 118.3677 -213.808318) (xy 118.359894 -213.758052) (xy 118.359428 -213.732618) (xy 117.138704 -213.732618)
			(xy 117.138353 -213.755595) (xy 117.132032 -213.80111) (xy 117.119448 -213.845306) (xy 117.11051 -213.866476)
			(xy 117.100604 -213.888828) (xy 117.314218 -214.293958) (xy 117.338348 -214.29853) (xy 117.363267 -214.303641)
			(xy 117.411277 -214.320441) (xy 117.456136 -214.344419) (xy 117.496776 -214.375006) (xy 117.532234 -214.411476)
			(xy 117.561666 -214.452961) (xy 117.584373 -214.498476) (xy 117.599815 -214.54694) (xy 117.607627 -214.597201)
			(xy 117.608096 -214.622634) (xy 117.607588 -214.648521) (xy 117.599489 -214.699659) (xy 117.58349 -214.748899)
			(xy 117.559984 -214.795031) (xy 117.529552 -214.836918) (xy 117.492942 -214.873528) (xy 117.451055 -214.90396)
			(xy 117.404923 -214.927466) (xy 117.355683 -214.943465) (xy 117.304545 -214.951564) (xy 117.252771 -214.951564)
			(xy 117.201633 -214.943465) (xy 117.152393 -214.927466) (xy 117.106261 -214.90396) (xy 117.064374 -214.873528)
			(xy 117.027764 -214.836918) (xy 116.997332 -214.795031) (xy 116.973826 -214.748899) (xy 116.957827 -214.699659)
			(xy 116.949728 -214.648521) (xy 116.94922 -214.622634) (xy 116.949587 -214.599658) (xy 116.9559 -214.554143)
			(xy 116.968479 -214.509947) (xy 116.977414 -214.488776) (xy 116.98732 -214.466424) (xy 116.773706 -214.061294)
			(xy 116.749576 -214.056722) (xy 116.72465 -214.051639) (xy 116.676636 -214.034839) (xy 116.631775 -214.010859)
			(xy 116.591132 -213.980269) (xy 116.555674 -213.943796) (xy 116.526243 -213.902307) (xy 116.503538 -213.856787)
			(xy 116.4881 -213.808318) (xy 116.480294 -213.758052) (xy 116.479828 -213.732618) (xy 115.613942 -213.732618)
			(xy 115.613942 -214.372698) (xy 115.631596 -214.388433) (xy 115.662657 -214.424091) (xy 115.688301 -214.463824)
			(xy 115.708001 -214.506815) (xy 115.721352 -214.55218) (xy 115.72808 -214.598989) (xy 115.728496 -214.622634)
			(xy 115.728107 -214.64628) (xy 115.721379 -214.693091) (xy 115.708025 -214.738458) (xy 115.688317 -214.781447)
			(xy 115.662663 -214.821176) (xy 115.631589 -214.856826) (xy 115.613942 -214.87257) (xy 115.613942 -215.03386)
			(xy 115.614401 -215.047942) (xy 115.622099 -215.075035) (xy 115.636895 -215.099001) (xy 115.657667 -215.118023)
			(xy 115.682839 -215.130658) (xy 115.710503 -215.135949) (xy 115.738561 -215.133493) (xy 115.751864 -215.128856)
			(xy 115.765502 -215.123776) (xy 115.793484 -215.115766) (xy 115.807744 -215.112854) (xy 115.830604 -215.108536)
			(xy 116.035582 -214.753444) (xy 116.027708 -214.7316) (xy 116.019131 -214.705181) (xy 116.009941 -214.650406)
			(xy 116.00942 -214.622634) (xy 116.009928 -214.596747) (xy 116.018027 -214.545609) (xy 116.034026 -214.496369)
			(xy 116.057532 -214.450237) (xy 116.087964 -214.40835) (xy 116.124574 -214.37174) (xy 116.166461 -214.341308)
			(xy 116.212593 -214.317802) (xy 116.261833 -214.301803) (xy 116.312971 -214.293704) (xy 116.364745 -214.293704)
			(xy 116.415883 -214.301803) (xy 116.465123 -214.317802) (xy 116.511255 -214.341308) (xy 116.553142 -214.37174)
			(xy 116.589752 -214.40835) (xy 116.620184 -214.450237) (xy 116.64369 -214.496369) (xy 116.659689 -214.545609)
			(xy 116.667788 -214.596747) (xy 116.668296 -214.622634) (xy 116.66783 -214.647968) (xy 116.660072 -214.69804)
			(xy 116.644746 -214.746335) (xy 116.622211 -214.791716) (xy 116.592999 -214.833116) (xy 116.557796 -214.869559)
			(xy 116.517432 -214.900187) (xy 116.472858 -214.924279) (xy 116.425122 -214.941268) (xy 116.400326 -214.946484)
			(xy 116.377466 -214.950802) (xy 116.172488 -215.305894) (xy 116.180362 -215.327738) (xy 116.189008 -215.354146)
			(xy 116.19833 -215.408922) (xy 116.198904 -215.436704) (xy 117.41912 -215.436704) (xy 117.419629 -215.41136)
			(xy 117.4274 -215.36127) (xy 117.442746 -215.31296) (xy 117.465303 -215.267567) (xy 117.494542 -215.226161)
			(xy 117.529773 -215.189717) (xy 117.570165 -215.159094) (xy 117.614769 -215.135013) (xy 117.662532 -215.118041)
			(xy 117.687344 -215.112854) (xy 117.710204 -215.108536) (xy 117.915182 -214.753444) (xy 117.907308 -214.7316)
			(xy 117.898729 -214.705181) (xy 117.889532 -214.650406) (xy 117.88902 -214.622634) (xy 117.889528 -214.596747)
			(xy 117.897627 -214.545609) (xy 117.913626 -214.496369) (xy 117.937132 -214.450237) (xy 117.967564 -214.40835)
			(xy 118.004174 -214.37174) (xy 118.046061 -214.341308) (xy 118.092193 -214.317802) (xy 118.141433 -214.301803)
			(xy 118.192571 -214.293704) (xy 118.244345 -214.293704) (xy 118.295483 -214.301803) (xy 118.344723 -214.317802)
			(xy 118.390855 -214.341308) (xy 118.432742 -214.37174) (xy 118.469352 -214.40835) (xy 118.499784 -214.450237)
			(xy 118.52329 -214.496369) (xy 118.539289 -214.545609) (xy 118.547388 -214.596747) (xy 118.547896 -214.622634)
			(xy 118.547447 -214.64797) (xy 118.53969 -214.698044) (xy 118.524363 -214.746341) (xy 118.501827 -214.791726)
			(xy 118.472612 -214.833128) (xy 118.437408 -214.869572) (xy 118.397042 -214.900202) (xy 118.352465 -214.924296)
			(xy 118.304727 -214.941286) (xy 118.279926 -214.946484) (xy 118.257066 -214.950802) (xy 118.052088 -215.305894)
			(xy 118.059962 -215.327738) (xy 118.06861 -215.354146) (xy 118.077929 -215.408922) (xy 118.078504 -215.436704)
			(xy 119.29872 -215.436704) (xy 119.299229 -215.41136) (xy 119.307 -215.36127) (xy 119.322346 -215.31296)
			(xy 119.344903 -215.267567) (xy 119.374142 -215.226161) (xy 119.409373 -215.189717) (xy 119.449765 -215.159094)
			(xy 119.494369 -215.135013) (xy 119.542132 -215.118041) (xy 119.566944 -215.112854) (xy 119.589804 -215.108536)
			(xy 119.794782 -214.753444) (xy 119.786908 -214.7316) (xy 119.778329 -214.705181) (xy 119.769132 -214.650406)
			(xy 119.76862 -214.622634) (xy 119.769128 -214.596747) (xy 119.777227 -214.545609) (xy 119.793226 -214.496369)
			(xy 119.816732 -214.450237) (xy 119.847164 -214.40835) (xy 119.883774 -214.37174) (xy 119.925661 -214.341308)
			(xy 119.971793 -214.317802) (xy 120.021033 -214.301803) (xy 120.072171 -214.293704) (xy 120.123945 -214.293704)
			(xy 120.175083 -214.301803) (xy 120.224323 -214.317802) (xy 120.270455 -214.341308) (xy 120.312342 -214.37174)
			(xy 120.348952 -214.40835) (xy 120.379384 -214.450237) (xy 120.40289 -214.496369) (xy 120.418889 -214.545609)
			(xy 120.426988 -214.596747) (xy 120.427496 -214.622634) (xy 120.427047 -214.64797) (xy 120.41929 -214.698044)
			(xy 120.403963 -214.746341) (xy 120.381427 -214.791726) (xy 120.352212 -214.833128) (xy 120.317008 -214.869572)
			(xy 120.276642 -214.900202) (xy 120.232065 -214.924296) (xy 120.184327 -214.941286) (xy 120.159526 -214.946484)
			(xy 120.136666 -214.950802) (xy 119.931688 -215.305894) (xy 119.939562 -215.327738) (xy 119.94821 -215.354146)
			(xy 119.957529 -215.408922) (xy 119.958104 -215.436704) (xy 121.17832 -215.436704) (xy 121.178829 -215.41136)
			(xy 121.1866 -215.36127) (xy 121.201946 -215.31296) (xy 121.224503 -215.267567) (xy 121.253742 -215.226161)
			(xy 121.288973 -215.189717) (xy 121.329365 -215.159094) (xy 121.373969 -215.135013) (xy 121.421732 -215.118041)
			(xy 121.446544 -215.112854) (xy 121.469404 -215.108536) (xy 121.674382 -214.753444) (xy 121.666508 -214.7316)
			(xy 121.657929 -214.705181) (xy 121.648732 -214.650406) (xy 121.64822 -214.622634) (xy 121.648728 -214.596747)
			(xy 121.656827 -214.545609) (xy 121.672826 -214.496369) (xy 121.696332 -214.450237) (xy 121.726764 -214.40835)
			(xy 121.763374 -214.37174) (xy 121.805261 -214.341308) (xy 121.851393 -214.317802) (xy 121.900633 -214.301803)
			(xy 121.951771 -214.293704) (xy 122.003545 -214.293704) (xy 122.054683 -214.301803) (xy 122.103923 -214.317802)
			(xy 122.150055 -214.341308) (xy 122.191942 -214.37174) (xy 122.228552 -214.40835) (xy 122.258984 -214.450237)
			(xy 122.28249 -214.496369) (xy 122.298489 -214.545609) (xy 122.306588 -214.596747) (xy 122.307096 -214.622634)
			(xy 122.306647 -214.64797) (xy 122.29889 -214.698044) (xy 122.283563 -214.746341) (xy 122.261027 -214.791726)
			(xy 122.231812 -214.833128) (xy 122.196608 -214.869572) (xy 122.156242 -214.900202) (xy 122.111665 -214.924296)
			(xy 122.063927 -214.941286) (xy 122.039126 -214.946484) (xy 122.016266 -214.950802) (xy 121.811288 -215.305894)
			(xy 121.819162 -215.327738) (xy 121.82781 -215.354146) (xy 121.837129 -215.408922) (xy 121.837704 -215.436704)
			(xy 123.05792 -215.436704) (xy 123.058429 -215.41136) (xy 123.0662 -215.36127) (xy 123.081546 -215.31296)
			(xy 123.104103 -215.267567) (xy 123.133342 -215.226161) (xy 123.168573 -215.189717) (xy 123.208965 -215.159094)
			(xy 123.253569 -215.135013) (xy 123.301332 -215.118041) (xy 123.326144 -215.112854) (xy 123.349004 -215.108536)
			(xy 123.553982 -214.753444) (xy 123.546108 -214.7316) (xy 123.537529 -214.705181) (xy 123.528332 -214.650406)
			(xy 123.52782 -214.622634) (xy 123.528328 -214.596747) (xy 123.536427 -214.545609) (xy 123.552426 -214.496369)
			(xy 123.575932 -214.450237) (xy 123.606364 -214.40835) (xy 123.642974 -214.37174) (xy 123.684861 -214.341308)
			(xy 123.730993 -214.317802) (xy 123.780233 -214.301803) (xy 123.831371 -214.293704) (xy 123.883145 -214.293704)
			(xy 123.934283 -214.301803) (xy 123.983523 -214.317802) (xy 124.029655 -214.341308) (xy 124.071542 -214.37174)
			(xy 124.108152 -214.40835) (xy 124.138584 -214.450237) (xy 124.16209 -214.496369) (xy 124.178089 -214.545609)
			(xy 124.186188 -214.596747) (xy 124.186696 -214.622634) (xy 124.186247 -214.64797) (xy 124.17849 -214.698044)
			(xy 124.163163 -214.746341) (xy 124.140627 -214.791726) (xy 124.111412 -214.833128) (xy 124.076208 -214.869572)
			(xy 124.035842 -214.900202) (xy 123.991265 -214.924296) (xy 123.943527 -214.941286) (xy 123.918726 -214.946484)
			(xy 123.895866 -214.950802) (xy 123.690888 -215.305894) (xy 123.698762 -215.327738) (xy 123.70741 -215.354146)
			(xy 123.716729 -215.408922) (xy 123.717304 -215.436704) (xy 124.93752 -215.436704) (xy 124.938029 -215.41136)
			(xy 124.9458 -215.36127) (xy 124.961146 -215.31296) (xy 124.983703 -215.267567) (xy 125.012942 -215.226161)
			(xy 125.048173 -215.189717) (xy 125.088565 -215.159094) (xy 125.133169 -215.135013) (xy 125.180932 -215.118041)
			(xy 125.205744 -215.112854) (xy 125.228604 -215.108536) (xy 125.433582 -214.753444) (xy 125.425708 -214.7316)
			(xy 125.417129 -214.705181) (xy 125.407932 -214.650406) (xy 125.40742 -214.622634) (xy 125.407928 -214.596747)
			(xy 125.416027 -214.545609) (xy 125.432026 -214.496369) (xy 125.455532 -214.450237) (xy 125.485964 -214.40835)
			(xy 125.522574 -214.37174) (xy 125.564461 -214.341308) (xy 125.610593 -214.317802) (xy 125.659833 -214.301803)
			(xy 125.710971 -214.293704) (xy 125.762745 -214.293704) (xy 125.813883 -214.301803) (xy 125.863123 -214.317802)
			(xy 125.909255 -214.341308) (xy 125.951142 -214.37174) (xy 125.987752 -214.40835) (xy 126.018184 -214.450237)
			(xy 126.04169 -214.496369) (xy 126.057689 -214.545609) (xy 126.065788 -214.596747) (xy 126.066296 -214.622634)
			(xy 126.065847 -214.64797) (xy 126.05809 -214.698044) (xy 126.042763 -214.746341) (xy 126.020227 -214.791726)
			(xy 125.991012 -214.833128) (xy 125.955808 -214.869572) (xy 125.915442 -214.900202) (xy 125.870865 -214.924296)
			(xy 125.823127 -214.941286) (xy 125.798326 -214.946484) (xy 125.775466 -214.950802) (xy 125.570488 -215.305894)
			(xy 125.578362 -215.327738) (xy 125.58701 -215.354146) (xy 125.596329 -215.408922) (xy 125.596904 -215.436704)
			(xy 125.596396 -215.462611) (xy 125.58829 -215.513788) (xy 125.572278 -215.563067) (xy 125.548755 -215.609234)
			(xy 125.518299 -215.651153) (xy 125.481661 -215.687791) (xy 125.439742 -215.718247) (xy 125.393575 -215.74177)
			(xy 125.344296 -215.757782) (xy 125.293119 -215.765888) (xy 125.241305 -215.765888) (xy 125.190128 -215.757782)
			(xy 125.140849 -215.74177) (xy 125.094682 -215.718247) (xy 125.052763 -215.687791) (xy 125.016125 -215.651153)
			(xy 124.985669 -215.609234) (xy 124.962146 -215.563067) (xy 124.946134 -215.513788) (xy 124.938028 -215.462611)
			(xy 124.93752 -215.436704) (xy 123.717304 -215.436704) (xy 123.716796 -215.462611) (xy 123.70869 -215.513788)
			(xy 123.692678 -215.563067) (xy 123.669155 -215.609234) (xy 123.638699 -215.651153) (xy 123.602061 -215.687791)
			(xy 123.560142 -215.718247) (xy 123.513975 -215.74177) (xy 123.464696 -215.757782) (xy 123.413519 -215.765888)
			(xy 123.361705 -215.765888) (xy 123.310528 -215.757782) (xy 123.261249 -215.74177) (xy 123.215082 -215.718247)
			(xy 123.173163 -215.687791) (xy 123.136525 -215.651153) (xy 123.106069 -215.609234) (xy 123.082546 -215.563067)
			(xy 123.066534 -215.513788) (xy 123.058428 -215.462611) (xy 123.05792 -215.436704) (xy 121.837704 -215.436704)
			(xy 121.837196 -215.462611) (xy 121.82909 -215.513788) (xy 121.813078 -215.563067) (xy 121.789555 -215.609234)
			(xy 121.759099 -215.651153) (xy 121.722461 -215.687791) (xy 121.680542 -215.718247) (xy 121.634375 -215.74177)
			(xy 121.585096 -215.757782) (xy 121.533919 -215.765888) (xy 121.482105 -215.765888) (xy 121.430928 -215.757782)
			(xy 121.381649 -215.74177) (xy 121.335482 -215.718247) (xy 121.293563 -215.687791) (xy 121.256925 -215.651153)
			(xy 121.226469 -215.609234) (xy 121.202946 -215.563067) (xy 121.186934 -215.513788) (xy 121.178828 -215.462611)
			(xy 121.17832 -215.436704) (xy 119.958104 -215.436704) (xy 119.957596 -215.462611) (xy 119.94949 -215.513788)
			(xy 119.933478 -215.563067) (xy 119.909955 -215.609234) (xy 119.879499 -215.651153) (xy 119.842861 -215.687791)
			(xy 119.800942 -215.718247) (xy 119.754775 -215.74177) (xy 119.705496 -215.757782) (xy 119.654319 -215.765888)
			(xy 119.602505 -215.765888) (xy 119.551328 -215.757782) (xy 119.502049 -215.74177) (xy 119.455882 -215.718247)
			(xy 119.413963 -215.687791) (xy 119.377325 -215.651153) (xy 119.346869 -215.609234) (xy 119.323346 -215.563067)
			(xy 119.307334 -215.513788) (xy 119.299228 -215.462611) (xy 119.29872 -215.436704) (xy 118.078504 -215.436704)
			(xy 118.077996 -215.462611) (xy 118.06989 -215.513788) (xy 118.053878 -215.563067) (xy 118.030355 -215.609234)
			(xy 117.999899 -215.651153) (xy 117.963261 -215.687791) (xy 117.921342 -215.718247) (xy 117.875175 -215.74177)
			(xy 117.825896 -215.757782) (xy 117.774719 -215.765888) (xy 117.722905 -215.765888) (xy 117.671728 -215.757782)
			(xy 117.622449 -215.74177) (xy 117.576282 -215.718247) (xy 117.534363 -215.687791) (xy 117.497725 -215.651153)
			(xy 117.467269 -215.609234) (xy 117.443746 -215.563067) (xy 117.427734 -215.513788) (xy 117.419628 -215.462611)
			(xy 117.41912 -215.436704) (xy 116.198904 -215.436704) (xy 116.198396 -215.462611) (xy 116.19029 -215.513788)
			(xy 116.174278 -215.563067) (xy 116.150755 -215.609235) (xy 116.120299 -215.651154) (xy 116.08366 -215.687794)
			(xy 116.041742 -215.71825) (xy 115.995575 -215.741775) (xy 115.946296 -215.757788) (xy 115.895119 -215.765895)
			(xy 115.869212 -215.766396) (xy 115.839186 -215.765661) (xy 115.780146 -215.754664) (xy 115.751864 -215.744552)
			(xy 115.738544 -215.739932) (xy 115.710473 -215.737421) (xy 115.682785 -215.742681) (xy 115.65759 -215.755309)
			(xy 115.636807 -215.774344) (xy 115.622019 -215.798336) (xy 115.614354 -215.825456) (xy 115.613942 -215.839548)
			(xy 115.613942 -216.002362) (xy 115.632994 -216.01947) (xy 115.666068 -216.058556) (xy 115.692664 -216.102308)
			(xy 115.712137 -216.149662) (xy 115.724012 -216.199467) (xy 115.728002 -216.250513) (xy 115.724008 -216.301559)
			(xy 115.712129 -216.351363) (xy 115.692653 -216.398716) (xy 115.666052 -216.442466) (xy 115.632975 -216.481549)
			(xy 115.613942 -216.498678) (xy 115.613942 -217.064336) (xy 116.47932 -217.064336) (xy 116.479828 -217.038429)
			(xy 116.487934 -216.987252) (xy 116.503946 -216.937973) (xy 116.527469 -216.891806) (xy 116.557925 -216.849887)
			(xy 116.594563 -216.813249) (xy 116.636482 -216.782793) (xy 116.682649 -216.75927) (xy 116.731928 -216.743258)
			(xy 116.783105 -216.735152) (xy 116.834919 -216.735152) (xy 116.886096 -216.743258) (xy 116.935375 -216.75927)
			(xy 116.981542 -216.782793) (xy 117.023461 -216.813249) (xy 117.060099 -216.849887) (xy 117.090555 -216.891806)
			(xy 117.114078 -216.937973) (xy 117.13009 -216.987252) (xy 117.138196 -217.038429) (xy 117.138704 -217.064336)
			(xy 118.35892 -217.064336) (xy 118.359428 -217.038429) (xy 118.367534 -216.987252) (xy 118.383546 -216.937973)
			(xy 118.407069 -216.891806) (xy 118.437525 -216.849887) (xy 118.474163 -216.813249) (xy 118.516082 -216.782793)
			(xy 118.562249 -216.75927) (xy 118.611528 -216.743258) (xy 118.662705 -216.735152) (xy 118.714519 -216.735152)
			(xy 118.765696 -216.743258) (xy 118.814975 -216.75927) (xy 118.861142 -216.782793) (xy 118.903061 -216.813249)
			(xy 118.939699 -216.849887) (xy 118.970155 -216.891806) (xy 118.993678 -216.937973) (xy 119.00969 -216.987252)
			(xy 119.017796 -217.038429) (xy 119.018304 -217.064336) (xy 120.23852 -217.064336) (xy 120.239028 -217.038429)
			(xy 120.247134 -216.987252) (xy 120.263146 -216.937973) (xy 120.286669 -216.891806) (xy 120.317125 -216.849887)
			(xy 120.353763 -216.813249) (xy 120.395682 -216.782793) (xy 120.441849 -216.75927) (xy 120.491128 -216.743258)
			(xy 120.542305 -216.735152) (xy 120.594119 -216.735152) (xy 120.645296 -216.743258) (xy 120.694575 -216.75927)
			(xy 120.740742 -216.782793) (xy 120.782661 -216.813249) (xy 120.819299 -216.849887) (xy 120.849755 -216.891806)
			(xy 120.873278 -216.937973) (xy 120.88929 -216.987252) (xy 120.897396 -217.038429) (xy 120.897904 -217.064336)
			(xy 122.11812 -217.064336) (xy 122.118628 -217.038429) (xy 122.126734 -216.987252) (xy 122.142746 -216.937973)
			(xy 122.166269 -216.891806) (xy 122.196725 -216.849887) (xy 122.233363 -216.813249) (xy 122.275282 -216.782793)
			(xy 122.321449 -216.75927) (xy 122.370728 -216.743258) (xy 122.421905 -216.735152) (xy 122.473719 -216.735152)
			(xy 122.524896 -216.743258) (xy 122.574175 -216.75927) (xy 122.620342 -216.782793) (xy 122.662261 -216.813249)
			(xy 122.698899 -216.849887) (xy 122.729355 -216.891806) (xy 122.752878 -216.937973) (xy 122.76889 -216.987252)
			(xy 122.776996 -217.038429) (xy 122.777504 -217.064336) (xy 123.99772 -217.064336) (xy 123.998228 -217.038429)
			(xy 124.006334 -216.987252) (xy 124.022346 -216.937973) (xy 124.045869 -216.891806) (xy 124.076325 -216.849887)
			(xy 124.112963 -216.813249) (xy 124.154882 -216.782793) (xy 124.201049 -216.75927) (xy 124.250328 -216.743258)
			(xy 124.301505 -216.735152) (xy 124.353319 -216.735152) (xy 124.404496 -216.743258) (xy 124.453775 -216.75927)
			(xy 124.499942 -216.782793) (xy 124.541861 -216.813249) (xy 124.578499 -216.849887) (xy 124.608955 -216.891806)
			(xy 124.632478 -216.937973) (xy 124.64849 -216.987252) (xy 124.656596 -217.038429) (xy 124.657104 -217.064336)
			(xy 125.87732 -217.064336) (xy 125.877828 -217.038429) (xy 125.885934 -216.987252) (xy 125.901946 -216.937973)
			(xy 125.925469 -216.891806) (xy 125.955925 -216.849887) (xy 125.992563 -216.813249) (xy 126.034482 -216.782793)
			(xy 126.080649 -216.75927) (xy 126.129928 -216.743258) (xy 126.181105 -216.735152) (xy 126.232919 -216.735152)
			(xy 126.284096 -216.743258) (xy 126.333375 -216.75927) (xy 126.379542 -216.782793) (xy 126.421461 -216.813249)
			(xy 126.458099 -216.849887) (xy 126.488555 -216.891806) (xy 126.512078 -216.937973) (xy 126.52809 -216.987252)
			(xy 126.536196 -217.038429) (xy 126.536704 -217.064336) (xy 126.536089 -217.091989) (xy 126.526769 -217.146507)
			(xy 126.518162 -217.172794) (xy 126.510542 -217.194892) (xy 126.715774 -217.550238) (xy 126.738634 -217.554556)
			(xy 126.763441 -217.559728) (xy 126.811179 -217.576721) (xy 126.855756 -217.600818) (xy 126.89612 -217.631451)
			(xy 126.931323 -217.6679) (xy 126.960534 -217.709305) (xy 126.983066 -217.754693) (xy 126.998389 -217.802993)
			(xy 127.006141 -217.85307) (xy 127.006604 -217.878406) (xy 127.006096 -217.904293) (xy 126.997997 -217.955431)
			(xy 126.981998 -218.004671) (xy 126.958492 -218.050803) (xy 126.92806 -218.09269) (xy 126.89145 -218.1293)
			(xy 126.849563 -218.159732) (xy 126.803431 -218.183238) (xy 126.754191 -218.199237) (xy 126.703053 -218.207336)
			(xy 126.651279 -218.207336) (xy 126.600141 -218.199237) (xy 126.550901 -218.183238) (xy 126.504769 -218.159732)
			(xy 126.462882 -218.1293) (xy 126.426272 -218.09269) (xy 126.39584 -218.050803) (xy 126.372334 -218.004671)
			(xy 126.356335 -217.955431) (xy 126.348236 -217.904293) (xy 126.347728 -217.878406) (xy 126.348262 -217.850698)
			(xy 126.357455 -217.796051) (xy 126.366016 -217.769694) (xy 126.37389 -217.747596) (xy 126.168912 -217.392504)
			(xy 126.146052 -217.388186) (xy 126.121196 -217.383069) (xy 126.073348 -217.366166) (xy 126.028656 -217.342128)
			(xy 125.988177 -217.311523) (xy 125.952867 -217.275076) (xy 125.923561 -217.233647) (xy 125.900952 -217.188215)
			(xy 125.885574 -217.139855) (xy 125.87779 -217.089709) (xy 125.87732 -217.064336) (xy 124.657104 -217.064336)
			(xy 124.656489 -217.091989) (xy 124.647169 -217.146507) (xy 124.638562 -217.172794) (xy 124.630942 -217.194892)
			(xy 124.836174 -217.550238) (xy 124.859034 -217.554556) (xy 124.883841 -217.559728) (xy 124.931579 -217.576721)
			(xy 124.976156 -217.600818) (xy 125.01652 -217.631451) (xy 125.051723 -217.6679) (xy 125.080934 -217.709305)
			(xy 125.103466 -217.754693) (xy 125.118789 -217.802993) (xy 125.126541 -217.85307) (xy 125.127004 -217.878406)
			(xy 125.126496 -217.904293) (xy 125.118397 -217.955431) (xy 125.102398 -218.004671) (xy 125.078892 -218.050803)
			(xy 125.04846 -218.09269) (xy 125.01185 -218.1293) (xy 124.969963 -218.159732) (xy 124.923831 -218.183238)
			(xy 124.874591 -218.199237) (xy 124.823453 -218.207336) (xy 124.771679 -218.207336) (xy 124.720541 -218.199237)
			(xy 124.671301 -218.183238) (xy 124.625169 -218.159732) (xy 124.583282 -218.1293) (xy 124.546672 -218.09269)
			(xy 124.51624 -218.050803) (xy 124.492734 -218.004671) (xy 124.476735 -217.955431) (xy 124.468636 -217.904293)
			(xy 124.468128 -217.878406) (xy 124.468662 -217.850698) (xy 124.477855 -217.796051) (xy 124.486416 -217.769694)
			(xy 124.49429 -217.747596) (xy 124.289312 -217.392504) (xy 124.266452 -217.388186) (xy 124.241596 -217.383069)
			(xy 124.193748 -217.366166) (xy 124.149056 -217.342128) (xy 124.108577 -217.311523) (xy 124.073267 -217.275076)
			(xy 124.043961 -217.233647) (xy 124.021352 -217.188215) (xy 124.005974 -217.139855) (xy 123.99819 -217.089709)
			(xy 123.99772 -217.064336) (xy 122.777504 -217.064336) (xy 122.776889 -217.091989) (xy 122.767569 -217.146507)
			(xy 122.758962 -217.172794) (xy 122.751342 -217.194892) (xy 122.956574 -217.550238) (xy 122.979434 -217.554556)
			(xy 123.004241 -217.559728) (xy 123.051979 -217.576721) (xy 123.096556 -217.600818) (xy 123.13692 -217.631451)
			(xy 123.172123 -217.6679) (xy 123.201334 -217.709305) (xy 123.223866 -217.754693) (xy 123.239189 -217.802993)
			(xy 123.246941 -217.85307) (xy 123.247404 -217.878406) (xy 123.246896 -217.904293) (xy 123.238797 -217.955431)
			(xy 123.222798 -218.004671) (xy 123.199292 -218.050803) (xy 123.16886 -218.09269) (xy 123.13225 -218.1293)
			(xy 123.090363 -218.159732) (xy 123.044231 -218.183238) (xy 122.994991 -218.199237) (xy 122.943853 -218.207336)
			(xy 122.892079 -218.207336) (xy 122.840941 -218.199237) (xy 122.791701 -218.183238) (xy 122.745569 -218.159732)
			(xy 122.703682 -218.1293) (xy 122.667072 -218.09269) (xy 122.63664 -218.050803) (xy 122.613134 -218.004671)
			(xy 122.597135 -217.955431) (xy 122.589036 -217.904293) (xy 122.588528 -217.878406) (xy 122.589062 -217.850698)
			(xy 122.598255 -217.796051) (xy 122.606816 -217.769694) (xy 122.61469 -217.747596) (xy 122.409712 -217.392504)
			(xy 122.386852 -217.388186) (xy 122.361996 -217.383069) (xy 122.314148 -217.366166) (xy 122.269456 -217.342128)
			(xy 122.228977 -217.311523) (xy 122.193667 -217.275076) (xy 122.164361 -217.233647) (xy 122.141752 -217.188215)
			(xy 122.126374 -217.139855) (xy 122.11859 -217.089709) (xy 122.11812 -217.064336) (xy 120.897904 -217.064336)
			(xy 120.897289 -217.091989) (xy 120.887969 -217.146507) (xy 120.879362 -217.172794) (xy 120.871742 -217.194892)
			(xy 121.076974 -217.550238) (xy 121.099834 -217.554556) (xy 121.124641 -217.559728) (xy 121.172379 -217.576721)
			(xy 121.216956 -217.600818) (xy 121.25732 -217.631451) (xy 121.292523 -217.6679) (xy 121.321734 -217.709305)
			(xy 121.344266 -217.754693) (xy 121.359589 -217.802993) (xy 121.367341 -217.85307) (xy 121.367804 -217.878406)
			(xy 121.367296 -217.904293) (xy 121.359197 -217.955431) (xy 121.343198 -218.004671) (xy 121.319692 -218.050803)
			(xy 121.28926 -218.09269) (xy 121.25265 -218.1293) (xy 121.210763 -218.159732) (xy 121.164631 -218.183238)
			(xy 121.115391 -218.199237) (xy 121.064253 -218.207336) (xy 121.012479 -218.207336) (xy 120.961341 -218.199237)
			(xy 120.912101 -218.183238) (xy 120.865969 -218.159732) (xy 120.824082 -218.1293) (xy 120.787472 -218.09269)
			(xy 120.75704 -218.050803) (xy 120.733534 -218.004671) (xy 120.717535 -217.955431) (xy 120.709436 -217.904293)
			(xy 120.708928 -217.878406) (xy 120.709462 -217.850698) (xy 120.718655 -217.796051) (xy 120.727216 -217.769694)
			(xy 120.73509 -217.747596) (xy 120.530112 -217.392504) (xy 120.507252 -217.388186) (xy 120.482396 -217.383069)
			(xy 120.434548 -217.366166) (xy 120.389856 -217.342128) (xy 120.349377 -217.311523) (xy 120.314067 -217.275076)
			(xy 120.284761 -217.233647) (xy 120.262152 -217.188215) (xy 120.246774 -217.139855) (xy 120.23899 -217.089709)
			(xy 120.23852 -217.064336) (xy 119.018304 -217.064336) (xy 119.017689 -217.091989) (xy 119.008369 -217.146507)
			(xy 118.999762 -217.172794) (xy 118.992142 -217.194892) (xy 119.197374 -217.550238) (xy 119.220234 -217.554556)
			(xy 119.245041 -217.559728) (xy 119.292779 -217.576721) (xy 119.337356 -217.600818) (xy 119.37772 -217.631451)
			(xy 119.412923 -217.6679) (xy 119.442134 -217.709305) (xy 119.464666 -217.754693) (xy 119.479989 -217.802993)
			(xy 119.487741 -217.85307) (xy 119.488204 -217.878406) (xy 119.487696 -217.904293) (xy 119.479597 -217.955431)
			(xy 119.463598 -218.004671) (xy 119.440092 -218.050803) (xy 119.40966 -218.09269) (xy 119.37305 -218.1293)
			(xy 119.331163 -218.159732) (xy 119.285031 -218.183238) (xy 119.235791 -218.199237) (xy 119.184653 -218.207336)
			(xy 119.132879 -218.207336) (xy 119.081741 -218.199237) (xy 119.032501 -218.183238) (xy 118.986369 -218.159732)
			(xy 118.944482 -218.1293) (xy 118.907872 -218.09269) (xy 118.87744 -218.050803) (xy 118.853934 -218.004671)
			(xy 118.837935 -217.955431) (xy 118.829836 -217.904293) (xy 118.829328 -217.878406) (xy 118.829862 -217.850698)
			(xy 118.839055 -217.796051) (xy 118.847616 -217.769694) (xy 118.85549 -217.747596) (xy 118.650512 -217.392504)
			(xy 118.627652 -217.388186) (xy 118.602796 -217.383069) (xy 118.554948 -217.366166) (xy 118.510256 -217.342128)
			(xy 118.469777 -217.311523) (xy 118.434467 -217.275076) (xy 118.405161 -217.233647) (xy 118.382552 -217.188215)
			(xy 118.367174 -217.139855) (xy 118.35939 -217.089709) (xy 118.35892 -217.064336) (xy 117.138704 -217.064336)
			(xy 117.138089 -217.091989) (xy 117.128769 -217.146507) (xy 117.120162 -217.172794) (xy 117.112542 -217.194892)
			(xy 117.317774 -217.550238) (xy 117.340634 -217.554556) (xy 117.365441 -217.559728) (xy 117.413179 -217.576721)
			(xy 117.457756 -217.600818) (xy 117.49812 -217.631451) (xy 117.533323 -217.6679) (xy 117.562534 -217.709305)
			(xy 117.585066 -217.754693) (xy 117.600389 -217.802993) (xy 117.608141 -217.85307) (xy 117.608604 -217.878406)
			(xy 117.608096 -217.904293) (xy 117.599997 -217.955431) (xy 117.583998 -218.004671) (xy 117.560492 -218.050803)
			(xy 117.53006 -218.09269) (xy 117.49345 -218.1293) (xy 117.451563 -218.159732) (xy 117.405431 -218.183238)
			(xy 117.356191 -218.199237) (xy 117.305053 -218.207336) (xy 117.253279 -218.207336) (xy 117.202141 -218.199237)
			(xy 117.152901 -218.183238) (xy 117.106769 -218.159732) (xy 117.064882 -218.1293) (xy 117.028272 -218.09269)
			(xy 116.99784 -218.050803) (xy 116.974334 -218.004671) (xy 116.958335 -217.955431) (xy 116.950236 -217.904293)
			(xy 116.949728 -217.878406) (xy 116.950262 -217.850698) (xy 116.959455 -217.796051) (xy 116.968016 -217.769694)
			(xy 116.97589 -217.747596) (xy 116.770912 -217.392504) (xy 116.748052 -217.388186) (xy 116.723196 -217.383069)
			(xy 116.675348 -217.366166) (xy 116.630656 -217.342128) (xy 116.590177 -217.311523) (xy 116.554867 -217.275076)
			(xy 116.525561 -217.233647) (xy 116.502952 -217.188215) (xy 116.487574 -217.139855) (xy 116.47979 -217.089709)
			(xy 116.47932 -217.064336) (xy 115.613942 -217.064336) (xy 115.613942 -217.628216) (xy 115.633239 -217.645412)
			(xy 115.666756 -217.684756) (xy 115.693718 -217.728851) (xy 115.713464 -217.776616) (xy 115.725508 -217.826878)
			(xy 115.729555 -217.878404) (xy 115.725507 -217.92993) (xy 115.713461 -217.980192) (xy 115.693715 -218.027956)
			(xy 115.666752 -218.07205) (xy 115.633234 -218.111393) (xy 115.613942 -218.128596) (xy 115.613942 -218.289378)
			(xy 115.614404 -218.303459) (xy 115.622105 -218.330547) (xy 115.636901 -218.354509) (xy 115.657672 -218.373526)
			(xy 115.682841 -218.386159) (xy 115.710502 -218.391449) (xy 115.738556 -218.388995) (xy 115.751864 -218.384374)
			(xy 115.765502 -218.379294) (xy 115.793484 -218.371283) (xy 115.807744 -218.368372) (xy 115.830604 -218.364054)
			(xy 116.035836 -218.008708) (xy 116.027962 -217.98661) (xy 116.0195 -217.960365) (xy 116.010438 -217.905976)
			(xy 116.009928 -217.878406) (xy 116.010436 -217.852519) (xy 116.018535 -217.801381) (xy 116.034534 -217.752141)
			(xy 116.05804 -217.706009) (xy 116.088472 -217.664122) (xy 116.125082 -217.627512) (xy 116.166969 -217.59708)
			(xy 116.213101 -217.573574) (xy 116.262341 -217.557575) (xy 116.313479 -217.549476) (xy 116.365253 -217.549476)
			(xy 116.416391 -217.557575) (xy 116.465631 -217.573574) (xy 116.511763 -217.59708) (xy 116.55365 -217.627512)
			(xy 116.59026 -217.664122) (xy 116.620692 -217.706009) (xy 116.644198 -217.752141) (xy 116.660197 -217.801381)
			(xy 116.668296 -217.852519) (xy 116.668804 -217.878406) (xy 116.668336 -217.903779) (xy 116.660555 -217.953924)
			(xy 116.645178 -218.002284) (xy 116.622569 -218.047715) (xy 116.593262 -218.089142) (xy 116.55795 -218.125586)
			(xy 116.517468 -218.156186) (xy 116.472773 -218.180218) (xy 116.424923 -218.197113) (xy 116.400072 -218.202256)
			(xy 116.377212 -218.206574) (xy 116.172488 -218.561412) (xy 116.180362 -218.583256) (xy 116.189007 -218.609665)
			(xy 116.198325 -218.66444) (xy 116.198904 -218.692222) (xy 117.41912 -218.692222) (xy 117.419645 -218.666878)
			(xy 117.427414 -218.616789) (xy 117.442757 -218.56848) (xy 117.465312 -218.523087) (xy 117.494549 -218.481681)
			(xy 117.529778 -218.445236) (xy 117.570169 -218.414613) (xy 117.61477 -218.390531) (xy 117.662532 -218.373559)
			(xy 117.687344 -218.368372) (xy 117.710204 -218.364054) (xy 117.915436 -218.008708) (xy 117.907562 -217.98661)
			(xy 117.899094 -217.960366) (xy 117.890024 -217.905977) (xy 117.889528 -217.878406) (xy 117.890036 -217.852519)
			(xy 117.898135 -217.801381) (xy 117.914134 -217.752141) (xy 117.93764 -217.706009) (xy 117.968072 -217.664122)
			(xy 118.004682 -217.627512) (xy 118.046569 -217.59708) (xy 118.092701 -217.573574) (xy 118.141941 -217.557575)
			(xy 118.193079 -217.549476) (xy 118.244853 -217.549476) (xy 118.295991 -217.557575) (xy 118.345231 -217.573574)
			(xy 118.391363 -217.59708) (xy 118.43325 -217.627512) (xy 118.46986 -217.664122) (xy 118.500292 -217.706009)
			(xy 118.523798 -217.752141) (xy 118.539797 -217.801381) (xy 118.547896 -217.852519) (xy 118.548404 -217.878406)
			(xy 118.547931 -217.90378) (xy 118.540162 -217.953931) (xy 118.524793 -218.002296) (xy 118.502188 -218.047732)
			(xy 118.472882 -218.089163) (xy 118.437568 -218.125609) (xy 118.397082 -218.156208) (xy 118.352382 -218.180235)
			(xy 118.304526 -218.197122) (xy 118.279672 -218.202256) (xy 118.256812 -218.206574) (xy 118.052088 -218.561412)
			(xy 118.059962 -218.583256) (xy 118.068614 -218.609662) (xy 118.07793 -218.66444) (xy 118.078504 -218.692222)
			(xy 119.29872 -218.692222) (xy 119.299245 -218.666878) (xy 119.307014 -218.616789) (xy 119.322357 -218.56848)
			(xy 119.344912 -218.523087) (xy 119.374149 -218.481681) (xy 119.409378 -218.445236) (xy 119.449769 -218.414613)
			(xy 119.49437 -218.390531) (xy 119.542132 -218.373559) (xy 119.566944 -218.368372) (xy 119.589804 -218.364054)
			(xy 119.795036 -218.008708) (xy 119.787162 -217.98661) (xy 119.778694 -217.960366) (xy 119.769624 -217.905977)
			(xy 119.769128 -217.878406) (xy 119.769636 -217.852519) (xy 119.777735 -217.801381) (xy 119.793734 -217.752141)
			(xy 119.81724 -217.706009) (xy 119.847672 -217.664122) (xy 119.884282 -217.627512) (xy 119.926169 -217.59708)
			(xy 119.972301 -217.573574) (xy 120.021541 -217.557575) (xy 120.072679 -217.549476) (xy 120.124453 -217.549476)
			(xy 120.175591 -217.557575) (xy 120.224831 -217.573574) (xy 120.270963 -217.59708) (xy 120.31285 -217.627512)
			(xy 120.34946 -217.664122) (xy 120.379892 -217.706009) (xy 120.403398 -217.752141) (xy 120.419397 -217.801381)
			(xy 120.427496 -217.852519) (xy 120.428004 -217.878406) (xy 120.427531 -217.90378) (xy 120.419762 -217.953931)
			(xy 120.404393 -218.002296) (xy 120.381788 -218.047732) (xy 120.352482 -218.089163) (xy 120.317168 -218.125609)
			(xy 120.276682 -218.156208) (xy 120.231982 -218.180235) (xy 120.184126 -218.197122) (xy 120.159272 -218.202256)
			(xy 120.136412 -218.206574) (xy 119.931688 -218.561412) (xy 119.939562 -218.583256) (xy 119.948214 -218.609662)
			(xy 119.95753 -218.66444) (xy 119.958104 -218.692222) (xy 121.17832 -218.692222) (xy 121.178845 -218.666878)
			(xy 121.186614 -218.616789) (xy 121.201957 -218.56848) (xy 121.224512 -218.523087) (xy 121.253749 -218.481681)
			(xy 121.288978 -218.445236) (xy 121.329369 -218.414613) (xy 121.37397 -218.390531) (xy 121.421732 -218.373559)
			(xy 121.446544 -218.368372) (xy 121.469404 -218.364054) (xy 121.674636 -218.008708) (xy 121.666762 -217.98661)
			(xy 121.658294 -217.960366) (xy 121.649224 -217.905977) (xy 121.648728 -217.878406) (xy 121.649236 -217.852519)
			(xy 121.657335 -217.801381) (xy 121.673334 -217.752141) (xy 121.69684 -217.706009) (xy 121.727272 -217.664122)
			(xy 121.763882 -217.627512) (xy 121.805769 -217.59708) (xy 121.851901 -217.573574) (xy 121.901141 -217.557575)
			(xy 121.952279 -217.549476) (xy 122.004053 -217.549476) (xy 122.055191 -217.557575) (xy 122.104431 -217.573574)
			(xy 122.150563 -217.59708) (xy 122.19245 -217.627512) (xy 122.22906 -217.664122) (xy 122.259492 -217.706009)
			(xy 122.282998 -217.752141) (xy 122.298997 -217.801381) (xy 122.307096 -217.852519) (xy 122.307604 -217.878406)
			(xy 122.307131 -217.90378) (xy 122.299362 -217.953931) (xy 122.283993 -218.002296) (xy 122.261388 -218.047732)
			(xy 122.232082 -218.089163) (xy 122.196768 -218.125609) (xy 122.156282 -218.156208) (xy 122.111582 -218.180235)
			(xy 122.063726 -218.197122) (xy 122.038872 -218.202256) (xy 122.016012 -218.206574) (xy 121.811288 -218.561412)
			(xy 121.819162 -218.583256) (xy 121.827814 -218.609662) (xy 121.83713 -218.66444) (xy 121.837704 -218.692222)
			(xy 123.05792 -218.692222) (xy 123.058445 -218.666878) (xy 123.066214 -218.616789) (xy 123.081557 -218.56848)
			(xy 123.104112 -218.523087) (xy 123.133349 -218.481681) (xy 123.168578 -218.445236) (xy 123.208969 -218.414613)
			(xy 123.25357 -218.390531) (xy 123.301332 -218.373559) (xy 123.326144 -218.368372) (xy 123.349004 -218.364054)
			(xy 123.554236 -218.008708) (xy 123.546362 -217.98661) (xy 123.537894 -217.960366) (xy 123.528824 -217.905977)
			(xy 123.528328 -217.878406) (xy 123.528836 -217.852519) (xy 123.536935 -217.801381) (xy 123.552934 -217.752141)
			(xy 123.57644 -217.706009) (xy 123.606872 -217.664122) (xy 123.643482 -217.627512) (xy 123.685369 -217.59708)
			(xy 123.731501 -217.573574) (xy 123.780741 -217.557575) (xy 123.831879 -217.549476) (xy 123.883653 -217.549476)
			(xy 123.934791 -217.557575) (xy 123.984031 -217.573574) (xy 124.030163 -217.59708) (xy 124.07205 -217.627512)
			(xy 124.10866 -217.664122) (xy 124.139092 -217.706009) (xy 124.162598 -217.752141) (xy 124.178597 -217.801381)
			(xy 124.186696 -217.852519) (xy 124.187204 -217.878406) (xy 124.186731 -217.90378) (xy 124.178962 -217.953931)
			(xy 124.163593 -218.002296) (xy 124.140988 -218.047732) (xy 124.111682 -218.089163) (xy 124.076368 -218.125609)
			(xy 124.035882 -218.156208) (xy 123.991182 -218.180235) (xy 123.943326 -218.197122) (xy 123.918472 -218.202256)
			(xy 123.895612 -218.206574) (xy 123.690888 -218.561412) (xy 123.698762 -218.583256) (xy 123.707414 -218.609662)
			(xy 123.71673 -218.66444) (xy 123.717304 -218.692222) (xy 124.93752 -218.692222) (xy 124.938045 -218.666878)
			(xy 124.945814 -218.616789) (xy 124.961157 -218.56848) (xy 124.983712 -218.523087) (xy 125.012949 -218.481681)
			(xy 125.048178 -218.445236) (xy 125.088569 -218.414613) (xy 125.13317 -218.390531) (xy 125.180932 -218.373559)
			(xy 125.205744 -218.368372) (xy 125.228604 -218.364054) (xy 125.433836 -218.008708) (xy 125.425962 -217.98661)
			(xy 125.417494 -217.960366) (xy 125.408424 -217.905977) (xy 125.407928 -217.878406) (xy 125.408436 -217.852519)
			(xy 125.416535 -217.801381) (xy 125.432534 -217.752141) (xy 125.45604 -217.706009) (xy 125.486472 -217.664122)
			(xy 125.523082 -217.627512) (xy 125.564969 -217.59708) (xy 125.611101 -217.573574) (xy 125.660341 -217.557575)
			(xy 125.711479 -217.549476) (xy 125.763253 -217.549476) (xy 125.814391 -217.557575) (xy 125.863631 -217.573574)
			(xy 125.909763 -217.59708) (xy 125.95165 -217.627512) (xy 125.98826 -217.664122) (xy 126.018692 -217.706009)
			(xy 126.042198 -217.752141) (xy 126.058197 -217.801381) (xy 126.066296 -217.852519) (xy 126.066804 -217.878406)
			(xy 126.066331 -217.90378) (xy 126.058562 -217.953931) (xy 126.043193 -218.002296) (xy 126.020588 -218.047732)
			(xy 125.991282 -218.089163) (xy 125.955968 -218.125609) (xy 125.915482 -218.156208) (xy 125.870782 -218.180235)
			(xy 125.822926 -218.197122) (xy 125.798072 -218.202256) (xy 125.775212 -218.206574) (xy 125.570488 -218.561412)
			(xy 125.578362 -218.583256) (xy 125.587014 -218.609662) (xy 125.59633 -218.66444) (xy 125.596904 -218.692222)
			(xy 125.596396 -218.718129) (xy 125.58829 -218.769306) (xy 125.572278 -218.818585) (xy 125.548755 -218.864752)
			(xy 125.518299 -218.906671) (xy 125.481661 -218.943309) (xy 125.439742 -218.973765) (xy 125.393575 -218.997288)
			(xy 125.344296 -219.0133) (xy 125.293119 -219.021406) (xy 125.241305 -219.021406) (xy 125.190128 -219.0133)
			(xy 125.140849 -218.997288) (xy 125.094682 -218.973765) (xy 125.052763 -218.943309) (xy 125.016125 -218.906671)
			(xy 124.985669 -218.864752) (xy 124.962146 -218.818585) (xy 124.946134 -218.769306) (xy 124.938028 -218.718129)
			(xy 124.93752 -218.692222) (xy 123.717304 -218.692222) (xy 123.716796 -218.718129) (xy 123.70869 -218.769306)
			(xy 123.692678 -218.818585) (xy 123.669155 -218.864752) (xy 123.638699 -218.906671) (xy 123.602061 -218.943309)
			(xy 123.560142 -218.973765) (xy 123.513975 -218.997288) (xy 123.464696 -219.0133) (xy 123.413519 -219.021406)
			(xy 123.361705 -219.021406) (xy 123.310528 -219.0133) (xy 123.261249 -218.997288) (xy 123.215082 -218.973765)
			(xy 123.173163 -218.943309) (xy 123.136525 -218.906671) (xy 123.106069 -218.864752) (xy 123.082546 -218.818585)
			(xy 123.066534 -218.769306) (xy 123.058428 -218.718129) (xy 123.05792 -218.692222) (xy 121.837704 -218.692222)
			(xy 121.837196 -218.718129) (xy 121.82909 -218.769306) (xy 121.813078 -218.818585) (xy 121.789555 -218.864752)
			(xy 121.759099 -218.906671) (xy 121.722461 -218.943309) (xy 121.680542 -218.973765) (xy 121.634375 -218.997288)
			(xy 121.585096 -219.0133) (xy 121.533919 -219.021406) (xy 121.482105 -219.021406) (xy 121.430928 -219.0133)
			(xy 121.381649 -218.997288) (xy 121.335482 -218.973765) (xy 121.293563 -218.943309) (xy 121.256925 -218.906671)
			(xy 121.226469 -218.864752) (xy 121.202946 -218.818585) (xy 121.186934 -218.769306) (xy 121.178828 -218.718129)
			(xy 121.17832 -218.692222) (xy 119.958104 -218.692222) (xy 119.957596 -218.718129) (xy 119.94949 -218.769306)
			(xy 119.933478 -218.818585) (xy 119.909955 -218.864752) (xy 119.879499 -218.906671) (xy 119.842861 -218.943309)
			(xy 119.800942 -218.973765) (xy 119.754775 -218.997288) (xy 119.705496 -219.0133) (xy 119.654319 -219.021406)
			(xy 119.602505 -219.021406) (xy 119.551328 -219.0133) (xy 119.502049 -218.997288) (xy 119.455882 -218.973765)
			(xy 119.413963 -218.943309) (xy 119.377325 -218.906671) (xy 119.346869 -218.864752) (xy 119.323346 -218.818585)
			(xy 119.307334 -218.769306) (xy 119.299228 -218.718129) (xy 119.29872 -218.692222) (xy 118.078504 -218.692222)
			(xy 118.077996 -218.718129) (xy 118.06989 -218.769306) (xy 118.053878 -218.818585) (xy 118.030355 -218.864752)
			(xy 117.999899 -218.906671) (xy 117.963261 -218.943309) (xy 117.921342 -218.973765) (xy 117.875175 -218.997288)
			(xy 117.825896 -219.0133) (xy 117.774719 -219.021406) (xy 117.722905 -219.021406) (xy 117.671728 -219.0133)
			(xy 117.622449 -218.997288) (xy 117.576282 -218.973765) (xy 117.534363 -218.943309) (xy 117.497725 -218.906671)
			(xy 117.467269 -218.864752) (xy 117.443746 -218.818585) (xy 117.427734 -218.769306) (xy 117.419628 -218.718129)
			(xy 117.41912 -218.692222) (xy 116.198904 -218.692222) (xy 116.19842 -218.718122) (xy 116.190309 -218.769283)
			(xy 116.174291 -218.818544) (xy 116.15076 -218.864691) (xy 116.120296 -218.906587) (xy 116.083651 -218.943198)
			(xy 116.041727 -218.973622) (xy 115.995558 -218.99711) (xy 115.946281 -219.013082) (xy 115.895113 -219.021144)
			(xy 115.869212 -219.02166) (xy 115.839194 -219.021001) (xy 115.780149 -219.010142) (xy 115.751864 -219.00007)
			(xy 115.738544 -218.99545) (xy 115.710475 -218.992939) (xy 115.682789 -218.998198) (xy 115.657595 -219.010826)
			(xy 115.636814 -219.029862) (xy 115.62203 -219.053854) (xy 115.614369 -219.080975) (xy 115.613942 -219.095066)
			(xy 115.613942 -219.257626) (xy 115.633023 -219.274745) (xy 115.666149 -219.313863) (xy 115.692788 -219.357656)
			(xy 115.712292 -219.405061) (xy 115.724186 -219.454921) (xy 115.72818 -219.506025) (xy 115.724178 -219.557128)
			(xy 115.712277 -219.606987) (xy 115.692766 -219.654388) (xy 115.66612 -219.698178) (xy 115.632988 -219.73729)
			(xy 115.613942 -219.75445) (xy 115.613942 -220.319854) (xy 116.47932 -220.319854) (xy 116.479828 -220.293947)
			(xy 116.487934 -220.24277) (xy 116.503946 -220.193491) (xy 116.527469 -220.147324) (xy 116.557925 -220.105405)
			(xy 116.594563 -220.068767) (xy 116.636482 -220.038311) (xy 116.682649 -220.014788) (xy 116.731928 -219.998776)
			(xy 116.783105 -219.99067) (xy 116.834919 -219.99067) (xy 116.886096 -219.998776) (xy 116.935375 -220.014788)
			(xy 116.981542 -220.038311) (xy 117.023461 -220.068767) (xy 117.060099 -220.105405) (xy 117.090555 -220.147324)
			(xy 117.114078 -220.193491) (xy 117.13009 -220.24277) (xy 117.138196 -220.293947) (xy 117.138704 -220.319854)
			(xy 118.35892 -220.319854) (xy 118.359428 -220.293947) (xy 118.367534 -220.24277) (xy 118.383546 -220.193491)
			(xy 118.407069 -220.147324) (xy 118.437525 -220.105405) (xy 118.474163 -220.068767) (xy 118.516082 -220.038311)
			(xy 118.562249 -220.014788) (xy 118.611528 -219.998776) (xy 118.662705 -219.99067) (xy 118.714519 -219.99067)
			(xy 118.765696 -219.998776) (xy 118.814975 -220.014788) (xy 118.861142 -220.038311) (xy 118.903061 -220.068767)
			(xy 118.939699 -220.105405) (xy 118.970155 -220.147324) (xy 118.993678 -220.193491) (xy 119.00969 -220.24277)
			(xy 119.017796 -220.293947) (xy 119.018304 -220.319854) (xy 120.23852 -220.319854) (xy 120.239028 -220.293947)
			(xy 120.247134 -220.24277) (xy 120.263146 -220.193491) (xy 120.286669 -220.147324) (xy 120.317125 -220.105405)
			(xy 120.353763 -220.068767) (xy 120.395682 -220.038311) (xy 120.441849 -220.014788) (xy 120.491128 -219.998776)
			(xy 120.542305 -219.99067) (xy 120.594119 -219.99067) (xy 120.645296 -219.998776) (xy 120.694575 -220.014788)
			(xy 120.740742 -220.038311) (xy 120.782661 -220.068767) (xy 120.819299 -220.105405) (xy 120.849755 -220.147324)
			(xy 120.873278 -220.193491) (xy 120.88929 -220.24277) (xy 120.897396 -220.293947) (xy 120.897904 -220.319854)
			(xy 122.11812 -220.319854) (xy 122.118628 -220.293947) (xy 122.126734 -220.24277) (xy 122.142746 -220.193491)
			(xy 122.166269 -220.147324) (xy 122.196725 -220.105405) (xy 122.233363 -220.068767) (xy 122.275282 -220.038311)
			(xy 122.321449 -220.014788) (xy 122.370728 -219.998776) (xy 122.421905 -219.99067) (xy 122.473719 -219.99067)
			(xy 122.524896 -219.998776) (xy 122.574175 -220.014788) (xy 122.620342 -220.038311) (xy 122.662261 -220.068767)
			(xy 122.698899 -220.105405) (xy 122.729355 -220.147324) (xy 122.752878 -220.193491) (xy 122.76889 -220.24277)
			(xy 122.776996 -220.293947) (xy 122.777504 -220.319854) (xy 123.99772 -220.319854) (xy 123.998228 -220.293947)
			(xy 124.006334 -220.24277) (xy 124.022346 -220.193491) (xy 124.045869 -220.147324) (xy 124.076325 -220.105405)
			(xy 124.112963 -220.068767) (xy 124.154882 -220.038311) (xy 124.201049 -220.014788) (xy 124.250328 -219.998776)
			(xy 124.301505 -219.99067) (xy 124.353319 -219.99067) (xy 124.404496 -219.998776) (xy 124.453775 -220.014788)
			(xy 124.499942 -220.038311) (xy 124.541861 -220.068767) (xy 124.578499 -220.105405) (xy 124.608955 -220.147324)
			(xy 124.632478 -220.193491) (xy 124.64849 -220.24277) (xy 124.656596 -220.293947) (xy 124.657104 -220.319854)
			(xy 125.87732 -220.319854) (xy 125.877828 -220.293947) (xy 125.885934 -220.24277) (xy 125.901946 -220.193491)
			(xy 125.925469 -220.147324) (xy 125.955925 -220.105405) (xy 125.992563 -220.068767) (xy 126.034482 -220.038311)
			(xy 126.080649 -220.014788) (xy 126.129928 -219.998776) (xy 126.181105 -219.99067) (xy 126.232919 -219.99067)
			(xy 126.284096 -219.998776) (xy 126.333375 -220.014788) (xy 126.379542 -220.038311) (xy 126.421461 -220.068767)
			(xy 126.458099 -220.105405) (xy 126.488555 -220.147324) (xy 126.512078 -220.193491) (xy 126.52809 -220.24277)
			(xy 126.536196 -220.293947) (xy 126.536704 -220.319854) (xy 126.536094 -220.347507) (xy 126.526771 -220.402025)
			(xy 126.518162 -220.428312) (xy 126.510542 -220.45041) (xy 126.715774 -220.805756) (xy 126.738634 -220.810074)
			(xy 126.763445 -220.815229) (xy 126.811184 -220.832223) (xy 126.855762 -220.856322) (xy 126.896127 -220.886957)
			(xy 126.93133 -220.923408) (xy 126.96054 -220.964816) (xy 126.983072 -221.010206) (xy 126.998392 -221.058509)
			(xy 127.006142 -221.108587) (xy 127.006604 -221.133924) (xy 127.006096 -221.159811) (xy 126.997997 -221.210949)
			(xy 126.981998 -221.260189) (xy 126.958492 -221.306321) (xy 126.92806 -221.348208) (xy 126.89145 -221.384818)
			(xy 126.849563 -221.41525) (xy 126.803431 -221.438756) (xy 126.754191 -221.454755) (xy 126.703053 -221.462854)
			(xy 126.651279 -221.462854) (xy 126.600141 -221.454755) (xy 126.550901 -221.438756) (xy 126.504769 -221.41525)
			(xy 126.462882 -221.384818) (xy 126.426272 -221.348208) (xy 126.39584 -221.306321) (xy 126.372334 -221.260189)
			(xy 126.356335 -221.210949) (xy 126.348236 -221.159811) (xy 126.347728 -221.133924) (xy 126.348267 -221.106216)
			(xy 126.357456 -221.05157) (xy 126.366016 -221.025212) (xy 126.37389 -221.003114) (xy 126.168912 -220.648022)
			(xy 126.146052 -220.643704) (xy 126.1212 -220.63857) (xy 126.073353 -220.621668) (xy 126.028662 -220.597632)
			(xy 125.988184 -220.567029) (xy 125.952874 -220.530584) (xy 125.923568 -220.489157) (xy 125.900957 -220.443728)
			(xy 125.885577 -220.39537) (xy 125.877791 -220.345226) (xy 125.87732 -220.319854) (xy 124.657104 -220.319854)
			(xy 124.656494 -220.347507) (xy 124.647171 -220.402025) (xy 124.638562 -220.428312) (xy 124.630942 -220.45041)
			(xy 124.836174 -220.805756) (xy 124.859034 -220.810074) (xy 124.883845 -220.815229) (xy 124.931584 -220.832223)
			(xy 124.976162 -220.856322) (xy 125.016527 -220.886957) (xy 125.05173 -220.923408) (xy 125.08094 -220.964816)
			(xy 125.103472 -221.010206) (xy 125.118792 -221.058509) (xy 125.126542 -221.108587) (xy 125.127004 -221.133924)
			(xy 125.126496 -221.159811) (xy 125.118397 -221.210949) (xy 125.102398 -221.260189) (xy 125.078892 -221.306321)
			(xy 125.04846 -221.348208) (xy 125.01185 -221.384818) (xy 124.969963 -221.41525) (xy 124.923831 -221.438756)
			(xy 124.874591 -221.454755) (xy 124.823453 -221.462854) (xy 124.771679 -221.462854) (xy 124.720541 -221.454755)
			(xy 124.671301 -221.438756) (xy 124.625169 -221.41525) (xy 124.583282 -221.384818) (xy 124.546672 -221.348208)
			(xy 124.51624 -221.306321) (xy 124.492734 -221.260189) (xy 124.476735 -221.210949) (xy 124.468636 -221.159811)
			(xy 124.468128 -221.133924) (xy 124.468667 -221.106216) (xy 124.477856 -221.05157) (xy 124.486416 -221.025212)
			(xy 124.49429 -221.003114) (xy 124.289312 -220.648022) (xy 124.266452 -220.643704) (xy 124.2416 -220.63857)
			(xy 124.193753 -220.621668) (xy 124.149062 -220.597632) (xy 124.108584 -220.567029) (xy 124.073274 -220.530584)
			(xy 124.043968 -220.489157) (xy 124.021357 -220.443728) (xy 124.005977 -220.39537) (xy 123.998191 -220.345226)
			(xy 123.99772 -220.319854) (xy 122.777504 -220.319854) (xy 122.776894 -220.347507) (xy 122.767571 -220.402025)
			(xy 122.758962 -220.428312) (xy 122.751342 -220.45041) (xy 122.956574 -220.805756) (xy 122.979434 -220.810074)
			(xy 123.004245 -220.815229) (xy 123.051984 -220.832223) (xy 123.096562 -220.856322) (xy 123.136927 -220.886957)
			(xy 123.17213 -220.923408) (xy 123.20134 -220.964816) (xy 123.223872 -221.010206) (xy 123.239192 -221.058509)
			(xy 123.246942 -221.108587) (xy 123.247404 -221.133924) (xy 123.246896 -221.159811) (xy 123.238797 -221.210949)
			(xy 123.222798 -221.260189) (xy 123.199292 -221.306321) (xy 123.16886 -221.348208) (xy 123.13225 -221.384818)
			(xy 123.090363 -221.41525) (xy 123.044231 -221.438756) (xy 122.994991 -221.454755) (xy 122.943853 -221.462854)
			(xy 122.892079 -221.462854) (xy 122.840941 -221.454755) (xy 122.791701 -221.438756) (xy 122.745569 -221.41525)
			(xy 122.703682 -221.384818) (xy 122.667072 -221.348208) (xy 122.63664 -221.306321) (xy 122.613134 -221.260189)
			(xy 122.597135 -221.210949) (xy 122.589036 -221.159811) (xy 122.588528 -221.133924) (xy 122.589067 -221.106216)
			(xy 122.598256 -221.05157) (xy 122.606816 -221.025212) (xy 122.61469 -221.003114) (xy 122.409712 -220.648022)
			(xy 122.386852 -220.643704) (xy 122.362 -220.63857) (xy 122.314153 -220.621668) (xy 122.269462 -220.597632)
			(xy 122.228984 -220.567029) (xy 122.193674 -220.530584) (xy 122.164368 -220.489157) (xy 122.141757 -220.443728)
			(xy 122.126377 -220.39537) (xy 122.118591 -220.345226) (xy 122.11812 -220.319854) (xy 120.897904 -220.319854)
			(xy 120.897294 -220.347507) (xy 120.887971 -220.402025) (xy 120.879362 -220.428312) (xy 120.871742 -220.45041)
			(xy 121.076974 -220.805756) (xy 121.099834 -220.810074) (xy 121.124645 -220.815229) (xy 121.172384 -220.832223)
			(xy 121.216962 -220.856322) (xy 121.257327 -220.886957) (xy 121.29253 -220.923408) (xy 121.32174 -220.964816)
			(xy 121.344272 -221.010206) (xy 121.359592 -221.058509) (xy 121.367342 -221.108587) (xy 121.367804 -221.133924)
			(xy 121.367296 -221.159811) (xy 121.359197 -221.210949) (xy 121.343198 -221.260189) (xy 121.319692 -221.306321)
			(xy 121.28926 -221.348208) (xy 121.25265 -221.384818) (xy 121.210763 -221.41525) (xy 121.164631 -221.438756)
			(xy 121.115391 -221.454755) (xy 121.064253 -221.462854) (xy 121.012479 -221.462854) (xy 120.961341 -221.454755)
			(xy 120.912101 -221.438756) (xy 120.865969 -221.41525) (xy 120.824082 -221.384818) (xy 120.787472 -221.348208)
			(xy 120.75704 -221.306321) (xy 120.733534 -221.260189) (xy 120.717535 -221.210949) (xy 120.709436 -221.159811)
			(xy 120.708928 -221.133924) (xy 120.709467 -221.106216) (xy 120.718656 -221.05157) (xy 120.727216 -221.025212)
			(xy 120.73509 -221.003114) (xy 120.530112 -220.648022) (xy 120.507252 -220.643704) (xy 120.4824 -220.63857)
			(xy 120.434553 -220.621668) (xy 120.389862 -220.597632) (xy 120.349384 -220.567029) (xy 120.314074 -220.530584)
			(xy 120.284768 -220.489157) (xy 120.262157 -220.443728) (xy 120.246777 -220.39537) (xy 120.238991 -220.345226)
			(xy 120.23852 -220.319854) (xy 119.018304 -220.319854) (xy 119.017694 -220.347507) (xy 119.008371 -220.402025)
			(xy 118.999762 -220.428312) (xy 118.992142 -220.45041) (xy 119.197374 -220.805756) (xy 119.220234 -220.810074)
			(xy 119.245045 -220.815229) (xy 119.292784 -220.832223) (xy 119.337362 -220.856322) (xy 119.377727 -220.886957)
			(xy 119.41293 -220.923408) (xy 119.44214 -220.964816) (xy 119.464672 -221.010206) (xy 119.479992 -221.058509)
			(xy 119.487742 -221.108587) (xy 119.488204 -221.133924) (xy 119.487696 -221.159811) (xy 119.479597 -221.210949)
			(xy 119.463598 -221.260189) (xy 119.440092 -221.306321) (xy 119.40966 -221.348208) (xy 119.37305 -221.384818)
			(xy 119.331163 -221.41525) (xy 119.285031 -221.438756) (xy 119.235791 -221.454755) (xy 119.184653 -221.462854)
			(xy 119.132879 -221.462854) (xy 119.081741 -221.454755) (xy 119.032501 -221.438756) (xy 118.986369 -221.41525)
			(xy 118.944482 -221.384818) (xy 118.907872 -221.348208) (xy 118.87744 -221.306321) (xy 118.853934 -221.260189)
			(xy 118.837935 -221.210949) (xy 118.829836 -221.159811) (xy 118.829328 -221.133924) (xy 118.829867 -221.106216)
			(xy 118.839056 -221.05157) (xy 118.847616 -221.025212) (xy 118.85549 -221.003114) (xy 118.650512 -220.648022)
			(xy 118.627652 -220.643704) (xy 118.6028 -220.63857) (xy 118.554953 -220.621668) (xy 118.510262 -220.597632)
			(xy 118.469784 -220.567029) (xy 118.434474 -220.530584) (xy 118.405168 -220.489157) (xy 118.382557 -220.443728)
			(xy 118.367177 -220.39537) (xy 118.359391 -220.345226) (xy 118.35892 -220.319854) (xy 117.138704 -220.319854)
			(xy 117.138094 -220.347507) (xy 117.128771 -220.402025) (xy 117.120162 -220.428312) (xy 117.112542 -220.45041)
			(xy 117.317774 -220.805756) (xy 117.340634 -220.810074) (xy 117.365445 -220.815229) (xy 117.413184 -220.832223)
			(xy 117.457762 -220.856322) (xy 117.498127 -220.886957) (xy 117.53333 -220.923408) (xy 117.56254 -220.964816)
			(xy 117.585072 -221.010206) (xy 117.600392 -221.058509) (xy 117.608142 -221.108587) (xy 117.608604 -221.133924)
			(xy 117.608096 -221.159811) (xy 117.599997 -221.210949) (xy 117.583998 -221.260189) (xy 117.560492 -221.306321)
			(xy 117.53006 -221.348208) (xy 117.49345 -221.384818) (xy 117.451563 -221.41525) (xy 117.405431 -221.438756)
			(xy 117.356191 -221.454755) (xy 117.305053 -221.462854) (xy 117.253279 -221.462854) (xy 117.202141 -221.454755)
			(xy 117.152901 -221.438756) (xy 117.106769 -221.41525) (xy 117.064882 -221.384818) (xy 117.028272 -221.348208)
			(xy 116.99784 -221.306321) (xy 116.974334 -221.260189) (xy 116.958335 -221.210949) (xy 116.950236 -221.159811)
			(xy 116.949728 -221.133924) (xy 116.950267 -221.106216) (xy 116.959456 -221.05157) (xy 116.968016 -221.025212)
			(xy 116.97589 -221.003114) (xy 116.770912 -220.648022) (xy 116.748052 -220.643704) (xy 116.7232 -220.63857)
			(xy 116.675353 -220.621668) (xy 116.630662 -220.597632) (xy 116.590184 -220.567029) (xy 116.554874 -220.530584)
			(xy 116.525568 -220.489157) (xy 116.502957 -220.443728) (xy 116.487577 -220.39537) (xy 116.479791 -220.345226)
			(xy 116.47932 -220.319854) (xy 115.613942 -220.319854) (xy 115.613942 -220.883734) (xy 115.633238 -220.90093)
			(xy 115.666752 -220.940273) (xy 115.693712 -220.984368) (xy 115.713454 -221.032131) (xy 115.725496 -221.082391)
			(xy 115.729542 -221.133916) (xy 115.725491 -221.185439) (xy 115.713445 -221.235699) (xy 115.693697 -221.28346)
			(xy 115.666734 -221.327552) (xy 115.633216 -221.366892) (xy 115.613942 -221.384114) (xy 115.613942 -221.544896)
			(xy 115.614406 -221.558975) (xy 115.62211 -221.586059) (xy 115.636907 -221.610016) (xy 115.657676 -221.62903)
			(xy 115.682843 -221.64166) (xy 115.7105 -221.646949) (xy 115.738552 -221.644496) (xy 115.751864 -221.639892)
			(xy 115.765502 -221.634811) (xy 115.793484 -221.626801) (xy 115.807744 -221.62389) (xy 115.830604 -221.619572)
			(xy 116.035836 -221.264226) (xy 116.027962 -221.242128) (xy 116.019499 -221.215884) (xy 116.010434 -221.161495)
			(xy 116.009928 -221.133924) (xy 116.010436 -221.108037) (xy 116.018535 -221.056899) (xy 116.034534 -221.007659)
			(xy 116.05804 -220.961527) (xy 116.088472 -220.91964) (xy 116.125082 -220.88303) (xy 116.166969 -220.852598)
			(xy 116.213101 -220.829092) (xy 116.262341 -220.813093) (xy 116.313479 -220.804994) (xy 116.365253 -220.804994)
			(xy 116.416391 -220.813093) (xy 116.465631 -220.829092) (xy 116.511763 -220.852598) (xy 116.55365 -220.88303)
			(xy 116.59026 -220.91964) (xy 116.620692 -220.961527) (xy 116.644198 -221.007659) (xy 116.660197 -221.056899)
			(xy 116.668296 -221.108037) (xy 116.668804 -221.133924) (xy 116.668335 -221.159296) (xy 116.660552 -221.20944)
			(xy 116.645173 -221.257797) (xy 116.622563 -221.303226) (xy 116.593255 -221.34465) (xy 116.557943 -221.381092)
			(xy 116.517462 -221.41169) (xy 116.472768 -221.43572) (xy 116.424919 -221.452614) (xy 116.400072 -221.457774)
			(xy 116.377212 -221.462092) (xy 116.172488 -221.81693) (xy 116.180362 -221.838774) (xy 116.189005 -221.865183)
			(xy 116.198321 -221.919959) (xy 116.198904 -221.94774) (xy 117.41912 -221.94774) (xy 117.419571 -221.922394)
			(xy 117.427352 -221.872302) (xy 117.442706 -221.82399) (xy 117.465272 -221.778597) (xy 117.494518 -221.737192)
			(xy 117.529755 -221.700749) (xy 117.570154 -221.670127) (xy 117.614762 -221.646047) (xy 117.66253 -221.629076)
			(xy 117.687344 -221.62389) (xy 117.710204 -221.619572) (xy 117.915436 -221.264226) (xy 117.907562 -221.242128)
			(xy 117.899098 -221.215883) (xy 117.890025 -221.161495) (xy 117.889528 -221.133924) (xy 117.890036 -221.108037)
			(xy 117.898135 -221.056899) (xy 117.914134 -221.007659) (xy 117.93764 -220.961527) (xy 117.968072 -220.91964)
			(xy 118.004682 -220.88303) (xy 118.046569 -220.852598) (xy 118.092701 -220.829092) (xy 118.141941 -220.813093)
			(xy 118.193079 -220.804994) (xy 118.244853 -220.804994) (xy 118.295991 -220.813093) (xy 118.345231 -220.829092)
			(xy 118.391363 -220.852598) (xy 118.43325 -220.88303) (xy 118.46986 -220.91964) (xy 118.500292 -220.961527)
			(xy 118.523798 -221.007659) (xy 118.539797 -221.056899) (xy 118.547896 -221.108037) (xy 118.548404 -221.133924)
			(xy 118.547948 -221.159299) (xy 118.540176 -221.20945) (xy 118.524804 -221.257815) (xy 118.502197 -221.303251)
			(xy 118.472889 -221.344682) (xy 118.437573 -221.381128) (xy 118.397085 -221.411727) (xy 118.352384 -221.435754)
			(xy 118.304526 -221.452641) (xy 118.279672 -221.457774) (xy 118.256812 -221.462092) (xy 118.052088 -221.81693)
			(xy 118.059962 -221.838774) (xy 118.068619 -221.865179) (xy 118.077932 -221.919958) (xy 118.078504 -221.94774)
			(xy 121.17832 -221.94774) (xy 121.178771 -221.922394) (xy 121.186552 -221.872302) (xy 121.201906 -221.82399)
			(xy 121.224472 -221.778597) (xy 121.253718 -221.737192) (xy 121.288955 -221.700749) (xy 121.329354 -221.670127)
			(xy 121.373962 -221.646047) (xy 121.42173 -221.629076) (xy 121.446544 -221.62389) (xy 121.469404 -221.619572)
			(xy 121.674636 -221.264226) (xy 121.666762 -221.242128) (xy 121.658298 -221.215883) (xy 121.649225 -221.161495)
			(xy 121.648728 -221.133924) (xy 121.649236 -221.108037) (xy 121.657335 -221.056899) (xy 121.673334 -221.007659)
			(xy 121.69684 -220.961527) (xy 121.727272 -220.91964) (xy 121.763882 -220.88303) (xy 121.805769 -220.852598)
			(xy 121.851901 -220.829092) (xy 121.901141 -220.813093) (xy 121.952279 -220.804994) (xy 122.004053 -220.804994)
			(xy 122.055191 -220.813093) (xy 122.104431 -220.829092) (xy 122.150563 -220.852598) (xy 122.19245 -220.88303)
			(xy 122.22906 -220.91964) (xy 122.259492 -220.961527) (xy 122.282998 -221.007659) (xy 122.298997 -221.056899)
			(xy 122.307096 -221.108037) (xy 122.307604 -221.133924) (xy 122.307148 -221.159299) (xy 122.299376 -221.20945)
			(xy 122.284004 -221.257815) (xy 122.261397 -221.303251) (xy 122.232089 -221.344682) (xy 122.196773 -221.381128)
			(xy 122.156285 -221.411727) (xy 122.111584 -221.435754) (xy 122.063726 -221.452641) (xy 122.038872 -221.457774)
			(xy 122.016012 -221.462092) (xy 121.811288 -221.81693) (xy 121.819162 -221.838774) (xy 121.827819 -221.865179)
			(xy 121.837132 -221.919958) (xy 121.837704 -221.94774) (xy 123.05792 -221.94774) (xy 123.058371 -221.922394)
			(xy 123.066152 -221.872302) (xy 123.081506 -221.82399) (xy 123.104072 -221.778597) (xy 123.133318 -221.737192)
			(xy 123.168555 -221.700749) (xy 123.208954 -221.670127) (xy 123.253562 -221.646047) (xy 123.30133 -221.629076)
			(xy 123.326144 -221.62389) (xy 123.349004 -221.619572) (xy 123.554236 -221.264226) (xy 123.546362 -221.242128)
			(xy 123.537898 -221.215883) (xy 123.528825 -221.161495) (xy 123.528328 -221.133924) (xy 123.528836 -221.108037)
			(xy 123.536935 -221.056899) (xy 123.552934 -221.007659) (xy 123.57644 -220.961527) (xy 123.606872 -220.91964)
			(xy 123.643482 -220.88303) (xy 123.685369 -220.852598) (xy 123.731501 -220.829092) (xy 123.780741 -220.813093)
			(xy 123.831879 -220.804994) (xy 123.883653 -220.804994) (xy 123.934791 -220.813093) (xy 123.984031 -220.829092)
			(xy 124.030163 -220.852598) (xy 124.07205 -220.88303) (xy 124.10866 -220.91964) (xy 124.139092 -220.961527)
			(xy 124.162598 -221.007659) (xy 124.178597 -221.056899) (xy 124.186696 -221.108037) (xy 124.187204 -221.133924)
			(xy 124.186748 -221.159299) (xy 124.178976 -221.20945) (xy 124.163604 -221.257815) (xy 124.140997 -221.303251)
			(xy 124.111689 -221.344682) (xy 124.076373 -221.381128) (xy 124.035885 -221.411727) (xy 123.991184 -221.435754)
			(xy 123.943326 -221.452641) (xy 123.918472 -221.457774) (xy 123.895612 -221.462092) (xy 123.690888 -221.81693)
			(xy 123.698762 -221.838774) (xy 123.707419 -221.865179) (xy 123.716732 -221.919958) (xy 123.717304 -221.94774)
			(xy 124.93752 -221.94774) (xy 124.937971 -221.922394) (xy 124.945752 -221.872302) (xy 124.961106 -221.82399)
			(xy 124.983672 -221.778597) (xy 125.012918 -221.737192) (xy 125.048155 -221.700749) (xy 125.088554 -221.670127)
			(xy 125.133162 -221.646047) (xy 125.18093 -221.629076) (xy 125.205744 -221.62389) (xy 125.228604 -221.619572)
			(xy 125.433836 -221.264226) (xy 125.425962 -221.242128) (xy 125.417498 -221.215883) (xy 125.408425 -221.161495)
			(xy 125.407928 -221.133924) (xy 125.408436 -221.108037) (xy 125.416535 -221.056899) (xy 125.432534 -221.007659)
			(xy 125.45604 -220.961527) (xy 125.486472 -220.91964) (xy 125.523082 -220.88303) (xy 125.564969 -220.852598)
			(xy 125.611101 -220.829092) (xy 125.660341 -220.813093) (xy 125.711479 -220.804994) (xy 125.763253 -220.804994)
			(xy 125.814391 -220.813093) (xy 125.863631 -220.829092) (xy 125.909763 -220.852598) (xy 125.95165 -220.88303)
			(xy 125.98826 -220.91964) (xy 126.018692 -220.961527) (xy 126.042198 -221.007659) (xy 126.058197 -221.056899)
			(xy 126.066296 -221.108037) (xy 126.066804 -221.133924) (xy 126.066348 -221.159299) (xy 126.058576 -221.20945)
			(xy 126.043204 -221.257815) (xy 126.020597 -221.303251) (xy 125.991289 -221.344682) (xy 125.955973 -221.381128)
			(xy 125.915485 -221.411727) (xy 125.870784 -221.435754) (xy 125.822926 -221.452641) (xy 125.798072 -221.457774)
			(xy 125.775212 -221.462092) (xy 125.570488 -221.81693) (xy 125.578362 -221.838774) (xy 125.587019 -221.865179)
			(xy 125.596332 -221.919958) (xy 125.596904 -221.94774) (xy 125.596396 -221.973647) (xy 125.58829 -222.024824)
			(xy 125.572278 -222.074103) (xy 125.548755 -222.12027) (xy 125.518299 -222.162189) (xy 125.481661 -222.198827)
			(xy 125.439742 -222.229283) (xy 125.393575 -222.252806) (xy 125.344296 -222.268818) (xy 125.293119 -222.276924)
			(xy 125.241305 -222.276924) (xy 125.190128 -222.268818) (xy 125.140849 -222.252806) (xy 125.094682 -222.229283)
			(xy 125.052763 -222.198827) (xy 125.016125 -222.162189) (xy 124.985669 -222.12027) (xy 124.962146 -222.074103)
			(xy 124.946134 -222.024824) (xy 124.938028 -221.973647) (xy 124.93752 -221.94774) (xy 123.717304 -221.94774)
			(xy 123.716796 -221.973647) (xy 123.70869 -222.024824) (xy 123.692678 -222.074103) (xy 123.669155 -222.12027)
			(xy 123.638699 -222.162189) (xy 123.602061 -222.198827) (xy 123.560142 -222.229283) (xy 123.513975 -222.252806)
			(xy 123.464696 -222.268818) (xy 123.413519 -222.276924) (xy 123.361705 -222.276924) (xy 123.310528 -222.268818)
			(xy 123.261249 -222.252806) (xy 123.215082 -222.229283) (xy 123.173163 -222.198827) (xy 123.136525 -222.162189)
			(xy 123.106069 -222.12027) (xy 123.082546 -222.074103) (xy 123.066534 -222.024824) (xy 123.058428 -221.973647)
			(xy 123.05792 -221.94774) (xy 121.837704 -221.94774) (xy 121.837196 -221.973647) (xy 121.82909 -222.024824)
			(xy 121.813078 -222.074103) (xy 121.789555 -222.12027) (xy 121.759099 -222.162189) (xy 121.722461 -222.198827)
			(xy 121.680542 -222.229283) (xy 121.634375 -222.252806) (xy 121.585096 -222.268818) (xy 121.533919 -222.276924)
			(xy 121.482105 -222.276924) (xy 121.430928 -222.268818) (xy 121.381649 -222.252806) (xy 121.335482 -222.229283)
			(xy 121.293563 -222.198827) (xy 121.256925 -222.162189) (xy 121.226469 -222.12027) (xy 121.202946 -222.074103)
			(xy 121.186934 -222.024824) (xy 121.178828 -221.973647) (xy 121.17832 -221.94774) (xy 118.078504 -221.94774)
			(xy 118.077996 -221.973647) (xy 118.06989 -222.024824) (xy 118.053878 -222.074103) (xy 118.030355 -222.12027)
			(xy 117.999899 -222.162189) (xy 117.963261 -222.198827) (xy 117.921342 -222.229283) (xy 117.875175 -222.252806)
			(xy 117.825896 -222.268818) (xy 117.774719 -222.276924) (xy 117.722905 -222.276924) (xy 117.671728 -222.268818)
			(xy 117.622449 -222.252806) (xy 117.576282 -222.229283) (xy 117.534363 -222.198827) (xy 117.497725 -222.162189)
			(xy 117.467269 -222.12027) (xy 117.443746 -222.074103) (xy 117.427734 -222.024824) (xy 117.419628 -221.973647)
			(xy 117.41912 -221.94774) (xy 116.198904 -221.94774) (xy 116.198393 -221.973646) (xy 116.190283 -222.024818)
			(xy 116.174268 -222.074092) (xy 116.150742 -222.120255) (xy 116.120286 -222.162169) (xy 116.083648 -222.198804)
			(xy 116.041731 -222.229257) (xy 115.995567 -222.252778) (xy 115.946291 -222.268789) (xy 115.895118 -222.276895)
			(xy 115.869212 -222.277432) (xy 115.839186 -222.276697) (xy 115.780145 -222.265701) (xy 115.751864 -222.255588)
			(xy 115.738541 -222.25097) (xy 115.710466 -222.248462) (xy 115.682774 -222.253721) (xy 115.657573 -222.266348)
			(xy 115.636782 -222.28538) (xy 115.621983 -222.30937) (xy 115.614303 -222.33649) (xy 115.613942 -222.350584)
			(xy 115.613942 -222.513144) (xy 115.633029 -222.530263) (xy 115.666168 -222.569383) (xy 115.69282 -222.61318)
			(xy 115.712335 -222.66059) (xy 115.724239 -222.710458) (xy 115.728243 -222.761571) (xy 115.724248 -222.812685)
			(xy 115.712353 -222.862555) (xy 115.692846 -222.909968) (xy 115.666202 -222.953771) (xy 115.63307 -222.992896)
			(xy 115.613942 -223.009968) (xy 115.613942 -224.139252) (xy 115.631661 -224.154976) (xy 115.662847 -224.190635)
			(xy 115.6886 -224.230396) (xy 115.70839 -224.273437) (xy 115.721808 -224.318869) (xy 115.728576 -224.365756)
			(xy 115.729004 -224.389442) (xy 116.009928 -224.389442) (xy 116.010335 -224.364105) (xy 116.018097 -224.314028)
			(xy 116.033429 -224.265728) (xy 116.05597 -224.220343) (xy 116.085189 -224.17894) (xy 116.120399 -224.142496)
			(xy 116.16077 -224.111867) (xy 116.205352 -224.087776) (xy 116.253095 -224.070789) (xy 116.277898 -224.065592)
			(xy 116.300758 -224.061274) (xy 116.505482 -223.706436) (xy 116.497862 -223.684338) (xy 116.489231 -223.657991)
			(xy 116.47991 -223.603344) (xy 116.47932 -223.575626) (xy 116.479828 -223.549719) (xy 116.487934 -223.498542)
			(xy 116.503946 -223.449263) (xy 116.527469 -223.403096) (xy 116.557925 -223.361177) (xy 116.594563 -223.324539)
			(xy 116.636482 -223.294083) (xy 116.682649 -223.27056) (xy 116.731928 -223.254548) (xy 116.783105 -223.246442)
			(xy 116.834919 -223.246442) (xy 116.886096 -223.254548) (xy 116.935375 -223.27056) (xy 116.981542 -223.294083)
			(xy 117.023461 -223.324539) (xy 117.060099 -223.361177) (xy 117.090555 -223.403096) (xy 117.114078 -223.449263)
			(xy 117.13009 -223.498542) (xy 117.138196 -223.549719) (xy 117.138704 -223.575626) (xy 117.138287 -223.600992)
			(xy 117.130534 -223.651127) (xy 117.115185 -223.69948) (xy 117.092603 -223.744908) (xy 117.063322 -223.786336)
			(xy 117.028034 -223.822783) (xy 116.987575 -223.853388) (xy 116.942901 -223.877427) (xy 116.895069 -223.894332)
			(xy 116.870226 -223.899476) (xy 116.847366 -223.903794) (xy 116.642642 -224.258632) (xy 116.650516 -224.280476)
			(xy 116.65909 -224.306896) (xy 116.66829 -224.36167) (xy 116.668804 -224.389442) (xy 116.949728 -224.389442)
			(xy 116.950236 -224.363555) (xy 116.958335 -224.312417) (xy 116.974334 -224.263177) (xy 116.99784 -224.217045)
			(xy 117.028272 -224.175158) (xy 117.064882 -224.138548) (xy 117.106769 -224.108116) (xy 117.152901 -224.08461)
			(xy 117.202141 -224.068611) (xy 117.253279 -224.060512) (xy 117.305053 -224.060512) (xy 117.356191 -224.068611)
			(xy 117.405431 -224.08461) (xy 117.451563 -224.108116) (xy 117.49345 -224.138548) (xy 117.53006 -224.175158)
			(xy 117.560492 -224.217045) (xy 117.583998 -224.263177) (xy 117.599997 -224.312417) (xy 117.608096 -224.363555)
			(xy 117.608604 -224.389442) (xy 117.889528 -224.389442) (xy 117.889935 -224.364105) (xy 117.897697 -224.314028)
			(xy 117.913029 -224.265728) (xy 117.93557 -224.220343) (xy 117.964789 -224.17894) (xy 117.999999 -224.142496)
			(xy 118.04037 -224.111867) (xy 118.084952 -224.087776) (xy 118.132695 -224.070789) (xy 118.157498 -224.065592)
			(xy 118.180358 -224.061274) (xy 118.385082 -223.706436) (xy 118.377462 -223.684338) (xy 118.368831 -223.657991)
			(xy 118.35951 -223.603344) (xy 118.35892 -223.575626) (xy 118.359428 -223.549719) (xy 118.367534 -223.498542)
			(xy 118.383546 -223.449263) (xy 118.407069 -223.403096) (xy 118.437525 -223.361177) (xy 118.474163 -223.324539)
			(xy 118.516082 -223.294083) (xy 118.562249 -223.27056) (xy 118.611528 -223.254548) (xy 118.662705 -223.246442)
			(xy 118.714519 -223.246442) (xy 118.765696 -223.254548) (xy 118.814975 -223.27056) (xy 118.861142 -223.294083)
			(xy 118.903061 -223.324539) (xy 118.939699 -223.361177) (xy 118.970155 -223.403096) (xy 118.993678 -223.449263)
			(xy 119.00969 -223.498542) (xy 119.017796 -223.549719) (xy 119.018304 -223.575626) (xy 119.017887 -223.600992)
			(xy 119.010134 -223.651127) (xy 118.994785 -223.69948) (xy 118.972203 -223.744908) (xy 118.942922 -223.786336)
			(xy 118.907634 -223.822783) (xy 118.867175 -223.853388) (xy 118.822501 -223.877427) (xy 118.774669 -223.894332)
			(xy 118.749826 -223.899476) (xy 118.726966 -223.903794) (xy 118.522242 -224.258632) (xy 118.530116 -224.280476)
			(xy 118.53869 -224.306896) (xy 118.54789 -224.36167) (xy 118.548404 -224.389442) (xy 118.829328 -224.389442)
			(xy 118.829836 -224.363555) (xy 118.837935 -224.312417) (xy 118.853934 -224.263177) (xy 118.87744 -224.217045)
			(xy 118.907872 -224.175158) (xy 118.944482 -224.138548) (xy 118.986369 -224.108116) (xy 119.032501 -224.08461)
			(xy 119.081741 -224.068611) (xy 119.132879 -224.060512) (xy 119.184653 -224.060512) (xy 119.235791 -224.068611)
			(xy 119.285031 -224.08461) (xy 119.331163 -224.108116) (xy 119.37305 -224.138548) (xy 119.40966 -224.175158)
			(xy 119.440092 -224.217045) (xy 119.463598 -224.263177) (xy 119.479597 -224.312417) (xy 119.487696 -224.363555)
			(xy 119.488204 -224.389442) (xy 119.769128 -224.389442) (xy 119.769535 -224.364105) (xy 119.777297 -224.314028)
			(xy 119.792629 -224.265728) (xy 119.81517 -224.220343) (xy 119.844389 -224.17894) (xy 119.879599 -224.142496)
			(xy 119.91997 -224.111867) (xy 119.964552 -224.087776) (xy 120.012295 -224.070789) (xy 120.037098 -224.065592)
			(xy 120.059958 -224.061274) (xy 120.264682 -223.706436) (xy 120.257062 -223.684338) (xy 120.248431 -223.657991)
			(xy 120.23911 -223.603344) (xy 120.23852 -223.575626) (xy 120.239028 -223.549719) (xy 120.247134 -223.498542)
			(xy 120.263146 -223.449263) (xy 120.286669 -223.403096) (xy 120.317125 -223.361177) (xy 120.353763 -223.324539)
			(xy 120.395682 -223.294083) (xy 120.441849 -223.27056) (xy 120.491128 -223.254548) (xy 120.542305 -223.246442)
			(xy 120.594119 -223.246442) (xy 120.645296 -223.254548) (xy 120.694575 -223.27056) (xy 120.740742 -223.294083)
			(xy 120.782661 -223.324539) (xy 120.819299 -223.361177) (xy 120.849755 -223.403096) (xy 120.873278 -223.449263)
			(xy 120.88929 -223.498542) (xy 120.897396 -223.549719) (xy 120.897904 -223.575626) (xy 120.897487 -223.600992)
			(xy 120.889734 -223.651127) (xy 120.874385 -223.69948) (xy 120.851803 -223.744908) (xy 120.822522 -223.786336)
			(xy 120.787234 -223.822783) (xy 120.746775 -223.853388) (xy 120.702101 -223.877427) (xy 120.654269 -223.894332)
			(xy 120.629426 -223.899476) (xy 120.606566 -223.903794) (xy 120.401842 -224.258632) (xy 120.409716 -224.280476)
			(xy 120.41829 -224.306896) (xy 120.42749 -224.36167) (xy 120.428004 -224.389442) (xy 120.708928 -224.389442)
			(xy 120.709436 -224.363555) (xy 120.717535 -224.312417) (xy 120.733534 -224.263177) (xy 120.75704 -224.217045)
			(xy 120.787472 -224.175158) (xy 120.824082 -224.138548) (xy 120.865969 -224.108116) (xy 120.912101 -224.08461)
			(xy 120.961341 -224.068611) (xy 121.012479 -224.060512) (xy 121.064253 -224.060512) (xy 121.115391 -224.068611)
			(xy 121.164631 -224.08461) (xy 121.210763 -224.108116) (xy 121.25265 -224.138548) (xy 121.28926 -224.175158)
			(xy 121.319692 -224.217045) (xy 121.343198 -224.263177) (xy 121.359197 -224.312417) (xy 121.367296 -224.363555)
			(xy 121.367804 -224.389442) (xy 121.648728 -224.389442) (xy 121.649135 -224.364105) (xy 121.656897 -224.314028)
			(xy 121.672229 -224.265728) (xy 121.69477 -224.220343) (xy 121.723989 -224.17894) (xy 121.759199 -224.142496)
			(xy 121.79957 -224.111867) (xy 121.844152 -224.087776) (xy 121.891895 -224.070789) (xy 121.916698 -224.065592)
			(xy 121.939558 -224.061274) (xy 122.144282 -223.706436) (xy 122.136662 -223.684338) (xy 122.128031 -223.657991)
			(xy 122.11871 -223.603344) (xy 122.11812 -223.575626) (xy 122.118628 -223.549719) (xy 122.126734 -223.498542)
			(xy 122.142746 -223.449263) (xy 122.166269 -223.403096) (xy 122.196725 -223.361177) (xy 122.233363 -223.324539)
			(xy 122.275282 -223.294083) (xy 122.321449 -223.27056) (xy 122.370728 -223.254548) (xy 122.421905 -223.246442)
			(xy 122.473719 -223.246442) (xy 122.524896 -223.254548) (xy 122.574175 -223.27056) (xy 122.620342 -223.294083)
			(xy 122.662261 -223.324539) (xy 122.698899 -223.361177) (xy 122.729355 -223.403096) (xy 122.752878 -223.449263)
			(xy 122.76889 -223.498542) (xy 122.776996 -223.549719) (xy 122.777504 -223.575626) (xy 122.777087 -223.600992)
			(xy 122.769334 -223.651127) (xy 122.753985 -223.69948) (xy 122.731403 -223.744908) (xy 122.702122 -223.786336)
			(xy 122.666834 -223.822783) (xy 122.626375 -223.853388) (xy 122.581701 -223.877427) (xy 122.533869 -223.894332)
			(xy 122.509026 -223.899476) (xy 122.486166 -223.903794) (xy 122.281442 -224.258632) (xy 122.289316 -224.280476)
			(xy 122.29789 -224.306896) (xy 122.30709 -224.36167) (xy 122.307604 -224.389442) (xy 122.588528 -224.389442)
			(xy 122.589036 -224.363555) (xy 122.597135 -224.312417) (xy 122.613134 -224.263177) (xy 122.63664 -224.217045)
			(xy 122.667072 -224.175158) (xy 122.703682 -224.138548) (xy 122.745569 -224.108116) (xy 122.791701 -224.08461)
			(xy 122.840941 -224.068611) (xy 122.892079 -224.060512) (xy 122.943853 -224.060512) (xy 122.994991 -224.068611)
			(xy 123.044231 -224.08461) (xy 123.090363 -224.108116) (xy 123.13225 -224.138548) (xy 123.16886 -224.175158)
			(xy 123.199292 -224.217045) (xy 123.222798 -224.263177) (xy 123.238797 -224.312417) (xy 123.246896 -224.363555)
			(xy 123.247404 -224.389442) (xy 123.528328 -224.389442) (xy 123.528735 -224.364105) (xy 123.536497 -224.314028)
			(xy 123.551829 -224.265728) (xy 123.57437 -224.220343) (xy 123.603589 -224.17894) (xy 123.638799 -224.142496)
			(xy 123.67917 -224.111867) (xy 123.723752 -224.087776) (xy 123.771495 -224.070789) (xy 123.796298 -224.065592)
			(xy 123.819158 -224.061274) (xy 124.023882 -223.706436) (xy 124.016262 -223.684338) (xy 124.007631 -223.657991)
			(xy 123.99831 -223.603344) (xy 123.99772 -223.575626) (xy 123.998228 -223.549719) (xy 124.006334 -223.498542)
			(xy 124.022346 -223.449263) (xy 124.045869 -223.403096) (xy 124.076325 -223.361177) (xy 124.112963 -223.324539)
			(xy 124.154882 -223.294083) (xy 124.201049 -223.27056) (xy 124.250328 -223.254548) (xy 124.301505 -223.246442)
			(xy 124.353319 -223.246442) (xy 124.404496 -223.254548) (xy 124.453775 -223.27056) (xy 124.499942 -223.294083)
			(xy 124.541861 -223.324539) (xy 124.578499 -223.361177) (xy 124.608955 -223.403096) (xy 124.632478 -223.449263)
			(xy 124.64849 -223.498542) (xy 124.656596 -223.549719) (xy 124.657104 -223.575626) (xy 124.656687 -223.600992)
			(xy 124.648934 -223.651127) (xy 124.633585 -223.69948) (xy 124.611003 -223.744908) (xy 124.581722 -223.786336)
			(xy 124.546434 -223.822783) (xy 124.505975 -223.853388) (xy 124.461301 -223.877427) (xy 124.413469 -223.894332)
			(xy 124.388626 -223.899476) (xy 124.365766 -223.903794) (xy 124.161042 -224.258632) (xy 124.168916 -224.280476)
			(xy 124.17749 -224.306896) (xy 124.18669 -224.36167) (xy 124.187204 -224.389442) (xy 124.468128 -224.389442)
			(xy 124.468636 -224.363555) (xy 124.476735 -224.312417) (xy 124.492734 -224.263177) (xy 124.51624 -224.217045)
			(xy 124.546672 -224.175158) (xy 124.583282 -224.138548) (xy 124.625169 -224.108116) (xy 124.671301 -224.08461)
			(xy 124.720541 -224.068611) (xy 124.771679 -224.060512) (xy 124.823453 -224.060512) (xy 124.874591 -224.068611)
			(xy 124.923831 -224.08461) (xy 124.969963 -224.108116) (xy 125.01185 -224.138548) (xy 125.04846 -224.175158)
			(xy 125.078892 -224.217045) (xy 125.102398 -224.263177) (xy 125.118397 -224.312417) (xy 125.126496 -224.363555)
			(xy 125.127004 -224.389442) (xy 125.407928 -224.389442) (xy 125.408335 -224.364105) (xy 125.416097 -224.314028)
			(xy 125.431429 -224.265728) (xy 125.45397 -224.220343) (xy 125.483189 -224.17894) (xy 125.518399 -224.142496)
			(xy 125.55877 -224.111867) (xy 125.603352 -224.087776) (xy 125.651095 -224.070789) (xy 125.675898 -224.065592)
			(xy 125.698758 -224.061274) (xy 125.903482 -223.706436) (xy 125.895862 -223.684338) (xy 125.887231 -223.657991)
			(xy 125.87791 -223.603344) (xy 125.87732 -223.575626) (xy 125.877828 -223.549719) (xy 125.885934 -223.498542)
			(xy 125.901946 -223.449263) (xy 125.925469 -223.403096) (xy 125.955925 -223.361177) (xy 125.992563 -223.324539)
			(xy 126.034482 -223.294083) (xy 126.080649 -223.27056) (xy 126.129928 -223.254548) (xy 126.181105 -223.246442)
			(xy 126.232919 -223.246442) (xy 126.284096 -223.254548) (xy 126.333375 -223.27056) (xy 126.379542 -223.294083)
			(xy 126.421461 -223.324539) (xy 126.458099 -223.361177) (xy 126.488555 -223.403096) (xy 126.512078 -223.449263)
			(xy 126.52809 -223.498542) (xy 126.536196 -223.549719) (xy 126.536704 -223.575626) (xy 126.536287 -223.600992)
			(xy 126.528534 -223.651127) (xy 126.513185 -223.69948) (xy 126.490603 -223.744908) (xy 126.461322 -223.786336)
			(xy 126.426034 -223.822783) (xy 126.385575 -223.853388) (xy 126.340901 -223.877427) (xy 126.293069 -223.894332)
			(xy 126.268226 -223.899476) (xy 126.245366 -223.903794) (xy 126.040642 -224.258632) (xy 126.048516 -224.280476)
			(xy 126.05709 -224.306896) (xy 126.06629 -224.36167) (xy 126.066804 -224.389442) (xy 126.066296 -224.415329)
			(xy 126.058197 -224.466467) (xy 126.042198 -224.515707) (xy 126.018692 -224.561839) (xy 125.98826 -224.603726)
			(xy 125.95165 -224.640336) (xy 125.909763 -224.670768) (xy 125.863631 -224.694274) (xy 125.814391 -224.710273)
			(xy 125.763253 -224.718372) (xy 125.711479 -224.718372) (xy 125.660341 -224.710273) (xy 125.611101 -224.694274)
			(xy 125.564969 -224.670768) (xy 125.523082 -224.640336) (xy 125.486472 -224.603726) (xy 125.45604 -224.561839)
			(xy 125.432534 -224.515707) (xy 125.416535 -224.466467) (xy 125.408436 -224.415329) (xy 125.407928 -224.389442)
			(xy 125.127004 -224.389442) (xy 125.12646 -224.417149) (xy 125.117274 -224.471796) (xy 125.108716 -224.498154)
			(xy 125.100842 -224.520252) (xy 125.30582 -224.87509) (xy 125.32868 -224.879408) (xy 125.353509 -224.884542)
			(xy 125.401288 -224.901501) (xy 125.445908 -224.925578) (xy 125.486314 -224.956202) (xy 125.521554 -224.992654)
			(xy 125.550797 -225.034071) (xy 125.573352 -225.079478) (xy 125.588688 -225.127804) (xy 125.596443 -225.177908)
			(xy 125.596904 -225.203258) (xy 125.596396 -225.229165) (xy 125.58829 -225.280342) (xy 125.572278 -225.329621)
			(xy 125.548755 -225.375788) (xy 125.518299 -225.417707) (xy 125.481661 -225.454345) (xy 125.439742 -225.484801)
			(xy 125.393575 -225.508324) (xy 125.344296 -225.524336) (xy 125.293119 -225.532442) (xy 125.241305 -225.532442)
			(xy 125.190128 -225.524336) (xy 125.140849 -225.508324) (xy 125.094682 -225.484801) (xy 125.052763 -225.454345)
			(xy 125.016125 -225.417707) (xy 124.985669 -225.375788) (xy 124.962146 -225.329621) (xy 124.946134 -225.280342)
			(xy 124.938028 -225.229165) (xy 124.93752 -225.203258) (xy 124.938127 -225.175541) (xy 124.947442 -225.120895)
			(xy 124.956062 -225.094546) (xy 124.963936 -225.072448) (xy 124.758958 -224.71761) (xy 124.736098 -224.713292)
			(xy 124.711285 -224.708145) (xy 124.663543 -224.691153) (xy 124.618963 -224.667056) (xy 124.578596 -224.63642)
			(xy 124.543393 -224.599968) (xy 124.514182 -224.558558) (xy 124.491652 -224.513166) (xy 124.476334 -224.46486)
			(xy 124.468588 -224.41478) (xy 124.468128 -224.389442) (xy 124.187204 -224.389442) (xy 124.186696 -224.415329)
			(xy 124.178597 -224.466467) (xy 124.162598 -224.515707) (xy 124.139092 -224.561839) (xy 124.10866 -224.603726)
			(xy 124.07205 -224.640336) (xy 124.030163 -224.670768) (xy 123.984031 -224.694274) (xy 123.934791 -224.710273)
			(xy 123.883653 -224.718372) (xy 123.831879 -224.718372) (xy 123.780741 -224.710273) (xy 123.731501 -224.694274)
			(xy 123.685369 -224.670768) (xy 123.643482 -224.640336) (xy 123.606872 -224.603726) (xy 123.57644 -224.561839)
			(xy 123.552934 -224.515707) (xy 123.536935 -224.466467) (xy 123.528836 -224.415329) (xy 123.528328 -224.389442)
			(xy 123.247404 -224.389442) (xy 123.24686 -224.417149) (xy 123.237674 -224.471796) (xy 123.229116 -224.498154)
			(xy 123.221242 -224.520252) (xy 123.42622 -224.87509) (xy 123.44908 -224.879408) (xy 123.473909 -224.884542)
			(xy 123.521688 -224.901501) (xy 123.566308 -224.925578) (xy 123.606714 -224.956202) (xy 123.641954 -224.992654)
			(xy 123.671197 -225.034071) (xy 123.693752 -225.079478) (xy 123.709088 -225.127804) (xy 123.716843 -225.177908)
			(xy 123.717304 -225.203258) (xy 123.716796 -225.229165) (xy 123.70869 -225.280342) (xy 123.692678 -225.329621)
			(xy 123.669155 -225.375788) (xy 123.638699 -225.417707) (xy 123.602061 -225.454345) (xy 123.560142 -225.484801)
			(xy 123.513975 -225.508324) (xy 123.464696 -225.524336) (xy 123.413519 -225.532442) (xy 123.361705 -225.532442)
			(xy 123.310528 -225.524336) (xy 123.261249 -225.508324) (xy 123.215082 -225.484801) (xy 123.173163 -225.454345)
			(xy 123.136525 -225.417707) (xy 123.106069 -225.375788) (xy 123.082546 -225.329621) (xy 123.066534 -225.280342)
			(xy 123.058428 -225.229165) (xy 123.05792 -225.203258) (xy 123.058527 -225.175541) (xy 123.067842 -225.120895)
			(xy 123.076462 -225.094546) (xy 123.084336 -225.072448) (xy 122.879358 -224.71761) (xy 122.856498 -224.713292)
			(xy 122.831685 -224.708145) (xy 122.783943 -224.691153) (xy 122.739363 -224.667056) (xy 122.698996 -224.63642)
			(xy 122.663793 -224.599968) (xy 122.634582 -224.558558) (xy 122.612052 -224.513166) (xy 122.596734 -224.46486)
			(xy 122.588988 -224.41478) (xy 122.588528 -224.389442) (xy 122.307604 -224.389442) (xy 122.307096 -224.415329)
			(xy 122.298997 -224.466467) (xy 122.282998 -224.515707) (xy 122.259492 -224.561839) (xy 122.22906 -224.603726)
			(xy 122.19245 -224.640336) (xy 122.150563 -224.670768) (xy 122.104431 -224.694274) (xy 122.055191 -224.710273)
			(xy 122.004053 -224.718372) (xy 121.952279 -224.718372) (xy 121.901141 -224.710273) (xy 121.851901 -224.694274)
			(xy 121.805769 -224.670768) (xy 121.763882 -224.640336) (xy 121.727272 -224.603726) (xy 121.69684 -224.561839)
			(xy 121.673334 -224.515707) (xy 121.657335 -224.466467) (xy 121.649236 -224.415329) (xy 121.648728 -224.389442)
			(xy 121.367804 -224.389442) (xy 121.36726 -224.417149) (xy 121.358074 -224.471796) (xy 121.349516 -224.498154)
			(xy 121.341642 -224.520252) (xy 121.54662 -224.87509) (xy 121.56948 -224.879408) (xy 121.594309 -224.884542)
			(xy 121.642088 -224.901501) (xy 121.686708 -224.925578) (xy 121.727114 -224.956202) (xy 121.762354 -224.992654)
			(xy 121.791597 -225.034071) (xy 121.814152 -225.079478) (xy 121.829488 -225.127804) (xy 121.837243 -225.177908)
			(xy 121.837704 -225.203258) (xy 121.837196 -225.229165) (xy 121.82909 -225.280342) (xy 121.813078 -225.329621)
			(xy 121.789555 -225.375788) (xy 121.759099 -225.417707) (xy 121.722461 -225.454345) (xy 121.680542 -225.484801)
			(xy 121.634375 -225.508324) (xy 121.585096 -225.524336) (xy 121.533919 -225.532442) (xy 121.482105 -225.532442)
			(xy 121.430928 -225.524336) (xy 121.381649 -225.508324) (xy 121.335482 -225.484801) (xy 121.293563 -225.454345)
			(xy 121.256925 -225.417707) (xy 121.226469 -225.375788) (xy 121.202946 -225.329621) (xy 121.186934 -225.280342)
			(xy 121.178828 -225.229165) (xy 121.17832 -225.203258) (xy 121.178927 -225.175541) (xy 121.188242 -225.120895)
			(xy 121.196862 -225.094546) (xy 121.204736 -225.072448) (xy 120.999758 -224.71761) (xy 120.976898 -224.713292)
			(xy 120.952085 -224.708145) (xy 120.904343 -224.691153) (xy 120.859763 -224.667056) (xy 120.819396 -224.63642)
			(xy 120.784193 -224.599968) (xy 120.754982 -224.558558) (xy 120.732452 -224.513166) (xy 120.717134 -224.46486)
			(xy 120.709388 -224.41478) (xy 120.708928 -224.389442) (xy 120.428004 -224.389442) (xy 120.427496 -224.415329)
			(xy 120.419397 -224.466467) (xy 120.403398 -224.515707) (xy 120.379892 -224.561839) (xy 120.34946 -224.603726)
			(xy 120.31285 -224.640336) (xy 120.270963 -224.670768) (xy 120.224831 -224.694274) (xy 120.175591 -224.710273)
			(xy 120.124453 -224.718372) (xy 120.072679 -224.718372) (xy 120.021541 -224.710273) (xy 119.972301 -224.694274)
			(xy 119.926169 -224.670768) (xy 119.884282 -224.640336) (xy 119.847672 -224.603726) (xy 119.81724 -224.561839)
			(xy 119.793734 -224.515707) (xy 119.777735 -224.466467) (xy 119.769636 -224.415329) (xy 119.769128 -224.389442)
			(xy 119.488204 -224.389442) (xy 119.48766 -224.417149) (xy 119.478474 -224.471796) (xy 119.469916 -224.498154)
			(xy 119.462042 -224.520252) (xy 119.66702 -224.87509) (xy 119.68988 -224.879408) (xy 119.714709 -224.884542)
			(xy 119.762488 -224.901501) (xy 119.807108 -224.925578) (xy 119.847514 -224.956202) (xy 119.882754 -224.992654)
			(xy 119.911997 -225.034071) (xy 119.934552 -225.079478) (xy 119.949888 -225.127804) (xy 119.957643 -225.177908)
			(xy 119.958104 -225.203258) (xy 119.957596 -225.229165) (xy 119.94949 -225.280342) (xy 119.933478 -225.329621)
			(xy 119.909955 -225.375788) (xy 119.879499 -225.417707) (xy 119.842861 -225.454345) (xy 119.800942 -225.484801)
			(xy 119.754775 -225.508324) (xy 119.705496 -225.524336) (xy 119.654319 -225.532442) (xy 119.602505 -225.532442)
			(xy 119.551328 -225.524336) (xy 119.502049 -225.508324) (xy 119.455882 -225.484801) (xy 119.413963 -225.454345)
			(xy 119.377325 -225.417707) (xy 119.346869 -225.375788) (xy 119.323346 -225.329621) (xy 119.307334 -225.280342)
			(xy 119.299228 -225.229165) (xy 119.29872 -225.203258) (xy 119.299327 -225.175541) (xy 119.308642 -225.120895)
			(xy 119.317262 -225.094546) (xy 119.325136 -225.072448) (xy 119.120158 -224.71761) (xy 119.097298 -224.713292)
			(xy 119.072485 -224.708145) (xy 119.024743 -224.691153) (xy 118.980163 -224.667056) (xy 118.939796 -224.63642)
			(xy 118.904593 -224.599968) (xy 118.875382 -224.558558) (xy 118.852852 -224.513166) (xy 118.837534 -224.46486)
			(xy 118.829788 -224.41478) (xy 118.829328 -224.389442) (xy 118.548404 -224.389442) (xy 118.547896 -224.415329)
			(xy 118.539797 -224.466467) (xy 118.523798 -224.515707) (xy 118.500292 -224.561839) (xy 118.46986 -224.603726)
			(xy 118.43325 -224.640336) (xy 118.391363 -224.670768) (xy 118.345231 -224.694274) (xy 118.295991 -224.710273)
			(xy 118.244853 -224.718372) (xy 118.193079 -224.718372) (xy 118.141941 -224.710273) (xy 118.092701 -224.694274)
			(xy 118.046569 -224.670768) (xy 118.004682 -224.640336) (xy 117.968072 -224.603726) (xy 117.93764 -224.561839)
			(xy 117.914134 -224.515707) (xy 117.898135 -224.466467) (xy 117.890036 -224.415329) (xy 117.889528 -224.389442)
			(xy 117.608604 -224.389442) (xy 117.60806 -224.417149) (xy 117.598874 -224.471796) (xy 117.590316 -224.498154)
			(xy 117.582442 -224.520252) (xy 117.78742 -224.87509) (xy 117.81028 -224.879408) (xy 117.835109 -224.884542)
			(xy 117.882888 -224.901501) (xy 117.927508 -224.925578) (xy 117.967914 -224.956202) (xy 118.003154 -224.992654)
			(xy 118.032397 -225.034071) (xy 118.054952 -225.079478) (xy 118.070288 -225.127804) (xy 118.078043 -225.177908)
			(xy 118.078504 -225.203258) (xy 118.077996 -225.229165) (xy 118.06989 -225.280342) (xy 118.053878 -225.329621)
			(xy 118.030355 -225.375788) (xy 117.999899 -225.417707) (xy 117.963261 -225.454345) (xy 117.921342 -225.484801)
			(xy 117.875175 -225.508324) (xy 117.825896 -225.524336) (xy 117.774719 -225.532442) (xy 117.722905 -225.532442)
			(xy 117.671728 -225.524336) (xy 117.622449 -225.508324) (xy 117.576282 -225.484801) (xy 117.534363 -225.454345)
			(xy 117.497725 -225.417707) (xy 117.467269 -225.375788) (xy 117.443746 -225.329621) (xy 117.427734 -225.280342)
			(xy 117.419628 -225.229165) (xy 117.41912 -225.203258) (xy 117.419727 -225.175541) (xy 117.429042 -225.120895)
			(xy 117.437662 -225.094546) (xy 117.445536 -225.072448) (xy 117.240558 -224.71761) (xy 117.217698 -224.713292)
			(xy 117.192885 -224.708145) (xy 117.145143 -224.691153) (xy 117.100563 -224.667056) (xy 117.060196 -224.63642)
			(xy 117.024993 -224.599968) (xy 116.995782 -224.558558) (xy 116.973252 -224.513166) (xy 116.957934 -224.46486)
			(xy 116.950188 -224.41478) (xy 116.949728 -224.389442) (xy 116.668804 -224.389442) (xy 116.668296 -224.415329)
			(xy 116.660197 -224.466467) (xy 116.644198 -224.515707) (xy 116.620692 -224.561839) (xy 116.59026 -224.603726)
			(xy 116.55365 -224.640336) (xy 116.511763 -224.670768) (xy 116.465631 -224.694274) (xy 116.416391 -224.710273)
			(xy 116.365253 -224.718372) (xy 116.313479 -224.718372) (xy 116.262341 -224.710273) (xy 116.213101 -224.694274)
			(xy 116.166969 -224.670768) (xy 116.125082 -224.640336) (xy 116.088472 -224.603726) (xy 116.05804 -224.561839)
			(xy 116.034534 -224.515707) (xy 116.018535 -224.466467) (xy 116.010436 -224.415329) (xy 116.009928 -224.389442)
			(xy 115.729004 -224.389442) (xy 115.728479 -224.417151) (xy 115.719288 -224.471799) (xy 115.710716 -224.498154)
			(xy 115.702842 -224.520252) (xy 115.90782 -224.87509) (xy 115.93068 -224.879408) (xy 115.955492 -224.884596)
			(xy 116.003256 -224.901569) (xy 116.04786 -224.925651) (xy 116.088254 -224.956274) (xy 116.123486 -224.992717)
			(xy 116.152728 -225.034123) (xy 116.175289 -225.079514) (xy 116.19064 -225.127824) (xy 116.198417 -225.177913)
			(xy 116.198904 -225.203258) (xy 116.198425 -225.229161) (xy 116.190322 -225.28033) (xy 116.174309 -225.3296)
			(xy 116.150782 -225.375756) (xy 116.120319 -225.41766) (xy 116.083673 -225.454279) (xy 116.041746 -225.48471)
			(xy 115.995572 -225.508204) (xy 115.946291 -225.524179) (xy 115.895116 -225.532244) (xy 115.869212 -225.532696)
			(xy 115.839194 -225.532037) (xy 115.78015 -225.521175) (xy 115.751864 -225.511106) (xy 115.738542 -225.506487)
			(xy 115.710468 -225.503979) (xy 115.682777 -225.509238) (xy 115.657578 -225.521865) (xy 115.636789 -225.540898)
			(xy 115.621993 -225.564888) (xy 115.614317 -225.592009) (xy 115.613942 -225.606102) (xy 115.613942 -225.768916)
			(xy 115.633023 -225.786035) (xy 115.666151 -225.825153) (xy 115.692792 -225.868947) (xy 115.712297 -225.916352)
			(xy 115.724192 -225.966214) (xy 115.728188 -226.017318) (xy 115.724187 -226.068423) (xy 115.712286 -226.118283)
			(xy 115.692775 -226.165685) (xy 115.66613 -226.209477) (xy 115.632998 -226.248591) (xy 115.613942 -226.26574)
			(xy 115.613942 -227.396548) (xy 115.634908 -227.415416) (xy 115.67068 -227.45902) (xy 115.698478 -227.508093)
			(xy 115.717485 -227.561194) (xy 115.727143 -227.61676) (xy 115.727734 -227.64496) (xy 115.727572 -227.659001)
			(xy 115.725152 -227.686978) (xy 115.722908 -227.70084) (xy 115.718336 -227.726748) (xy 117.749574 -229.757986)
			(xy 117.768624 -229.759002) (xy 117.795002 -229.761131) (xy 117.846625 -229.772757) (xy 117.895715 -229.792513)
			(xy 117.941001 -229.819888) (xy 117.981309 -229.854172) (xy 118.015596 -229.894477) (xy 118.042974 -229.93976)
			(xy 118.062735 -229.988849) (xy 118.074365 -230.040471) (xy 118.076472 -230.06685) (xy 118.077488 -230.0859)
			(xy 119.43715 -231.445562) (xy 119.470678 -231.42702) (xy 119.495077 -231.414245) (xy 119.547085 -231.396134)
			(xy 119.601385 -231.386952) (xy 119.62892 -231.38638) (xy 119.654707 -231.386861) (xy 119.705646 -231.394933)
			(xy 119.754695 -231.410874) (xy 119.800646 -231.434292) (xy 119.842368 -231.464611) (xy 119.878833 -231.501084)
			(xy 119.909143 -231.542812) (xy 119.932552 -231.588768) (xy 119.948483 -231.63782) (xy 119.956544 -231.688761)
			(xy 119.957088 -231.714548) (xy 119.956531 -231.742085) (xy 119.947353 -231.796389) (xy 119.929243 -231.8484)
			(xy 119.916448 -231.87279) (xy 119.897906 -231.906318) (xy 120.21185 -232.220262) (xy 120.221502 -232.224072)
			(xy 120.245708 -232.234434) (xy 120.290732 -232.261726) (xy 120.330824 -232.295854) (xy 120.364956 -232.335942)
			(xy 120.392252 -232.380964) (xy 120.402604 -232.405174) (xy 120.406414 -232.414826) (xy 121.845832 -233.854244)
			(xy 121.87555 -233.844592) (xy 121.900501 -233.836883) (xy 121.952056 -233.828582) (xy 121.978166 -233.828082)
			(xy 122.003956 -233.828559) (xy 122.054901 -233.836624) (xy 122.103957 -233.852561) (xy 122.149916 -233.875976)
			(xy 122.191645 -233.906294) (xy 122.228116 -233.942767) (xy 122.258432 -233.984498) (xy 122.281846 -234.030457)
			(xy 122.29778 -234.079514) (xy 122.305842 -234.13046) (xy 122.306334 -234.15625) (xy 122.305807 -234.182358)
			(xy 122.297513 -234.233911) (xy 122.289824 -234.258866) (xy 122.280172 -234.288584) (xy 124.266198 -236.27461)
			(xy 124.290582 -236.271816) (xy 124.299759 -236.27085) (xy 124.318185 -236.269836) (xy 124.327412 -236.269784)
			(xy 124.3532 -236.270291) (xy 124.404142 -236.27836) (xy 124.453194 -236.294298) (xy 124.49915 -236.317712)
			(xy 124.540877 -236.348027) (xy 124.57735 -236.384495) (xy 124.607669 -236.426219) (xy 124.631088 -236.472172)
			(xy 124.647032 -236.521223) (xy 124.655107 -236.572164) (xy 124.65558 -236.597952) (xy 124.65552 -236.607179)
			(xy 124.654503 -236.625604) (xy 124.653548 -236.634782) (xy 124.650754 -236.659166) (xy 125.98019 -237.988602)
			(xy 125.998642 -237.971598) (xy 126.039743 -237.942819) (xy 126.084741 -237.920623) (xy 126.13259 -237.905526)
			(xy 126.182179 -237.897878) (xy 126.207266 -237.897416) (xy 126.233058 -237.897893) (xy 126.284007 -237.905957)
			(xy 126.333068 -237.921893) (xy 126.379031 -237.945307) (xy 126.420766 -237.975624) (xy 126.457243 -238.012096)
			(xy 126.487566 -238.053826) (xy 126.510988 -238.099786) (xy 126.526931 -238.148844) (xy 126.535003 -238.199792)
			(xy 126.535434 -238.225584) (xy 126.534942 -238.251553) (xy 126.526768 -238.302844) (xy 126.51062 -238.352208)
			(xy 126.486903 -238.398414) (xy 126.471934 -238.41964) (xy 126.44628 -238.454692) (xy 126.703328 -238.71174)
			(xy 126.720346 -238.714026) (xy 126.746871 -238.718082) (xy 126.798206 -238.733693) (xy 126.846318 -238.757445)
			(xy 126.889926 -238.788707) (xy 126.927868 -238.826645) (xy 126.959135 -238.870249) (xy 126.982893 -238.918359)
			(xy 126.99851 -238.969692) (xy 127.00254 -238.99622) (xy 127.004826 -239.013238) (xy 127.422656 -239.431068)
			(xy 127.439913 -239.44911) (xy 127.467665 -239.490605) (xy 127.486773 -239.536723) (xy 127.4965 -239.585686)
			(xy 127.497078 -239.610646) (xy 127.497078 -254.510032) (xy 127.513517 -254.528344) (xy 127.541284 -254.568972)
			(xy 127.562674 -254.613289) (xy 127.577208 -254.660303) (xy 127.58456 -254.70896) (xy 127.584565 -254.75817)
			(xy 127.577223 -254.806828) (xy 127.562699 -254.853845) (xy 127.541319 -254.898167) (xy 127.513561 -254.938801)
			(xy 127.497078 -254.957072) (xy 127.497078 -256.137918) (xy 127.513511 -256.15623) (xy 127.541265 -256.196856)
			(xy 127.562642 -256.241169) (xy 127.577165 -256.288178) (xy 127.584506 -256.336827) (xy 127.584502 -256.386028)
			(xy 127.577152 -256.434677) (xy 127.562622 -256.481683) (xy 127.541237 -256.525993) (xy 127.513476 -256.566613)
			(xy 127.497078 -256.584958) (xy 127.497078 -257.765296) (xy 127.513555 -257.783619) (xy 127.54139 -257.82428)
			(xy 127.562833 -257.868646) (xy 127.577403 -257.915718) (xy 127.584773 -257.96444) (xy 127.584776 -258.013716)
			(xy 127.577413 -258.062439) (xy 127.562849 -258.109513) (xy 127.541412 -258.153882) (xy 127.513583 -258.194547)
			(xy 127.497078 -258.212844) (xy 127.497078 -259.393436) (xy 127.513517 -259.411748) (xy 127.541283 -259.452376)
			(xy 127.562672 -259.496693) (xy 127.577206 -259.543707) (xy 127.584557 -259.592363) (xy 127.584562 -259.641572)
			(xy 127.57722 -259.69023) (xy 127.562696 -259.737247) (xy 127.541315 -259.781569) (xy 127.513557 -259.822201)
			(xy 127.497078 -259.840476) (xy 127.497078 -261.021322) (xy 127.513511 -261.039635) (xy 127.541265 -261.080262)
			(xy 127.562643 -261.124578) (xy 127.577164 -261.171589) (xy 127.584504 -261.220241) (xy 127.584962 -261.244842)
			(xy 127.584453 -261.270627) (xy 127.57638 -261.321562) (xy 127.560438 -261.370607) (xy 127.537021 -261.416554)
			(xy 127.506705 -261.458273) (xy 127.470237 -261.494737) (xy 127.428513 -261.525047) (xy 127.382562 -261.548457)
			(xy 127.333515 -261.564391) (xy 127.282579 -261.572457) (xy 127.256794 -261.57301) (xy 127.23273 -261.572587)
			(xy 127.185118 -261.565553) (xy 127.139045 -261.551637) (xy 127.117094 -261.541768) (xy 127.084836 -261.526528)
			(xy 126.388876 -262.222488) (xy 126.370837 -262.239752) (xy 126.329345 -262.267519) (xy 126.283227 -262.28664)
			(xy 126.234261 -262.296379) (xy 126.209298 -262.29691) (xy 126.072646 -262.29691) (xy 126.054266 -262.313693)
			(xy 126.013381 -262.342076) (xy 125.968676 -262.363954) (xy 125.921179 -262.378825) (xy 125.87198 -262.386347)
			(xy 125.822208 -262.386347) (xy 125.773009 -262.378825) (xy 125.725512 -262.363954) (xy 125.680807 -262.342076)
			(xy 125.639922 -262.313693) (xy 125.621542 -262.29691) (xy 125.1331 -262.29691) (xy 125.11472 -262.313693)
			(xy 125.073835 -262.342076) (xy 125.02913 -262.363954) (xy 124.981633 -262.378825) (xy 124.932434 -262.386347)
			(xy 124.882662 -262.386347) (xy 124.833463 -262.378825) (xy 124.785966 -262.363954) (xy 124.741261 -262.342076)
			(xy 124.700376 -262.313693) (xy 124.681996 -262.29691) (xy 124.1933 -262.29691) (xy 124.17492 -262.313693)
			(xy 124.134035 -262.342076) (xy 124.08933 -262.363954) (xy 124.041833 -262.378825) (xy 123.992634 -262.386347)
			(xy 123.942862 -262.386347) (xy 123.893663 -262.378825) (xy 123.846166 -262.363954) (xy 123.801461 -262.342076)
			(xy 123.760576 -262.313693) (xy 123.742196 -262.29691) (xy 123.253246 -262.29691) (xy 123.234866 -262.313693)
			(xy 123.193981 -262.342076) (xy 123.149276 -262.363954) (xy 123.101779 -262.378825) (xy 123.05258 -262.386347)
			(xy 123.002808 -262.386347) (xy 122.953609 -262.378825) (xy 122.906112 -262.363954) (xy 122.861407 -262.342076)
			(xy 122.820522 -262.313693) (xy 122.802142 -262.29691) (xy 122.3137 -262.29691) (xy 122.295318 -262.313691)
			(xy 122.254432 -262.342071) (xy 122.209728 -262.363948) (xy 122.162231 -262.37882) (xy 122.113033 -262.386347)
			(xy 122.088148 -262.386826) (xy 122.062995 -262.386341) (xy 122.01328 -262.378657) (xy 121.965319 -262.363477)
			(xy 121.920236 -262.341156) (xy 121.879087 -262.312217) (xy 121.842836 -262.277338) (xy 121.812332 -262.237336)
			(xy 121.788289 -262.193148) (xy 121.779284 -262.169656) (xy 121.76382 -262.168409) (xy 121.734151 -262.159372)
			(xy 121.707537 -262.143445) (xy 121.696226 -262.132826) (xy 121.606564 -262.043164) (xy 121.60631 -262.043164)
			(xy 121.354088 -261.790942) (xy 121.354088 -261.582408) (xy 121.330838 -261.563572) (xy 121.289282 -261.520521)
			(xy 121.25412 -261.472107) (xy 121.226035 -261.419272) (xy 121.205573 -261.363044) (xy 121.193134 -261.304516)
			(xy 121.188958 -261.244826) (xy 121.193127 -261.185136) (xy 121.205559 -261.126606) (xy 121.226014 -261.070375)
			(xy 121.254092 -261.017537) (xy 121.289249 -260.969119) (xy 121.3308 -260.926063) (xy 121.354088 -260.907276)
			(xy 121.354088 -260.520688) (xy 121.190004 -260.356858) (xy 120.84812 -260.698488) (xy 120.830079 -260.715748)
			(xy 120.788586 -260.743505) (xy 120.742468 -260.762616) (xy 120.693503 -260.772344) (xy 120.668542 -260.77291)
			(xy 118.966996 -260.77291) (xy 118.788942 -260.950964) (xy 118.788942 -263.04494) (xy 118.822724 -263.056878)
			(xy 118.846313 -263.065778) (xy 118.890653 -263.089774) (xy 118.930801 -263.120269) (xy 118.965813 -263.156544)
			(xy 118.994866 -263.197748) (xy 119.017275 -263.24291) (xy 119.032514 -263.290968) (xy 119.040225 -263.340791)
			(xy 119.040225 -263.391207) (xy 119.032515 -263.44103) (xy 119.017276 -263.489088) (xy 118.994867 -263.53425)
			(xy 118.965815 -263.575454) (xy 118.930803 -263.61173) (xy 118.890655 -263.642225) (xy 118.846316 -263.666221)
			(xy 118.822724 -263.675114) (xy 118.788942 -263.687052) (xy 118.788942 -270.016732) (xy 119.47652 -270.70431)
			(xy 119.622316 -270.70431)
		)
		(stroke
			(width 0)
			(type solid)
		)
		(fill yes)
		(layer "In8.Cu")
		(net "PVCCINFAON_CPU1")
	)
	(gr_poly
		(pts
			(xy 296.131996 -133.722618) (xy 296.141442 -133.696922) (xy 296.167119 -133.648571) (xy 296.199935 -133.604751)
			(xy 296.239108 -133.566507) (xy 296.283702 -133.534751) (xy 296.332655 -133.51024) (xy 296.384798 -133.493561)
			(xy 296.438887 -133.485109) (xy 296.46626 -133.48462) (xy 296.493576 -133.485127) (xy 296.547558 -133.493531)
			(xy 296.599603 -133.510145) (xy 296.648469 -133.534573) (xy 296.692993 -133.566232) (xy 296.712894 -133.58495)
			(xy 296.724569 -133.595489) (xy 296.752698 -133.609523) (xy 296.78376 -133.614352) (xy 296.814822 -133.609523)
			(xy 296.842951 -133.595489) (xy 296.854626 -133.58495) (xy 296.874538 -133.566243) (xy 296.919057 -133.534575)
			(xy 296.96792 -133.510138) (xy 297.019962 -133.493513) (xy 297.073943 -133.485097) (xy 297.10126 -133.48462)
			(xy 297.128634 -133.485129) (xy 297.18273 -133.49356) (xy 297.23488 -133.510225) (xy 297.283839 -133.534728)
			(xy 297.328438 -133.566482) (xy 297.367611 -133.60473) (xy 297.400422 -133.648557) (xy 297.426088 -133.696916)
			(xy 297.435524 -133.722618) (xy 297.447462 -133.756908) (xy 297.663108 -133.756908) (xy 297.686412 -133.742343)
			(xy 297.736319 -133.719339) (xy 297.789014 -133.703746) (xy 297.843403 -133.695889) (xy 297.87088 -133.69544)
			(xy 297.898354 -133.695922) (xy 297.952735 -133.703801) (xy 298.005427 -133.719386) (xy 298.055345 -133.742354)
			(xy 298.078652 -133.756908) (xy 333.803244 -133.756908) (xy 364.300262 -103.25989) (xy 364.318303 -103.24263)
			(xy 364.359796 -103.214872) (xy 364.405914 -103.19576) (xy 364.454879 -103.186029) (xy 364.47984 -103.185468)
			(xy 367.901982 -103.185468) (xy 367.922958 -103.16968) (xy 367.968629 -103.14379) (xy 368.017606 -103.124886)
			(xy 368.068828 -103.113378) (xy 368.121184 -103.109514) (xy 368.17354 -103.113378) (xy 368.224762 -103.124886)
			(xy 368.273739 -103.14379) (xy 368.31941 -103.16968) (xy 368.340386 -103.185468) (xy 371.292374 -103.185468)
			(xy 371.301772 -103.146606) (xy 371.308974 -103.119314) (xy 371.33032 -103.067064) (xy 371.359131 -103.018529)
			(xy 371.394779 -102.974768) (xy 371.436485 -102.936737) (xy 371.483339 -102.905265) (xy 371.534318 -102.88104)
			(xy 371.58831 -102.86459) (xy 371.644137 -102.856274) (xy 371.700579 -102.856274) (xy 371.756406 -102.86459)
			(xy 371.810398 -102.88104) (xy 371.861377 -102.905265) (xy 371.908231 -102.936737) (xy 371.949937 -102.974768)
			(xy 371.985585 -103.018529) (xy 372.014396 -103.067064) (xy 372.035742 -103.119314) (xy 372.042944 -103.146606)
			(xy 372.052342 -103.185468) (xy 373.242332 -103.185468) (xy 373.25173 -103.146606) (xy 373.258932 -103.119314)
			(xy 373.280278 -103.067064) (xy 373.309089 -103.018529) (xy 373.344737 -102.974768) (xy 373.386443 -102.936737)
			(xy 373.433297 -102.905265) (xy 373.484276 -102.88104) (xy 373.538268 -102.86459) (xy 373.594095 -102.856274)
			(xy 373.650537 -102.856274) (xy 373.706364 -102.86459) (xy 373.760356 -102.88104) (xy 373.811335 -102.905265)
			(xy 373.858189 -102.936737) (xy 373.899895 -102.974768) (xy 373.935543 -103.018529) (xy 373.964354 -103.067064)
			(xy 373.9857 -103.119314) (xy 373.992902 -103.146606) (xy 374.0023 -103.185468) (xy 378.32538 -103.185468)
			(xy 378.344777 -103.16916) (xy 378.38736 -103.141684) (xy 378.433429 -103.12057) (xy 378.48204 -103.106249)
			(xy 378.532198 -103.099014) (xy 378.582874 -103.099014) (xy 378.633032 -103.106249) (xy 378.681643 -103.12057)
			(xy 378.727712 -103.141684) (xy 378.770295 -103.16916) (xy 378.789692 -103.185468) (xy 381.743204 -103.185468)
			(xy 390.62914 -94.299532) (xy 390.62914 -78.151228) (xy 390.629718 -78.126271) (xy 390.63947 -78.077318)
			(xy 390.658586 -78.031208) (xy 390.68633 -77.989713) (xy 390.703562 -77.97165) (xy 396.512542 -72.16267)
			(xy 396.530583 -72.145409) (xy 396.572076 -72.11765) (xy 396.618194 -72.098536) (xy 396.667159 -72.088803)
			(xy 396.69212 -72.088248) (xy 421.29456 -72.088248) (xy 421.29456 -66.06794) (xy 421.295065 -65.962416)
			(xy 421.303149 -65.751522) (xy 421.319305 -65.541093) (xy 421.343508 -65.331436) (xy 421.375725 -65.122861)
			(xy 421.415907 -64.915673) (xy 421.463995 -64.710176) (xy 421.519919 -64.506672) (xy 421.583596 -64.305459)
			(xy 421.654934 -64.106832) (xy 421.733828 -63.911084) (xy 421.820161 -63.718502) (xy 421.913808 -63.529367)
			(xy 422.01463 -63.343958) (xy 422.12248 -63.162547) (xy 422.237199 -62.9854) (xy 422.358619 -62.812778)
			(xy 422.486562 -62.644932) (xy 422.62084 -62.48211) (xy 422.761256 -62.324551) (xy 422.907604 -62.172486)
			(xy 423.059669 -62.026138) (xy 423.217228 -61.885722) (xy 423.38005 -61.751444) (xy 423.547896 -61.623501)
			(xy 423.720518 -61.502081) (xy 423.897665 -61.387362) (xy 424.079076 -61.279512) (xy 424.264485 -61.17869)
			(xy 424.45362 -61.085043) (xy 424.646202 -60.99871) (xy 424.84195 -60.919816) (xy 425.040577 -60.848478)
			(xy 425.24179 -60.784801) (xy 425.445294 -60.728877) (xy 425.650791 -60.680789) (xy 425.857979 -60.640607)
			(xy 426.066554 -60.60839) (xy 426.276211 -60.584187) (xy 426.48664 -60.568031) (xy 426.697534 -60.559947)
			(xy 426.908582 -60.559947) (xy 427.119476 -60.568031) (xy 427.329905 -60.584187) (xy 427.539562 -60.60839)
			(xy 427.748137 -60.640607) (xy 427.955325 -60.680789) (xy 428.160822 -60.728877) (xy 428.364326 -60.784801)
			(xy 428.565539 -60.848478) (xy 428.764166 -60.919816) (xy 428.959914 -60.99871) (xy 429.152496 -61.085043)
			(xy 429.341631 -61.17869) (xy 429.52704 -61.279512) (xy 429.708451 -61.387362) (xy 429.885598 -61.502081)
			(xy 430.05822 -61.623501) (xy 430.226066 -61.751444) (xy 430.388888 -61.885722) (xy 430.546447 -62.026138)
			(xy 430.698512 -62.172486) (xy 430.84486 -62.324551) (xy 430.985276 -62.48211) (xy 431.119554 -62.644932)
			(xy 431.247497 -62.812778) (xy 431.368917 -62.9854) (xy 431.483636 -63.162547) (xy 431.591486 -63.343958)
			(xy 431.692308 -63.529367) (xy 431.785955 -63.718502) (xy 431.872288 -63.911084) (xy 431.951182 -64.106832)
			(xy 432.02252 -64.305459) (xy 432.086197 -64.506672) (xy 432.142121 -64.710176) (xy 432.190209 -64.915673)
			(xy 432.230391 -65.122861) (xy 432.262608 -65.331436) (xy 432.286811 -65.541093) (xy 432.302967 -65.751522)
			(xy 432.311051 -65.962416) (xy 432.311556 -66.06794) (xy 432.311556 -72.088248) (xy 446.006474 -72.088248)
			(xy 446.01384 -72.046338) (xy 446.018968 -72.020223) (xy 446.035505 -71.969639) (xy 446.058915 -71.921845)
			(xy 446.088742 -71.87777) (xy 446.124408 -71.83827) (xy 446.165218 -71.804113) (xy 446.210382 -71.775961)
			(xy 446.259021 -71.754362) (xy 446.31019 -71.739735) (xy 446.362896 -71.732364) (xy 446.389506 -71.731886)
			(xy 446.417184 -71.732381) (xy 446.471956 -71.740388) (xy 446.524995 -71.756233) (xy 446.575185 -71.779582)
			(xy 446.62147 -71.809945) (xy 446.662877 -71.846682) (xy 446.681098 -71.867522) (xy 446.691282 -71.878741)
			(xy 446.716727 -71.895164) (xy 446.745863 -71.903422) (xy 446.776141 -71.902794) (xy 446.804909 -71.893333)
			(xy 446.82965 -71.875868) (xy 446.83934 -71.86422) (xy 446.857509 -71.841569) (xy 446.899546 -71.801514)
			(xy 446.947169 -71.768294) (xy 446.999278 -71.742679) (xy 447.054669 -71.72526) (xy 447.11206 -71.71644)
			(xy 447.141092 -71.715884) (xy 447.169951 -71.716421) (xy 447.227008 -71.725129) (xy 447.282102 -71.742332)
			(xy 447.333976 -71.767637) (xy 447.381447 -71.800468) (xy 447.423431 -71.840075) (xy 447.458969 -71.885554)
			(xy 447.473578 -71.910448) (xy 447.480606 -71.922093) (xy 447.4997 -71.94145) (xy 447.52323 -71.955072)
			(xy 447.549524 -71.961993) (xy 447.576712 -71.961719) (xy 447.602861 -71.95427) (xy 447.626112 -71.940176)
			(xy 447.644812 -71.920439) (xy 447.651632 -71.90867) (xy 447.666041 -71.883073) (xy 447.701499 -71.836245)
			(xy 447.743712 -71.795401) (xy 447.791683 -71.761504) (xy 447.844279 -71.735355) (xy 447.90026 -71.71757)
			(xy 447.958305 -71.708569) (xy 447.987674 -71.70801) (xy 448.015347 -71.708502) (xy 448.070112 -71.716496)
			(xy 448.123147 -71.732319) (xy 448.173338 -71.75564) (xy 448.219634 -71.785969) (xy 448.26106 -71.82267)
			(xy 448.296749 -71.864972) (xy 448.32595 -71.911987) (xy 448.348051 -71.962727) (xy 448.362588 -72.01613)
			(xy 448.366388 -72.043544) (xy 448.371722 -72.088248) (xy 450.861684 -72.088248) (xy 452.12254 -70.827392)
			(xy 452.12254 -45.486066) (xy 452.08698 -45.47489) (xy 452.060008 -45.465869) (xy 452.008879 -45.440962)
			(xy 451.962015 -45.408741) (xy 451.920453 -45.36992) (xy 451.885114 -45.325359) (xy 451.856782 -45.276047)
			(xy 451.836083 -45.223075) (xy 451.823478 -45.167617) (xy 451.819245 -45.110902) (xy 451.823477 -45.054188)
			(xy 451.836082 -44.99873) (xy 451.85678 -44.945758) (xy 451.885111 -44.896445) (xy 451.92045 -44.851884)
			(xy 451.962011 -44.813062) (xy 452.008875 -44.780841) (xy 452.060003 -44.755933) (xy 452.08698 -44.746926)
			(xy 452.12254 -44.73575) (xy 452.12254 -41.228264) (xy 448.047364 -37.153088) (xy 430.0601 -37.153088)
			(xy 430.051464 -37.192966) (xy 430.041964 -37.234056) (xy 430.016309 -37.314402) (xy 429.983267 -37.392004)
			(xy 429.943127 -37.466183) (xy 429.89624 -37.536292) (xy 429.843015 -37.601719) (xy 429.783916 -37.661894)
			(xy 429.719459 -37.716291) (xy 429.650207 -37.764435) (xy 429.576764 -37.805905) (xy 429.499771 -37.840341)
			(xy 429.419901 -37.867441) (xy 429.33785 -37.886969) (xy 429.254335 -37.898755) (xy 429.170084 -37.902695)
			(xy 429.085833 -37.898755) (xy 429.002318 -37.886969) (xy 428.920267 -37.867441) (xy 428.840397 -37.840341)
			(xy 428.763404 -37.805905) (xy 428.689961 -37.764435) (xy 428.620709 -37.716291) (xy 428.556252 -37.661894)
			(xy 428.497153 -37.601719) (xy 428.443928 -37.536292) (xy 428.397041 -37.466183) (xy 428.356901 -37.392004)
			(xy 428.323859 -37.314402) (xy 428.298204 -37.234056) (xy 428.288704 -37.192966) (xy 428.280068 -37.153088)
			(xy 427.5201 -37.153088) (xy 427.511464 -37.192966) (xy 427.501964 -37.234056) (xy 427.476309 -37.314402)
			(xy 427.443267 -37.392004) (xy 427.403127 -37.466183) (xy 427.35624 -37.536292) (xy 427.303015 -37.601719)
			(xy 427.243916 -37.661894) (xy 427.179459 -37.716291) (xy 427.110207 -37.764435) (xy 427.036764 -37.805905)
			(xy 426.959771 -37.840341) (xy 426.879901 -37.867441) (xy 426.79785 -37.886969) (xy 426.714335 -37.898755)
			(xy 426.630084 -37.902695) (xy 426.545833 -37.898755) (xy 426.462318 -37.886969) (xy 426.380267 -37.867441)
			(xy 426.300397 -37.840341) (xy 426.223404 -37.805905) (xy 426.149961 -37.764435) (xy 426.080709 -37.716291)
			(xy 426.016252 -37.661894) (xy 425.957153 -37.601719) (xy 425.903928 -37.536292) (xy 425.857041 -37.466183)
			(xy 425.816901 -37.392004) (xy 425.783859 -37.314402) (xy 425.758204 -37.234056) (xy 425.748704 -37.192966)
			(xy 425.740068 -37.153088) (xy 388.008876 -37.153088) (xy 388.002526 -37.196522) (xy 387.998101 -37.223359)
			(xy 387.982644 -37.275506) (xy 387.959936 -37.324929) (xy 387.930439 -37.370626) (xy 387.894751 -37.411669)
			(xy 387.853594 -37.447228) (xy 387.807805 -37.476581) (xy 387.758311 -37.499133) (xy 387.706115 -37.514427)
			(xy 387.652277 -37.522152) (xy 387.597887 -37.522152) (xy 387.544049 -37.514427) (xy 387.491853 -37.499133)
			(xy 387.442359 -37.476581) (xy 387.39657 -37.447228) (xy 387.355413 -37.411669) (xy 387.319725 -37.370626)
			(xy 387.290228 -37.324929) (xy 387.26752 -37.275506) (xy 387.252063 -37.223359) (xy 387.247638 -37.196522)
			(xy 387.241288 -37.153088) (xy 386.18668 -37.153088) (xy 386.16172 -37.152515) (xy 386.112761 -37.142772)
			(xy 386.066643 -37.123665) (xy 386.025139 -37.095928) (xy 386.007102 -37.078666) (xy 372.939564 -24.011128)
			(xy 354.18649 -24.011128) (xy 354.172598 -24.032795) (xy 354.139533 -24.072239) (xy 354.101098 -24.106471)
			(xy 354.058105 -24.134767) (xy 354.011464 -24.15653) (xy 353.962159 -24.1713) (xy 353.911234 -24.178763)
			(xy 353.859766 -24.178763) (xy 353.808841 -24.1713) (xy 353.759536 -24.15653) (xy 353.712895 -24.134767)
			(xy 353.669902 -24.106471) (xy 353.631467 -24.072239) (xy 353.598402 -24.032795) (xy 353.58451 -24.011128)
			(xy 336.364326 -24.011128) (xy 336.352388 -24.045418) (xy 336.342943 -24.071112) (xy 336.317267 -24.119458)
			(xy 336.28445 -24.163272) (xy 336.245276 -24.201507) (xy 336.20068 -24.233252) (xy 336.151725 -24.257749)
			(xy 336.099582 -24.274412) (xy 336.045495 -24.282844) (xy 335.990753 -24.282844) (xy 335.936666 -24.274412)
			(xy 335.884523 -24.257749) (xy 335.835568 -24.233252) (xy 335.790972 -24.201507) (xy 335.751798 -24.163272)
			(xy 335.718981 -24.119458) (xy 335.693305 -24.071112) (xy 335.68386 -24.045418) (xy 335.671922 -24.011128)
			(xy 334.114394 -24.011128) (xy 334.101482 -24.036529) (xy 334.069265 -24.083525) (xy 334.030419 -24.12521)
			(xy 333.985809 -24.160657) (xy 333.936425 -24.189078) (xy 333.883364 -24.209843) (xy 333.827806 -24.222489)
			(xy 333.770986 -24.226736) (xy 333.714166 -24.222489) (xy 333.658608 -24.209843) (xy 333.605547 -24.189078)
			(xy 333.556163 -24.160657) (xy 333.511553 -24.12521) (xy 333.472707 -24.083525) (xy 333.44049 -24.036529)
			(xy 333.427578 -24.011128) (xy 328.454766 -24.011128) (xy 328.450448 -24.01189) (xy 328.435824 -24.014172)
			(xy 328.406321 -24.016589) (xy 328.39152 -24.016716) (xy 328.376719 -24.016598) (xy 328.347215 -24.014182)
			(xy 328.332592 -24.01189) (xy 328.328274 -24.011128) (xy 287.480756 -24.011128) (xy 283.041852 -28.450032)
			(xy 354.840804 -28.450032) (xy 354.844787 -28.322014) (xy 354.856722 -28.194492) (xy 354.876561 -28.067958)
			(xy 354.904228 -27.942902) (xy 354.939617 -27.819809) (xy 354.98259 -27.699153) (xy 355.032981 -27.581403)
			(xy 355.090595 -27.467013) (xy 355.155209 -27.356426) (xy 355.226573 -27.25007) (xy 355.304411 -27.148357)
			(xy 355.388422 -27.051679) (xy 355.478281 -26.960412) (xy 355.57364 -26.874907) (xy 355.674131 -26.795497)
			(xy 355.779364 -26.722487) (xy 355.888933 -26.656161) (xy 356.002413 -26.596775) (xy 356.119365 -26.544559)
			(xy 356.239338 -26.499715) (xy 356.361866 -26.462417) (xy 356.486477 -26.432808) (xy 356.612686 -26.411003)
			(xy 356.740008 -26.397087) (xy 356.867948 -26.391113) (xy 356.996012 -26.393105) (xy 357.123705 -26.403055)
			(xy 357.250532 -26.420924) (xy 357.376003 -26.446643) (xy 357.499632 -26.480113) (xy 357.620941 -26.521204)
			(xy 357.739461 -26.569758) (xy 357.854733 -26.625586) (xy 357.966311 -26.688472) (xy 358.073764 -26.758174)
			(xy 358.176676 -26.834421) (xy 358.274648 -26.916918) (xy 358.367302 -27.005347) (xy 358.454279 -27.099365)
			(xy 358.535243 -27.198608) (xy 358.60988 -27.302693) (xy 358.677902 -27.411217) (xy 358.739046 -27.52376)
			(xy 358.793074 -27.639886) (xy 358.839779 -27.759147) (xy 358.878979 -27.88108) (xy 358.910522 -28.005215)
			(xy 358.934287 -28.131071) (xy 358.950181 -28.25816) (xy 358.958144 -28.385992) (xy 358.958642 -28.450032)
			(xy 358.958144 -28.514072) (xy 358.950181 -28.641904) (xy 358.934287 -28.768993) (xy 358.910522 -28.894849)
			(xy 358.878979 -29.018984) (xy 358.839779 -29.140917) (xy 358.793074 -29.260178) (xy 358.739046 -29.376304)
			(xy 358.677902 -29.488847) (xy 358.60988 -29.597371) (xy 358.535243 -29.701456) (xy 358.454279 -29.800699)
			(xy 358.367302 -29.894717) (xy 358.274648 -29.983146) (xy 358.176676 -30.065643) (xy 358.073764 -30.14189)
			(xy 357.966311 -30.211592) (xy 357.854733 -30.274478) (xy 357.739461 -30.330306) (xy 357.620941 -30.37886)
			(xy 357.499632 -30.419951) (xy 357.376003 -30.453421) (xy 357.250532 -30.47914) (xy 357.123705 -30.497009)
			(xy 356.996012 -30.506959) (xy 356.867948 -30.508951) (xy 356.740008 -30.502977) (xy 356.612686 -30.489061)
			(xy 356.486477 -30.467256) (xy 356.361866 -30.437647) (xy 356.239338 -30.400349) (xy 356.119365 -30.355505)
			(xy 356.002413 -30.303289) (xy 355.888933 -30.243903) (xy 355.779364 -30.177577) (xy 355.674131 -30.104567)
			(xy 355.57364 -30.025157) (xy 355.478281 -29.939652) (xy 355.388422 -29.848385) (xy 355.304411 -29.751707)
			(xy 355.226573 -29.649994) (xy 355.155209 -29.543638) (xy 355.090595 -29.433051) (xy 355.032981 -29.318661)
			(xy 354.98259 -29.200911) (xy 354.939617 -29.080255) (xy 354.904228 -28.957162) (xy 354.876561 -28.832106)
			(xy 354.856722 -28.705572) (xy 354.844787 -28.57805) (xy 354.840804 -28.450032) (xy 283.041852 -28.450032)
			(xy 276.224131 -35.267753) (xy 356.989346 -35.267753) (xy 356.989346 -35.213247) (xy 356.997102 -35.159297)
			(xy 357.012458 -35.106999) (xy 357.035099 -35.057419) (xy 357.064566 -35.011566) (xy 357.100259 -34.970373)
			(xy 357.14145 -34.934678) (xy 357.187302 -34.905209) (xy 357.236881 -34.882565) (xy 357.289177 -34.867207)
			(xy 357.343127 -34.859447) (xy 357.37038 -34.85896) (xy 358.23398 -34.85896) (xy 358.261232 -34.859486)
			(xy 358.31518 -34.86724) (xy 358.367476 -34.882593) (xy 358.417054 -34.905232) (xy 358.462906 -34.934697)
			(xy 358.504098 -34.970388) (xy 358.539791 -35.011578) (xy 358.569258 -35.057428) (xy 358.5919 -35.107005)
			(xy 358.607256 -35.1593) (xy 358.615013 -35.213249) (xy 358.615013 -35.267751) (xy 358.607256 -35.3217)
			(xy 358.5919 -35.373995) (xy 358.569258 -35.423572) (xy 358.539791 -35.469422) (xy 358.504098 -35.510612)
			(xy 358.462906 -35.546303) (xy 358.417054 -35.575768) (xy 358.367476 -35.598407) (xy 358.31518 -35.61376)
			(xy 358.261232 -35.621514) (xy 358.23398 -35.621976) (xy 357.37038 -35.621976) (xy 357.343127 -35.621553)
			(xy 357.289177 -35.613793) (xy 357.236881 -35.598435) (xy 357.187302 -35.575791) (xy 357.14145 -35.546322)
			(xy 357.100259 -35.510627) (xy 357.064566 -35.469434) (xy 357.035099 -35.423581) (xy 357.012458 -35.374001)
			(xy 356.997102 -35.321703) (xy 356.989346 -35.267753) (xy 276.224131 -35.267753) (xy 274.25396 -37.237924)
			(xy 274.25396 -39.657528) (xy 357.003604 -39.657528) (xy 357.003604 -38.793928) (xy 357.00409 -38.766659)
			(xy 357.011852 -38.712675) (xy 357.027217 -38.660345) (xy 357.049874 -38.610735) (xy 357.07936 -38.564854)
			(xy 357.115075 -38.523637) (xy 357.156292 -38.487922) (xy 357.202173 -38.458436) (xy 357.251783 -38.435779)
			(xy 357.304113 -38.420414) (xy 357.358097 -38.412652) (xy 357.412635 -38.412652) (xy 357.466619 -38.420414)
			(xy 357.518949 -38.435779) (xy 357.568559 -38.458436) (xy 357.61444 -38.487922) (xy 357.655657 -38.523637)
			(xy 357.691372 -38.564854) (xy 357.720858 -38.610735) (xy 357.743515 -38.660345) (xy 357.75888 -38.712675)
			(xy 357.766642 -38.766659) (xy 357.767128 -38.793928) (xy 357.767128 -39.657528) (xy 357.766642 -39.684797)
			(xy 357.75888 -39.738781) (xy 357.743515 -39.791111) (xy 357.720858 -39.840721) (xy 357.691372 -39.886602)
			(xy 357.655657 -39.927819) (xy 357.61444 -39.963534) (xy 357.568559 -39.99302) (xy 357.518949 -40.015677)
			(xy 357.466619 -40.031042) (xy 357.412635 -40.038804) (xy 357.358097 -40.038804) (xy 357.304113 -40.031042)
			(xy 357.251783 -40.015677) (xy 357.202173 -39.99302) (xy 357.156292 -39.963534) (xy 357.115075 -39.927819)
			(xy 357.07936 -39.886602) (xy 357.049874 -39.840721) (xy 357.027217 -39.791111) (xy 357.011852 -39.738781)
			(xy 357.00409 -39.684797) (xy 357.003604 -39.657528) (xy 274.25396 -39.657528) (xy 274.25396 -41.578276)
			(xy 274.270978 -41.59377) (xy 274.679156 -42.001948) (xy 322.633594 -42.001948) (xy 322.647818 -41.975024)
			(xy 322.66118 -41.950955) (xy 322.693766 -41.906585) (xy 322.73239 -41.867359) (xy 322.77625 -41.83409)
			(xy 322.824436 -41.80747) (xy 322.875947 -41.788051) (xy 322.929715 -41.776235) (xy 322.984622 -41.77227)
			(xy 323.039529 -41.776235) (xy 323.093297 -41.788051) (xy 323.144808 -41.80747) (xy 323.192994 -41.83409)
			(xy 323.236854 -41.867359) (xy 323.275478 -41.906585) (xy 323.308064 -41.950955) (xy 323.321426 -41.975024)
			(xy 323.33565 -42.001948) (xy 328.518266 -42.001948) (xy 328.525378 -41.999916) (xy 328.549906 -41.993146)
			(xy 328.600267 -41.985884) (xy 328.625708 -41.985438) (xy 328.651147 -41.98591) (xy 328.701504 -41.993174)
			(xy 328.726038 -41.999916) (xy 328.73315 -42.001948) (xy 330.146406 -42.001948) (xy 330.153518 -41.999916)
			(xy 330.178045 -41.993142) (xy 330.228406 -41.985871) (xy 330.253848 -41.985438) (xy 330.279286 -41.985913)
			(xy 330.329642 -41.993182) (xy 330.354178 -41.999916) (xy 330.36129 -42.001948) (xy 331.774546 -42.001948)
			(xy 331.781658 -41.999916) (xy 331.806186 -41.993145) (xy 331.856547 -41.98588) (xy 331.881988 -41.985438)
			(xy 331.907427 -41.985908) (xy 331.957785 -41.993169) (xy 331.982318 -41.999916) (xy 331.98943 -42.001948)
			(xy 333.40294 -42.001948) (xy 333.410052 -41.999916) (xy 333.434579 -41.993144) (xy 333.484941 -41.985878)
			(xy 333.510382 -41.985438) (xy 333.535821 -41.985908) (xy 333.58618 -41.993168) (xy 333.610712 -41.999916)
			(xy 333.617824 -42.001948) (xy 335.033366 -42.001948) (xy 335.040478 -41.999916) (xy 335.065006 -41.993146)
			(xy 335.115367 -41.985884) (xy 335.140808 -41.985438) (xy 335.166247 -41.98591) (xy 335.216604 -41.993174)
			(xy 335.241138 -41.999916) (xy 335.24825 -42.001948) (xy 338.28863 -42.001948) (xy 338.295742 -41.999916)
			(xy 338.320269 -41.993144) (xy 338.370631 -41.985876) (xy 338.396072 -41.985438) (xy 338.424447 -41.986011)
			(xy 338.480467 -41.995077) (xy 338.507578 -42.003472) (xy 338.528944 -42.006234) (xy 338.570381 -42.01801)
			(xy 338.609241 -42.036601) (xy 338.644411 -42.061477) (xy 338.659978 -42.07637) (xy 339.06714 -42.483532)
			(xy 339.097112 -42.473626) (xy 339.124451 -42.46507) (xy 339.180992 -42.455885) (xy 339.209634 -42.455338)
			(xy 339.209888 -42.455338) (xy 339.237873 -42.455858) (xy 339.293153 -42.464612) (xy 339.346383 -42.481908)
			(xy 339.396251 -42.507318) (xy 339.441531 -42.540217) (xy 339.481105 -42.579795) (xy 339.514 -42.625078)
			(xy 339.539405 -42.674949) (xy 339.556696 -42.72818) (xy 339.565445 -42.783461) (xy 339.565996 -42.811446)
			(xy 339.565471 -42.839074) (xy 339.556931 -42.893667) (xy 339.540063 -42.946286) (xy 339.515272 -42.995669)
			(xy 339.483152 -43.040631) (xy 339.444474 -43.080093) (xy 339.400166 -43.11311) (xy 339.351291 -43.138888)
			(xy 339.299022 -43.156809) (xy 339.244611 -43.166444) (xy 339.217 -43.167554) (xy 339.217 -43.395138)
			(xy 339.243299 -43.396135) (xy 339.295188 -43.404916) (xy 339.34522 -43.421238) (xy 339.392306 -43.444745)
			(xy 339.435419 -43.474925) (xy 339.473621 -43.511122) (xy 339.506081 -43.552546) (xy 339.506567 -43.5534)
			(xy 353.767583 -43.5534) (xy 353.771544 -43.500544) (xy 353.783339 -43.44887) (xy 353.802705 -43.39953)
			(xy 353.829208 -43.353628) (xy 353.862256 -43.312189) (xy 353.901112 -43.276139) (xy 353.944908 -43.246283)
			(xy 353.992664 -43.223289) (xy 354.043314 -43.207669) (xy 354.095726 -43.199773) (xy 354.122228 -43.199304)
			(xy 354.122736 -43.199304) (xy 354.153713 -43.199978) (xy 354.214715 -43.210807) (xy 354.272905 -43.232077)
			(xy 354.300028 -43.247056) (xy 354.328004 -43.238767) (xy 354.385663 -43.229845) (xy 354.414836 -43.229276)
			(xy 354.99548 -43.229276) (xy 355.004624 -43.225466) (xy 355.025917 -43.217194) (xy 355.070087 -43.205543)
			(xy 355.115388 -43.199665) (xy 355.138228 -43.199304) (xy 355.162681 -43.199729) (xy 355.211118 -43.206478)
			(xy 355.25817 -43.219815) (xy 355.280722 -43.229276) (xy 355.307866 -43.229907) (xy 355.361565 -43.237931)
			(xy 355.413585 -43.253486) (xy 355.462874 -43.276259) (xy 355.508436 -43.305789) (xy 355.549352 -43.341481)
			(xy 355.584795 -43.382612) (xy 355.61405 -43.428352) (xy 355.636524 -43.477777) (xy 355.651765 -43.52989)
			(xy 355.659465 -43.583636) (xy 355.659944 -43.610784) (xy 355.659468 -43.634951) (xy 356.178591 -43.634951)
			(xy 356.178591 -43.580449) (xy 356.186348 -43.526502) (xy 356.201703 -43.474208) (xy 356.224344 -43.424632)
			(xy 356.253811 -43.378783) (xy 356.289502 -43.337594) (xy 356.330692 -43.301903) (xy 356.376543 -43.272438)
			(xy 356.42612 -43.249799) (xy 356.478414 -43.234445) (xy 356.532361 -43.22669) (xy 356.559612 -43.226228)
			(xy 357.423212 -43.226228) (xy 357.450465 -43.226643) (xy 357.504417 -43.234401) (xy 357.556715 -43.249759)
			(xy 357.606295 -43.272403) (xy 357.652149 -43.301872) (xy 357.693341 -43.337567) (xy 357.729035 -43.378761)
			(xy 357.758503 -43.424615) (xy 357.781145 -43.474196) (xy 357.796501 -43.526495) (xy 357.804258 -43.580447)
			(xy 357.804258 -43.634953) (xy 357.803812 -43.638056) (xy 358.339039 -43.638056) (xy 358.339039 -43.583544)
			(xy 358.346797 -43.529588) (xy 358.362156 -43.477285) (xy 358.384802 -43.4277) (xy 358.414274 -43.381843)
			(xy 358.449974 -43.340648) (xy 358.491172 -43.304953) (xy 358.537032 -43.275485) (xy 358.586619 -43.252843)
			(xy 358.638923 -43.23749) (xy 358.69288 -43.229736) (xy 358.720136 -43.229276) (xy 359.583736 -43.229276)
			(xy 359.610984 -43.229797) (xy 359.664926 -43.237557) (xy 359.717214 -43.252915) (xy 359.766785 -43.275557)
			(xy 359.812629 -43.305023) (xy 359.853813 -43.340713) (xy 359.889499 -43.3819) (xy 359.91896 -43.427747)
			(xy 359.941598 -43.47732) (xy 359.956951 -43.529609) (xy 359.964706 -43.583552) (xy 359.964706 -43.638048)
			(xy 359.956951 -43.691991) (xy 359.941598 -43.74428) (xy 359.91896 -43.793853) (xy 359.889499 -43.8397)
			(xy 359.853813 -43.880887) (xy 359.812629 -43.916577) (xy 359.766785 -43.946043) (xy 359.717214 -43.968685)
			(xy 359.664926 -43.984043) (xy 359.610984 -43.991803) (xy 359.583736 -43.992292) (xy 358.720136 -43.992292)
			(xy 358.69288 -43.991864) (xy 358.638923 -43.98411) (xy 358.586619 -43.968757) (xy 358.537032 -43.946115)
			(xy 358.491172 -43.916647) (xy 358.449974 -43.880952) (xy 358.414274 -43.839757) (xy 358.384802 -43.7939)
			(xy 358.362156 -43.744315) (xy 358.346797 -43.692012) (xy 358.339039 -43.638056) (xy 357.803812 -43.638056)
			(xy 357.796501 -43.688905) (xy 357.781145 -43.741204) (xy 357.758503 -43.790785) (xy 357.729035 -43.836639)
			(xy 357.693341 -43.877833) (xy 357.652149 -43.913528) (xy 357.606295 -43.942997) (xy 357.556715 -43.965641)
			(xy 357.504417 -43.980999) (xy 357.450465 -43.988757) (xy 357.423212 -43.989244) (xy 356.559612 -43.989244)
			(xy 356.532361 -43.98871) (xy 356.478414 -43.980955) (xy 356.42612 -43.965601) (xy 356.376543 -43.942962)
			(xy 356.330692 -43.913497) (xy 356.289502 -43.877806) (xy 356.253811 -43.836617) (xy 356.224344 -43.790768)
			(xy 356.201703 -43.741192) (xy 356.186348 -43.688898) (xy 356.178591 -43.634951) (xy 355.659468 -43.634951)
			(xy 355.659407 -43.638033) (xy 355.651654 -43.691977) (xy 355.636302 -43.744269) (xy 355.613666 -43.793843)
			(xy 355.584204 -43.839692) (xy 355.548518 -43.880882) (xy 355.507334 -43.916573) (xy 355.461489 -43.946041)
			(xy 355.411917 -43.968684) (xy 355.359628 -43.984043) (xy 355.305685 -43.991803) (xy 355.278436 -43.992292)
			(xy 354.414836 -43.992292) (xy 354.388369 -43.991825) (xy 354.335944 -43.984518) (xy 354.285033 -43.970025)
			(xy 354.236619 -43.948625) (xy 354.191633 -43.920731) (xy 354.170996 -43.904154) (xy 354.158864 -43.905712)
			(xy 354.134459 -43.907367) (xy 354.122228 -43.907456) (xy 354.095726 -43.907027) (xy 354.043314 -43.899131)
			(xy 353.992664 -43.883511) (xy 353.944908 -43.860517) (xy 353.901112 -43.830661) (xy 353.862256 -43.794611)
			(xy 353.829208 -43.753172) (xy 353.802705 -43.70727) (xy 353.783339 -43.65793) (xy 353.771544 -43.606256)
			(xy 353.767583 -43.5534) (xy 339.506567 -43.5534) (xy 339.532091 -43.598297) (xy 339.551085 -43.647376)
			(xy 339.562649 -43.698717) (xy 339.566532 -43.751201) (xy 339.562649 -43.803685) (xy 339.551085 -43.855025)
			(xy 339.53209 -43.904105) (xy 339.50608 -43.949855) (xy 339.47362 -43.99128) (xy 339.435418 -44.027476)
			(xy 339.392304 -44.057656) (xy 339.345219 -44.081163) (xy 339.295186 -44.097484) (xy 339.243297 -44.106265)
			(xy 339.217 -44.107354) (xy 339.217 -44.687236) (xy 339.221826 -44.69765) (xy 339.232617 -44.721546)
			(xy 339.247844 -44.771718) (xy 339.255541 -44.823581) (xy 339.255541 -44.840452) (xy 348.511075 -44.840452)
			(xy 348.511075 -44.785948) (xy 348.518832 -44.731999) (xy 348.534188 -44.679702) (xy 348.556831 -44.630124)
			(xy 348.586298 -44.584273) (xy 348.621992 -44.543082) (xy 348.663184 -44.50739) (xy 348.709036 -44.477924)
			(xy 348.758616 -44.455283) (xy 348.810912 -44.439929) (xy 348.864862 -44.432174) (xy 348.892114 -44.431712)
			(xy 349.755714 -44.431712) (xy 349.782966 -44.432159) (xy 349.836915 -44.439917) (xy 349.889211 -44.455274)
			(xy 349.938789 -44.477918) (xy 349.98464 -44.507386) (xy 350.025831 -44.543079) (xy 350.061523 -44.584271)
			(xy 350.090989 -44.630123) (xy 350.11363 -44.679702) (xy 350.128986 -44.731999) (xy 350.136742 -44.785948)
			(xy 350.136742 -44.840452) (xy 350.128986 -44.894401) (xy 350.11363 -44.946698) (xy 350.090989 -44.996277)
			(xy 350.072098 -45.025673) (xy 355.559288 -45.025673) (xy 355.559288 -44.971127) (xy 355.56705 -44.917137)
			(xy 355.582418 -44.864802) (xy 355.605077 -44.815186) (xy 355.634567 -44.7693) (xy 355.670288 -44.728078)
			(xy 355.711511 -44.692359) (xy 355.757398 -44.662871) (xy 355.807015 -44.640213) (xy 355.859351 -44.624847)
			(xy 355.913341 -44.617087) (xy 355.940614 -44.616624) (xy 356.804214 -44.616624) (xy 356.831482 -44.617139)
			(xy 356.885462 -44.624902) (xy 356.937788 -44.640268) (xy 356.987394 -44.662925) (xy 357.033272 -44.69241)
			(xy 357.074486 -44.728124) (xy 357.110199 -44.769339) (xy 357.139682 -44.815218) (xy 357.162337 -44.864825)
			(xy 357.177701 -44.917152) (xy 357.185462 -44.971132) (xy 357.185462 -45.025668) (xy 357.177701 -45.079648)
			(xy 357.162337 -45.131975) (xy 357.139682 -45.181582) (xy 357.110199 -45.227461) (xy 357.074486 -45.268676)
			(xy 357.033272 -45.30439) (xy 356.987394 -45.333875) (xy 356.937788 -45.356532) (xy 356.885462 -45.371898)
			(xy 356.831482 -45.379661) (xy 356.804214 -45.380148) (xy 355.940614 -45.380148) (xy 355.913341 -45.379713)
			(xy 355.859351 -45.371953) (xy 355.807015 -45.356587) (xy 355.757398 -45.333929) (xy 355.711511 -45.304441)
			(xy 355.670288 -45.268722) (xy 355.634567 -45.2275) (xy 355.605077 -45.181614) (xy 355.582418 -45.131998)
			(xy 355.56705 -45.079663) (xy 355.559288 -45.025673) (xy 350.072098 -45.025673) (xy 350.061523 -45.042129)
			(xy 350.025831 -45.083321) (xy 349.98464 -45.119014) (xy 349.938789 -45.148482) (xy 349.889211 -45.171126)
			(xy 349.836915 -45.186483) (xy 349.782966 -45.194241) (xy 349.755714 -45.194728) (xy 348.892114 -45.194728)
			(xy 348.864862 -45.194226) (xy 348.810912 -45.186471) (xy 348.758616 -45.171117) (xy 348.709036 -45.148476)
			(xy 348.663184 -45.11901) (xy 348.621992 -45.083318) (xy 348.586298 -45.042127) (xy 348.556831 -44.996276)
			(xy 348.534188 -44.946698) (xy 348.518832 -44.894401) (xy 348.511075 -44.840452) (xy 339.255541 -44.840452)
			(xy 339.255541 -44.876012) (xy 339.247845 -44.927875) (xy 339.232619 -44.978047) (xy 339.221826 -45.001942)
			(xy 339.217 -45.012356) (xy 339.217 -46.830068) (xy 356.445326 -46.830068) (xy 356.445326 -46.775532)
			(xy 356.453087 -46.721552) (xy 356.468451 -46.669225) (xy 356.491104 -46.619618) (xy 356.520587 -46.573739)
			(xy 356.556298 -46.532522) (xy 356.597512 -46.496807) (xy 356.643388 -46.467321) (xy 356.692994 -46.444663)
			(xy 356.745319 -46.429294) (xy 356.799298 -46.421529) (xy 356.826566 -46.42104) (xy 357.690166 -46.42104)
			(xy 357.717439 -46.421497) (xy 357.77143 -46.429255) (xy 357.823767 -46.444619) (xy 357.873384 -46.467275)
			(xy 357.919272 -46.496761) (xy 357.960497 -46.532479) (xy 357.996218 -46.5737) (xy 358.025709 -46.619586)
			(xy 358.048369 -46.669202) (xy 358.063737 -46.721537) (xy 358.0715 -46.775527) (xy 358.0715 -46.830069)
			(xy 358.762026 -46.830069) (xy 358.762026 -46.775531) (xy 358.769788 -46.721547) (xy 358.785153 -46.669218)
			(xy 358.807809 -46.619608) (xy 358.837295 -46.573728) (xy 358.87301 -46.53251) (xy 358.914228 -46.496795)
			(xy 358.960108 -46.467309) (xy 359.009718 -46.444653) (xy 359.062047 -46.429288) (xy 359.116031 -46.421526)
			(xy 359.1433 -46.42104) (xy 360.0069 -46.42104) (xy 360.03417 -46.421522) (xy 360.088153 -46.429284)
			(xy 360.140483 -46.44465) (xy 360.190094 -46.467306) (xy 360.235975 -46.496792) (xy 360.277193 -46.532507)
			(xy 360.312908 -46.573725) (xy 360.342394 -46.619606) (xy 360.36505 -46.669217) (xy 360.380416 -46.721547)
			(xy 360.388178 -46.77553) (xy 360.388178 -46.83007) (xy 360.388178 -46.830073) (xy 361.088604 -46.830073)
			(xy 361.088604 -46.775527) (xy 361.096367 -46.721537) (xy 361.111735 -46.669202) (xy 361.134395 -46.619586)
			(xy 361.163887 -46.573701) (xy 361.199608 -46.53248) (xy 361.240833 -46.496763) (xy 361.286721 -46.467276)
			(xy 361.336339 -46.444621) (xy 361.388676 -46.429258) (xy 361.442667 -46.421501) (xy 361.46994 -46.42104)
			(xy 362.33354 -46.42104) (xy 362.360808 -46.421525) (xy 362.414787 -46.429291) (xy 362.467112 -46.44466)
			(xy 362.516718 -46.467319) (xy 362.562594 -46.496806) (xy 362.603807 -46.532522) (xy 362.639518 -46.573738)
			(xy 362.669 -46.619618) (xy 362.691654 -46.669225) (xy 362.707017 -46.721552) (xy 362.714778 -46.775532)
			(xy 362.714778 -46.830068) (xy 362.707017 -46.884048) (xy 362.691654 -46.936375) (xy 362.672751 -46.977768)
			(xy 396.642323 -46.977768) (xy 396.642323 -46.891996) (xy 396.650237 -46.806588) (xy 396.665998 -46.722276)
			(xy 396.689471 -46.639777) (xy 396.720456 -46.559796) (xy 396.758688 -46.483015) (xy 396.803842 -46.41009)
			(xy 396.855532 -46.341642) (xy 396.913317 -46.278255) (xy 396.976704 -46.22047) (xy 397.045152 -46.16878)
			(xy 397.118077 -46.123626) (xy 397.194858 -46.085394) (xy 397.274839 -46.054409) (xy 397.357338 -46.030936)
			(xy 397.44165 -46.015175) (xy 397.527058 -46.007261) (xy 397.61283 -46.007261) (xy 397.698238 -46.015175)
			(xy 397.78255 -46.030936) (xy 397.865049 -46.054409) (xy 397.94503 -46.085394) (xy 398.021811 -46.123626)
			(xy 398.094736 -46.16878) (xy 398.163184 -46.22047) (xy 398.226571 -46.278255) (xy 398.284356 -46.341642)
			(xy 398.336046 -46.41009) (xy 398.3812 -46.483015) (xy 398.419432 -46.559796) (xy 398.450417 -46.639777)
			(xy 398.47389 -46.722276) (xy 398.489651 -46.806588) (xy 398.497565 -46.891996) (xy 398.49806 -46.934882)
			(xy 398.497565 -46.977768) (xy 398.489651 -47.063176) (xy 398.47389 -47.147488) (xy 398.450417 -47.229987)
			(xy 398.419432 -47.309968) (xy 398.3812 -47.386749) (xy 398.336046 -47.459674) (xy 398.284356 -47.528122)
			(xy 398.226571 -47.591509) (xy 398.163184 -47.649294) (xy 398.094736 -47.700984) (xy 398.021811 -47.746138)
			(xy 397.94503 -47.78437) (xy 397.865049 -47.815355) (xy 397.78255 -47.838828) (xy 397.698238 -47.854589)
			(xy 397.61283 -47.862503) (xy 397.527058 -47.862503) (xy 397.44165 -47.854589) (xy 397.357338 -47.838828)
			(xy 397.274839 -47.815355) (xy 397.194858 -47.78437) (xy 397.118077 -47.746138) (xy 397.045152 -47.700984)
			(xy 396.976704 -47.649294) (xy 396.913317 -47.591509) (xy 396.855532 -47.528122) (xy 396.803842 -47.459674)
			(xy 396.758688 -47.386749) (xy 396.720456 -47.309968) (xy 396.689471 -47.229987) (xy 396.665998 -47.147488)
			(xy 396.650237 -47.063176) (xy 396.642323 -46.977768) (xy 362.672751 -46.977768) (xy 362.669 -46.985982)
			(xy 362.639518 -47.031862) (xy 362.603807 -47.073078) (xy 362.562594 -47.108794) (xy 362.516718 -47.138281)
			(xy 362.467112 -47.16094) (xy 362.414787 -47.176309) (xy 362.360808 -47.184075) (xy 362.33354 -47.184564)
			(xy 361.46994 -47.184564) (xy 361.442667 -47.184099) (xy 361.388676 -47.176342) (xy 361.336339 -47.160979)
			(xy 361.286721 -47.138324) (xy 361.240833 -47.108837) (xy 361.199608 -47.07312) (xy 361.163887 -47.031899)
			(xy 361.134395 -46.986014) (xy 361.111735 -46.936398) (xy 361.096367 -46.884063) (xy 361.088604 -46.830073)
			(xy 360.388178 -46.830073) (xy 360.380416 -46.884053) (xy 360.36505 -46.936383) (xy 360.342394 -46.985994)
			(xy 360.312908 -47.031875) (xy 360.277193 -47.073093) (xy 360.235975 -47.108808) (xy 360.190094 -47.138294)
			(xy 360.140483 -47.16095) (xy 360.088153 -47.176316) (xy 360.03417 -47.184078) (xy 360.0069 -47.184564)
			(xy 359.1433 -47.184564) (xy 359.116031 -47.184074) (xy 359.062047 -47.176312) (xy 359.009718 -47.160947)
			(xy 358.960108 -47.138291) (xy 358.914228 -47.108805) (xy 358.87301 -47.07309) (xy 358.837295 -47.031872)
			(xy 358.807809 -46.985992) (xy 358.785153 -46.936382) (xy 358.769788 -46.884053) (xy 358.762026 -46.830069)
			(xy 358.0715 -46.830069) (xy 358.0715 -46.830073) (xy 358.063737 -46.884063) (xy 358.048369 -46.936398)
			(xy 358.025709 -46.986014) (xy 357.996218 -47.0319) (xy 357.960497 -47.073121) (xy 357.919272 -47.108839)
			(xy 357.873384 -47.138325) (xy 357.823767 -47.160981) (xy 357.77143 -47.176345) (xy 357.717439 -47.184103)
			(xy 357.690166 -47.184564) (xy 356.826566 -47.184564) (xy 356.799298 -47.184071) (xy 356.745319 -47.176306)
			(xy 356.692994 -47.160937) (xy 356.643388 -47.138279) (xy 356.597512 -47.108793) (xy 356.556298 -47.073078)
			(xy 356.520587 -47.031861) (xy 356.491104 -46.985982) (xy 356.468451 -46.936375) (xy 356.453087 -46.884048)
			(xy 356.445326 -46.830068) (xy 339.217 -46.830068) (xy 339.217 -49.487836) (xy 339.221826 -49.49825)
			(xy 339.232617 -49.522146) (xy 339.247844 -49.572318) (xy 339.255541 -49.624181) (xy 339.255541 -49.676612)
			(xy 339.247845 -49.728475) (xy 339.232619 -49.778647) (xy 339.221826 -49.802542) (xy 339.217 -49.812956)
			(xy 339.217 -50.234955) (xy 350.291827 -50.234955) (xy 350.291827 -50.180445) (xy 350.299585 -50.126489)
			(xy 350.314942 -50.074187) (xy 350.337587 -50.024602) (xy 350.367058 -49.978745) (xy 350.402755 -49.937549)
			(xy 350.443952 -49.901853) (xy 350.489809 -49.872383) (xy 350.539394 -49.849739) (xy 350.591697 -49.834383)
			(xy 350.645653 -49.826626) (xy 350.672908 -49.826164) (xy 351.536508 -49.826164) (xy 351.563757 -49.826707)
			(xy 351.6177 -49.834464) (xy 351.66999 -49.849818) (xy 351.719562 -49.872458) (xy 351.765408 -49.901922)
			(xy 351.806594 -49.937611) (xy 351.842282 -49.978798) (xy 351.871746 -50.024645) (xy 351.894385 -50.074218)
			(xy 351.909738 -50.126508) (xy 351.917494 -50.180451) (xy 351.917494 -50.234949) (xy 351.917493 -50.234956)
			(xy 352.489927 -50.234956) (xy 352.489927 -50.180444) (xy 352.497685 -50.126487) (xy 352.513044 -50.074183)
			(xy 352.535689 -50.024598) (xy 352.565162 -49.97874) (xy 352.600861 -49.937544) (xy 352.642059 -49.901848)
			(xy 352.687919 -49.872378) (xy 352.737506 -49.849735) (xy 352.78981 -49.83438) (xy 352.843768 -49.826625)
			(xy 352.871024 -49.826164) (xy 353.734624 -49.826164) (xy 353.761872 -49.826708) (xy 353.815813 -49.834467)
			(xy 353.868101 -49.849823) (xy 353.917672 -49.872463) (xy 353.963516 -49.901928) (xy 354.0047 -49.937617)
			(xy 354.040386 -49.978804) (xy 354.069848 -50.024649) (xy 354.092486 -50.074221) (xy 354.107839 -50.12651)
			(xy 354.115594 -50.180452) (xy 354.115594 -50.234948) (xy 354.115593 -50.234956) (xy 354.712427 -50.234956)
			(xy 354.712427 -50.180444) (xy 354.720185 -50.126487) (xy 354.735544 -50.074183) (xy 354.758189 -50.024598)
			(xy 354.787662 -49.97874) (xy 354.823361 -49.937544) (xy 354.864559 -49.901848) (xy 354.910419 -49.872378)
			(xy 354.960006 -49.849735) (xy 355.01231 -49.83438) (xy 355.066268 -49.826625) (xy 355.093524 -49.826164)
			(xy 355.957124 -49.826164) (xy 355.984372 -49.826708) (xy 356.038313 -49.834467) (xy 356.090601 -49.849823)
			(xy 356.140172 -49.872463) (xy 356.186016 -49.901928) (xy 356.2272 -49.937617) (xy 356.262886 -49.978804)
			(xy 356.292348 -50.024649) (xy 356.314986 -50.074221) (xy 356.330339 -50.12651) (xy 356.338094 -50.180452)
			(xy 356.338094 -50.234948) (xy 356.338093 -50.234957) (xy 356.942527 -50.234957) (xy 356.942527 -50.180443)
			(xy 356.950286 -50.126484) (xy 356.965645 -50.074179) (xy 356.988293 -50.024592) (xy 357.017767 -49.978734)
			(xy 357.053468 -49.937537) (xy 357.094669 -49.90184) (xy 357.140531 -49.872371) (xy 357.19012 -49.84973)
			(xy 357.242427 -49.834376) (xy 357.296387 -49.826624) (xy 357.323644 -49.826164) (xy 358.187244 -49.826164)
			(xy 358.214491 -49.826709) (xy 358.26843 -49.83447) (xy 358.320716 -49.849828) (xy 358.370284 -49.87247)
			(xy 358.416125 -49.901935) (xy 358.457307 -49.937624) (xy 358.492991 -49.97881) (xy 358.522451 -50.024655)
			(xy 358.545087 -50.074226) (xy 358.560439 -50.126513) (xy 358.568194 -50.180453) (xy 358.568194 -50.234947)
			(xy 358.560439 -50.288887) (xy 358.545087 -50.341174) (xy 358.522451 -50.390745) (xy 358.492991 -50.43659)
			(xy 358.457307 -50.477776) (xy 358.416125 -50.513465) (xy 358.370284 -50.54293) (xy 358.320716 -50.565572)
			(xy 358.26843 -50.58093) (xy 358.214491 -50.588691) (xy 358.187244 -50.58918) (xy 357.323644 -50.58918)
			(xy 357.296387 -50.588776) (xy 357.242427 -50.581024) (xy 357.19012 -50.56567) (xy 357.140531 -50.543029)
			(xy 357.094669 -50.51356) (xy 357.053468 -50.477863) (xy 357.017767 -50.436666) (xy 356.988293 -50.390808)
			(xy 356.965645 -50.341221) (xy 356.950286 -50.288916) (xy 356.942527 -50.234957) (xy 356.338093 -50.234957)
			(xy 356.330339 -50.28889) (xy 356.314986 -50.341179) (xy 356.292348 -50.390751) (xy 356.262886 -50.436596)
			(xy 356.2272 -50.477783) (xy 356.186016 -50.513472) (xy 356.140172 -50.542937) (xy 356.090601 -50.565577)
			(xy 356.038313 -50.580933) (xy 355.984372 -50.588692) (xy 355.957124 -50.58918) (xy 355.093524 -50.58918)
			(xy 355.066268 -50.588775) (xy 355.01231 -50.58102) (xy 354.960006 -50.565665) (xy 354.910419 -50.543022)
			(xy 354.864559 -50.513552) (xy 354.823361 -50.477856) (xy 354.787662 -50.43666) (xy 354.758189 -50.390802)
			(xy 354.735544 -50.341217) (xy 354.720185 -50.288913) (xy 354.712427 -50.234956) (xy 354.115593 -50.234956)
			(xy 354.107839 -50.28889) (xy 354.092486 -50.341179) (xy 354.069848 -50.390751) (xy 354.040386 -50.436596)
			(xy 354.0047 -50.477783) (xy 353.963516 -50.513472) (xy 353.917672 -50.542937) (xy 353.868101 -50.565577)
			(xy 353.815813 -50.580933) (xy 353.761872 -50.588692) (xy 353.734624 -50.58918) (xy 352.871024 -50.58918)
			(xy 352.843768 -50.588775) (xy 352.78981 -50.58102) (xy 352.737506 -50.565665) (xy 352.687919 -50.543022)
			(xy 352.642059 -50.513552) (xy 352.600861 -50.477856) (xy 352.565162 -50.43666) (xy 352.535689 -50.390802)
			(xy 352.513044 -50.341217) (xy 352.497685 -50.288913) (xy 352.489927 -50.234956) (xy 351.917493 -50.234956)
			(xy 351.909738 -50.288892) (xy 351.894385 -50.341182) (xy 351.871746 -50.390755) (xy 351.842282 -50.436602)
			(xy 351.806594 -50.477789) (xy 351.765408 -50.513477) (xy 351.719562 -50.542942) (xy 351.66999 -50.565582)
			(xy 351.6177 -50.580936) (xy 351.563757 -50.588693) (xy 351.536508 -50.58918) (xy 350.672908 -50.58918)
			(xy 350.645653 -50.588774) (xy 350.591697 -50.581017) (xy 350.539394 -50.565661) (xy 350.489809 -50.543017)
			(xy 350.443952 -50.513547) (xy 350.402755 -50.477851) (xy 350.367058 -50.436655) (xy 350.337587 -50.390798)
			(xy 350.314942 -50.341213) (xy 350.299585 -50.288911) (xy 350.291827 -50.234955) (xy 339.217 -50.234955)
			(xy 339.217 -55.911852) (xy 357.10365 -55.911852) (xy 357.10365 -55.857348) (xy 357.111406 -55.803398)
			(xy 357.126762 -55.751101) (xy 357.149403 -55.701521) (xy 357.17887 -55.655668) (xy 357.214562 -55.614476)
			(xy 357.255752 -55.578782) (xy 357.301604 -55.549313) (xy 357.351182 -55.526669) (xy 357.403478 -55.511311)
			(xy 357.457428 -55.503551) (xy 357.48468 -55.503064) (xy 358.34828 -55.503064) (xy 358.375532 -55.503582)
			(xy 358.429481 -55.511336) (xy 358.481777 -55.526689) (xy 358.531356 -55.549329) (xy 358.577209 -55.578794)
			(xy 358.618401 -55.614485) (xy 358.654094 -55.655675) (xy 358.683562 -55.701526) (xy 358.706204 -55.751104)
			(xy 358.72156 -55.8034) (xy 358.729317 -55.857348) (xy 358.729317 -55.911852) (xy 358.729316 -55.911856)
			(xy 359.950927 -55.911856) (xy 359.950927 -55.857344) (xy 359.958685 -55.803388) (xy 359.974043 -55.751084)
			(xy 359.996689 -55.701499) (xy 360.026161 -55.655642) (xy 360.061859 -55.614445) (xy 360.103058 -55.578749)
			(xy 360.148917 -55.549279) (xy 360.198503 -55.526636) (xy 360.250807 -55.511281) (xy 360.304764 -55.503526)
			(xy 360.33202 -55.503064) (xy 361.19562 -55.503064) (xy 361.222868 -55.503608) (xy 361.27681 -55.511366)
			(xy 361.329098 -55.526722) (xy 361.378669 -55.549362) (xy 361.424514 -55.578827) (xy 361.465699 -55.614516)
			(xy 361.501385 -55.655702) (xy 361.530847 -55.701548) (xy 361.553485 -55.75112) (xy 361.568838 -55.80341)
			(xy 361.576594 -55.857352) (xy 361.576594 -55.911848) (xy 361.576593 -55.911857) (xy 363.514527 -55.911857)
			(xy 363.514527 -55.857343) (xy 363.522286 -55.803385) (xy 363.537645 -55.75108) (xy 363.560292 -55.701493)
			(xy 363.589766 -55.655635) (xy 363.625466 -55.614438) (xy 363.666667 -55.578742) (xy 363.712529 -55.549273)
			(xy 363.762117 -55.526631) (xy 363.814424 -55.511277) (xy 363.868383 -55.503524) (xy 363.89564 -55.503064)
			(xy 364.75924 -55.503064) (xy 364.786487 -55.503609) (xy 364.840427 -55.511369) (xy 364.892713 -55.526727)
			(xy 364.942281 -55.549369) (xy 364.988123 -55.578834) (xy 365.029306 -55.614523) (xy 365.06499 -55.655709)
			(xy 365.094451 -55.701554) (xy 365.117087 -55.751125) (xy 365.132439 -55.803412) (xy 365.140194 -55.857353)
			(xy 365.140194 -55.911847) (xy 365.132439 -55.965788) (xy 365.117087 -56.018075) (xy 365.094451 -56.067646)
			(xy 365.06499 -56.113491) (xy 365.029306 -56.154677) (xy 364.988123 -56.190366) (xy 364.942281 -56.219831)
			(xy 364.892713 -56.242473) (xy 364.840427 -56.257831) (xy 364.786487 -56.265591) (xy 364.75924 -56.26608)
			(xy 363.89564 -56.26608) (xy 363.868383 -56.265676) (xy 363.814424 -56.257923) (xy 363.762117 -56.242569)
			(xy 363.712529 -56.219927) (xy 363.666667 -56.190458) (xy 363.625466 -56.154762) (xy 363.589766 -56.113565)
			(xy 363.560292 -56.067707) (xy 363.537645 -56.01812) (xy 363.522286 -55.965815) (xy 363.514527 -55.911857)
			(xy 361.576593 -55.911857) (xy 361.568838 -55.96579) (xy 361.553485 -56.01808) (xy 361.530847 -56.067652)
			(xy 361.501385 -56.113498) (xy 361.465699 -56.154684) (xy 361.424514 -56.190373) (xy 361.378669 -56.219838)
			(xy 361.329098 -56.242478) (xy 361.27681 -56.257834) (xy 361.222868 -56.265592) (xy 361.19562 -56.26608)
			(xy 360.33202 -56.26608) (xy 360.304764 -56.265674) (xy 360.250807 -56.257919) (xy 360.198503 -56.242564)
			(xy 360.148917 -56.219921) (xy 360.103058 -56.190451) (xy 360.061859 -56.154755) (xy 360.026161 -56.113558)
			(xy 359.996689 -56.067701) (xy 359.974043 -56.018116) (xy 359.958685 -55.965812) (xy 359.950927 -55.911856)
			(xy 358.729316 -55.911856) (xy 358.72156 -55.9658) (xy 358.706204 -56.018096) (xy 358.683562 -56.067674)
			(xy 358.654094 -56.113525) (xy 358.618401 -56.154715) (xy 358.577209 -56.190406) (xy 358.531356 -56.219871)
			(xy 358.481777 -56.242511) (xy 358.429481 -56.257864) (xy 358.375532 -56.265618) (xy 358.34828 -56.26608)
			(xy 357.48468 -56.26608) (xy 357.457428 -56.265649) (xy 357.403478 -56.257889) (xy 357.351182 -56.242531)
			(xy 357.301604 -56.219887) (xy 357.255752 -56.190418) (xy 357.214562 -56.154724) (xy 357.17887 -56.113532)
			(xy 357.149403 -56.067679) (xy 357.126762 -56.018099) (xy 357.111406 -55.965802) (xy 357.10365 -55.911852)
			(xy 339.217 -55.911852) (xy 339.217 -56.200548) (xy 339.216384 -56.225503) (xy 339.206638 -56.274452)
			(xy 339.187531 -56.320559) (xy 339.159797 -56.362053) (xy 339.142578 -56.380126) (xy 338.405978 -57.116726)
			(xy 338.387938 -57.133988) (xy 338.346445 -57.161751) (xy 338.300327 -57.18087) (xy 338.251362 -57.190607)
			(xy 338.2264 -57.191148) (xy 337.798156 -57.191148) (xy 337.77732 -57.206519) (xy 337.732088 -57.231716)
			(xy 337.683687 -57.250103) (xy 337.633134 -57.261292) (xy 337.581494 -57.265048) (xy 337.529854 -57.261292)
			(xy 337.479301 -57.250103) (xy 337.4309 -57.231716) (xy 337.385668 -57.206519) (xy 337.364832 -57.191148)
			(xy 336.17027 -57.191148) (xy 336.149434 -57.206519) (xy 336.104202 -57.231716) (xy 336.055801 -57.250103)
			(xy 336.005248 -57.261292) (xy 335.953608 -57.265048) (xy 335.901968 -57.261292) (xy 335.851415 -57.250103)
			(xy 335.803014 -57.231716) (xy 335.757782 -57.206519) (xy 335.736946 -57.191148) (xy 332.912974 -57.191148)
			(xy 332.892138 -57.206519) (xy 332.846906 -57.231716) (xy 332.798505 -57.250103) (xy 332.747952 -57.261292)
			(xy 332.696312 -57.265048) (xy 332.644672 -57.261292) (xy 332.594119 -57.250103) (xy 332.545718 -57.231716)
			(xy 332.500486 -57.206519) (xy 332.47965 -57.191148) (xy 331.286612 -57.191148) (xy 331.265776 -57.206519)
			(xy 331.220544 -57.231716) (xy 331.172143 -57.250103) (xy 331.12159 -57.261292) (xy 331.06995 -57.265048)
			(xy 331.01831 -57.261292) (xy 330.967757 -57.250103) (xy 330.919356 -57.231716) (xy 330.874124 -57.206519)
			(xy 330.853288 -57.191148) (xy 330.076556 -57.191148) (xy 329.5142 -57.753504) (xy 329.5142 -61.480954)
			(xy 351.822512 -61.480954) (xy 351.822512 -60.617354) (xy 351.822998 -60.590103) (xy 351.830754 -60.536155)
			(xy 351.846109 -60.48386) (xy 351.868751 -60.434283) (xy 351.898217 -60.388433) (xy 351.933908 -60.347242)
			(xy 351.975099 -60.311551) (xy 352.020949 -60.282085) (xy 352.070526 -60.259443) (xy 352.122821 -60.244088)
			(xy 352.176769 -60.236332) (xy 352.231271 -60.236332) (xy 352.285219 -60.244088) (xy 352.337514 -60.259443)
			(xy 352.387091 -60.282085) (xy 352.432941 -60.311551) (xy 352.474132 -60.347242) (xy 352.509823 -60.388433)
			(xy 352.539289 -60.434283) (xy 352.561931 -60.48386) (xy 352.577286 -60.536155) (xy 352.585042 -60.590103)
			(xy 352.585528 -60.617354) (xy 352.585528 -61.223271) (xy 355.46889 -61.223271) (xy 355.46889 -61.168729)
			(xy 355.476653 -61.114741) (xy 355.492019 -61.062408) (xy 355.514676 -61.012794) (xy 355.544164 -60.966909)
			(xy 355.579881 -60.925688) (xy 355.621101 -60.88997) (xy 355.666985 -60.860481) (xy 355.716598 -60.837822)
			(xy 355.768931 -60.822455) (xy 355.822919 -60.814691) (xy 355.85019 -60.814204) (xy 356.71379 -60.814204)
			(xy 356.741059 -60.814735) (xy 356.795042 -60.822495) (xy 356.847371 -60.837859) (xy 356.896981 -60.860514)
			(xy 356.942862 -60.889999) (xy 356.98408 -60.925713) (xy 357.019795 -60.96693) (xy 357.049281 -61.01281)
			(xy 357.071937 -61.062419) (xy 357.087303 -61.114748) (xy 357.095065 -61.168731) (xy 357.095065 -61.223269)
			(xy 357.087303 -61.277252) (xy 357.071937 -61.329581) (xy 357.049281 -61.37919) (xy 357.019795 -61.42507)
			(xy 356.98408 -61.466287) (xy 356.942862 -61.502001) (xy 356.896981 -61.531486) (xy 356.847371 -61.554141)
			(xy 356.795042 -61.569505) (xy 356.741059 -61.577265) (xy 356.71379 -61.577728) (xy 355.85019 -61.577728)
			(xy 355.822919 -61.577309) (xy 355.768931 -61.569545) (xy 355.716598 -61.554178) (xy 355.666985 -61.531519)
			(xy 355.621101 -61.50203) (xy 355.579881 -61.466312) (xy 355.544164 -61.425091) (xy 355.514676 -61.379206)
			(xy 355.492019 -61.329592) (xy 355.476653 -61.277259) (xy 355.46889 -61.223271) (xy 352.585528 -61.223271)
			(xy 352.585528 -61.480954) (xy 352.585042 -61.508205) (xy 352.577286 -61.562153) (xy 352.561931 -61.614448)
			(xy 352.539289 -61.664025) (xy 352.509823 -61.709875) (xy 352.474132 -61.751066) (xy 352.432941 -61.786757)
			(xy 352.387091 -61.816223) (xy 352.337514 -61.838865) (xy 352.285219 -61.85422) (xy 352.231271 -61.861976)
			(xy 352.176769 -61.861976) (xy 352.122821 -61.85422) (xy 352.070526 -61.838865) (xy 352.020949 -61.816223)
			(xy 351.975099 -61.786757) (xy 351.933908 -61.751066) (xy 351.898217 -61.709875) (xy 351.868751 -61.664025)
			(xy 351.846109 -61.614448) (xy 351.830754 -61.562153) (xy 351.822998 -61.508205) (xy 351.822512 -61.480954)
			(xy 329.5142 -61.480954) (xy 329.5142 -63.269876) (xy 350.300544 -63.269876) (xy 350.300544 -62.406276)
			(xy 350.30103 -62.379025) (xy 350.308786 -62.325077) (xy 350.324141 -62.272782) (xy 350.346783 -62.223205)
			(xy 350.376249 -62.177355) (xy 350.41194 -62.136164) (xy 350.453131 -62.100473) (xy 350.498981 -62.071007)
			(xy 350.548558 -62.048365) (xy 350.600853 -62.03301) (xy 350.654801 -62.025254) (xy 350.709303 -62.025254)
			(xy 350.763251 -62.03301) (xy 350.815546 -62.048365) (xy 350.865123 -62.071007) (xy 350.910973 -62.100473)
			(xy 350.952164 -62.136164) (xy 350.987855 -62.177355) (xy 351.017321 -62.223205) (xy 351.039963 -62.272782)
			(xy 351.055318 -62.325077) (xy 351.063074 -62.379025) (xy 351.06356 -62.406276) (xy 351.06356 -63.269876)
			(xy 351.063074 -63.297127) (xy 351.055318 -63.351075) (xy 351.039963 -63.40337) (xy 351.017321 -63.452947)
			(xy 350.987855 -63.498797) (xy 350.952164 -63.539988) (xy 350.910973 -63.575679) (xy 350.865123 -63.605145)
			(xy 350.815546 -63.627787) (xy 350.763251 -63.643142) (xy 350.709303 -63.650898) (xy 350.654801 -63.650898)
			(xy 350.600853 -63.643142) (xy 350.548558 -63.627787) (xy 350.498981 -63.605145) (xy 350.453131 -63.575679)
			(xy 350.41194 -63.539988) (xy 350.376249 -63.498797) (xy 350.346783 -63.452947) (xy 350.324141 -63.40337)
			(xy 350.308786 -63.351075) (xy 350.30103 -63.297127) (xy 350.300544 -63.269876) (xy 329.5142 -63.269876)
			(xy 329.5142 -65.329562) (xy 352.362008 -65.329562) (xy 352.362008 -64.465962) (xy 352.362494 -64.438711)
			(xy 352.37025 -64.384763) (xy 352.385605 -64.332468) (xy 352.408247 -64.282891) (xy 352.437713 -64.237041)
			(xy 352.473404 -64.19585) (xy 352.514595 -64.160159) (xy 352.560445 -64.130693) (xy 352.610022 -64.108051)
			(xy 352.662317 -64.092696) (xy 352.716265 -64.08494) (xy 352.770767 -64.08494) (xy 352.824715 -64.092696)
			(xy 352.87701 -64.108051) (xy 352.926587 -64.130693) (xy 352.972437 -64.160159) (xy 353.013628 -64.19585)
			(xy 353.049319 -64.237041) (xy 353.078785 -64.282891) (xy 353.101427 -64.332468) (xy 353.116782 -64.384763)
			(xy 353.124538 -64.438711) (xy 353.125024 -64.465962) (xy 353.125024 -65.329562) (xy 353.124538 -65.356813)
			(xy 353.116782 -65.410761) (xy 353.101427 -65.463056) (xy 353.078785 -65.512633) (xy 353.049319 -65.558483)
			(xy 353.013628 -65.599674) (xy 352.972437 -65.635365) (xy 352.926587 -65.664831) (xy 352.87701 -65.687473)
			(xy 352.824715 -65.702828) (xy 352.770767 -65.710584) (xy 352.716265 -65.710584) (xy 352.662317 -65.702828)
			(xy 352.610022 -65.687473) (xy 352.560445 -65.664831) (xy 352.514595 -65.635365) (xy 352.473404 -65.599674)
			(xy 352.437713 -65.558483) (xy 352.408247 -65.512633) (xy 352.385605 -65.463056) (xy 352.37025 -65.410761)
			(xy 352.362494 -65.356813) (xy 352.362008 -65.329562) (xy 329.5142 -65.329562) (xy 329.5142 -66.963544)
			(xy 350.27108 -66.963544) (xy 350.27108 -66.099944) (xy 350.271566 -66.072693) (xy 350.279322 -66.018745)
			(xy 350.294677 -65.96645) (xy 350.317319 -65.916873) (xy 350.346785 -65.871023) (xy 350.382476 -65.829832)
			(xy 350.423667 -65.794141) (xy 350.469517 -65.764675) (xy 350.519094 -65.742033) (xy 350.571389 -65.726678)
			(xy 350.625337 -65.718922) (xy 350.679839 -65.718922) (xy 350.733787 -65.726678) (xy 350.786082 -65.742033)
			(xy 350.835659 -65.764675) (xy 350.881509 -65.794141) (xy 350.9227 -65.829832) (xy 350.958391 -65.871023)
			(xy 350.987857 -65.916873) (xy 351.010499 -65.96645) (xy 351.025854 -66.018745) (xy 351.03361 -66.072693)
			(xy 351.034096 -66.099944) (xy 351.034096 -66.963544) (xy 351.03361 -66.990795) (xy 351.025854 -67.044743)
			(xy 351.010499 -67.097038) (xy 351.005595 -67.107776) (xy 396.642323 -67.107776) (xy 396.642323 -67.022004)
			(xy 396.650237 -66.936596) (xy 396.665998 -66.852284) (xy 396.689471 -66.769785) (xy 396.720456 -66.689804)
			(xy 396.758688 -66.613023) (xy 396.803842 -66.540098) (xy 396.855532 -66.47165) (xy 396.913317 -66.408263)
			(xy 396.976704 -66.350478) (xy 397.045152 -66.298788) (xy 397.118077 -66.253634) (xy 397.194858 -66.215402)
			(xy 397.274839 -66.184417) (xy 397.357338 -66.160944) (xy 397.44165 -66.145183) (xy 397.527058 -66.137269)
			(xy 397.61283 -66.137269) (xy 397.698238 -66.145183) (xy 397.78255 -66.160944) (xy 397.865049 -66.184417)
			(xy 397.94503 -66.215402) (xy 398.021811 -66.253634) (xy 398.094736 -66.298788) (xy 398.163184 -66.350478)
			(xy 398.226571 -66.408263) (xy 398.284356 -66.47165) (xy 398.336046 -66.540098) (xy 398.3812 -66.613023)
			(xy 398.419432 -66.689804) (xy 398.450417 -66.769785) (xy 398.47389 -66.852284) (xy 398.489651 -66.936596)
			(xy 398.497565 -67.022004) (xy 398.49806 -67.06489) (xy 398.497565 -67.107776) (xy 398.489651 -67.193184)
			(xy 398.47389 -67.277496) (xy 398.450417 -67.359995) (xy 398.419432 -67.439976) (xy 398.3812 -67.516757)
			(xy 398.336046 -67.589682) (xy 398.284356 -67.65813) (xy 398.226571 -67.721517) (xy 398.163184 -67.779302)
			(xy 398.094736 -67.830992) (xy 398.021811 -67.876146) (xy 397.94503 -67.914378) (xy 397.865049 -67.945363)
			(xy 397.78255 -67.968836) (xy 397.698238 -67.984597) (xy 397.61283 -67.992511) (xy 397.527058 -67.992511)
			(xy 397.44165 -67.984597) (xy 397.357338 -67.968836) (xy 397.274839 -67.945363) (xy 397.194858 -67.914378)
			(xy 397.118077 -67.876146) (xy 397.045152 -67.830992) (xy 396.976704 -67.779302) (xy 396.913317 -67.721517)
			(xy 396.855532 -67.65813) (xy 396.803842 -67.589682) (xy 396.758688 -67.516757) (xy 396.720456 -67.439976)
			(xy 396.689471 -67.359995) (xy 396.665998 -67.277496) (xy 396.650237 -67.193184) (xy 396.642323 -67.107776)
			(xy 351.005595 -67.107776) (xy 350.987857 -67.146615) (xy 350.958391 -67.192465) (xy 350.9227 -67.233656)
			(xy 350.881509 -67.269347) (xy 350.835659 -67.298813) (xy 350.786082 -67.321455) (xy 350.733787 -67.33681)
			(xy 350.679839 -67.344566) (xy 350.625337 -67.344566) (xy 350.571389 -67.33681) (xy 350.519094 -67.321455)
			(xy 350.469517 -67.298813) (xy 350.423667 -67.269347) (xy 350.382476 -67.233656) (xy 350.346785 -67.192465)
			(xy 350.317319 -67.146615) (xy 350.294677 -67.097038) (xy 350.279322 -67.044743) (xy 350.271566 -66.990795)
			(xy 350.27108 -66.963544) (xy 329.5142 -66.963544) (xy 329.5142 -69.10578) (xy 351.73158 -69.10578)
			(xy 351.73158 -68.24218) (xy 351.732066 -68.214911) (xy 351.739828 -68.160927) (xy 351.755193 -68.108597)
			(xy 351.77785 -68.058987) (xy 351.807336 -68.013106) (xy 351.843051 -67.971889) (xy 351.884268 -67.936174)
			(xy 351.930149 -67.906688) (xy 351.979759 -67.884031) (xy 352.032089 -67.868666) (xy 352.086073 -67.860904)
			(xy 352.140611 -67.860904) (xy 352.194595 -67.868666) (xy 352.246925 -67.884031) (xy 352.296535 -67.906688)
			(xy 352.342416 -67.936174) (xy 352.383633 -67.971889) (xy 352.419348 -68.013106) (xy 352.448834 -68.058987)
			(xy 352.471491 -68.108597) (xy 352.486856 -68.160927) (xy 352.494618 -68.214911) (xy 352.495104 -68.24218)
			(xy 352.495104 -69.10578) (xy 352.494618 -69.133049) (xy 352.486856 -69.187033) (xy 352.471491 -69.239363)
			(xy 352.448834 -69.288973) (xy 352.419348 -69.334854) (xy 352.383633 -69.376071) (xy 352.342416 -69.411786)
			(xy 352.296535 -69.441272) (xy 352.246925 -69.463929) (xy 352.194595 -69.479294) (xy 352.140611 -69.487056)
			(xy 352.086073 -69.487056) (xy 352.032089 -69.479294) (xy 351.979759 -69.463929) (xy 351.930149 -69.441272)
			(xy 351.884268 -69.411786) (xy 351.843051 -69.376071) (xy 351.807336 -69.334854) (xy 351.77785 -69.288973)
			(xy 351.755193 -69.239363) (xy 351.739828 -69.187033) (xy 351.732066 -69.133049) (xy 351.73158 -69.10578)
			(xy 329.5142 -69.10578) (xy 329.5142 -71.213074) (xy 341.168388 -71.213074) (xy 341.168388 -71.158526)
			(xy 341.176151 -71.104534) (xy 341.19152 -71.052197) (xy 341.214181 -71.00258) (xy 341.243673 -70.956692)
			(xy 341.279395 -70.91547) (xy 341.320621 -70.879751) (xy 341.366511 -70.850263) (xy 341.416131 -70.827607)
			(xy 341.46847 -70.812243) (xy 341.522462 -70.804485) (xy 341.549736 -70.804024) (xy 342.413336 -70.804024)
			(xy 342.440603 -70.804541) (xy 342.49458 -70.812306) (xy 342.546904 -70.827674) (xy 342.596508 -70.850332)
			(xy 342.642382 -70.879817) (xy 342.683594 -70.915531) (xy 342.719304 -70.956747) (xy 342.748786 -71.002624)
			(xy 342.771438 -71.05223) (xy 342.786801 -71.104555) (xy 342.794562 -71.158533) (xy 342.794562 -71.213067)
			(xy 342.786801 -71.267045) (xy 342.771438 -71.31937) (xy 342.748786 -71.368976) (xy 342.719304 -71.414853)
			(xy 342.683594 -71.456069) (xy 342.642382 -71.491783) (xy 342.596508 -71.521268) (xy 342.546904 -71.543926)
			(xy 342.49458 -71.559294) (xy 342.440603 -71.567059) (xy 342.413336 -71.567548) (xy 341.549736 -71.567548)
			(xy 341.522462 -71.567115) (xy 341.46847 -71.559357) (xy 341.416131 -71.543993) (xy 341.366511 -71.521337)
			(xy 341.320621 -71.491849) (xy 341.279395 -71.45613) (xy 341.243673 -71.414908) (xy 341.214181 -71.36902)
			(xy 341.19152 -71.319403) (xy 341.176151 -71.267066) (xy 341.168388 -71.213074) (xy 329.5142 -71.213074)
			(xy 329.5142 -71.844253) (xy 346.360454 -71.844253) (xy 346.360454 -71.789747) (xy 346.368211 -71.735796)
			(xy 346.383567 -71.683499) (xy 346.406209 -71.633919) (xy 346.435677 -71.588066) (xy 346.47137 -71.546873)
			(xy 346.512562 -71.511179) (xy 346.558415 -71.481711) (xy 346.607995 -71.459068) (xy 346.660293 -71.443712)
			(xy 346.714243 -71.435954) (xy 346.741496 -71.435468) (xy 347.605096 -71.435468) (xy 347.632347 -71.435979)
			(xy 347.686295 -71.443735) (xy 347.73859 -71.45909) (xy 347.788168 -71.481731) (xy 347.834019 -71.511197)
			(xy 347.875209 -71.546888) (xy 347.910901 -71.588078) (xy 347.940367 -71.633929) (xy 347.963009 -71.683506)
			(xy 347.978364 -71.735801) (xy 347.986121 -71.789749) (xy 347.986121 -71.844251) (xy 347.978364 -71.898199)
			(xy 347.963009 -71.950494) (xy 347.940367 -72.000071) (xy 347.910901 -72.045922) (xy 347.875209 -72.087112)
			(xy 347.834019 -72.122803) (xy 347.788168 -72.152269) (xy 347.73859 -72.17491) (xy 347.686295 -72.190265)
			(xy 347.632347 -72.198021) (xy 347.605096 -72.198484) (xy 346.741496 -72.198484) (xy 346.714243 -72.198046)
			(xy 346.660293 -72.190288) (xy 346.607995 -72.174932) (xy 346.558415 -72.152289) (xy 346.512562 -72.122821)
			(xy 346.47137 -72.087127) (xy 346.435677 -72.045934) (xy 346.406209 -72.000081) (xy 346.383567 -71.950501)
			(xy 346.368211 -71.898204) (xy 346.360454 -71.844253) (xy 329.5142 -71.844253) (xy 329.5142 -72.404055)
			(xy 332.037847 -72.404055) (xy 332.037847 -72.349545) (xy 332.045606 -72.295589) (xy 332.060964 -72.243286)
			(xy 332.083611 -72.193702) (xy 332.113083 -72.147846) (xy 332.148782 -72.106651) (xy 332.189981 -72.070957)
			(xy 332.235841 -72.041489) (xy 332.285427 -72.018849) (xy 332.337732 -72.003496) (xy 332.391689 -71.995744)
			(xy 332.418944 -71.995284) (xy 333.282544 -71.995284) (xy 333.309793 -71.995789) (xy 333.363734 -72.00355)
			(xy 333.416023 -72.018909) (xy 333.465593 -72.041552) (xy 333.511437 -72.071019) (xy 333.552622 -72.10671)
			(xy 333.588308 -72.147898) (xy 333.617769 -72.193745) (xy 333.640407 -72.243318) (xy 333.655759 -72.295609)
			(xy 333.660251 -72.326853) (xy 343.845854 -72.326853) (xy 343.845854 -72.272347) (xy 343.853611 -72.218396)
			(xy 343.868967 -72.166099) (xy 343.891609 -72.116519) (xy 343.921077 -72.070666) (xy 343.95677 -72.029473)
			(xy 343.997962 -71.993779) (xy 344.043815 -71.964311) (xy 344.093395 -71.941668) (xy 344.145693 -71.926312)
			(xy 344.199643 -71.918554) (xy 344.226896 -71.918068) (xy 345.090496 -71.918068) (xy 345.117747 -71.918579)
			(xy 345.171695 -71.926335) (xy 345.22399 -71.94169) (xy 345.273568 -71.964331) (xy 345.319419 -71.993797)
			(xy 345.360609 -72.029488) (xy 345.396301 -72.070678) (xy 345.425767 -72.116529) (xy 345.448409 -72.166106)
			(xy 345.463764 -72.218401) (xy 345.471521 -72.272349) (xy 345.471521 -72.326851) (xy 345.463764 -72.380799)
			(xy 345.448409 -72.433094) (xy 345.425767 -72.482671) (xy 345.396301 -72.528522) (xy 345.360609 -72.569712)
			(xy 345.319419 -72.605403) (xy 345.273568 -72.634869) (xy 345.22399 -72.65751) (xy 345.171695 -72.672865)
			(xy 345.117747 -72.680621) (xy 345.090496 -72.681084) (xy 344.226896 -72.681084) (xy 344.199643 -72.680646)
			(xy 344.145693 -72.672888) (xy 344.093395 -72.657532) (xy 344.043815 -72.634889) (xy 343.997962 -72.605421)
			(xy 343.95677 -72.569727) (xy 343.921077 -72.528534) (xy 343.891609 -72.482681) (xy 343.868967 -72.433101)
			(xy 343.853611 -72.380804) (xy 343.845854 -72.326853) (xy 333.660251 -72.326853) (xy 333.663514 -72.349551)
			(xy 333.663514 -72.404049) (xy 333.655759 -72.457991) (xy 333.640407 -72.510282) (xy 333.617769 -72.559855)
			(xy 333.588308 -72.605702) (xy 333.552622 -72.64689) (xy 333.511437 -72.682581) (xy 333.465593 -72.712048)
			(xy 333.416023 -72.734691) (xy 333.363734 -72.75005) (xy 333.309793 -72.757811) (xy 333.282544 -72.7583)
			(xy 332.418944 -72.7583) (xy 332.391689 -72.757856) (xy 332.337732 -72.750104) (xy 332.285427 -72.734751)
			(xy 332.235841 -72.712111) (xy 332.189981 -72.682643) (xy 332.148782 -72.646949) (xy 332.113083 -72.605754)
			(xy 332.083611 -72.559898) (xy 332.060964 -72.510314) (xy 332.045606 -72.458011) (xy 332.037847 -72.404055)
			(xy 329.5142 -72.404055) (xy 329.5142 -74.356747) (xy 330.744122 -74.356747) (xy 330.744122 -74.302253)
			(xy 330.751877 -74.248315) (xy 330.767229 -74.196029) (xy 330.789865 -74.146459) (xy 330.819325 -74.100616)
			(xy 330.855009 -74.059431) (xy 330.89619 -74.023744) (xy 330.942031 -73.99428) (xy 330.991599 -73.97164)
			(xy 331.043883 -73.956284) (xy 331.097821 -73.948524) (xy 331.125068 -73.948036) (xy 331.988668 -73.948036)
			(xy 332.015926 -73.948409) (xy 332.069886 -73.956163) (xy 332.122194 -73.971518) (xy 332.171784 -73.994161)
			(xy 332.217646 -74.023632) (xy 332.258848 -74.05933) (xy 332.294549 -74.100528) (xy 332.324023 -74.146388)
			(xy 332.346671 -74.195976) (xy 332.36203 -74.248283) (xy 332.369789 -74.302243) (xy 332.369789 -74.356757)
			(xy 332.36203 -74.410717) (xy 332.346671 -74.463024) (xy 332.324023 -74.512612) (xy 332.294549 -74.558472)
			(xy 332.26684 -74.590448) (xy 336.274202 -74.590448) (xy 336.274202 -74.535953) (xy 336.281957 -74.482012)
			(xy 336.297309 -74.429724) (xy 336.319945 -74.380153) (xy 336.349406 -74.334308) (xy 336.38509 -74.293121)
			(xy 336.426272 -74.257432) (xy 336.472114 -74.227966) (xy 336.521683 -74.205324) (xy 336.573969 -74.189966)
			(xy 336.627909 -74.182205) (xy 336.655156 -74.181716) (xy 337.518756 -74.181716) (xy 337.546013 -74.182128)
			(xy 337.599972 -74.18988) (xy 337.652278 -74.205233) (xy 337.701867 -74.227875) (xy 337.747729 -74.257344)
			(xy 337.788929 -74.29304) (xy 337.82463 -74.334236) (xy 337.854104 -74.380094) (xy 337.876751 -74.42968)
			(xy 337.89211 -74.481985) (xy 337.899869 -74.535943) (xy 337.899869 -74.55185) (xy 339.156294 -74.55185)
			(xy 339.156294 -74.49735) (xy 339.16405 -74.443405) (xy 339.179404 -74.391113) (xy 339.202044 -74.341539)
			(xy 339.231509 -74.29569) (xy 339.267198 -74.254502) (xy 339.308386 -74.218812) (xy 339.354233 -74.189347)
			(xy 339.403808 -74.166707) (xy 339.456099 -74.151352) (xy 339.510044 -74.143595) (xy 339.537294 -74.143108)
			(xy 340.400894 -74.143108) (xy 340.428148 -74.143538) (xy 340.482102 -74.151295) (xy 340.534403 -74.166651)
			(xy 340.583986 -74.189294) (xy 340.629842 -74.218763) (xy 340.671037 -74.254459) (xy 340.706733 -74.295653)
			(xy 340.736203 -74.341509) (xy 340.758847 -74.391091) (xy 340.774204 -74.443392) (xy 340.781961 -74.497346)
			(xy 340.781961 -74.551854) (xy 340.774204 -74.605808) (xy 340.758847 -74.658109) (xy 340.736203 -74.707691)
			(xy 340.706733 -74.753547) (xy 340.671037 -74.794741) (xy 340.629842 -74.830437) (xy 340.583986 -74.859906)
			(xy 340.534403 -74.882549) (xy 340.482102 -74.897905) (xy 340.428148 -74.905662) (xy 340.400894 -74.906124)
			(xy 339.537294 -74.906124) (xy 339.510044 -74.905605) (xy 339.456099 -74.897848) (xy 339.403808 -74.882493)
			(xy 339.354233 -74.859853) (xy 339.308386 -74.830388) (xy 339.267198 -74.794698) (xy 339.231509 -74.75351)
			(xy 339.202044 -74.707661) (xy 339.179404 -74.658087) (xy 339.16405 -74.605795) (xy 339.156294 -74.55185)
			(xy 337.899869 -74.55185) (xy 337.899869 -74.590457) (xy 337.89211 -74.644415) (xy 337.876751 -74.69672)
			(xy 337.854104 -74.746306) (xy 337.82463 -74.792164) (xy 337.788929 -74.83336) (xy 337.747729 -74.869056)
			(xy 337.701867 -74.898525) (xy 337.652278 -74.921167) (xy 337.599972 -74.93652) (xy 337.546013 -74.944272)
			(xy 337.518756 -74.944732) (xy 336.655156 -74.944732) (xy 336.627909 -74.944195) (xy 336.573969 -74.936434)
			(xy 336.521683 -74.921076) (xy 336.472114 -74.898434) (xy 336.426272 -74.868968) (xy 336.38509 -74.833279)
			(xy 336.349406 -74.792092) (xy 336.319945 -74.746247) (xy 336.297309 -74.696676) (xy 336.281957 -74.644388)
			(xy 336.274202 -74.590448) (xy 332.26684 -74.590448) (xy 332.258848 -74.59967) (xy 332.217646 -74.635368)
			(xy 332.171784 -74.664839) (xy 332.122194 -74.687482) (xy 332.069886 -74.702837) (xy 332.015926 -74.710591)
			(xy 331.988668 -74.711052) (xy 331.125068 -74.711052) (xy 331.097821 -74.710476) (xy 331.043883 -74.702716)
			(xy 330.991599 -74.68736) (xy 330.942031 -74.66472) (xy 330.89619 -74.635256) (xy 330.855009 -74.599569)
			(xy 330.819325 -74.558384) (xy 330.789865 -74.512541) (xy 330.767229 -74.462971) (xy 330.751877 -74.410685)
			(xy 330.744122 -74.356747) (xy 329.5142 -74.356747) (xy 329.5142 -76.017949) (xy 334.874382 -76.017949)
			(xy 334.874382 -75.963451) (xy 334.882137 -75.909507) (xy 334.89749 -75.857216) (xy 334.920128 -75.807642)
			(xy 334.949591 -75.761793) (xy 334.985278 -75.720605) (xy 335.026463 -75.684914) (xy 335.072308 -75.655447)
			(xy 335.12188 -75.632803) (xy 335.17417 -75.617445) (xy 335.228113 -75.609684) (xy 335.255362 -75.609196)
			(xy 336.118962 -75.609196) (xy 336.146217 -75.609649) (xy 336.200173 -75.617401) (xy 336.252475 -75.632754)
			(xy 336.302061 -75.655395) (xy 336.347919 -75.684862) (xy 336.389117 -75.720556) (xy 336.424815 -75.76175)
			(xy 336.454287 -75.807606) (xy 336.476932 -75.857189) (xy 336.49229 -75.90949) (xy 336.500049 -75.963445)
			(xy 336.500049 -76.017955) (xy 336.49229 -76.07191) (xy 336.476932 -76.124211) (xy 336.454287 -76.173794)
			(xy 336.424815 -76.21965) (xy 336.389117 -76.260844) (xy 336.347919 -76.296538) (xy 336.302061 -76.326005)
			(xy 336.252475 -76.348646) (xy 336.200173 -76.363999) (xy 336.146217 -76.371751) (xy 336.118962 -76.372212)
			(xy 335.255362 -76.372212) (xy 335.228113 -76.371716) (xy 335.17417 -76.363955) (xy 335.12188 -76.348597)
			(xy 335.072308 -76.325953) (xy 335.026463 -76.296486) (xy 334.985278 -76.260795) (xy 334.949591 -76.219607)
			(xy 334.920128 -76.173758) (xy 334.89749 -76.124184) (xy 334.882137 -76.071893) (xy 334.874382 -76.017949)
			(xy 329.5142 -76.017949) (xy 329.5142 -78.00475) (xy 330.84567 -78.00475) (xy 330.84567 -77.95025)
			(xy 330.853426 -77.896304) (xy 330.868779 -77.84401) (xy 330.891419 -77.794434) (xy 330.920883 -77.748584)
			(xy 330.956571 -77.707394) (xy 330.997759 -77.671702) (xy 331.043606 -77.642234) (xy 331.09318 -77.619591)
			(xy 331.145472 -77.604232) (xy 331.199418 -77.596472) (xy 331.226668 -77.595984) (xy 332.090268 -77.595984)
			(xy 332.117522 -77.596461) (xy 332.171475 -77.604214) (xy 332.223776 -77.619567) (xy 332.273359 -77.642207)
			(xy 332.319215 -77.671674) (xy 332.360411 -77.707367) (xy 332.396107 -77.748559) (xy 332.425577 -77.794413)
			(xy 332.448222 -77.843994) (xy 332.463579 -77.896294) (xy 332.471337 -77.950246) (xy 332.471337 -78.004754)
			(xy 332.463579 -78.058706) (xy 332.448222 -78.111006) (xy 332.425577 -78.160587) (xy 332.396107 -78.206441)
			(xy 332.360411 -78.247633) (xy 332.319215 -78.283326) (xy 332.273359 -78.312793) (xy 332.223776 -78.335433)
			(xy 332.171475 -78.350786) (xy 332.117522 -78.358539) (xy 332.090268 -78.359) (xy 331.226668 -78.359)
			(xy 331.199418 -78.358528) (xy 331.145472 -78.350768) (xy 331.09318 -78.335409) (xy 331.043606 -78.312766)
			(xy 330.997759 -78.283298) (xy 330.956571 -78.247606) (xy 330.920883 -78.206416) (xy 330.891419 -78.160566)
			(xy 330.868779 -78.11099) (xy 330.853426 -78.058696) (xy 330.84567 -78.00475) (xy 329.5142 -78.00475)
			(xy 329.5142 -80.025748) (xy 329.51674 -80.033622) (xy 329.526077 -80.063104) (xy 329.536165 -80.124115)
			(xy 329.536806 -80.155034) (xy 329.536144 -80.185951) (xy 329.526062 -80.24696) (xy 329.51674 -80.276446)
			(xy 329.5142 -80.28432) (xy 329.5142 -80.817765) (xy 333.938166 -80.817765) (xy 333.938166 -80.763235)
			(xy 333.945926 -80.70926) (xy 333.961289 -80.656938) (xy 333.98394 -80.607335) (xy 334.01342 -80.561461)
			(xy 334.049129 -80.520248) (xy 334.090338 -80.484537) (xy 334.136211 -80.455054) (xy 334.185812 -80.432398)
			(xy 334.238132 -80.417032) (xy 334.292107 -80.409268) (xy 334.319372 -80.40878) (xy 335.182972 -80.40878)
			(xy 335.210247 -80.409158) (xy 335.264243 -80.416917) (xy 335.316585 -80.432283) (xy 335.366207 -80.454941)
			(xy 335.412099 -80.484432) (xy 335.453327 -80.520153) (xy 335.489052 -80.561378) (xy 335.518545 -80.607268)
			(xy 335.541207 -80.656889) (xy 335.556577 -80.709229) (xy 335.56434 -80.763225) (xy 335.56434 -80.817775)
			(xy 335.556577 -80.871771) (xy 335.541207 -80.924111) (xy 335.518545 -80.973732) (xy 335.489052 -81.019622)
			(xy 335.453327 -81.060847) (xy 335.412099 -81.096568) (xy 335.366207 -81.126059) (xy 335.316585 -81.148717)
			(xy 335.264243 -81.164083) (xy 335.210247 -81.171842) (xy 335.182972 -81.172304) (xy 334.319372 -81.172304)
			(xy 334.292107 -81.171732) (xy 334.238132 -81.163968) (xy 334.185812 -81.148602) (xy 334.136211 -81.125946)
			(xy 334.090338 -81.096463) (xy 334.049129 -81.060752) (xy 334.01342 -81.019539) (xy 333.98394 -80.973665)
			(xy 333.961289 -80.924062) (xy 333.945926 -80.87174) (xy 333.938166 -80.817765) (xy 329.5142 -80.817765)
			(xy 329.5142 -82.06825) (xy 331.768962 -82.06825) (xy 331.768962 -82.01375) (xy 331.776717 -81.959803)
			(xy 331.792071 -81.90751) (xy 331.81471 -81.857933) (xy 331.844174 -81.812083) (xy 331.879862 -81.770892)
			(xy 331.921049 -81.735199) (xy 331.966896 -81.70573) (xy 332.01647 -81.683086) (xy 332.068762 -81.667726)
			(xy 332.122708 -81.659965) (xy 332.149958 -81.659476) (xy 333.013558 -81.659476) (xy 333.040812 -81.659968)
			(xy 333.094765 -81.66772) (xy 333.147066 -81.683072) (xy 333.196649 -81.705711) (xy 333.242505 -81.735177)
			(xy 333.283701 -81.770869) (xy 333.319398 -81.812061) (xy 333.348869 -81.857914) (xy 333.371513 -81.907495)
			(xy 333.386871 -81.959794) (xy 333.394629 -82.013746) (xy 333.394629 -82.068254) (xy 333.386871 -82.122206)
			(xy 333.371513 -82.174505) (xy 333.348869 -82.224086) (xy 333.319398 -82.269939) (xy 333.294774 -82.298353)
			(xy 336.189263 -82.298353) (xy 336.189263 -82.243847) (xy 336.197021 -82.189895) (xy 336.212377 -82.137597)
			(xy 336.235021 -82.088017) (xy 336.26449 -82.042163) (xy 336.300185 -82.000971) (xy 336.341379 -81.965278)
			(xy 336.387234 -81.935811) (xy 336.436816 -81.91317) (xy 336.489115 -81.897816) (xy 336.543067 -81.890062)
			(xy 336.57032 -81.8896) (xy 337.43392 -81.8896) (xy 337.461171 -81.890071) (xy 337.515118 -81.89783)
			(xy 337.567411 -81.913187) (xy 337.616987 -81.93583) (xy 337.662836 -81.965298) (xy 337.692804 -81.991267)
			(xy 339.478646 -81.991267) (xy 339.478646 -81.936733) (xy 339.486407 -81.882755) (xy 339.50177 -81.830431)
			(xy 339.524423 -81.780825) (xy 339.553905 -81.734948) (xy 339.589615 -81.693734) (xy 339.630827 -81.65802)
			(xy 339.676702 -81.628535) (xy 339.726306 -81.605879) (xy 339.77863 -81.590512) (xy 339.832607 -81.582748)
			(xy 339.859874 -81.58226) (xy 340.723474 -81.58226) (xy 340.750748 -81.582678) (xy 340.804741 -81.590437)
			(xy 340.857079 -81.605802) (xy 340.906699 -81.62846) (xy 340.952588 -81.657948) (xy 340.993814 -81.693668)
			(xy 341.029536 -81.734891) (xy 341.059028 -81.780778) (xy 341.081689 -81.830396) (xy 341.097057 -81.882734)
			(xy 341.10482 -81.936726) (xy 341.10482 -81.991274) (xy 341.097057 -82.045266) (xy 341.081689 -82.097604)
			(xy 341.059028 -82.147222) (xy 341.029536 -82.193109) (xy 340.993814 -82.234332) (xy 340.952588 -82.270052)
			(xy 340.906699 -82.29954) (xy 340.857079 -82.322198) (xy 340.804741 -82.337563) (xy 340.750748 -82.345322)
			(xy 340.723474 -82.345784) (xy 339.859874 -82.345784) (xy 339.832607 -82.345252) (xy 339.77863 -82.337488)
			(xy 339.726306 -82.322121) (xy 339.676702 -82.299465) (xy 339.630827 -82.26998) (xy 339.589615 -82.234266)
			(xy 339.553905 -82.193052) (xy 339.524423 -82.147175) (xy 339.50177 -82.097569) (xy 339.486407 -82.045245)
			(xy 339.478646 -81.991267) (xy 337.692804 -81.991267) (xy 337.704024 -82.00099) (xy 337.739714 -82.04218)
			(xy 337.76918 -82.088031) (xy 337.79182 -82.137608) (xy 337.807174 -82.189902) (xy 337.81493 -82.243849)
			(xy 337.81493 -82.298351) (xy 337.807174 -82.352298) (xy 337.79182 -82.404592) (xy 337.769179 -82.454169)
			(xy 337.739714 -82.50002) (xy 337.704024 -82.54121) (xy 337.662836 -82.576902) (xy 337.616987 -82.60637)
			(xy 337.567411 -82.629013) (xy 337.515118 -82.64437) (xy 337.461171 -82.652129) (xy 337.43392 -82.652616)
			(xy 336.57032 -82.652616) (xy 336.543067 -82.652138) (xy 336.489115 -82.644384) (xy 336.436816 -82.62903)
			(xy 336.387234 -82.606389) (xy 336.341379 -82.576922) (xy 336.300185 -82.541229) (xy 336.26449 -82.500037)
			(xy 336.235021 -82.454183) (xy 336.212377 -82.404603) (xy 336.197021 -82.352305) (xy 336.189263 -82.298353)
			(xy 333.294774 -82.298353) (xy 333.283701 -82.311131) (xy 333.242505 -82.346823) (xy 333.196649 -82.376289)
			(xy 333.147066 -82.398928) (xy 333.094765 -82.41428) (xy 333.040812 -82.422032) (xy 333.013558 -82.422492)
			(xy 332.149958 -82.422492) (xy 332.122708 -82.422035) (xy 332.068762 -82.414274) (xy 332.01647 -82.398914)
			(xy 331.966896 -82.37627) (xy 331.921049 -82.346801) (xy 331.879862 -82.311108) (xy 331.844174 -82.269917)
			(xy 331.81471 -82.224067) (xy 331.792071 -82.17449) (xy 331.776717 -82.122197) (xy 331.768962 -82.06825)
			(xy 329.5142 -82.06825) (xy 329.5142 -82.258408) (xy 329.513588 -82.283364) (xy 329.503849 -82.332318)
			(xy 329.484747 -82.37843) (xy 329.457016 -82.41993) (xy 329.439778 -82.437986) (xy 328.289293 -83.588471)
			(xy 341.356398 -83.588471) (xy 341.356398 -83.533929) (xy 341.364161 -83.479942) (xy 341.379527 -83.427609)
			(xy 341.402184 -83.377996) (xy 341.431672 -83.332112) (xy 341.467389 -83.290892) (xy 341.508609 -83.255174)
			(xy 341.554492 -83.225686) (xy 341.604106 -83.203028) (xy 341.656438 -83.187661) (xy 341.710425 -83.179899)
			(xy 341.737696 -83.179412) (xy 342.601296 -83.179412) (xy 342.628565 -83.179927) (xy 342.682549 -83.187688)
			(xy 342.734879 -83.203053) (xy 342.784489 -83.225709) (xy 342.83037 -83.255194) (xy 342.871588 -83.290909)
			(xy 342.907303 -83.332127) (xy 342.936789 -83.378008) (xy 342.959445 -83.427618) (xy 342.974811 -83.479947)
			(xy 342.982573 -83.533931) (xy 342.982573 -83.588469) (xy 342.974811 -83.642453) (xy 342.959445 -83.694782)
			(xy 342.936789 -83.744392) (xy 342.907303 -83.790273) (xy 342.871588 -83.831491) (xy 342.83037 -83.867206)
			(xy 342.784489 -83.896691) (xy 342.734879 -83.919347) (xy 342.682549 -83.934712) (xy 342.628565 -83.942473)
			(xy 342.601296 -83.942936) (xy 341.737696 -83.942936) (xy 341.710425 -83.942501) (xy 341.656438 -83.934739)
			(xy 341.604106 -83.919372) (xy 341.554492 -83.896714) (xy 341.508609 -83.867226) (xy 341.467389 -83.831508)
			(xy 341.431672 -83.790288) (xy 341.402184 -83.744404) (xy 341.379527 -83.694791) (xy 341.364161 -83.642458)
			(xy 341.356398 -83.588471) (xy 328.289293 -83.588471) (xy 327.727818 -84.149946) (xy 327.709776 -84.167203)
			(xy 327.668281 -84.194953) (xy 327.622163 -84.21406) (xy 327.5732 -84.223784) (xy 327.54824 -84.224368)
			(xy 274.03552 -84.224368) (xy 274.010567 -84.223749) (xy 273.961622 -84.213997) (xy 273.91552 -84.194884)
			(xy 273.874033 -84.167145) (xy 273.855942 -84.149946) (xy 272.057622 -82.351626) (xy 272.040361 -82.333586)
			(xy 272.012602 -82.292093) (xy 271.993489 -82.245974) (xy 271.98376 -82.197009) (xy 271.9832 -82.172048)
			(xy 271.9832 -77.311504) (xy 271.725644 -77.053948) (xy 258.303268 -77.053948) (xy 258.289806 -77.08392)
			(xy 258.278121 -77.108661) (xy 258.248716 -77.154802) (xy 258.213021 -77.196269) (xy 258.171769 -77.232212)
			(xy 258.125804 -77.261893) (xy 258.076072 -77.284704) (xy 258.02359 -77.300176) (xy 257.969437 -77.307992)
			(xy 257.914723 -77.307992) (xy 257.86057 -77.300176) (xy 257.808088 -77.284704) (xy 257.758356 -77.261893)
			(xy 257.712391 -77.232212) (xy 257.671139 -77.196269) (xy 257.635444 -77.154802) (xy 257.606039 -77.108661)
			(xy 257.594354 -77.08392) (xy 257.580892 -77.053948) (xy 238.765842 -77.053948) (xy 238.751273 -77.054455)
			(xy 238.723337 -77.062748) (xy 238.698876 -77.078586) (xy 238.679878 -77.100682) (xy 238.667886 -77.127241)
			(xy 238.663875 -77.156105) (xy 238.668171 -77.184927) (xy 238.680424 -77.211366) (xy 238.69964 -77.233274)
			(xy 238.71174 -77.2414) (xy 238.797916 -77.296332) (xy 238.966439 -77.41198) (xy 239.130353 -77.534073)
			(xy 239.28941 -77.662429) (xy 239.443372 -77.796854) (xy 239.592007 -77.937147) (xy 239.735091 -78.083096)
			(xy 239.872411 -78.234483) (xy 240.003758 -78.391079) (xy 240.128936 -78.552649) (xy 240.247756 -78.71895)
			(xy 240.36004 -78.889733) (xy 240.465619 -79.06474) (xy 240.564335 -79.243708) (xy 240.656038 -79.426369)
			(xy 240.740592 -79.612447) (xy 240.817868 -79.801664) (xy 240.887751 -79.993733) (xy 240.950135 -80.188368)
			(xy 241.004928 -80.385274) (xy 241.052046 -80.584157) (xy 241.091419 -80.784717) (xy 241.122987 -80.986652)
			(xy 241.146703 -81.189659) (xy 241.162531 -81.393434) (xy 241.170448 -81.597668) (xy 241.170968 -81.699862)
			(xy 241.170472 -81.802088) (xy 241.162545 -82.006387) (xy 241.146701 -82.210225) (xy 241.122965 -82.413296)
			(xy 241.091374 -82.615293) (xy 241.051973 -82.815913) (xy 241.004823 -83.014855) (xy 240.949994 -83.211819)
			(xy 240.88757 -83.406509) (xy 240.817643 -83.598632) (xy 240.740319 -83.787898) (xy 240.655714 -83.974025)
			(xy 240.563956 -84.15673) (xy 240.465182 -84.335741) (xy 240.359541 -84.510786) (xy 240.358902 -84.511757)
			(xy 337.882119 -84.511757) (xy 337.882119 -84.457243) (xy 337.889878 -84.403284) (xy 337.905237 -84.350979)
			(xy 337.927883 -84.301392) (xy 337.957357 -84.255533) (xy 337.993057 -84.214336) (xy 338.034257 -84.178639)
			(xy 338.080119 -84.149169) (xy 338.129707 -84.126526) (xy 338.182014 -84.111171) (xy 338.235973 -84.103417)
			(xy 338.26323 -84.102956) (xy 339.12683 -84.102956) (xy 339.154077 -84.103516) (xy 339.208017 -84.111275)
			(xy 339.260303 -84.126632) (xy 339.309871 -84.149272) (xy 339.355714 -84.178737) (xy 339.396896 -84.214425)
			(xy 339.432581 -84.25561) (xy 339.462042 -84.301455) (xy 339.484679 -84.351025) (xy 339.500031 -84.403313)
			(xy 339.503159 -84.425069) (xy 344.644951 -84.425069) (xy 344.644951 -84.370531) (xy 344.652713 -84.316548)
			(xy 344.668079 -84.26422) (xy 344.690737 -84.214611) (xy 344.720223 -84.168731) (xy 344.75594 -84.127516)
			(xy 344.797159 -84.091803) (xy 344.843041 -84.06232) (xy 344.892652 -84.039668) (xy 344.944981 -84.024306)
			(xy 344.998965 -84.016549) (xy 345.026234 -84.016088) (xy 345.889834 -84.016088) (xy 345.917105 -84.016477)
			(xy 345.971092 -84.024243) (xy 346.023425 -84.039614) (xy 346.073037 -84.062275) (xy 346.11892 -84.091766)
			(xy 346.160139 -84.127485) (xy 346.195855 -84.168708) (xy 346.225341 -84.214593) (xy 346.247998 -84.264207)
			(xy 346.263364 -84.316541) (xy 346.271126 -84.370529) (xy 346.271126 -84.425071) (xy 346.263364 -84.479059)
			(xy 346.247998 -84.531393) (xy 346.225341 -84.581007) (xy 346.195855 -84.626892) (xy 346.160139 -84.668115)
			(xy 346.11892 -84.703834) (xy 346.073037 -84.733325) (xy 346.023425 -84.755986) (xy 345.971092 -84.771357)
			(xy 345.917105 -84.779123) (xy 345.889834 -84.779612) (xy 345.026234 -84.779612) (xy 344.998965 -84.779051)
			(xy 344.944981 -84.771294) (xy 344.892652 -84.755932) (xy 344.843041 -84.73328) (xy 344.797159 -84.703797)
			(xy 344.75594 -84.668084) (xy 344.720223 -84.626869) (xy 344.690737 -84.580989) (xy 344.668079 -84.53138)
			(xy 344.652713 -84.479052) (xy 344.644951 -84.425069) (xy 339.503159 -84.425069) (xy 339.507786 -84.457253)
			(xy 339.507786 -84.511747) (xy 339.500031 -84.565687) (xy 339.484679 -84.617975) (xy 339.462042 -84.667545)
			(xy 339.432581 -84.71339) (xy 339.396896 -84.754575) (xy 339.355714 -84.790263) (xy 339.309871 -84.819728)
			(xy 339.260303 -84.842368) (xy 339.208017 -84.857725) (xy 339.154077 -84.865484) (xy 339.12683 -84.865972)
			(xy 338.26323 -84.865972) (xy 338.235973 -84.865583) (xy 338.182014 -84.857829) (xy 338.129707 -84.842474)
			(xy 338.080119 -84.819831) (xy 338.034257 -84.790361) (xy 337.993057 -84.754664) (xy 337.957357 -84.713467)
			(xy 337.927883 -84.667608) (xy 337.905237 -84.618021) (xy 337.889878 -84.565716) (xy 337.882119 -84.511757)
			(xy 240.358902 -84.511757) (xy 240.247193 -84.681604) (xy 240.128305 -84.847937) (xy 240.003057 -85.009535)
			(xy 239.871637 -85.166155) (xy 239.734243 -85.317562) (xy 239.591082 -85.463526) (xy 239.442368 -85.60383)
			(xy 239.288326 -85.738263) (xy 239.162975 -85.839368) (xy 342.975946 -85.839368) (xy 342.975946 -85.784832)
			(xy 342.983708 -85.730852) (xy 342.999072 -85.678525) (xy 343.021727 -85.628918) (xy 343.051211 -85.58304)
			(xy 343.086924 -85.541824) (xy 343.12814 -85.506111) (xy 343.174018 -85.476627) (xy 343.223625 -85.453972)
			(xy 343.275952 -85.438608) (xy 343.329932 -85.430846) (xy 343.3572 -85.43036) (xy 344.2208 -85.43036)
			(xy 344.248071 -85.430802) (xy 344.302058 -85.438565) (xy 344.35439 -85.453931) (xy 344.404003 -85.476588)
			(xy 344.449887 -85.506076) (xy 344.491107 -85.541793) (xy 344.526824 -85.583013) (xy 344.556312 -85.628897)
			(xy 344.578969 -85.67851) (xy 344.594335 -85.730842) (xy 344.602098 -85.784829) (xy 344.602098 -85.839371)
			(xy 344.594335 -85.893358) (xy 344.578969 -85.94569) (xy 344.556312 -85.995303) (xy 344.526824 -86.041187)
			(xy 344.491107 -86.082407) (xy 344.449887 -86.118124) (xy 344.404003 -86.147612) (xy 344.35439 -86.170269)
			(xy 344.302058 -86.185635) (xy 344.248071 -86.193398) (xy 344.2208 -86.193884) (xy 343.3572 -86.193884)
			(xy 343.329932 -86.193354) (xy 343.275952 -86.185592) (xy 343.223625 -86.170228) (xy 343.174018 -86.147573)
			(xy 343.12814 -86.118089) (xy 343.086924 -86.082376) (xy 343.051211 -86.04116) (xy 343.021727 -85.995282)
			(xy 342.999072 -85.945675) (xy 342.983708 -85.893348) (xy 342.975946 -85.839368) (xy 239.162975 -85.839368)
			(xy 239.129188 -85.86662) (xy 238.965191 -85.988711) (xy 238.796584 -86.104351) (xy 238.62362 -86.213366)
			(xy 238.446558 -86.315593) (xy 238.265666 -86.410877) (xy 238.081216 -86.499075) (xy 237.893484 -86.580054)
			(xy 237.702753 -86.653694) (xy 237.509311 -86.719882) (xy 237.313447 -86.77852) (xy 237.115457 -86.829519)
			(xy 236.915638 -86.872802) (xy 236.714292 -86.908305) (xy 236.51172 -86.935974) (xy 236.308227 -86.955767)
			(xy 236.10412 -86.967655) (xy 235.899706 -86.97162) (xy 235.695292 -86.967655) (xy 235.491185 -86.955767)
			(xy 235.287692 -86.935974) (xy 235.08512 -86.908305) (xy 234.883774 -86.872802) (xy 234.683955 -86.829519)
			(xy 234.485965 -86.77852) (xy 234.290101 -86.719882) (xy 234.096659 -86.653694) (xy 233.905928 -86.580054)
			(xy 233.718196 -86.499075) (xy 233.533746 -86.410877) (xy 233.352854 -86.315593) (xy 233.175792 -86.213366)
			(xy 233.002828 -86.104351) (xy 232.834221 -85.988711) (xy 232.670224 -85.86662) (xy 232.511086 -85.738263)
			(xy 232.357044 -85.60383) (xy 232.20833 -85.463526) (xy 232.065169 -85.317562) (xy 231.927775 -85.166155)
			(xy 231.796355 -85.009535) (xy 231.671107 -84.847937) (xy 231.552219 -84.681604) (xy 231.439871 -84.510786)
			(xy 231.33423 -84.335741) (xy 231.235456 -84.15673) (xy 231.143698 -83.974025) (xy 231.059093 -83.787898)
			(xy 230.981769 -83.598632) (xy 230.911842 -83.406509) (xy 230.849418 -83.211819) (xy 230.794589 -83.014855)
			(xy 230.747439 -82.815913) (xy 230.708038 -82.615293) (xy 230.676447 -82.413296) (xy 230.652711 -82.210225)
			(xy 230.636867 -82.006387) (xy 230.62894 -81.802088) (xy 230.628444 -81.699862) (xy 230.62894 -81.597668)
			(xy 230.636864 -81.393435) (xy 230.652699 -81.189662) (xy 230.676422 -80.986656) (xy 230.707995 -80.784722)
			(xy 230.747373 -80.584164) (xy 230.794495 -80.385284) (xy 230.849292 -80.188379) (xy 230.91168 -79.993746)
			(xy 230.981565 -79.801678) (xy 231.058844 -79.612464) (xy 231.143399 -79.426387) (xy 231.235104 -79.243728)
			(xy 231.33382 -79.06476) (xy 231.439399 -78.889754) (xy 231.551683 -78.718973) (xy 231.670503 -78.552672)
			(xy 231.79568 -78.391102) (xy 231.927025 -78.234505) (xy 232.064343 -78.083118) (xy 232.207425 -77.937168)
			(xy 232.356058 -77.796873) (xy 232.510017 -77.662446) (xy 232.669071 -77.534088) (xy 232.832982 -77.411991)
			(xy 233.001502 -77.296341) (xy 233.087672 -77.2414) (xy 233.099718 -77.233211) (xy 233.118916 -77.21132)
			(xy 233.131158 -77.184902) (xy 233.13545 -77.156103) (xy 233.131442 -77.127263) (xy 233.11946 -77.100726)
			(xy 233.100479 -77.078647) (xy 233.076039 -77.06282) (xy 233.048127 -77.054531) (xy 233.03357 -77.053948)
			(xy 213.09076 -77.053948) (xy 213.065802 -77.053373) (xy 213.016845 -77.043626) (xy 212.970732 -77.024513)
			(xy 212.929234 -76.996771) (xy 212.911182 -76.979526) (xy 210.665822 -74.734166) (xy 210.65236 -74.73061)
			(xy 210.625514 -74.723063) (xy 210.574194 -74.701249) (xy 210.526596 -74.672197) (xy 210.483734 -74.636525)
			(xy 210.446522 -74.594994) (xy 210.415752 -74.548487) (xy 210.39208 -74.497997) (xy 210.376011 -74.444599)
			(xy 210.367886 -74.38943) (xy 210.367372 -74.361548) (xy 210.36749 -74.346178) (xy 210.369902 -74.315532)
			(xy 210.372198 -74.300334) (xy 210.37296 -74.29627) (xy 210.37296 -71.357998) (xy 210.363174 -71.33415)
			(xy 210.349386 -71.284479) (xy 210.342412 -71.233404) (xy 210.341972 -71.20763) (xy 210.342415 -71.181856)
			(xy 210.34939 -71.130782) (xy 210.363176 -71.081111) (xy 210.37296 -71.057262) (xy 210.37296 -70.566026)
			(xy 210.372198 -70.561962) (xy 210.369917 -70.546762) (xy 210.367502 -70.516118) (xy 210.367372 -70.500748)
			(xy 210.36749 -70.485378) (xy 210.369902 -70.454732) (xy 210.372198 -70.439534) (xy 210.37296 -70.43547)
			(xy 210.37296 -67.311778) (xy 210.371182 -67.305174) (xy 210.364672 -67.280214) (xy 210.357662 -67.229111)
			(xy 210.357212 -67.20332) (xy 210.357674 -67.17753) (xy 210.364683 -67.126428) (xy 210.371182 -67.101466)
			(xy 210.37296 -67.094862) (xy 210.37296 -61.533024) (xy 209.231484 -60.391548) (xy 171.50715 -60.391548)
			(xy 171.5008 -60.435236) (xy 171.496537 -60.462211) (xy 171.4813 -60.514655) (xy 171.458739 -60.564389)
			(xy 171.429315 -60.610397) (xy 171.39363 -60.651738) (xy 171.352413 -60.687567) (xy 171.306508 -60.717151)
			(xy 171.256852 -60.739885) (xy 171.204462 -60.755304) (xy 171.150408 -60.763093) (xy 171.095796 -60.763093)
			(xy 171.041742 -60.755304) (xy 170.989352 -60.739885) (xy 170.939696 -60.717151) (xy 170.893791 -60.687567)
			(xy 170.852574 -60.651738) (xy 170.816889 -60.610397) (xy 170.787465 -60.564389) (xy 170.764904 -60.514655)
			(xy 170.749667 -60.462211) (xy 170.745404 -60.435236) (xy 170.739054 -60.391548) (xy 164.7444 -60.391548)
			(xy 164.71944 -60.390977) (xy 164.670479 -60.381236) (xy 164.624361 -60.362129) (xy 164.582857 -60.33439)
			(xy 164.564822 -60.317126) (xy 161.491422 -57.243726) (xy 161.474161 -57.225686) (xy 161.446402 -57.184193)
			(xy 161.427289 -57.138074) (xy 161.41756 -57.089109) (xy 161.417 -57.064148) (xy 161.417 -32.582104)
			(xy 160.473644 -31.638748) (xy 152.36063 -31.638748) (xy 152.347676 -31.66999) (xy 152.336383 -31.695579)
			(xy 152.307403 -31.743417) (xy 152.271747 -31.786509) (xy 152.230179 -31.823931) (xy 152.183591 -31.854879)
			(xy 152.132981 -31.878691) (xy 152.079437 -31.894855) (xy 152.024106 -31.903025) (xy 151.968174 -31.903025)
			(xy 151.912843 -31.894855) (xy 151.859299 -31.878691) (xy 151.808689 -31.854879) (xy 151.762101 -31.823931)
			(xy 151.720533 -31.786509) (xy 151.684877 -31.743417) (xy 151.655897 -31.695579) (xy 151.644604 -31.66999)
			(xy 151.63165 -31.638748) (xy 97.719896 -31.638748) (xy 97.694496 -31.664148) (xy 97.69094 -31.677356)
			(xy 97.683016 -31.704665) (xy 97.660198 -31.756747) (xy 97.629903 -31.804867) (xy 97.592802 -31.847957)
			(xy 97.549718 -31.885065) (xy 97.501604 -31.915368) (xy 97.449525 -31.938195) (xy 97.422208 -31.946088)
			(xy 97.409 -31.949644) (xy 91.693238 -37.665406) (xy 91.675197 -37.682666) (xy 91.633704 -37.710424)
			(xy 91.587586 -37.729537) (xy 91.538621 -37.739268) (xy 91.51366 -37.739828) (xy 87.955628 -37.739828)
			(xy 87.947754 -37.780976) (xy 87.942051 -37.808143) (xy 87.923834 -37.860579) (xy 87.89821 -37.90982)
			(xy 87.865718 -37.954826) (xy 87.827046 -37.994648) (xy 87.78301 -38.028444) (xy 87.73454 -38.0555)
			(xy 87.68266 -38.075244) (xy 87.628467 -38.08726) (xy 87.573104 -38.091294) (xy 87.517741 -38.08726)
			(xy 87.463548 -38.075244) (xy 87.411668 -38.0555) (xy 87.363198 -38.028444) (xy 87.319162 -37.994648)
			(xy 87.28049 -37.954826) (xy 87.247998 -37.90982) (xy 87.222374 -37.860579) (xy 87.204157 -37.808143)
			(xy 87.198454 -37.780976) (xy 87.19058 -37.739828) (xy 32.708596 -37.739828) (xy 25.46096 -44.987464)
			(xy 25.46096 -47.049813) (xy 59.781451 -47.049813) (xy 59.785436 -46.895317) (xy 59.79737 -46.74123)
			(xy 59.817219 -46.587962) (xy 59.844933 -46.43592) (xy 59.880436 -46.285505) (xy 59.923635 -46.137118)
			(xy 59.974415 -45.991151) (xy 60.032642 -45.847991) (xy 60.098162 -45.708019) (xy 60.1708 -45.571605)
			(xy 60.250363 -45.439111) (xy 60.336642 -45.310889) (xy 60.429407 -45.187278) (xy 60.528412 -45.068606)
			(xy 60.633395 -44.955188) (xy 60.744077 -44.847324) (xy 60.860165 -44.745302) (xy 60.981351 -44.64939)
			(xy 61.107313 -44.559844) (xy 61.237718 -44.476901) (xy 61.37222 -44.400781) (xy 61.510462 -44.331685)
			(xy 61.652077 -44.269798) (xy 61.796691 -44.215282) (xy 61.943919 -44.168283) (xy 62.093371 -44.128926)
			(xy 62.244652 -44.097314) (xy 62.397358 -44.073531) (xy 62.551087 -44.057641) (xy 62.70543 -44.049685)
			(xy 62.782704 -44.049188) (xy 64.383158 -44.049188) (xy 64.461004 -44.049716) (xy 64.616485 -44.057793)
			(xy 64.771339 -44.073923) (xy 64.925148 -44.098061) (xy 65.077498 -44.130145) (xy 65.227979 -44.170085)
			(xy 65.376186 -44.217777) (xy 65.52172 -44.27309) (xy 65.66419 -44.335876) (xy 65.803212 -44.405966)
			(xy 65.938412 -44.483172) (xy 66.069427 -44.567285) (xy 66.195902 -44.65808) (xy 66.317499 -44.755312)
			(xy 66.43389 -44.858719) (xy 66.544761 -44.968023) (xy 66.649815 -45.08293) (xy 66.748768 -45.20313)
			(xy 66.841354 -45.3283) (xy 66.927324 -45.458104) (xy 67.006447 -45.592191) (xy 67.07851 -45.730201)
			(xy 67.111372 -45.800772) (xy 67.117919 -45.814089) (xy 67.137463 -45.836407) (xy 67.162592 -45.852176)
			(xy 67.191189 -45.860067) (xy 67.220848 -45.859416) (xy 67.249072 -45.850279) (xy 67.273485 -45.833424)
			(xy 67.292032 -45.81027) (xy 67.298062 -45.796708) (xy 67.329489 -45.72075) (xy 67.398808 -45.571676)
			(xy 67.475398 -45.426204) (xy 67.559074 -45.284688) (xy 67.64963 -45.147475) (xy 67.746848 -45.014897)
			(xy 67.850489 -44.887277) (xy 67.960301 -44.764928) (xy 68.076018 -44.648146) (xy 68.197355 -44.537217)
			(xy 68.324019 -44.432411) (xy 68.455701 -44.333982) (xy 68.592079 -44.242172) (xy 68.732821 -44.157203)
			(xy 68.877585 -44.079283) (xy 69.026018 -44.008601) (xy 69.177757 -43.945329) (xy 69.332434 -43.889623)
			(xy 69.489672 -43.841617) (xy 69.649086 -43.801429) (xy 69.81029 -43.769156) (xy 69.97289 -43.744877)
			(xy 70.13649 -43.728652) (xy 70.300691 -43.720519) (xy 70.382892 -43.720004) (xy 70.464625 -43.720498)
			(xy 70.627895 -43.728519) (xy 70.790574 -43.744541) (xy 70.952271 -43.768527) (xy 71.112596 -43.800418)
			(xy 71.271164 -43.840137) (xy 71.427591 -43.887589) (xy 71.581502 -43.942659) (xy 71.732525 -44.005215)
			(xy 71.880297 -44.075106) (xy 72.024462 -44.152163) (xy 72.164671 -44.236202) (xy 72.300589 -44.327019)
			(xy 72.431886 -44.424396) (xy 72.558247 -44.528098) (xy 72.679368 -44.637875) (xy 72.794956 -44.753463)
			(xy 72.904733 -44.874584) (xy 73.008435 -45.000945) (xy 73.105812 -45.132243) (xy 73.196629 -45.26816)
			(xy 73.280668 -45.40837) (xy 73.357725 -45.552535) (xy 73.427616 -45.700306) (xy 73.490172 -45.85133)
			(xy 73.545242 -46.00524) (xy 73.592694 -46.161668) (xy 73.632413 -46.320236) (xy 73.664304 -46.480561)
			(xy 73.688289 -46.642258) (xy 73.704312 -46.804937) (xy 73.712332 -46.968207) (xy 73.712332 -47.04994)
			(xy 89.78165 -47.04994) (xy 89.78563 -46.895439) (xy 89.797557 -46.741349) (xy 89.817402 -46.588076)
			(xy 89.84511 -46.436028) (xy 89.880608 -46.285609) (xy 89.923803 -46.137216) (xy 89.97458 -45.991243)
			(xy 90.032804 -45.848078) (xy 90.098321 -45.708101) (xy 90.170957 -45.571681) (xy 90.250519 -45.439181)
			(xy 90.336796 -45.310953) (xy 90.42956 -45.187337) (xy 90.528565 -45.068659) (xy 90.633548 -44.955236)
			(xy 90.74423 -44.847368) (xy 90.860319 -44.74534) (xy 90.981506 -44.649424) (xy 91.10747 -44.559873)
			(xy 91.237877 -44.476926) (xy 91.372381 -44.400801) (xy 91.510626 -44.331702) (xy 91.652244 -44.269811)
			(xy 91.796861 -44.215293) (xy 91.944092 -44.168291) (xy 92.093548 -44.128931) (xy 92.244832 -44.097317)
			(xy 92.397543 -44.073533) (xy 92.551275 -44.057642) (xy 92.705622 -44.049686) (xy 92.782898 -44.049188)
			(xy 94.383098 -44.049188) (xy 94.460945 -44.049695) (xy 94.61643 -44.057764) (xy 94.771287 -44.073884)
			(xy 94.9251 -44.098013) (xy 95.077454 -44.130086) (xy 95.227941 -44.170016) (xy 95.376154 -44.217696)
			(xy 95.521696 -44.272997) (xy 95.664174 -44.335772) (xy 95.803205 -44.40585) (xy 95.938415 -44.483043)
			(xy 96.06944 -44.567145) (xy 96.195928 -44.657927) (xy 96.317538 -44.755147) (xy 96.433943 -44.858542)
			(xy 96.544829 -44.967834) (xy 96.649899 -45.082729) (xy 96.74887 -45.202918) (xy 96.841474 -45.328078)
			(xy 96.927464 -45.457871) (xy 97.006608 -45.591949) (xy 97.078692 -45.729951) (xy 97.111566 -45.800518)
			(xy 97.118214 -45.813727) (xy 97.137759 -45.835901) (xy 97.162829 -45.851559) (xy 97.19133 -45.859393)
			(xy 97.220881 -45.858749) (xy 97.249013 -45.84968) (xy 97.273377 -45.832945) (xy 97.291937 -45.809941)
			(xy 97.298002 -45.796454) (xy 97.329371 -45.720474) (xy 97.398691 -45.571403) (xy 97.475283 -45.425935)
			(xy 97.55896 -45.284424) (xy 97.64952 -45.147215) (xy 97.74674 -45.014643) (xy 97.850385 -44.88703)
			(xy 97.960201 -44.764687) (xy 98.075921 -44.647913) (xy 98.197263 -44.536993) (xy 98.323931 -44.432196)
			(xy 98.455617 -44.333778) (xy 98.592 -44.241978) (xy 98.732746 -44.157021) (xy 98.877514 -44.079114)
			(xy 99.02595 -44.008446) (xy 99.177693 -43.945189) (xy 99.332373 -43.889499) (xy 99.489612 -43.84151)
			(xy 99.649029 -43.801339) (xy 99.810234 -43.769085) (xy 99.972834 -43.744825) (xy 100.136433 -43.72862)
			(xy 100.300632 -43.720508) (xy 100.382832 -43.720004) (xy 100.464565 -43.720498) (xy 100.627835 -43.728519)
			(xy 100.790514 -43.744541) (xy 100.952211 -43.768527) (xy 101.112536 -43.800418) (xy 101.271104 -43.840137)
			(xy 101.427531 -43.887589) (xy 101.581442 -43.942659) (xy 101.732465 -44.005215) (xy 101.880237 -44.075106)
			(xy 102.024402 -44.152163) (xy 102.164611 -44.236202) (xy 102.300529 -44.327019) (xy 102.431826 -44.424396)
			(xy 102.558187 -44.528098) (xy 102.679308 -44.637875) (xy 102.794896 -44.753463) (xy 102.904673 -44.874584)
			(xy 103.008375 -45.000945) (xy 103.105752 -45.132243) (xy 103.196569 -45.26816) (xy 103.280608 -45.40837)
			(xy 103.357665 -45.552535) (xy 103.404915 -45.652436) (xy 155.97378 -45.652436) (xy 155.97378 -44.788836)
			(xy 155.974266 -44.761567) (xy 155.982028 -44.707583) (xy 155.997393 -44.655253) (xy 156.02005 -44.605643)
			(xy 156.049536 -44.559762) (xy 156.085251 -44.518545) (xy 156.126468 -44.48283) (xy 156.172349 -44.453344)
			(xy 156.221959 -44.430687) (xy 156.274289 -44.415322) (xy 156.328273 -44.40756) (xy 156.382811 -44.40756)
			(xy 156.436795 -44.415322) (xy 156.489125 -44.430687) (xy 156.538735 -44.453344) (xy 156.584616 -44.48283)
			(xy 156.625833 -44.518545) (xy 156.661548 -44.559762) (xy 156.691034 -44.605643) (xy 156.713691 -44.655253)
			(xy 156.72159 -44.682156) (xy 159.179768 -44.682156) (xy 159.179768 -43.818556) (xy 159.180254 -43.791287)
			(xy 159.188016 -43.737303) (xy 159.203381 -43.684973) (xy 159.226038 -43.635363) (xy 159.255524 -43.589482)
			(xy 159.291239 -43.548265) (xy 159.332456 -43.51255) (xy 159.378337 -43.483064) (xy 159.427947 -43.460407)
			(xy 159.480277 -43.445042) (xy 159.534261 -43.43728) (xy 159.588799 -43.43728) (xy 159.642783 -43.445042)
			(xy 159.695113 -43.460407) (xy 159.744723 -43.483064) (xy 159.790604 -43.51255) (xy 159.831821 -43.548265)
			(xy 159.867536 -43.589482) (xy 159.897022 -43.635363) (xy 159.919679 -43.684973) (xy 159.935044 -43.737303)
			(xy 159.942806 -43.791287) (xy 159.943292 -43.818556) (xy 159.943292 -44.682156) (xy 159.942806 -44.709425)
			(xy 159.935044 -44.763409) (xy 159.919679 -44.815739) (xy 159.897022 -44.865349) (xy 159.867536 -44.91123)
			(xy 159.831821 -44.952447) (xy 159.790604 -44.988162) (xy 159.744723 -45.017648) (xy 159.695113 -45.040305)
			(xy 159.642783 -45.05567) (xy 159.588799 -45.063432) (xy 159.534261 -45.063432) (xy 159.480277 -45.05567)
			(xy 159.427947 -45.040305) (xy 159.378337 -45.017648) (xy 159.332456 -44.988162) (xy 159.291239 -44.952447)
			(xy 159.255524 -44.91123) (xy 159.226038 -44.865349) (xy 159.203381 -44.815739) (xy 159.188016 -44.763409)
			(xy 159.180254 -44.709425) (xy 159.179768 -44.682156) (xy 156.72159 -44.682156) (xy 156.729056 -44.707583)
			(xy 156.736818 -44.761567) (xy 156.737304 -44.788836) (xy 156.737304 -45.652436) (xy 156.736818 -45.679705)
			(xy 156.729056 -45.733689) (xy 156.713691 -45.786019) (xy 156.691034 -45.835629) (xy 156.661548 -45.88151)
			(xy 156.625833 -45.922727) (xy 156.584616 -45.958442) (xy 156.538735 -45.987928) (xy 156.489125 -46.010585)
			(xy 156.436795 -46.02595) (xy 156.382811 -46.033712) (xy 156.328273 -46.033712) (xy 156.274289 -46.02595)
			(xy 156.221959 -46.010585) (xy 156.172349 -45.987928) (xy 156.126468 -45.958442) (xy 156.085251 -45.922727)
			(xy 156.049536 -45.88151) (xy 156.02005 -45.835629) (xy 155.997393 -45.786019) (xy 155.982028 -45.733689)
			(xy 155.974266 -45.679705) (xy 155.97378 -45.652436) (xy 103.404915 -45.652436) (xy 103.427556 -45.700306)
			(xy 103.490112 -45.85133) (xy 103.545182 -46.00524) (xy 103.592634 -46.161668) (xy 103.632353 -46.320236)
			(xy 103.664244 -46.480561) (xy 103.688229 -46.642258) (xy 103.704252 -46.804937) (xy 103.712272 -46.968207)
			(xy 103.712272 -47.131673) (xy 103.704252 -47.294943) (xy 103.688229 -47.457622) (xy 103.664244 -47.619319)
			(xy 103.632353 -47.779644) (xy 103.592634 -47.938212) (xy 103.582915 -47.97025) (xy 155.567386 -47.97025)
			(xy 155.567386 -47.91575) (xy 155.575142 -47.861805) (xy 155.590495 -47.809513) (xy 155.613135 -47.759938)
			(xy 155.642598 -47.71409) (xy 155.678287 -47.672901) (xy 155.719474 -47.63721) (xy 155.765321 -47.607744)
			(xy 155.814895 -47.585102) (xy 155.867186 -47.569746) (xy 155.92113 -47.561987) (xy 155.94838 -47.5615)
			(xy 156.81198 -47.5615) (xy 156.839234 -47.561946) (xy 156.893189 -47.569701) (xy 156.94549 -47.585055)
			(xy 156.995074 -47.607697) (xy 157.04093 -47.637165) (xy 157.082126 -47.67286) (xy 157.117823 -47.714054)
			(xy 157.147293 -47.759909) (xy 157.169938 -47.809491) (xy 157.185295 -47.861792) (xy 157.193053 -47.915746)
			(xy 157.193053 -47.970249) (xy 158.785586 -47.970249) (xy 158.785586 -47.915751) (xy 158.793341 -47.861808)
			(xy 158.808694 -47.809518) (xy 158.831331 -47.759944) (xy 158.860793 -47.714097) (xy 158.89648 -47.672908)
			(xy 158.937664 -47.637217) (xy 158.983509 -47.607751) (xy 159.03308 -47.585108) (xy 159.085369 -47.569749)
			(xy 159.139311 -47.561988) (xy 159.16656 -47.5615) (xy 160.03016 -47.5615) (xy 160.057415 -47.561945)
			(xy 160.111372 -47.569697) (xy 160.163675 -47.58505) (xy 160.213262 -47.607691) (xy 160.259121 -47.637158)
			(xy 160.300319 -47.672853) (xy 160.336018 -47.714047) (xy 160.36549 -47.759903) (xy 160.388136 -47.809487)
			(xy 160.403494 -47.861789) (xy 160.411253 -47.915745) (xy 160.411253 -47.970255) (xy 160.403494 -48.024211)
			(xy 160.388136 -48.076513) (xy 160.36549 -48.126097) (xy 160.336018 -48.171953) (xy 160.300319 -48.213147)
			(xy 160.259121 -48.248842) (xy 160.213262 -48.278309) (xy 160.163675 -48.30095) (xy 160.111372 -48.316303)
			(xy 160.057415 -48.324055) (xy 160.03016 -48.324516) (xy 159.16656 -48.324516) (xy 159.139311 -48.324012)
			(xy 159.085369 -48.316251) (xy 159.03308 -48.300892) (xy 158.983509 -48.278249) (xy 158.937664 -48.248783)
			(xy 158.89648 -48.213092) (xy 158.860793 -48.171903) (xy 158.831331 -48.126056) (xy 158.808694 -48.076482)
			(xy 158.793341 -48.024192) (xy 158.785586 -47.970249) (xy 157.193053 -47.970249) (xy 157.193053 -47.970254)
			(xy 157.185295 -48.024208) (xy 157.169938 -48.076509) (xy 157.147293 -48.126091) (xy 157.117823 -48.171946)
			(xy 157.082126 -48.21314) (xy 157.04093 -48.248835) (xy 156.995074 -48.278303) (xy 156.94549 -48.300945)
			(xy 156.893189 -48.316299) (xy 156.839234 -48.324054) (xy 156.81198 -48.324516) (xy 155.94838 -48.324516)
			(xy 155.92113 -48.324013) (xy 155.867186 -48.316254) (xy 155.814895 -48.300898) (xy 155.765321 -48.278256)
			(xy 155.719474 -48.24879) (xy 155.678287 -48.213099) (xy 155.642598 -48.17191) (xy 155.613135 -48.126062)
			(xy 155.590495 -48.076487) (xy 155.575142 -48.024195) (xy 155.567386 -47.97025) (xy 103.582915 -47.97025)
			(xy 103.545182 -48.09464) (xy 103.490112 -48.24855) (xy 103.427556 -48.399574) (xy 103.357665 -48.547345)
			(xy 103.280608 -48.69151) (xy 103.196569 -48.83172) (xy 103.105752 -48.967637) (xy 103.008375 -49.098935)
			(xy 102.904673 -49.225296) (xy 102.794896 -49.346417) (xy 102.679308 -49.462005) (xy 102.558187 -49.571782)
			(xy 102.431826 -49.675484) (xy 102.300529 -49.772861) (xy 102.164611 -49.863678) (xy 102.024402 -49.947717)
			(xy 101.880237 -50.024774) (xy 101.732465 -50.094665) (xy 101.581442 -50.157221) (xy 101.427531 -50.212291)
			(xy 101.271104 -50.259743) (xy 101.112536 -50.299462) (xy 100.952211 -50.331353) (xy 100.790514 -50.355339)
			(xy 100.627835 -50.371361) (xy 100.464565 -50.379382) (xy 100.382832 -50.379884) (xy 100.300633 -50.379346)
			(xy 100.136435 -50.371235) (xy 99.972838 -50.35503) (xy 99.81024 -50.33077) (xy 99.649037 -50.298516)
			(xy 99.489622 -50.258346) (xy 99.332384 -50.210357) (xy 99.177706 -50.154667) (xy 99.025965 -50.091411)
			(xy 98.87753 -50.020744) (xy 98.732764 -49.942837) (xy 98.592019 -49.857881) (xy 98.455639 -49.766082)
			(xy 98.323954 -49.667665) (xy 98.197288 -49.562869) (xy 98.075947 -49.451949) (xy 97.960229 -49.335176)
			(xy 97.850414 -49.212835) (xy 97.746771 -49.085223) (xy 97.649552 -48.952651) (xy 97.558994 -48.815444)
			(xy 97.475318 -48.673934) (xy 97.398727 -48.528468) (xy 97.329409 -48.379398) (xy 97.298002 -48.303434)
			(xy 97.291959 -48.289914) (xy 97.273434 -48.266828) (xy 97.249065 -48.250026) (xy 97.220901 -48.240919)
			(xy 97.191308 -48.240273) (xy 97.162774 -48.248142) (xy 97.137695 -48.263865) (xy 97.118181 -48.286121)
			(xy 97.111566 -48.29937) (xy 97.078712 -48.369946) (xy 97.006622 -48.507944) (xy 96.927474 -48.642019)
			(xy 96.84148 -48.77181) (xy 96.748872 -48.896966) (xy 96.649898 -49.017153) (xy 96.544826 -49.132045)
			(xy 96.433938 -49.241335) (xy 96.317532 -49.344728) (xy 96.195921 -49.441946) (xy 96.069433 -49.532727)
			(xy 95.938408 -49.616828) (xy 95.803198 -49.694021) (xy 95.664167 -49.764099) (xy 95.52169 -49.826874)
			(xy 95.376149 -49.882177) (xy 95.227937 -49.929859) (xy 95.077451 -49.969791) (xy 94.925097 -50.001867)
			(xy 94.771285 -50.025999) (xy 94.616429 -50.042123) (xy 94.460945 -50.050196) (xy 94.383098 -50.0507)
			(xy 92.782898 -50.0507) (xy 92.705622 -50.050194) (xy 92.551275 -50.042238) (xy 92.397543 -50.026347)
			(xy 92.244832 -50.002563) (xy 92.093548 -49.970949) (xy 91.944092 -49.931589) (xy 91.796861 -49.884587)
			(xy 91.652244 -49.830069) (xy 91.510626 -49.768178) (xy 91.372381 -49.699079) (xy 91.237877 -49.622954)
			(xy 91.10747 -49.540007) (xy 90.981506 -49.450456) (xy 90.860319 -49.35454) (xy 90.74423 -49.252512)
			(xy 90.633548 -49.144644) (xy 90.528565 -49.031221) (xy 90.42956 -48.912543) (xy 90.336796 -48.788927)
			(xy 90.250519 -48.660699) (xy 90.170957 -48.528199) (xy 90.098321 -48.391779) (xy 90.032804 -48.251802)
			(xy 89.97458 -48.108637) (xy 89.923803 -47.962664) (xy 89.880608 -47.814271) (xy 89.84511 -47.663852)
			(xy 89.817402 -47.511804) (xy 89.797557 -47.358531) (xy 89.78563 -47.204441) (xy 89.78165 -47.04994)
			(xy 73.712332 -47.04994) (xy 73.712332 -47.131673) (xy 73.704312 -47.294943) (xy 73.688289 -47.457622)
			(xy 73.664304 -47.619319) (xy 73.632413 -47.779644) (xy 73.592694 -47.938212) (xy 73.545242 -48.09464)
			(xy 73.490172 -48.24855) (xy 73.427616 -48.399574) (xy 73.357725 -48.547345) (xy 73.280668 -48.69151)
			(xy 73.196629 -48.83172) (xy 73.105812 -48.967637) (xy 73.008435 -49.098935) (xy 72.904733 -49.225296)
			(xy 72.794956 -49.346417) (xy 72.679368 -49.462005) (xy 72.558247 -49.571782) (xy 72.431886 -49.675484)
			(xy 72.300589 -49.772861) (xy 72.164671 -49.863678) (xy 72.024462 -49.947717) (xy 71.880297 -50.024774)
			(xy 71.732525 -50.094665) (xy 71.581502 -50.157221) (xy 71.427591 -50.212291) (xy 71.271164 -50.259743)
			(xy 71.112596 -50.299462) (xy 70.952271 -50.331353) (xy 70.790574 -50.355339) (xy 70.627895 -50.371361)
			(xy 70.464625 -50.379382) (xy 70.382892 -50.379884) (xy 70.300688 -50.379384) (xy 70.13648 -50.371273)
			(xy 69.972873 -50.355068) (xy 69.810265 -50.330807) (xy 69.649053 -50.298549) (xy 69.489629 -50.258374)
			(xy 69.332383 -50.210379) (xy 69.177697 -50.15468) (xy 69.025949 -50.091415) (xy 68.877509 -50.020737)
			(xy 68.732738 -49.942818) (xy 68.591989 -49.857849) (xy 68.455606 -49.766036) (xy 68.323921 -49.667603)
			(xy 68.197255 -49.56279) (xy 68.075917 -49.451854) (xy 67.960202 -49.335063) (xy 67.850393 -49.212703)
			(xy 67.746757 -49.085073) (xy 67.649547 -48.952483) (xy 67.559 -48.815256) (xy 67.475337 -48.673727)
			(xy 67.398761 -48.528241) (xy 67.329459 -48.379153) (xy 67.298062 -48.30318) (xy 67.291963 -48.28966)
			(xy 67.273429 -48.266526) (xy 67.249036 -48.249686) (xy 67.220834 -48.240557) (xy 67.1912 -48.239907)
			(xy 67.162625 -48.24779) (xy 67.137517 -48.263545) (xy 67.117987 -48.285843) (xy 67.111372 -48.299116)
			(xy 67.078481 -48.369679) (xy 67.006404 -48.507691) (xy 66.927268 -48.641781) (xy 66.841285 -48.771586)
			(xy 66.748686 -48.896758) (xy 66.64972 -49.01696) (xy 66.544655 -49.131868) (xy 66.433772 -49.241173)
			(xy 66.31737 -49.34458) (xy 66.195763 -49.441813) (xy 66.069277 -49.532608) (xy 65.938253 -49.616723)
			(xy 65.803043 -49.693929) (xy 65.664011 -49.764021) (xy 65.521532 -49.826808) (xy 65.375989 -49.882122)
			(xy 65.227772 -49.929815) (xy 65.077283 -49.969757) (xy 64.924924 -50.001842) (xy 64.771107 -50.025982)
			(xy 64.616245 -50.042114) (xy 64.460754 -50.050194) (xy 64.382904 -50.0507) (xy 62.78245 -50.0507)
			(xy 62.705176 -50.050188) (xy 62.550834 -50.04222) (xy 62.397107 -50.026316) (xy 62.244402 -50.002521)
			(xy 62.093124 -49.970896) (xy 61.943675 -49.931526) (xy 61.796451 -49.884514) (xy 61.651842 -49.829987)
			(xy 61.510232 -49.768087) (xy 61.371996 -49.69898) (xy 61.2375 -49.622848) (xy 61.107102 -49.539894)
			(xy 60.981148 -49.450337) (xy 60.85997 -49.354416) (xy 60.743891 -49.252383) (xy 60.633218 -49.14451)
			(xy 60.528245 -49.031083) (xy 60.429249 -48.912403) (xy 60.336495 -48.788784) (xy 60.250227 -48.660555)
			(xy 60.170674 -48.528054) (xy 60.098048 -48.391634) (xy 60.032541 -48.251656) (xy 59.974326 -48.108492)
			(xy 59.923558 -47.96252) (xy 59.880371 -47.814129) (xy 59.844881 -47.663712) (xy 59.81718 -47.511667)
			(xy 59.797344 -47.358397) (xy 59.785423 -47.20431) (xy 59.781451 -47.049813) (xy 25.46096 -47.049813)
			(xy 25.46096 -74.760836) (xy 39.554404 -74.760836) (xy 39.554404 -66.060828) (xy 39.554909 -65.955304)
			(xy 39.562993 -65.74441) (xy 39.579149 -65.533981) (xy 39.603352 -65.324324) (xy 39.635569 -65.115749)
			(xy 39.675751 -64.908561) (xy 39.723839 -64.703064) (xy 39.779763 -64.49956) (xy 39.84344 -64.298347)
			(xy 39.914778 -64.09972) (xy 39.993672 -63.903972) (xy 40.080005 -63.71139) (xy 40.173652 -63.522255)
			(xy 40.274474 -63.336846) (xy 40.382324 -63.155435) (xy 40.497043 -62.978288) (xy 40.618463 -62.805666)
			(xy 40.746406 -62.63782) (xy 40.880684 -62.474998) (xy 41.0211 -62.317439) (xy 41.167448 -62.165374)
			(xy 41.319513 -62.019026) (xy 41.477072 -61.87861) (xy 41.639894 -61.744332) (xy 41.80774 -61.616389)
			(xy 41.980362 -61.494969) (xy 42.157509 -61.38025) (xy 42.33892 -61.2724) (xy 42.524329 -61.171578)
			(xy 42.713464 -61.077931) (xy 42.906046 -60.991598) (xy 43.101794 -60.912704) (xy 43.300421 -60.841366)
			(xy 43.501634 -60.777689) (xy 43.705138 -60.721765) (xy 43.910635 -60.673677) (xy 44.117823 -60.633495)
			(xy 44.326398 -60.601278) (xy 44.536055 -60.577075) (xy 44.746484 -60.560919) (xy 44.957378 -60.552835)
			(xy 45.168426 -60.552835) (xy 45.37932 -60.560919) (xy 45.589749 -60.577075) (xy 45.799406 -60.601278)
			(xy 46.007981 -60.633495) (xy 46.215169 -60.673677) (xy 46.420666 -60.721765) (xy 46.62417 -60.777689)
			(xy 46.825383 -60.841366) (xy 47.02401 -60.912704) (xy 47.219758 -60.991598) (xy 47.41234 -61.077931)
			(xy 47.601475 -61.171578) (xy 47.786884 -61.2724) (xy 47.968295 -61.38025) (xy 48.145442 -61.494969)
			(xy 48.318064 -61.616389) (xy 48.48591 -61.744332) (xy 48.648732 -61.87861) (xy 48.806291 -62.019026)
			(xy 48.958356 -62.165374) (xy 49.104704 -62.317439) (xy 49.24512 -62.474998) (xy 49.379398 -62.63782)
			(xy 49.507341 -62.805666) (xy 49.628761 -62.978288) (xy 49.74348 -63.155435) (xy 49.85133 -63.336846)
			(xy 49.952152 -63.522255) (xy 50.045799 -63.71139) (xy 50.132132 -63.903972) (xy 50.211026 -64.09972)
			(xy 50.282364 -64.298347) (xy 50.346041 -64.49956) (xy 50.401965 -64.703064) (xy 50.450053 -64.908561)
			(xy 50.490235 -65.115749) (xy 50.522452 -65.324324) (xy 50.546655 -65.533981) (xy 50.562811 -65.74441)
			(xy 50.570895 -65.955304) (xy 50.5714 -66.060828) (xy 50.5714 -74.760836) (xy 50.571366 -74.767948)
			(xy 173.354492 -74.767948) (xy 173.354492 -66.06794) (xy 173.354997 -65.962416) (xy 173.363081 -65.751522)
			(xy 173.379237 -65.541093) (xy 173.40344 -65.331436) (xy 173.435657 -65.122861) (xy 173.475839 -64.915673)
			(xy 173.523927 -64.710176) (xy 173.579851 -64.506672) (xy 173.643528 -64.305459) (xy 173.714866 -64.106832)
			(xy 173.79376 -63.911084) (xy 173.880093 -63.718502) (xy 173.97374 -63.529367) (xy 174.074562 -63.343958)
			(xy 174.182412 -63.162547) (xy 174.297131 -62.9854) (xy 174.418551 -62.812778) (xy 174.546494 -62.644932)
			(xy 174.680772 -62.48211) (xy 174.821188 -62.324551) (xy 174.967536 -62.172486) (xy 175.119601 -62.026138)
			(xy 175.27716 -61.885722) (xy 175.439982 -61.751444) (xy 175.607828 -61.623501) (xy 175.78045 -61.502081)
			(xy 175.957597 -61.387362) (xy 176.139008 -61.279512) (xy 176.324417 -61.17869) (xy 176.513552 -61.085043)
			(xy 176.706134 -60.99871) (xy 176.901882 -60.919816) (xy 177.100509 -60.848478) (xy 177.301722 -60.784801)
			(xy 177.505226 -60.728877) (xy 177.710723 -60.680789) (xy 177.917911 -60.640607) (xy 178.126486 -60.60839)
			(xy 178.336143 -60.584187) (xy 178.546572 -60.568031) (xy 178.757466 -60.559947) (xy 178.968514 -60.559947)
			(xy 179.179408 -60.568031) (xy 179.389837 -60.584187) (xy 179.599494 -60.60839) (xy 179.808069 -60.640607)
			(xy 180.015257 -60.680789) (xy 180.220754 -60.728877) (xy 180.424258 -60.784801) (xy 180.625471 -60.848478)
			(xy 180.824098 -60.919816) (xy 181.019846 -60.99871) (xy 181.212428 -61.085043) (xy 181.401563 -61.17869)
			(xy 181.586972 -61.279512) (xy 181.768383 -61.387362) (xy 181.94553 -61.502081) (xy 182.118152 -61.623501)
			(xy 182.285998 -61.751444) (xy 182.44882 -61.885722) (xy 182.606379 -62.026138) (xy 182.758444 -62.172486)
			(xy 182.904792 -62.324551) (xy 183.045208 -62.48211) (xy 183.179486 -62.644932) (xy 183.307429 -62.812778)
			(xy 183.428849 -62.9854) (xy 183.543568 -63.162547) (xy 183.651418 -63.343958) (xy 183.75224 -63.529367)
			(xy 183.845887 -63.718502) (xy 183.93222 -63.911084) (xy 184.011114 -64.106832) (xy 184.082452 -64.305459)
			(xy 184.146129 -64.506672) (xy 184.202053 -64.710176) (xy 184.250141 -64.915673) (xy 184.290323 -65.122861)
			(xy 184.32254 -65.331436) (xy 184.346743 -65.541093) (xy 184.362899 -65.751522) (xy 184.370983 -65.962416)
			(xy 184.371488 -66.06794) (xy 184.371488 -74.767948) (xy 184.370983 -74.873472) (xy 184.362899 -75.084366)
			(xy 184.346743 -75.294795) (xy 184.32254 -75.504452) (xy 184.290323 -75.713027) (xy 184.250141 -75.920215)
			(xy 184.202053 -76.125712) (xy 184.146129 -76.329216) (xy 184.082452 -76.530429) (xy 184.011114 -76.729056)
			(xy 183.93222 -76.924804) (xy 183.845887 -77.117386) (xy 183.75224 -77.306521) (xy 183.651418 -77.49193)
			(xy 183.543568 -77.673341) (xy 183.428849 -77.850488) (xy 183.307429 -78.02311) (xy 183.179486 -78.190956)
			(xy 183.045208 -78.353778) (xy 182.904792 -78.511337) (xy 182.758444 -78.663402) (xy 182.606379 -78.80975)
			(xy 182.44882 -78.950166) (xy 182.285998 -79.084444) (xy 182.118152 -79.212387) (xy 181.94553 -79.333807)
			(xy 181.768383 -79.448526) (xy 181.586972 -79.556376) (xy 181.401563 -79.657198) (xy 181.212428 -79.750845)
			(xy 181.019846 -79.837178) (xy 180.824098 -79.916072) (xy 180.625471 -79.98741) (xy 180.424258 -80.051087)
			(xy 180.220754 -80.107011) (xy 180.015257 -80.155099) (xy 179.808069 -80.195281) (xy 179.599494 -80.227498)
			(xy 179.389837 -80.251701) (xy 179.179408 -80.267857) (xy 178.968514 -80.275941) (xy 178.757466 -80.275941)
			(xy 178.546572 -80.267857) (xy 178.336143 -80.251701) (xy 178.126486 -80.227498) (xy 177.917911 -80.195281)
			(xy 177.710723 -80.155099) (xy 177.505226 -80.107011) (xy 177.301722 -80.051087) (xy 177.100509 -79.98741)
			(xy 176.901882 -79.916072) (xy 176.706134 -79.837178) (xy 176.513552 -79.750845) (xy 176.324417 -79.657198)
			(xy 176.139008 -79.556376) (xy 175.957597 -79.448526) (xy 175.78045 -79.333807) (xy 175.607828 -79.212387)
			(xy 175.439982 -79.084444) (xy 175.27716 -78.950166) (xy 175.119601 -78.80975) (xy 174.967536 -78.663402)
			(xy 174.821188 -78.511337) (xy 174.680772 -78.353778) (xy 174.546494 -78.190956) (xy 174.418551 -78.02311)
			(xy 174.297131 -77.850488) (xy 174.182412 -77.673341) (xy 174.074562 -77.49193) (xy 173.97374 -77.306521)
			(xy 173.880093 -77.117386) (xy 173.79376 -76.924804) (xy 173.714866 -76.729056) (xy 173.643528 -76.530429)
			(xy 173.579851 -76.329216) (xy 173.523927 -76.125712) (xy 173.475839 -75.920215) (xy 173.435657 -75.713027)
			(xy 173.40344 -75.504452) (xy 173.379237 -75.294795) (xy 173.363081 -75.084366) (xy 173.354997 -74.873472)
			(xy 173.354492 -74.767948) (xy 50.571366 -74.767948) (xy 50.570895 -74.86636) (xy 50.562811 -75.077254)
			(xy 50.546655 -75.287683) (xy 50.522452 -75.49734) (xy 50.490235 -75.705915) (xy 50.450053 -75.913103)
			(xy 50.401965 -76.1186) (xy 50.346041 -76.322104) (xy 50.282364 -76.523317) (xy 50.211026 -76.721944)
			(xy 50.132132 -76.917692) (xy 50.045799 -77.110274) (xy 49.952152 -77.299409) (xy 49.85133 -77.484818)
			(xy 49.74348 -77.666229) (xy 49.628761 -77.843376) (xy 49.507341 -78.015998) (xy 49.379398 -78.183844)
			(xy 49.24512 -78.346666) (xy 49.104704 -78.504225) (xy 48.958356 -78.65629) (xy 48.806291 -78.802638)
			(xy 48.648732 -78.943054) (xy 48.48591 -79.077332) (xy 48.318064 -79.205275) (xy 48.145442 -79.326695)
			(xy 47.968295 -79.441414) (xy 47.786884 -79.549264) (xy 47.601475 -79.650086) (xy 47.41234 -79.743733)
			(xy 47.219758 -79.830066) (xy 47.02401 -79.90896) (xy 46.825383 -79.980298) (xy 46.62417 -80.043975)
			(xy 46.420666 -80.099899) (xy 46.215169 -80.147987) (xy 46.007981 -80.188169) (xy 45.799406 -80.220386)
			(xy 45.589749 -80.244589) (xy 45.37932 -80.260745) (xy 45.168426 -80.268829) (xy 44.957378 -80.268829)
			(xy 44.746484 -80.260745) (xy 44.536055 -80.244589) (xy 44.326398 -80.220386) (xy 44.117823 -80.188169)
			(xy 43.910635 -80.147987) (xy 43.705138 -80.099899) (xy 43.501634 -80.043975) (xy 43.300421 -79.980298)
			(xy 43.101794 -79.90896) (xy 42.906046 -79.830066) (xy 42.713464 -79.743733) (xy 42.524329 -79.650086)
			(xy 42.33892 -79.549264) (xy 42.157509 -79.441414) (xy 41.980362 -79.326695) (xy 41.80774 -79.205275)
			(xy 41.639894 -79.077332) (xy 41.477072 -78.943054) (xy 41.319513 -78.802638) (xy 41.167448 -78.65629)
			(xy 41.0211 -78.504225) (xy 40.880684 -78.346666) (xy 40.746406 -78.183844) (xy 40.618463 -78.015998)
			(xy 40.497043 -77.843376) (xy 40.382324 -77.666229) (xy 40.274474 -77.484818) (xy 40.173652 -77.299409)
			(xy 40.080005 -77.110274) (xy 39.993672 -76.917692) (xy 39.914778 -76.721944) (xy 39.84344 -76.523317)
			(xy 39.779763 -76.322104) (xy 39.723839 -76.1186) (xy 39.675751 -75.913103) (xy 39.635569 -75.705915)
			(xy 39.603352 -75.49734) (xy 39.579149 -75.287683) (xy 39.562993 -75.077254) (xy 39.554909 -74.86636)
			(xy 39.554404 -74.760836) (xy 25.46096 -74.760836) (xy 25.46096 -98.341434) (xy 261.733792 -98.341434)
			(xy 261.733792 -97.477834) (xy 261.734278 -97.450583) (xy 261.742034 -97.396635) (xy 261.757389 -97.34434)
			(xy 261.780031 -97.294763) (xy 261.809497 -97.248913) (xy 261.845188 -97.207722) (xy 261.886379 -97.172031)
			(xy 261.932229 -97.142565) (xy 261.981806 -97.119923) (xy 262.034101 -97.104568) (xy 262.088049 -97.096812)
			(xy 262.142551 -97.096812) (xy 262.196499 -97.104568) (xy 262.248794 -97.119923) (xy 262.298371 -97.142565)
			(xy 262.344221 -97.172031) (xy 262.385412 -97.207722) (xy 262.421103 -97.248913) (xy 262.450569 -97.294763)
			(xy 262.473211 -97.34434) (xy 262.488566 -97.396635) (xy 262.496322 -97.450583) (xy 262.496808 -97.477834)
			(xy 262.496808 -98.341434) (xy 262.496322 -98.368685) (xy 262.488566 -98.422633) (xy 262.473211 -98.474928)
			(xy 262.450569 -98.524505) (xy 262.421103 -98.570355) (xy 262.385412 -98.611546) (xy 262.344221 -98.647237)
			(xy 262.298371 -98.676703) (xy 262.248794 -98.699345) (xy 262.196499 -98.7147) (xy 262.142551 -98.722456)
			(xy 262.088049 -98.722456) (xy 262.034101 -98.7147) (xy 261.981806 -98.699345) (xy 261.932229 -98.676703)
			(xy 261.886379 -98.647237) (xy 261.845188 -98.611546) (xy 261.809497 -98.570355) (xy 261.780031 -98.524505)
			(xy 261.757389 -98.474928) (xy 261.742034 -98.422633) (xy 261.734278 -98.368685) (xy 261.733792 -98.341434)
			(xy 25.46096 -98.341434) (xy 25.46096 -108.689394) (xy 238.647224 -108.689394) (xy 238.647224 -107.825794)
			(xy 238.64771 -107.798525) (xy 238.655472 -107.744541) (xy 238.670837 -107.692211) (xy 238.693494 -107.642601)
			(xy 238.72298 -107.59672) (xy 238.758695 -107.555503) (xy 238.799912 -107.519788) (xy 238.845793 -107.490302)
			(xy 238.895403 -107.467645) (xy 238.947733 -107.45228) (xy 239.001717 -107.444518) (xy 239.056255 -107.444518)
			(xy 239.110239 -107.45228) (xy 239.162569 -107.467645) (xy 239.212179 -107.490302) (xy 239.25806 -107.519788)
			(xy 239.299277 -107.555503) (xy 239.334992 -107.59672) (xy 239.364478 -107.642601) (xy 239.387135 -107.692211)
			(xy 239.4025 -107.744541) (xy 239.410262 -107.798525) (xy 239.410748 -107.825794) (xy 239.410748 -108.689394)
			(xy 239.410262 -108.716663) (xy 239.4025 -108.770647) (xy 239.387135 -108.822977) (xy 239.364478 -108.872587)
			(xy 239.334992 -108.918468) (xy 239.299277 -108.959685) (xy 239.25806 -108.9954) (xy 239.212179 -109.024886)
			(xy 239.162569 -109.047543) (xy 239.110239 -109.062908) (xy 239.056255 -109.07067) (xy 239.001717 -109.07067)
			(xy 238.947733 -109.062908) (xy 238.895403 -109.047543) (xy 238.845793 -109.024886) (xy 238.799912 -108.9954)
			(xy 238.758695 -108.959685) (xy 238.72298 -108.918468) (xy 238.693494 -108.872587) (xy 238.670837 -108.822977)
			(xy 238.655472 -108.770647) (xy 238.64771 -108.716663) (xy 238.647224 -108.689394) (xy 25.46096 -108.689394)
			(xy 25.46096 -109.550266) (xy 250.428546 -109.550266) (xy 250.428546 -109.495734) (xy 250.436306 -109.441757)
			(xy 250.451669 -109.389434) (xy 250.474321 -109.339829) (xy 250.503801 -109.293953) (xy 250.53951 -109.252739)
			(xy 250.580721 -109.217025) (xy 250.626594 -109.18754) (xy 250.676196 -109.164883) (xy 250.728518 -109.149515)
			(xy 250.782494 -109.141749) (xy 250.80976 -109.14126) (xy 251.67336 -109.14126) (xy 251.700634 -109.141677)
			(xy 251.754629 -109.149435) (xy 251.806969 -109.164798) (xy 251.85659 -109.187455) (xy 251.902482 -109.216943)
			(xy 251.943709 -109.252663) (xy 251.979433 -109.293886) (xy 252.008926 -109.339775) (xy 252.031588 -109.389393)
			(xy 252.046957 -109.441732) (xy 252.05472 -109.495726) (xy 252.05472 -109.550274) (xy 252.046957 -109.604268)
			(xy 252.031588 -109.656607) (xy 252.008926 -109.706225) (xy 251.979433 -109.752114) (xy 251.943709 -109.793337)
			(xy 251.902482 -109.829057) (xy 251.85659 -109.858545) (xy 251.806969 -109.881202) (xy 251.754629 -109.896565)
			(xy 251.700634 -109.904323) (xy 251.67336 -109.904784) (xy 250.80976 -109.904784) (xy 250.782494 -109.904251)
			(xy 250.728518 -109.896485) (xy 250.676196 -109.881117) (xy 250.626594 -109.85846) (xy 250.580721 -109.828975)
			(xy 250.53951 -109.793262) (xy 250.503801 -109.752047) (xy 250.474321 -109.706171) (xy 250.451669 -109.656566)
			(xy 250.436306 -109.604243) (xy 250.428546 -109.550266) (xy 25.46096 -109.550266) (xy 25.46096 -111.158274)
			(xy 239.40262 -111.158274) (xy 239.40262 -110.294674) (xy 239.403106 -110.267423) (xy 239.410862 -110.213475)
			(xy 239.426217 -110.16118) (xy 239.448859 -110.111603) (xy 239.478325 -110.065753) (xy 239.514016 -110.024562)
			(xy 239.555207 -109.988871) (xy 239.601057 -109.959405) (xy 239.650634 -109.936763) (xy 239.702929 -109.921408)
			(xy 239.756877 -109.913652) (xy 239.811379 -109.913652) (xy 239.865327 -109.921408) (xy 239.917622 -109.936763)
			(xy 239.967199 -109.959405) (xy 240.000574 -109.980854) (xy 256.88563 -109.980854) (xy 256.88563 -109.926346)
			(xy 256.893387 -109.872392) (xy 256.908744 -109.820091) (xy 256.931388 -109.770508) (xy 256.960857 -109.724652)
			(xy 256.996552 -109.683457) (xy 257.037747 -109.647761) (xy 257.083602 -109.61829) (xy 257.133185 -109.595646)
			(xy 257.185486 -109.580288) (xy 257.23944 -109.57253) (xy 257.266694 -109.572044) (xy 258.130294 -109.572044)
			(xy 258.157544 -109.572603) (xy 258.211488 -109.580358) (xy 258.26378 -109.595712) (xy 258.313355 -109.618351)
			(xy 258.359203 -109.647815) (xy 258.400391 -109.683504) (xy 258.436081 -109.724692) (xy 258.465546 -109.77054)
			(xy 258.488186 -109.820114) (xy 258.503541 -109.872406) (xy 258.511297 -109.92635) (xy 258.511297 -109.98085)
			(xy 258.503541 -110.034794) (xy 258.488186 -110.087086) (xy 258.465546 -110.13666) (xy 258.436081 -110.182508)
			(xy 258.400391 -110.223696) (xy 258.359203 -110.259385) (xy 258.313355 -110.288849) (xy 258.26378 -110.311488)
			(xy 258.211488 -110.326842) (xy 258.157544 -110.334597) (xy 258.130294 -110.33506) (xy 257.266694 -110.33506)
			(xy 257.23944 -110.33467) (xy 257.185486 -110.326912) (xy 257.133185 -110.311554) (xy 257.083602 -110.28891)
			(xy 257.037747 -110.259439) (xy 256.996552 -110.223743) (xy 256.960857 -110.182548) (xy 256.931388 -110.136692)
			(xy 256.908744 -110.087109) (xy 256.893387 -110.034808) (xy 256.88563 -109.980854) (xy 240.000574 -109.980854)
			(xy 240.013049 -109.988871) (xy 240.05424 -110.024562) (xy 240.089931 -110.065753) (xy 240.119397 -110.111603)
			(xy 240.142039 -110.16118) (xy 240.157394 -110.213475) (xy 240.16515 -110.267423) (xy 240.165636 -110.294674)
			(xy 240.165636 -111.158274) (xy 240.16515 -111.185525) (xy 240.157394 -111.239473) (xy 240.142039 -111.291768)
			(xy 240.119397 -111.341345) (xy 240.089931 -111.387195) (xy 240.05424 -111.428386) (xy 240.013049 -111.464077)
			(xy 239.967199 -111.493543) (xy 239.917622 -111.516185) (xy 239.865327 -111.53154) (xy 239.811379 -111.539296)
			(xy 239.756877 -111.539296) (xy 239.702929 -111.53154) (xy 239.650634 -111.516185) (xy 239.601057 -111.493543)
			(xy 239.555207 -111.464077) (xy 239.514016 -111.428386) (xy 239.478325 -111.387195) (xy 239.448859 -111.341345)
			(xy 239.426217 -111.291768) (xy 239.410862 -111.239473) (xy 239.403106 -111.185525) (xy 239.40262 -111.158274)
			(xy 25.46096 -111.158274) (xy 25.46096 -116.393573) (xy 230.652992 -116.393573) (xy 230.652992 -116.339027)
			(xy 230.660755 -116.285035) (xy 230.676123 -116.232698) (xy 230.698784 -116.183081) (xy 230.728276 -116.137195)
			(xy 230.763998 -116.095973) (xy 230.805224 -116.060254) (xy 230.851113 -116.030767) (xy 230.900732 -116.008111)
			(xy 230.95307 -115.992747) (xy 231.007063 -115.984989) (xy 231.034336 -115.984528) (xy 231.897936 -115.984528)
			(xy 231.925203 -115.985037) (xy 231.979181 -115.992802) (xy 232.031505 -116.008171) (xy 232.081109 -116.030828)
			(xy 232.126985 -116.060314) (xy 232.168197 -116.096029) (xy 232.203907 -116.137244) (xy 232.233389 -116.183122)
			(xy 232.256042 -116.232729) (xy 232.271405 -116.285054) (xy 232.277026 -116.324151) (xy 236.866903 -116.324151)
			(xy 236.866903 -116.269649) (xy 236.87466 -116.215701) (xy 236.890016 -116.163407) (xy 236.912659 -116.113831)
			(xy 236.942127 -116.067981) (xy 236.97782 -116.026793) (xy 237.019012 -115.991104) (xy 237.064864 -115.961641)
			(xy 237.114443 -115.939003) (xy 237.166739 -115.923652) (xy 237.220687 -115.915901) (xy 237.247938 -115.91544)
			(xy 238.111538 -115.91544) (xy 238.138791 -115.915832) (xy 238.192741 -115.923594) (xy 238.245038 -115.938955)
			(xy 238.294617 -115.961601) (xy 238.340468 -115.991072) (xy 238.381659 -116.026768) (xy 238.417351 -116.067962)
			(xy 238.446817 -116.113817) (xy 238.469459 -116.163398) (xy 238.484814 -116.215696) (xy 238.49257 -116.269647)
			(xy 238.49257 -116.324153) (xy 238.484814 -116.378104) (xy 238.469459 -116.430402) (xy 238.446817 -116.479983)
			(xy 238.417351 -116.525838) (xy 238.381659 -116.567032) (xy 238.340468 -116.602728) (xy 238.294617 -116.632199)
			(xy 238.245038 -116.654845) (xy 238.192741 -116.670206) (xy 238.138791 -116.677968) (xy 238.111538 -116.678456)
			(xy 237.247938 -116.678456) (xy 237.220687 -116.677899) (xy 237.166739 -116.670148) (xy 237.114443 -116.654797)
			(xy 237.064864 -116.632159) (xy 237.019012 -116.602696) (xy 236.97782 -116.567007) (xy 236.942127 -116.525819)
			(xy 236.912659 -116.479969) (xy 236.890016 -116.430393) (xy 236.87466 -116.378099) (xy 236.866903 -116.324151)
			(xy 232.277026 -116.324151) (xy 232.279166 -116.339033) (xy 232.279166 -116.393567) (xy 232.271405 -116.447546)
			(xy 232.256042 -116.499871) (xy 232.233389 -116.549478) (xy 232.203907 -116.595356) (xy 232.168197 -116.636571)
			(xy 232.126985 -116.672286) (xy 232.081109 -116.701772) (xy 232.031505 -116.724429) (xy 231.979181 -116.739798)
			(xy 231.925203 -116.747563) (xy 231.897936 -116.748052) (xy 231.034336 -116.748052) (xy 231.007063 -116.747611)
			(xy 230.95307 -116.739853) (xy 230.900732 -116.724489) (xy 230.851113 -116.701833) (xy 230.805224 -116.672346)
			(xy 230.763998 -116.636627) (xy 230.728276 -116.595405) (xy 230.698784 -116.549519) (xy 230.676123 -116.499902)
			(xy 230.660755 -116.447565) (xy 230.652992 -116.393573) (xy 25.46096 -116.393573) (xy 25.46096 -117.632251)
			(xy 233.564903 -117.632251) (xy 233.564903 -117.577749) (xy 233.57266 -117.523801) (xy 233.588016 -117.471507)
			(xy 233.610659 -117.421931) (xy 233.640127 -117.376081) (xy 233.67582 -117.334893) (xy 233.717012 -117.299204)
			(xy 233.762864 -117.269741) (xy 233.812443 -117.247103) (xy 233.864739 -117.231752) (xy 233.918687 -117.224001)
			(xy 233.945938 -117.22354) (xy 234.809538 -117.22354) (xy 234.836791 -117.223932) (xy 234.890741 -117.231694)
			(xy 234.943038 -117.247055) (xy 234.992617 -117.269701) (xy 235.038468 -117.299172) (xy 235.079659 -117.334868)
			(xy 235.115351 -117.376062) (xy 235.144817 -117.421917) (xy 235.167459 -117.471498) (xy 235.182814 -117.523796)
			(xy 235.19057 -117.577747) (xy 235.19057 -117.632251) (xy 238.898903 -117.632251) (xy 238.898903 -117.577749)
			(xy 238.90666 -117.523801) (xy 238.922016 -117.471507) (xy 238.944659 -117.421931) (xy 238.974127 -117.376081)
			(xy 239.00982 -117.334893) (xy 239.051012 -117.299204) (xy 239.096864 -117.269741) (xy 239.146443 -117.247103)
			(xy 239.198739 -117.231752) (xy 239.252687 -117.224001) (xy 239.279938 -117.22354) (xy 240.143538 -117.22354)
			(xy 240.170791 -117.223932) (xy 240.224741 -117.231694) (xy 240.277038 -117.247055) (xy 240.326617 -117.269701)
			(xy 240.372468 -117.299172) (xy 240.413659 -117.334868) (xy 240.449351 -117.376062) (xy 240.478817 -117.421917)
			(xy 240.501459 -117.471498) (xy 240.516814 -117.523796) (xy 240.52457 -117.577747) (xy 240.52457 -117.632253)
			(xy 240.516814 -117.686204) (xy 240.501459 -117.738502) (xy 240.478817 -117.788083) (xy 240.449351 -117.833938)
			(xy 240.413659 -117.875132) (xy 240.372468 -117.910828) (xy 240.326617 -117.940299) (xy 240.277038 -117.962945)
			(xy 240.224741 -117.978306) (xy 240.170791 -117.986068) (xy 240.143538 -117.986556) (xy 239.279938 -117.986556)
			(xy 239.252687 -117.985999) (xy 239.198739 -117.978248) (xy 239.146443 -117.962897) (xy 239.096864 -117.940259)
			(xy 239.051012 -117.910796) (xy 239.00982 -117.875107) (xy 238.974127 -117.833919) (xy 238.944659 -117.788069)
			(xy 238.922016 -117.738493) (xy 238.90666 -117.686199) (xy 238.898903 -117.632251) (xy 235.19057 -117.632251)
			(xy 235.19057 -117.632253) (xy 235.182814 -117.686204) (xy 235.167459 -117.738502) (xy 235.144817 -117.788083)
			(xy 235.115351 -117.833938) (xy 235.079659 -117.875132) (xy 235.038468 -117.910828) (xy 234.992617 -117.940299)
			(xy 234.943038 -117.962945) (xy 234.890741 -117.978306) (xy 234.836791 -117.986068) (xy 234.809538 -117.986556)
			(xy 233.945938 -117.986556) (xy 233.918687 -117.985999) (xy 233.864739 -117.978248) (xy 233.812443 -117.962897)
			(xy 233.762864 -117.940259) (xy 233.717012 -117.910796) (xy 233.67582 -117.875107) (xy 233.640127 -117.833919)
			(xy 233.610659 -117.788069) (xy 233.588016 -117.738493) (xy 233.57266 -117.686199) (xy 233.564903 -117.632251)
			(xy 25.46096 -117.632251) (xy 25.46096 -126.669292) (xy 30.247336 -131.455668) (xy 38.74262 -131.455668)
			(xy 40.263064 -129.935224) (xy 40.281104 -129.917962) (xy 40.322596 -129.890201) (xy 40.368715 -129.871086)
			(xy 40.41768 -129.861355) (xy 40.442642 -129.860802) (xy 41.122854 -129.860802) (xy 41.14679 -129.845025)
			(xy 41.198396 -129.820061) (xy 41.253155 -129.803099) (xy 41.309837 -129.794522) (xy 41.367163 -129.794522)
			(xy 41.423845 -129.803099) (xy 41.478604 -129.820061) (xy 41.53021 -129.845025) (xy 41.554146 -129.860802)
			(xy 109.454188 -129.860802) (xy 109.459268 -129.859786) (xy 109.47673 -129.856453) (xy 109.512104 -129.852893)
			(xy 109.52988 -129.852674) (xy 109.547656 -129.852896) (xy 109.583028 -129.856461) (xy 109.600492 -129.859786)
			(xy 109.605572 -129.860802) (xy 132.122164 -129.860802) (xy 132.13207 -129.822956) (xy 132.13912 -129.797905)
			(xy 132.159487 -129.750016) (xy 132.186604 -129.705599) (xy 132.219896 -129.665601) (xy 132.258653 -129.630872)
			(xy 132.30205 -129.602152) (xy 132.349164 -129.580051) (xy 132.398992 -129.56504) (xy 132.450474 -129.557439)
			(xy 132.476494 -129.557018) (xy 132.504858 -129.557567) (xy 132.560868 -129.566555) (xy 132.614747 -129.584305)
			(xy 132.665132 -129.610367) (xy 132.710751 -129.644085) (xy 132.731002 -129.663952) (xy 132.741227 -129.673727)
			(xy 132.765796 -129.687723) (xy 132.79326 -129.69445) (xy 132.821517 -129.693391) (xy 132.848401 -129.684629)
			(xy 132.871854 -129.668833) (xy 132.88137 -129.658364) (xy 132.898244 -129.638991) (xy 132.936637 -129.604855)
			(xy 132.97957 -129.576641) (xy 133.026139 -129.554945) (xy 133.075359 -129.540226) (xy 133.126193 -129.532794)
			(xy 133.15188 -129.53238) (xy 133.178457 -129.532859) (xy 133.231013 -129.540821) (xy 133.281782 -129.556567)
			(xy 133.329618 -129.579744) (xy 133.373441 -129.609826) (xy 133.39318 -129.62763) (xy 133.403279 -129.636554)
			(xy 133.427054 -129.649225) (xy 133.453318 -129.655227) (xy 133.480238 -129.65414) (xy 133.505932 -129.64604)
			(xy 133.528609 -129.631493) (xy 133.53796 -129.621788) (xy 133.556112 -129.60245) (xy 133.596839 -129.568477)
			(xy 133.641881 -129.540474) (xy 133.690368 -129.518981) (xy 133.741366 -129.504414) (xy 133.79389 -129.497053)
			(xy 133.820408 -129.496566) (xy 133.847359 -129.497032) (xy 133.900723 -129.504621) (xy 133.952488 -129.519648)
			(xy 134.001621 -129.541812) (xy 134.047145 -129.570673) (xy 134.088153 -129.605655) (xy 134.123827 -129.646061)
			(xy 134.153458 -129.691088) (xy 134.176455 -129.739838) (xy 134.192359 -129.791339) (xy 134.19709 -129.817876)
			(xy 134.203948 -129.860802) (xy 150.598124 -129.860802) (xy 150.611354 -129.836323) (xy 150.643826 -129.791138)
			(xy 150.682517 -129.751151) (xy 150.726608 -129.717208) (xy 150.775162 -129.690032) (xy 150.827149 -129.670197)
			(xy 150.881466 -129.658125) (xy 150.93696 -129.654073) (xy 150.992454 -129.658125) (xy 151.046771 -129.670197)
			(xy 151.098758 -129.690032) (xy 151.147312 -129.717208) (xy 151.191403 -129.751151) (xy 151.230094 -129.791138)
			(xy 151.262566 -129.836323) (xy 151.275796 -129.860802) (xy 155.222702 -129.860802) (xy 155.244674 -129.848456)
			(xy 155.291172 -129.829008) (xy 155.339822 -129.815838) (xy 155.38978 -129.809175) (xy 155.41498 -129.808732)
			(xy 155.440184 -129.809133) (xy 155.490152 -129.815771) (xy 155.538806 -129.828948) (xy 155.585294 -129.848433)
			(xy 155.607258 -129.860802) (xy 198.638414 -129.860802) (xy 198.650318 -129.836584) (xy 198.679933 -129.791473)
			(xy 198.71561 -129.750987) (xy 198.756637 -129.715933) (xy 198.802195 -129.687012) (xy 198.851375 -129.6648)
			(xy 198.903194 -129.649741) (xy 198.956619 -129.642135) (xy 199.010581 -129.642135) (xy 199.064006 -129.649741)
			(xy 199.115825 -129.6648) (xy 199.165005 -129.687012) (xy 199.210563 -129.715933) (xy 199.25159 -129.750987)
			(xy 199.287267 -129.791473) (xy 199.316882 -129.836584) (xy 199.328786 -129.860802) (xy 202.329288 -129.860802)
			(xy 202.353208 -129.845076) (xy 202.404764 -129.820198) (xy 202.459456 -129.803296) (xy 202.516058 -129.79475)
			(xy 202.573302 -129.79475) (xy 202.629904 -129.803296) (xy 202.684596 -129.820198) (xy 202.736152 -129.845076)
			(xy 202.760072 -129.860802) (xy 211.66201 -129.860802) (xy 222.918782 -118.60403) (xy 222.936825 -118.586775)
			(xy 222.97832 -118.559027) (xy 223.024438 -118.539922) (xy 223.0734 -118.530198) (xy 223.09836 -118.529608)
			(xy 240.219738 -118.529608) (xy 240.244693 -118.530223) (xy 240.293643 -118.539967) (xy 240.339751 -118.559073)
			(xy 240.381246 -118.586808) (xy 240.399316 -118.60403) (xy 244.7163 -122.921014) (xy 245.563136 -122.921014)
			(xy 245.563136 -122.057414) (xy 245.563622 -122.030163) (xy 245.571378 -121.976215) (xy 245.586733 -121.92392)
			(xy 245.609375 -121.874343) (xy 245.638841 -121.828493) (xy 245.674532 -121.787302) (xy 245.715723 -121.751611)
			(xy 245.761573 -121.722145) (xy 245.81115 -121.699503) (xy 245.863445 -121.684148) (xy 245.917393 -121.676392)
			(xy 245.971895 -121.676392) (xy 246.025843 -121.684148) (xy 246.078138 -121.699503) (xy 246.127715 -121.722145)
			(xy 246.173565 -121.751611) (xy 246.214756 -121.787302) (xy 246.250447 -121.828493) (xy 246.279913 -121.874343)
			(xy 246.302555 -121.92392) (xy 246.31791 -121.976215) (xy 246.325666 -122.030163) (xy 246.326152 -122.057414)
			(xy 246.326152 -122.921014) (xy 246.325666 -122.948265) (xy 246.31791 -123.002213) (xy 246.302555 -123.054508)
			(xy 246.279913 -123.104085) (xy 246.250447 -123.149935) (xy 246.214756 -123.191126) (xy 246.173565 -123.226817)
			(xy 246.127715 -123.256283) (xy 246.078138 -123.278925) (xy 246.025843 -123.29428) (xy 245.971895 -123.302036)
			(xy 245.917393 -123.302036) (xy 245.863445 -123.29428) (xy 245.81115 -123.278925) (xy 245.761573 -123.256283)
			(xy 245.715723 -123.226817) (xy 245.674532 -123.191126) (xy 245.638841 -123.149935) (xy 245.609375 -123.104085)
			(xy 245.586733 -123.054508) (xy 245.571378 -123.002213) (xy 245.563622 -122.948265) (xy 245.563136 -122.921014)
			(xy 244.7163 -122.921014) (xy 255.552194 -133.756908) (xy 296.120058 -133.756908)
		)
		(stroke
			(width 0)
			(type solid)
		)
		(fill yes)
		(layer "In8.Cu")
		(net "P3V3_AUX")
	)
	(gr_poly
		(pts
			(xy 121.731532 -261.808722) (xy 121.74278 -261.819215) (xy 121.770005 -261.833505) (xy 121.800247 -261.83906)
			(xy 121.830773 -261.835378) (xy 121.858827 -261.822793) (xy 121.870724 -261.81304) (xy 121.888804 -261.79758)
			(xy 121.928586 -261.771499) (xy 121.971719 -261.751439) (xy 122.017296 -261.737819) (xy 122.064364 -261.730926)
			(xy 122.088148 -261.73049) (xy 122.113022 -261.730946) (xy 122.162202 -261.738446) (xy 122.209687 -261.753282)
			(xy 122.254389 -261.775115) (xy 122.275092 -261.78891) (xy 122.84075 -261.78891) (xy 122.861461 -261.775128)
			(xy 122.906163 -261.753303) (xy 122.953645 -261.73847) (xy 123.002821 -261.730967) (xy 123.052567 -261.730967)
			(xy 123.101743 -261.73847) (xy 123.149225 -261.753303) (xy 123.193927 -261.775128) (xy 123.214638 -261.78891)
			(xy 123.780804 -261.78891) (xy 123.801515 -261.775128) (xy 123.846217 -261.753303) (xy 123.893699 -261.73847)
			(xy 123.942875 -261.730967) (xy 123.992621 -261.730967) (xy 124.041797 -261.73847) (xy 124.089279 -261.753303)
			(xy 124.133981 -261.775128) (xy 124.154692 -261.78891) (xy 124.720604 -261.78891) (xy 124.741315 -261.775128)
			(xy 124.786017 -261.753303) (xy 124.833499 -261.73847) (xy 124.882675 -261.730967) (xy 124.932421 -261.730967)
			(xy 124.981597 -261.73847) (xy 125.029079 -261.753303) (xy 125.073781 -261.775128) (xy 125.094492 -261.78891)
			(xy 125.66015 -261.78891) (xy 125.680861 -261.775129) (xy 125.725564 -261.753301) (xy 125.773045 -261.738461)
			(xy 125.822221 -261.730947) (xy 125.847094 -261.73049) (xy 125.870178 -261.730882) (xy 125.91589 -261.737348)
			(xy 125.960245 -261.750156) (xy 126.002368 -261.76905) (xy 126.0221 -261.781036) (xy 126.034546 -261.78891)
			(xy 126.104142 -261.78891) (xy 126.989078 -260.903974) (xy 126.989078 -259.806694) (xy 126.974821 -259.785783)
			(xy 126.952231 -259.740497) (xy 126.936868 -259.692276) (xy 126.929097 -259.642268) (xy 126.929103 -259.59166)
			(xy 126.936885 -259.541654) (xy 126.952258 -259.493437) (xy 126.974858 -259.448155) (xy 126.989078 -259.427218)
			(xy 126.989078 -258.178554) (xy 126.974884 -258.157654) (xy 126.952401 -258.112412) (xy 126.937112 -258.064261)
			(xy 126.929378 -258.014336) (xy 126.929382 -257.963815) (xy 126.937123 -257.913892) (xy 126.952419 -257.865742)
			(xy 126.974909 -257.820504) (xy 126.989078 -257.799586) (xy 126.989078 -256.551176) (xy 126.974814 -256.530265)
			(xy 126.952212 -256.484976) (xy 126.936837 -256.436753) (xy 126.929055 -256.386739) (xy 126.92905 -256.336123)
			(xy 126.936823 -256.286108) (xy 126.952189 -256.237881) (xy 126.974783 -256.192588) (xy 126.989078 -256.1717)
			(xy 126.989078 -254.92329) (xy 126.974821 -254.902379) (xy 126.952232 -254.857093) (xy 126.93687 -254.808873)
			(xy 126.929099 -254.758865) (xy 126.929105 -254.708257) (xy 126.936888 -254.658251) (xy 126.952261 -254.610035)
			(xy 126.974861 -254.564753) (xy 126.989078 -254.543814) (xy 126.989078 -249.907806) (xy 126.96731 -249.895335)
			(xy 126.9275 -249.864812) (xy 126.892797 -249.828587) (xy 126.864012 -249.787502) (xy 126.841815 -249.742515)
			(xy 126.826723 -249.694674) (xy 126.819087 -249.645094) (xy 126.819085 -249.594929) (xy 126.826717 -249.545348)
			(xy 126.841806 -249.497506) (xy 126.864001 -249.452518) (xy 126.892783 -249.411431) (xy 126.927482 -249.375203)
			(xy 126.967291 -249.344678) (xy 126.989078 -249.332242) (xy 126.989078 -248.27992) (xy 126.967309 -248.267449)
			(xy 126.927496 -248.236926) (xy 126.892792 -248.2007) (xy 126.864005 -248.159614) (xy 126.841806 -248.114626)
			(xy 126.826712 -248.066784) (xy 126.819075 -248.017202) (xy 126.819072 -247.967035) (xy 126.826704 -247.917452)
			(xy 126.841793 -247.869608) (xy 126.863987 -247.824617) (xy 126.892769 -247.783528) (xy 126.927469 -247.747298)
			(xy 126.967279 -247.716771) (xy 126.989078 -247.704356) (xy 126.989078 -246.652288) (xy 126.967312 -246.639817)
			(xy 126.927504 -246.609295) (xy 126.892804 -246.57307) (xy 126.864022 -246.531987) (xy 126.841827 -246.487001)
			(xy 126.826736 -246.439162) (xy 126.819102 -246.389584) (xy 126.819101 -246.339422) (xy 126.826735 -246.289843)
			(xy 126.841824 -246.242004) (xy 126.864019 -246.197018) (xy 126.8928 -246.155934) (xy 126.927499 -246.119709)
			(xy 126.967307 -246.089186) (xy 126.989078 -246.076724) (xy 126.989078 -245.024148) (xy 126.967338 -245.011682)
			(xy 126.927578 -244.981178) (xy 126.892922 -244.944981) (xy 126.864175 -244.903932) (xy 126.842009 -244.858989)
			(xy 126.826937 -244.811196) (xy 126.819312 -244.761666) (xy 126.81931 -244.711553) (xy 126.826933 -244.662023)
			(xy 126.842001 -244.614229) (xy 126.864166 -244.569284) (xy 126.892909 -244.528234) (xy 126.927563 -244.492035)
			(xy 126.967321 -244.461529) (xy 126.989078 -244.449092) (xy 126.989078 -243.39677) (xy 126.967313 -243.384299)
			(xy 126.927508 -243.353777) (xy 126.892811 -243.317553) (xy 126.864031 -243.276471) (xy 126.841838 -243.231487)
			(xy 126.826749 -243.18365) (xy 126.819117 -243.134074) (xy 126.819118 -243.083914) (xy 126.826752 -243.034338)
			(xy 126.841842 -242.986502) (xy 126.864037 -242.941519) (xy 126.892818 -242.900438) (xy 126.927516 -242.864215)
			(xy 126.967323 -242.833695) (xy 126.989078 -242.821206) (xy 126.989078 -241.768884) (xy 126.967312 -241.756413)
			(xy 126.927505 -241.725891) (xy 126.892806 -241.689666) (xy 126.864024 -241.648583) (xy 126.841829 -241.603598)
			(xy 126.826739 -241.55576) (xy 126.819105 -241.506182) (xy 126.819105 -241.45602) (xy 126.826739 -241.406442)
			(xy 126.841828 -241.358603) (xy 126.864023 -241.313619) (xy 126.892804 -241.272535) (xy 126.927503 -241.23631)
			(xy 126.96731 -241.205788) (xy 126.989078 -241.19332) (xy 126.989078 -240.140998) (xy 126.967312 -240.128527)
			(xy 126.927503 -240.098006) (xy 126.892802 -240.061782) (xy 126.864019 -240.020699) (xy 126.841822 -239.975714)
			(xy 126.82673 -239.927875) (xy 126.819094 -239.878297) (xy 126.818644 -239.853216) (xy 126.819066 -239.828862)
			(xy 126.82623 -239.780683) (xy 126.840448 -239.734096) (xy 126.861405 -239.690127) (xy 126.888641 -239.649745)
			(xy 126.90475 -239.631474) (xy 126.639066 -239.36579) (xy 126.623064 -239.362996) (xy 126.598063 -239.358329)
			(xy 126.549798 -239.342298) (xy 126.504585 -239.319011) (xy 126.463507 -239.289027) (xy 126.427548 -239.253063)
			(xy 126.397568 -239.211982) (xy 126.374287 -239.166766) (xy 126.358262 -239.118499) (xy 126.35357 -239.093502)
			(xy 126.350776 -239.0775) (xy 124.967746 -237.69447) (xy 124.935488 -237.709202) (xy 124.913779 -237.718816)
			(xy 124.868283 -237.732385) (xy 124.821304 -237.739247) (xy 124.797566 -237.739682) (xy 124.77178 -237.739174)
			(xy 124.720843 -237.731102) (xy 124.671796 -237.715161) (xy 124.625846 -237.691745) (xy 124.584124 -237.661429)
			(xy 124.547658 -237.624961) (xy 124.517345 -237.583237) (xy 124.493931 -237.537286) (xy 124.477994 -237.488238)
			(xy 124.469925 -237.4373) (xy 124.469398 -237.411514) (xy 124.469836 -237.387776) (xy 124.476707 -237.3408)
			(xy 124.490265 -237.295301) (xy 124.499878 -237.273592) (xy 124.51461 -237.241334) (xy 124.141992 -236.868716)
			(xy 124.138436 -236.86643) (xy 124.114849 -236.849005) (xy 124.073702 -236.807229) (xy 124.056648 -236.783372)
			(xy 122.555 -235.281724) (xy 122.52706 -235.288582) (xy 122.507562 -235.293111) (xy 122.467827 -235.297953)
			(xy 122.447812 -235.298234) (xy 122.422023 -235.297755) (xy 122.371079 -235.289688) (xy 122.322025 -235.273749)
			(xy 122.276068 -235.250333) (xy 122.234341 -235.220015) (xy 122.197871 -235.183542) (xy 122.167556 -235.141813)
			(xy 122.144142 -235.095855) (xy 122.128207 -235.0468) (xy 122.120143 -234.995855) (xy 122.119644 -234.970066)
			(xy 122.119927 -234.950051) (xy 122.124767 -234.910316) (xy 122.129296 -234.890818) (xy 122.136154 -234.862878)
			(xy 120.129046 -232.85577) (xy 120.107202 -232.856532) (xy 120.098312 -232.856532) (xy 120.072523 -232.856053)
			(xy 120.021579 -232.847986) (xy 119.972525 -232.832047) (xy 119.926569 -232.808631) (xy 119.884842 -232.778313)
			(xy 119.848371 -232.74184) (xy 119.818057 -232.700111) (xy 119.794643 -232.654153) (xy 119.778709 -232.605097)
			(xy 119.770645 -232.554153) (xy 119.770144 -232.528364) (xy 119.770144 -232.519474) (xy 119.770906 -232.49763)
			(xy 118.429024 -231.155748) (xy 118.394734 -231.177592) (xy 118.37493 -231.189676) (xy 118.332643 -231.208758)
			(xy 118.288092 -231.221698) (xy 118.242162 -231.228237) (xy 118.218966 -231.228646) (xy 118.193181 -231.228138)
			(xy 118.142246 -231.220065) (xy 118.093201 -231.204124) (xy 118.047254 -231.180708) (xy 118.005535 -231.150391)
			(xy 117.969072 -231.113923) (xy 117.938763 -231.072199) (xy 117.915354 -231.026247) (xy 117.899422 -230.977199)
			(xy 117.891358 -230.926263) (xy 117.890798 -230.900478) (xy 117.891201 -230.877282) (xy 117.897741 -230.831353)
			(xy 117.910687 -230.786804) (xy 117.929782 -230.744523) (xy 117.941852 -230.72471) (xy 117.963696 -230.69042)
			(xy 117.681502 -230.408226) (xy 117.667786 -230.40467) (xy 117.643546 -230.397999) (xy 117.597294 -230.378301)
			(xy 117.554587 -230.351779) (xy 117.516426 -230.319052) (xy 117.483703 -230.280888) (xy 117.457184 -230.238178)
			(xy 117.437491 -230.191924) (xy 117.430804 -230.167688) (xy 117.427248 -230.153972) (xy 116.023644 -228.750368)
			(xy 115.992656 -228.763068) (xy 115.96304 -228.774304) (xy 115.900879 -228.786446) (xy 115.869212 -228.787198)
			(xy 115.843423 -228.786693) (xy 115.79248 -228.778627) (xy 115.743425 -228.762691) (xy 115.697467 -228.739277)
			(xy 115.655738 -228.708963) (xy 115.619265 -228.672494) (xy 115.588945 -228.630768) (xy 115.565525 -228.584814)
			(xy 115.549583 -228.535761) (xy 115.54151 -228.484819) (xy 115.541044 -228.45903) (xy 115.541778 -228.427361)
			(xy 115.553926 -228.365199) (xy 115.565174 -228.335586) (xy 115.577874 -228.304598) (xy 115.180364 -227.907088)
			(xy 115.163342 -227.889242) (xy 115.135841 -227.848313) (xy 115.125754 -227.825808) (xy 115.11289 -227.805595)
			(xy 115.092569 -227.762206) (xy 115.078784 -227.71632) (xy 115.071827 -227.668916) (xy 115.071398 -227.64496)
			(xy 115.071804 -227.621409) (xy 115.078549 -227.574793) (xy 115.091909 -227.529625) (xy 115.10137 -227.508054)
			(xy 115.105942 -227.497894) (xy 115.105942 -226.164394) (xy 115.10137 -226.154234) (xy 115.091916 -226.132661)
			(xy 115.078579 -226.087489) (xy 115.071818 -226.040877) (xy 115.071398 -226.017328) (xy 115.071799 -225.993776)
			(xy 115.078535 -225.947156) (xy 115.091887 -225.901984) (xy 115.10137 -225.880422) (xy 115.105942 -225.870262)
			(xy 115.105942 -224.539556) (xy 115.101116 -224.529396) (xy 115.091333 -224.507374) (xy 115.077521 -224.461209)
			(xy 115.070539 -224.413531) (xy 115.070533 -224.365345) (xy 115.077505 -224.317665) (xy 115.091306 -224.271497)
			(xy 115.101116 -224.249488) (xy 115.105942 -224.239328) (xy 115.105942 -223.883982) (xy 115.046506 -223.883982)
			(xy 115.038378 -223.886776) (xy 115.026664 -223.890741) (xy 115.002761 -223.897095) (xy 114.990626 -223.899476)
			(xy 114.967766 -223.903794) (xy 114.763042 -224.258632) (xy 114.770916 -224.280476) (xy 114.779496 -224.306895)
			(xy 114.788693 -224.36167) (xy 114.789204 -224.389442) (xy 114.788696 -224.415329) (xy 114.780597 -224.466467)
			(xy 114.764598 -224.515707) (xy 114.741092 -224.561839) (xy 114.71066 -224.603726) (xy 114.67405 -224.640336)
			(xy 114.632163 -224.670768) (xy 114.586031 -224.694274) (xy 114.536791 -224.710273) (xy 114.485653 -224.718372)
			(xy 114.433879 -224.718372) (xy 114.382741 -224.710273) (xy 114.333501 -224.694274) (xy 114.287369 -224.670768)
			(xy 114.245482 -224.640336) (xy 114.208872 -224.603726) (xy 114.17844 -224.561839) (xy 114.154934 -224.515707)
			(xy 114.138935 -224.466467) (xy 114.130836 -224.415329) (xy 114.130328 -224.389442) (xy 114.130789 -224.364105)
			(xy 114.138537 -224.314026) (xy 114.153857 -224.265723) (xy 114.176387 -224.220333) (xy 114.205599 -224.178925)
			(xy 114.240802 -224.142475) (xy 114.281169 -224.111841) (xy 114.325747 -224.087744) (xy 114.373488 -224.070754)
			(xy 114.398298 -224.065592) (xy 114.421158 -224.061274) (xy 114.626136 -223.706182) (xy 114.618516 -223.684084)
			(xy 114.60997 -223.657788) (xy 114.600779 -223.60327) (xy 114.600228 -223.575626) (xy 114.600734 -223.549736)
			(xy 114.60883 -223.498594) (xy 114.624826 -223.449347) (xy 114.648329 -223.40321) (xy 114.678761 -223.361317)
			(xy 114.715371 -223.3247) (xy 114.757258 -223.294261) (xy 114.803392 -223.270749) (xy 114.852635 -223.254744)
			(xy 114.903776 -223.246638) (xy 114.929666 -223.246188) (xy 114.944025 -223.246296) (xy 114.972641 -223.248716)
			(xy 114.986816 -223.251014) (xy 115.001477 -223.253064) (xy 115.030864 -223.249591) (xy 115.058024 -223.237844)
			(xy 115.08068 -223.218809) (xy 115.096933 -223.194081) (xy 115.105421 -223.165733) (xy 115.105942 -223.150938)
			(xy 115.105942 -222.908622) (xy 115.10137 -222.898462) (xy 115.091914 -222.87689) (xy 115.078574 -222.831718)
			(xy 115.071809 -222.785106) (xy 115.071398 -222.761556) (xy 115.071804 -222.738005) (xy 115.07855 -222.691389)
			(xy 115.09191 -222.646222) (xy 115.10137 -222.62465) (xy 115.105942 -222.61449) (xy 115.105942 -221.284038)
			(xy 115.101116 -221.273878) (xy 115.091338 -221.251856) (xy 115.077539 -221.205692) (xy 115.070572 -221.158015)
			(xy 115.070128 -221.133924) (xy 115.070655 -221.106216) (xy 115.07985 -221.051569) (xy 115.088416 -221.025212)
			(xy 115.09629 -221.003114) (xy 114.891312 -220.648022) (xy 114.868452 -220.643704) (xy 114.843599 -220.638571)
			(xy 114.795743 -220.621685) (xy 114.751044 -220.597658) (xy 114.71056 -220.567059) (xy 114.675249 -220.530612)
			(xy 114.645946 -220.48918) (xy 114.623346 -220.443744) (xy 114.607983 -220.395378) (xy 114.600221 -220.345228)
			(xy 114.59972 -220.319854) (xy 114.600206 -220.293953) (xy 114.608319 -220.24279) (xy 114.624339 -220.193527)
			(xy 114.64787 -220.147378) (xy 114.678332 -220.10548) (xy 114.714976 -220.068865) (xy 114.756899 -220.038435)
			(xy 114.803066 -220.01494) (xy 114.852342 -219.998959) (xy 114.903511 -219.990885) (xy 114.929412 -219.990416)
			(xy 114.943835 -219.990515) (xy 114.972578 -219.992934) (xy 114.986816 -219.995242) (xy 115.001474 -219.997293)
			(xy 115.030854 -219.993819) (xy 115.058006 -219.982071) (xy 115.080651 -219.963034) (xy 115.09689 -219.938305)
			(xy 115.10536 -219.909958) (xy 115.105942 -219.895166) (xy 115.105942 -219.653104) (xy 115.10137 -219.642944)
			(xy 115.091915 -219.621372) (xy 115.078577 -219.5762) (xy 115.071815 -219.529588) (xy 115.071398 -219.506038)
			(xy 115.071798 -219.482486) (xy 115.078533 -219.435865) (xy 115.091884 -219.390693) (xy 115.10137 -219.369132)
			(xy 115.105942 -219.358972) (xy 115.105942 -218.02852) (xy 115.101116 -218.01836) (xy 115.091333 -217.996339)
			(xy 115.077522 -217.950175) (xy 115.070543 -217.902499) (xy 115.070128 -217.878406) (xy 115.070657 -217.850698)
			(xy 115.079855 -217.796052) (xy 115.088416 -217.769694) (xy 115.09629 -217.747596) (xy 114.891312 -217.392504)
			(xy 114.868452 -217.388186) (xy 114.843596 -217.383054) (xy 114.795735 -217.36617) (xy 114.751029 -217.342145)
			(xy 114.710537 -217.311547) (xy 114.675218 -217.275102) (xy 114.645905 -217.23367) (xy 114.623295 -217.188233)
			(xy 114.60792 -217.139865) (xy 114.600146 -217.089712) (xy 114.59972 -217.064336) (xy 114.600199 -217.038425)
			(xy 114.608301 -216.987241) (xy 114.624311 -216.937954) (xy 114.647834 -216.891779) (xy 114.678292 -216.849853)
			(xy 114.714934 -216.813208) (xy 114.756858 -216.782747) (xy 114.803032 -216.75922) (xy 114.852317 -216.743206)
			(xy 114.903501 -216.735101) (xy 114.929412 -216.734644) (xy 114.94384 -216.734812) (xy 114.972582 -216.737359)
			(xy 114.986816 -216.739724) (xy 115.001478 -216.741774) (xy 115.030865 -216.738301) (xy 115.058026 -216.726554)
			(xy 115.080684 -216.707519) (xy 115.096939 -216.682792) (xy 115.10543 -216.654444) (xy 115.105942 -216.639648)
			(xy 115.105942 -216.398094) (xy 115.10137 -216.387934) (xy 115.091825 -216.366297) (xy 115.078364 -216.320964)
			(xy 115.071569 -216.274165) (xy 115.071144 -216.25052) (xy 115.071581 -216.226877) (xy 115.078403 -216.180086)
			(xy 115.091853 -216.134753) (xy 115.10137 -216.113106) (xy 115.105942 -216.102946) (xy 115.105942 -214.773764)
			(xy 115.101116 -214.76335) (xy 115.091174 -214.741239) (xy 115.077152 -214.694832) (xy 115.070062 -214.646874)
			(xy 115.06962 -214.622634) (xy 115.069981 -214.599657) (xy 115.076293 -214.554141) (xy 115.088869 -214.509943)
			(xy 115.097814 -214.488776) (xy 115.10772 -214.466424) (xy 114.894106 -214.061294) (xy 114.869976 -214.056722)
			(xy 114.845055 -214.051631) (xy 114.797054 -214.034807) (xy 114.752206 -214.010813) (xy 114.711573 -213.980218)
			(xy 114.676118 -213.943748) (xy 114.646682 -213.902268) (xy 114.623963 -213.856761) (xy 114.608499 -213.808305)
			(xy 114.600658 -213.758049) (xy 114.600228 -213.732618) (xy 114.600734 -213.706729) (xy 114.608831 -213.655587)
			(xy 114.624828 -213.606342) (xy 114.648332 -213.560205) (xy 114.678764 -213.518313) (xy 114.715374 -213.481698)
			(xy 114.757261 -213.451259) (xy 114.803394 -213.427748) (xy 114.852637 -213.411743) (xy 114.903777 -213.403638)
			(xy 114.929666 -213.40318) (xy 114.944025 -213.403288) (xy 114.972641 -213.405708) (xy 114.986816 -213.408006)
			(xy 115.001477 -213.410056) (xy 115.030863 -213.406583) (xy 115.058022 -213.394836) (xy 115.080677 -213.375801)
			(xy 115.096928 -213.351073) (xy 115.105414 -213.322725) (xy 115.105942 -213.30793) (xy 115.105942 -195.700396)
			(xy 79.898494 -160.492948) (xy 75.538076 -160.492948) (xy 75.517122 -160.510669) (xy 75.471085 -160.540537)
			(xy 75.42124 -160.563496) (xy 75.368619 -160.57907) (xy 75.314309 -160.586939) (xy 75.259431 -160.586939)
			(xy 75.205121 -160.57907) (xy 75.1525 -160.563496) (xy 75.102655 -160.540537) (xy 75.056618 -160.510669)
			(xy 75.035664 -160.492948) (xy 73.050146 -160.492948) (xy 73.028908 -160.511802) (xy 72.981894 -160.543658)
			(xy 72.930675 -160.568187) (xy 72.876384 -160.584849) (xy 72.820223 -160.593272) (xy 72.763433 -160.593272)
			(xy 72.707272 -160.584849) (xy 72.652981 -160.568187) (xy 72.601762 -160.543658) (xy 72.554748 -160.511802)
			(xy 72.53351 -160.492948) (xy 72.073516 -160.492948) (xy 70.918578 -161.647886) (xy 70.900539 -161.665151)
			(xy 70.859048 -161.692918) (xy 70.812929 -161.712039) (xy 70.763963 -161.721778) (xy 70.739 -161.722308)
			(xy 61.94298 -161.722308) (xy 61.582808 -162.08248) (xy 61.587634 -162.108642) (xy 61.590478 -162.125452)
			(xy 61.593531 -162.159412) (xy 61.59373 -162.17646) (xy 61.593194 -162.205721) (xy 61.58425 -162.263557)
			(xy 61.566582 -162.319349) (xy 61.540604 -162.37179) (xy 61.506925 -162.41965) (xy 61.466333 -162.461808)
			(xy 61.419782 -162.497274) (xy 61.39434 -162.51174) (xy 61.39434 -167.448992) (xy 61.395864 -167.455088)
			(xy 61.399546 -167.470511) (xy 61.403498 -167.501972) (xy 61.403738 -167.517826) (xy 61.403492 -167.53368)
			(xy 61.399538 -167.56514) (xy 61.395864 -167.580564) (xy 61.39434 -167.58666) (xy 61.39434 -168.801542)
			(xy 61.394594 -168.80459) (xy 61.396372 -168.8338) (xy 61.396372 -168.862248) (xy 61.394594 -168.891458)
			(xy 61.39434 -168.894506) (xy 61.39434 -169.839132) (xy 61.852556 -170.297348) (xy 65.6844 -170.297348)
			(xy 65.70936 -170.297919) (xy 65.758321 -170.30766) (xy 65.80444 -170.326767) (xy 65.845944 -170.354505)
			(xy 65.863978 -170.37177) (xy 68.177156 -172.684948) (xy 74.980038 -172.684948) (xy 75.004997 -172.685523)
			(xy 75.053953 -172.69527) (xy 75.100067 -172.714381) (xy 75.141566 -172.742123) (xy 75.159616 -172.75937)
			(xy 77.24902 -174.848774) (xy 77.265058 -174.865547) (xy 77.291383 -174.90376) (xy 77.301344 -174.92472)
			(xy 86.172548 -194.80276) (xy 86.176572 -194.811974) (xy 86.18331 -194.83092) (xy 86.18601 -194.840606)
			(xy 86.864698 -197.36943) (xy 86.887304 -197.379082) (xy 86.910791 -197.389673) (xy 86.954682 -197.416654)
			(xy 86.994192 -197.449719) (xy 87.028486 -197.488168) (xy 87.056837 -197.531187) (xy 87.078644 -197.577865)
			(xy 87.093447 -197.627214) (xy 87.100931 -197.678188) (xy 87.101426 -197.703948) (xy 87.100863 -197.732276)
			(xy 87.091822 -197.788206) (xy 87.073979 -197.841979) (xy 87.04779 -197.892219) (xy 87.031322 -197.915276)
			(xy 87.01659 -197.935088) (xy 88.597486 -203.825094) (xy 88.641682 -203.819506) (xy 88.712178 -203.811037)
			(xy 88.853891 -203.802016) (xy 88.924892 -203.801472) (xy 88.992065 -203.801979) (xy 89.126165 -203.81009)
			(xy 89.25953 -203.826283) (xy 89.391675 -203.850499) (xy 89.522116 -203.882649) (xy 89.650378 -203.922617)
			(xy 89.775993 -203.970256) (xy 89.898503 -204.025392) (xy 90.01746 -204.087825) (xy 90.13243 -204.157326)
			(xy 90.242994 -204.233642) (xy 90.348749 -204.316495) (xy 90.449308 -204.405582) (xy 90.544304 -204.500578)
			(xy 90.633392 -204.601136) (xy 90.716246 -204.70689) (xy 90.792563 -204.817453) (xy 90.862065 -204.932423)
			(xy 90.924499 -205.051379) (xy 90.979637 -205.173888) (xy 91.027277 -205.299503) (xy 91.067245 -205.427765)
			(xy 91.099397 -205.558206) (xy 91.123614 -205.69035) (xy 91.139808 -205.823716) (xy 91.147921 -205.957815)
			(xy 91.148408 -206.024988) (xy 91.147952 -206.089784) (xy 91.140422 -206.219157) (xy 91.125369 -206.347872)
			(xy 91.102844 -206.475492) (xy 91.072923 -206.601583) (xy 91.035709 -206.725717) (xy 90.991327 -206.847472)
			(xy 90.966036 -206.90713) (xy 90.94851 -206.948024) (xy 101.025198 -213.021926) (xy 101.043629 -213.033536)
			(xy 101.076576 -213.062028) (xy 101.104177 -213.095724) (xy 101.125622 -213.133637) (xy 101.14028 -213.174654)
			(xy 101.147723 -213.217571) (xy 101.148134 -213.23935) (xy 101.148134 -213.64194) (xy 101.149912 -213.64829)
			(xy 101.155045 -213.668992) (xy 101.160518 -213.711291) (xy 101.160834 -213.732618) (xy 101.443028 -213.732618)
			(xy 101.443536 -213.706731) (xy 101.451635 -213.655593) (xy 101.467634 -213.606353) (xy 101.49114 -213.560221)
			(xy 101.521572 -213.518334) (xy 101.558182 -213.481724) (xy 101.600069 -213.451292) (xy 101.646201 -213.427786)
			(xy 101.695441 -213.411787) (xy 101.746579 -213.403688) (xy 101.798353 -213.403688) (xy 101.849491 -213.411787)
			(xy 101.898731 -213.427786) (xy 101.944863 -213.451292) (xy 101.98675 -213.481724) (xy 102.02336 -213.518334)
			(xy 102.053792 -213.560221) (xy 102.077298 -213.606353) (xy 102.093297 -213.655593) (xy 102.101396 -213.706731)
			(xy 102.101904 -213.732618) (xy 103.322628 -213.732618) (xy 103.323136 -213.706731) (xy 103.331235 -213.655593)
			(xy 103.347234 -213.606353) (xy 103.37074 -213.560221) (xy 103.401172 -213.518334) (xy 103.437782 -213.481724)
			(xy 103.479669 -213.451292) (xy 103.525801 -213.427786) (xy 103.575041 -213.411787) (xy 103.626179 -213.403688)
			(xy 103.677953 -213.403688) (xy 103.729091 -213.411787) (xy 103.778331 -213.427786) (xy 103.824463 -213.451292)
			(xy 103.86635 -213.481724) (xy 103.90296 -213.518334) (xy 103.933392 -213.560221) (xy 103.956898 -213.606353)
			(xy 103.972897 -213.655593) (xy 103.980996 -213.706731) (xy 103.981504 -213.732618) (xy 105.202228 -213.732618)
			(xy 105.202736 -213.706731) (xy 105.210835 -213.655593) (xy 105.226834 -213.606353) (xy 105.25034 -213.560221)
			(xy 105.280772 -213.518334) (xy 105.317382 -213.481724) (xy 105.359269 -213.451292) (xy 105.405401 -213.427786)
			(xy 105.454641 -213.411787) (xy 105.505779 -213.403688) (xy 105.557553 -213.403688) (xy 105.608691 -213.411787)
			(xy 105.657931 -213.427786) (xy 105.704063 -213.451292) (xy 105.74595 -213.481724) (xy 105.78256 -213.518334)
			(xy 105.812992 -213.560221) (xy 105.836498 -213.606353) (xy 105.852497 -213.655593) (xy 105.860596 -213.706731)
			(xy 105.861104 -213.732618) (xy 107.081828 -213.732618) (xy 107.082336 -213.706731) (xy 107.090435 -213.655593)
			(xy 107.106434 -213.606353) (xy 107.12994 -213.560221) (xy 107.160372 -213.518334) (xy 107.196982 -213.481724)
			(xy 107.238869 -213.451292) (xy 107.285001 -213.427786) (xy 107.334241 -213.411787) (xy 107.385379 -213.403688)
			(xy 107.437153 -213.403688) (xy 107.488291 -213.411787) (xy 107.537531 -213.427786) (xy 107.583663 -213.451292)
			(xy 107.62555 -213.481724) (xy 107.66216 -213.518334) (xy 107.692592 -213.560221) (xy 107.716098 -213.606353)
			(xy 107.732097 -213.655593) (xy 107.740196 -213.706731) (xy 107.740704 -213.732618) (xy 107.740353 -213.755595)
			(xy 107.734032 -213.80111) (xy 107.721448 -213.845306) (xy 107.71251 -213.866476) (xy 107.702604 -213.888828)
			(xy 107.916218 -214.293958) (xy 107.940348 -214.29853) (xy 107.965267 -214.303641) (xy 108.013277 -214.320441)
			(xy 108.058136 -214.344419) (xy 108.098776 -214.375006) (xy 108.134234 -214.411476) (xy 108.163666 -214.452961)
			(xy 108.186373 -214.498476) (xy 108.201815 -214.54694) (xy 108.209627 -214.597201) (xy 108.210096 -214.622634)
			(xy 108.209588 -214.648521) (xy 108.201489 -214.699659) (xy 108.18549 -214.748899) (xy 108.161984 -214.795031)
			(xy 108.131552 -214.836918) (xy 108.094942 -214.873528) (xy 108.053055 -214.90396) (xy 108.006923 -214.927466)
			(xy 107.957683 -214.943465) (xy 107.906545 -214.951564) (xy 107.854771 -214.951564) (xy 107.803633 -214.943465)
			(xy 107.754393 -214.927466) (xy 107.708261 -214.90396) (xy 107.666374 -214.873528) (xy 107.629764 -214.836918)
			(xy 107.599332 -214.795031) (xy 107.575826 -214.748899) (xy 107.559827 -214.699659) (xy 107.551728 -214.648521)
			(xy 107.55122 -214.622634) (xy 107.551587 -214.599658) (xy 107.5579 -214.554143) (xy 107.570479 -214.509947)
			(xy 107.579414 -214.488776) (xy 107.58932 -214.466424) (xy 107.375706 -214.061294) (xy 107.351576 -214.056722)
			(xy 107.32665 -214.051639) (xy 107.278636 -214.034839) (xy 107.233775 -214.010859) (xy 107.193132 -213.980269)
			(xy 107.157674 -213.943796) (xy 107.128243 -213.902307) (xy 107.105538 -213.856787) (xy 107.0901 -213.808318)
			(xy 107.082294 -213.758052) (xy 107.081828 -213.732618) (xy 105.861104 -213.732618) (xy 105.860753 -213.755595)
			(xy 105.854432 -213.80111) (xy 105.841848 -213.845306) (xy 105.83291 -213.866476) (xy 105.823004 -213.888828)
			(xy 106.036618 -214.293958) (xy 106.060748 -214.29853) (xy 106.085667 -214.303641) (xy 106.133677 -214.320441)
			(xy 106.178536 -214.344419) (xy 106.219176 -214.375006) (xy 106.254634 -214.411476) (xy 106.284066 -214.452961)
			(xy 106.306773 -214.498476) (xy 106.322215 -214.54694) (xy 106.330027 -214.597201) (xy 106.330496 -214.622634)
			(xy 106.329988 -214.648521) (xy 106.321889 -214.699659) (xy 106.30589 -214.748899) (xy 106.282384 -214.795031)
			(xy 106.251952 -214.836918) (xy 106.215342 -214.873528) (xy 106.173455 -214.90396) (xy 106.127323 -214.927466)
			(xy 106.078083 -214.943465) (xy 106.026945 -214.951564) (xy 105.975171 -214.951564) (xy 105.924033 -214.943465)
			(xy 105.874793 -214.927466) (xy 105.828661 -214.90396) (xy 105.786774 -214.873528) (xy 105.750164 -214.836918)
			(xy 105.719732 -214.795031) (xy 105.696226 -214.748899) (xy 105.680227 -214.699659) (xy 105.672128 -214.648521)
			(xy 105.67162 -214.622634) (xy 105.671987 -214.599658) (xy 105.6783 -214.554143) (xy 105.690879 -214.509947)
			(xy 105.699814 -214.488776) (xy 105.70972 -214.466424) (xy 105.496106 -214.061294) (xy 105.471976 -214.056722)
			(xy 105.44705 -214.051639) (xy 105.399036 -214.034839) (xy 105.354175 -214.010859) (xy 105.313532 -213.980269)
			(xy 105.278074 -213.943796) (xy 105.248643 -213.902307) (xy 105.225938 -213.856787) (xy 105.2105 -213.808318)
			(xy 105.202694 -213.758052) (xy 105.202228 -213.732618) (xy 103.981504 -213.732618) (xy 103.981153 -213.755595)
			(xy 103.974832 -213.80111) (xy 103.962248 -213.845306) (xy 103.95331 -213.866476) (xy 103.943404 -213.888828)
			(xy 104.157018 -214.293958) (xy 104.181148 -214.29853) (xy 104.206067 -214.303641) (xy 104.254077 -214.320441)
			(xy 104.298936 -214.344419) (xy 104.339576 -214.375006) (xy 104.375034 -214.411476) (xy 104.404466 -214.452961)
			(xy 104.427173 -214.498476) (xy 104.442615 -214.54694) (xy 104.450427 -214.597201) (xy 104.450896 -214.622634)
			(xy 104.450388 -214.648521) (xy 104.442289 -214.699659) (xy 104.42629 -214.748899) (xy 104.402784 -214.795031)
			(xy 104.372352 -214.836918) (xy 104.335742 -214.873528) (xy 104.293855 -214.90396) (xy 104.247723 -214.927466)
			(xy 104.198483 -214.943465) (xy 104.147345 -214.951564) (xy 104.095571 -214.951564) (xy 104.044433 -214.943465)
			(xy 103.995193 -214.927466) (xy 103.949061 -214.90396) (xy 103.907174 -214.873528) (xy 103.870564 -214.836918)
			(xy 103.840132 -214.795031) (xy 103.816626 -214.748899) (xy 103.800627 -214.699659) (xy 103.792528 -214.648521)
			(xy 103.79202 -214.622634) (xy 103.792387 -214.599658) (xy 103.7987 -214.554143) (xy 103.811279 -214.509947)
			(xy 103.820214 -214.488776) (xy 103.83012 -214.466424) (xy 103.616506 -214.061294) (xy 103.592376 -214.056722)
			(xy 103.56745 -214.051639) (xy 103.519436 -214.034839) (xy 103.474575 -214.010859) (xy 103.433932 -213.980269)
			(xy 103.398474 -213.943796) (xy 103.369043 -213.902307) (xy 103.346338 -213.856787) (xy 103.3309 -213.808318)
			(xy 103.323094 -213.758052) (xy 103.322628 -213.732618) (xy 102.101904 -213.732618) (xy 102.101553 -213.755595)
			(xy 102.095232 -213.80111) (xy 102.082648 -213.845306) (xy 102.07371 -213.866476) (xy 102.063804 -213.888828)
			(xy 102.277418 -214.293958) (xy 102.301548 -214.29853) (xy 102.326467 -214.303641) (xy 102.374477 -214.320441)
			(xy 102.419336 -214.344419) (xy 102.459976 -214.375006) (xy 102.495434 -214.411476) (xy 102.524866 -214.452961)
			(xy 102.547573 -214.498476) (xy 102.563015 -214.54694) (xy 102.570827 -214.597201) (xy 102.571296 -214.622634)
			(xy 102.570788 -214.648521) (xy 102.562689 -214.699659) (xy 102.54669 -214.748899) (xy 102.523184 -214.795031)
			(xy 102.492752 -214.836918) (xy 102.456142 -214.873528) (xy 102.414255 -214.90396) (xy 102.368123 -214.927466)
			(xy 102.318883 -214.943465) (xy 102.267745 -214.951564) (xy 102.215971 -214.951564) (xy 102.164833 -214.943465)
			(xy 102.115593 -214.927466) (xy 102.069461 -214.90396) (xy 102.027574 -214.873528) (xy 101.990964 -214.836918)
			(xy 101.960532 -214.795031) (xy 101.937026 -214.748899) (xy 101.921027 -214.699659) (xy 101.912928 -214.648521)
			(xy 101.91242 -214.622634) (xy 101.912787 -214.599658) (xy 101.9191 -214.554143) (xy 101.931679 -214.509947)
			(xy 101.940614 -214.488776) (xy 101.95052 -214.466424) (xy 101.736906 -214.061294) (xy 101.712776 -214.056722)
			(xy 101.68785 -214.051639) (xy 101.639836 -214.034839) (xy 101.594975 -214.010859) (xy 101.554332 -213.980269)
			(xy 101.518874 -213.943796) (xy 101.489443 -213.902307) (xy 101.466738 -213.856787) (xy 101.4513 -213.808318)
			(xy 101.443494 -213.758052) (xy 101.443028 -213.732618) (xy 101.160834 -213.732618) (xy 101.160511 -213.753944)
			(xy 101.155038 -213.796243) (xy 101.149912 -213.816946) (xy 101.148134 -213.823296) (xy 101.148134 -214.194644)
			(xy 101.148633 -214.209003) (xy 101.156643 -214.236581) (xy 101.172017 -214.260837) (xy 101.193538 -214.279852)
			(xy 101.219504 -214.29212) (xy 101.247859 -214.296671) (xy 101.26218 -214.295482) (xy 101.272112 -214.294374)
			(xy 101.292065 -214.293227) (xy 101.302058 -214.293196) (xy 101.327949 -214.293674) (xy 101.379093 -214.301769)
			(xy 101.428341 -214.317766) (xy 101.47448 -214.341272) (xy 101.516373 -214.371707) (xy 101.552988 -214.408321)
			(xy 101.583424 -214.450213) (xy 101.606931 -214.496351) (xy 101.622929 -214.545599) (xy 101.631025 -214.596743)
			(xy 101.631496 -214.622634) (xy 101.63103 -214.647968) (xy 101.623272 -214.69804) (xy 101.607946 -214.746335)
			(xy 101.585411 -214.791716) (xy 101.556199 -214.833116) (xy 101.520996 -214.869559) (xy 101.480632 -214.900187)
			(xy 101.436058 -214.924279) (xy 101.388322 -214.941268) (xy 101.363526 -214.946484) (xy 101.340666 -214.950802)
			(xy 101.148134 -215.284558) (xy 101.148134 -215.341962) (xy 101.149912 -215.348566) (xy 101.155578 -215.37016)
			(xy 101.1617 -215.414383) (xy 101.162104 -215.436704) (xy 102.38232 -215.436704) (xy 102.382829 -215.41136)
			(xy 102.3906 -215.36127) (xy 102.405946 -215.31296) (xy 102.428503 -215.267567) (xy 102.457742 -215.226161)
			(xy 102.492973 -215.189717) (xy 102.533365 -215.159094) (xy 102.577969 -215.135013) (xy 102.625732 -215.118041)
			(xy 102.650544 -215.112854) (xy 102.673404 -215.108536) (xy 102.878382 -214.753444) (xy 102.870508 -214.7316)
			(xy 102.861929 -214.705181) (xy 102.852732 -214.650406) (xy 102.85222 -214.622634) (xy 102.852728 -214.596747)
			(xy 102.860827 -214.545609) (xy 102.876826 -214.496369) (xy 102.900332 -214.450237) (xy 102.930764 -214.40835)
			(xy 102.967374 -214.37174) (xy 103.009261 -214.341308) (xy 103.055393 -214.317802) (xy 103.104633 -214.301803)
			(xy 103.155771 -214.293704) (xy 103.207545 -214.293704) (xy 103.258683 -214.301803) (xy 103.307923 -214.317802)
			(xy 103.354055 -214.341308) (xy 103.395942 -214.37174) (xy 103.432552 -214.40835) (xy 103.462984 -214.450237)
			(xy 103.48649 -214.496369) (xy 103.502489 -214.545609) (xy 103.510588 -214.596747) (xy 103.511096 -214.622634)
			(xy 103.510647 -214.64797) (xy 103.50289 -214.698044) (xy 103.487563 -214.746341) (xy 103.465027 -214.791726)
			(xy 103.435812 -214.833128) (xy 103.400608 -214.869572) (xy 103.360242 -214.900202) (xy 103.315665 -214.924296)
			(xy 103.267927 -214.941286) (xy 103.243126 -214.946484) (xy 103.220266 -214.950802) (xy 103.015288 -215.305894)
			(xy 103.023162 -215.327738) (xy 103.03181 -215.354146) (xy 103.041129 -215.408922) (xy 103.041704 -215.436704)
			(xy 104.26192 -215.436704) (xy 104.262429 -215.41136) (xy 104.2702 -215.36127) (xy 104.285546 -215.31296)
			(xy 104.308103 -215.267567) (xy 104.337342 -215.226161) (xy 104.372573 -215.189717) (xy 104.412965 -215.159094)
			(xy 104.457569 -215.135013) (xy 104.505332 -215.118041) (xy 104.530144 -215.112854) (xy 104.553004 -215.108536)
			(xy 104.757982 -214.753444) (xy 104.750108 -214.7316) (xy 104.741529 -214.705181) (xy 104.732332 -214.650406)
			(xy 104.73182 -214.622634) (xy 104.732328 -214.596747) (xy 104.740427 -214.545609) (xy 104.756426 -214.496369)
			(xy 104.779932 -214.450237) (xy 104.810364 -214.40835) (xy 104.846974 -214.37174) (xy 104.888861 -214.341308)
			(xy 104.934993 -214.317802) (xy 104.984233 -214.301803) (xy 105.035371 -214.293704) (xy 105.087145 -214.293704)
			(xy 105.138283 -214.301803) (xy 105.187523 -214.317802) (xy 105.233655 -214.341308) (xy 105.275542 -214.37174)
			(xy 105.312152 -214.40835) (xy 105.342584 -214.450237) (xy 105.36609 -214.496369) (xy 105.382089 -214.545609)
			(xy 105.390188 -214.596747) (xy 105.390696 -214.622634) (xy 105.390247 -214.64797) (xy 105.38249 -214.698044)
			(xy 105.367163 -214.746341) (xy 105.344627 -214.791726) (xy 105.315412 -214.833128) (xy 105.280208 -214.869572)
			(xy 105.239842 -214.900202) (xy 105.195265 -214.924296) (xy 105.147527 -214.941286) (xy 105.122726 -214.946484)
			(xy 105.099866 -214.950802) (xy 104.894888 -215.305894) (xy 104.902762 -215.327738) (xy 104.91141 -215.354146)
			(xy 104.920729 -215.408922) (xy 104.921304 -215.436704) (xy 106.14152 -215.436704) (xy 106.142029 -215.41136)
			(xy 106.1498 -215.36127) (xy 106.165146 -215.31296) (xy 106.187703 -215.267567) (xy 106.216942 -215.226161)
			(xy 106.252173 -215.189717) (xy 106.292565 -215.159094) (xy 106.337169 -215.135013) (xy 106.384932 -215.118041)
			(xy 106.409744 -215.112854) (xy 106.432604 -215.108536) (xy 106.637582 -214.753444) (xy 106.629708 -214.7316)
			(xy 106.621129 -214.705181) (xy 106.611932 -214.650406) (xy 106.61142 -214.622634) (xy 106.611928 -214.596747)
			(xy 106.620027 -214.545609) (xy 106.636026 -214.496369) (xy 106.659532 -214.450237) (xy 106.689964 -214.40835)
			(xy 106.726574 -214.37174) (xy 106.768461 -214.341308) (xy 106.814593 -214.317802) (xy 106.863833 -214.301803)
			(xy 106.914971 -214.293704) (xy 106.966745 -214.293704) (xy 107.017883 -214.301803) (xy 107.067123 -214.317802)
			(xy 107.113255 -214.341308) (xy 107.155142 -214.37174) (xy 107.191752 -214.40835) (xy 107.222184 -214.450237)
			(xy 107.24569 -214.496369) (xy 107.261689 -214.545609) (xy 107.269788 -214.596747) (xy 107.270296 -214.622634)
			(xy 107.269847 -214.64797) (xy 107.26209 -214.698044) (xy 107.246763 -214.746341) (xy 107.224227 -214.791726)
			(xy 107.195012 -214.833128) (xy 107.159808 -214.869572) (xy 107.119442 -214.900202) (xy 107.074865 -214.924296)
			(xy 107.027127 -214.941286) (xy 107.002326 -214.946484) (xy 106.979466 -214.950802) (xy 106.774488 -215.305894)
			(xy 106.782362 -215.327738) (xy 106.79101 -215.354146) (xy 106.800329 -215.408922) (xy 106.800904 -215.436704)
			(xy 108.02112 -215.436704) (xy 108.021629 -215.41136) (xy 108.0294 -215.36127) (xy 108.044746 -215.31296)
			(xy 108.067303 -215.267567) (xy 108.096542 -215.226161) (xy 108.131773 -215.189717) (xy 108.172165 -215.159094)
			(xy 108.216769 -215.135013) (xy 108.264532 -215.118041) (xy 108.289344 -215.112854) (xy 108.312204 -215.108536)
			(xy 108.517182 -214.753444) (xy 108.509308 -214.7316) (xy 108.500729 -214.705181) (xy 108.491532 -214.650406)
			(xy 108.49102 -214.622634) (xy 108.491528 -214.596747) (xy 108.499627 -214.545609) (xy 108.515626 -214.496369)
			(xy 108.539132 -214.450237) (xy 108.569564 -214.40835) (xy 108.606174 -214.37174) (xy 108.648061 -214.341308)
			(xy 108.694193 -214.317802) (xy 108.743433 -214.301803) (xy 108.794571 -214.293704) (xy 108.846345 -214.293704)
			(xy 108.897483 -214.301803) (xy 108.946723 -214.317802) (xy 108.992855 -214.341308) (xy 109.034742 -214.37174)
			(xy 109.071352 -214.40835) (xy 109.101784 -214.450237) (xy 109.12529 -214.496369) (xy 109.141289 -214.545609)
			(xy 109.14142 -214.546434) (xy 110.371128 -214.546434) (xy 110.371636 -214.520547) (xy 110.379735 -214.469409)
			(xy 110.395734 -214.420169) (xy 110.41924 -214.374037) (xy 110.449672 -214.33215) (xy 110.486282 -214.29554)
			(xy 110.528169 -214.265108) (xy 110.574301 -214.241602) (xy 110.623541 -214.225603) (xy 110.674679 -214.217504)
			(xy 110.726453 -214.217504) (xy 110.777591 -214.225603) (xy 110.826831 -214.241602) (xy 110.872963 -214.265108)
			(xy 110.91485 -214.29554) (xy 110.95146 -214.33215) (xy 110.981892 -214.374037) (xy 111.005398 -214.420169)
			(xy 111.021397 -214.469409) (xy 111.029496 -214.520547) (xy 111.030004 -214.546434) (xy 111.029625 -214.569368)
			(xy 111.029219 -214.572283) (xy 112.250803 -214.572283) (xy 112.250803 -214.520517) (xy 112.258901 -214.469389)
			(xy 112.274896 -214.420157) (xy 112.298395 -214.374033) (xy 112.32882 -214.332153) (xy 112.365421 -214.295547)
			(xy 112.407297 -214.265117) (xy 112.453418 -214.241612) (xy 112.502648 -214.22561) (xy 112.553775 -214.217507)
			(xy 112.579658 -214.216996) (xy 112.605169 -214.217509) (xy 112.655581 -214.225363) (xy 112.704182 -214.24089)
			(xy 112.749811 -214.263719) (xy 112.791377 -214.293306) (xy 112.827889 -214.328944) (xy 112.843564 -214.349076)
			(xy 113.255552 -214.349076) (xy 113.271247 -214.328958) (xy 113.307753 -214.293314) (xy 113.349314 -214.263719)
			(xy 113.394938 -214.24088) (xy 113.443536 -214.225342) (xy 113.493947 -214.217476) (xy 113.519458 -214.216996)
			(xy 113.545352 -214.217406) (xy 113.596504 -214.225502) (xy 113.645759 -214.2415) (xy 113.691905 -214.265008)
			(xy 113.733805 -214.295445) (xy 113.770428 -214.332063) (xy 113.80087 -214.373959) (xy 113.824384 -214.420102)
			(xy 113.840388 -214.469355) (xy 113.848491 -214.520506) (xy 113.848491 -214.572294) (xy 113.840388 -214.623445)
			(xy 113.824384 -214.672698) (xy 113.80087 -214.718841) (xy 113.770428 -214.760737) (xy 113.733805 -214.797355)
			(xy 113.691905 -214.827792) (xy 113.645759 -214.8513) (xy 113.596504 -214.867298) (xy 113.545352 -214.875394)
			(xy 113.519458 -214.875872) (xy 113.493944 -214.875433) (xy 113.443527 -214.867566) (xy 113.394925 -214.852025)
			(xy 113.349296 -214.829181) (xy 113.307732 -214.799581) (xy 113.271224 -214.763931) (xy 113.255552 -214.743792)
			(xy 112.843564 -214.743792) (xy 112.827909 -214.763943) (xy 112.791396 -214.799586) (xy 112.749827 -214.829178)
			(xy 112.704195 -214.852012) (xy 112.655589 -214.867542) (xy 112.605171 -214.875398) (xy 112.579658 -214.875872)
			(xy 112.553775 -214.875293) (xy 112.502648 -214.86719) (xy 112.453418 -214.851188) (xy 112.407297 -214.827683)
			(xy 112.365421 -214.797253) (xy 112.32882 -214.760647) (xy 112.298395 -214.718767) (xy 112.274896 -214.672643)
			(xy 112.258901 -214.623411) (xy 112.250803 -214.572283) (xy 111.029219 -214.572283) (xy 111.023299 -214.614796)
			(xy 111.010731 -214.658907) (xy 111.00181 -214.680038) (xy 110.991904 -214.702644) (xy 111.205772 -215.108028)
			(xy 111.229902 -215.1126) (xy 111.254835 -215.117694) (xy 111.302873 -215.134477) (xy 111.347761 -215.158443)
			(xy 111.388433 -215.189024) (xy 111.423922 -215.225492) (xy 111.453384 -215.266981) (xy 111.47612 -215.312505)
			(xy 111.491589 -215.360982) (xy 111.499424 -215.411261) (xy 111.499904 -215.436704) (xy 113.65992 -215.436704)
			(xy 113.660429 -215.41136) (xy 113.6682 -215.36127) (xy 113.683546 -215.31296) (xy 113.706103 -215.267567)
			(xy 113.735342 -215.226161) (xy 113.770573 -215.189717) (xy 113.810965 -215.159094) (xy 113.855569 -215.135013)
			(xy 113.903332 -215.118041) (xy 113.928144 -215.112854) (xy 113.951004 -215.108536) (xy 114.156236 -214.753444)
			(xy 114.148362 -214.731346) (xy 114.139733 -214.704999) (xy 114.130411 -214.650352) (xy 114.12982 -214.622634)
			(xy 114.130328 -214.596727) (xy 114.138434 -214.54555) (xy 114.154446 -214.496271) (xy 114.177969 -214.450104)
			(xy 114.208425 -214.408185) (xy 114.245063 -214.371547) (xy 114.286982 -214.341091) (xy 114.333149 -214.317568)
			(xy 114.382428 -214.301556) (xy 114.433605 -214.29345) (xy 114.485419 -214.29345) (xy 114.536596 -214.301556)
			(xy 114.585875 -214.317568) (xy 114.632042 -214.341091) (xy 114.673961 -214.371547) (xy 114.710599 -214.408185)
			(xy 114.741055 -214.450104) (xy 114.764578 -214.496271) (xy 114.78059 -214.54555) (xy 114.788696 -214.596727)
			(xy 114.789204 -214.622634) (xy 114.78871 -214.647978) (xy 114.780934 -214.698068) (xy 114.765584 -214.746377)
			(xy 114.743024 -214.791769) (xy 114.713783 -214.833174) (xy 114.678552 -214.869617) (xy 114.638158 -214.90024)
			(xy 114.593555 -214.924322) (xy 114.545792 -214.941296) (xy 114.52098 -214.946484) (xy 114.49812 -214.950802)
			(xy 114.292888 -215.305894) (xy 114.300762 -215.327992) (xy 114.309397 -215.354337) (xy 114.318716 -215.408986)
			(xy 114.319304 -215.436704) (xy 114.318796 -215.462611) (xy 114.31069 -215.513788) (xy 114.294678 -215.563067)
			(xy 114.271155 -215.609234) (xy 114.240699 -215.651153) (xy 114.204061 -215.687791) (xy 114.162142 -215.718247)
			(xy 114.115975 -215.74177) (xy 114.066696 -215.757782) (xy 114.015519 -215.765888) (xy 113.963705 -215.765888)
			(xy 113.912528 -215.757782) (xy 113.863249 -215.74177) (xy 113.817082 -215.718247) (xy 113.775163 -215.687791)
			(xy 113.738525 -215.651153) (xy 113.708069 -215.609234) (xy 113.684546 -215.563067) (xy 113.668534 -215.513788)
			(xy 113.660428 -215.462611) (xy 113.65992 -215.436704) (xy 111.499904 -215.436704) (xy 111.499396 -215.462611)
			(xy 111.49129 -215.513788) (xy 111.475278 -215.563067) (xy 111.451755 -215.609234) (xy 111.421299 -215.651153)
			(xy 111.384661 -215.687791) (xy 111.342742 -215.718247) (xy 111.296575 -215.74177) (xy 111.247296 -215.757782)
			(xy 111.196119 -215.765888) (xy 111.144305 -215.765888) (xy 111.093128 -215.757782) (xy 111.043849 -215.74177)
			(xy 110.997682 -215.718247) (xy 110.955763 -215.687791) (xy 110.919125 -215.651153) (xy 110.888669 -215.609234)
			(xy 110.865146 -215.563067) (xy 110.849134 -215.513788) (xy 110.841028 -215.462611) (xy 110.84052 -215.436704)
			(xy 110.840955 -215.413764) (xy 110.847378 -215.368334) (xy 110.860018 -215.324227) (xy 110.868968 -215.3031)
			(xy 110.878874 -215.280494) (xy 110.665006 -214.87511) (xy 110.640876 -214.870538) (xy 110.615954 -214.86544)
			(xy 110.567941 -214.848641) (xy 110.523081 -214.824663) (xy 110.482438 -214.794075) (xy 110.44698 -214.757604)
			(xy 110.417549 -214.716116) (xy 110.394843 -214.670598) (xy 110.379403 -214.622131) (xy 110.371595 -214.571867)
			(xy 110.371128 -214.546434) (xy 109.14142 -214.546434) (xy 109.149388 -214.596747) (xy 109.149896 -214.622634)
			(xy 109.149447 -214.64797) (xy 109.14169 -214.698044) (xy 109.126363 -214.746341) (xy 109.103827 -214.791726)
			(xy 109.074612 -214.833128) (xy 109.039408 -214.869572) (xy 108.999042 -214.900202) (xy 108.954465 -214.924296)
			(xy 108.906727 -214.941286) (xy 108.881926 -214.946484) (xy 108.859066 -214.950802) (xy 108.654088 -215.305894)
			(xy 108.661962 -215.327738) (xy 108.67061 -215.354146) (xy 108.679929 -215.408922) (xy 108.680504 -215.436704)
			(xy 108.679996 -215.46261) (xy 108.961394 -215.46261) (xy 108.961394 -215.41079) (xy 108.9695 -215.359609)
			(xy 108.985513 -215.310326) (xy 109.00904 -215.264155) (xy 109.039499 -215.222232) (xy 109.076141 -215.185591)
			(xy 109.118065 -215.155133) (xy 109.164237 -215.131609) (xy 109.213521 -215.115597) (xy 109.264702 -215.107493)
			(xy 109.290612 -215.107012) (xy 109.316124 -215.107479) (xy 109.36654 -215.115342) (xy 109.415142 -215.130878)
			(xy 109.46077 -215.153716) (xy 109.502335 -215.183311) (xy 109.538845 -215.218956) (xy 109.554518 -215.239092)
			(xy 109.966506 -215.239092) (xy 109.982174 -215.218952) (xy 110.018685 -215.183309) (xy 110.060252 -215.153716)
			(xy 110.105881 -215.130881) (xy 110.154484 -215.115348) (xy 110.2049 -215.107489) (xy 110.230412 -215.107012)
			(xy 110.256319 -215.107513) (xy 110.307495 -215.11562) (xy 110.356773 -215.131633) (xy 110.402939 -215.155158)
			(xy 110.444856 -215.185614) (xy 110.481494 -215.222253) (xy 110.511949 -215.264172) (xy 110.535471 -215.310339)
			(xy 110.551482 -215.359617) (xy 110.559588 -215.410793) (xy 110.559588 -215.462607) (xy 110.551482 -215.513783)
			(xy 110.535471 -215.563061) (xy 110.511949 -215.609228) (xy 110.481494 -215.651147) (xy 110.444856 -215.687786)
			(xy 110.402939 -215.718242) (xy 110.356773 -215.741767) (xy 110.307495 -215.75778) (xy 110.256319 -215.765887)
			(xy 110.230412 -215.766396) (xy 110.2049 -215.765908) (xy 110.154486 -215.758049) (xy 110.105885 -215.742517)
			(xy 110.060256 -215.719683) (xy 110.018691 -215.690092) (xy 109.98218 -215.65445) (xy 109.966506 -215.634316)
			(xy 109.554518 -215.634316) (xy 109.538838 -215.654446) (xy 109.502329 -215.69009) (xy 109.460765 -215.719683)
			(xy 109.415138 -215.74252) (xy 109.366537 -215.758055) (xy 109.316124 -215.765918) (xy 109.290612 -215.766396)
			(xy 109.264702 -215.765907) (xy 109.213521 -215.757803) (xy 109.164237 -215.741791) (xy 109.118065 -215.718267)
			(xy 109.076141 -215.687809) (xy 109.039499 -215.651168) (xy 109.00904 -215.609245) (xy 108.985513 -215.563074)
			(xy 108.9695 -215.513791) (xy 108.961394 -215.46261) (xy 108.679996 -215.46261) (xy 108.679996 -215.462611)
			(xy 108.67189 -215.513788) (xy 108.655878 -215.563067) (xy 108.632355 -215.609234) (xy 108.601899 -215.651153)
			(xy 108.565261 -215.687791) (xy 108.523342 -215.718247) (xy 108.477175 -215.74177) (xy 108.427896 -215.757782)
			(xy 108.376719 -215.765888) (xy 108.324905 -215.765888) (xy 108.273728 -215.757782) (xy 108.224449 -215.74177)
			(xy 108.178282 -215.718247) (xy 108.136363 -215.687791) (xy 108.099725 -215.651153) (xy 108.069269 -215.609234)
			(xy 108.045746 -215.563067) (xy 108.029734 -215.513788) (xy 108.021628 -215.462611) (xy 108.02112 -215.436704)
			(xy 106.800904 -215.436704) (xy 106.800396 -215.462611) (xy 106.79229 -215.513788) (xy 106.776278 -215.563067)
			(xy 106.752755 -215.609234) (xy 106.722299 -215.651153) (xy 106.685661 -215.687791) (xy 106.643742 -215.718247)
			(xy 106.597575 -215.74177) (xy 106.548296 -215.757782) (xy 106.497119 -215.765888) (xy 106.445305 -215.765888)
			(xy 106.394128 -215.757782) (xy 106.344849 -215.74177) (xy 106.298682 -215.718247) (xy 106.256763 -215.687791)
			(xy 106.220125 -215.651153) (xy 106.189669 -215.609234) (xy 106.166146 -215.563067) (xy 106.150134 -215.513788)
			(xy 106.142028 -215.462611) (xy 106.14152 -215.436704) (xy 104.921304 -215.436704) (xy 104.920796 -215.462611)
			(xy 104.91269 -215.513788) (xy 104.896678 -215.563067) (xy 104.873155 -215.609234) (xy 104.842699 -215.651153)
			(xy 104.806061 -215.687791) (xy 104.764142 -215.718247) (xy 104.717975 -215.74177) (xy 104.668696 -215.757782)
			(xy 104.617519 -215.765888) (xy 104.565705 -215.765888) (xy 104.514528 -215.757782) (xy 104.465249 -215.74177)
			(xy 104.419082 -215.718247) (xy 104.377163 -215.687791) (xy 104.340525 -215.651153) (xy 104.310069 -215.609234)
			(xy 104.286546 -215.563067) (xy 104.270534 -215.513788) (xy 104.262428 -215.462611) (xy 104.26192 -215.436704)
			(xy 103.041704 -215.436704) (xy 103.041196 -215.462611) (xy 103.03309 -215.513788) (xy 103.017078 -215.563067)
			(xy 102.993555 -215.609234) (xy 102.963099 -215.651153) (xy 102.926461 -215.687791) (xy 102.884542 -215.718247)
			(xy 102.838375 -215.74177) (xy 102.789096 -215.757782) (xy 102.737919 -215.765888) (xy 102.686105 -215.765888)
			(xy 102.634928 -215.757782) (xy 102.585649 -215.74177) (xy 102.539482 -215.718247) (xy 102.497563 -215.687791)
			(xy 102.460925 -215.651153) (xy 102.430469 -215.609234) (xy 102.406946 -215.563067) (xy 102.390934 -215.513788)
			(xy 102.382828 -215.462611) (xy 102.38232 -215.436704) (xy 101.162104 -215.436704) (xy 101.161683 -215.459024)
			(xy 101.15557 -215.503247) (xy 101.149912 -215.524842) (xy 101.148134 -215.531446) (xy 101.148134 -216.973658)
			(xy 101.149912 -216.980008) (xy 101.15505 -217.000709) (xy 101.160534 -217.043009) (xy 101.160834 -217.064336)
			(xy 101.160509 -217.085662) (xy 101.155034 -217.12796) (xy 101.149912 -217.148664) (xy 101.148134 -217.155014)
			(xy 101.148134 -217.563192) (xy 101.206046 -217.563192) (xy 101.21265 -217.561414) (xy 101.241098 -217.554556)
			(xy 101.263958 -217.550238) (xy 101.468936 -217.195146) (xy 101.461062 -217.173302) (xy 101.452412 -217.146894)
			(xy 101.443083 -217.092118) (xy 101.44252 -217.064336) (xy 101.443028 -217.038429) (xy 101.451134 -216.987252)
			(xy 101.467146 -216.937973) (xy 101.490669 -216.891806) (xy 101.521125 -216.849887) (xy 101.557763 -216.813249)
			(xy 101.599682 -216.782793) (xy 101.645849 -216.75927) (xy 101.695128 -216.743258) (xy 101.746305 -216.735152)
			(xy 101.798119 -216.735152) (xy 101.849296 -216.743258) (xy 101.898575 -216.75927) (xy 101.944742 -216.782793)
			(xy 101.986661 -216.813249) (xy 102.023299 -216.849887) (xy 102.053755 -216.891806) (xy 102.077278 -216.937973)
			(xy 102.09329 -216.987252) (xy 102.101396 -217.038429) (xy 102.101904 -217.064336) (xy 102.101444 -217.089687)
			(xy 102.093689 -217.139791) (xy 102.078354 -217.188117) (xy 102.055799 -217.233525) (xy 102.026556 -217.274944)
			(xy 101.991316 -217.311396) (xy 101.95091 -217.342021) (xy 101.90629 -217.366098) (xy 101.85851 -217.383058)
			(xy 101.83368 -217.388186) (xy 101.81082 -217.392504) (xy 101.605842 -217.747596) (xy 101.613716 -217.76944)
			(xy 101.622291 -217.795859) (xy 101.631477 -217.850635) (xy 101.632004 -217.878406) (xy 101.912928 -217.878406)
			(xy 101.913436 -217.852519) (xy 101.921535 -217.801381) (xy 101.937534 -217.752141) (xy 101.96104 -217.706009)
			(xy 101.991472 -217.664122) (xy 102.028082 -217.627512) (xy 102.069969 -217.59708) (xy 102.116101 -217.573574)
			(xy 102.165341 -217.557575) (xy 102.216479 -217.549476) (xy 102.268253 -217.549476) (xy 102.319391 -217.557575)
			(xy 102.368631 -217.573574) (xy 102.414763 -217.59708) (xy 102.45665 -217.627512) (xy 102.49326 -217.664122)
			(xy 102.523692 -217.706009) (xy 102.547198 -217.752141) (xy 102.563197 -217.801381) (xy 102.571296 -217.852519)
			(xy 102.571804 -217.878406) (xy 102.852728 -217.878406) (xy 102.853194 -217.853071) (xy 102.860946 -217.802996)
			(xy 102.876269 -217.754698) (xy 102.898802 -217.709313) (xy 102.928014 -217.66791) (xy 102.963217 -217.631464)
			(xy 103.003582 -217.600835) (xy 103.048159 -217.576742) (xy 103.095897 -217.559754) (xy 103.120698 -217.554556)
			(xy 103.143558 -217.550238) (xy 103.348536 -217.195146) (xy 103.340662 -217.173302) (xy 103.332024 -217.146891)
			(xy 103.322699 -217.092117) (xy 103.32212 -217.064336) (xy 103.322628 -217.038429) (xy 103.330734 -216.987252)
			(xy 103.346746 -216.937973) (xy 103.370269 -216.891806) (xy 103.400725 -216.849887) (xy 103.437363 -216.813249)
			(xy 103.479282 -216.782793) (xy 103.525449 -216.75927) (xy 103.574728 -216.743258) (xy 103.625905 -216.735152)
			(xy 103.677719 -216.735152) (xy 103.728896 -216.743258) (xy 103.778175 -216.75927) (xy 103.824342 -216.782793)
			(xy 103.866261 -216.813249) (xy 103.902899 -216.849887) (xy 103.933355 -216.891806) (xy 103.956878 -216.937973)
			(xy 103.97289 -216.987252) (xy 103.980996 -217.038429) (xy 103.981504 -217.064336) (xy 103.981012 -217.08968)
			(xy 103.973235 -217.13977) (xy 103.957886 -217.188079) (xy 103.935325 -217.233471) (xy 103.906084 -217.274876)
			(xy 103.870852 -217.311319) (xy 103.830459 -217.341943) (xy 103.785855 -217.366024) (xy 103.738092 -217.382998)
			(xy 103.71328 -217.388186) (xy 103.69042 -217.392504) (xy 103.485442 -217.747596) (xy 103.493316 -217.76944)
			(xy 103.501906 -217.795856) (xy 103.511095 -217.850633) (xy 103.511604 -217.878406) (xy 103.792528 -217.878406)
			(xy 103.793036 -217.852519) (xy 103.801135 -217.801381) (xy 103.817134 -217.752141) (xy 103.84064 -217.706009)
			(xy 103.871072 -217.664122) (xy 103.907682 -217.627512) (xy 103.949569 -217.59708) (xy 103.995701 -217.573574)
			(xy 104.044941 -217.557575) (xy 104.096079 -217.549476) (xy 104.147853 -217.549476) (xy 104.198991 -217.557575)
			(xy 104.248231 -217.573574) (xy 104.294363 -217.59708) (xy 104.33625 -217.627512) (xy 104.37286 -217.664122)
			(xy 104.403292 -217.706009) (xy 104.426798 -217.752141) (xy 104.442797 -217.801381) (xy 104.450896 -217.852519)
			(xy 104.451404 -217.878406) (xy 104.732328 -217.878406) (xy 104.732794 -217.853071) (xy 104.740546 -217.802996)
			(xy 104.755869 -217.754698) (xy 104.778402 -217.709313) (xy 104.807614 -217.66791) (xy 104.842817 -217.631464)
			(xy 104.883182 -217.600835) (xy 104.927759 -217.576742) (xy 104.975497 -217.559754) (xy 105.000298 -217.554556)
			(xy 105.023158 -217.550238) (xy 105.228136 -217.195146) (xy 105.220262 -217.173302) (xy 105.211624 -217.146891)
			(xy 105.202299 -217.092117) (xy 105.20172 -217.064336) (xy 105.202228 -217.038429) (xy 105.210334 -216.987252)
			(xy 105.226346 -216.937973) (xy 105.249869 -216.891806) (xy 105.280325 -216.849887) (xy 105.316963 -216.813249)
			(xy 105.358882 -216.782793) (xy 105.405049 -216.75927) (xy 105.454328 -216.743258) (xy 105.505505 -216.735152)
			(xy 105.557319 -216.735152) (xy 105.608496 -216.743258) (xy 105.657775 -216.75927) (xy 105.703942 -216.782793)
			(xy 105.745861 -216.813249) (xy 105.782499 -216.849887) (xy 105.812955 -216.891806) (xy 105.836478 -216.937973)
			(xy 105.85249 -216.987252) (xy 105.860596 -217.038429) (xy 105.861104 -217.064336) (xy 105.860612 -217.08968)
			(xy 105.852835 -217.13977) (xy 105.837486 -217.188079) (xy 105.814925 -217.233471) (xy 105.785684 -217.274876)
			(xy 105.750452 -217.311319) (xy 105.710059 -217.341943) (xy 105.665455 -217.366024) (xy 105.617692 -217.382998)
			(xy 105.59288 -217.388186) (xy 105.57002 -217.392504) (xy 105.365042 -217.747596) (xy 105.372916 -217.76944)
			(xy 105.381506 -217.795856) (xy 105.390695 -217.850633) (xy 105.391204 -217.878406) (xy 105.672128 -217.878406)
			(xy 105.672636 -217.852519) (xy 105.680735 -217.801381) (xy 105.696734 -217.752141) (xy 105.72024 -217.706009)
			(xy 105.750672 -217.664122) (xy 105.787282 -217.627512) (xy 105.829169 -217.59708) (xy 105.875301 -217.573574)
			(xy 105.924541 -217.557575) (xy 105.975679 -217.549476) (xy 106.027453 -217.549476) (xy 106.078591 -217.557575)
			(xy 106.127831 -217.573574) (xy 106.173963 -217.59708) (xy 106.21585 -217.627512) (xy 106.25246 -217.664122)
			(xy 106.282892 -217.706009) (xy 106.306398 -217.752141) (xy 106.322397 -217.801381) (xy 106.330496 -217.852519)
			(xy 106.331004 -217.878406) (xy 106.611928 -217.878406) (xy 106.612394 -217.853071) (xy 106.620146 -217.802996)
			(xy 106.635469 -217.754698) (xy 106.658002 -217.709313) (xy 106.687214 -217.66791) (xy 106.722417 -217.631464)
			(xy 106.762782 -217.600835) (xy 106.807359 -217.576742) (xy 106.855097 -217.559754) (xy 106.879898 -217.554556)
			(xy 106.902758 -217.550238) (xy 107.107736 -217.195146) (xy 107.099862 -217.173302) (xy 107.091224 -217.146891)
			(xy 107.081899 -217.092117) (xy 107.08132 -217.064336) (xy 107.081828 -217.038429) (xy 107.089934 -216.987252)
			(xy 107.105946 -216.937973) (xy 107.129469 -216.891806) (xy 107.159925 -216.849887) (xy 107.196563 -216.813249)
			(xy 107.238482 -216.782793) (xy 107.284649 -216.75927) (xy 107.333928 -216.743258) (xy 107.385105 -216.735152)
			(xy 107.436919 -216.735152) (xy 107.488096 -216.743258) (xy 107.537375 -216.75927) (xy 107.583542 -216.782793)
			(xy 107.625461 -216.813249) (xy 107.662099 -216.849887) (xy 107.692555 -216.891806) (xy 107.716078 -216.937973)
			(xy 107.73209 -216.987252) (xy 107.740196 -217.038429) (xy 107.740704 -217.064336) (xy 107.740212 -217.08968)
			(xy 107.732435 -217.13977) (xy 107.717086 -217.188079) (xy 107.694525 -217.233471) (xy 107.665284 -217.274876)
			(xy 107.630052 -217.311319) (xy 107.589659 -217.341943) (xy 107.545055 -217.366024) (xy 107.497292 -217.382998)
			(xy 107.47248 -217.388186) (xy 107.44962 -217.392504) (xy 107.244642 -217.747596) (xy 107.252516 -217.76944)
			(xy 107.261106 -217.795856) (xy 107.270295 -217.850633) (xy 107.270804 -217.878406) (xy 107.551728 -217.878406)
			(xy 107.552236 -217.852519) (xy 107.560335 -217.801381) (xy 107.576334 -217.752141) (xy 107.59984 -217.706009)
			(xy 107.630272 -217.664122) (xy 107.666882 -217.627512) (xy 107.708769 -217.59708) (xy 107.754901 -217.573574)
			(xy 107.804141 -217.557575) (xy 107.855279 -217.549476) (xy 107.907053 -217.549476) (xy 107.958191 -217.557575)
			(xy 108.007431 -217.573574) (xy 108.053563 -217.59708) (xy 108.09545 -217.627512) (xy 108.13206 -217.664122)
			(xy 108.162492 -217.706009) (xy 108.185998 -217.752141) (xy 108.201997 -217.801381) (xy 108.210096 -217.852519)
			(xy 108.210604 -217.878406) (xy 108.491528 -217.878406) (xy 108.491994 -217.853071) (xy 108.499746 -217.802996)
			(xy 108.515069 -217.754698) (xy 108.537602 -217.709313) (xy 108.566814 -217.66791) (xy 108.602017 -217.631464)
			(xy 108.642382 -217.600835) (xy 108.686959 -217.576742) (xy 108.734697 -217.559754) (xy 108.759498 -217.554556)
			(xy 108.782358 -217.550238) (xy 108.987336 -217.195146) (xy 108.979462 -217.173302) (xy 108.970824 -217.146891)
			(xy 108.961499 -217.092117) (xy 108.96092 -217.064336) (xy 108.961428 -217.038429) (xy 108.969534 -216.987252)
			(xy 108.985546 -216.937973) (xy 109.009069 -216.891806) (xy 109.039525 -216.849887) (xy 109.076163 -216.813249)
			(xy 109.118082 -216.782793) (xy 109.164249 -216.75927) (xy 109.213528 -216.743258) (xy 109.264705 -216.735152)
			(xy 109.316519 -216.735152) (xy 109.367696 -216.743258) (xy 109.416975 -216.75927) (xy 109.463142 -216.782793)
			(xy 109.505061 -216.813249) (xy 109.541699 -216.849887) (xy 109.572155 -216.891806) (xy 109.595678 -216.937973)
			(xy 109.61169 -216.987252) (xy 109.619796 -217.038429) (xy 109.620304 -217.064336) (xy 109.619812 -217.08968)
			(xy 109.612035 -217.13977) (xy 109.596686 -217.188079) (xy 109.574125 -217.233471) (xy 109.544884 -217.274876)
			(xy 109.509652 -217.311319) (xy 109.469259 -217.341943) (xy 109.424655 -217.366024) (xy 109.376892 -217.382998)
			(xy 109.35208 -217.388186) (xy 109.32922 -217.392504) (xy 109.124242 -217.747596) (xy 109.132116 -217.76944)
			(xy 109.140706 -217.795856) (xy 109.149895 -217.850633) (xy 109.150404 -217.878406) (xy 109.431328 -217.878406)
			(xy 109.431836 -217.852519) (xy 109.439935 -217.801381) (xy 109.455934 -217.752141) (xy 109.47944 -217.706009)
			(xy 109.509872 -217.664122) (xy 109.546482 -217.627512) (xy 109.588369 -217.59708) (xy 109.634501 -217.573574)
			(xy 109.683741 -217.557575) (xy 109.734879 -217.549476) (xy 109.786653 -217.549476) (xy 109.837791 -217.557575)
			(xy 109.887031 -217.573574) (xy 109.933163 -217.59708) (xy 109.97505 -217.627512) (xy 110.01166 -217.664122)
			(xy 110.042092 -217.706009) (xy 110.065598 -217.752141) (xy 110.081597 -217.801381) (xy 110.089696 -217.852519)
			(xy 110.090204 -217.878406) (xy 110.371128 -217.878406) (xy 110.371594 -217.853071) (xy 110.379346 -217.802996)
			(xy 110.394669 -217.754698) (xy 110.417202 -217.709313) (xy 110.446414 -217.66791) (xy 110.481617 -217.631464)
			(xy 110.521982 -217.600835) (xy 110.566559 -217.576742) (xy 110.614297 -217.559754) (xy 110.639098 -217.554556)
			(xy 110.661958 -217.550238) (xy 110.866936 -217.194892) (xy 110.859316 -217.173048) (xy 110.850741 -217.146694)
			(xy 110.841552 -217.092045) (xy 110.841028 -217.064336) (xy 110.841536 -217.038449) (xy 110.849635 -216.987311)
			(xy 110.865634 -216.938071) (xy 110.88914 -216.891939) (xy 110.919572 -216.850052) (xy 110.956182 -216.813442)
			(xy 110.998069 -216.78301) (xy 111.044201 -216.759504) (xy 111.093441 -216.743505) (xy 111.144579 -216.735406)
			(xy 111.196353 -216.735406) (xy 111.247491 -216.743505) (xy 111.296731 -216.759504) (xy 111.342863 -216.78301)
			(xy 111.38475 -216.813442) (xy 111.42136 -216.850052) (xy 111.451792 -216.891939) (xy 111.475298 -216.938071)
			(xy 111.491297 -216.987311) (xy 111.499396 -217.038449) (xy 111.499904 -217.064336) (xy 112.72012 -217.064336)
			(xy 112.720628 -217.038429) (xy 112.728734 -216.987252) (xy 112.744746 -216.937973) (xy 112.768269 -216.891806)
			(xy 112.798725 -216.849887) (xy 112.835363 -216.813249) (xy 112.877282 -216.782793) (xy 112.923449 -216.75927)
			(xy 112.972728 -216.743258) (xy 113.023905 -216.735152) (xy 113.075719 -216.735152) (xy 113.126896 -216.743258)
			(xy 113.176175 -216.75927) (xy 113.222342 -216.782793) (xy 113.264261 -216.813249) (xy 113.300899 -216.849887)
			(xy 113.331355 -216.891806) (xy 113.354878 -216.937973) (xy 113.37089 -216.987252) (xy 113.378996 -217.038429)
			(xy 113.379504 -217.064336) (xy 113.378889 -217.091989) (xy 113.369569 -217.146507) (xy 113.360962 -217.172794)
			(xy 113.353342 -217.194892) (xy 113.558574 -217.550238) (xy 113.581434 -217.554556) (xy 113.606241 -217.559728)
			(xy 113.653979 -217.576721) (xy 113.698556 -217.600818) (xy 113.73892 -217.631451) (xy 113.774123 -217.6679)
			(xy 113.803334 -217.709305) (xy 113.825866 -217.754693) (xy 113.841189 -217.802993) (xy 113.848941 -217.85307)
			(xy 113.849404 -217.878406) (xy 113.848896 -217.904293) (xy 113.840797 -217.955431) (xy 113.824798 -218.004671)
			(xy 113.801292 -218.050803) (xy 113.77086 -218.09269) (xy 113.73425 -218.1293) (xy 113.692363 -218.159732)
			(xy 113.646231 -218.183238) (xy 113.596991 -218.199237) (xy 113.545853 -218.207336) (xy 113.494079 -218.207336)
			(xy 113.442941 -218.199237) (xy 113.393701 -218.183238) (xy 113.347569 -218.159732) (xy 113.305682 -218.1293)
			(xy 113.269072 -218.09269) (xy 113.23864 -218.050803) (xy 113.215134 -218.004671) (xy 113.199135 -217.955431)
			(xy 113.191036 -217.904293) (xy 113.190528 -217.878406) (xy 113.191062 -217.850698) (xy 113.200255 -217.796051)
			(xy 113.208816 -217.769694) (xy 113.21669 -217.747596) (xy 113.011712 -217.392504) (xy 112.988852 -217.388186)
			(xy 112.963996 -217.383069) (xy 112.916148 -217.366166) (xy 112.871456 -217.342128) (xy 112.830977 -217.311523)
			(xy 112.795667 -217.275076) (xy 112.766361 -217.233647) (xy 112.743752 -217.188215) (xy 112.728374 -217.139855)
			(xy 112.72059 -217.089709) (xy 112.72012 -217.064336) (xy 111.499904 -217.064336) (xy 111.499412 -217.08968)
			(xy 111.491635 -217.13977) (xy 111.476286 -217.188079) (xy 111.453725 -217.233471) (xy 111.424484 -217.274876)
			(xy 111.389252 -217.311319) (xy 111.348859 -217.341943) (xy 111.304255 -217.366024) (xy 111.256492 -217.382998)
			(xy 111.23168 -217.388186) (xy 111.20882 -217.392504) (xy 111.003842 -217.747596) (xy 111.011716 -217.76944)
			(xy 111.020306 -217.795856) (xy 111.029495 -217.850633) (xy 111.030004 -217.878406) (xy 111.029496 -217.904293)
			(xy 111.021397 -217.955431) (xy 111.005398 -218.004671) (xy 110.981892 -218.050803) (xy 110.95146 -218.09269)
			(xy 110.91485 -218.1293) (xy 110.872963 -218.159732) (xy 110.826831 -218.183238) (xy 110.777591 -218.199237)
			(xy 110.726453 -218.207336) (xy 110.674679 -218.207336) (xy 110.623541 -218.199237) (xy 110.574301 -218.183238)
			(xy 110.528169 -218.159732) (xy 110.486282 -218.1293) (xy 110.449672 -218.09269) (xy 110.41924 -218.050803)
			(xy 110.395734 -218.004671) (xy 110.379735 -217.955431) (xy 110.371636 -217.904293) (xy 110.371128 -217.878406)
			(xy 110.090204 -217.878406) (xy 110.089676 -217.906114) (xy 110.08048 -217.960761) (xy 110.071916 -217.987118)
			(xy 110.064296 -218.008962) (xy 110.269274 -218.364054) (xy 110.292134 -218.368372) (xy 110.316944 -218.373529)
			(xy 110.364684 -218.390523) (xy 110.409261 -218.414621) (xy 110.449626 -218.445257) (xy 110.484829 -218.481707)
			(xy 110.51404 -218.523115) (xy 110.536571 -218.568504) (xy 110.551892 -218.616807) (xy 110.559642 -218.666885)
			(xy 110.560104 -218.692222) (xy 111.78032 -218.692222) (xy 111.780845 -218.666878) (xy 111.788614 -218.616789)
			(xy 111.803957 -218.56848) (xy 111.826512 -218.523087) (xy 111.855749 -218.481681) (xy 111.890978 -218.445236)
			(xy 111.931369 -218.414613) (xy 111.97597 -218.390531) (xy 112.023732 -218.373559) (xy 112.048544 -218.368372)
			(xy 112.071404 -218.364054) (xy 112.276636 -218.008708) (xy 112.268762 -217.98661) (xy 112.260294 -217.960366)
			(xy 112.251224 -217.905977) (xy 112.250728 -217.878406) (xy 112.251236 -217.852519) (xy 112.259335 -217.801381)
			(xy 112.275334 -217.752141) (xy 112.29884 -217.706009) (xy 112.329272 -217.664122) (xy 112.365882 -217.627512)
			(xy 112.407769 -217.59708) (xy 112.453901 -217.573574) (xy 112.503141 -217.557575) (xy 112.554279 -217.549476)
			(xy 112.606053 -217.549476) (xy 112.657191 -217.557575) (xy 112.706431 -217.573574) (xy 112.752563 -217.59708)
			(xy 112.79445 -217.627512) (xy 112.83106 -217.664122) (xy 112.861492 -217.706009) (xy 112.884998 -217.752141)
			(xy 112.900997 -217.801381) (xy 112.909096 -217.852519) (xy 112.909604 -217.878406) (xy 112.909131 -217.90378)
			(xy 112.901362 -217.953931) (xy 112.885993 -218.002296) (xy 112.863388 -218.047732) (xy 112.834082 -218.089163)
			(xy 112.798768 -218.125609) (xy 112.758282 -218.156208) (xy 112.713582 -218.180235) (xy 112.665726 -218.197122)
			(xy 112.640872 -218.202256) (xy 112.618012 -218.206574) (xy 112.413288 -218.561412) (xy 112.421162 -218.583256)
			(xy 112.429814 -218.609662) (xy 112.43913 -218.66444) (xy 112.439704 -218.692222) (xy 113.660428 -218.692222)
			(xy 113.660908 -218.666887) (xy 113.668658 -218.616813) (xy 113.683979 -218.568515) (xy 113.70651 -218.52313)
			(xy 113.73572 -218.481727) (xy 113.770922 -218.445282) (xy 113.811285 -218.414651) (xy 113.855861 -218.390558)
			(xy 113.903598 -218.37357) (xy 113.928398 -218.368372) (xy 113.951258 -218.364054) (xy 114.156236 -218.008962)
			(xy 114.148616 -217.986864) (xy 114.140061 -217.960571) (xy 114.130869 -217.906051) (xy 114.130328 -217.878406)
			(xy 114.130836 -217.852519) (xy 114.138935 -217.801381) (xy 114.154934 -217.752141) (xy 114.17844 -217.706009)
			(xy 114.208872 -217.664122) (xy 114.245482 -217.627512) (xy 114.287369 -217.59708) (xy 114.333501 -217.573574)
			(xy 114.382741 -217.557575) (xy 114.433879 -217.549476) (xy 114.485653 -217.549476) (xy 114.536791 -217.557575)
			(xy 114.586031 -217.573574) (xy 114.632163 -217.59708) (xy 114.67405 -217.627512) (xy 114.71066 -217.664122)
			(xy 114.741092 -217.706009) (xy 114.764598 -217.752141) (xy 114.780597 -217.801381) (xy 114.788696 -217.852519)
			(xy 114.789204 -217.878406) (xy 114.788769 -217.903771) (xy 114.781019 -217.953906) (xy 114.765673 -218.002259)
			(xy 114.743093 -218.047686) (xy 114.713814 -218.089114) (xy 114.678529 -218.125562) (xy 114.638071 -218.156167)
			(xy 114.593399 -218.180207) (xy 114.545568 -218.197111) (xy 114.520726 -218.202256) (xy 114.497866 -218.206574)
			(xy 114.293142 -218.561412) (xy 114.301016 -218.583256) (xy 114.309609 -218.609671) (xy 114.318797 -218.664449)
			(xy 114.319304 -218.692222) (xy 114.318796 -218.718109) (xy 114.310697 -218.769247) (xy 114.294698 -218.818487)
			(xy 114.271192 -218.864619) (xy 114.24076 -218.906506) (xy 114.20415 -218.943116) (xy 114.162263 -218.973548)
			(xy 114.116131 -218.997054) (xy 114.066891 -219.013053) (xy 114.015753 -219.021152) (xy 113.963979 -219.021152)
			(xy 113.912841 -219.013053) (xy 113.863601 -218.997054) (xy 113.817469 -218.973548) (xy 113.775582 -218.943116)
			(xy 113.738972 -218.906506) (xy 113.70854 -218.864619) (xy 113.685034 -218.818487) (xy 113.669035 -218.769247)
			(xy 113.660936 -218.718109) (xy 113.660428 -218.692222) (xy 112.439704 -218.692222) (xy 112.439196 -218.718129)
			(xy 112.43109 -218.769306) (xy 112.415078 -218.818585) (xy 112.391555 -218.864752) (xy 112.361099 -218.906671)
			(xy 112.324461 -218.943309) (xy 112.282542 -218.973765) (xy 112.236375 -218.997288) (xy 112.187096 -219.0133)
			(xy 112.135919 -219.021406) (xy 112.084105 -219.021406) (xy 112.032928 -219.0133) (xy 111.983649 -218.997288)
			(xy 111.937482 -218.973765) (xy 111.895563 -218.943309) (xy 111.858925 -218.906671) (xy 111.828469 -218.864752)
			(xy 111.804946 -218.818585) (xy 111.788934 -218.769306) (xy 111.780828 -218.718129) (xy 111.78032 -218.692222)
			(xy 110.560104 -218.692222) (xy 110.559596 -218.718109) (xy 110.551497 -218.769247) (xy 110.535498 -218.818487)
			(xy 110.511992 -218.864619) (xy 110.48156 -218.906506) (xy 110.44495 -218.943116) (xy 110.403063 -218.973548)
			(xy 110.356931 -218.997054) (xy 110.307691 -219.013053) (xy 110.256553 -219.021152) (xy 110.204779 -219.021152)
			(xy 110.153641 -219.013053) (xy 110.104401 -218.997054) (xy 110.058269 -218.973548) (xy 110.016382 -218.943116)
			(xy 109.979772 -218.906506) (xy 109.94934 -218.864619) (xy 109.925834 -218.818487) (xy 109.909835 -218.769247)
			(xy 109.901736 -218.718109) (xy 109.901228 -218.692222) (xy 109.901766 -218.664514) (xy 109.910956 -218.609868)
			(xy 109.919516 -218.58351) (xy 109.92739 -218.561412) (xy 109.722412 -218.206574) (xy 109.699552 -218.202256)
			(xy 109.67472 -218.197133) (xy 109.626938 -218.180175) (xy 109.582316 -218.1561) (xy 109.541908 -218.125474)
			(xy 109.506667 -218.089022) (xy 109.477424 -218.047602) (xy 109.45487 -218.002192) (xy 109.439537 -217.953864)
			(xy 109.431786 -217.903757) (xy 109.431328 -217.878406) (xy 109.150404 -217.878406) (xy 109.149896 -217.904293)
			(xy 109.141797 -217.955431) (xy 109.125798 -218.004671) (xy 109.102292 -218.050803) (xy 109.07186 -218.09269)
			(xy 109.03525 -218.1293) (xy 108.993363 -218.159732) (xy 108.947231 -218.183238) (xy 108.897991 -218.199237)
			(xy 108.846853 -218.207336) (xy 108.795079 -218.207336) (xy 108.743941 -218.199237) (xy 108.694701 -218.183238)
			(xy 108.648569 -218.159732) (xy 108.606682 -218.1293) (xy 108.570072 -218.09269) (xy 108.53964 -218.050803)
			(xy 108.516134 -218.004671) (xy 108.500135 -217.955431) (xy 108.492036 -217.904293) (xy 108.491528 -217.878406)
			(xy 108.210604 -217.878406) (xy 108.210076 -217.906114) (xy 108.20088 -217.960761) (xy 108.192316 -217.987118)
			(xy 108.184442 -218.009216) (xy 108.38942 -218.364054) (xy 108.41228 -218.368372) (xy 108.4371 -218.37354)
			(xy 108.484878 -218.390497) (xy 108.529495 -218.41457) (xy 108.5699 -218.44519) (xy 108.60514 -218.481637)
			(xy 108.634384 -218.52305) (xy 108.656942 -218.568452) (xy 108.672281 -218.616773) (xy 108.680041 -218.666873)
			(xy 108.680504 -218.692222) (xy 108.679996 -218.718129) (xy 108.67189 -218.769306) (xy 108.655878 -218.818585)
			(xy 108.632355 -218.864752) (xy 108.601899 -218.906671) (xy 108.565261 -218.943309) (xy 108.523342 -218.973765)
			(xy 108.477175 -218.997288) (xy 108.427896 -219.0133) (xy 108.376719 -219.021406) (xy 108.324905 -219.021406)
			(xy 108.273728 -219.0133) (xy 108.224449 -218.997288) (xy 108.178282 -218.973765) (xy 108.136363 -218.943309)
			(xy 108.099725 -218.906671) (xy 108.069269 -218.864752) (xy 108.045746 -218.818585) (xy 108.029734 -218.769306)
			(xy 108.021628 -218.718129) (xy 108.02112 -218.692222) (xy 108.021718 -218.664505) (xy 108.031039 -218.609858)
			(xy 108.039662 -218.58351) (xy 108.047536 -218.561412) (xy 107.842558 -218.206574) (xy 107.819698 -218.202256)
			(xy 107.794899 -218.197049) (xy 107.747162 -218.180062) (xy 107.702585 -218.15597) (xy 107.66222 -218.125341)
			(xy 107.627017 -218.088897) (xy 107.597804 -218.047495) (xy 107.575271 -218.002112) (xy 107.559946 -217.953814)
			(xy 107.552192 -217.903741) (xy 107.551728 -217.878406) (xy 107.270804 -217.878406) (xy 107.270296 -217.904293)
			(xy 107.262197 -217.955431) (xy 107.246198 -218.004671) (xy 107.222692 -218.050803) (xy 107.19226 -218.09269)
			(xy 107.15565 -218.1293) (xy 107.113763 -218.159732) (xy 107.067631 -218.183238) (xy 107.018391 -218.199237)
			(xy 106.967253 -218.207336) (xy 106.915479 -218.207336) (xy 106.864341 -218.199237) (xy 106.815101 -218.183238)
			(xy 106.768969 -218.159732) (xy 106.727082 -218.1293) (xy 106.690472 -218.09269) (xy 106.66004 -218.050803)
			(xy 106.636534 -218.004671) (xy 106.620535 -217.955431) (xy 106.612436 -217.904293) (xy 106.611928 -217.878406)
			(xy 106.331004 -217.878406) (xy 106.330476 -217.906114) (xy 106.32128 -217.960761) (xy 106.312716 -217.987118)
			(xy 106.304842 -218.009216) (xy 106.50982 -218.364054) (xy 106.53268 -218.368372) (xy 106.5575 -218.37354)
			(xy 106.605278 -218.390497) (xy 106.649895 -218.41457) (xy 106.6903 -218.44519) (xy 106.72554 -218.481637)
			(xy 106.754784 -218.52305) (xy 106.777342 -218.568452) (xy 106.792681 -218.616773) (xy 106.800441 -218.666873)
			(xy 106.800904 -218.692222) (xy 106.800396 -218.718129) (xy 106.79229 -218.769306) (xy 106.776278 -218.818585)
			(xy 106.752755 -218.864752) (xy 106.722299 -218.906671) (xy 106.685661 -218.943309) (xy 106.643742 -218.973765)
			(xy 106.597575 -218.997288) (xy 106.548296 -219.0133) (xy 106.497119 -219.021406) (xy 106.445305 -219.021406)
			(xy 106.394128 -219.0133) (xy 106.344849 -218.997288) (xy 106.298682 -218.973765) (xy 106.256763 -218.943309)
			(xy 106.220125 -218.906671) (xy 106.189669 -218.864752) (xy 106.166146 -218.818585) (xy 106.150134 -218.769306)
			(xy 106.142028 -218.718129) (xy 106.14152 -218.692222) (xy 106.142118 -218.664505) (xy 106.151439 -218.609858)
			(xy 106.160062 -218.58351) (xy 106.167936 -218.561412) (xy 105.962958 -218.206574) (xy 105.940098 -218.202256)
			(xy 105.915299 -218.197049) (xy 105.867562 -218.180062) (xy 105.822985 -218.15597) (xy 105.78262 -218.125341)
			(xy 105.747417 -218.088897) (xy 105.718204 -218.047495) (xy 105.695671 -218.002112) (xy 105.680346 -217.953814)
			(xy 105.672592 -217.903741) (xy 105.672128 -217.878406) (xy 105.391204 -217.878406) (xy 105.390696 -217.904293)
			(xy 105.382597 -217.955431) (xy 105.366598 -218.004671) (xy 105.343092 -218.050803) (xy 105.31266 -218.09269)
			(xy 105.27605 -218.1293) (xy 105.234163 -218.159732) (xy 105.188031 -218.183238) (xy 105.138791 -218.199237)
			(xy 105.087653 -218.207336) (xy 105.035879 -218.207336) (xy 104.984741 -218.199237) (xy 104.935501 -218.183238)
			(xy 104.889369 -218.159732) (xy 104.847482 -218.1293) (xy 104.810872 -218.09269) (xy 104.78044 -218.050803)
			(xy 104.756934 -218.004671) (xy 104.740935 -217.955431) (xy 104.732836 -217.904293) (xy 104.732328 -217.878406)
			(xy 104.451404 -217.878406) (xy 104.450876 -217.906114) (xy 104.44168 -217.960761) (xy 104.433116 -217.987118)
			(xy 104.425242 -218.009216) (xy 104.63022 -218.364054) (xy 104.65308 -218.368372) (xy 104.6779 -218.37354)
			(xy 104.725678 -218.390497) (xy 104.770295 -218.41457) (xy 104.8107 -218.44519) (xy 104.84594 -218.481637)
			(xy 104.875184 -218.52305) (xy 104.897742 -218.568452) (xy 104.913081 -218.616773) (xy 104.920841 -218.666873)
			(xy 104.921304 -218.692222) (xy 104.920796 -218.718129) (xy 104.91269 -218.769306) (xy 104.896678 -218.818585)
			(xy 104.873155 -218.864752) (xy 104.842699 -218.906671) (xy 104.806061 -218.943309) (xy 104.764142 -218.973765)
			(xy 104.717975 -218.997288) (xy 104.668696 -219.0133) (xy 104.617519 -219.021406) (xy 104.565705 -219.021406)
			(xy 104.514528 -219.0133) (xy 104.465249 -218.997288) (xy 104.419082 -218.973765) (xy 104.377163 -218.943309)
			(xy 104.340525 -218.906671) (xy 104.310069 -218.864752) (xy 104.286546 -218.818585) (xy 104.270534 -218.769306)
			(xy 104.262428 -218.718129) (xy 104.26192 -218.692222) (xy 104.262518 -218.664505) (xy 104.271839 -218.609858)
			(xy 104.280462 -218.58351) (xy 104.288336 -218.561412) (xy 104.083358 -218.206574) (xy 104.060498 -218.202256)
			(xy 104.035699 -218.197049) (xy 103.987962 -218.180062) (xy 103.943385 -218.15597) (xy 103.90302 -218.125341)
			(xy 103.867817 -218.088897) (xy 103.838604 -218.047495) (xy 103.816071 -218.002112) (xy 103.800746 -217.953814)
			(xy 103.792992 -217.903741) (xy 103.792528 -217.878406) (xy 103.511604 -217.878406) (xy 103.511096 -217.904293)
			(xy 103.502997 -217.955431) (xy 103.486998 -218.004671) (xy 103.463492 -218.050803) (xy 103.43306 -218.09269)
			(xy 103.39645 -218.1293) (xy 103.354563 -218.159732) (xy 103.308431 -218.183238) (xy 103.259191 -218.199237)
			(xy 103.208053 -218.207336) (xy 103.156279 -218.207336) (xy 103.105141 -218.199237) (xy 103.055901 -218.183238)
			(xy 103.009769 -218.159732) (xy 102.967882 -218.1293) (xy 102.931272 -218.09269) (xy 102.90084 -218.050803)
			(xy 102.877334 -218.004671) (xy 102.861335 -217.955431) (xy 102.853236 -217.904293) (xy 102.852728 -217.878406)
			(xy 102.571804 -217.878406) (xy 102.571276 -217.906114) (xy 102.56208 -217.960761) (xy 102.553516 -217.987118)
			(xy 102.545642 -218.009216) (xy 102.75062 -218.364054) (xy 102.77348 -218.368372) (xy 102.7983 -218.37354)
			(xy 102.846078 -218.390497) (xy 102.890695 -218.41457) (xy 102.9311 -218.44519) (xy 102.96634 -218.481637)
			(xy 102.995584 -218.52305) (xy 103.018142 -218.568452) (xy 103.033481 -218.616773) (xy 103.041241 -218.666873)
			(xy 103.041704 -218.692222) (xy 103.041196 -218.718129) (xy 103.03309 -218.769306) (xy 103.017078 -218.818585)
			(xy 102.993555 -218.864752) (xy 102.963099 -218.906671) (xy 102.926461 -218.943309) (xy 102.884542 -218.973765)
			(xy 102.838375 -218.997288) (xy 102.789096 -219.0133) (xy 102.737919 -219.021406) (xy 102.686105 -219.021406)
			(xy 102.634928 -219.0133) (xy 102.585649 -218.997288) (xy 102.539482 -218.973765) (xy 102.497563 -218.943309)
			(xy 102.460925 -218.906671) (xy 102.430469 -218.864752) (xy 102.406946 -218.818585) (xy 102.390934 -218.769306)
			(xy 102.382828 -218.718129) (xy 102.38232 -218.692222) (xy 102.382918 -218.664505) (xy 102.392239 -218.609858)
			(xy 102.400862 -218.58351) (xy 102.408736 -218.561412) (xy 102.203758 -218.206574) (xy 102.180898 -218.202256)
			(xy 102.156099 -218.197049) (xy 102.108362 -218.180062) (xy 102.063785 -218.15597) (xy 102.02342 -218.125341)
			(xy 101.988217 -218.088897) (xy 101.959004 -218.047495) (xy 101.936471 -218.002112) (xy 101.921146 -217.953814)
			(xy 101.913392 -217.903741) (xy 101.912928 -217.878406) (xy 101.632004 -217.878406) (xy 101.631522 -217.904294)
			(xy 101.623421 -217.955433) (xy 101.60742 -218.004675) (xy 101.583912 -218.050807) (xy 101.553476 -218.092693)
			(xy 101.516863 -218.129302) (xy 101.474973 -218.159733) (xy 101.428838 -218.183235) (xy 101.379594 -218.199231)
			(xy 101.328454 -218.207325) (xy 101.302566 -218.207844) (xy 101.292446 -218.207812) (xy 101.272239 -218.206669)
			(xy 101.26218 -218.205558) (xy 101.247859 -218.204283) (xy 101.219484 -218.208838) (xy 101.193502 -218.221118)
			(xy 101.171968 -218.24015) (xy 101.15659 -218.264427) (xy 101.148583 -218.292027) (xy 101.148134 -218.306396)
			(xy 101.148134 -218.59748) (xy 101.149912 -218.604084) (xy 101.155576 -218.625678) (xy 101.161697 -218.669901)
			(xy 101.162104 -218.692222) (xy 101.161682 -218.714542) (xy 101.155566 -218.758764) (xy 101.149912 -218.78036)
			(xy 101.148134 -218.786964) (xy 101.148134 -219.079572) (xy 101.148624 -219.093938) (xy 101.156622 -219.121533)
			(xy 101.171992 -219.145808) (xy 101.193518 -219.164838) (xy 101.219493 -219.177117) (xy 101.247861 -219.181671)
			(xy 101.26218 -219.18041) (xy 101.272236 -219.179236) (xy 101.292443 -219.177963) (xy 101.302566 -219.17787)
			(xy 101.328356 -219.178347) (xy 101.379302 -219.186412) (xy 101.428359 -219.202348) (xy 101.474319 -219.225764)
			(xy 101.516049 -219.256081) (xy 101.552521 -219.292554) (xy 101.582838 -219.334285) (xy 101.606253 -219.380244)
			(xy 101.622189 -219.429302) (xy 101.630253 -219.480248) (xy 101.630734 -219.506038) (xy 101.630189 -219.532081)
			(xy 101.62189 -219.583504) (xy 101.614224 -219.6084) (xy 101.604572 -219.638118) (xy 102.863396 -220.896942)
			(xy 102.870762 -220.904562) (xy 102.878164 -220.911888) (xy 102.897165 -220.920361) (xy 102.917968 -220.920582)
			(xy 102.937145 -220.912515) (xy 102.944676 -220.905324) (xy 102.962654 -220.88733) (xy 103.003142 -220.856542)
			(xy 103.047879 -220.832341) (xy 103.095804 -220.8153) (xy 103.120698 -220.810074) (xy 103.143558 -220.805756)
			(xy 103.348536 -220.450664) (xy 103.340662 -220.42882) (xy 103.332019 -220.402411) (xy 103.322703 -220.347635)
			(xy 103.32212 -220.319854) (xy 103.322628 -220.293947) (xy 103.330734 -220.24277) (xy 103.346746 -220.193491)
			(xy 103.370269 -220.147324) (xy 103.400725 -220.105405) (xy 103.437363 -220.068767) (xy 103.479282 -220.038311)
			(xy 103.525449 -220.014788) (xy 103.574728 -219.998776) (xy 103.625905 -219.99067) (xy 103.677719 -219.99067)
			(xy 103.728896 -219.998776) (xy 103.778175 -220.014788) (xy 103.824342 -220.038311) (xy 103.866261 -220.068767)
			(xy 103.902899 -220.105405) (xy 103.933355 -220.147324) (xy 103.956878 -220.193491) (xy 103.97289 -220.24277)
			(xy 103.980996 -220.293947) (xy 103.981504 -220.319854) (xy 105.20172 -220.319854) (xy 105.202228 -220.293947)
			(xy 105.210334 -220.24277) (xy 105.226346 -220.193491) (xy 105.249869 -220.147324) (xy 105.280325 -220.105405)
			(xy 105.316963 -220.068767) (xy 105.358882 -220.038311) (xy 105.405049 -220.014788) (xy 105.454328 -219.998776)
			(xy 105.505505 -219.99067) (xy 105.557319 -219.99067) (xy 105.608496 -219.998776) (xy 105.657775 -220.014788)
			(xy 105.703942 -220.038311) (xy 105.745861 -220.068767) (xy 105.782499 -220.105405) (xy 105.812955 -220.147324)
			(xy 105.836478 -220.193491) (xy 105.85249 -220.24277) (xy 105.860596 -220.293947) (xy 105.861104 -220.319854)
			(xy 107.08132 -220.319854) (xy 107.081828 -220.293947) (xy 107.089934 -220.24277) (xy 107.105946 -220.193491)
			(xy 107.129469 -220.147324) (xy 107.159925 -220.105405) (xy 107.196563 -220.068767) (xy 107.238482 -220.038311)
			(xy 107.284649 -220.014788) (xy 107.333928 -219.998776) (xy 107.385105 -219.99067) (xy 107.436919 -219.99067)
			(xy 107.488096 -219.998776) (xy 107.537375 -220.014788) (xy 107.583542 -220.038311) (xy 107.625461 -220.068767)
			(xy 107.662099 -220.105405) (xy 107.692555 -220.147324) (xy 107.716078 -220.193491) (xy 107.73209 -220.24277)
			(xy 107.740196 -220.293947) (xy 107.740704 -220.319854) (xy 108.96092 -220.319854) (xy 108.961428 -220.293947)
			(xy 108.969534 -220.24277) (xy 108.985546 -220.193491) (xy 109.009069 -220.147324) (xy 109.039525 -220.105405)
			(xy 109.076163 -220.068767) (xy 109.118082 -220.038311) (xy 109.164249 -220.014788) (xy 109.213528 -219.998776)
			(xy 109.264705 -219.99067) (xy 109.316519 -219.99067) (xy 109.367696 -219.998776) (xy 109.416975 -220.014788)
			(xy 109.463142 -220.038311) (xy 109.505061 -220.068767) (xy 109.541699 -220.105405) (xy 109.572155 -220.147324)
			(xy 109.595678 -220.193491) (xy 109.61169 -220.24277) (xy 109.619796 -220.293947) (xy 109.620304 -220.319854)
			(xy 110.84052 -220.319854) (xy 110.841028 -220.293947) (xy 110.849134 -220.24277) (xy 110.865146 -220.193491)
			(xy 110.888669 -220.147324) (xy 110.919125 -220.105405) (xy 110.955763 -220.068767) (xy 110.997682 -220.038311)
			(xy 111.043849 -220.014788) (xy 111.093128 -219.998776) (xy 111.144305 -219.99067) (xy 111.196119 -219.99067)
			(xy 111.247296 -219.998776) (xy 111.296575 -220.014788) (xy 111.342742 -220.038311) (xy 111.384661 -220.068767)
			(xy 111.421299 -220.105405) (xy 111.451755 -220.147324) (xy 111.475278 -220.193491) (xy 111.49129 -220.24277)
			(xy 111.499396 -220.293947) (xy 111.499904 -220.319854) (xy 112.72012 -220.319854) (xy 112.720628 -220.293947)
			(xy 112.728734 -220.24277) (xy 112.744746 -220.193491) (xy 112.768269 -220.147324) (xy 112.798725 -220.105405)
			(xy 112.835363 -220.068767) (xy 112.877282 -220.038311) (xy 112.923449 -220.014788) (xy 112.972728 -219.998776)
			(xy 113.023905 -219.99067) (xy 113.075719 -219.99067) (xy 113.126896 -219.998776) (xy 113.176175 -220.014788)
			(xy 113.222342 -220.038311) (xy 113.264261 -220.068767) (xy 113.300899 -220.105405) (xy 113.331355 -220.147324)
			(xy 113.354878 -220.193491) (xy 113.37089 -220.24277) (xy 113.378996 -220.293947) (xy 113.379504 -220.319854)
			(xy 113.378894 -220.347507) (xy 113.369571 -220.402025) (xy 113.360962 -220.428312) (xy 113.353342 -220.45041)
			(xy 113.558574 -220.805756) (xy 113.581434 -220.810074) (xy 113.606245 -220.815229) (xy 113.653984 -220.832223)
			(xy 113.698562 -220.856322) (xy 113.738927 -220.886957) (xy 113.77413 -220.923408) (xy 113.80334 -220.964816)
			(xy 113.825872 -221.010206) (xy 113.841192 -221.058509) (xy 113.848942 -221.108587) (xy 113.849404 -221.133924)
			(xy 113.848896 -221.159811) (xy 113.840797 -221.210949) (xy 113.824798 -221.260189) (xy 113.801292 -221.306321)
			(xy 113.77086 -221.348208) (xy 113.73425 -221.384818) (xy 113.692363 -221.41525) (xy 113.646231 -221.438756)
			(xy 113.596991 -221.454755) (xy 113.545853 -221.462854) (xy 113.494079 -221.462854) (xy 113.442941 -221.454755)
			(xy 113.393701 -221.438756) (xy 113.347569 -221.41525) (xy 113.305682 -221.384818) (xy 113.269072 -221.348208)
			(xy 113.23864 -221.306321) (xy 113.215134 -221.260189) (xy 113.199135 -221.210949) (xy 113.191036 -221.159811)
			(xy 113.190528 -221.133924) (xy 113.191067 -221.106216) (xy 113.200256 -221.05157) (xy 113.208816 -221.025212)
			(xy 113.21669 -221.003114) (xy 113.011712 -220.648022) (xy 112.988852 -220.643704) (xy 112.964 -220.63857)
			(xy 112.916153 -220.621668) (xy 112.871462 -220.597632) (xy 112.830984 -220.567029) (xy 112.795674 -220.530584)
			(xy 112.766368 -220.489157) (xy 112.743757 -220.443728) (xy 112.728377 -220.39537) (xy 112.720591 -220.345226)
			(xy 112.72012 -220.319854) (xy 111.499904 -220.319854) (xy 111.499294 -220.347507) (xy 111.489971 -220.402025)
			(xy 111.481362 -220.428312) (xy 111.473742 -220.45041) (xy 111.678974 -220.805756) (xy 111.701834 -220.810074)
			(xy 111.726645 -220.815229) (xy 111.774384 -220.832223) (xy 111.818962 -220.856322) (xy 111.859327 -220.886957)
			(xy 111.89453 -220.923408) (xy 111.92374 -220.964816) (xy 111.946272 -221.010206) (xy 111.961592 -221.058509)
			(xy 111.969342 -221.108587) (xy 111.969804 -221.133924) (xy 111.969296 -221.159811) (xy 111.961197 -221.210949)
			(xy 111.945198 -221.260189) (xy 111.921692 -221.306321) (xy 111.89126 -221.348208) (xy 111.85465 -221.384818)
			(xy 111.812763 -221.41525) (xy 111.766631 -221.438756) (xy 111.717391 -221.454755) (xy 111.666253 -221.462854)
			(xy 111.614479 -221.462854) (xy 111.563341 -221.454755) (xy 111.514101 -221.438756) (xy 111.467969 -221.41525)
			(xy 111.426082 -221.384818) (xy 111.389472 -221.348208) (xy 111.35904 -221.306321) (xy 111.335534 -221.260189)
			(xy 111.319535 -221.210949) (xy 111.311436 -221.159811) (xy 111.310928 -221.133924) (xy 111.311467 -221.106216)
			(xy 111.320656 -221.05157) (xy 111.329216 -221.025212) (xy 111.33709 -221.003114) (xy 111.132112 -220.648022)
			(xy 111.109252 -220.643704) (xy 111.0844 -220.63857) (xy 111.036553 -220.621668) (xy 110.991862 -220.597632)
			(xy 110.951384 -220.567029) (xy 110.916074 -220.530584) (xy 110.886768 -220.489157) (xy 110.864157 -220.443728)
			(xy 110.848777 -220.39537) (xy 110.840991 -220.345226) (xy 110.84052 -220.319854) (xy 109.620304 -220.319854)
			(xy 109.619694 -220.347507) (xy 109.610371 -220.402025) (xy 109.601762 -220.428312) (xy 109.594142 -220.45041)
			(xy 109.799374 -220.805756) (xy 109.822234 -220.810074) (xy 109.847045 -220.815229) (xy 109.894784 -220.832223)
			(xy 109.939362 -220.856322) (xy 109.979727 -220.886957) (xy 110.01493 -220.923408) (xy 110.04414 -220.964816)
			(xy 110.066672 -221.010206) (xy 110.081992 -221.058509) (xy 110.089742 -221.108587) (xy 110.090204 -221.133924)
			(xy 110.089696 -221.159811) (xy 110.081597 -221.210949) (xy 110.065598 -221.260189) (xy 110.042092 -221.306321)
			(xy 110.01166 -221.348208) (xy 109.97505 -221.384818) (xy 109.933163 -221.41525) (xy 109.887031 -221.438756)
			(xy 109.837791 -221.454755) (xy 109.786653 -221.462854) (xy 109.734879 -221.462854) (xy 109.683741 -221.454755)
			(xy 109.634501 -221.438756) (xy 109.588369 -221.41525) (xy 109.546482 -221.384818) (xy 109.509872 -221.348208)
			(xy 109.47944 -221.306321) (xy 109.455934 -221.260189) (xy 109.439935 -221.210949) (xy 109.431836 -221.159811)
			(xy 109.431328 -221.133924) (xy 109.431867 -221.106216) (xy 109.441056 -221.05157) (xy 109.449616 -221.025212)
			(xy 109.45749 -221.003114) (xy 109.252512 -220.648022) (xy 109.229652 -220.643704) (xy 109.2048 -220.63857)
			(xy 109.156953 -220.621668) (xy 109.112262 -220.597632) (xy 109.071784 -220.567029) (xy 109.036474 -220.530584)
			(xy 109.007168 -220.489157) (xy 108.984557 -220.443728) (xy 108.969177 -220.39537) (xy 108.961391 -220.345226)
			(xy 108.96092 -220.319854) (xy 107.740704 -220.319854) (xy 107.740094 -220.347507) (xy 107.730771 -220.402025)
			(xy 107.722162 -220.428312) (xy 107.714542 -220.45041) (xy 107.919774 -220.805756) (xy 107.942634 -220.810074)
			(xy 107.967445 -220.815229) (xy 108.015184 -220.832223) (xy 108.059762 -220.856322) (xy 108.100127 -220.886957)
			(xy 108.13533 -220.923408) (xy 108.16454 -220.964816) (xy 108.187072 -221.010206) (xy 108.202392 -221.058509)
			(xy 108.210142 -221.108587) (xy 108.210604 -221.133924) (xy 108.210096 -221.159811) (xy 108.201997 -221.210949)
			(xy 108.185998 -221.260189) (xy 108.162492 -221.306321) (xy 108.13206 -221.348208) (xy 108.09545 -221.384818)
			(xy 108.053563 -221.41525) (xy 108.007431 -221.438756) (xy 107.958191 -221.454755) (xy 107.907053 -221.462854)
			(xy 107.855279 -221.462854) (xy 107.804141 -221.454755) (xy 107.754901 -221.438756) (xy 107.708769 -221.41525)
			(xy 107.666882 -221.384818) (xy 107.630272 -221.348208) (xy 107.59984 -221.306321) (xy 107.576334 -221.260189)
			(xy 107.560335 -221.210949) (xy 107.552236 -221.159811) (xy 107.551728 -221.133924) (xy 107.552267 -221.106216)
			(xy 107.561456 -221.05157) (xy 107.570016 -221.025212) (xy 107.57789 -221.003114) (xy 107.372912 -220.648022)
			(xy 107.350052 -220.643704) (xy 107.3252 -220.63857) (xy 107.277353 -220.621668) (xy 107.232662 -220.597632)
			(xy 107.192184 -220.567029) (xy 107.156874 -220.530584) (xy 107.127568 -220.489157) (xy 107.104957 -220.443728)
			(xy 107.089577 -220.39537) (xy 107.081791 -220.345226) (xy 107.08132 -220.319854) (xy 105.861104 -220.319854)
			(xy 105.860494 -220.347507) (xy 105.851171 -220.402025) (xy 105.842562 -220.428312) (xy 105.834942 -220.45041)
			(xy 106.040174 -220.805756) (xy 106.063034 -220.810074) (xy 106.087845 -220.815229) (xy 106.135584 -220.832223)
			(xy 106.180162 -220.856322) (xy 106.220527 -220.886957) (xy 106.25573 -220.923408) (xy 106.28494 -220.964816)
			(xy 106.307472 -221.010206) (xy 106.322792 -221.058509) (xy 106.330542 -221.108587) (xy 106.331004 -221.133924)
			(xy 106.330496 -221.159811) (xy 106.322397 -221.210949) (xy 106.306398 -221.260189) (xy 106.282892 -221.306321)
			(xy 106.25246 -221.348208) (xy 106.21585 -221.384818) (xy 106.173963 -221.41525) (xy 106.127831 -221.438756)
			(xy 106.078591 -221.454755) (xy 106.027453 -221.462854) (xy 105.975679 -221.462854) (xy 105.924541 -221.454755)
			(xy 105.875301 -221.438756) (xy 105.829169 -221.41525) (xy 105.787282 -221.384818) (xy 105.750672 -221.348208)
			(xy 105.72024 -221.306321) (xy 105.696734 -221.260189) (xy 105.680735 -221.210949) (xy 105.672636 -221.159811)
			(xy 105.672128 -221.133924) (xy 105.672667 -221.106216) (xy 105.681856 -221.05157) (xy 105.690416 -221.025212)
			(xy 105.69829 -221.003114) (xy 105.493312 -220.648022) (xy 105.470452 -220.643704) (xy 105.4456 -220.63857)
			(xy 105.397753 -220.621668) (xy 105.353062 -220.597632) (xy 105.312584 -220.567029) (xy 105.277274 -220.530584)
			(xy 105.247968 -220.489157) (xy 105.225357 -220.443728) (xy 105.209977 -220.39537) (xy 105.202191 -220.345226)
			(xy 105.20172 -220.319854) (xy 103.981504 -220.319854) (xy 103.981042 -220.345204) (xy 103.973286 -220.395306)
			(xy 103.957949 -220.44363) (xy 103.935392 -220.489036) (xy 103.90615 -220.530452) (xy 103.870909 -220.566902)
			(xy 103.830504 -220.597525) (xy 103.785885 -220.6216) (xy 103.738106 -220.638559) (xy 103.71328 -220.643704)
			(xy 103.69042 -220.648022) (xy 103.485442 -221.003114) (xy 103.493316 -221.024958) (xy 103.501897 -221.051376)
			(xy 103.511097 -221.106152) (xy 103.511604 -221.133924) (xy 103.511095 -221.159818) (xy 103.502995 -221.210968)
			(xy 103.486997 -221.260223) (xy 103.463494 -221.30637) (xy 103.433066 -221.348276) (xy 103.39646 -221.384909)
			(xy 103.354577 -221.415368) (xy 103.308446 -221.438904) (xy 103.259204 -221.454938) (xy 103.208059 -221.463076)
			(xy 103.182166 -221.463616) (xy 103.154312 -221.46299) (xy 103.099409 -221.453535) (xy 103.072946 -221.44482)
			(xy 103.059699 -221.440682) (xy 103.032014 -221.438911) (xy 103.004875 -221.444661) (xy 102.980287 -221.457506)
			(xy 102.960067 -221.476499) (xy 102.945708 -221.500235) (xy 102.938272 -221.526961) (xy 102.937818 -221.540832)
			(xy 102.937818 -221.70771) (xy 102.957062 -221.726527) (xy 102.98977 -221.769267) (xy 103.015096 -221.816755)
			(xy 103.032368 -221.867728) (xy 103.041125 -221.92083) (xy 103.041704 -221.94774) (xy 104.26192 -221.94774)
			(xy 104.262371 -221.922394) (xy 104.270152 -221.872302) (xy 104.285506 -221.82399) (xy 104.308072 -221.778597)
			(xy 104.337318 -221.737192) (xy 104.372555 -221.700749) (xy 104.412954 -221.670127) (xy 104.457562 -221.646047)
			(xy 104.50533 -221.629076) (xy 104.530144 -221.62389) (xy 104.553004 -221.619572) (xy 104.758236 -221.264226)
			(xy 104.750362 -221.242128) (xy 104.741898 -221.215883) (xy 104.732825 -221.161495) (xy 104.732328 -221.133924)
			(xy 104.732836 -221.108037) (xy 104.740935 -221.056899) (xy 104.756934 -221.007659) (xy 104.78044 -220.961527)
			(xy 104.810872 -220.91964) (xy 104.847482 -220.88303) (xy 104.889369 -220.852598) (xy 104.935501 -220.829092)
			(xy 104.984741 -220.813093) (xy 105.035879 -220.804994) (xy 105.087653 -220.804994) (xy 105.138791 -220.813093)
			(xy 105.188031 -220.829092) (xy 105.234163 -220.852598) (xy 105.27605 -220.88303) (xy 105.31266 -220.91964)
			(xy 105.343092 -220.961527) (xy 105.366598 -221.007659) (xy 105.382597 -221.056899) (xy 105.390696 -221.108037)
			(xy 105.391204 -221.133924) (xy 105.390748 -221.159299) (xy 105.382976 -221.20945) (xy 105.367604 -221.257815)
			(xy 105.344997 -221.303251) (xy 105.315689 -221.344682) (xy 105.280373 -221.381128) (xy 105.239885 -221.411727)
			(xy 105.195184 -221.435754) (xy 105.147326 -221.452641) (xy 105.122472 -221.457774) (xy 105.099612 -221.462092)
			(xy 104.894888 -221.81693) (xy 104.902762 -221.838774) (xy 104.911419 -221.865179) (xy 104.920732 -221.919958)
			(xy 104.921304 -221.94774) (xy 106.14152 -221.94774) (xy 106.141971 -221.922394) (xy 106.149752 -221.872302)
			(xy 106.165106 -221.82399) (xy 106.187672 -221.778597) (xy 106.216918 -221.737192) (xy 106.252155 -221.700749)
			(xy 106.292554 -221.670127) (xy 106.337162 -221.646047) (xy 106.38493 -221.629076) (xy 106.409744 -221.62389)
			(xy 106.432604 -221.619572) (xy 106.637836 -221.264226) (xy 106.629962 -221.242128) (xy 106.621498 -221.215883)
			(xy 106.612425 -221.161495) (xy 106.611928 -221.133924) (xy 106.612436 -221.108037) (xy 106.620535 -221.056899)
			(xy 106.636534 -221.007659) (xy 106.66004 -220.961527) (xy 106.690472 -220.91964) (xy 106.727082 -220.88303)
			(xy 106.768969 -220.852598) (xy 106.815101 -220.829092) (xy 106.864341 -220.813093) (xy 106.915479 -220.804994)
			(xy 106.967253 -220.804994) (xy 107.018391 -220.813093) (xy 107.067631 -220.829092) (xy 107.113763 -220.852598)
			(xy 107.15565 -220.88303) (xy 107.19226 -220.91964) (xy 107.222692 -220.961527) (xy 107.246198 -221.007659)
			(xy 107.262197 -221.056899) (xy 107.270296 -221.108037) (xy 107.270804 -221.133924) (xy 107.270348 -221.159299)
			(xy 107.262576 -221.20945) (xy 107.247204 -221.257815) (xy 107.224597 -221.303251) (xy 107.195289 -221.344682)
			(xy 107.159973 -221.381128) (xy 107.119485 -221.411727) (xy 107.074784 -221.435754) (xy 107.026926 -221.452641)
			(xy 107.002072 -221.457774) (xy 106.979212 -221.462092) (xy 106.774488 -221.81693) (xy 106.782362 -221.838774)
			(xy 106.791019 -221.865179) (xy 106.800332 -221.919958) (xy 106.800904 -221.94774) (xy 108.02112 -221.94774)
			(xy 108.021571 -221.922394) (xy 108.029352 -221.872302) (xy 108.044706 -221.82399) (xy 108.067272 -221.778597)
			(xy 108.096518 -221.737192) (xy 108.131755 -221.700749) (xy 108.172154 -221.670127) (xy 108.216762 -221.646047)
			(xy 108.26453 -221.629076) (xy 108.289344 -221.62389) (xy 108.312204 -221.619572) (xy 108.517436 -221.264226)
			(xy 108.509562 -221.242128) (xy 108.501098 -221.215883) (xy 108.492025 -221.161495) (xy 108.491528 -221.133924)
			(xy 108.492036 -221.108037) (xy 108.500135 -221.056899) (xy 108.516134 -221.007659) (xy 108.53964 -220.961527)
			(xy 108.570072 -220.91964) (xy 108.606682 -220.88303) (xy 108.648569 -220.852598) (xy 108.694701 -220.829092)
			(xy 108.743941 -220.813093) (xy 108.795079 -220.804994) (xy 108.846853 -220.804994) (xy 108.897991 -220.813093)
			(xy 108.947231 -220.829092) (xy 108.993363 -220.852598) (xy 109.03525 -220.88303) (xy 109.07186 -220.91964)
			(xy 109.102292 -220.961527) (xy 109.125798 -221.007659) (xy 109.141797 -221.056899) (xy 109.149896 -221.108037)
			(xy 109.150404 -221.133924) (xy 109.149948 -221.159299) (xy 109.142176 -221.20945) (xy 109.126804 -221.257815)
			(xy 109.104197 -221.303251) (xy 109.074889 -221.344682) (xy 109.039573 -221.381128) (xy 108.999085 -221.411727)
			(xy 108.954384 -221.435754) (xy 108.906526 -221.452641) (xy 108.881672 -221.457774) (xy 108.858812 -221.462092)
			(xy 108.654088 -221.81693) (xy 108.661962 -221.838774) (xy 108.670619 -221.865179) (xy 108.679932 -221.919958)
			(xy 108.680504 -221.94774) (xy 109.901228 -221.94774) (xy 109.901634 -221.922403) (xy 109.909396 -221.872326)
			(xy 109.924728 -221.824026) (xy 109.947269 -221.77864) (xy 109.976489 -221.737238) (xy 110.011699 -221.700794)
			(xy 110.05207 -221.670165) (xy 110.096652 -221.646074) (xy 110.144395 -221.629087) (xy 110.169198 -221.62389)
			(xy 110.192058 -221.619572) (xy 110.397036 -221.26448) (xy 110.389416 -221.242382) (xy 110.380865 -221.216087)
			(xy 110.371671 -221.161569) (xy 110.371128 -221.133924) (xy 110.371636 -221.108037) (xy 110.379735 -221.056899)
			(xy 110.395734 -221.007659) (xy 110.41924 -220.961527) (xy 110.449672 -220.91964) (xy 110.486282 -220.88303)
			(xy 110.528169 -220.852598) (xy 110.574301 -220.829092) (xy 110.623541 -220.813093) (xy 110.674679 -220.804994)
			(xy 110.726453 -220.804994) (xy 110.777591 -220.813093) (xy 110.826831 -220.829092) (xy 110.872963 -220.852598)
			(xy 110.91485 -220.88303) (xy 110.95146 -220.91964) (xy 110.981892 -220.961527) (xy 111.005398 -221.007659)
			(xy 111.021397 -221.056899) (xy 111.029496 -221.108037) (xy 111.030004 -221.133924) (xy 111.029585 -221.15929)
			(xy 111.021833 -221.209425) (xy 111.006484 -221.257778) (xy 110.983902 -221.303206) (xy 110.954621 -221.344633)
			(xy 110.919333 -221.381081) (xy 110.878874 -221.411686) (xy 110.8342 -221.435725) (xy 110.786369 -221.45263)
			(xy 110.761526 -221.457774) (xy 110.738666 -221.462092) (xy 110.533942 -221.81693) (xy 110.541816 -221.838774)
			(xy 110.550414 -221.865187) (xy 110.559598 -221.919967) (xy 110.560104 -221.94774) (xy 111.78032 -221.94774)
			(xy 111.780771 -221.922394) (xy 111.788552 -221.872302) (xy 111.803906 -221.82399) (xy 111.826472 -221.778597)
			(xy 111.855718 -221.737192) (xy 111.890955 -221.700749) (xy 111.931354 -221.670127) (xy 111.975962 -221.646047)
			(xy 112.02373 -221.629076) (xy 112.048544 -221.62389) (xy 112.071404 -221.619572) (xy 112.276636 -221.264226)
			(xy 112.268762 -221.242128) (xy 112.260298 -221.215883) (xy 112.251225 -221.161495) (xy 112.250728 -221.133924)
			(xy 112.251236 -221.108037) (xy 112.259335 -221.056899) (xy 112.275334 -221.007659) (xy 112.29884 -220.961527)
			(xy 112.329272 -220.91964) (xy 112.365882 -220.88303) (xy 112.407769 -220.852598) (xy 112.453901 -220.829092)
			(xy 112.503141 -220.813093) (xy 112.554279 -220.804994) (xy 112.606053 -220.804994) (xy 112.657191 -220.813093)
			(xy 112.706431 -220.829092) (xy 112.752563 -220.852598) (xy 112.79445 -220.88303) (xy 112.83106 -220.91964)
			(xy 112.861492 -220.961527) (xy 112.884998 -221.007659) (xy 112.900997 -221.056899) (xy 112.909096 -221.108037)
			(xy 112.909604 -221.133924) (xy 112.909148 -221.159299) (xy 112.901376 -221.20945) (xy 112.886004 -221.257815)
			(xy 112.863397 -221.303251) (xy 112.834089 -221.344682) (xy 112.798773 -221.381128) (xy 112.758285 -221.411727)
			(xy 112.713584 -221.435754) (xy 112.665726 -221.452641) (xy 112.640872 -221.457774) (xy 112.618012 -221.462092)
			(xy 112.413288 -221.81693) (xy 112.421162 -221.838774) (xy 112.429819 -221.865179) (xy 112.439132 -221.919958)
			(xy 112.439704 -221.94774) (xy 113.660428 -221.94774) (xy 113.660834 -221.922403) (xy 113.668596 -221.872326)
			(xy 113.683928 -221.824026) (xy 113.706469 -221.77864) (xy 113.735689 -221.737238) (xy 113.770899 -221.700794)
			(xy 113.81127 -221.670165) (xy 113.855852 -221.646074) (xy 113.903595 -221.629087) (xy 113.928398 -221.62389)
			(xy 113.951258 -221.619572) (xy 114.156236 -221.26448) (xy 114.148616 -221.242382) (xy 114.140065 -221.216087)
			(xy 114.130871 -221.161569) (xy 114.130328 -221.133924) (xy 114.130836 -221.108037) (xy 114.138935 -221.056899)
			(xy 114.154934 -221.007659) (xy 114.17844 -220.961527) (xy 114.208872 -220.91964) (xy 114.245482 -220.88303)
			(xy 114.287369 -220.852598) (xy 114.333501 -220.829092) (xy 114.382741 -220.813093) (xy 114.433879 -220.804994)
			(xy 114.485653 -220.804994) (xy 114.536791 -220.813093) (xy 114.586031 -220.829092) (xy 114.632163 -220.852598)
			(xy 114.67405 -220.88303) (xy 114.71066 -220.91964) (xy 114.741092 -220.961527) (xy 114.764598 -221.007659)
			(xy 114.780597 -221.056899) (xy 114.788696 -221.108037) (xy 114.789204 -221.133924) (xy 114.788785 -221.15929)
			(xy 114.781033 -221.209425) (xy 114.765684 -221.257778) (xy 114.743102 -221.303206) (xy 114.713821 -221.344633)
			(xy 114.678533 -221.381081) (xy 114.638074 -221.411686) (xy 114.5934 -221.435725) (xy 114.545569 -221.45263)
			(xy 114.520726 -221.457774) (xy 114.497866 -221.462092) (xy 114.293142 -221.81693) (xy 114.301016 -221.838774)
			(xy 114.309614 -221.865187) (xy 114.318798 -221.919967) (xy 114.319304 -221.94774) (xy 114.318796 -221.973627)
			(xy 114.310697 -222.024765) (xy 114.294698 -222.074005) (xy 114.271192 -222.120137) (xy 114.24076 -222.162024)
			(xy 114.20415 -222.198634) (xy 114.162263 -222.229066) (xy 114.116131 -222.252572) (xy 114.066891 -222.268571)
			(xy 114.015753 -222.27667) (xy 113.963979 -222.27667) (xy 113.912841 -222.268571) (xy 113.863601 -222.252572)
			(xy 113.817469 -222.229066) (xy 113.775582 -222.198634) (xy 113.738972 -222.162024) (xy 113.70854 -222.120137)
			(xy 113.685034 -222.074005) (xy 113.669035 -222.024765) (xy 113.660936 -221.973627) (xy 113.660428 -221.94774)
			(xy 112.439704 -221.94774) (xy 112.439196 -221.973647) (xy 112.43109 -222.024824) (xy 112.415078 -222.074103)
			(xy 112.391555 -222.12027) (xy 112.361099 -222.162189) (xy 112.324461 -222.198827) (xy 112.282542 -222.229283)
			(xy 112.236375 -222.252806) (xy 112.187096 -222.268818) (xy 112.135919 -222.276924) (xy 112.084105 -222.276924)
			(xy 112.032928 -222.268818) (xy 111.983649 -222.252806) (xy 111.937482 -222.229283) (xy 111.895563 -222.198827)
			(xy 111.858925 -222.162189) (xy 111.828469 -222.12027) (xy 111.804946 -222.074103) (xy 111.788934 -222.024824)
			(xy 111.780828 -221.973647) (xy 111.78032 -221.94774) (xy 110.560104 -221.94774) (xy 110.559596 -221.973627)
			(xy 110.551497 -222.024765) (xy 110.535498 -222.074005) (xy 110.511992 -222.120137) (xy 110.48156 -222.162024)
			(xy 110.44495 -222.198634) (xy 110.403063 -222.229066) (xy 110.356931 -222.252572) (xy 110.307691 -222.268571)
			(xy 110.256553 -222.27667) (xy 110.204779 -222.27667) (xy 110.153641 -222.268571) (xy 110.104401 -222.252572)
			(xy 110.058269 -222.229066) (xy 110.016382 -222.198634) (xy 109.979772 -222.162024) (xy 109.94934 -222.120137)
			(xy 109.925834 -222.074005) (xy 109.909835 -222.024765) (xy 109.901736 -221.973627) (xy 109.901228 -221.94774)
			(xy 108.680504 -221.94774) (xy 108.679996 -221.973647) (xy 108.67189 -222.024824) (xy 108.655878 -222.074103)
			(xy 108.632355 -222.12027) (xy 108.601899 -222.162189) (xy 108.565261 -222.198827) (xy 108.523342 -222.229283)
			(xy 108.477175 -222.252806) (xy 108.427896 -222.268818) (xy 108.376719 -222.276924) (xy 108.324905 -222.276924)
			(xy 108.273728 -222.268818) (xy 108.224449 -222.252806) (xy 108.178282 -222.229283) (xy 108.136363 -222.198827)
			(xy 108.099725 -222.162189) (xy 108.069269 -222.12027) (xy 108.045746 -222.074103) (xy 108.029734 -222.024824)
			(xy 108.021628 -221.973647) (xy 108.02112 -221.94774) (xy 106.800904 -221.94774) (xy 106.800396 -221.973647)
			(xy 106.79229 -222.024824) (xy 106.776278 -222.074103) (xy 106.752755 -222.12027) (xy 106.722299 -222.162189)
			(xy 106.685661 -222.198827) (xy 106.643742 -222.229283) (xy 106.597575 -222.252806) (xy 106.548296 -222.268818)
			(xy 106.497119 -222.276924) (xy 106.445305 -222.276924) (xy 106.394128 -222.268818) (xy 106.344849 -222.252806)
			(xy 106.298682 -222.229283) (xy 106.256763 -222.198827) (xy 106.220125 -222.162189) (xy 106.189669 -222.12027)
			(xy 106.166146 -222.074103) (xy 106.150134 -222.024824) (xy 106.142028 -221.973647) (xy 106.14152 -221.94774)
			(xy 104.921304 -221.94774) (xy 104.920796 -221.973647) (xy 104.91269 -222.024824) (xy 104.896678 -222.074103)
			(xy 104.873155 -222.12027) (xy 104.842699 -222.162189) (xy 104.806061 -222.198827) (xy 104.764142 -222.229283)
			(xy 104.717975 -222.252806) (xy 104.668696 -222.268818) (xy 104.617519 -222.276924) (xy 104.565705 -222.276924)
			(xy 104.514528 -222.268818) (xy 104.465249 -222.252806) (xy 104.419082 -222.229283) (xy 104.377163 -222.198827)
			(xy 104.340525 -222.162189) (xy 104.310069 -222.12027) (xy 104.286546 -222.074103) (xy 104.270534 -222.024824)
			(xy 104.262428 -221.973647) (xy 104.26192 -221.94774) (xy 103.041704 -221.94774) (xy 103.041144 -221.974647)
			(xy 103.032355 -222.02774) (xy 103.015065 -222.078703) (xy 102.989733 -222.126183) (xy 102.957031 -222.168922)
			(xy 102.937818 -222.18777) (xy 102.937818 -223.337374) (xy 102.956845 -223.356091) (xy 102.989167 -223.398558)
			(xy 103.014186 -223.445699) (xy 103.03124 -223.496269) (xy 103.03988 -223.548934) (xy 103.039877 -223.602302)
			(xy 103.031232 -223.654966) (xy 103.014172 -223.705534) (xy 102.989148 -223.752672) (xy 102.956821 -223.795136)
			(xy 102.937818 -223.813878) (xy 102.937818 -223.982534) (xy 102.938289 -223.996396) (xy 102.945753 -224.023097)
			(xy 102.96012 -224.046808) (xy 102.980334 -224.065783) (xy 103.004906 -224.078624) (xy 103.032025 -224.084386)
			(xy 103.059694 -224.082644) (xy 103.072946 -224.078546) (xy 103.084657 -224.074522) (xy 103.108559 -224.068041)
			(xy 103.120698 -224.065592) (xy 103.143558 -224.061274) (xy 103.348282 -223.706436) (xy 103.340662 -223.684338)
			(xy 103.332035 -223.65799) (xy 103.322706 -223.603344) (xy 103.32212 -223.575626) (xy 103.322628 -223.549719)
			(xy 103.330734 -223.498542) (xy 103.346746 -223.449263) (xy 103.370269 -223.403096) (xy 103.400725 -223.361177)
			(xy 103.437363 -223.324539) (xy 103.479282 -223.294083) (xy 103.525449 -223.27056) (xy 103.574728 -223.254548)
			(xy 103.625905 -223.246442) (xy 103.677719 -223.246442) (xy 103.728896 -223.254548) (xy 103.778175 -223.27056)
			(xy 103.824342 -223.294083) (xy 103.866261 -223.324539) (xy 103.902899 -223.361177) (xy 103.933355 -223.403096)
			(xy 103.956878 -223.449263) (xy 103.97289 -223.498542) (xy 103.980996 -223.549719) (xy 103.981504 -223.575626)
			(xy 103.981029 -223.600984) (xy 103.973244 -223.651099) (xy 103.957876 -223.699431) (xy 103.935288 -223.744839)
			(xy 103.906013 -223.786253) (xy 103.870742 -223.822696) (xy 103.830306 -223.853307) (xy 103.78566 -223.877366)
			(xy 103.737855 -223.894304) (xy 103.713026 -223.899476) (xy 103.690166 -223.903794) (xy 103.485442 -224.258632)
			(xy 103.493316 -224.280476) (xy 103.501896 -224.306895) (xy 103.511093 -224.36167) (xy 103.511604 -224.389442)
			(xy 103.792528 -224.389442) (xy 103.793036 -224.363555) (xy 103.801135 -224.312417) (xy 103.817134 -224.263177)
			(xy 103.84064 -224.217045) (xy 103.871072 -224.175158) (xy 103.907682 -224.138548) (xy 103.949569 -224.108116)
			(xy 103.995701 -224.08461) (xy 104.044941 -224.068611) (xy 104.096079 -224.060512) (xy 104.147853 -224.060512)
			(xy 104.198991 -224.068611) (xy 104.248231 -224.08461) (xy 104.294363 -224.108116) (xy 104.33625 -224.138548)
			(xy 104.37286 -224.175158) (xy 104.403292 -224.217045) (xy 104.426798 -224.263177) (xy 104.442797 -224.312417)
			(xy 104.450896 -224.363555) (xy 104.451404 -224.389442) (xy 104.732328 -224.389442) (xy 104.732735 -224.364105)
			(xy 104.740497 -224.314028) (xy 104.755829 -224.265728) (xy 104.77837 -224.220343) (xy 104.807589 -224.17894)
			(xy 104.842799 -224.142496) (xy 104.88317 -224.111867) (xy 104.927752 -224.087776) (xy 104.975495 -224.070789)
			(xy 105.000298 -224.065592) (xy 105.023158 -224.061274) (xy 105.227882 -223.706436) (xy 105.220262 -223.684338)
			(xy 105.211631 -223.657991) (xy 105.20231 -223.603344) (xy 105.20172 -223.575626) (xy 105.202228 -223.549719)
			(xy 105.210334 -223.498542) (xy 105.226346 -223.449263) (xy 105.249869 -223.403096) (xy 105.280325 -223.361177)
			(xy 105.316963 -223.324539) (xy 105.358882 -223.294083) (xy 105.405049 -223.27056) (xy 105.454328 -223.254548)
			(xy 105.505505 -223.246442) (xy 105.557319 -223.246442) (xy 105.608496 -223.254548) (xy 105.657775 -223.27056)
			(xy 105.703942 -223.294083) (xy 105.745861 -223.324539) (xy 105.782499 -223.361177) (xy 105.812955 -223.403096)
			(xy 105.836478 -223.449263) (xy 105.85249 -223.498542) (xy 105.860596 -223.549719) (xy 105.861104 -223.575626)
			(xy 105.860687 -223.600992) (xy 105.852934 -223.651127) (xy 105.837585 -223.69948) (xy 105.815003 -223.744908)
			(xy 105.785722 -223.786336) (xy 105.750434 -223.822783) (xy 105.709975 -223.853388) (xy 105.665301 -223.877427)
			(xy 105.617469 -223.894332) (xy 105.592626 -223.899476) (xy 105.569766 -223.903794) (xy 105.365042 -224.258632)
			(xy 105.372916 -224.280476) (xy 105.38149 -224.306896) (xy 105.39069 -224.36167) (xy 105.391204 -224.389442)
			(xy 105.672128 -224.389442) (xy 105.672636 -224.363555) (xy 105.680735 -224.312417) (xy 105.696734 -224.263177)
			(xy 105.72024 -224.217045) (xy 105.750672 -224.175158) (xy 105.787282 -224.138548) (xy 105.829169 -224.108116)
			(xy 105.875301 -224.08461) (xy 105.924541 -224.068611) (xy 105.975679 -224.060512) (xy 106.027453 -224.060512)
			(xy 106.078591 -224.068611) (xy 106.127831 -224.08461) (xy 106.173963 -224.108116) (xy 106.21585 -224.138548)
			(xy 106.25246 -224.175158) (xy 106.282892 -224.217045) (xy 106.306398 -224.263177) (xy 106.322397 -224.312417)
			(xy 106.330496 -224.363555) (xy 106.331004 -224.389442) (xy 106.611928 -224.389442) (xy 106.612335 -224.364105)
			(xy 106.620097 -224.314028) (xy 106.635429 -224.265728) (xy 106.65797 -224.220343) (xy 106.687189 -224.17894)
			(xy 106.722399 -224.142496) (xy 106.76277 -224.111867) (xy 106.807352 -224.087776) (xy 106.855095 -224.070789)
			(xy 106.879898 -224.065592) (xy 106.902758 -224.061274) (xy 107.107482 -223.706436) (xy 107.099862 -223.684338)
			(xy 107.091231 -223.657991) (xy 107.08191 -223.603344) (xy 107.08132 -223.575626) (xy 107.081828 -223.549719)
			(xy 107.089934 -223.498542) (xy 107.105946 -223.449263) (xy 107.129469 -223.403096) (xy 107.159925 -223.361177)
			(xy 107.196563 -223.324539) (xy 107.238482 -223.294083) (xy 107.284649 -223.27056) (xy 107.333928 -223.254548)
			(xy 107.385105 -223.246442) (xy 107.436919 -223.246442) (xy 107.488096 -223.254548) (xy 107.537375 -223.27056)
			(xy 107.583542 -223.294083) (xy 107.625461 -223.324539) (xy 107.662099 -223.361177) (xy 107.692555 -223.403096)
			(xy 107.716078 -223.449263) (xy 107.73209 -223.498542) (xy 107.740196 -223.549719) (xy 107.740704 -223.575626)
			(xy 107.740287 -223.600992) (xy 107.732534 -223.651127) (xy 107.717185 -223.69948) (xy 107.694603 -223.744908)
			(xy 107.665322 -223.786336) (xy 107.630034 -223.822783) (xy 107.589575 -223.853388) (xy 107.544901 -223.877427)
			(xy 107.497069 -223.894332) (xy 107.472226 -223.899476) (xy 107.449366 -223.903794) (xy 107.244642 -224.258632)
			(xy 107.252516 -224.280476) (xy 107.26109 -224.306896) (xy 107.27029 -224.36167) (xy 107.270804 -224.389442)
			(xy 107.551728 -224.389442) (xy 107.552236 -224.363555) (xy 107.560335 -224.312417) (xy 107.576334 -224.263177)
			(xy 107.59984 -224.217045) (xy 107.630272 -224.175158) (xy 107.666882 -224.138548) (xy 107.708769 -224.108116)
			(xy 107.754901 -224.08461) (xy 107.804141 -224.068611) (xy 107.855279 -224.060512) (xy 107.907053 -224.060512)
			(xy 107.958191 -224.068611) (xy 108.007431 -224.08461) (xy 108.053563 -224.108116) (xy 108.09545 -224.138548)
			(xy 108.13206 -224.175158) (xy 108.162492 -224.217045) (xy 108.185998 -224.263177) (xy 108.201997 -224.312417)
			(xy 108.210096 -224.363555) (xy 108.210604 -224.389442) (xy 108.491528 -224.389442) (xy 108.491935 -224.364105)
			(xy 108.499697 -224.314028) (xy 108.515029 -224.265728) (xy 108.53757 -224.220343) (xy 108.566789 -224.17894)
			(xy 108.601999 -224.142496) (xy 108.64237 -224.111867) (xy 108.686952 -224.087776) (xy 108.734695 -224.070789)
			(xy 108.759498 -224.065592) (xy 108.782358 -224.061274) (xy 108.987082 -223.706436) (xy 108.979462 -223.684338)
			(xy 108.970831 -223.657991) (xy 108.96151 -223.603344) (xy 108.96092 -223.575626) (xy 108.961428 -223.549719)
			(xy 108.969534 -223.498542) (xy 108.985546 -223.449263) (xy 109.009069 -223.403096) (xy 109.039525 -223.361177)
			(xy 109.076163 -223.324539) (xy 109.118082 -223.294083) (xy 109.164249 -223.27056) (xy 109.213528 -223.254548)
			(xy 109.264705 -223.246442) (xy 109.316519 -223.246442) (xy 109.367696 -223.254548) (xy 109.416975 -223.27056)
			(xy 109.463142 -223.294083) (xy 109.505061 -223.324539) (xy 109.541699 -223.361177) (xy 109.572155 -223.403096)
			(xy 109.595678 -223.449263) (xy 109.61169 -223.498542) (xy 109.619796 -223.549719) (xy 109.620304 -223.575626)
			(xy 109.619887 -223.600992) (xy 109.612134 -223.651127) (xy 109.596785 -223.69948) (xy 109.574203 -223.744908)
			(xy 109.544922 -223.786336) (xy 109.509634 -223.822783) (xy 109.469175 -223.853388) (xy 109.424501 -223.877427)
			(xy 109.376669 -223.894332) (xy 109.351826 -223.899476) (xy 109.328966 -223.903794) (xy 109.124242 -224.258632)
			(xy 109.132116 -224.280476) (xy 109.14069 -224.306896) (xy 109.14989 -224.36167) (xy 109.150404 -224.389442)
			(xy 109.431328 -224.389442) (xy 109.431836 -224.363555) (xy 109.439935 -224.312417) (xy 109.455934 -224.263177)
			(xy 109.47944 -224.217045) (xy 109.509872 -224.175158) (xy 109.546482 -224.138548) (xy 109.588369 -224.108116)
			(xy 109.634501 -224.08461) (xy 109.683741 -224.068611) (xy 109.734879 -224.060512) (xy 109.786653 -224.060512)
			(xy 109.837791 -224.068611) (xy 109.887031 -224.08461) (xy 109.933163 -224.108116) (xy 109.97505 -224.138548)
			(xy 110.01166 -224.175158) (xy 110.042092 -224.217045) (xy 110.065598 -224.263177) (xy 110.081597 -224.312417)
			(xy 110.089696 -224.363555) (xy 110.090204 -224.389442) (xy 110.371128 -224.389442) (xy 110.371535 -224.364105)
			(xy 110.379297 -224.314028) (xy 110.394629 -224.265728) (xy 110.41717 -224.220343) (xy 110.446389 -224.17894)
			(xy 110.481599 -224.142496) (xy 110.52197 -224.111867) (xy 110.566552 -224.087776) (xy 110.614295 -224.070789)
			(xy 110.639098 -224.065592) (xy 110.661958 -224.061274) (xy 110.866682 -223.706436) (xy 110.859062 -223.684338)
			(xy 110.850431 -223.657991) (xy 110.84111 -223.603344) (xy 110.84052 -223.575626) (xy 110.841028 -223.549719)
			(xy 110.849134 -223.498542) (xy 110.865146 -223.449263) (xy 110.888669 -223.403096) (xy 110.919125 -223.361177)
			(xy 110.955763 -223.324539) (xy 110.997682 -223.294083) (xy 111.043849 -223.27056) (xy 111.093128 -223.254548)
			(xy 111.144305 -223.246442) (xy 111.196119 -223.246442) (xy 111.247296 -223.254548) (xy 111.296575 -223.27056)
			(xy 111.342742 -223.294083) (xy 111.384661 -223.324539) (xy 111.421299 -223.361177) (xy 111.451755 -223.403096)
			(xy 111.475278 -223.449263) (xy 111.49129 -223.498542) (xy 111.499396 -223.549719) (xy 111.499904 -223.575626)
			(xy 111.499487 -223.600992) (xy 111.491734 -223.651127) (xy 111.476385 -223.69948) (xy 111.453803 -223.744908)
			(xy 111.424522 -223.786336) (xy 111.389234 -223.822783) (xy 111.348775 -223.853388) (xy 111.304101 -223.877427)
			(xy 111.256269 -223.894332) (xy 111.231426 -223.899476) (xy 111.208566 -223.903794) (xy 111.003842 -224.258632)
			(xy 111.011716 -224.280476) (xy 111.02029 -224.306896) (xy 111.02949 -224.36167) (xy 111.030004 -224.389442)
			(xy 111.310928 -224.389442) (xy 111.311436 -224.363555) (xy 111.319535 -224.312417) (xy 111.335534 -224.263177)
			(xy 111.35904 -224.217045) (xy 111.389472 -224.175158) (xy 111.426082 -224.138548) (xy 111.467969 -224.108116)
			(xy 111.514101 -224.08461) (xy 111.563341 -224.068611) (xy 111.614479 -224.060512) (xy 111.666253 -224.060512)
			(xy 111.717391 -224.068611) (xy 111.766631 -224.08461) (xy 111.812763 -224.108116) (xy 111.85465 -224.138548)
			(xy 111.89126 -224.175158) (xy 111.921692 -224.217045) (xy 111.945198 -224.263177) (xy 111.961197 -224.312417)
			(xy 111.969296 -224.363555) (xy 111.969804 -224.389442) (xy 112.250728 -224.389442) (xy 112.251135 -224.364105)
			(xy 112.258897 -224.314028) (xy 112.274229 -224.265728) (xy 112.29677 -224.220343) (xy 112.325989 -224.17894)
			(xy 112.361199 -224.142496) (xy 112.40157 -224.111867) (xy 112.446152 -224.087776) (xy 112.493895 -224.070789)
			(xy 112.518698 -224.065592) (xy 112.541558 -224.061274) (xy 112.746282 -223.706436) (xy 112.738662 -223.684338)
			(xy 112.730031 -223.657991) (xy 112.72071 -223.603344) (xy 112.72012 -223.575626) (xy 112.720628 -223.549719)
			(xy 112.728734 -223.498542) (xy 112.744746 -223.449263) (xy 112.768269 -223.403096) (xy 112.798725 -223.361177)
			(xy 112.835363 -223.324539) (xy 112.877282 -223.294083) (xy 112.923449 -223.27056) (xy 112.972728 -223.254548)
			(xy 113.023905 -223.246442) (xy 113.075719 -223.246442) (xy 113.126896 -223.254548) (xy 113.176175 -223.27056)
			(xy 113.222342 -223.294083) (xy 113.264261 -223.324539) (xy 113.300899 -223.361177) (xy 113.331355 -223.403096)
			(xy 113.354878 -223.449263) (xy 113.37089 -223.498542) (xy 113.378996 -223.549719) (xy 113.379504 -223.575626)
			(xy 113.379087 -223.600992) (xy 113.371334 -223.651127) (xy 113.355985 -223.69948) (xy 113.333403 -223.744908)
			(xy 113.304122 -223.786336) (xy 113.268834 -223.822783) (xy 113.228375 -223.853388) (xy 113.183701 -223.877427)
			(xy 113.135869 -223.894332) (xy 113.111026 -223.899476) (xy 113.088166 -223.903794) (xy 112.883442 -224.258632)
			(xy 112.891316 -224.280476) (xy 112.89989 -224.306896) (xy 112.90909 -224.36167) (xy 112.909604 -224.389442)
			(xy 113.190528 -224.389442) (xy 113.191036 -224.363555) (xy 113.199135 -224.312417) (xy 113.215134 -224.263177)
			(xy 113.23864 -224.217045) (xy 113.269072 -224.175158) (xy 113.305682 -224.138548) (xy 113.347569 -224.108116)
			(xy 113.393701 -224.08461) (xy 113.442941 -224.068611) (xy 113.494079 -224.060512) (xy 113.545853 -224.060512)
			(xy 113.596991 -224.068611) (xy 113.646231 -224.08461) (xy 113.692363 -224.108116) (xy 113.73425 -224.138548)
			(xy 113.77086 -224.175158) (xy 113.801292 -224.217045) (xy 113.824798 -224.263177) (xy 113.840797 -224.312417)
			(xy 113.848896 -224.363555) (xy 113.849404 -224.389442) (xy 113.84886 -224.417149) (xy 113.839674 -224.471796)
			(xy 113.831116 -224.498154) (xy 113.823242 -224.520252) (xy 114.02822 -224.87509) (xy 114.05108 -224.879408)
			(xy 114.075909 -224.884542) (xy 114.123688 -224.901501) (xy 114.168308 -224.925578) (xy 114.208714 -224.956202)
			(xy 114.243954 -224.992654) (xy 114.273197 -225.034071) (xy 114.295752 -225.079478) (xy 114.311088 -225.127804)
			(xy 114.318843 -225.177908) (xy 114.319304 -225.203258) (xy 114.318796 -225.229165) (xy 114.31069 -225.280342)
			(xy 114.294678 -225.329621) (xy 114.271155 -225.375788) (xy 114.240699 -225.417707) (xy 114.204061 -225.454345)
			(xy 114.162142 -225.484801) (xy 114.115975 -225.508324) (xy 114.066696 -225.524336) (xy 114.015519 -225.532442)
			(xy 113.963705 -225.532442) (xy 113.912528 -225.524336) (xy 113.863249 -225.508324) (xy 113.817082 -225.484801)
			(xy 113.775163 -225.454345) (xy 113.738525 -225.417707) (xy 113.708069 -225.375788) (xy 113.684546 -225.329621)
			(xy 113.668534 -225.280342) (xy 113.660428 -225.229165) (xy 113.65992 -225.203258) (xy 113.660527 -225.175541)
			(xy 113.669842 -225.120895) (xy 113.678462 -225.094546) (xy 113.686336 -225.072448) (xy 113.481358 -224.71761)
			(xy 113.458498 -224.713292) (xy 113.433685 -224.708145) (xy 113.385943 -224.691153) (xy 113.341363 -224.667056)
			(xy 113.300996 -224.63642) (xy 113.265793 -224.599968) (xy 113.236582 -224.558558) (xy 113.214052 -224.513166)
			(xy 113.198734 -224.46486) (xy 113.190988 -224.41478) (xy 113.190528 -224.389442) (xy 112.909604 -224.389442)
			(xy 112.909096 -224.415329) (xy 112.900997 -224.466467) (xy 112.884998 -224.515707) (xy 112.861492 -224.561839)
			(xy 112.83106 -224.603726) (xy 112.79445 -224.640336) (xy 112.752563 -224.670768) (xy 112.706431 -224.694274)
			(xy 112.657191 -224.710273) (xy 112.606053 -224.718372) (xy 112.554279 -224.718372) (xy 112.503141 -224.710273)
			(xy 112.453901 -224.694274) (xy 112.407769 -224.670768) (xy 112.365882 -224.640336) (xy 112.329272 -224.603726)
			(xy 112.29884 -224.561839) (xy 112.275334 -224.515707) (xy 112.259335 -224.466467) (xy 112.251236 -224.415329)
			(xy 112.250728 -224.389442) (xy 111.969804 -224.389442) (xy 111.96926 -224.417149) (xy 111.960074 -224.471796)
			(xy 111.951516 -224.498154) (xy 111.943642 -224.520252) (xy 112.14862 -224.87509) (xy 112.17148 -224.879408)
			(xy 112.196309 -224.884542) (xy 112.244088 -224.901501) (xy 112.288708 -224.925578) (xy 112.329114 -224.956202)
			(xy 112.364354 -224.992654) (xy 112.393597 -225.034071) (xy 112.416152 -225.079478) (xy 112.431488 -225.127804)
			(xy 112.439243 -225.177908) (xy 112.439704 -225.203258) (xy 112.439196 -225.229165) (xy 112.43109 -225.280342)
			(xy 112.415078 -225.329621) (xy 112.391555 -225.375788) (xy 112.361099 -225.417707) (xy 112.324461 -225.454345)
			(xy 112.282542 -225.484801) (xy 112.236375 -225.508324) (xy 112.187096 -225.524336) (xy 112.135919 -225.532442)
			(xy 112.084105 -225.532442) (xy 112.032928 -225.524336) (xy 111.983649 -225.508324) (xy 111.937482 -225.484801)
			(xy 111.895563 -225.454345) (xy 111.858925 -225.417707) (xy 111.828469 -225.375788) (xy 111.804946 -225.329621)
			(xy 111.788934 -225.280342) (xy 111.780828 -225.229165) (xy 111.78032 -225.203258) (xy 111.780927 -225.175541)
			(xy 111.790242 -225.120895) (xy 111.798862 -225.094546) (xy 111.806736 -225.072448) (xy 111.601758 -224.71761)
			(xy 111.578898 -224.713292) (xy 111.554085 -224.708145) (xy 111.506343 -224.691153) (xy 111.461763 -224.667056)
			(xy 111.421396 -224.63642) (xy 111.386193 -224.599968) (xy 111.356982 -224.558558) (xy 111.334452 -224.513166)
			(xy 111.319134 -224.46486) (xy 111.311388 -224.41478) (xy 111.310928 -224.389442) (xy 111.030004 -224.389442)
			(xy 111.029496 -224.415329) (xy 111.021397 -224.466467) (xy 111.005398 -224.515707) (xy 110.981892 -224.561839)
			(xy 110.95146 -224.603726) (xy 110.91485 -224.640336) (xy 110.872963 -224.670768) (xy 110.826831 -224.694274)
			(xy 110.777591 -224.710273) (xy 110.726453 -224.718372) (xy 110.674679 -224.718372) (xy 110.623541 -224.710273)
			(xy 110.574301 -224.694274) (xy 110.528169 -224.670768) (xy 110.486282 -224.640336) (xy 110.449672 -224.603726)
			(xy 110.41924 -224.561839) (xy 110.395734 -224.515707) (xy 110.379735 -224.466467) (xy 110.371636 -224.415329)
			(xy 110.371128 -224.389442) (xy 110.090204 -224.389442) (xy 110.08966 -224.417149) (xy 110.080474 -224.471796)
			(xy 110.071916 -224.498154) (xy 110.064042 -224.520252) (xy 110.26902 -224.87509) (xy 110.29188 -224.879408)
			(xy 110.316709 -224.884542) (xy 110.364488 -224.901501) (xy 110.409108 -224.925578) (xy 110.449514 -224.956202)
			(xy 110.484754 -224.992654) (xy 110.513997 -225.034071) (xy 110.536552 -225.079478) (xy 110.551888 -225.127804)
			(xy 110.559643 -225.177908) (xy 110.560104 -225.203258) (xy 110.559596 -225.229165) (xy 110.55149 -225.280342)
			(xy 110.535478 -225.329621) (xy 110.511955 -225.375788) (xy 110.481499 -225.417707) (xy 110.444861 -225.454345)
			(xy 110.402942 -225.484801) (xy 110.356775 -225.508324) (xy 110.307496 -225.524336) (xy 110.256319 -225.532442)
			(xy 110.204505 -225.532442) (xy 110.153328 -225.524336) (xy 110.104049 -225.508324) (xy 110.057882 -225.484801)
			(xy 110.015963 -225.454345) (xy 109.979325 -225.417707) (xy 109.948869 -225.375788) (xy 109.925346 -225.329621)
			(xy 109.909334 -225.280342) (xy 109.901228 -225.229165) (xy 109.90072 -225.203258) (xy 109.901327 -225.175541)
			(xy 109.910642 -225.120895) (xy 109.919262 -225.094546) (xy 109.927136 -225.072448) (xy 109.722158 -224.71761)
			(xy 109.699298 -224.713292) (xy 109.674485 -224.708145) (xy 109.626743 -224.691153) (xy 109.582163 -224.667056)
			(xy 109.541796 -224.63642) (xy 109.506593 -224.599968) (xy 109.477382 -224.558558) (xy 109.454852 -224.513166)
			(xy 109.439534 -224.46486) (xy 109.431788 -224.41478) (xy 109.431328 -224.389442) (xy 109.150404 -224.389442)
			(xy 109.149896 -224.415329) (xy 109.141797 -224.466467) (xy 109.125798 -224.515707) (xy 109.102292 -224.561839)
			(xy 109.07186 -224.603726) (xy 109.03525 -224.640336) (xy 108.993363 -224.670768) (xy 108.947231 -224.694274)
			(xy 108.897991 -224.710273) (xy 108.846853 -224.718372) (xy 108.795079 -224.718372) (xy 108.743941 -224.710273)
			(xy 108.694701 -224.694274) (xy 108.648569 -224.670768) (xy 108.606682 -224.640336) (xy 108.570072 -224.603726)
			(xy 108.53964 -224.561839) (xy 108.516134 -224.515707) (xy 108.500135 -224.466467) (xy 108.492036 -224.415329)
			(xy 108.491528 -224.389442) (xy 108.210604 -224.389442) (xy 108.21006 -224.417149) (xy 108.200874 -224.471796)
			(xy 108.192316 -224.498154) (xy 108.184442 -224.520252) (xy 108.38942 -224.87509) (xy 108.41228 -224.879408)
			(xy 108.437109 -224.884542) (xy 108.484888 -224.901501) (xy 108.529508 -224.925578) (xy 108.569914 -224.956202)
			(xy 108.605154 -224.992654) (xy 108.634397 -225.034071) (xy 108.656952 -225.079478) (xy 108.672288 -225.127804)
			(xy 108.680043 -225.177908) (xy 108.680504 -225.203258) (xy 108.679996 -225.229165) (xy 108.67189 -225.280342)
			(xy 108.655878 -225.329621) (xy 108.632355 -225.375788) (xy 108.601899 -225.417707) (xy 108.565261 -225.454345)
			(xy 108.523342 -225.484801) (xy 108.477175 -225.508324) (xy 108.427896 -225.524336) (xy 108.376719 -225.532442)
			(xy 108.324905 -225.532442) (xy 108.273728 -225.524336) (xy 108.224449 -225.508324) (xy 108.178282 -225.484801)
			(xy 108.136363 -225.454345) (xy 108.099725 -225.417707) (xy 108.069269 -225.375788) (xy 108.045746 -225.329621)
			(xy 108.029734 -225.280342) (xy 108.021628 -225.229165) (xy 108.02112 -225.203258) (xy 108.021727 -225.175541)
			(xy 108.031042 -225.120895) (xy 108.039662 -225.094546) (xy 108.047536 -225.072448) (xy 107.842558 -224.71761)
			(xy 107.819698 -224.713292) (xy 107.794885 -224.708145) (xy 107.747143 -224.691153) (xy 107.702563 -224.667056)
			(xy 107.662196 -224.63642) (xy 107.626993 -224.599968) (xy 107.597782 -224.558558) (xy 107.575252 -224.513166)
			(xy 107.559934 -224.46486) (xy 107.552188 -224.41478) (xy 107.551728 -224.389442) (xy 107.270804 -224.389442)
			(xy 107.270296 -224.415329) (xy 107.262197 -224.466467) (xy 107.246198 -224.515707) (xy 107.222692 -224.561839)
			(xy 107.19226 -224.603726) (xy 107.15565 -224.640336) (xy 107.113763 -224.670768) (xy 107.067631 -224.694274)
			(xy 107.018391 -224.710273) (xy 106.967253 -224.718372) (xy 106.915479 -224.718372) (xy 106.864341 -224.710273)
			(xy 106.815101 -224.694274) (xy 106.768969 -224.670768) (xy 106.727082 -224.640336) (xy 106.690472 -224.603726)
			(xy 106.66004 -224.561839) (xy 106.636534 -224.515707) (xy 106.620535 -224.466467) (xy 106.612436 -224.415329)
			(xy 106.611928 -224.389442) (xy 106.331004 -224.389442) (xy 106.33046 -224.417149) (xy 106.321274 -224.471796)
			(xy 106.312716 -224.498154) (xy 106.304842 -224.520252) (xy 106.50982 -224.87509) (xy 106.53268 -224.879408)
			(xy 106.557509 -224.884542) (xy 106.605288 -224.901501) (xy 106.649908 -224.925578) (xy 106.690314 -224.956202)
			(xy 106.725554 -224.992654) (xy 106.754797 -225.034071) (xy 106.777352 -225.079478) (xy 106.792688 -225.127804)
			(xy 106.800443 -225.177908) (xy 106.800904 -225.203258) (xy 106.800396 -225.229165) (xy 106.79229 -225.280342)
			(xy 106.776278 -225.329621) (xy 106.752755 -225.375788) (xy 106.722299 -225.417707) (xy 106.685661 -225.454345)
			(xy 106.643742 -225.484801) (xy 106.597575 -225.508324) (xy 106.548296 -225.524336) (xy 106.497119 -225.532442)
			(xy 106.445305 -225.532442) (xy 106.394128 -225.524336) (xy 106.344849 -225.508324) (xy 106.298682 -225.484801)
			(xy 106.256763 -225.454345) (xy 106.220125 -225.417707) (xy 106.189669 -225.375788) (xy 106.166146 -225.329621)
			(xy 106.150134 -225.280342) (xy 106.142028 -225.229165) (xy 106.14152 -225.203258) (xy 106.142127 -225.175541)
			(xy 106.151442 -225.120895) (xy 106.160062 -225.094546) (xy 106.167936 -225.072448) (xy 105.962958 -224.71761)
			(xy 105.940098 -224.713292) (xy 105.915285 -224.708145) (xy 105.867543 -224.691153) (xy 105.822963 -224.667056)
			(xy 105.782596 -224.63642) (xy 105.747393 -224.599968) (xy 105.718182 -224.558558) (xy 105.695652 -224.513166)
			(xy 105.680334 -224.46486) (xy 105.672588 -224.41478) (xy 105.672128 -224.389442) (xy 105.391204 -224.389442)
			(xy 105.390696 -224.415329) (xy 105.382597 -224.466467) (xy 105.366598 -224.515707) (xy 105.343092 -224.561839)
			(xy 105.31266 -224.603726) (xy 105.27605 -224.640336) (xy 105.234163 -224.670768) (xy 105.188031 -224.694274)
			(xy 105.138791 -224.710273) (xy 105.087653 -224.718372) (xy 105.035879 -224.718372) (xy 104.984741 -224.710273)
			(xy 104.935501 -224.694274) (xy 104.889369 -224.670768) (xy 104.847482 -224.640336) (xy 104.810872 -224.603726)
			(xy 104.78044 -224.561839) (xy 104.756934 -224.515707) (xy 104.740935 -224.466467) (xy 104.732836 -224.415329)
			(xy 104.732328 -224.389442) (xy 104.451404 -224.389442) (xy 104.45086 -224.417149) (xy 104.441674 -224.471796)
			(xy 104.433116 -224.498154) (xy 104.425242 -224.520252) (xy 104.63022 -224.87509) (xy 104.65308 -224.879408)
			(xy 104.677909 -224.884542) (xy 104.725688 -224.901501) (xy 104.770308 -224.925578) (xy 104.810714 -224.956202)
			(xy 104.845954 -224.992654) (xy 104.875197 -225.034071) (xy 104.897752 -225.079478) (xy 104.913088 -225.127804)
			(xy 104.920843 -225.177908) (xy 104.921304 -225.203258) (xy 104.920796 -225.229165) (xy 104.91269 -225.280342)
			(xy 104.896678 -225.329621) (xy 104.873155 -225.375788) (xy 104.842699 -225.417707) (xy 104.806061 -225.454345)
			(xy 104.764142 -225.484801) (xy 104.717975 -225.508324) (xy 104.668696 -225.524336) (xy 104.617519 -225.532442)
			(xy 104.565705 -225.532442) (xy 104.514528 -225.524336) (xy 104.465249 -225.508324) (xy 104.419082 -225.484801)
			(xy 104.377163 -225.454345) (xy 104.340525 -225.417707) (xy 104.310069 -225.375788) (xy 104.286546 -225.329621)
			(xy 104.270534 -225.280342) (xy 104.262428 -225.229165) (xy 104.26192 -225.203258) (xy 104.262527 -225.175541)
			(xy 104.271842 -225.120895) (xy 104.280462 -225.094546) (xy 104.288336 -225.072448) (xy 104.083358 -224.71761)
			(xy 104.060498 -224.713292) (xy 104.035685 -224.708145) (xy 103.987943 -224.691153) (xy 103.943363 -224.667056)
			(xy 103.902996 -224.63642) (xy 103.867793 -224.599968) (xy 103.838582 -224.558558) (xy 103.816052 -224.513166)
			(xy 103.800734 -224.46486) (xy 103.792988 -224.41478) (xy 103.792528 -224.389442) (xy 103.511604 -224.389442)
			(xy 103.511093 -224.415326) (xy 103.502988 -224.466457) (xy 103.486985 -224.515689) (xy 103.463477 -224.561813)
			(xy 103.433043 -224.603691) (xy 103.396433 -224.640293) (xy 103.354548 -224.670717) (xy 103.308419 -224.694214)
			(xy 103.259183 -224.710206) (xy 103.20805 -224.718299) (xy 103.182166 -224.71888) (xy 103.15432 -224.718321)
			(xy 103.099415 -224.709003) (xy 103.072946 -224.700338) (xy 103.059699 -224.6962) (xy 103.032016 -224.694428)
			(xy 103.004878 -224.700177) (xy 102.980292 -224.713023) (xy 102.960074 -224.732017) (xy 102.945719 -224.755753)
			(xy 102.938287 -224.782479) (xy 102.937818 -224.79635) (xy 102.937818 -224.963228) (xy 102.957067 -224.982044)
			(xy 102.989786 -225.024781) (xy 103.015124 -225.072268) (xy 103.032408 -225.123241) (xy 103.041178 -225.176346)
			(xy 103.041704 -225.203258) (xy 103.041151 -225.230168) (xy 103.032373 -225.283268) (xy 103.015093 -225.334239)
			(xy 102.989768 -225.381729) (xy 102.95707 -225.424479) (xy 102.937818 -225.443288) (xy 102.937818 -226.592892)
			(xy 102.956808 -226.611628) (xy 102.989061 -226.654116) (xy 103.014022 -226.701259) (xy 103.031035 -226.751816)
			(xy 103.039652 -226.804459) (xy 103.039647 -226.857802) (xy 103.03102 -226.910443) (xy 103.013998 -226.960997)
			(xy 102.989028 -227.008135) (xy 102.956767 -227.050617) (xy 102.937818 -227.069396) (xy 102.937818 -228.220778)
			(xy 102.956809 -228.239514) (xy 102.989064 -228.282002) (xy 103.014028 -228.329146) (xy 103.031043 -228.379704)
			(xy 103.039662 -228.432348) (xy 103.039658 -228.485693) (xy 103.031033 -228.538336) (xy 103.014011 -228.588892)
			(xy 102.989042 -228.636033) (xy 102.956781 -228.678517) (xy 102.937818 -228.697282) (xy 102.937818 -228.98735)
			(xy 102.937202 -229.012305) (xy 102.927457 -229.061254) (xy 102.90835 -229.107362) (xy 102.880617 -229.148857)
			(xy 102.863396 -229.166928) (xy 102.074726 -229.955598) (xy 102.084378 -229.985316) (xy 102.091884 -230.009976)
			(xy 102.099921 -230.060889) (xy 102.10038 -230.086662) (xy 102.099904 -230.112454) (xy 102.09184 -230.163404)
			(xy 102.075904 -230.212464) (xy 102.05249 -230.258428) (xy 102.022173 -230.300163) (xy 101.985701 -230.336641)
			(xy 101.943971 -230.366964) (xy 101.898011 -230.390385) (xy 101.848952 -230.406328) (xy 101.798004 -230.4144)
			(xy 101.772212 -230.41483) (xy 101.746443 -230.414325) (xy 101.695536 -230.406291) (xy 101.670866 -230.398828)
			(xy 101.641148 -230.389176) (xy 100.199698 -231.830626) (xy 100.195888 -231.840024) (xy 100.18557 -231.863696)
			(xy 100.158596 -231.907728) (xy 100.12506 -231.946993) (xy 100.08579 -231.980523) (xy 100.041754 -232.007491)
			(xy 100.018088 -232.017824) (xy 100.00869 -232.021634) (xy 99.692714 -232.33761) (xy 99.711002 -232.370884)
			(xy 99.723639 -232.395188) (xy 99.741535 -232.446956) (xy 99.750595 -232.500976) (xy 99.751134 -232.528364)
			(xy 99.750657 -232.554155) (xy 99.742592 -232.605101) (xy 99.726656 -232.654158) (xy 99.703241 -232.700118)
			(xy 99.672924 -232.741849) (xy 99.636451 -232.778322) (xy 99.59472 -232.80864) (xy 99.54876 -232.832056)
			(xy 99.499703 -232.847992) (xy 99.448756 -232.856057) (xy 99.422966 -232.856532) (xy 99.395578 -232.856004)
			(xy 99.341556 -232.846946) (xy 99.28979 -232.829039) (xy 99.265486 -232.8164) (xy 99.232212 -232.798112)
			(xy 97.872042 -234.158282) (xy 97.870772 -234.177332) (xy 97.868559 -234.203542) (xy 97.856839 -234.254816)
			(xy 97.83709 -234.303563) (xy 97.809815 -234.348534) (xy 97.775714 -234.388578) (xy 97.735662 -234.422667)
			(xy 97.690683 -234.44993) (xy 97.64193 -234.469666) (xy 97.590653 -234.481371) (xy 97.564448 -234.483656)
			(xy 97.545398 -234.484926) (xy 96.986598 -235.043726) (xy 96.986598 -253.737618) (xy 96.999628 -253.757945)
			(xy 97.020226 -253.801613) (xy 97.034209 -253.847826) (xy 97.041274 -253.895589) (xy 97.04127 -253.943871)
			(xy 97.034196 -253.991632) (xy 97.020205 -254.037843) (xy 96.999598 -254.081507) (xy 96.986598 -254.101854)
			(xy 96.986598 -255.365504) (xy 96.999629 -255.385831) (xy 97.020229 -255.429499) (xy 97.034214 -255.475713)
			(xy 97.041281 -255.523477) (xy 97.041278 -255.57176) (xy 97.034206 -255.619523) (xy 97.020216 -255.665735)
			(xy 96.999611 -255.709401) (xy 96.986598 -255.72974) (xy 96.986598 -256.993136) (xy 96.999634 -257.013463)
			(xy 97.020244 -257.057133) (xy 97.034238 -257.10335) (xy 97.041314 -257.151117) (xy 97.04132 -257.199406)
			(xy 97.034255 -257.247176) (xy 97.020272 -257.293395) (xy 96.999672 -257.33707) (xy 96.986598 -257.357372)
			(xy 96.986598 -258.621022) (xy 96.999628 -258.641349) (xy 97.020225 -258.685017) (xy 97.034207 -258.73123)
			(xy 97.041272 -258.778992) (xy 97.041267 -258.827274) (xy 97.034193 -258.875035) (xy 97.020202 -258.921245)
			(xy 96.999595 -258.964909) (xy 96.986598 -258.985258) (xy 96.986598 -260.249416) (xy 96.99952 -260.269679)
			(xy 97.019939 -260.313183) (xy 97.033801 -260.359199) (xy 97.040808 -260.406743) (xy 97.041208 -260.430772)
			(xy 97.0407 -260.44906) (xy 97.03943 -260.471666) (xy 97.391474 -260.82371) (xy 102.427786 -260.82371)
			(xy 102.567232 -260.684264) (xy 102.571042 -260.675882) (xy 102.581151 -260.654793) (xy 102.606454 -260.615463)
			(xy 102.637083 -260.580123) (xy 102.672418 -260.549487) (xy 102.711744 -260.524177) (xy 102.73284 -260.514084)
			(xy 102.741222 -260.510274) (xy 102.837742 -260.413754) (xy 102.837742 -260.025896) (xy 102.79761 -260.01726)
			(xy 102.772051 -260.01125) (xy 102.723126 -259.992206) (xy 102.677859 -259.965613) (xy 102.637404 -259.932149)
			(xy 102.602796 -259.892669) (xy 102.574918 -259.848182) (xy 102.55448 -259.799822) (xy 102.542006 -259.748825)
			(xy 102.537813 -259.696491) (xy 102.542009 -259.644158) (xy 102.554486 -259.593161) (xy 102.574926 -259.544802)
			(xy 102.602807 -259.500316) (xy 102.637417 -259.460839) (xy 102.677873 -259.427377) (xy 102.723142 -259.400786)
			(xy 102.772068 -259.381745) (xy 102.79761 -259.375656) (xy 102.837742 -259.36702) (xy 102.837742 -258.564126)
			(xy 102.619302 -258.345686) (xy 102.602037 -258.327647) (xy 102.57427 -258.286155) (xy 102.555148 -258.240037)
			(xy 102.545408 -258.191071) (xy 102.54488 -258.166108) (xy 102.54488 -257.42773) (xy 102.545498 -257.402776)
			(xy 102.555247 -257.353829) (xy 102.574355 -257.307723) (xy 102.60209 -257.266231) (xy 102.619302 -257.248152)
			(xy 102.837742 -257.029712) (xy 102.837742 -256.135124) (xy 102.805738 -256.122424) (xy 102.783232 -256.112918)
			(xy 102.74108 -256.088222) (xy 102.70305 -256.057556) (xy 102.669981 -256.021597) (xy 102.642601 -255.981137)
			(xy 102.621515 -255.937068) (xy 102.607188 -255.890363) (xy 102.599935 -255.842051) (xy 102.59949 -255.817624)
			(xy 102.599937 -255.792916) (xy 102.607348 -255.744058) (xy 102.622007 -255.696866) (xy 102.643581 -255.652408)
			(xy 102.671582 -255.611691) (xy 102.688136 -255.593342) (xy 102.698182 -255.581835) (xy 102.711503 -255.554362)
			(xy 102.716117 -255.524181) (xy 102.71161 -255.493983) (xy 102.698385 -255.466463) (xy 102.68839 -255.454912)
			(xy 102.671952 -255.436601) (xy 102.644188 -255.395976) (xy 102.622801 -255.351661) (xy 102.608272 -255.304649)
			(xy 102.600925 -255.255995) (xy 102.600506 -255.231392) (xy 102.600944 -255.207022) (xy 102.608144 -255.158817)
			(xy 102.622397 -255.112207) (xy 102.643391 -255.068221) (xy 102.670663 -255.027825) (xy 102.703612 -254.99191)
			(xy 102.741514 -254.961266) (xy 102.783533 -254.936568) (xy 102.805992 -254.9271) (xy 102.837742 -254.914146)
			(xy 102.837742 -253.123954) (xy 102.80142 -253.113286) (xy 102.77642 -253.105232) (xy 102.72917 -253.0823)
			(xy 102.686171 -253.052142) (xy 102.648518 -253.015527) (xy 102.617171 -252.973387) (xy 102.592928 -252.926797)
			(xy 102.576408 -252.876942) (xy 102.56803 -252.825094) (xy 102.567486 -252.798834) (xy 102.567946 -252.774306)
			(xy 102.575253 -252.725796) (xy 102.589695 -252.678914) (xy 102.610949 -252.6347) (xy 102.638544 -252.594141)
			(xy 102.654862 -252.575822) (xy 102.664806 -252.564276) (xy 102.678027 -252.536839) (xy 102.682573 -252.506725)
			(xy 102.678042 -252.476609) (xy 102.664835 -252.449166) (xy 102.654862 -252.437646) (xy 102.638527 -252.41934)
			(xy 102.610919 -252.378785) (xy 102.589662 -252.33457) (xy 102.57523 -252.28768) (xy 102.567945 -252.239164)
			(xy 102.567486 -252.214634) (xy 102.568 -252.188371) (xy 102.57636 -252.136514) (xy 102.592873 -252.086651)
			(xy 102.617116 -252.040054) (xy 102.648471 -251.997913) (xy 102.686138 -251.961304) (xy 102.729154 -251.931161)
			(xy 102.776422 -251.908254) (xy 102.80142 -251.900182) (xy 102.837742 -251.889514) (xy 102.837742 -248.50471)
			(xy 102.838322 -248.479753) (xy 102.848077 -248.430802) (xy 102.867195 -248.384695) (xy 102.894941 -248.343203)
			(xy 102.912164 -248.325132) (xy 103.394764 -247.842532) (xy 103.412806 -247.825275) (xy 103.454301 -247.797524)
			(xy 103.500419 -247.778416) (xy 103.549382 -247.768689) (xy 103.574342 -247.76811) (xy 104.383586 -247.76811)
			(xy 104.869742 -247.281954) (xy 104.869742 -246.298466) (xy 104.688386 -246.11711) (xy 103.574342 -246.11711)
			(xy 103.549388 -246.116493) (xy 103.500439 -246.106746) (xy 103.454333 -246.087638) (xy 103.412839 -246.059904)
			(xy 103.394764 -246.042688) (xy 103.002842 -245.650766) (xy 102.97541 -245.657116) (xy 102.957065 -245.661124)
			(xy 102.919763 -245.665452) (xy 102.900988 -245.665752) (xy 102.875199 -245.665272) (xy 102.824258 -245.657201)
			(xy 102.775205 -245.641261) (xy 102.729251 -245.617844) (xy 102.687525 -245.587526) (xy 102.651056 -245.551054)
			(xy 102.620741 -245.509325) (xy 102.597328 -245.463369) (xy 102.581392 -245.414315) (xy 102.573326 -245.363373)
			(xy 102.57282 -245.337584) (xy 102.573277 -245.313055) (xy 102.580578 -245.264542) (xy 102.595015 -245.217656)
			(xy 102.616266 -245.173439) (xy 102.64386 -245.132875) (xy 102.660196 -245.114572) (xy 102.670187 -245.103062)
			(xy 102.68341 -245.075614) (xy 102.68795 -245.045488) (xy 102.683403 -245.015363) (xy 102.670174 -244.987919)
			(xy 102.660196 -244.976396) (xy 102.643861 -244.95809) (xy 102.616252 -244.917535) (xy 102.594993 -244.873319)
			(xy 102.580556 -244.826431) (xy 102.573266 -244.777915) (xy 102.57282 -244.753384) (xy 102.57334 -244.727103)
			(xy 102.581724 -244.675213) (xy 102.598273 -244.625324) (xy 102.622565 -244.578711) (xy 102.653978 -244.536568)
			(xy 102.691708 -244.499972) (xy 102.734791 -244.469861) (xy 102.75824 -244.457982) (xy 102.786942 -244.444012)
			(xy 102.786942 -241.235992) (xy 102.759002 -241.222022) (xy 102.73611 -241.209916) (xy 102.694124 -241.179608)
			(xy 102.657412 -241.143089) (xy 102.626885 -241.101262) (xy 102.603298 -241.055164) (xy 102.587235 -241.005936)
			(xy 102.579094 -240.954797) (xy 102.578662 -240.928906) (xy 102.579117 -240.904376) (xy 102.586414 -240.855861)
			(xy 102.600847 -240.808971) (xy 102.622093 -240.764749) (xy 102.649682 -240.72418) (xy 102.666038 -240.705894)
			(xy 102.676029 -240.694382) (xy 102.689252 -240.666932) (xy 102.693796 -240.636804) (xy 102.689255 -240.606676)
			(xy 102.676034 -240.579225) (xy 102.666038 -240.567718) (xy 102.6497 -240.549413) (xy 102.622085 -240.50886)
			(xy 102.60082 -240.464645) (xy 102.586378 -240.417755) (xy 102.579083 -240.369238) (xy 102.578662 -240.344706)
			(xy 102.579148 -240.318817) (xy 102.587274 -240.26768) (xy 102.603325 -240.218453) (xy 102.626904 -240.172354)
			(xy 102.657426 -240.130528) (xy 102.694134 -240.094011) (xy 102.736119 -240.063708) (xy 102.759002 -240.05159)
			(xy 102.786942 -240.03762) (xy 102.786942 -239.5982) (xy 102.765042 -239.585753) (xy 102.724972 -239.555232)
			(xy 102.690029 -239.518953) (xy 102.661033 -239.477765) (xy 102.638664 -239.432634) (xy 102.623445 -239.384618)
			(xy 102.615733 -239.334841) (xy 102.615238 -239.309656) (xy 102.615747 -239.283871) (xy 102.623821 -239.232936)
			(xy 102.639762 -239.183892) (xy 102.663179 -239.137944) (xy 102.693495 -239.096226) (xy 102.729964 -239.059763)
			(xy 102.771687 -239.029453) (xy 102.817638 -239.006043) (xy 102.866685 -238.990109) (xy 102.917621 -238.982043)
			(xy 102.943406 -238.981488) (xy 102.964779 -238.981814) (xy 103.007166 -238.987334) (xy 103.048476 -238.998318)
			(xy 103.068374 -239.006126) (xy 103.099616 -239.01908) (xy 104.207564 -237.911132) (xy 104.225606 -237.893875)
			(xy 104.267101 -237.866124) (xy 104.313219 -237.847016) (xy 104.362182 -237.837289) (xy 104.387142 -237.83671)
			(xy 108.350558 -237.83671) (xy 108.35894 -237.796324) (xy 108.364842 -237.770617) (xy 108.383733 -237.721375)
			(xy 108.410256 -237.675787) (xy 108.443727 -237.635028) (xy 108.483285 -237.600145) (xy 108.527912 -237.572036)
			(xy 108.57646 -237.551426) (xy 108.627678 -237.538843) (xy 108.68025 -237.534613) (xy 108.732822 -237.538843)
			(xy 108.78404 -237.551426) (xy 108.832588 -237.572036) (xy 108.877215 -237.600145) (xy 108.916773 -237.635028)
			(xy 108.950244 -237.675787) (xy 108.976767 -237.721375) (xy 108.995658 -237.770617) (xy 109.00156 -237.796324)
			(xy 109.009942 -237.83671) (xy 115.334542 -237.83671) (xy 115.359497 -237.837326) (xy 115.408446 -237.84707)
			(xy 115.454554 -237.866177) (xy 115.496048 -237.893912) (xy 115.51412 -237.911132) (xy 116.02212 -238.419132)
			(xy 116.039382 -238.437172) (xy 116.067144 -238.478665) (xy 116.086261 -238.524783) (xy 116.095996 -238.573748)
			(xy 116.096542 -238.59871) (xy 116.096542 -239.915954) (xy 117.852698 -241.67211) (xy 120.465342 -241.67211)
			(xy 120.490297 -241.672726) (xy 120.539246 -241.68247) (xy 120.585354 -241.701577) (xy 120.626848 -241.729312)
			(xy 120.64492 -241.746532) (xy 121.20372 -242.305332) (xy 121.220982 -242.323372) (xy 121.248744 -242.364865)
			(xy 121.267861 -242.410983) (xy 121.277596 -242.459948) (xy 121.278142 -242.48491) (xy 121.278142 -243.32311)
			(xy 121.27757 -243.34807) (xy 121.267827 -243.397029) (xy 121.248719 -243.443146) (xy 121.220979 -243.484648)
			(xy 121.20372 -243.502688) (xy 120.92432 -243.782088) (xy 120.906279 -243.799348) (xy 120.864786 -243.827105)
			(xy 120.818668 -243.846216) (xy 120.769703 -243.855944) (xy 120.744742 -243.85651) (xy 120.189498 -243.85651)
			(xy 118.872 -245.174008) (xy 118.872 -246.730012) (xy 120.926098 -248.78411) (xy 120.950736 -248.781316)
			(xy 120.960289 -248.780257) (xy 120.979479 -248.779115) (xy 120.98909 -248.77903) (xy 121.01488 -248.779509)
			(xy 121.065826 -248.787576) (xy 121.114882 -248.803514) (xy 121.160841 -248.82693) (xy 121.202571 -248.857247)
			(xy 121.239045 -248.89372) (xy 121.269364 -248.935449) (xy 121.292781 -248.981407) (xy 121.308721 -249.030462)
			(xy 121.316791 -249.081408) (xy 121.317258 -249.107198) (xy 121.316996 -249.124152) (xy 121.313432 -249.157873)
			(xy 121.310146 -249.174508) (xy 121.323928 -249.195788) (xy 121.343644 -249.242488) (xy 121.353731 -249.292165)
			(xy 121.354342 -249.31751) (xy 121.354342 -260.087364) (xy 121.354237 -260.097633) (xy 121.352585 -260.118105)
			(xy 121.35104 -260.128258) (xy 121.346722 -260.153912) (xy 121.571258 -260.378194) (xy 121.582577 -260.390311)
			(xy 121.599134 -260.419023) (xy 121.607742 -260.451031) (xy 121.608342 -260.467602) (xy 121.608342 -261.685532)
		)
		(stroke
			(width 0)
			(type solid)
		)
		(fill yes)
		(layer "In8.Cu")
		(net "PVCCD_HV_CPU1")
	)
	(gr_poly
		(pts
			(xy 369.6716 -261.808722) (xy 369.682848 -261.81922) (xy 369.710076 -261.833519) (xy 369.740323 -261.839082)
			(xy 369.770856 -261.835407) (xy 369.798919 -261.822826) (xy 369.810792 -261.81304) (xy 369.828871 -261.797578)
			(xy 369.868653 -261.771494) (xy 369.911785 -261.751429) (xy 369.957363 -261.737805) (xy 370.004431 -261.730907)
			(xy 370.028216 -261.73049) (xy 370.053017 -261.730947) (xy 370.102052 -261.738422) (xy 370.149401 -261.753199)
			(xy 370.193983 -261.774942) (xy 370.214652 -261.788656) (xy 370.781326 -261.788656) (xy 370.801987 -261.77493)
			(xy 370.846574 -261.753195) (xy 370.893925 -261.738424) (xy 370.942961 -261.730953) (xy 370.992563 -261.730953)
			(xy 371.041599 -261.738424) (xy 371.08895 -261.753195) (xy 371.133537 -261.77493) (xy 371.154198 -261.788656)
			(xy 371.72138 -261.788656) (xy 371.742041 -261.77493) (xy 371.786628 -261.753195) (xy 371.833979 -261.738424)
			(xy 371.883015 -261.730953) (xy 371.932617 -261.730953) (xy 371.981653 -261.738424) (xy 372.029004 -261.753195)
			(xy 372.073591 -261.77493) (xy 372.094252 -261.788656) (xy 372.66118 -261.788656) (xy 372.681841 -261.77493)
			(xy 372.726428 -261.753195) (xy 372.773779 -261.738424) (xy 372.822815 -261.730953) (xy 372.872417 -261.730953)
			(xy 372.921453 -261.738424) (xy 372.968804 -261.753195) (xy 373.013391 -261.77493) (xy 373.034052 -261.788656)
			(xy 373.600726 -261.788656) (xy 373.621388 -261.774931) (xy 373.665975 -261.753198) (xy 373.713326 -261.738425)
			(xy 373.762361 -261.730951) (xy 373.787162 -261.73049) (xy 373.787416 -261.73049) (xy 373.810428 -261.730874)
			(xy 373.856 -261.737303) (xy 373.900224 -261.750048) (xy 373.942229 -261.768857) (xy 373.961914 -261.780782)
			(xy 373.97436 -261.788656) (xy 374.043956 -261.788656) (xy 374.928892 -260.90372) (xy 374.928892 -259.80644)
			(xy 374.914698 -259.78554) (xy 374.892216 -259.740299) (xy 374.876929 -259.692148) (xy 374.869197 -259.642224)
			(xy 374.869203 -259.591704) (xy 374.876946 -259.541782) (xy 374.892243 -259.493634) (xy 374.914735 -259.448398)
			(xy 374.928892 -259.427472) (xy 374.928892 -258.178046) (xy 374.914755 -258.157195) (xy 374.892366 -258.112067)
			(xy 374.877143 -258.064047) (xy 374.869442 -258.014263) (xy 374.869446 -257.963888) (xy 374.877154 -257.914105)
			(xy 374.892385 -257.866087) (xy 374.91478 -257.820963) (xy 374.928892 -257.800094) (xy 374.928892 -256.550922)
			(xy 374.914691 -256.530022) (xy 374.892197 -256.484779) (xy 374.876898 -256.436624) (xy 374.869155 -256.386694)
			(xy 374.86915 -256.336168) (xy 374.876884 -256.286236) (xy 374.892174 -256.238079) (xy 374.91466 -256.192831)
			(xy 374.928892 -256.171954) (xy 374.928892 -254.923036) (xy 374.914698 -254.902136) (xy 374.892217 -254.856895)
			(xy 374.876931 -254.808744) (xy 374.869199 -254.75882) (xy 374.869205 -254.708301) (xy 374.876949 -254.658379)
			(xy 374.892247 -254.610232) (xy 374.914739 -254.564996) (xy 374.928892 -254.544068) (xy 374.928892 -249.907552)
			(xy 374.90715 -249.895086) (xy 374.867389 -249.864583) (xy 374.83273 -249.828386) (xy 374.803982 -249.787338)
			(xy 374.781814 -249.742393) (xy 374.766741 -249.694599) (xy 374.759115 -249.645069) (xy 374.759114 -249.594954)
			(xy 374.766736 -249.545423) (xy 374.781805 -249.497628) (xy 374.80397 -249.452682) (xy 374.832716 -249.411632)
			(xy 374.867371 -249.375432) (xy 374.907131 -249.344926) (xy 374.928892 -249.332496) (xy 374.928892 -248.279666)
			(xy 374.907149 -248.2672) (xy 374.867385 -248.236697) (xy 374.832725 -248.200499) (xy 374.803975 -248.15945)
			(xy 374.781805 -248.114504) (xy 374.766731 -248.066709) (xy 374.759104 -248.017176) (xy 374.759101 -247.96706)
			(xy 374.766723 -247.917527) (xy 374.781791 -247.86973) (xy 374.803956 -247.824782) (xy 374.832702 -247.783729)
			(xy 374.867358 -247.747527) (xy 374.907119 -247.71702) (xy 374.928892 -247.70461) (xy 374.928892 -246.652034)
			(xy 374.907152 -246.639568) (xy 374.867393 -246.609066) (xy 374.832737 -246.57287) (xy 374.803991 -246.531822)
			(xy 374.781825 -246.486879) (xy 374.766755 -246.439087) (xy 374.75913 -246.389559) (xy 374.75913 -246.339447)
			(xy 374.766753 -246.289918) (xy 374.781823 -246.242126) (xy 374.803988 -246.197183) (xy 374.832733 -246.156135)
			(xy 374.867388 -246.119938) (xy 374.907147 -246.089435) (xy 374.928892 -246.076978) (xy 374.928892 -245.024148)
			(xy 374.907178 -245.011662) (xy 374.867472 -244.981129) (xy 374.832866 -244.944917) (xy 374.804165 -244.903868)
			(xy 374.782034 -244.858934) (xy 374.766988 -244.81116) (xy 374.759376 -244.761654) (xy 374.759374 -244.711566)
			(xy 374.766984 -244.662059) (xy 374.782027 -244.614283) (xy 374.804155 -244.569348) (xy 374.832854 -244.528298)
			(xy 374.867457 -244.492084) (xy 374.907161 -244.461549) (xy 374.928892 -244.449092) (xy 374.928892 -243.396516)
			(xy 374.907153 -243.384051) (xy 374.867397 -243.353548) (xy 374.832744 -243.317353) (xy 374.804001 -243.276307)
			(xy 374.781837 -243.231365) (xy 374.766768 -243.183575) (xy 374.759145 -243.134049) (xy 374.759146 -243.08394)
			(xy 374.766771 -243.034414) (xy 374.781841 -242.986624) (xy 374.804006 -242.941683) (xy 374.832751 -242.900638)
			(xy 374.867405 -242.864444) (xy 374.907163 -242.833943) (xy 374.928892 -242.82146) (xy 374.928892 -241.76863)
			(xy 374.907152 -241.756164) (xy 374.867394 -241.725662) (xy 374.832738 -241.689466) (xy 374.803993 -241.648419)
			(xy 374.781828 -241.603476) (xy 374.766758 -241.555685) (xy 374.759134 -241.506157) (xy 374.759134 -241.456045)
			(xy 374.766757 -241.406517) (xy 374.781827 -241.358726) (xy 374.803992 -241.313783) (xy 374.832737 -241.272736)
			(xy 374.867392 -241.236539) (xy 374.907151 -241.206037) (xy 374.928892 -241.193574) (xy 374.928892 -240.140744)
			(xy 374.907151 -240.128281) (xy 374.86739 -240.097782) (xy 374.832734 -240.061587) (xy 374.80399 -240.020539)
			(xy 374.781828 -239.975595) (xy 374.766765 -239.927801) (xy 374.759151 -239.878272) (xy 374.758712 -239.853216)
			(xy 374.759191 -239.82807) (xy 374.766862 -239.778366) (xy 374.782026 -239.730415) (xy 374.804328 -239.685338)
			(xy 374.818402 -239.664494) (xy 374.84304 -239.629696) (xy 374.579134 -239.36579) (xy 374.563132 -239.362996)
			(xy 374.538127 -239.358333) (xy 374.489855 -239.342309) (xy 374.444634 -239.319027) (xy 374.403547 -239.289046)
			(xy 374.36758 -239.253083) (xy 374.337593 -239.212) (xy 374.314306 -239.166781) (xy 374.298277 -239.118511)
			(xy 374.293638 -239.093502) (xy 374.290844 -239.0775) (xy 372.907814 -237.69447) (xy 372.875556 -237.709202)
			(xy 372.853847 -237.718814) (xy 372.80835 -237.732379) (xy 372.761372 -237.739235) (xy 372.737634 -237.739682)
			(xy 372.711842 -237.739205) (xy 372.660893 -237.731141) (xy 372.611833 -237.715205) (xy 372.565869 -237.691791)
			(xy 372.524135 -237.661474) (xy 372.487657 -237.625001) (xy 372.457335 -237.583272) (xy 372.433913 -237.537312)
			(xy 372.41797 -237.488254) (xy 372.409898 -237.437306) (xy 372.409466 -237.411514) (xy 372.409904 -237.387776)
			(xy 372.416775 -237.340799) (xy 372.430332 -237.2953) (xy 372.439946 -237.273592) (xy 372.454678 -237.241334)
			(xy 372.08206 -236.868716) (xy 372.078504 -236.86643) (xy 372.055727 -236.84968) (xy 372.015749 -236.809707)
			(xy 371.999002 -236.786928) (xy 371.996716 -236.783372) (xy 370.495068 -235.281724) (xy 370.467128 -235.288582)
			(xy 370.447755 -235.293087) (xy 370.408275 -235.297927) (xy 370.388388 -235.298234) (xy 370.38788 -235.298234)
			(xy 370.362092 -235.297753) (xy 370.311153 -235.289681) (xy 370.262103 -235.27374) (xy 370.21615 -235.250322)
			(xy 370.174428 -235.220004) (xy 370.137961 -235.183531) (xy 370.10765 -235.141803) (xy 370.084239 -235.095847)
			(xy 370.068306 -235.046795) (xy 370.060243 -234.995854) (xy 370.059712 -234.970066) (xy 370.059712 -234.969558)
			(xy 370.060018 -234.949671) (xy 370.064857 -234.910191) (xy 370.069364 -234.890818) (xy 370.076222 -234.862878)
			(xy 368.069114 -232.85577) (xy 368.04727 -232.856532) (xy 368.03838 -232.856532) (xy 368.012592 -232.856051)
			(xy 367.961653 -232.847979) (xy 367.912603 -232.832038) (xy 367.866651 -232.80862) (xy 367.824928 -232.778302)
			(xy 367.788462 -232.741829) (xy 367.758151 -232.700101) (xy 367.73474 -232.654145) (xy 367.718808 -232.605093)
			(xy 367.710745 -232.554152) (xy 367.710212 -232.528364) (xy 367.710212 -232.519474) (xy 367.710974 -232.49763)
			(xy 366.369092 -231.155748) (xy 366.334802 -231.177592) (xy 366.314998 -231.189674) (xy 366.27271 -231.208752)
			(xy 366.228159 -231.221687) (xy 366.18223 -231.228223) (xy 366.159034 -231.228646) (xy 366.133243 -231.228169)
			(xy 366.082296 -231.220105) (xy 366.033238 -231.204168) (xy 365.987277 -231.180753) (xy 365.945546 -231.150436)
			(xy 365.909072 -231.113963) (xy 365.878753 -231.072233) (xy 365.855336 -231.026273) (xy 365.839398 -230.977216)
			(xy 365.831332 -230.926269) (xy 365.830866 -230.900478) (xy 365.831269 -230.877282) (xy 365.837808 -230.831352)
			(xy 365.850754 -230.786803) (xy 365.869846 -230.744521) (xy 365.88192 -230.72471) (xy 365.903764 -230.69042)
			(xy 365.62157 -230.408226) (xy 365.607854 -230.40467) (xy 365.583616 -230.397997) (xy 365.537367 -230.378296)
			(xy 365.494664 -230.351772) (xy 365.456506 -230.319044) (xy 365.423787 -230.280879) (xy 365.397271 -230.23817)
			(xy 365.37758 -230.191917) (xy 365.370872 -230.167688) (xy 365.367316 -230.153972) (xy 363.963712 -228.750368)
			(xy 363.932724 -228.763068) (xy 363.903109 -228.77431) (xy 363.840949 -228.786466) (xy 363.80928 -228.787198)
			(xy 363.783493 -228.786691) (xy 363.732553 -228.77862) (xy 363.683503 -228.762681) (xy 363.63755 -228.739266)
			(xy 363.595825 -228.708951) (xy 363.559355 -228.672483) (xy 363.529039 -228.630759) (xy 363.505622 -228.584806)
			(xy 363.489682 -228.535757) (xy 363.48161 -228.484817) (xy 363.481112 -228.45903) (xy 363.481846 -228.427361)
			(xy 363.493996 -228.3652) (xy 363.505242 -228.335586) (xy 363.517942 -228.304598) (xy 363.120178 -227.906834)
			(xy 363.103076 -227.888941) (xy 363.075451 -227.84788) (xy 363.065314 -227.8253) (xy 363.052602 -227.805164)
			(xy 363.032494 -227.762001) (xy 363.018831 -227.716386) (xy 363.0119 -227.669276) (xy 363.011466 -227.645468)
			(xy 363.011466 -227.64496) (xy 363.011869 -227.621504) (xy 363.018562 -227.575071) (xy 363.031805 -227.530066)
			(xy 363.041184 -227.508562) (xy 363.045756 -227.498402) (xy 363.045756 -226.163886) (xy 363.041184 -226.153726)
			(xy 363.030001 -226.127881) (xy 363.015663 -226.073428) (xy 363.010833 -226.017326) (xy 363.015654 -225.961223)
			(xy 363.029983 -225.906767) (xy 363.041184 -225.88093) (xy 363.045756 -225.87077) (xy 363.045756 -224.539048)
			(xy 363.04093 -224.528888) (xy 363.0312 -224.506944) (xy 363.017482 -224.460945) (xy 363.010584 -224.413443)
			(xy 363.010196 -224.389442) (xy 363.01059 -224.365441) (xy 363.017479 -224.317937) (xy 363.03119 -224.271935)
			(xy 363.04093 -224.249996) (xy 363.045756 -224.239836) (xy 363.045756 -223.883982) (xy 362.98632 -223.883982)
			(xy 362.978192 -223.886776) (xy 362.96654 -223.890731) (xy 362.942766 -223.897089) (xy 362.930694 -223.899476)
			(xy 362.907834 -223.903794) (xy 362.70311 -224.258632) (xy 362.710984 -224.280476) (xy 362.719563 -224.306895)
			(xy 362.728758 -224.36167) (xy 362.729272 -224.389442) (xy 362.728764 -224.415329) (xy 362.720665 -224.466467)
			(xy 362.704666 -224.515707) (xy 362.68116 -224.561839) (xy 362.650728 -224.603726) (xy 362.614118 -224.640336)
			(xy 362.572231 -224.670768) (xy 362.526099 -224.694274) (xy 362.476859 -224.710273) (xy 362.425721 -224.718372)
			(xy 362.373947 -224.718372) (xy 362.322809 -224.710273) (xy 362.273569 -224.694274) (xy 362.227437 -224.670768)
			(xy 362.18555 -224.640336) (xy 362.14894 -224.603726) (xy 362.118508 -224.561839) (xy 362.095002 -224.515707)
			(xy 362.079003 -224.466467) (xy 362.070904 -224.415329) (xy 362.070396 -224.389442) (xy 362.070856 -224.364104)
			(xy 362.078604 -224.314024) (xy 362.093923 -224.265719) (xy 362.116453 -224.220327) (xy 362.145664 -224.178916)
			(xy 362.180866 -224.142463) (xy 362.221232 -224.111826) (xy 362.26581 -224.087725) (xy 362.313551 -224.07073)
			(xy 362.338366 -224.065592) (xy 362.361226 -224.061274) (xy 362.566204 -223.706182) (xy 362.558584 -223.684084)
			(xy 362.550071 -223.657911) (xy 362.540881 -223.60365) (xy 362.540296 -223.576134) (xy 362.540296 -223.575626)
			(xy 362.540775 -223.549736) (xy 362.548872 -223.498594) (xy 362.564871 -223.449348) (xy 362.588377 -223.403211)
			(xy 362.618812 -223.36132) (xy 362.655426 -223.324707) (xy 362.697318 -223.294273) (xy 362.743455 -223.270768)
			(xy 362.792701 -223.25477) (xy 362.843844 -223.246675) (xy 362.869734 -223.246188) (xy 362.88403 -223.246305)
			(xy 362.912519 -223.248718) (xy 362.92663 -223.251014) (xy 362.941299 -223.253077) (xy 362.970706 -223.249622)
			(xy 362.997889 -223.237883) (xy 363.020567 -223.218845) (xy 363.036838 -223.194107) (xy 363.045335 -223.165743)
			(xy 363.045756 -223.150938) (xy 363.045756 -222.908114) (xy 363.041184 -222.897954) (xy 363.030007 -222.872109)
			(xy 363.015681 -222.817658) (xy 363.010863 -222.76156) (xy 363.015695 -222.705463) (xy 363.030034 -222.651015)
			(xy 363.041184 -222.625158) (xy 363.045756 -222.614998) (xy 363.045756 -221.28353) (xy 363.04093 -221.27337)
			(xy 363.031201 -221.251426) (xy 363.017486 -221.205427) (xy 363.01059 -221.157925) (xy 363.010196 -221.133924)
			(xy 363.010724 -221.106216) (xy 363.01992 -221.051569) (xy 363.028484 -221.025212) (xy 363.036358 -221.003114)
			(xy 362.83138 -220.648022) (xy 362.80852 -220.643704) (xy 362.783668 -220.638569) (xy 362.735817 -220.62168)
			(xy 362.691122 -220.597651) (xy 362.650642 -220.567051) (xy 362.615334 -220.530604) (xy 362.586035 -220.489173)
			(xy 362.563437 -220.443738) (xy 362.548076 -220.395374) (xy 362.540315 -220.345227) (xy 362.539788 -220.319854)
			(xy 362.540274 -220.293955) (xy 362.548387 -220.242796) (xy 362.564408 -220.193538) (xy 362.58794 -220.147393)
			(xy 362.618404 -220.105501) (xy 362.655049 -220.068892) (xy 362.696972 -220.038469) (xy 362.743139 -220.014983)
			(xy 362.792414 -219.999011) (xy 362.84358 -219.990948) (xy 362.86948 -219.990416) (xy 362.883839 -219.990525)
			(xy 362.912455 -219.992946) (xy 362.92663 -219.995242) (xy 362.941296 -219.997305) (xy 362.970696 -219.99385)
			(xy 362.997871 -219.98211) (xy 363.020539 -219.96307) (xy 363.036794 -219.93833) (xy 363.045274 -219.909968)
			(xy 363.045756 -219.895166) (xy 363.045756 -219.652596) (xy 363.041184 -219.642436) (xy 363.03 -219.616591)
			(xy 363.01566 -219.562137) (xy 363.010829 -219.506035) (xy 363.015648 -219.449931) (xy 363.029976 -219.395474)
			(xy 363.041184 -219.36964) (xy 363.045756 -219.35948) (xy 363.045756 -218.028012) (xy 363.04093 -218.017852)
			(xy 363.031202 -217.995908) (xy 363.01749 -217.949909) (xy 363.010597 -217.902406) (xy 363.010196 -217.878406)
			(xy 363.010725 -217.850698) (xy 363.019925 -217.796052) (xy 363.028484 -217.769694) (xy 363.036358 -217.747596)
			(xy 362.83138 -217.392504) (xy 362.80852 -217.388186) (xy 362.783666 -217.383052) (xy 362.735808 -217.366165)
			(xy 362.691107 -217.342138) (xy 362.650619 -217.311539) (xy 362.615303 -217.275093) (xy 362.585994 -217.233662)
			(xy 362.563386 -217.188227) (xy 362.548013 -217.139862) (xy 362.54024 -217.089711) (xy 362.539788 -217.064336)
			(xy 362.540267 -217.038424) (xy 362.548368 -216.987238) (xy 362.564378 -216.937949) (xy 362.587901 -216.891772)
			(xy 362.618358 -216.849843) (xy 362.655 -216.813195) (xy 362.696924 -216.78273) (xy 362.743097 -216.759199)
			(xy 362.792383 -216.743182) (xy 362.843568 -216.735071) (xy 362.86948 -216.734644) (xy 362.883844 -216.734821)
			(xy 362.912461 -216.737361) (xy 362.92663 -216.739724) (xy 362.941299 -216.741787) (xy 362.970708 -216.738331)
			(xy 362.997892 -216.726593) (xy 363.020571 -216.707556) (xy 363.036843 -216.682817) (xy 363.045343 -216.654453)
			(xy 363.045756 -216.639648) (xy 363.045756 -216.397586) (xy 363.041184 -216.387426) (xy 363.03173 -216.365853)
			(xy 363.018394 -216.320681) (xy 363.011634 -216.274069) (xy 363.011212 -216.25052) (xy 363.011613 -216.226968)
			(xy 363.018351 -216.180349) (xy 363.031704 -216.135178) (xy 363.041184 -216.113614) (xy 363.045756 -216.103454)
			(xy 363.045756 -201.196194) (xy 363.046328 -201.171234) (xy 363.05607 -201.122274) (xy 363.075178 -201.076157)
			(xy 363.102917 -201.034654) (xy 363.120178 -201.016616) (xy 397.786352 -166.350442) (xy 397.804394 -166.333184)
			(xy 397.845888 -166.30543) (xy 397.892006 -166.286319) (xy 397.940969 -166.276589) (xy 397.96593 -166.27602)
			(xy 409.64612 -166.27602) (xy 409.966668 -165.955472) (xy 409.966668 -157.991302) (xy 409.505912 -157.530546)
			(xy 373.176038 -157.530546) (xy 369.79523 -160.911354) (xy 372.506163 -160.911354) (xy 372.506163 -160.856846)
			(xy 372.513921 -160.802893) (xy 372.529279 -160.750593) (xy 372.551924 -160.701011) (xy 372.581395 -160.655157)
			(xy 372.617092 -160.613964) (xy 372.658289 -160.578271) (xy 372.704146 -160.548805) (xy 372.75373 -160.526165)
			(xy 372.806032 -160.510813) (xy 372.859986 -160.503061) (xy 372.88724 -160.5026) (xy 373.75084 -160.5026)
			(xy 373.77809 -160.503073) (xy 373.832034 -160.510834) (xy 373.884326 -160.526193) (xy 373.933899 -160.548837)
			(xy 373.979745 -160.578305) (xy 374.020931 -160.613997) (xy 374.056619 -160.655187) (xy 374.086083 -160.701036)
			(xy 374.108721 -160.750612) (xy 374.124075 -160.802905) (xy 374.13183 -160.85685) (xy 374.13183 -160.91135)
			(xy 374.124075 -160.965295) (xy 374.108721 -161.017588) (xy 374.086083 -161.067164) (xy 374.056619 -161.113013)
			(xy 374.020931 -161.154203) (xy 373.979745 -161.189895) (xy 373.933899 -161.219363) (xy 373.884326 -161.242007)
			(xy 373.832034 -161.257366) (xy 373.77809 -161.265127) (xy 373.75084 -161.265616) (xy 372.88724 -161.265616)
			(xy 372.859986 -161.265139) (xy 372.806032 -161.257387) (xy 372.75373 -161.242035) (xy 372.704146 -161.219395)
			(xy 372.658289 -161.189929) (xy 372.617092 -161.154236) (xy 372.581395 -161.113043) (xy 372.551924 -161.067189)
			(xy 372.529279 -161.017607) (xy 372.513921 -160.965307) (xy 372.506163 -160.911354) (xy 369.79523 -160.911354)
			(xy 363.830616 -166.875968) (xy 369.614196 -166.875968) (xy 369.614752 -166.84267) (xy 369.623426 -166.776641)
			(xy 369.640648 -166.71231) (xy 369.666122 -166.650779) (xy 369.699412 -166.593101) (xy 369.739949 -166.540263)
			(xy 369.787038 -166.493171) (xy 369.839873 -166.452631) (xy 369.86845 -166.435532) (xy 370.792502 -165.901878)
			(xy 370.82156 -165.885769) (xy 370.882966 -165.8604) (xy 370.947153 -165.843245) (xy 371.013028 -165.834597)
			(xy 371.046248 -165.83406) (xy 371.046756 -165.83406) (xy 371.077486 -165.834579) (xy 371.138498 -165.841982)
			(xy 371.198173 -165.856685) (xy 371.255641 -165.878475) (xy 371.310063 -165.907032) (xy 371.360647 -165.941941)
			(xy 371.406653 -165.982693) (xy 371.447412 -166.028694) (xy 371.482329 -166.079272) (xy 371.510894 -166.133689)
			(xy 371.532692 -166.191154) (xy 371.547404 -166.250827) (xy 371.554816 -166.311838) (xy 371.555264 -166.342568)
			(xy 371.554757 -166.375868) (xy 371.546077 -166.4419) (xy 371.52885 -166.506232) (xy 371.503369 -166.567765)
			(xy 371.470072 -166.625443) (xy 371.429528 -166.67828) (xy 371.382432 -166.72537) (xy 371.329591 -166.765907)
			(xy 371.30101 -166.783004) (xy 370.964111 -166.977568) (xy 373.398796 -166.977568) (xy 373.399226 -166.946836)
			(xy 373.406638 -166.885821) (xy 373.421351 -166.826144) (xy 373.443149 -166.768676) (xy 373.471715 -166.714254)
			(xy 373.506633 -166.663671) (xy 373.547392 -166.617667) (xy 373.5934 -166.57691) (xy 373.643984 -166.541996)
			(xy 373.698409 -166.513434) (xy 373.755879 -166.49164) (xy 373.815556 -166.476932) (xy 373.876572 -166.469524)
			(xy 373.907304 -166.46906) (xy 373.907812 -166.46906) (xy 373.941031 -166.469606) (xy 374.006903 -166.478264)
			(xy 374.071088 -166.495419) (xy 374.132496 -166.520778) (xy 374.161558 -166.536878) (xy 375.08561 -167.070532)
			(xy 375.114171 -167.087654) (xy 375.166997 -167.128201) (xy 375.214079 -167.175295) (xy 375.254613 -167.22813)
			(xy 375.287906 -167.285802) (xy 375.313388 -167.347326) (xy 375.330623 -167.411649) (xy 375.339318 -167.477672)
			(xy 375.339864 -167.510968) (xy 375.339432 -167.541701) (xy 375.332026 -167.60272) (xy 375.317319 -167.6624)
			(xy 375.295524 -167.719873) (xy 375.266961 -167.774299) (xy 375.232044 -167.824885) (xy 375.191284 -167.870893)
			(xy 375.145275 -167.911651) (xy 375.094689 -167.946567) (xy 375.040262 -167.975129) (xy 374.982789 -167.996923)
			(xy 374.923108 -168.011629) (xy 374.862089 -168.019033) (xy 374.831356 -168.019476) (xy 374.830848 -168.019476)
			(xy 374.797629 -168.018942) (xy 374.731757 -168.01028) (xy 374.667571 -167.993122) (xy 374.606164 -167.967759)
			(xy 374.577102 -167.951658) (xy 373.65305 -167.418004) (xy 373.624495 -167.400872) (xy 373.571672 -167.360325)
			(xy 373.524591 -167.313232) (xy 373.484057 -167.260398) (xy 373.450764 -167.202727) (xy 373.42528 -167.141205)
			(xy 373.408042 -167.076884) (xy 373.399344 -167.010863) (xy 373.398796 -166.977568) (xy 370.964111 -166.977568)
			(xy 370.376958 -167.316658) (xy 370.34791 -167.332786) (xy 370.2865 -167.35815) (xy 370.22231 -167.375299)
			(xy 370.156433 -167.383942) (xy 370.123212 -167.384476) (xy 370.122704 -167.384476) (xy 370.091971 -167.384059)
			(xy 370.030952 -167.37665) (xy 369.971272 -167.36194) (xy 369.9138 -167.340143) (xy 369.859375 -167.311577)
			(xy 369.808789 -167.276659) (xy 369.762782 -167.235898) (xy 369.722023 -167.189889) (xy 369.687108 -167.139301)
			(xy 369.658546 -167.084874) (xy 369.636752 -167.027401) (xy 369.622045 -166.96772) (xy 369.61464 -166.906701)
			(xy 369.614196 -166.875968) (xy 363.830616 -166.875968) (xy 360.782616 -169.923968) (xy 369.614196 -169.923968)
			(xy 369.614752 -169.89067) (xy 369.623426 -169.824641) (xy 369.640648 -169.76031) (xy 369.666122 -169.698779)
			(xy 369.699412 -169.641101) (xy 369.739949 -169.588263) (xy 369.787038 -169.541171) (xy 369.839873 -169.500631)
			(xy 369.86845 -169.483532) (xy 370.792502 -168.949878) (xy 370.82156 -168.933769) (xy 370.882966 -168.9084)
			(xy 370.947153 -168.891245) (xy 371.013028 -168.882597) (xy 371.046248 -168.88206) (xy 371.046756 -168.88206)
			(xy 371.077486 -168.882579) (xy 371.138498 -168.889982) (xy 371.198173 -168.904685) (xy 371.255641 -168.926475)
			(xy 371.310063 -168.955032) (xy 371.360647 -168.989941) (xy 371.406653 -169.030693) (xy 371.447412 -169.076694)
			(xy 371.482329 -169.127272) (xy 371.510894 -169.181689) (xy 371.532692 -169.239154) (xy 371.547404 -169.298827)
			(xy 371.554816 -169.359838) (xy 371.555264 -169.390568) (xy 371.554757 -169.423868) (xy 371.546077 -169.4899)
			(xy 371.52885 -169.554232) (xy 371.503369 -169.615765) (xy 371.470072 -169.673443) (xy 371.429528 -169.72628)
			(xy 371.382432 -169.77337) (xy 371.329591 -169.813907) (xy 371.30101 -169.831004) (xy 370.376958 -170.364658)
			(xy 370.34791 -170.380786) (xy 370.2865 -170.40615) (xy 370.22231 -170.423299) (xy 370.156433 -170.431942)
			(xy 370.123212 -170.432476) (xy 370.122704 -170.432476) (xy 370.091971 -170.432059) (xy 370.030952 -170.42465)
			(xy 369.971272 -170.40994) (xy 369.9138 -170.388143) (xy 369.859375 -170.359577) (xy 369.808789 -170.324659)
			(xy 369.762782 -170.283898) (xy 369.722023 -170.237889) (xy 369.687108 -170.187301) (xy 369.658546 -170.132874)
			(xy 369.636752 -170.075401) (xy 369.622045 -170.01572) (xy 369.61464 -169.954701) (xy 369.614196 -169.923968)
			(xy 360.782616 -169.923968) (xy 360.046016 -170.660568) (xy 373.398796 -170.660568) (xy 373.399226 -170.629836)
			(xy 373.406638 -170.568821) (xy 373.421351 -170.509144) (xy 373.443149 -170.451676) (xy 373.471715 -170.397254)
			(xy 373.506633 -170.346671) (xy 373.547392 -170.300667) (xy 373.5934 -170.25991) (xy 373.643984 -170.224996)
			(xy 373.698409 -170.196434) (xy 373.755879 -170.17464) (xy 373.815556 -170.159932) (xy 373.876572 -170.152524)
			(xy 373.907304 -170.15206) (xy 373.907812 -170.15206) (xy 373.941031 -170.152606) (xy 374.006903 -170.161264)
			(xy 374.071088 -170.178419) (xy 374.132496 -170.203778) (xy 374.161558 -170.219878) (xy 375.08561 -170.753532)
			(xy 375.114171 -170.770654) (xy 375.166997 -170.811201) (xy 375.214079 -170.858295) (xy 375.254613 -170.91113)
			(xy 375.287906 -170.968802) (xy 375.313388 -171.030326) (xy 375.330623 -171.094649) (xy 375.339318 -171.160672)
			(xy 375.339864 -171.193968) (xy 375.339432 -171.224701) (xy 375.332026 -171.28572) (xy 375.317319 -171.3454)
			(xy 375.295524 -171.402873) (xy 375.266961 -171.457299) (xy 375.232044 -171.507885) (xy 375.191284 -171.553893)
			(xy 375.145275 -171.594651) (xy 375.094689 -171.629567) (xy 375.040262 -171.658129) (xy 374.982789 -171.679923)
			(xy 374.923108 -171.694629) (xy 374.862089 -171.702033) (xy 374.831356 -171.702476) (xy 374.830848 -171.702476)
			(xy 374.797629 -171.701942) (xy 374.731757 -171.69328) (xy 374.667571 -171.676122) (xy 374.606164 -171.650759)
			(xy 374.577102 -171.634658) (xy 373.65305 -171.101004) (xy 373.624495 -171.083872) (xy 373.571672 -171.043325)
			(xy 373.524591 -170.996232) (xy 373.484057 -170.943398) (xy 373.450764 -170.885727) (xy 373.42528 -170.824205)
			(xy 373.408042 -170.759884) (xy 373.399344 -170.693863) (xy 373.398796 -170.660568) (xy 360.046016 -170.660568)
			(xy 357.734616 -172.971968) (xy 369.614196 -172.971968) (xy 369.614752 -172.93867) (xy 369.623426 -172.872641)
			(xy 369.640648 -172.80831) (xy 369.666122 -172.746779) (xy 369.699412 -172.689101) (xy 369.739949 -172.636263)
			(xy 369.787038 -172.589171) (xy 369.839873 -172.548631) (xy 369.86845 -172.531532) (xy 370.792502 -171.997878)
			(xy 370.82156 -171.981769) (xy 370.882966 -171.9564) (xy 370.947153 -171.939245) (xy 371.013028 -171.930597)
			(xy 371.046248 -171.93006) (xy 371.046756 -171.93006) (xy 371.077486 -171.930579) (xy 371.138498 -171.937982)
			(xy 371.198173 -171.952685) (xy 371.255641 -171.974475) (xy 371.310063 -172.003032) (xy 371.360647 -172.037941)
			(xy 371.406653 -172.078693) (xy 371.447412 -172.124694) (xy 371.482329 -172.175272) (xy 371.510894 -172.229689)
			(xy 371.532692 -172.287154) (xy 371.547404 -172.346827) (xy 371.554816 -172.407838) (xy 371.555264 -172.438568)
			(xy 371.554757 -172.471868) (xy 371.546077 -172.5379) (xy 371.52885 -172.602232) (xy 371.503369 -172.663765)
			(xy 371.470072 -172.721443) (xy 371.429528 -172.77428) (xy 371.382432 -172.82137) (xy 371.329591 -172.861907)
			(xy 371.30101 -172.879004) (xy 370.376958 -173.412658) (xy 370.34791 -173.428786) (xy 370.2865 -173.45415)
			(xy 370.22231 -173.471299) (xy 370.156433 -173.479942) (xy 370.123212 -173.480476) (xy 370.122704 -173.480476)
			(xy 370.091971 -173.480059) (xy 370.030952 -173.47265) (xy 369.971272 -173.45794) (xy 369.9138 -173.436143)
			(xy 369.859375 -173.407577) (xy 369.808789 -173.372659) (xy 369.762782 -173.331898) (xy 369.722023 -173.285889)
			(xy 369.687108 -173.235301) (xy 369.658546 -173.180874) (xy 369.636752 -173.123401) (xy 369.622045 -173.06372)
			(xy 369.61464 -173.002701) (xy 369.614196 -172.971968) (xy 357.734616 -172.971968) (xy 356.363016 -174.343568)
			(xy 373.398796 -174.343568) (xy 373.399226 -174.312836) (xy 373.406638 -174.251821) (xy 373.421351 -174.192144)
			(xy 373.443149 -174.134676) (xy 373.471715 -174.080254) (xy 373.506633 -174.029671) (xy 373.547392 -173.983667)
			(xy 373.5934 -173.94291) (xy 373.643984 -173.907996) (xy 373.698409 -173.879434) (xy 373.755879 -173.85764)
			(xy 373.815556 -173.842932) (xy 373.876572 -173.835524) (xy 373.907304 -173.83506) (xy 373.907812 -173.83506)
			(xy 373.941031 -173.835606) (xy 374.006903 -173.844264) (xy 374.071088 -173.861419) (xy 374.132496 -173.886778)
			(xy 374.161558 -173.902878) (xy 375.08561 -174.436532) (xy 375.114171 -174.453654) (xy 375.166997 -174.494201)
			(xy 375.214079 -174.541295) (xy 375.254613 -174.59413) (xy 375.287906 -174.651802) (xy 375.313388 -174.713326)
			(xy 375.330623 -174.777649) (xy 375.339318 -174.843672) (xy 375.339864 -174.876968) (xy 375.339432 -174.907701)
			(xy 375.332026 -174.96872) (xy 375.317319 -175.0284) (xy 375.295524 -175.085873) (xy 375.266961 -175.140299)
			(xy 375.232044 -175.190885) (xy 375.191284 -175.236893) (xy 375.145275 -175.277651) (xy 375.094689 -175.312567)
			(xy 375.040262 -175.341129) (xy 374.982789 -175.362923) (xy 374.923108 -175.377629) (xy 374.862089 -175.385033)
			(xy 374.831356 -175.385476) (xy 374.830848 -175.385476) (xy 374.797629 -175.384942) (xy 374.731757 -175.37628)
			(xy 374.667571 -175.359122) (xy 374.606164 -175.333759) (xy 374.577102 -175.317658) (xy 373.65305 -174.784004)
			(xy 373.624495 -174.766872) (xy 373.571672 -174.726325) (xy 373.524591 -174.679232) (xy 373.484057 -174.626398)
			(xy 373.450764 -174.568727) (xy 373.42528 -174.507205) (xy 373.408042 -174.442884) (xy 373.399344 -174.376863)
			(xy 373.398796 -174.343568) (xy 356.363016 -174.343568) (xy 356.09276 -174.613824) (xy 356.09276 -176.019968)
			(xy 369.614196 -176.019968) (xy 369.614752 -175.98667) (xy 369.623426 -175.920641) (xy 369.640648 -175.85631)
			(xy 369.666122 -175.794779) (xy 369.699412 -175.737101) (xy 369.739949 -175.684263) (xy 369.787038 -175.637171)
			(xy 369.839873 -175.596631) (xy 369.86845 -175.579532) (xy 370.792502 -175.045878) (xy 370.82156 -175.029769)
			(xy 370.882966 -175.0044) (xy 370.947153 -174.987245) (xy 371.013028 -174.978597) (xy 371.046248 -174.97806)
			(xy 371.046756 -174.97806) (xy 371.077486 -174.978579) (xy 371.138498 -174.985982) (xy 371.198173 -175.000685)
			(xy 371.255641 -175.022475) (xy 371.310063 -175.051032) (xy 371.360647 -175.085941) (xy 371.406653 -175.126693)
			(xy 371.447412 -175.172694) (xy 371.482329 -175.223272) (xy 371.510894 -175.277689) (xy 371.532692 -175.335154)
			(xy 371.547404 -175.394827) (xy 371.554816 -175.455838) (xy 371.555264 -175.486568) (xy 371.554757 -175.519868)
			(xy 371.546077 -175.5859) (xy 371.52885 -175.650232) (xy 371.503369 -175.711765) (xy 371.470072 -175.769443)
			(xy 371.429528 -175.82228) (xy 371.382432 -175.86937) (xy 371.329591 -175.909907) (xy 371.30101 -175.927004)
			(xy 370.376958 -176.460658) (xy 370.34791 -176.476786) (xy 370.2865 -176.50215) (xy 370.22231 -176.519299)
			(xy 370.156433 -176.527942) (xy 370.123212 -176.528476) (xy 370.122704 -176.528476) (xy 370.091971 -176.528059)
			(xy 370.030952 -176.52065) (xy 369.971272 -176.50594) (xy 369.9138 -176.484143) (xy 369.859375 -176.455577)
			(xy 369.808789 -176.420659) (xy 369.762782 -176.379898) (xy 369.722023 -176.333889) (xy 369.687108 -176.283301)
			(xy 369.658546 -176.228874) (xy 369.636752 -176.171401) (xy 369.622045 -176.11172) (xy 369.61464 -176.050701)
			(xy 369.614196 -176.019968) (xy 356.09276 -176.019968) (xy 356.09276 -179.067968) (xy 369.614196 -179.067968)
			(xy 369.614752 -179.03467) (xy 369.623426 -178.968641) (xy 369.640648 -178.90431) (xy 369.666122 -178.842779)
			(xy 369.699412 -178.785101) (xy 369.739949 -178.732263) (xy 369.787038 -178.685171) (xy 369.839873 -178.644631)
			(xy 369.86845 -178.627532) (xy 370.792502 -178.093878) (xy 370.82156 -178.077769) (xy 370.882966 -178.0524)
			(xy 370.947153 -178.035245) (xy 371.013028 -178.026597) (xy 371.046248 -178.02606) (xy 371.046756 -178.02606)
			(xy 371.076835 -178.026568) (xy 373.398796 -178.026568) (xy 373.399226 -177.995836) (xy 373.406638 -177.934821)
			(xy 373.421351 -177.875144) (xy 373.443149 -177.817676) (xy 373.471715 -177.763254) (xy 373.506633 -177.712671)
			(xy 373.547392 -177.666667) (xy 373.5934 -177.62591) (xy 373.643984 -177.590996) (xy 373.698409 -177.562434)
			(xy 373.755879 -177.54064) (xy 373.815556 -177.525932) (xy 373.876572 -177.518524) (xy 373.907304 -177.51806)
			(xy 373.907812 -177.51806) (xy 373.941031 -177.518606) (xy 374.006903 -177.527264) (xy 374.071088 -177.544419)
			(xy 374.132496 -177.569778) (xy 374.161558 -177.585878) (xy 375.08561 -178.119532) (xy 375.114171 -178.136654)
			(xy 375.166997 -178.177201) (xy 375.214079 -178.224295) (xy 375.254613 -178.27713) (xy 375.287906 -178.334802)
			(xy 375.313388 -178.396326) (xy 375.330623 -178.460649) (xy 375.339318 -178.526672) (xy 375.339864 -178.559968)
			(xy 375.339432 -178.590701) (xy 375.332026 -178.65172) (xy 375.317319 -178.7114) (xy 375.295524 -178.768873)
			(xy 375.266961 -178.823299) (xy 375.232044 -178.873885) (xy 375.191284 -178.919893) (xy 375.145275 -178.960651)
			(xy 375.094689 -178.995567) (xy 375.040262 -179.024129) (xy 374.982789 -179.045923) (xy 374.923108 -179.060629)
			(xy 374.862089 -179.068033) (xy 374.831356 -179.068476) (xy 374.830848 -179.068476) (xy 374.797629 -179.067942)
			(xy 374.731757 -179.05928) (xy 374.667571 -179.042122) (xy 374.606164 -179.016759) (xy 374.577102 -179.000658)
			(xy 373.65305 -178.467004) (xy 373.624495 -178.449872) (xy 373.571672 -178.409325) (xy 373.524591 -178.362232)
			(xy 373.484057 -178.309398) (xy 373.450764 -178.251727) (xy 373.42528 -178.190205) (xy 373.408042 -178.125884)
			(xy 373.399344 -178.059863) (xy 373.398796 -178.026568) (xy 371.076835 -178.026568) (xy 371.077486 -178.026579)
			(xy 371.138498 -178.033982) (xy 371.198173 -178.048685) (xy 371.255641 -178.070475) (xy 371.310063 -178.099032)
			(xy 371.360647 -178.133941) (xy 371.406653 -178.174693) (xy 371.447412 -178.220694) (xy 371.482329 -178.271272)
			(xy 371.510894 -178.325689) (xy 371.532692 -178.383154) (xy 371.547404 -178.442827) (xy 371.554816 -178.503838)
			(xy 371.555264 -178.534568) (xy 371.554757 -178.567868) (xy 371.546077 -178.6339) (xy 371.52885 -178.698232)
			(xy 371.503369 -178.759765) (xy 371.470072 -178.817443) (xy 371.429528 -178.87028) (xy 371.382432 -178.91737)
			(xy 371.329591 -178.957907) (xy 371.30101 -178.975004) (xy 370.376958 -179.508658) (xy 370.34791 -179.524786)
			(xy 370.2865 -179.55015) (xy 370.22231 -179.567299) (xy 370.156433 -179.575942) (xy 370.123212 -179.576476)
			(xy 370.122704 -179.576476) (xy 370.091971 -179.576059) (xy 370.030952 -179.56865) (xy 369.971272 -179.55394)
			(xy 369.9138 -179.532143) (xy 369.859375 -179.503577) (xy 369.808789 -179.468659) (xy 369.762782 -179.427898)
			(xy 369.722023 -179.381889) (xy 369.687108 -179.331301) (xy 369.658546 -179.276874) (xy 369.636752 -179.219401)
			(xy 369.622045 -179.15972) (xy 369.61464 -179.098701) (xy 369.614196 -179.067968) (xy 356.09276 -179.067968)
			(xy 356.09276 -182.115968) (xy 369.614196 -182.115968) (xy 369.614752 -182.08267) (xy 369.623426 -182.016641)
			(xy 369.640648 -181.95231) (xy 369.666122 -181.890779) (xy 369.699412 -181.833101) (xy 369.739949 -181.780263)
			(xy 369.787038 -181.733171) (xy 369.839873 -181.692631) (xy 369.86845 -181.675532) (xy 370.792502 -181.141878)
			(xy 370.82156 -181.125769) (xy 370.882966 -181.1004) (xy 370.947153 -181.083245) (xy 371.013028 -181.074597)
			(xy 371.046248 -181.07406) (xy 371.046756 -181.07406) (xy 371.077486 -181.074579) (xy 371.138498 -181.081982)
			(xy 371.198173 -181.096685) (xy 371.255641 -181.118475) (xy 371.310063 -181.147032) (xy 371.360647 -181.181941)
			(xy 371.406653 -181.222693) (xy 371.447412 -181.268694) (xy 371.482329 -181.319272) (xy 371.510894 -181.373689)
			(xy 371.532692 -181.431154) (xy 371.547404 -181.490827) (xy 371.554816 -181.551838) (xy 371.555264 -181.582568)
			(xy 371.554757 -181.615868) (xy 371.546077 -181.6819) (xy 371.538668 -181.709568) (xy 373.398796 -181.709568)
			(xy 373.399226 -181.678836) (xy 373.406638 -181.617821) (xy 373.421351 -181.558144) (xy 373.443149 -181.500676)
			(xy 373.471715 -181.446254) (xy 373.506633 -181.395671) (xy 373.547392 -181.349667) (xy 373.5934 -181.30891)
			(xy 373.643984 -181.273996) (xy 373.698409 -181.245434) (xy 373.755879 -181.22364) (xy 373.815556 -181.208932)
			(xy 373.876572 -181.201524) (xy 373.907304 -181.20106) (xy 373.907812 -181.20106) (xy 373.941031 -181.201606)
			(xy 374.006903 -181.210264) (xy 374.071088 -181.227419) (xy 374.132496 -181.252778) (xy 374.161558 -181.268878)
			(xy 375.08561 -181.802532) (xy 375.114171 -181.819654) (xy 375.166997 -181.860201) (xy 375.214079 -181.907295)
			(xy 375.254613 -181.96013) (xy 375.287906 -182.017802) (xy 375.313388 -182.079326) (xy 375.330623 -182.143649)
			(xy 375.339318 -182.209672) (xy 375.339864 -182.242968) (xy 375.339432 -182.273701) (xy 375.332026 -182.33472)
			(xy 375.317319 -182.3944) (xy 375.295524 -182.451873) (xy 375.266961 -182.506299) (xy 375.232044 -182.556885)
			(xy 375.191284 -182.602893) (xy 375.145275 -182.643651) (xy 375.094689 -182.678567) (xy 375.040262 -182.707129)
			(xy 374.982789 -182.728923) (xy 374.923108 -182.743629) (xy 374.862089 -182.751033) (xy 374.831356 -182.751476)
			(xy 374.830848 -182.751476) (xy 374.797629 -182.750942) (xy 374.731757 -182.74228) (xy 374.667571 -182.725122)
			(xy 374.606164 -182.699759) (xy 374.577102 -182.683658) (xy 373.65305 -182.150004) (xy 373.624495 -182.132872)
			(xy 373.571672 -182.092325) (xy 373.524591 -182.045232) (xy 373.484057 -181.992398) (xy 373.450764 -181.934727)
			(xy 373.42528 -181.873205) (xy 373.408042 -181.808884) (xy 373.399344 -181.742863) (xy 373.398796 -181.709568)
			(xy 371.538668 -181.709568) (xy 371.52885 -181.746232) (xy 371.503369 -181.807765) (xy 371.470072 -181.865443)
			(xy 371.429528 -181.91828) (xy 371.382432 -181.96537) (xy 371.329591 -182.005907) (xy 371.30101 -182.023004)
			(xy 370.376958 -182.556658) (xy 370.34791 -182.572786) (xy 370.2865 -182.59815) (xy 370.22231 -182.615299)
			(xy 370.156433 -182.623942) (xy 370.123212 -182.624476) (xy 370.122704 -182.624476) (xy 370.091971 -182.624059)
			(xy 370.030952 -182.61665) (xy 369.971272 -182.60194) (xy 369.9138 -182.580143) (xy 369.859375 -182.551577)
			(xy 369.808789 -182.516659) (xy 369.762782 -182.475898) (xy 369.722023 -182.429889) (xy 369.687108 -182.379301)
			(xy 369.658546 -182.324874) (xy 369.636752 -182.267401) (xy 369.622045 -182.20772) (xy 369.61464 -182.146701)
			(xy 369.614196 -182.115968) (xy 356.09276 -182.115968) (xy 356.09276 -185.011568) (xy 372.585996 -185.011568)
			(xy 372.586426 -184.980836) (xy 372.593838 -184.919821) (xy 372.608551 -184.860144) (xy 372.630349 -184.802676)
			(xy 372.658915 -184.748254) (xy 372.693833 -184.697671) (xy 372.734592 -184.651667) (xy 372.7806 -184.61091)
			(xy 372.831184 -184.575996) (xy 372.885609 -184.547434) (xy 372.943079 -184.52564) (xy 373.002756 -184.510932)
			(xy 373.063772 -184.503524) (xy 373.094504 -184.50306) (xy 373.095012 -184.50306) (xy 373.128231 -184.503606)
			(xy 373.194103 -184.512264) (xy 373.258288 -184.529419) (xy 373.319696 -184.554778) (xy 373.348758 -184.570878)
			(xy 374.27281 -185.104532) (xy 374.301371 -185.121654) (xy 374.354197 -185.162201) (xy 374.401279 -185.209295)
			(xy 374.441813 -185.26213) (xy 374.475106 -185.319802) (xy 374.500588 -185.381326) (xy 374.517823 -185.445649)
			(xy 374.526518 -185.511672) (xy 374.527064 -185.544968) (xy 374.526632 -185.575701) (xy 374.519226 -185.63672)
			(xy 374.504519 -185.6964) (xy 374.482724 -185.753873) (xy 374.454161 -185.808299) (xy 374.419244 -185.858885)
			(xy 374.378484 -185.904893) (xy 374.332475 -185.945651) (xy 374.281889 -185.980567) (xy 374.227462 -186.009129)
			(xy 374.169989 -186.030923) (xy 374.110308 -186.045629) (xy 374.049289 -186.053033) (xy 374.018556 -186.053476)
			(xy 374.018048 -186.053476) (xy 373.984829 -186.052942) (xy 373.918957 -186.04428) (xy 373.854771 -186.027122)
			(xy 373.793364 -186.001759) (xy 373.764302 -185.985658) (xy 372.84025 -185.452004) (xy 372.811695 -185.434872)
			(xy 372.758872 -185.394325) (xy 372.711791 -185.347232) (xy 372.671257 -185.294398) (xy 372.637964 -185.236727)
			(xy 372.61248 -185.175205) (xy 372.595242 -185.110884) (xy 372.586544 -185.044863) (xy 372.585996 -185.011568)
			(xy 356.09276 -185.011568) (xy 356.09276 -188.140848) (xy 356.092184 -188.165806) (xy 356.082436 -188.214762)
			(xy 356.063323 -188.260875) (xy 356.035582 -188.302373) (xy 356.018338 -188.320426) (xy 355.378258 -188.960506)
			(xy 355.360218 -188.977768) (xy 355.318725 -189.00553) (xy 355.272607 -189.024646) (xy 355.223642 -189.03438)
			(xy 355.19868 -189.034928) (xy 349.807276 -189.034928) (xy 349.387668 -189.454536) (xy 349.387668 -213.36381)
			(xy 349.388082 -213.377258) (xy 349.395115 -213.403219) (xy 349.408688 -213.42644) (xy 349.427858 -213.445306)
			(xy 349.451294 -213.458505) (xy 349.477364 -213.465121) (xy 349.504257 -213.464692) (xy 349.530103 -213.45725)
			(xy 349.541846 -213.450678) (xy 349.567713 -213.435797) (xy 349.623502 -213.414629) (xy 349.682191 -213.403853)
			(xy 349.712026 -213.40318) (xy 349.712534 -213.40318) (xy 349.738419 -213.40369) (xy 349.789551 -213.411794)
			(xy 349.838786 -213.427796) (xy 349.884912 -213.451304) (xy 349.926792 -213.481737) (xy 349.963397 -213.518347)
			(xy 349.993823 -213.560232) (xy 350.017324 -213.606362) (xy 350.033318 -213.655599) (xy 350.041414 -213.706733)
			(xy 350.041972 -213.732618) (xy 351.262696 -213.732618) (xy 351.263204 -213.706731) (xy 351.271303 -213.655593)
			(xy 351.287302 -213.606353) (xy 351.310808 -213.560221) (xy 351.34124 -213.518334) (xy 351.37785 -213.481724)
			(xy 351.419737 -213.451292) (xy 351.465869 -213.427786) (xy 351.515109 -213.411787) (xy 351.566247 -213.403688)
			(xy 351.618021 -213.403688) (xy 351.669159 -213.411787) (xy 351.718399 -213.427786) (xy 351.764531 -213.451292)
			(xy 351.806418 -213.481724) (xy 351.843028 -213.518334) (xy 351.87346 -213.560221) (xy 351.896966 -213.606353)
			(xy 351.912965 -213.655593) (xy 351.921064 -213.706731) (xy 351.921572 -213.732618) (xy 353.142296 -213.732618)
			(xy 353.142804 -213.706731) (xy 353.150903 -213.655593) (xy 353.166902 -213.606353) (xy 353.190408 -213.560221)
			(xy 353.22084 -213.518334) (xy 353.25745 -213.481724) (xy 353.299337 -213.451292) (xy 353.345469 -213.427786)
			(xy 353.394709 -213.411787) (xy 353.445847 -213.403688) (xy 353.497621 -213.403688) (xy 353.548759 -213.411787)
			(xy 353.597999 -213.427786) (xy 353.644131 -213.451292) (xy 353.686018 -213.481724) (xy 353.722628 -213.518334)
			(xy 353.75306 -213.560221) (xy 353.776566 -213.606353) (xy 353.792565 -213.655593) (xy 353.800664 -213.706731)
			(xy 353.801172 -213.732618) (xy 355.021896 -213.732618) (xy 355.022404 -213.706731) (xy 355.030503 -213.655593)
			(xy 355.046502 -213.606353) (xy 355.070008 -213.560221) (xy 355.10044 -213.518334) (xy 355.13705 -213.481724)
			(xy 355.178937 -213.451292) (xy 355.225069 -213.427786) (xy 355.274309 -213.411787) (xy 355.325447 -213.403688)
			(xy 355.377221 -213.403688) (xy 355.428359 -213.411787) (xy 355.477599 -213.427786) (xy 355.523731 -213.451292)
			(xy 355.565618 -213.481724) (xy 355.602228 -213.518334) (xy 355.63266 -213.560221) (xy 355.656166 -213.606353)
			(xy 355.672165 -213.655593) (xy 355.680264 -213.706731) (xy 355.680772 -213.732618) (xy 355.680423 -213.755595)
			(xy 355.674102 -213.801111) (xy 355.661516 -213.845306) (xy 355.652578 -213.866476) (xy 355.642672 -213.888828)
			(xy 355.856286 -214.293958) (xy 355.880416 -214.29853) (xy 355.90533 -214.303664) (xy 355.95334 -214.320459)
			(xy 355.998199 -214.344434) (xy 356.038841 -214.375017) (xy 356.074299 -214.411484) (xy 356.103732 -214.452967)
			(xy 356.12644 -214.49848) (xy 356.141883 -214.546942) (xy 356.149695 -214.597202) (xy 356.150164 -214.622634)
			(xy 356.149656 -214.648521) (xy 356.141557 -214.699659) (xy 356.125558 -214.748899) (xy 356.102052 -214.795031)
			(xy 356.07162 -214.836918) (xy 356.03501 -214.873528) (xy 355.993123 -214.90396) (xy 355.946991 -214.927466)
			(xy 355.897751 -214.943465) (xy 355.846613 -214.951564) (xy 355.794839 -214.951564) (xy 355.743701 -214.943465)
			(xy 355.694461 -214.927466) (xy 355.648329 -214.90396) (xy 355.606442 -214.873528) (xy 355.569832 -214.836918)
			(xy 355.5394 -214.795031) (xy 355.515894 -214.748899) (xy 355.499895 -214.699659) (xy 355.491796 -214.648521)
			(xy 355.491288 -214.622634) (xy 355.491658 -214.599658) (xy 355.49797 -214.554143) (xy 355.510548 -214.509947)
			(xy 355.519482 -214.488776) (xy 355.529388 -214.466424) (xy 355.315774 -214.061294) (xy 355.291644 -214.056722)
			(xy 355.266713 -214.051663) (xy 355.218699 -214.034858) (xy 355.173839 -214.010874) (xy 355.133197 -213.980281)
			(xy 355.097739 -213.943805) (xy 355.068309 -213.902313) (xy 355.045605 -213.856791) (xy 355.030167 -213.80832)
			(xy 355.022362 -213.758053) (xy 355.021896 -213.732618) (xy 353.801172 -213.732618) (xy 353.800823 -213.755595)
			(xy 353.794502 -213.801111) (xy 353.781916 -213.845306) (xy 353.772978 -213.866476) (xy 353.763072 -213.888828)
			(xy 353.976686 -214.293958) (xy 354.000816 -214.29853) (xy 354.02573 -214.303664) (xy 354.07374 -214.320459)
			(xy 354.118599 -214.344434) (xy 354.159241 -214.375017) (xy 354.194699 -214.411484) (xy 354.224132 -214.452967)
			(xy 354.24684 -214.49848) (xy 354.262283 -214.546942) (xy 354.270095 -214.597202) (xy 354.270564 -214.622634)
			(xy 354.270056 -214.648521) (xy 354.261957 -214.699659) (xy 354.245958 -214.748899) (xy 354.222452 -214.795031)
			(xy 354.19202 -214.836918) (xy 354.15541 -214.873528) (xy 354.113523 -214.90396) (xy 354.067391 -214.927466)
			(xy 354.018151 -214.943465) (xy 353.967013 -214.951564) (xy 353.915239 -214.951564) (xy 353.864101 -214.943465)
			(xy 353.814861 -214.927466) (xy 353.768729 -214.90396) (xy 353.726842 -214.873528) (xy 353.690232 -214.836918)
			(xy 353.6598 -214.795031) (xy 353.636294 -214.748899) (xy 353.620295 -214.699659) (xy 353.612196 -214.648521)
			(xy 353.611688 -214.622634) (xy 353.612058 -214.599658) (xy 353.61837 -214.554143) (xy 353.630948 -214.509947)
			(xy 353.639882 -214.488776) (xy 353.649788 -214.466424) (xy 353.436174 -214.061294) (xy 353.412044 -214.056722)
			(xy 353.387113 -214.051663) (xy 353.339099 -214.034858) (xy 353.294239 -214.010874) (xy 353.253597 -213.980281)
			(xy 353.218139 -213.943805) (xy 353.188709 -213.902313) (xy 353.166005 -213.856791) (xy 353.150567 -213.80832)
			(xy 353.142762 -213.758053) (xy 353.142296 -213.732618) (xy 351.921572 -213.732618) (xy 351.921223 -213.755595)
			(xy 351.914902 -213.801111) (xy 351.902316 -213.845306) (xy 351.893378 -213.866476) (xy 351.883472 -213.888828)
			(xy 352.097086 -214.293958) (xy 352.121216 -214.29853) (xy 352.14613 -214.303664) (xy 352.19414 -214.320459)
			(xy 352.238999 -214.344434) (xy 352.279641 -214.375017) (xy 352.315099 -214.411484) (xy 352.344532 -214.452967)
			(xy 352.36724 -214.49848) (xy 352.382683 -214.546942) (xy 352.390495 -214.597202) (xy 352.390964 -214.622634)
			(xy 352.390456 -214.648521) (xy 352.382357 -214.699659) (xy 352.366358 -214.748899) (xy 352.342852 -214.795031)
			(xy 352.31242 -214.836918) (xy 352.27581 -214.873528) (xy 352.233923 -214.90396) (xy 352.187791 -214.927466)
			(xy 352.138551 -214.943465) (xy 352.087413 -214.951564) (xy 352.035639 -214.951564) (xy 351.984501 -214.943465)
			(xy 351.935261 -214.927466) (xy 351.889129 -214.90396) (xy 351.847242 -214.873528) (xy 351.810632 -214.836918)
			(xy 351.7802 -214.795031) (xy 351.756694 -214.748899) (xy 351.740695 -214.699659) (xy 351.732596 -214.648521)
			(xy 351.732088 -214.622634) (xy 351.732458 -214.599658) (xy 351.73877 -214.554143) (xy 351.751348 -214.509947)
			(xy 351.760282 -214.488776) (xy 351.770188 -214.466424) (xy 351.556574 -214.061294) (xy 351.532444 -214.056722)
			(xy 351.507513 -214.051663) (xy 351.459499 -214.034858) (xy 351.414639 -214.010874) (xy 351.373997 -213.980281)
			(xy 351.338539 -213.943805) (xy 351.309109 -213.902313) (xy 351.286405 -213.856791) (xy 351.270967 -213.80832)
			(xy 351.263162 -213.758053) (xy 351.262696 -213.732618) (xy 350.041972 -213.732618) (xy 350.041607 -213.755594)
			(xy 350.035288 -213.801108) (xy 350.022706 -213.845303) (xy 350.013778 -213.866476) (xy 350.003872 -213.888828)
			(xy 350.217486 -214.293958) (xy 350.241616 -214.29853) (xy 350.266536 -214.303621) (xy 350.314534 -214.320446)
			(xy 350.359379 -214.34444) (xy 350.400008 -214.375035) (xy 350.435459 -214.411506) (xy 350.46489 -214.452987)
			(xy 350.487603 -214.498494) (xy 350.50306 -214.54695) (xy 350.510894 -214.597204) (xy 350.511364 -214.622634)
			(xy 350.510856 -214.648521) (xy 350.502757 -214.699659) (xy 350.486758 -214.748899) (xy 350.463252 -214.795031)
			(xy 350.43282 -214.836918) (xy 350.39621 -214.873528) (xy 350.354323 -214.90396) (xy 350.308191 -214.927466)
			(xy 350.258951 -214.943465) (xy 350.207813 -214.951564) (xy 350.156039 -214.951564) (xy 350.104901 -214.943465)
			(xy 350.055661 -214.927466) (xy 350.009529 -214.90396) (xy 349.967642 -214.873528) (xy 349.931032 -214.836918)
			(xy 349.9006 -214.795031) (xy 349.877094 -214.748899) (xy 349.861095 -214.699659) (xy 349.852996 -214.648521)
			(xy 349.852488 -214.622634) (xy 349.85285 -214.599657) (xy 349.859163 -214.554141) (xy 349.871741 -214.509944)
			(xy 349.880682 -214.488776) (xy 349.890588 -214.466424) (xy 349.676974 -214.061294) (xy 349.652844 -214.056722)
			(xy 349.623588 -214.05067) (xy 349.567745 -214.029451) (xy 349.541846 -214.014558) (xy 349.530127 -214.007956)
			(xy 349.504281 -214.000541) (xy 349.477396 -214.000132) (xy 349.451337 -214.006758) (xy 349.427912 -214.01996)
			(xy 349.408748 -214.038821) (xy 349.395175 -214.062032) (xy 349.388134 -214.087982) (xy 349.387668 -214.101426)
			(xy 349.387668 -214.326978) (xy 349.410954 -214.339025) (xy 349.453711 -214.36936) (xy 349.491127 -214.406081)
			(xy 349.522258 -214.448262) (xy 349.54632 -214.494839) (xy 349.562706 -214.544638) (xy 349.571002 -214.596402)
			(xy 349.570999 -214.648828) (xy 349.562698 -214.700591) (xy 349.546308 -214.750389) (xy 349.522242 -214.796963)
			(xy 349.491107 -214.839141) (xy 349.453688 -214.875859) (xy 349.410928 -214.906191) (xy 349.387668 -214.91829)
			(xy 349.387668 -215.436704) (xy 350.322388 -215.436704) (xy 350.322923 -215.411361) (xy 350.330693 -215.361274)
			(xy 350.346037 -215.312966) (xy 350.368592 -215.267575) (xy 350.397827 -215.226169) (xy 350.433054 -215.189725)
			(xy 350.473443 -215.159101) (xy 350.518042 -215.135018) (xy 350.565801 -215.118043) (xy 350.590612 -215.112854)
			(xy 350.613472 -215.108536) (xy 350.81845 -214.753444) (xy 350.810576 -214.7316) (xy 350.801999 -214.705181)
			(xy 350.7928 -214.650406) (xy 350.792288 -214.622634) (xy 350.792796 -214.596747) (xy 350.800895 -214.545609)
			(xy 350.816894 -214.496369) (xy 350.8404 -214.450237) (xy 350.870832 -214.40835) (xy 350.907442 -214.37174)
			(xy 350.949329 -214.341308) (xy 350.995461 -214.317802) (xy 351.044701 -214.301803) (xy 351.095839 -214.293704)
			(xy 351.147613 -214.293704) (xy 351.198751 -214.301803) (xy 351.247991 -214.317802) (xy 351.294123 -214.341308)
			(xy 351.33601 -214.37174) (xy 351.37262 -214.40835) (xy 351.403052 -214.450237) (xy 351.426558 -214.496369)
			(xy 351.442557 -214.545609) (xy 351.450656 -214.596747) (xy 351.451164 -214.622634) (xy 351.450741 -214.647971)
			(xy 351.442983 -214.698047) (xy 351.427654 -214.746347) (xy 351.405115 -214.791733) (xy 351.375898 -214.833136)
			(xy 351.34069 -214.869581) (xy 351.30032 -214.90021) (xy 351.255739 -214.924301) (xy 351.207997 -214.941288)
			(xy 351.183194 -214.946484) (xy 351.160334 -214.950802) (xy 350.955356 -215.305894) (xy 350.96323 -215.327738)
			(xy 350.971877 -215.354146) (xy 350.981197 -215.408922) (xy 350.981772 -215.436704) (xy 352.201988 -215.436704)
			(xy 352.202523 -215.411361) (xy 352.210293 -215.361274) (xy 352.225637 -215.312966) (xy 352.248192 -215.267575)
			(xy 352.277427 -215.226169) (xy 352.312654 -215.189725) (xy 352.353043 -215.159101) (xy 352.397642 -215.135018)
			(xy 352.445401 -215.118043) (xy 352.470212 -215.112854) (xy 352.493072 -215.108536) (xy 352.69805 -214.753444)
			(xy 352.690176 -214.7316) (xy 352.681599 -214.705181) (xy 352.6724 -214.650406) (xy 352.671888 -214.622634)
			(xy 352.672396 -214.596747) (xy 352.680495 -214.545609) (xy 352.696494 -214.496369) (xy 352.72 -214.450237)
			(xy 352.750432 -214.40835) (xy 352.787042 -214.37174) (xy 352.828929 -214.341308) (xy 352.875061 -214.317802)
			(xy 352.924301 -214.301803) (xy 352.975439 -214.293704) (xy 353.027213 -214.293704) (xy 353.078351 -214.301803)
			(xy 353.127591 -214.317802) (xy 353.173723 -214.341308) (xy 353.21561 -214.37174) (xy 353.25222 -214.40835)
			(xy 353.282652 -214.450237) (xy 353.306158 -214.496369) (xy 353.322157 -214.545609) (xy 353.330256 -214.596747)
			(xy 353.330764 -214.622634) (xy 353.330341 -214.647971) (xy 353.322583 -214.698047) (xy 353.307254 -214.746347)
			(xy 353.284715 -214.791733) (xy 353.255498 -214.833136) (xy 353.22029 -214.869581) (xy 353.17992 -214.90021)
			(xy 353.135339 -214.924301) (xy 353.087597 -214.941288) (xy 353.062794 -214.946484) (xy 353.039934 -214.950802)
			(xy 352.834956 -215.305894) (xy 352.84283 -215.327738) (xy 352.851477 -215.354146) (xy 352.860797 -215.408922)
			(xy 352.861372 -215.436704) (xy 354.081588 -215.436704) (xy 354.082123 -215.411361) (xy 354.089893 -215.361274)
			(xy 354.105237 -215.312966) (xy 354.127792 -215.267575) (xy 354.157027 -215.226169) (xy 354.192254 -215.189725)
			(xy 354.232643 -215.159101) (xy 354.277242 -215.135018) (xy 354.325001 -215.118043) (xy 354.349812 -215.112854)
			(xy 354.372672 -215.108536) (xy 354.57765 -214.753444) (xy 354.569776 -214.7316) (xy 354.561199 -214.705181)
			(xy 354.552 -214.650406) (xy 354.551488 -214.622634) (xy 354.551996 -214.596747) (xy 354.560095 -214.545609)
			(xy 354.576094 -214.496369) (xy 354.5996 -214.450237) (xy 354.630032 -214.40835) (xy 354.666642 -214.37174)
			(xy 354.708529 -214.341308) (xy 354.754661 -214.317802) (xy 354.803901 -214.301803) (xy 354.855039 -214.293704)
			(xy 354.906813 -214.293704) (xy 354.957951 -214.301803) (xy 355.007191 -214.317802) (xy 355.053323 -214.341308)
			(xy 355.09521 -214.37174) (xy 355.13182 -214.40835) (xy 355.162252 -214.450237) (xy 355.185758 -214.496369)
			(xy 355.201757 -214.545609) (xy 355.209856 -214.596747) (xy 355.210364 -214.622634) (xy 355.209941 -214.647971)
			(xy 355.202183 -214.698047) (xy 355.186854 -214.746347) (xy 355.164315 -214.791733) (xy 355.135098 -214.833136)
			(xy 355.09989 -214.869581) (xy 355.05952 -214.90021) (xy 355.014939 -214.924301) (xy 354.967197 -214.941288)
			(xy 354.942394 -214.946484) (xy 354.919534 -214.950802) (xy 354.714556 -215.305894) (xy 354.72243 -215.327738)
			(xy 354.731077 -215.354146) (xy 354.740397 -215.408922) (xy 354.740972 -215.436704) (xy 355.961188 -215.436704)
			(xy 355.961723 -215.411361) (xy 355.969493 -215.361274) (xy 355.984837 -215.312966) (xy 356.007392 -215.267575)
			(xy 356.036627 -215.226169) (xy 356.071854 -215.189725) (xy 356.112243 -215.159101) (xy 356.156842 -215.135018)
			(xy 356.204601 -215.118043) (xy 356.229412 -215.112854) (xy 356.252272 -215.108536) (xy 356.45725 -214.753444)
			(xy 356.449376 -214.7316) (xy 356.440799 -214.705181) (xy 356.4316 -214.650406) (xy 356.431088 -214.622634)
			(xy 356.431596 -214.596747) (xy 356.439695 -214.545609) (xy 356.455694 -214.496369) (xy 356.4792 -214.450237)
			(xy 356.509632 -214.40835) (xy 356.546242 -214.37174) (xy 356.588129 -214.341308) (xy 356.634261 -214.317802)
			(xy 356.683501 -214.301803) (xy 356.734639 -214.293704) (xy 356.786413 -214.293704) (xy 356.837551 -214.301803)
			(xy 356.886791 -214.317802) (xy 356.932923 -214.341308) (xy 356.97481 -214.37174) (xy 357.01142 -214.40835)
			(xy 357.041852 -214.450237) (xy 357.065358 -214.496369) (xy 357.081357 -214.545609) (xy 357.089456 -214.596747)
			(xy 357.089964 -214.622634) (xy 358.310688 -214.622634) (xy 358.311196 -214.596747) (xy 358.319295 -214.545609)
			(xy 358.335294 -214.496369) (xy 358.3588 -214.450237) (xy 358.389232 -214.40835) (xy 358.425842 -214.37174)
			(xy 358.467729 -214.341308) (xy 358.513861 -214.317802) (xy 358.563101 -214.301803) (xy 358.614239 -214.293704)
			(xy 358.666013 -214.293704) (xy 358.717151 -214.301803) (xy 358.766391 -214.317802) (xy 358.812523 -214.341308)
			(xy 358.85441 -214.37174) (xy 358.89102 -214.40835) (xy 358.921452 -214.450237) (xy 358.944958 -214.496369)
			(xy 358.960957 -214.545609) (xy 358.969056 -214.596747) (xy 358.969564 -214.622634) (xy 358.969564 -214.623142)
			(xy 358.968984 -214.650659) (xy 358.959791 -214.70492) (xy 358.951276 -214.731092) (xy 358.943656 -214.75319)
			(xy 359.148888 -215.108536) (xy 359.171748 -215.112854) (xy 359.196559 -215.118062) (xy 359.244336 -215.135013)
			(xy 359.288953 -215.15908) (xy 359.329358 -215.189696) (xy 359.364599 -215.226137) (xy 359.393844 -215.267545)
			(xy 359.416403 -215.312943) (xy 359.431745 -215.36126) (xy 359.439507 -215.411357) (xy 359.439972 -215.436704)
			(xy 359.439464 -215.462611) (xy 359.431358 -215.513788) (xy 359.415346 -215.563067) (xy 359.391823 -215.609234)
			(xy 359.361367 -215.651153) (xy 359.324729 -215.687791) (xy 359.28281 -215.718247) (xy 359.236643 -215.74177)
			(xy 359.187364 -215.757782) (xy 359.136187 -215.765888) (xy 359.084373 -215.765888) (xy 359.033196 -215.757782)
			(xy 358.983917 -215.74177) (xy 358.93775 -215.718247) (xy 358.895831 -215.687791) (xy 358.859193 -215.651153)
			(xy 358.828737 -215.609234) (xy 358.805214 -215.563067) (xy 358.789202 -215.513788) (xy 358.781096 -215.462611)
			(xy 358.780588 -215.436704) (xy 358.781184 -215.408987) (xy 358.790506 -215.35434) (xy 358.79913 -215.327992)
			(xy 358.80675 -215.306148) (xy 358.601772 -214.950802) (xy 358.578912 -214.946484) (xy 358.554096 -214.941291)
			(xy 358.506315 -214.924344) (xy 358.461694 -214.900279) (xy 358.421285 -214.869663) (xy 358.386043 -214.833219)
			(xy 358.356798 -214.791807) (xy 358.33424 -214.746405) (xy 358.318903 -214.698083) (xy 358.311148 -214.647983)
			(xy 358.310688 -214.622634) (xy 357.089964 -214.622634) (xy 357.089541 -214.647971) (xy 357.081783 -214.698047)
			(xy 357.066454 -214.746347) (xy 357.043915 -214.791733) (xy 357.014698 -214.833136) (xy 356.97949 -214.869581)
			(xy 356.93912 -214.90021) (xy 356.894539 -214.924301) (xy 356.846797 -214.941288) (xy 356.821994 -214.946484)
			(xy 356.799134 -214.950802) (xy 356.594156 -215.305894) (xy 356.60203 -215.327738) (xy 356.610677 -215.354146)
			(xy 356.619997 -215.408922) (xy 356.620572 -215.436704) (xy 356.620064 -215.462606) (xy 356.90152 -215.462606)
			(xy 356.90152 -215.410794) (xy 356.909625 -215.35962) (xy 356.925635 -215.310344) (xy 356.949157 -215.264178)
			(xy 356.97961 -215.222261) (xy 357.016246 -215.185623) (xy 357.058161 -215.155167) (xy 357.104325 -215.131643)
			(xy 357.1536 -215.11563) (xy 357.204774 -215.107522) (xy 357.23068 -215.107012) (xy 357.256191 -215.107502)
			(xy 357.306606 -215.11536) (xy 357.355207 -215.130891) (xy 357.400836 -215.153725) (xy 357.442402 -215.183316)
			(xy 357.478912 -215.218958) (xy 357.494586 -215.239092) (xy 357.906574 -215.239092) (xy 357.92226 -215.218967)
			(xy 357.958768 -215.183323) (xy 358.000331 -215.153729) (xy 358.045956 -215.130891) (xy 358.094556 -215.115355)
			(xy 358.144969 -215.107491) (xy 358.17048 -215.107012) (xy 358.196391 -215.107484) (xy 358.247575 -215.115588)
			(xy 358.296861 -215.131599) (xy 358.343035 -215.155124) (xy 358.38496 -215.185582) (xy 358.421605 -215.222224)
			(xy 358.452066 -215.264148) (xy 358.475593 -215.310321) (xy 358.491607 -215.359606) (xy 358.499714 -215.410789)
			(xy 358.499714 -215.462611) (xy 358.491607 -215.513794) (xy 358.475593 -215.563079) (xy 358.452066 -215.609252)
			(xy 358.421605 -215.651176) (xy 358.38496 -215.687818) (xy 358.343035 -215.718276) (xy 358.296861 -215.741801)
			(xy 358.247575 -215.757812) (xy 358.196391 -215.765916) (xy 358.17048 -215.766396) (xy 358.144968 -215.765932)
			(xy 358.094552 -215.758068) (xy 358.04595 -215.742532) (xy 358.000322 -215.719693) (xy 357.958757 -215.690098)
			(xy 357.922247 -215.654452) (xy 357.906574 -215.634316) (xy 357.494586 -215.634316) (xy 357.478925 -215.654461)
			(xy 357.442412 -215.690104) (xy 357.400844 -215.719696) (xy 357.355213 -215.74253) (xy 357.306609 -215.758062)
			(xy 357.256193 -215.76592) (xy 357.23068 -215.766396) (xy 357.204774 -215.765878) (xy 357.1536 -215.75777)
			(xy 357.104325 -215.741757) (xy 357.058161 -215.718233) (xy 357.016246 -215.687777) (xy 356.97961 -215.651139)
			(xy 356.949157 -215.609222) (xy 356.925635 -215.563056) (xy 356.909625 -215.51378) (xy 356.90152 -215.462606)
			(xy 356.620064 -215.462606) (xy 356.620064 -215.462611) (xy 356.611958 -215.513788) (xy 356.595946 -215.563067)
			(xy 356.572423 -215.609234) (xy 356.541967 -215.651153) (xy 356.505329 -215.687791) (xy 356.46341 -215.718247)
			(xy 356.417243 -215.74177) (xy 356.367964 -215.757782) (xy 356.316787 -215.765888) (xy 356.264973 -215.765888)
			(xy 356.213796 -215.757782) (xy 356.164517 -215.74177) (xy 356.11835 -215.718247) (xy 356.076431 -215.687791)
			(xy 356.039793 -215.651153) (xy 356.009337 -215.609234) (xy 355.985814 -215.563067) (xy 355.969802 -215.513788)
			(xy 355.961696 -215.462611) (xy 355.961188 -215.436704) (xy 354.740972 -215.436704) (xy 354.740464 -215.462611)
			(xy 354.732358 -215.513788) (xy 354.716346 -215.563067) (xy 354.692823 -215.609234) (xy 354.662367 -215.651153)
			(xy 354.625729 -215.687791) (xy 354.58381 -215.718247) (xy 354.537643 -215.74177) (xy 354.488364 -215.757782)
			(xy 354.437187 -215.765888) (xy 354.385373 -215.765888) (xy 354.334196 -215.757782) (xy 354.284917 -215.74177)
			(xy 354.23875 -215.718247) (xy 354.196831 -215.687791) (xy 354.160193 -215.651153) (xy 354.129737 -215.609234)
			(xy 354.106214 -215.563067) (xy 354.090202 -215.513788) (xy 354.082096 -215.462611) (xy 354.081588 -215.436704)
			(xy 352.861372 -215.436704) (xy 352.860864 -215.462611) (xy 352.852758 -215.513788) (xy 352.836746 -215.563067)
			(xy 352.813223 -215.609234) (xy 352.782767 -215.651153) (xy 352.746129 -215.687791) (xy 352.70421 -215.718247)
			(xy 352.658043 -215.74177) (xy 352.608764 -215.757782) (xy 352.557587 -215.765888) (xy 352.505773 -215.765888)
			(xy 352.454596 -215.757782) (xy 352.405317 -215.74177) (xy 352.35915 -215.718247) (xy 352.317231 -215.687791)
			(xy 352.280593 -215.651153) (xy 352.250137 -215.609234) (xy 352.226614 -215.563067) (xy 352.210602 -215.513788)
			(xy 352.202496 -215.462611) (xy 352.201988 -215.436704) (xy 350.981772 -215.436704) (xy 350.981264 -215.462611)
			(xy 350.973158 -215.513788) (xy 350.957146 -215.563067) (xy 350.933623 -215.609234) (xy 350.903167 -215.651153)
			(xy 350.866529 -215.687791) (xy 350.82461 -215.718247) (xy 350.778443 -215.74177) (xy 350.729164 -215.757782)
			(xy 350.677987 -215.765888) (xy 350.626173 -215.765888) (xy 350.574996 -215.757782) (xy 350.525717 -215.74177)
			(xy 350.47955 -215.718247) (xy 350.437631 -215.687791) (xy 350.400993 -215.651153) (xy 350.370537 -215.609234)
			(xy 350.347014 -215.563067) (xy 350.331002 -215.513788) (xy 350.322896 -215.462611) (xy 350.322388 -215.436704)
			(xy 349.387668 -215.436704) (xy 349.387668 -215.956134) (xy 349.410859 -215.968125) (xy 349.453444 -215.998326)
			(xy 349.490709 -216.034888) (xy 349.521716 -216.076888) (xy 349.545682 -216.123268) (xy 349.562003 -216.172858)
			(xy 349.570267 -216.224406) (xy 349.570266 -216.276612) (xy 349.561999 -216.328159) (xy 349.545676 -216.377748)
			(xy 349.521707 -216.424127) (xy 349.490697 -216.466126) (xy 349.45343 -216.502686) (xy 349.410844 -216.532884)
			(xy 349.387668 -216.544906) (xy 349.387668 -216.695528) (xy 349.388072 -216.708984) (xy 349.395092 -216.734965)
			(xy 349.408661 -216.758206) (xy 349.427836 -216.777089) (xy 349.451282 -216.790301) (xy 349.477367 -216.796921)
			(xy 349.504276 -216.796489) (xy 349.530135 -216.789036) (xy 349.541846 -216.782396) (xy 349.567738 -216.767448)
			(xy 349.623603 -216.746165) (xy 349.68239 -216.735308) (xy 349.71228 -216.734644) (xy 349.738189 -216.735125)
			(xy 349.78937 -216.743229) (xy 349.838653 -216.75924) (xy 349.884825 -216.782765) (xy 349.926747 -216.813223)
			(xy 349.963387 -216.849866) (xy 349.993844 -216.891789) (xy 350.017366 -216.937961) (xy 350.033375 -216.987245)
			(xy 350.041477 -217.038427) (xy 350.041972 -217.064336) (xy 350.041512 -217.089686) (xy 350.033757 -217.139789)
			(xy 350.018421 -217.188114) (xy 349.995865 -217.233519) (xy 349.966622 -217.274935) (xy 349.931381 -217.311384)
			(xy 349.890973 -217.342006) (xy 349.846353 -217.366079) (xy 349.798573 -217.383035) (xy 349.773748 -217.388186)
			(xy 349.750888 -217.392504) (xy 349.54591 -217.747596) (xy 349.553784 -217.76944) (xy 349.562358 -217.79586)
			(xy 349.571542 -217.850635) (xy 349.572072 -217.878406) (xy 349.852996 -217.878406) (xy 349.853504 -217.852519)
			(xy 349.861603 -217.801381) (xy 349.877602 -217.752141) (xy 349.901108 -217.706009) (xy 349.93154 -217.664122)
			(xy 349.96815 -217.627512) (xy 350.010037 -217.59708) (xy 350.056169 -217.573574) (xy 350.105409 -217.557575)
			(xy 350.156547 -217.549476) (xy 350.208321 -217.549476) (xy 350.259459 -217.557575) (xy 350.308699 -217.573574)
			(xy 350.354831 -217.59708) (xy 350.396718 -217.627512) (xy 350.433328 -217.664122) (xy 350.46376 -217.706009)
			(xy 350.487266 -217.752141) (xy 350.503265 -217.801381) (xy 350.511364 -217.852519) (xy 350.511872 -217.878406)
			(xy 350.792796 -217.878406) (xy 350.793288 -217.853072) (xy 350.801039 -217.803) (xy 350.81636 -217.754704)
			(xy 350.838891 -217.70932) (xy 350.868099 -217.667918) (xy 350.903299 -217.631473) (xy 350.94366 -217.600842)
			(xy 350.988233 -217.576747) (xy 351.035967 -217.559756) (xy 351.060766 -217.554556) (xy 351.083626 -217.550238)
			(xy 351.288604 -217.195146) (xy 351.28073 -217.173302) (xy 351.272091 -217.146892) (xy 351.262767 -217.092117)
			(xy 351.262188 -217.064336) (xy 351.262696 -217.038429) (xy 351.270802 -216.987252) (xy 351.286814 -216.937973)
			(xy 351.310337 -216.891806) (xy 351.340793 -216.849887) (xy 351.377431 -216.813249) (xy 351.41935 -216.782793)
			(xy 351.465517 -216.75927) (xy 351.514796 -216.743258) (xy 351.565973 -216.735152) (xy 351.617787 -216.735152)
			(xy 351.668964 -216.743258) (xy 351.718243 -216.75927) (xy 351.76441 -216.782793) (xy 351.806329 -216.813249)
			(xy 351.842967 -216.849887) (xy 351.873423 -216.891806) (xy 351.896946 -216.937973) (xy 351.912958 -216.987252)
			(xy 351.921064 -217.038429) (xy 351.921572 -217.064336) (xy 351.921106 -217.089682) (xy 351.913328 -217.139773)
			(xy 351.897977 -217.188085) (xy 351.875413 -217.233478) (xy 351.846169 -217.274884) (xy 351.810934 -217.311328)
			(xy 351.770536 -217.34195) (xy 351.725929 -217.36603) (xy 351.678162 -217.383) (xy 351.653348 -217.388186)
			(xy 351.630488 -217.392504) (xy 351.42551 -217.747596) (xy 351.433384 -217.76944) (xy 351.441973 -217.795856)
			(xy 351.451163 -217.850633) (xy 351.451672 -217.878406) (xy 351.732596 -217.878406) (xy 351.733104 -217.852519)
			(xy 351.741203 -217.801381) (xy 351.757202 -217.752141) (xy 351.780708 -217.706009) (xy 351.81114 -217.664122)
			(xy 351.84775 -217.627512) (xy 351.889637 -217.59708) (xy 351.935769 -217.573574) (xy 351.985009 -217.557575)
			(xy 352.036147 -217.549476) (xy 352.087921 -217.549476) (xy 352.139059 -217.557575) (xy 352.188299 -217.573574)
			(xy 352.234431 -217.59708) (xy 352.276318 -217.627512) (xy 352.312928 -217.664122) (xy 352.34336 -217.706009)
			(xy 352.366866 -217.752141) (xy 352.382865 -217.801381) (xy 352.390964 -217.852519) (xy 352.391472 -217.878406)
			(xy 352.672396 -217.878406) (xy 352.672888 -217.853072) (xy 352.680639 -217.803) (xy 352.69596 -217.754704)
			(xy 352.718491 -217.70932) (xy 352.747699 -217.667918) (xy 352.782899 -217.631473) (xy 352.82326 -217.600842)
			(xy 352.867833 -217.576747) (xy 352.915567 -217.559756) (xy 352.940366 -217.554556) (xy 352.963226 -217.550238)
			(xy 353.168204 -217.195146) (xy 353.16033 -217.173302) (xy 353.151691 -217.146892) (xy 353.142367 -217.092117)
			(xy 353.141788 -217.064336) (xy 353.142296 -217.038429) (xy 353.150402 -216.987252) (xy 353.166414 -216.937973)
			(xy 353.189937 -216.891806) (xy 353.220393 -216.849887) (xy 353.257031 -216.813249) (xy 353.29895 -216.782793)
			(xy 353.345117 -216.75927) (xy 353.394396 -216.743258) (xy 353.445573 -216.735152) (xy 353.497387 -216.735152)
			(xy 353.548564 -216.743258) (xy 353.597843 -216.75927) (xy 353.64401 -216.782793) (xy 353.685929 -216.813249)
			(xy 353.722567 -216.849887) (xy 353.753023 -216.891806) (xy 353.776546 -216.937973) (xy 353.792558 -216.987252)
			(xy 353.800664 -217.038429) (xy 353.801172 -217.064336) (xy 353.800706 -217.089682) (xy 353.792928 -217.139773)
			(xy 353.777577 -217.188085) (xy 353.755013 -217.233478) (xy 353.725769 -217.274884) (xy 353.690534 -217.311328)
			(xy 353.650136 -217.34195) (xy 353.605529 -217.36603) (xy 353.557762 -217.383) (xy 353.532948 -217.388186)
			(xy 353.510088 -217.392504) (xy 353.30511 -217.747596) (xy 353.312984 -217.76944) (xy 353.321573 -217.795856)
			(xy 353.330763 -217.850633) (xy 353.331272 -217.878406) (xy 353.612196 -217.878406) (xy 353.612704 -217.852519)
			(xy 353.620803 -217.801381) (xy 353.636802 -217.752141) (xy 353.660308 -217.706009) (xy 353.69074 -217.664122)
			(xy 353.72735 -217.627512) (xy 353.769237 -217.59708) (xy 353.815369 -217.573574) (xy 353.864609 -217.557575)
			(xy 353.915747 -217.549476) (xy 353.967521 -217.549476) (xy 354.018659 -217.557575) (xy 354.067899 -217.573574)
			(xy 354.114031 -217.59708) (xy 354.155918 -217.627512) (xy 354.192528 -217.664122) (xy 354.22296 -217.706009)
			(xy 354.246466 -217.752141) (xy 354.262465 -217.801381) (xy 354.270564 -217.852519) (xy 354.271072 -217.878406)
			(xy 354.551996 -217.878406) (xy 354.552488 -217.853072) (xy 354.560239 -217.803) (xy 354.57556 -217.754704)
			(xy 354.598091 -217.70932) (xy 354.627299 -217.667918) (xy 354.662499 -217.631473) (xy 354.70286 -217.600842)
			(xy 354.747433 -217.576747) (xy 354.795167 -217.559756) (xy 354.819966 -217.554556) (xy 354.842826 -217.550238)
			(xy 355.047804 -217.195146) (xy 355.03993 -217.173302) (xy 355.031291 -217.146892) (xy 355.021967 -217.092117)
			(xy 355.021388 -217.064336) (xy 355.021896 -217.038429) (xy 355.030002 -216.987252) (xy 355.046014 -216.937973)
			(xy 355.069537 -216.891806) (xy 355.099993 -216.849887) (xy 355.136631 -216.813249) (xy 355.17855 -216.782793)
			(xy 355.224717 -216.75927) (xy 355.273996 -216.743258) (xy 355.325173 -216.735152) (xy 355.376987 -216.735152)
			(xy 355.428164 -216.743258) (xy 355.477443 -216.75927) (xy 355.52361 -216.782793) (xy 355.565529 -216.813249)
			(xy 355.602167 -216.849887) (xy 355.632623 -216.891806) (xy 355.656146 -216.937973) (xy 355.672158 -216.987252)
			(xy 355.680264 -217.038429) (xy 355.680772 -217.064336) (xy 355.680306 -217.089682) (xy 355.672528 -217.139773)
			(xy 355.657177 -217.188085) (xy 355.634613 -217.233478) (xy 355.605369 -217.274884) (xy 355.570134 -217.311328)
			(xy 355.529736 -217.34195) (xy 355.485129 -217.36603) (xy 355.437362 -217.383) (xy 355.412548 -217.388186)
			(xy 355.389688 -217.392504) (xy 355.18471 -217.747596) (xy 355.192584 -217.76944) (xy 355.201173 -217.795856)
			(xy 355.210363 -217.850633) (xy 355.210872 -217.878406) (xy 355.491796 -217.878406) (xy 355.492304 -217.852519)
			(xy 355.500403 -217.801381) (xy 355.516402 -217.752141) (xy 355.539908 -217.706009) (xy 355.57034 -217.664122)
			(xy 355.60695 -217.627512) (xy 355.648837 -217.59708) (xy 355.694969 -217.573574) (xy 355.744209 -217.557575)
			(xy 355.795347 -217.549476) (xy 355.847121 -217.549476) (xy 355.898259 -217.557575) (xy 355.947499 -217.573574)
			(xy 355.993631 -217.59708) (xy 356.035518 -217.627512) (xy 356.072128 -217.664122) (xy 356.10256 -217.706009)
			(xy 356.126066 -217.752141) (xy 356.142065 -217.801381) (xy 356.150164 -217.852519) (xy 356.150672 -217.878406)
			(xy 356.431596 -217.878406) (xy 356.432088 -217.853072) (xy 356.439839 -217.803) (xy 356.45516 -217.754704)
			(xy 356.477691 -217.70932) (xy 356.506899 -217.667918) (xy 356.542099 -217.631473) (xy 356.58246 -217.600842)
			(xy 356.627033 -217.576747) (xy 356.674767 -217.559756) (xy 356.699566 -217.554556) (xy 356.722426 -217.550238)
			(xy 356.927404 -217.195146) (xy 356.91953 -217.173302) (xy 356.910891 -217.146892) (xy 356.901567 -217.092117)
			(xy 356.900988 -217.064336) (xy 356.901496 -217.038429) (xy 356.909602 -216.987252) (xy 356.925614 -216.937973)
			(xy 356.949137 -216.891806) (xy 356.979593 -216.849887) (xy 357.016231 -216.813249) (xy 357.05815 -216.782793)
			(xy 357.104317 -216.75927) (xy 357.153596 -216.743258) (xy 357.204773 -216.735152) (xy 357.256587 -216.735152)
			(xy 357.307764 -216.743258) (xy 357.357043 -216.75927) (xy 357.40321 -216.782793) (xy 357.445129 -216.813249)
			(xy 357.481767 -216.849887) (xy 357.512223 -216.891806) (xy 357.535746 -216.937973) (xy 357.551758 -216.987252)
			(xy 357.559864 -217.038429) (xy 357.560372 -217.064336) (xy 357.559906 -217.089682) (xy 357.552128 -217.139773)
			(xy 357.536777 -217.188085) (xy 357.514213 -217.233478) (xy 357.484969 -217.274884) (xy 357.449734 -217.311328)
			(xy 357.409336 -217.34195) (xy 357.364729 -217.36603) (xy 357.316962 -217.383) (xy 357.292148 -217.388186)
			(xy 357.269288 -217.392504) (xy 357.06431 -217.747596) (xy 357.072184 -217.76944) (xy 357.080773 -217.795856)
			(xy 357.089963 -217.850633) (xy 357.090472 -217.878406) (xy 357.371396 -217.878406) (xy 357.371904 -217.852519)
			(xy 357.380003 -217.801381) (xy 357.396002 -217.752141) (xy 357.419508 -217.706009) (xy 357.44994 -217.664122)
			(xy 357.48655 -217.627512) (xy 357.528437 -217.59708) (xy 357.574569 -217.573574) (xy 357.623809 -217.557575)
			(xy 357.674947 -217.549476) (xy 357.726721 -217.549476) (xy 357.777859 -217.557575) (xy 357.827099 -217.573574)
			(xy 357.873231 -217.59708) (xy 357.915118 -217.627512) (xy 357.951728 -217.664122) (xy 357.98216 -217.706009)
			(xy 358.005666 -217.752141) (xy 358.021665 -217.801381) (xy 358.029764 -217.852519) (xy 358.030272 -217.878406)
			(xy 358.311196 -217.878406) (xy 358.311688 -217.853072) (xy 358.319439 -217.803) (xy 358.33476 -217.754704)
			(xy 358.357291 -217.70932) (xy 358.386499 -217.667918) (xy 358.421699 -217.631473) (xy 358.46206 -217.600842)
			(xy 358.506633 -217.576747) (xy 358.554367 -217.559756) (xy 358.579166 -217.554556) (xy 358.602026 -217.550238)
			(xy 358.807004 -217.194892) (xy 358.799384 -217.173048) (xy 358.790811 -217.146694) (xy 358.78162 -217.092045)
			(xy 358.781096 -217.064336) (xy 358.781604 -217.038449) (xy 358.789703 -216.987311) (xy 358.805702 -216.938071)
			(xy 358.829208 -216.891939) (xy 358.85964 -216.850052) (xy 358.89625 -216.813442) (xy 358.938137 -216.78301)
			(xy 358.984269 -216.759504) (xy 359.033509 -216.743505) (xy 359.084647 -216.735406) (xy 359.136421 -216.735406)
			(xy 359.187559 -216.743505) (xy 359.236799 -216.759504) (xy 359.282931 -216.78301) (xy 359.324818 -216.813442)
			(xy 359.361428 -216.850052) (xy 359.39186 -216.891939) (xy 359.415366 -216.938071) (xy 359.431365 -216.987311)
			(xy 359.439464 -217.038449) (xy 359.439972 -217.064336) (xy 360.660188 -217.064336) (xy 360.660696 -217.038429)
			(xy 360.668802 -216.987252) (xy 360.684814 -216.937973) (xy 360.708337 -216.891806) (xy 360.738793 -216.849887)
			(xy 360.775431 -216.813249) (xy 360.81735 -216.782793) (xy 360.863517 -216.75927) (xy 360.912796 -216.743258)
			(xy 360.963973 -216.735152) (xy 361.015787 -216.735152) (xy 361.066964 -216.743258) (xy 361.116243 -216.75927)
			(xy 361.16241 -216.782793) (xy 361.204329 -216.813249) (xy 361.240967 -216.849887) (xy 361.271423 -216.891806)
			(xy 361.294946 -216.937973) (xy 361.310958 -216.987252) (xy 361.319064 -217.038429) (xy 361.319572 -217.064336)
			(xy 361.318959 -217.091989) (xy 361.309638 -217.146507) (xy 361.30103 -217.172794) (xy 361.29341 -217.194892)
			(xy 361.498642 -217.550238) (xy 361.521502 -217.554556) (xy 361.546303 -217.559751) (xy 361.594042 -217.57674)
			(xy 361.638619 -217.600833) (xy 361.678984 -217.631463) (xy 361.714188 -217.667908) (xy 361.7434 -217.709312)
			(xy 361.765933 -217.754697) (xy 361.781256 -217.802996) (xy 361.789008 -217.85307) (xy 361.789472 -217.878406)
			(xy 361.788964 -217.904293) (xy 361.780865 -217.955431) (xy 361.764866 -218.004671) (xy 361.74136 -218.050803)
			(xy 361.710928 -218.09269) (xy 361.674318 -218.1293) (xy 361.632431 -218.159732) (xy 361.586299 -218.183238)
			(xy 361.537059 -218.199237) (xy 361.485921 -218.207336) (xy 361.434147 -218.207336) (xy 361.383009 -218.199237)
			(xy 361.333769 -218.183238) (xy 361.287637 -218.159732) (xy 361.24575 -218.1293) (xy 361.20914 -218.09269)
			(xy 361.178708 -218.050803) (xy 361.155202 -218.004671) (xy 361.139203 -217.955431) (xy 361.131104 -217.904293)
			(xy 361.130596 -217.878406) (xy 361.131127 -217.850698) (xy 361.140321 -217.796051) (xy 361.148884 -217.769694)
			(xy 361.156758 -217.747596) (xy 360.95178 -217.392504) (xy 360.92892 -217.388186) (xy 360.904075 -217.38302)
			(xy 360.856226 -217.366126) (xy 360.811533 -217.342096) (xy 360.771053 -217.311499) (xy 360.735741 -217.275058)
			(xy 360.706433 -217.233634) (xy 360.683822 -217.188207) (xy 360.668443 -217.13985) (xy 360.660658 -217.089708)
			(xy 360.660188 -217.064336) (xy 359.439972 -217.064336) (xy 359.439506 -217.089682) (xy 359.431728 -217.139773)
			(xy 359.416377 -217.188085) (xy 359.393813 -217.233478) (xy 359.364569 -217.274884) (xy 359.329334 -217.311328)
			(xy 359.288936 -217.34195) (xy 359.244329 -217.36603) (xy 359.196562 -217.383) (xy 359.171748 -217.388186)
			(xy 359.148888 -217.392504) (xy 358.94391 -217.747596) (xy 358.951784 -217.76944) (xy 358.960373 -217.795856)
			(xy 358.969563 -217.850633) (xy 358.970072 -217.878406) (xy 358.969564 -217.904293) (xy 358.961465 -217.955431)
			(xy 358.945466 -218.004671) (xy 358.92196 -218.050803) (xy 358.891528 -218.09269) (xy 358.854918 -218.1293)
			(xy 358.813031 -218.159732) (xy 358.766899 -218.183238) (xy 358.717659 -218.199237) (xy 358.666521 -218.207336)
			(xy 358.614747 -218.207336) (xy 358.563609 -218.199237) (xy 358.514369 -218.183238) (xy 358.468237 -218.159732)
			(xy 358.42635 -218.1293) (xy 358.38974 -218.09269) (xy 358.359308 -218.050803) (xy 358.335802 -218.004671)
			(xy 358.319803 -217.955431) (xy 358.311704 -217.904293) (xy 358.311196 -217.878406) (xy 358.030272 -217.878406)
			(xy 358.029741 -217.906114) (xy 358.020546 -217.960761) (xy 358.011984 -217.987118) (xy 358.004364 -218.008962)
			(xy 358.209342 -218.364054) (xy 358.232202 -218.368372) (xy 358.257007 -218.373552) (xy 358.304747 -218.390542)
			(xy 358.349324 -218.414636) (xy 358.38969 -218.445268) (xy 358.424894 -218.481716) (xy 358.454106 -218.523121)
			(xy 358.476638 -218.568508) (xy 358.491959 -218.616809) (xy 358.49971 -218.666886) (xy 358.500172 -218.692222)
			(xy 359.720388 -218.692222) (xy 359.720939 -218.66688) (xy 359.728707 -218.616793) (xy 359.744048 -218.568485)
			(xy 359.766601 -218.523094) (xy 359.795834 -218.481689) (xy 359.831059 -218.445245) (xy 359.871446 -218.41462)
			(xy 359.916044 -218.390537) (xy 359.963802 -218.373561) (xy 359.988612 -218.368372) (xy 360.011472 -218.364054)
			(xy 360.216704 -218.008708) (xy 360.20883 -217.98661) (xy 360.200361 -217.960367) (xy 360.191292 -217.905977)
			(xy 360.190796 -217.878406) (xy 360.191304 -217.852519) (xy 360.199403 -217.801381) (xy 360.215402 -217.752141)
			(xy 360.238908 -217.706009) (xy 360.26934 -217.664122) (xy 360.30595 -217.627512) (xy 360.347837 -217.59708)
			(xy 360.393969 -217.573574) (xy 360.443209 -217.557575) (xy 360.494347 -217.549476) (xy 360.546121 -217.549476)
			(xy 360.597259 -217.557575) (xy 360.646499 -217.573574) (xy 360.692631 -217.59708) (xy 360.734518 -217.627512)
			(xy 360.771128 -217.664122) (xy 360.80156 -217.706009) (xy 360.825066 -217.752141) (xy 360.841065 -217.801381)
			(xy 360.849164 -217.852519) (xy 360.849672 -217.878406) (xy 360.849225 -217.903782) (xy 360.841455 -217.953934)
			(xy 360.826085 -218.002302) (xy 360.803477 -218.047739) (xy 360.774167 -218.089171) (xy 360.73885 -218.125617)
			(xy 360.69836 -218.156215) (xy 360.653656 -218.18024) (xy 360.605796 -218.197124) (xy 360.58094 -218.202256)
			(xy 360.55808 -218.206574) (xy 360.353356 -218.561412) (xy 360.36123 -218.583256) (xy 360.369881 -218.609663)
			(xy 360.379198 -218.66444) (xy 360.379772 -218.692222) (xy 361.600496 -218.692222) (xy 361.601002 -218.666888)
			(xy 361.608751 -218.616817) (xy 361.62407 -218.568521) (xy 361.646599 -218.523138) (xy 361.675805 -218.481736)
			(xy 361.711003 -218.44529) (xy 361.751363 -218.414659) (xy 361.795934 -218.390564) (xy 361.843667 -218.373572)
			(xy 361.868466 -218.368372) (xy 361.891326 -218.364054) (xy 362.096304 -218.008962) (xy 362.088684 -217.986864)
			(xy 362.080159 -217.960694) (xy 362.070969 -217.906431) (xy 362.070396 -217.878914) (xy 362.070396 -217.878406)
			(xy 362.070904 -217.852519) (xy 362.079003 -217.801381) (xy 362.095002 -217.752141) (xy 362.118508 -217.706009)
			(xy 362.14894 -217.664122) (xy 362.18555 -217.627512) (xy 362.227437 -217.59708) (xy 362.273569 -217.573574)
			(xy 362.322809 -217.557575) (xy 362.373947 -217.549476) (xy 362.425721 -217.549476) (xy 362.476859 -217.557575)
			(xy 362.526099 -217.573574) (xy 362.572231 -217.59708) (xy 362.614118 -217.627512) (xy 362.650728 -217.664122)
			(xy 362.68116 -217.706009) (xy 362.704666 -217.752141) (xy 362.720665 -217.801381) (xy 362.728764 -217.852519)
			(xy 362.729272 -217.878406) (xy 362.728863 -217.903772) (xy 362.721112 -217.953909) (xy 362.705764 -218.002264)
			(xy 362.683182 -218.047694) (xy 362.6539 -218.089122) (xy 362.61861 -218.12557) (xy 362.578149 -218.156175)
			(xy 362.533472 -218.180212) (xy 362.485638 -218.197113) (xy 362.460794 -218.202256) (xy 362.437934 -218.206574)
			(xy 362.23321 -218.561412) (xy 362.241084 -218.583256) (xy 362.249677 -218.609671) (xy 362.258865 -218.664449)
			(xy 362.259372 -218.692222) (xy 362.258864 -218.718109) (xy 362.250765 -218.769247) (xy 362.234766 -218.818487)
			(xy 362.21126 -218.864619) (xy 362.180828 -218.906506) (xy 362.144218 -218.943116) (xy 362.102331 -218.973548)
			(xy 362.056199 -218.997054) (xy 362.006959 -219.013053) (xy 361.955821 -219.021152) (xy 361.904047 -219.021152)
			(xy 361.852909 -219.013053) (xy 361.803669 -218.997054) (xy 361.757537 -218.973548) (xy 361.71565 -218.943116)
			(xy 361.67904 -218.906506) (xy 361.648608 -218.864619) (xy 361.625102 -218.818487) (xy 361.609103 -218.769247)
			(xy 361.601004 -218.718109) (xy 361.600496 -218.692222) (xy 360.379772 -218.692222) (xy 360.379264 -218.718129)
			(xy 360.371158 -218.769306) (xy 360.355146 -218.818585) (xy 360.331623 -218.864752) (xy 360.301167 -218.906671)
			(xy 360.264529 -218.943309) (xy 360.22261 -218.973765) (xy 360.176443 -218.997288) (xy 360.127164 -219.0133)
			(xy 360.075987 -219.021406) (xy 360.024173 -219.021406) (xy 359.972996 -219.0133) (xy 359.923717 -218.997288)
			(xy 359.87755 -218.973765) (xy 359.835631 -218.943309) (xy 359.798993 -218.906671) (xy 359.768537 -218.864752)
			(xy 359.745014 -218.818585) (xy 359.729002 -218.769306) (xy 359.720896 -218.718129) (xy 359.720388 -218.692222)
			(xy 358.500172 -218.692222) (xy 358.499664 -218.718109) (xy 358.491565 -218.769247) (xy 358.475566 -218.818487)
			(xy 358.45206 -218.864619) (xy 358.421628 -218.906506) (xy 358.385018 -218.943116) (xy 358.343131 -218.973548)
			(xy 358.296999 -218.997054) (xy 358.247759 -219.013053) (xy 358.196621 -219.021152) (xy 358.144847 -219.021152)
			(xy 358.093709 -219.013053) (xy 358.044469 -218.997054) (xy 357.998337 -218.973548) (xy 357.95645 -218.943116)
			(xy 357.91984 -218.906506) (xy 357.889408 -218.864619) (xy 357.865902 -218.818487) (xy 357.849903 -218.769247)
			(xy 357.841804 -218.718109) (xy 357.841296 -218.692222) (xy 357.841831 -218.664514) (xy 357.851023 -218.609867)
			(xy 357.859584 -218.58351) (xy 357.867458 -218.561412) (xy 357.66248 -218.206574) (xy 357.63962 -218.202256)
			(xy 357.614783 -218.197156) (xy 357.567001 -218.180194) (xy 357.52238 -218.156114) (xy 357.481972 -218.125486)
			(xy 357.446732 -218.08903) (xy 357.417491 -218.047608) (xy 357.394937 -218.002196) (xy 357.379605 -217.953866)
			(xy 357.371854 -217.903758) (xy 357.371396 -217.878406) (xy 357.090472 -217.878406) (xy 357.089964 -217.904293)
			(xy 357.081865 -217.955431) (xy 357.065866 -218.004671) (xy 357.04236 -218.050803) (xy 357.011928 -218.09269)
			(xy 356.975318 -218.1293) (xy 356.933431 -218.159732) (xy 356.887299 -218.183238) (xy 356.838059 -218.199237)
			(xy 356.786921 -218.207336) (xy 356.735147 -218.207336) (xy 356.684009 -218.199237) (xy 356.634769 -218.183238)
			(xy 356.588637 -218.159732) (xy 356.54675 -218.1293) (xy 356.51014 -218.09269) (xy 356.479708 -218.050803)
			(xy 356.456202 -218.004671) (xy 356.440203 -217.955431) (xy 356.432104 -217.904293) (xy 356.431596 -217.878406)
			(xy 356.150672 -217.878406) (xy 356.150141 -217.906114) (xy 356.140946 -217.960761) (xy 356.132384 -217.987118)
			(xy 356.12451 -218.009216) (xy 356.329488 -218.364054) (xy 356.352348 -218.368372) (xy 356.377163 -218.373563)
			(xy 356.424941 -218.390515) (xy 356.469559 -218.414584) (xy 356.509965 -218.445202) (xy 356.545206 -218.481645)
			(xy 356.57445 -218.523056) (xy 356.597009 -218.568456) (xy 356.612349 -218.616776) (xy 356.620108 -218.666874)
			(xy 356.620572 -218.692222) (xy 356.620064 -218.718129) (xy 356.611958 -218.769306) (xy 356.595946 -218.818585)
			(xy 356.572423 -218.864752) (xy 356.541967 -218.906671) (xy 356.505329 -218.943309) (xy 356.46341 -218.973765)
			(xy 356.417243 -218.997288) (xy 356.367964 -219.0133) (xy 356.316787 -219.021406) (xy 356.264973 -219.021406)
			(xy 356.213796 -219.0133) (xy 356.164517 -218.997288) (xy 356.11835 -218.973765) (xy 356.076431 -218.943309)
			(xy 356.039793 -218.906671) (xy 356.009337 -218.864752) (xy 355.985814 -218.818585) (xy 355.969802 -218.769306)
			(xy 355.961696 -218.718129) (xy 355.961188 -218.692222) (xy 355.961788 -218.664505) (xy 355.971107 -218.609859)
			(xy 355.97973 -218.58351) (xy 355.987604 -218.561412) (xy 355.782626 -218.206574) (xy 355.759766 -218.202256)
			(xy 355.734962 -218.197073) (xy 355.687224 -218.180081) (xy 355.642649 -218.155985) (xy 355.602284 -218.125353)
			(xy 355.567082 -218.088906) (xy 355.53787 -218.047502) (xy 355.515337 -218.002116) (xy 355.500013 -217.953817)
			(xy 355.49226 -217.903742) (xy 355.491796 -217.878406) (xy 355.210872 -217.878406) (xy 355.210364 -217.904293)
			(xy 355.202265 -217.955431) (xy 355.186266 -218.004671) (xy 355.16276 -218.050803) (xy 355.132328 -218.09269)
			(xy 355.095718 -218.1293) (xy 355.053831 -218.159732) (xy 355.007699 -218.183238) (xy 354.958459 -218.199237)
			(xy 354.907321 -218.207336) (xy 354.855547 -218.207336) (xy 354.804409 -218.199237) (xy 354.755169 -218.183238)
			(xy 354.709037 -218.159732) (xy 354.66715 -218.1293) (xy 354.63054 -218.09269) (xy 354.600108 -218.050803)
			(xy 354.576602 -218.004671) (xy 354.560603 -217.955431) (xy 354.552504 -217.904293) (xy 354.551996 -217.878406)
			(xy 354.271072 -217.878406) (xy 354.270541 -217.906114) (xy 354.261346 -217.960761) (xy 354.252784 -217.987118)
			(xy 354.24491 -218.009216) (xy 354.449888 -218.364054) (xy 354.472748 -218.368372) (xy 354.497563 -218.373563)
			(xy 354.545341 -218.390515) (xy 354.589959 -218.414584) (xy 354.630365 -218.445202) (xy 354.665606 -218.481645)
			(xy 354.69485 -218.523056) (xy 354.717409 -218.568456) (xy 354.732749 -218.616776) (xy 354.740508 -218.666874)
			(xy 354.740972 -218.692222) (xy 354.740464 -218.718129) (xy 354.732358 -218.769306) (xy 354.716346 -218.818585)
			(xy 354.692823 -218.864752) (xy 354.662367 -218.906671) (xy 354.625729 -218.943309) (xy 354.58381 -218.973765)
			(xy 354.537643 -218.997288) (xy 354.488364 -219.0133) (xy 354.437187 -219.021406) (xy 354.385373 -219.021406)
			(xy 354.334196 -219.0133) (xy 354.284917 -218.997288) (xy 354.23875 -218.973765) (xy 354.196831 -218.943309)
			(xy 354.160193 -218.906671) (xy 354.129737 -218.864752) (xy 354.106214 -218.818585) (xy 354.090202 -218.769306)
			(xy 354.082096 -218.718129) (xy 354.081588 -218.692222) (xy 354.082188 -218.664505) (xy 354.091507 -218.609859)
			(xy 354.10013 -218.58351) (xy 354.108004 -218.561412) (xy 353.903026 -218.206574) (xy 353.880166 -218.202256)
			(xy 353.855362 -218.197073) (xy 353.807624 -218.180081) (xy 353.763049 -218.155985) (xy 353.722684 -218.125353)
			(xy 353.687482 -218.088906) (xy 353.65827 -218.047502) (xy 353.635737 -218.002116) (xy 353.620413 -217.953817)
			(xy 353.61266 -217.903742) (xy 353.612196 -217.878406) (xy 353.331272 -217.878406) (xy 353.330764 -217.904293)
			(xy 353.322665 -217.955431) (xy 353.306666 -218.004671) (xy 353.28316 -218.050803) (xy 353.252728 -218.09269)
			(xy 353.216118 -218.1293) (xy 353.174231 -218.159732) (xy 353.128099 -218.183238) (xy 353.078859 -218.199237)
			(xy 353.027721 -218.207336) (xy 352.975947 -218.207336) (xy 352.924809 -218.199237) (xy 352.875569 -218.183238)
			(xy 352.829437 -218.159732) (xy 352.78755 -218.1293) (xy 352.75094 -218.09269) (xy 352.720508 -218.050803)
			(xy 352.697002 -218.004671) (xy 352.681003 -217.955431) (xy 352.672904 -217.904293) (xy 352.672396 -217.878406)
			(xy 352.391472 -217.878406) (xy 352.390941 -217.906114) (xy 352.381746 -217.960761) (xy 352.373184 -217.987118)
			(xy 352.36531 -218.009216) (xy 352.570288 -218.364054) (xy 352.593148 -218.368372) (xy 352.617963 -218.373563)
			(xy 352.665741 -218.390515) (xy 352.710359 -218.414584) (xy 352.750765 -218.445202) (xy 352.786006 -218.481645)
			(xy 352.81525 -218.523056) (xy 352.837809 -218.568456) (xy 352.853149 -218.616776) (xy 352.860908 -218.666874)
			(xy 352.861372 -218.692222) (xy 352.860864 -218.718129) (xy 352.852758 -218.769306) (xy 352.836746 -218.818585)
			(xy 352.813223 -218.864752) (xy 352.782767 -218.906671) (xy 352.746129 -218.943309) (xy 352.70421 -218.973765)
			(xy 352.658043 -218.997288) (xy 352.608764 -219.0133) (xy 352.557587 -219.021406) (xy 352.505773 -219.021406)
			(xy 352.454596 -219.0133) (xy 352.405317 -218.997288) (xy 352.35915 -218.973765) (xy 352.317231 -218.943309)
			(xy 352.280593 -218.906671) (xy 352.250137 -218.864752) (xy 352.226614 -218.818585) (xy 352.210602 -218.769306)
			(xy 352.202496 -218.718129) (xy 352.201988 -218.692222) (xy 352.202588 -218.664505) (xy 352.211907 -218.609859)
			(xy 352.22053 -218.58351) (xy 352.228404 -218.561412) (xy 352.023426 -218.206574) (xy 352.000566 -218.202256)
			(xy 351.975762 -218.197073) (xy 351.928024 -218.180081) (xy 351.883449 -218.155985) (xy 351.843084 -218.125353)
			(xy 351.807882 -218.088906) (xy 351.77867 -218.047502) (xy 351.756137 -218.002116) (xy 351.740813 -217.953817)
			(xy 351.73306 -217.903742) (xy 351.732596 -217.878406) (xy 351.451672 -217.878406) (xy 351.451164 -217.904293)
			(xy 351.443065 -217.955431) (xy 351.427066 -218.004671) (xy 351.40356 -218.050803) (xy 351.373128 -218.09269)
			(xy 351.336518 -218.1293) (xy 351.294631 -218.159732) (xy 351.248499 -218.183238) (xy 351.199259 -218.199237)
			(xy 351.148121 -218.207336) (xy 351.096347 -218.207336) (xy 351.045209 -218.199237) (xy 350.995969 -218.183238)
			(xy 350.949837 -218.159732) (xy 350.90795 -218.1293) (xy 350.87134 -218.09269) (xy 350.840908 -218.050803)
			(xy 350.817402 -218.004671) (xy 350.801403 -217.955431) (xy 350.793304 -217.904293) (xy 350.792796 -217.878406)
			(xy 350.511872 -217.878406) (xy 350.511341 -217.906114) (xy 350.502146 -217.960761) (xy 350.493584 -217.987118)
			(xy 350.48571 -218.009216) (xy 350.690688 -218.364054) (xy 350.713548 -218.368372) (xy 350.738363 -218.373563)
			(xy 350.786141 -218.390515) (xy 350.830759 -218.414584) (xy 350.871165 -218.445202) (xy 350.906406 -218.481645)
			(xy 350.93565 -218.523056) (xy 350.958209 -218.568456) (xy 350.973549 -218.616776) (xy 350.981308 -218.666874)
			(xy 350.981772 -218.692222) (xy 350.981264 -218.718129) (xy 350.973158 -218.769306) (xy 350.957146 -218.818585)
			(xy 350.933623 -218.864752) (xy 350.903167 -218.906671) (xy 350.866529 -218.943309) (xy 350.82461 -218.973765)
			(xy 350.778443 -218.997288) (xy 350.729164 -219.0133) (xy 350.677987 -219.021406) (xy 350.626173 -219.021406)
			(xy 350.574996 -219.0133) (xy 350.525717 -218.997288) (xy 350.47955 -218.973765) (xy 350.437631 -218.943309)
			(xy 350.400993 -218.906671) (xy 350.370537 -218.864752) (xy 350.347014 -218.818585) (xy 350.331002 -218.769306)
			(xy 350.322896 -218.718129) (xy 350.322388 -218.692222) (xy 350.322988 -218.664505) (xy 350.332307 -218.609859)
			(xy 350.34093 -218.58351) (xy 350.348804 -218.561412) (xy 350.143826 -218.206574) (xy 350.120966 -218.202256)
			(xy 350.096162 -218.197073) (xy 350.048424 -218.180081) (xy 350.003849 -218.155985) (xy 349.963484 -218.125353)
			(xy 349.928282 -218.088906) (xy 349.89907 -218.047502) (xy 349.876537 -218.002116) (xy 349.861213 -217.953817)
			(xy 349.85346 -217.903742) (xy 349.852996 -217.878406) (xy 349.572072 -217.878406) (xy 349.571562 -217.904662)
			(xy 349.563234 -217.956509) (xy 349.54679 -218.00638) (xy 349.522646 -218.053012) (xy 349.491413 -218.095226)
			(xy 349.453881 -218.131953) (xy 349.411001 -218.162264) (xy 349.387668 -218.174316) (xy 349.387668 -218.974924)
			(xy 350.462342 -220.049598) (xy 350.495616 -220.031564) (xy 350.51981 -220.019009) (xy 350.57133 -220.001225)
			(xy 350.625082 -219.992203) (xy 350.652334 -219.991686) (xy 350.678121 -219.992194) (xy 350.72906 -220.000266)
			(xy 350.778109 -220.016206) (xy 350.824062 -220.039622) (xy 350.865786 -220.069937) (xy 350.902255 -220.106405)
			(xy 350.932572 -220.148128) (xy 350.955989 -220.19408) (xy 350.971931 -220.243128) (xy 350.980005 -220.294067)
			(xy 350.980502 -220.319854) (xy 350.979966 -220.347106) (xy 350.970962 -220.400861) (xy 350.953193 -220.452386)
			(xy 350.940624 -220.476572) (xy 350.92259 -220.509846) (xy 351.03943 -220.626686) (xy 351.049124 -220.635829)
			(xy 351.07219 -220.649154) (xy 351.097921 -220.656047) (xy 351.12456 -220.656036) (xy 351.150285 -220.649123)
			(xy 351.173341 -220.63578) (xy 351.192151 -220.616917) (xy 351.199196 -220.605604) (xy 351.288604 -220.450664)
			(xy 351.28073 -220.42882) (xy 351.272087 -220.402411) (xy 351.262773 -220.347635) (xy 351.262188 -220.319854)
			(xy 351.262696 -220.293947) (xy 351.270802 -220.24277) (xy 351.286814 -220.193491) (xy 351.310337 -220.147324)
			(xy 351.340793 -220.105405) (xy 351.377431 -220.068767) (xy 351.41935 -220.038311) (xy 351.465517 -220.014788)
			(xy 351.514796 -219.998776) (xy 351.565973 -219.99067) (xy 351.617787 -219.99067) (xy 351.668964 -219.998776)
			(xy 351.718243 -220.014788) (xy 351.76441 -220.038311) (xy 351.806329 -220.068767) (xy 351.842967 -220.105405)
			(xy 351.873423 -220.147324) (xy 351.896946 -220.193491) (xy 351.912958 -220.24277) (xy 351.921064 -220.293947)
			(xy 351.921572 -220.319854) (xy 353.141788 -220.319854) (xy 353.142296 -220.293947) (xy 353.150402 -220.24277)
			(xy 353.166414 -220.193491) (xy 353.189937 -220.147324) (xy 353.220393 -220.105405) (xy 353.257031 -220.068767)
			(xy 353.29895 -220.038311) (xy 353.345117 -220.014788) (xy 353.394396 -219.998776) (xy 353.445573 -219.99067)
			(xy 353.497387 -219.99067) (xy 353.548564 -219.998776) (xy 353.597843 -220.014788) (xy 353.64401 -220.038311)
			(xy 353.685929 -220.068767) (xy 353.722567 -220.105405) (xy 353.753023 -220.147324) (xy 353.776546 -220.193491)
			(xy 353.792558 -220.24277) (xy 353.800664 -220.293947) (xy 353.801172 -220.319854) (xy 355.021388 -220.319854)
			(xy 355.021896 -220.293947) (xy 355.030002 -220.24277) (xy 355.046014 -220.193491) (xy 355.069537 -220.147324)
			(xy 355.099993 -220.105405) (xy 355.136631 -220.068767) (xy 355.17855 -220.038311) (xy 355.224717 -220.014788)
			(xy 355.273996 -219.998776) (xy 355.325173 -219.99067) (xy 355.376987 -219.99067) (xy 355.428164 -219.998776)
			(xy 355.477443 -220.014788) (xy 355.52361 -220.038311) (xy 355.565529 -220.068767) (xy 355.602167 -220.105405)
			(xy 355.632623 -220.147324) (xy 355.656146 -220.193491) (xy 355.672158 -220.24277) (xy 355.680264 -220.293947)
			(xy 355.680772 -220.319854) (xy 356.900988 -220.319854) (xy 356.901496 -220.293947) (xy 356.909602 -220.24277)
			(xy 356.925614 -220.193491) (xy 356.949137 -220.147324) (xy 356.979593 -220.105405) (xy 357.016231 -220.068767)
			(xy 357.05815 -220.038311) (xy 357.104317 -220.014788) (xy 357.153596 -219.998776) (xy 357.204773 -219.99067)
			(xy 357.256587 -219.99067) (xy 357.307764 -219.998776) (xy 357.357043 -220.014788) (xy 357.40321 -220.038311)
			(xy 357.445129 -220.068767) (xy 357.481767 -220.105405) (xy 357.512223 -220.147324) (xy 357.535746 -220.193491)
			(xy 357.551758 -220.24277) (xy 357.559864 -220.293947) (xy 357.560372 -220.319854) (xy 358.780588 -220.319854)
			(xy 358.781096 -220.293947) (xy 358.789202 -220.24277) (xy 358.805214 -220.193491) (xy 358.828737 -220.147324)
			(xy 358.859193 -220.105405) (xy 358.895831 -220.068767) (xy 358.93775 -220.038311) (xy 358.983917 -220.014788)
			(xy 359.033196 -219.998776) (xy 359.084373 -219.99067) (xy 359.136187 -219.99067) (xy 359.187364 -219.998776)
			(xy 359.236643 -220.014788) (xy 359.28281 -220.038311) (xy 359.324729 -220.068767) (xy 359.361367 -220.105405)
			(xy 359.391823 -220.147324) (xy 359.415346 -220.193491) (xy 359.431358 -220.24277) (xy 359.439464 -220.293947)
			(xy 359.439972 -220.319854) (xy 360.660188 -220.319854) (xy 360.660696 -220.293947) (xy 360.668802 -220.24277)
			(xy 360.684814 -220.193491) (xy 360.708337 -220.147324) (xy 360.738793 -220.105405) (xy 360.775431 -220.068767)
			(xy 360.81735 -220.038311) (xy 360.863517 -220.014788) (xy 360.912796 -219.998776) (xy 360.963973 -219.99067)
			(xy 361.015787 -219.99067) (xy 361.066964 -219.998776) (xy 361.116243 -220.014788) (xy 361.16241 -220.038311)
			(xy 361.204329 -220.068767) (xy 361.240967 -220.105405) (xy 361.271423 -220.147324) (xy 361.294946 -220.193491)
			(xy 361.310958 -220.24277) (xy 361.319064 -220.293947) (xy 361.319572 -220.319854) (xy 361.318963 -220.347508)
			(xy 361.309639 -220.402026) (xy 361.30103 -220.428312) (xy 361.29341 -220.45041) (xy 361.498642 -220.805756)
			(xy 361.521502 -220.810074) (xy 361.546308 -220.815252) (xy 361.594047 -220.832242) (xy 361.638625 -220.856337)
			(xy 361.678991 -220.886969) (xy 361.714195 -220.923417) (xy 361.743406 -220.964822) (xy 361.765938 -221.01021)
			(xy 361.78126 -221.058511) (xy 361.78901 -221.108588) (xy 361.789472 -221.133924) (xy 361.788964 -221.159811)
			(xy 361.780865 -221.210949) (xy 361.764866 -221.260189) (xy 361.74136 -221.306321) (xy 361.710928 -221.348208)
			(xy 361.674318 -221.384818) (xy 361.632431 -221.41525) (xy 361.586299 -221.438756) (xy 361.537059 -221.454755)
			(xy 361.485921 -221.462854) (xy 361.434147 -221.462854) (xy 361.383009 -221.454755) (xy 361.333769 -221.438756)
			(xy 361.287637 -221.41525) (xy 361.24575 -221.384818) (xy 361.20914 -221.348208) (xy 361.178708 -221.306321)
			(xy 361.155202 -221.260189) (xy 361.139203 -221.210949) (xy 361.131104 -221.159811) (xy 361.130596 -221.133924)
			(xy 361.131132 -221.106216) (xy 361.140323 -221.051569) (xy 361.148884 -221.025212) (xy 361.156758 -221.003114)
			(xy 360.95178 -220.648022) (xy 360.92892 -220.643704) (xy 360.904079 -220.638521) (xy 360.856232 -220.621628)
			(xy 360.81154 -220.5976) (xy 360.771059 -220.567005) (xy 360.735748 -220.530566) (xy 360.706439 -220.489145)
			(xy 360.683827 -220.44372) (xy 360.668446 -220.395365) (xy 360.660659 -220.345225) (xy 360.660188 -220.319854)
			(xy 359.439972 -220.319854) (xy 359.439363 -220.347508) (xy 359.430039 -220.402026) (xy 359.42143 -220.428312)
			(xy 359.41381 -220.45041) (xy 359.619042 -220.805756) (xy 359.641902 -220.810074) (xy 359.666708 -220.815252)
			(xy 359.714447 -220.832242) (xy 359.759025 -220.856337) (xy 359.799391 -220.886969) (xy 359.834595 -220.923417)
			(xy 359.863806 -220.964822) (xy 359.886338 -221.01021) (xy 359.90166 -221.058511) (xy 359.90941 -221.108588)
			(xy 359.909872 -221.133924) (xy 359.909364 -221.159811) (xy 359.901265 -221.210949) (xy 359.885266 -221.260189)
			(xy 359.86176 -221.306321) (xy 359.831328 -221.348208) (xy 359.794718 -221.384818) (xy 359.752831 -221.41525)
			(xy 359.706699 -221.438756) (xy 359.657459 -221.454755) (xy 359.606321 -221.462854) (xy 359.554547 -221.462854)
			(xy 359.503409 -221.454755) (xy 359.454169 -221.438756) (xy 359.408037 -221.41525) (xy 359.36615 -221.384818)
			(xy 359.32954 -221.348208) (xy 359.299108 -221.306321) (xy 359.275602 -221.260189) (xy 359.259603 -221.210949)
			(xy 359.251504 -221.159811) (xy 359.250996 -221.133924) (xy 359.251532 -221.106216) (xy 359.260723 -221.051569)
			(xy 359.269284 -221.025212) (xy 359.277158 -221.003114) (xy 359.07218 -220.648022) (xy 359.04932 -220.643704)
			(xy 359.024479 -220.638521) (xy 358.976632 -220.621628) (xy 358.93194 -220.5976) (xy 358.891459 -220.567005)
			(xy 358.856148 -220.530566) (xy 358.826839 -220.489145) (xy 358.804227 -220.44372) (xy 358.788846 -220.395365)
			(xy 358.781059 -220.345225) (xy 358.780588 -220.319854) (xy 357.560372 -220.319854) (xy 357.559763 -220.347508)
			(xy 357.550439 -220.402026) (xy 357.54183 -220.428312) (xy 357.53421 -220.45041) (xy 357.739442 -220.805756)
			(xy 357.762302 -220.810074) (xy 357.787108 -220.815252) (xy 357.834847 -220.832242) (xy 357.879425 -220.856337)
			(xy 357.919791 -220.886969) (xy 357.954995 -220.923417) (xy 357.984206 -220.964822) (xy 358.006738 -221.01021)
			(xy 358.02206 -221.058511) (xy 358.02981 -221.108588) (xy 358.030272 -221.133924) (xy 358.029764 -221.159811)
			(xy 358.021665 -221.210949) (xy 358.005666 -221.260189) (xy 357.98216 -221.306321) (xy 357.951728 -221.348208)
			(xy 357.915118 -221.384818) (xy 357.873231 -221.41525) (xy 357.827099 -221.438756) (xy 357.777859 -221.454755)
			(xy 357.726721 -221.462854) (xy 357.674947 -221.462854) (xy 357.623809 -221.454755) (xy 357.574569 -221.438756)
			(xy 357.528437 -221.41525) (xy 357.48655 -221.384818) (xy 357.44994 -221.348208) (xy 357.419508 -221.306321)
			(xy 357.396002 -221.260189) (xy 357.380003 -221.210949) (xy 357.371904 -221.159811) (xy 357.371396 -221.133924)
			(xy 357.371932 -221.106216) (xy 357.381123 -221.051569) (xy 357.389684 -221.025212) (xy 357.397558 -221.003114)
			(xy 357.19258 -220.648022) (xy 357.16972 -220.643704) (xy 357.144879 -220.638521) (xy 357.097032 -220.621628)
			(xy 357.05234 -220.5976) (xy 357.011859 -220.567005) (xy 356.976548 -220.530566) (xy 356.947239 -220.489145)
			(xy 356.924627 -220.44372) (xy 356.909246 -220.395365) (xy 356.901459 -220.345225) (xy 356.900988 -220.319854)
			(xy 355.680772 -220.319854) (xy 355.680163 -220.347508) (xy 355.670839 -220.402026) (xy 355.66223 -220.428312)
			(xy 355.65461 -220.45041) (xy 355.859842 -220.805756) (xy 355.882702 -220.810074) (xy 355.907508 -220.815252)
			(xy 355.955247 -220.832242) (xy 355.999825 -220.856337) (xy 356.040191 -220.886969) (xy 356.075395 -220.923417)
			(xy 356.104606 -220.964822) (xy 356.127138 -221.01021) (xy 356.14246 -221.058511) (xy 356.15021 -221.108588)
			(xy 356.150672 -221.133924) (xy 356.150164 -221.159811) (xy 356.142065 -221.210949) (xy 356.126066 -221.260189)
			(xy 356.10256 -221.306321) (xy 356.072128 -221.348208) (xy 356.035518 -221.384818) (xy 355.993631 -221.41525)
			(xy 355.947499 -221.438756) (xy 355.898259 -221.454755) (xy 355.847121 -221.462854) (xy 355.795347 -221.462854)
			(xy 355.744209 -221.454755) (xy 355.694969 -221.438756) (xy 355.648837 -221.41525) (xy 355.60695 -221.384818)
			(xy 355.57034 -221.348208) (xy 355.539908 -221.306321) (xy 355.516402 -221.260189) (xy 355.500403 -221.210949)
			(xy 355.492304 -221.159811) (xy 355.491796 -221.133924) (xy 355.492332 -221.106216) (xy 355.501523 -221.051569)
			(xy 355.510084 -221.025212) (xy 355.517958 -221.003114) (xy 355.31298 -220.648022) (xy 355.29012 -220.643704)
			(xy 355.265279 -220.638521) (xy 355.217432 -220.621628) (xy 355.17274 -220.5976) (xy 355.132259 -220.567005)
			(xy 355.096948 -220.530566) (xy 355.067639 -220.489145) (xy 355.045027 -220.44372) (xy 355.029646 -220.395365)
			(xy 355.021859 -220.345225) (xy 355.021388 -220.319854) (xy 353.801172 -220.319854) (xy 353.800563 -220.347508)
			(xy 353.791239 -220.402026) (xy 353.78263 -220.428312) (xy 353.77501 -220.45041) (xy 353.980242 -220.805756)
			(xy 354.003102 -220.810074) (xy 354.027908 -220.815252) (xy 354.075647 -220.832242) (xy 354.120225 -220.856337)
			(xy 354.160591 -220.886969) (xy 354.195795 -220.923417) (xy 354.225006 -220.964822) (xy 354.247538 -221.01021)
			(xy 354.26286 -221.058511) (xy 354.27061 -221.108588) (xy 354.271072 -221.133924) (xy 354.270564 -221.159811)
			(xy 354.262465 -221.210949) (xy 354.246466 -221.260189) (xy 354.22296 -221.306321) (xy 354.192528 -221.348208)
			(xy 354.155918 -221.384818) (xy 354.114031 -221.41525) (xy 354.067899 -221.438756) (xy 354.018659 -221.454755)
			(xy 353.967521 -221.462854) (xy 353.915747 -221.462854) (xy 353.864609 -221.454755) (xy 353.815369 -221.438756)
			(xy 353.769237 -221.41525) (xy 353.72735 -221.384818) (xy 353.69074 -221.348208) (xy 353.660308 -221.306321)
			(xy 353.636802 -221.260189) (xy 353.620803 -221.210949) (xy 353.612704 -221.159811) (xy 353.612196 -221.133924)
			(xy 353.612732 -221.106216) (xy 353.621923 -221.051569) (xy 353.630484 -221.025212) (xy 353.638358 -221.003114)
			(xy 353.43338 -220.648022) (xy 353.41052 -220.643704) (xy 353.385679 -220.638521) (xy 353.337832 -220.621628)
			(xy 353.29314 -220.5976) (xy 353.252659 -220.567005) (xy 353.217348 -220.530566) (xy 353.188039 -220.489145)
			(xy 353.165427 -220.44372) (xy 353.150046 -220.395365) (xy 353.142259 -220.345225) (xy 353.141788 -220.319854)
			(xy 351.921572 -220.319854) (xy 351.92111 -220.345203) (xy 351.913353 -220.395304) (xy 351.898016 -220.443627)
			(xy 351.875459 -220.48903) (xy 351.846215 -220.530444) (xy 351.810974 -220.56689) (xy 351.770567 -220.59751)
			(xy 351.725948 -220.621582) (xy 351.678169 -220.638536) (xy 351.653348 -220.643704) (xy 351.630488 -220.648022)
			(xy 351.425002 -221.003876) (xy 351.430844 -221.0181) (xy 352.141536 -221.728792) (xy 352.151538 -221.738172)
			(xy 352.175372 -221.751708) (xy 352.201948 -221.758413) (xy 352.229351 -221.757803) (xy 352.255603 -221.749923)
			(xy 352.278811 -221.73534) (xy 352.288348 -221.72549) (xy 352.306617 -221.706275) (xy 352.348171 -221.673351)
			(xy 352.39445 -221.647487) (xy 352.444267 -221.629347) (xy 352.470212 -221.62389) (xy 352.493072 -221.619572)
			(xy 352.698304 -221.264226) (xy 352.69043 -221.242128) (xy 352.681967 -221.215884) (xy 352.672903 -221.161494)
			(xy 352.672396 -221.133924) (xy 352.672904 -221.108037) (xy 352.681003 -221.056899) (xy 352.697002 -221.007659)
			(xy 352.720508 -220.961527) (xy 352.75094 -220.91964) (xy 352.78755 -220.88303) (xy 352.829437 -220.852598)
			(xy 352.875569 -220.829092) (xy 352.924809 -220.813093) (xy 352.975947 -220.804994) (xy 353.027721 -220.804994)
			(xy 353.078859 -220.813093) (xy 353.128099 -220.829092) (xy 353.174231 -220.852598) (xy 353.216118 -220.88303)
			(xy 353.252728 -220.91964) (xy 353.28316 -220.961527) (xy 353.306666 -221.007659) (xy 353.322665 -221.056899)
			(xy 353.330764 -221.108037) (xy 353.331272 -221.133924) (xy 353.330803 -221.159298) (xy 353.32302 -221.209444)
			(xy 353.307643 -221.257806) (xy 353.285034 -221.303238) (xy 353.255729 -221.344668) (xy 353.220419 -221.381116)
			(xy 353.179939 -221.411721) (xy 353.135246 -221.435759) (xy 353.087397 -221.452663) (xy 353.06254 -221.457774)
			(xy 353.03968 -221.462092) (xy 352.834956 -221.81693) (xy 352.84283 -221.838774) (xy 352.851474 -221.865183)
			(xy 352.860791 -221.919959) (xy 352.861372 -221.94774) (xy 354.081588 -221.94774) (xy 354.082065 -221.922395)
			(xy 354.089845 -221.872306) (xy 354.105197 -221.823996) (xy 354.12776 -221.778605) (xy 354.157003 -221.7372)
			(xy 354.192237 -221.700757) (xy 354.232631 -221.670134) (xy 354.277236 -221.646052) (xy 354.324999 -221.629078)
			(xy 354.349812 -221.62389) (xy 354.372672 -221.619572) (xy 354.577904 -221.264226) (xy 354.57003 -221.242128)
			(xy 354.561565 -221.215883) (xy 354.552493 -221.161495) (xy 354.551996 -221.133924) (xy 354.552504 -221.108037)
			(xy 354.560603 -221.056899) (xy 354.576602 -221.007659) (xy 354.600108 -220.961527) (xy 354.63054 -220.91964)
			(xy 354.66715 -220.88303) (xy 354.709037 -220.852598) (xy 354.755169 -220.829092) (xy 354.804409 -220.813093)
			(xy 354.855547 -220.804994) (xy 354.907321 -220.804994) (xy 354.958459 -220.813093) (xy 355.007699 -220.829092)
			(xy 355.053831 -220.852598) (xy 355.095718 -220.88303) (xy 355.132328 -220.91964) (xy 355.16276 -220.961527)
			(xy 355.186266 -221.007659) (xy 355.202265 -221.056899) (xy 355.210364 -221.108037) (xy 355.210872 -221.133924)
			(xy 355.210442 -221.1593) (xy 355.202669 -221.209454) (xy 355.187296 -221.257821) (xy 355.164686 -221.303259)
			(xy 355.135374 -221.344691) (xy 355.100055 -221.381137) (xy 355.059563 -221.411734) (xy 355.014858 -221.435759)
			(xy 354.966996 -221.452643) (xy 354.94214 -221.457774) (xy 354.91928 -221.462092) (xy 354.714556 -221.81693)
			(xy 354.72243 -221.838774) (xy 354.731086 -221.865179) (xy 354.7404 -221.919958) (xy 354.740972 -221.94774)
			(xy 355.961188 -221.94774) (xy 355.961665 -221.922395) (xy 355.969445 -221.872306) (xy 355.984797 -221.823996)
			(xy 356.00736 -221.778605) (xy 356.036603 -221.7372) (xy 356.071837 -221.700757) (xy 356.112231 -221.670134)
			(xy 356.156836 -221.646052) (xy 356.204599 -221.629078) (xy 356.229412 -221.62389) (xy 356.252272 -221.619572)
			(xy 356.457504 -221.264226) (xy 356.44963 -221.242128) (xy 356.441165 -221.215883) (xy 356.432093 -221.161495)
			(xy 356.431596 -221.133924) (xy 356.432104 -221.108037) (xy 356.440203 -221.056899) (xy 356.456202 -221.007659)
			(xy 356.479708 -220.961527) (xy 356.51014 -220.91964) (xy 356.54675 -220.88303) (xy 356.588637 -220.852598)
			(xy 356.634769 -220.829092) (xy 356.684009 -220.813093) (xy 356.735147 -220.804994) (xy 356.786921 -220.804994)
			(xy 356.838059 -220.813093) (xy 356.887299 -220.829092) (xy 356.933431 -220.852598) (xy 356.975318 -220.88303)
			(xy 357.011928 -220.91964) (xy 357.04236 -220.961527) (xy 357.065866 -221.007659) (xy 357.081865 -221.056899)
			(xy 357.089964 -221.108037) (xy 357.090472 -221.133924) (xy 357.090042 -221.1593) (xy 357.082269 -221.209454)
			(xy 357.066896 -221.257821) (xy 357.044286 -221.303259) (xy 357.014974 -221.344691) (xy 356.979655 -221.381137)
			(xy 356.939163 -221.411734) (xy 356.894458 -221.435759) (xy 356.846596 -221.452643) (xy 356.82174 -221.457774)
			(xy 356.79888 -221.462092) (xy 356.594156 -221.81693) (xy 356.60203 -221.838774) (xy 356.610686 -221.865179)
			(xy 356.62 -221.919958) (xy 356.620572 -221.94774) (xy 357.841296 -221.94774) (xy 357.841727 -221.922404)
			(xy 357.849489 -221.872329) (xy 357.864819 -221.824032) (xy 357.887358 -221.778648) (xy 357.916574 -221.737246)
			(xy 357.95178 -221.700802) (xy 357.992148 -221.670172) (xy 358.036725 -221.646079) (xy 358.084465 -221.629089)
			(xy 358.109266 -221.62389) (xy 358.132126 -221.619572) (xy 358.337104 -221.26448) (xy 358.329484 -221.242382)
			(xy 358.320964 -221.216211) (xy 358.311771 -221.161949) (xy 358.311196 -221.134432) (xy 358.311196 -221.133924)
			(xy 358.311704 -221.108037) (xy 358.319803 -221.056899) (xy 358.335802 -221.007659) (xy 358.359308 -220.961527)
			(xy 358.38974 -220.91964) (xy 358.42635 -220.88303) (xy 358.468237 -220.852598) (xy 358.514369 -220.829092)
			(xy 358.563609 -220.813093) (xy 358.614747 -220.804994) (xy 358.666521 -220.804994) (xy 358.717659 -220.813093)
			(xy 358.766899 -220.829092) (xy 358.813031 -220.852598) (xy 358.854918 -220.88303) (xy 358.891528 -220.91964)
			(xy 358.92196 -220.961527) (xy 358.945466 -221.007659) (xy 358.961465 -221.056899) (xy 358.969564 -221.108037)
			(xy 358.970072 -221.133924) (xy 358.969679 -221.159291) (xy 358.961926 -221.209429) (xy 358.946575 -221.257784)
			(xy 358.923991 -221.303213) (xy 358.894706 -221.344642) (xy 358.859415 -221.381089) (xy 358.818952 -221.411694)
			(xy 358.774274 -221.435731) (xy 358.726438 -221.452632) (xy 358.701594 -221.457774) (xy 358.678734 -221.462092)
			(xy 358.47401 -221.81693) (xy 358.481884 -221.838774) (xy 358.490481 -221.865188) (xy 358.499666 -221.919967)
			(xy 358.500172 -221.94774) (xy 359.720388 -221.94774) (xy 359.720865 -221.922395) (xy 359.728645 -221.872306)
			(xy 359.743997 -221.823996) (xy 359.76656 -221.778605) (xy 359.795803 -221.7372) (xy 359.831037 -221.700757)
			(xy 359.871431 -221.670134) (xy 359.916036 -221.646052) (xy 359.963799 -221.629078) (xy 359.988612 -221.62389)
			(xy 360.011472 -221.619572) (xy 360.216704 -221.264226) (xy 360.20883 -221.242128) (xy 360.200365 -221.215883)
			(xy 360.191293 -221.161495) (xy 360.190796 -221.133924) (xy 360.191304 -221.108037) (xy 360.199403 -221.056899)
			(xy 360.215402 -221.007659) (xy 360.238908 -220.961527) (xy 360.26934 -220.91964) (xy 360.30595 -220.88303)
			(xy 360.347837 -220.852598) (xy 360.393969 -220.829092) (xy 360.443209 -220.813093) (xy 360.494347 -220.804994)
			(xy 360.546121 -220.804994) (xy 360.597259 -220.813093) (xy 360.646499 -220.829092) (xy 360.692631 -220.852598)
			(xy 360.734518 -220.88303) (xy 360.771128 -220.91964) (xy 360.80156 -220.961527) (xy 360.825066 -221.007659)
			(xy 360.841065 -221.056899) (xy 360.849164 -221.108037) (xy 360.849672 -221.133924) (xy 360.849242 -221.1593)
			(xy 360.841469 -221.209454) (xy 360.826096 -221.257821) (xy 360.803486 -221.303259) (xy 360.774174 -221.344691)
			(xy 360.738855 -221.381137) (xy 360.698363 -221.411734) (xy 360.653658 -221.435759) (xy 360.605796 -221.452643)
			(xy 360.58094 -221.457774) (xy 360.55808 -221.462092) (xy 360.353356 -221.81693) (xy 360.36123 -221.838774)
			(xy 360.369886 -221.865179) (xy 360.3792 -221.919958) (xy 360.379772 -221.94774) (xy 361.600496 -221.94774)
			(xy 361.600927 -221.922404) (xy 361.608689 -221.872329) (xy 361.624019 -221.824032) (xy 361.646558 -221.778648)
			(xy 361.675774 -221.737246) (xy 361.71098 -221.700802) (xy 361.751348 -221.670172) (xy 361.795925 -221.646079)
			(xy 361.843665 -221.629089) (xy 361.868466 -221.62389) (xy 361.891326 -221.619572) (xy 362.096304 -221.26448)
			(xy 362.088684 -221.242382) (xy 362.080164 -221.216211) (xy 362.070971 -221.161949) (xy 362.070396 -221.134432)
			(xy 362.070396 -221.133924) (xy 362.070904 -221.108037) (xy 362.079003 -221.056899) (xy 362.095002 -221.007659)
			(xy 362.118508 -220.961527) (xy 362.14894 -220.91964) (xy 362.18555 -220.88303) (xy 362.227437 -220.852598)
			(xy 362.273569 -220.829092) (xy 362.322809 -220.813093) (xy 362.373947 -220.804994) (xy 362.425721 -220.804994)
			(xy 362.476859 -220.813093) (xy 362.526099 -220.829092) (xy 362.572231 -220.852598) (xy 362.614118 -220.88303)
			(xy 362.650728 -220.91964) (xy 362.68116 -220.961527) (xy 362.704666 -221.007659) (xy 362.720665 -221.056899)
			(xy 362.728764 -221.108037) (xy 362.729272 -221.133924) (xy 362.728879 -221.159291) (xy 362.721126 -221.209429)
			(xy 362.705775 -221.257784) (xy 362.683191 -221.303213) (xy 362.653906 -221.344642) (xy 362.618615 -221.381089)
			(xy 362.578152 -221.411694) (xy 362.533474 -221.435731) (xy 362.485638 -221.452632) (xy 362.460794 -221.457774)
			(xy 362.437934 -221.462092) (xy 362.23321 -221.81693) (xy 362.241084 -221.838774) (xy 362.249681 -221.865188)
			(xy 362.258866 -221.919967) (xy 362.259372 -221.94774) (xy 362.258864 -221.973627) (xy 362.250765 -222.024765)
			(xy 362.234766 -222.074005) (xy 362.21126 -222.120137) (xy 362.180828 -222.162024) (xy 362.144218 -222.198634)
			(xy 362.102331 -222.229066) (xy 362.056199 -222.252572) (xy 362.006959 -222.268571) (xy 361.955821 -222.27667)
			(xy 361.904047 -222.27667) (xy 361.852909 -222.268571) (xy 361.803669 -222.252572) (xy 361.757537 -222.229066)
			(xy 361.71565 -222.198634) (xy 361.67904 -222.162024) (xy 361.648608 -222.120137) (xy 361.625102 -222.074005)
			(xy 361.609103 -222.024765) (xy 361.601004 -221.973627) (xy 361.600496 -221.94774) (xy 360.379772 -221.94774)
			(xy 360.379264 -221.973647) (xy 360.371158 -222.024824) (xy 360.355146 -222.074103) (xy 360.331623 -222.12027)
			(xy 360.301167 -222.162189) (xy 360.264529 -222.198827) (xy 360.22261 -222.229283) (xy 360.176443 -222.252806)
			(xy 360.127164 -222.268818) (xy 360.075987 -222.276924) (xy 360.024173 -222.276924) (xy 359.972996 -222.268818)
			(xy 359.923717 -222.252806) (xy 359.87755 -222.229283) (xy 359.835631 -222.198827) (xy 359.798993 -222.162189)
			(xy 359.768537 -222.12027) (xy 359.745014 -222.074103) (xy 359.729002 -222.024824) (xy 359.720896 -221.973647)
			(xy 359.720388 -221.94774) (xy 358.500172 -221.94774) (xy 358.499664 -221.973627) (xy 358.491565 -222.024765)
			(xy 358.475566 -222.074005) (xy 358.45206 -222.120137) (xy 358.421628 -222.162024) (xy 358.385018 -222.198634)
			(xy 358.343131 -222.229066) (xy 358.296999 -222.252572) (xy 358.247759 -222.268571) (xy 358.196621 -222.27667)
			(xy 358.144847 -222.27667) (xy 358.093709 -222.268571) (xy 358.044469 -222.252572) (xy 357.998337 -222.229066)
			(xy 357.95645 -222.198634) (xy 357.91984 -222.162024) (xy 357.889408 -222.120137) (xy 357.865902 -222.074005)
			(xy 357.849903 -222.024765) (xy 357.841804 -221.973627) (xy 357.841296 -221.94774) (xy 356.620572 -221.94774)
			(xy 356.620064 -221.973647) (xy 356.611958 -222.024824) (xy 356.595946 -222.074103) (xy 356.572423 -222.12027)
			(xy 356.541967 -222.162189) (xy 356.505329 -222.198827) (xy 356.46341 -222.229283) (xy 356.417243 -222.252806)
			(xy 356.367964 -222.268818) (xy 356.316787 -222.276924) (xy 356.264973 -222.276924) (xy 356.213796 -222.268818)
			(xy 356.164517 -222.252806) (xy 356.11835 -222.229283) (xy 356.076431 -222.198827) (xy 356.039793 -222.162189)
			(xy 356.009337 -222.12027) (xy 355.985814 -222.074103) (xy 355.969802 -222.024824) (xy 355.961696 -221.973647)
			(xy 355.961188 -221.94774) (xy 354.740972 -221.94774) (xy 354.740464 -221.973647) (xy 354.732358 -222.024824)
			(xy 354.716346 -222.074103) (xy 354.692823 -222.12027) (xy 354.662367 -222.162189) (xy 354.625729 -222.198827)
			(xy 354.58381 -222.229283) (xy 354.537643 -222.252806) (xy 354.488364 -222.268818) (xy 354.437187 -222.276924)
			(xy 354.385373 -222.276924) (xy 354.334196 -222.268818) (xy 354.284917 -222.252806) (xy 354.23875 -222.229283)
			(xy 354.196831 -222.198827) (xy 354.160193 -222.162189) (xy 354.129737 -222.12027) (xy 354.106214 -222.074103)
			(xy 354.090202 -222.024824) (xy 354.082096 -221.973647) (xy 354.081588 -221.94774) (xy 352.861372 -221.94774)
			(xy 352.860861 -221.973645) (xy 352.85275 -222.024815) (xy 352.836735 -222.074087) (xy 352.813209 -222.120248)
			(xy 352.782752 -222.162159) (xy 352.746114 -222.198791) (xy 352.704196 -222.22924) (xy 352.658032 -222.252758)
			(xy 352.608757 -222.268764) (xy 352.557585 -222.276865) (xy 352.53168 -222.277432) (xy 352.504501 -222.276907)
			(xy 352.450883 -222.267965) (xy 352.425 -222.259652) (xy 352.411797 -222.255649) (xy 352.384264 -222.254087)
			(xy 352.357316 -222.25995) (xy 352.332919 -222.272808) (xy 352.312852 -222.291725) (xy 352.298578 -222.315321)
			(xy 352.291138 -222.341876) (xy 352.290634 -222.355664) (xy 352.290634 -222.526098) (xy 352.309126 -222.544773)
			(xy 352.340518 -222.58692) (xy 352.364793 -222.63353) (xy 352.381331 -222.683413) (xy 352.389709 -222.735293)
			(xy 352.389714 -222.787846) (xy 352.381346 -222.839728) (xy 352.364817 -222.889614) (xy 352.340551 -222.936228)
			(xy 352.309167 -222.978381) (xy 352.290634 -222.997014) (xy 352.290634 -224.151952) (xy 352.309364 -224.170741)
			(xy 352.341168 -224.213199) (xy 352.365755 -224.260206) (xy 352.382489 -224.310546) (xy 352.390938 -224.362917)
			(xy 352.391472 -224.389442) (xy 352.672396 -224.389442) (xy 352.672829 -224.364106) (xy 352.68059 -224.314032)
			(xy 352.69592 -224.265734) (xy 352.718459 -224.22035) (xy 352.747675 -224.178949) (xy 352.782881 -224.142504)
			(xy 352.823248 -224.111874) (xy 352.867826 -224.087781) (xy 352.915565 -224.070791) (xy 352.940366 -224.065592)
			(xy 352.963226 -224.061274) (xy 353.16795 -223.706436) (xy 353.16033 -223.684338) (xy 353.151702 -223.657991)
			(xy 353.142379 -223.603344) (xy 353.141788 -223.575626) (xy 353.142296 -223.549719) (xy 353.150402 -223.498542)
			(xy 353.166414 -223.449263) (xy 353.189937 -223.403096) (xy 353.220393 -223.361177) (xy 353.257031 -223.324539)
			(xy 353.29895 -223.294083) (xy 353.345117 -223.27056) (xy 353.394396 -223.254548) (xy 353.445573 -223.246442)
			(xy 353.497387 -223.246442) (xy 353.548564 -223.254548) (xy 353.597843 -223.27056) (xy 353.64401 -223.294083)
			(xy 353.685929 -223.324539) (xy 353.722567 -223.361177) (xy 353.753023 -223.403096) (xy 353.776546 -223.449263)
			(xy 353.792558 -223.498542) (xy 353.800664 -223.549719) (xy 353.801172 -223.575626) (xy 353.800781 -223.600993)
			(xy 353.793028 -223.651131) (xy 353.777677 -223.699486) (xy 353.755092 -223.744915) (xy 353.725807 -223.786344)
			(xy 353.690516 -223.822791) (xy 353.650052 -223.853396) (xy 353.605374 -223.877433) (xy 353.557539 -223.894334)
			(xy 353.532694 -223.899476) (xy 353.509834 -223.903794) (xy 353.30511 -224.258632) (xy 353.312984 -224.280476)
			(xy 353.321557 -224.306897) (xy 353.330758 -224.36167) (xy 353.331272 -224.389442) (xy 353.612196 -224.389442)
			(xy 353.612704 -224.363555) (xy 353.620803 -224.312417) (xy 353.636802 -224.263177) (xy 353.660308 -224.217045)
			(xy 353.69074 -224.175158) (xy 353.72735 -224.138548) (xy 353.769237 -224.108116) (xy 353.815369 -224.08461)
			(xy 353.864609 -224.068611) (xy 353.915747 -224.060512) (xy 353.967521 -224.060512) (xy 354.018659 -224.068611)
			(xy 354.067899 -224.08461) (xy 354.114031 -224.108116) (xy 354.155918 -224.138548) (xy 354.192528 -224.175158)
			(xy 354.22296 -224.217045) (xy 354.246466 -224.263177) (xy 354.262465 -224.312417) (xy 354.270564 -224.363555)
			(xy 354.271072 -224.389442) (xy 354.551996 -224.389442) (xy 354.552429 -224.364106) (xy 354.56019 -224.314032)
			(xy 354.57552 -224.265734) (xy 354.598059 -224.22035) (xy 354.627275 -224.178949) (xy 354.662481 -224.142504)
			(xy 354.702848 -224.111874) (xy 354.747426 -224.087781) (xy 354.795165 -224.070791) (xy 354.819966 -224.065592)
			(xy 354.842826 -224.061274) (xy 355.04755 -223.706436) (xy 355.03993 -223.684338) (xy 355.031302 -223.657991)
			(xy 355.021979 -223.603344) (xy 355.021388 -223.575626) (xy 355.021896 -223.549719) (xy 355.030002 -223.498542)
			(xy 355.046014 -223.449263) (xy 355.069537 -223.403096) (xy 355.099993 -223.361177) (xy 355.136631 -223.324539)
			(xy 355.17855 -223.294083) (xy 355.224717 -223.27056) (xy 355.273996 -223.254548) (xy 355.325173 -223.246442)
			(xy 355.376987 -223.246442) (xy 355.428164 -223.254548) (xy 355.477443 -223.27056) (xy 355.52361 -223.294083)
			(xy 355.565529 -223.324539) (xy 355.602167 -223.361177) (xy 355.632623 -223.403096) (xy 355.656146 -223.449263)
			(xy 355.672158 -223.498542) (xy 355.680264 -223.549719) (xy 355.680772 -223.575626) (xy 355.680381 -223.600993)
			(xy 355.672628 -223.651131) (xy 355.657277 -223.699486) (xy 355.634692 -223.744915) (xy 355.605407 -223.786344)
			(xy 355.570116 -223.822791) (xy 355.529652 -223.853396) (xy 355.484974 -223.877433) (xy 355.437139 -223.894334)
			(xy 355.412294 -223.899476) (xy 355.389434 -223.903794) (xy 355.18471 -224.258632) (xy 355.192584 -224.280476)
			(xy 355.201157 -224.306897) (xy 355.210358 -224.36167) (xy 355.210872 -224.389442) (xy 355.491796 -224.389442)
			(xy 355.492304 -224.363555) (xy 355.500403 -224.312417) (xy 355.516402 -224.263177) (xy 355.539908 -224.217045)
			(xy 355.57034 -224.175158) (xy 355.60695 -224.138548) (xy 355.648837 -224.108116) (xy 355.694969 -224.08461)
			(xy 355.744209 -224.068611) (xy 355.795347 -224.060512) (xy 355.847121 -224.060512) (xy 355.898259 -224.068611)
			(xy 355.947499 -224.08461) (xy 355.993631 -224.108116) (xy 356.035518 -224.138548) (xy 356.072128 -224.175158)
			(xy 356.10256 -224.217045) (xy 356.126066 -224.263177) (xy 356.142065 -224.312417) (xy 356.150164 -224.363555)
			(xy 356.150672 -224.389442) (xy 356.431596 -224.389442) (xy 356.432029 -224.364106) (xy 356.43979 -224.314032)
			(xy 356.45512 -224.265734) (xy 356.477659 -224.22035) (xy 356.506875 -224.178949) (xy 356.542081 -224.142504)
			(xy 356.582448 -224.111874) (xy 356.627026 -224.087781) (xy 356.674765 -224.070791) (xy 356.699566 -224.065592)
			(xy 356.722426 -224.061274) (xy 356.92715 -223.706436) (xy 356.91953 -223.684338) (xy 356.910902 -223.657991)
			(xy 356.901579 -223.603344) (xy 356.900988 -223.575626) (xy 356.901496 -223.549719) (xy 356.909602 -223.498542)
			(xy 356.925614 -223.449263) (xy 356.949137 -223.403096) (xy 356.979593 -223.361177) (xy 357.016231 -223.324539)
			(xy 357.05815 -223.294083) (xy 357.104317 -223.27056) (xy 357.153596 -223.254548) (xy 357.204773 -223.246442)
			(xy 357.256587 -223.246442) (xy 357.307764 -223.254548) (xy 357.357043 -223.27056) (xy 357.40321 -223.294083)
			(xy 357.445129 -223.324539) (xy 357.481767 -223.361177) (xy 357.512223 -223.403096) (xy 357.535746 -223.449263)
			(xy 357.551758 -223.498542) (xy 357.559864 -223.549719) (xy 357.560372 -223.575626) (xy 357.559981 -223.600993)
			(xy 357.552228 -223.651131) (xy 357.536877 -223.699486) (xy 357.514292 -223.744915) (xy 357.485007 -223.786344)
			(xy 357.449716 -223.822791) (xy 357.409252 -223.853396) (xy 357.364574 -223.877433) (xy 357.316739 -223.894334)
			(xy 357.291894 -223.899476) (xy 357.269034 -223.903794) (xy 357.06431 -224.258632) (xy 357.072184 -224.280476)
			(xy 357.080757 -224.306897) (xy 357.089958 -224.36167) (xy 357.090472 -224.389442) (xy 357.371396 -224.389442)
			(xy 357.371904 -224.363555) (xy 357.380003 -224.312417) (xy 357.396002 -224.263177) (xy 357.419508 -224.217045)
			(xy 357.44994 -224.175158) (xy 357.48655 -224.138548) (xy 357.528437 -224.108116) (xy 357.574569 -224.08461)
			(xy 357.623809 -224.068611) (xy 357.674947 -224.060512) (xy 357.726721 -224.060512) (xy 357.777859 -224.068611)
			(xy 357.827099 -224.08461) (xy 357.873231 -224.108116) (xy 357.915118 -224.138548) (xy 357.951728 -224.175158)
			(xy 357.98216 -224.217045) (xy 358.005666 -224.263177) (xy 358.021665 -224.312417) (xy 358.029764 -224.363555)
			(xy 358.030272 -224.389442) (xy 358.311196 -224.389442) (xy 358.311629 -224.364106) (xy 358.31939 -224.314032)
			(xy 358.33472 -224.265734) (xy 358.357259 -224.22035) (xy 358.386475 -224.178949) (xy 358.421681 -224.142504)
			(xy 358.462048 -224.111874) (xy 358.506626 -224.087781) (xy 358.554365 -224.070791) (xy 358.579166 -224.065592)
			(xy 358.602026 -224.061274) (xy 358.80675 -223.706436) (xy 358.79913 -223.684338) (xy 358.790502 -223.657991)
			(xy 358.781179 -223.603344) (xy 358.780588 -223.575626) (xy 358.781096 -223.549719) (xy 358.789202 -223.498542)
			(xy 358.805214 -223.449263) (xy 358.828737 -223.403096) (xy 358.859193 -223.361177) (xy 358.895831 -223.324539)
			(xy 358.93775 -223.294083) (xy 358.983917 -223.27056) (xy 359.033196 -223.254548) (xy 359.084373 -223.246442)
			(xy 359.136187 -223.246442) (xy 359.187364 -223.254548) (xy 359.236643 -223.27056) (xy 359.28281 -223.294083)
			(xy 359.324729 -223.324539) (xy 359.361367 -223.361177) (xy 359.391823 -223.403096) (xy 359.415346 -223.449263)
			(xy 359.431358 -223.498542) (xy 359.439464 -223.549719) (xy 359.439972 -223.575626) (xy 359.439581 -223.600993)
			(xy 359.431828 -223.651131) (xy 359.416477 -223.699486) (xy 359.393892 -223.744915) (xy 359.364607 -223.786344)
			(xy 359.329316 -223.822791) (xy 359.288852 -223.853396) (xy 359.244174 -223.877433) (xy 359.196339 -223.894334)
			(xy 359.171494 -223.899476) (xy 359.148634 -223.903794) (xy 358.94391 -224.258632) (xy 358.951784 -224.280476)
			(xy 358.960357 -224.306897) (xy 358.969558 -224.36167) (xy 358.970072 -224.389442) (xy 359.250996 -224.389442)
			(xy 359.251504 -224.363555) (xy 359.259603 -224.312417) (xy 359.275602 -224.263177) (xy 359.299108 -224.217045)
			(xy 359.32954 -224.175158) (xy 359.36615 -224.138548) (xy 359.408037 -224.108116) (xy 359.454169 -224.08461)
			(xy 359.503409 -224.068611) (xy 359.554547 -224.060512) (xy 359.606321 -224.060512) (xy 359.657459 -224.068611)
			(xy 359.706699 -224.08461) (xy 359.752831 -224.108116) (xy 359.794718 -224.138548) (xy 359.831328 -224.175158)
			(xy 359.86176 -224.217045) (xy 359.885266 -224.263177) (xy 359.901265 -224.312417) (xy 359.909364 -224.363555)
			(xy 359.909872 -224.389442) (xy 360.190796 -224.389442) (xy 360.191229 -224.364106) (xy 360.19899 -224.314032)
			(xy 360.21432 -224.265734) (xy 360.236859 -224.22035) (xy 360.266075 -224.178949) (xy 360.301281 -224.142504)
			(xy 360.341648 -224.111874) (xy 360.386226 -224.087781) (xy 360.433965 -224.070791) (xy 360.458766 -224.065592)
			(xy 360.481626 -224.061274) (xy 360.68635 -223.706436) (xy 360.67873 -223.684338) (xy 360.670102 -223.657991)
			(xy 360.660779 -223.603344) (xy 360.660188 -223.575626) (xy 360.660696 -223.549719) (xy 360.668802 -223.498542)
			(xy 360.684814 -223.449263) (xy 360.708337 -223.403096) (xy 360.738793 -223.361177) (xy 360.775431 -223.324539)
			(xy 360.81735 -223.294083) (xy 360.863517 -223.27056) (xy 360.912796 -223.254548) (xy 360.963973 -223.246442)
			(xy 361.015787 -223.246442) (xy 361.066964 -223.254548) (xy 361.116243 -223.27056) (xy 361.16241 -223.294083)
			(xy 361.204329 -223.324539) (xy 361.240967 -223.361177) (xy 361.271423 -223.403096) (xy 361.294946 -223.449263)
			(xy 361.310958 -223.498542) (xy 361.319064 -223.549719) (xy 361.319572 -223.575626) (xy 361.319181 -223.600993)
			(xy 361.311428 -223.651131) (xy 361.296077 -223.699486) (xy 361.273492 -223.744915) (xy 361.244207 -223.786344)
			(xy 361.208916 -223.822791) (xy 361.168452 -223.853396) (xy 361.123774 -223.877433) (xy 361.075939 -223.894334)
			(xy 361.051094 -223.899476) (xy 361.028234 -223.903794) (xy 360.82351 -224.258632) (xy 360.831384 -224.280476)
			(xy 360.839957 -224.306897) (xy 360.849158 -224.36167) (xy 360.849672 -224.389442) (xy 361.130596 -224.389442)
			(xy 361.131104 -224.363555) (xy 361.139203 -224.312417) (xy 361.155202 -224.263177) (xy 361.178708 -224.217045)
			(xy 361.20914 -224.175158) (xy 361.24575 -224.138548) (xy 361.287637 -224.108116) (xy 361.333769 -224.08461)
			(xy 361.383009 -224.068611) (xy 361.434147 -224.060512) (xy 361.485921 -224.060512) (xy 361.537059 -224.068611)
			(xy 361.586299 -224.08461) (xy 361.632431 -224.108116) (xy 361.674318 -224.138548) (xy 361.710928 -224.175158)
			(xy 361.74136 -224.217045) (xy 361.764866 -224.263177) (xy 361.780865 -224.312417) (xy 361.788964 -224.363555)
			(xy 361.789472 -224.389442) (xy 361.788925 -224.417149) (xy 361.779741 -224.471796) (xy 361.771184 -224.498154)
			(xy 361.76331 -224.520252) (xy 361.968288 -224.87509) (xy 361.991148 -224.879408) (xy 362.015971 -224.884565)
			(xy 362.063751 -224.90152) (xy 362.108371 -224.925592) (xy 362.148778 -224.956214) (xy 362.184019 -224.992662)
			(xy 362.213263 -225.034077) (xy 362.235819 -225.079482) (xy 362.251156 -225.127806) (xy 362.258911 -225.177908)
			(xy 362.259372 -225.203258) (xy 362.258864 -225.229165) (xy 362.250758 -225.280342) (xy 362.234746 -225.329621)
			(xy 362.211223 -225.375788) (xy 362.180767 -225.417707) (xy 362.144129 -225.454345) (xy 362.10221 -225.484801)
			(xy 362.056043 -225.508324) (xy 362.006764 -225.524336) (xy 361.955587 -225.532442) (xy 361.903773 -225.532442)
			(xy 361.852596 -225.524336) (xy 361.803317 -225.508324) (xy 361.75715 -225.484801) (xy 361.715231 -225.454345)
			(xy 361.678593 -225.417707) (xy 361.648137 -225.375788) (xy 361.624614 -225.329621) (xy 361.608602 -225.280342)
			(xy 361.600496 -225.229165) (xy 361.599988 -225.203258) (xy 361.600597 -225.175541) (xy 361.60991 -225.120895)
			(xy 361.61853 -225.094546) (xy 361.626404 -225.072448) (xy 361.421426 -224.71761) (xy 361.398566 -224.713292)
			(xy 361.373748 -224.708169) (xy 361.326005 -224.691172) (xy 361.281426 -224.667071) (xy 361.24106 -224.636431)
			(xy 361.205857 -224.599976) (xy 361.176648 -224.558564) (xy 361.154119 -224.51317) (xy 361.138801 -224.464863)
			(xy 361.131055 -224.414781) (xy 361.130596 -224.389442) (xy 360.849672 -224.389442) (xy 360.849164 -224.415329)
			(xy 360.841065 -224.466467) (xy 360.825066 -224.515707) (xy 360.80156 -224.561839) (xy 360.771128 -224.603726)
			(xy 360.734518 -224.640336) (xy 360.692631 -224.670768) (xy 360.646499 -224.694274) (xy 360.597259 -224.710273)
			(xy 360.546121 -224.718372) (xy 360.494347 -224.718372) (xy 360.443209 -224.710273) (xy 360.393969 -224.694274)
			(xy 360.347837 -224.670768) (xy 360.30595 -224.640336) (xy 360.26934 -224.603726) (xy 360.238908 -224.561839)
			(xy 360.215402 -224.515707) (xy 360.199403 -224.466467) (xy 360.191304 -224.415329) (xy 360.190796 -224.389442)
			(xy 359.909872 -224.389442) (xy 359.909325 -224.417149) (xy 359.900141 -224.471796) (xy 359.891584 -224.498154)
			(xy 359.88371 -224.520252) (xy 360.088688 -224.87509) (xy 360.111548 -224.879408) (xy 360.136371 -224.884565)
			(xy 360.184151 -224.90152) (xy 360.228771 -224.925592) (xy 360.269178 -224.956214) (xy 360.304419 -224.992662)
			(xy 360.333663 -225.034077) (xy 360.356219 -225.079482) (xy 360.371556 -225.127806) (xy 360.379311 -225.177908)
			(xy 360.379772 -225.203258) (xy 360.379264 -225.229165) (xy 360.371158 -225.280342) (xy 360.355146 -225.329621)
			(xy 360.331623 -225.375788) (xy 360.301167 -225.417707) (xy 360.264529 -225.454345) (xy 360.22261 -225.484801)
			(xy 360.176443 -225.508324) (xy 360.127164 -225.524336) (xy 360.075987 -225.532442) (xy 360.024173 -225.532442)
			(xy 359.972996 -225.524336) (xy 359.923717 -225.508324) (xy 359.87755 -225.484801) (xy 359.835631 -225.454345)
			(xy 359.798993 -225.417707) (xy 359.768537 -225.375788) (xy 359.745014 -225.329621) (xy 359.729002 -225.280342)
			(xy 359.720896 -225.229165) (xy 359.720388 -225.203258) (xy 359.720997 -225.175541) (xy 359.73031 -225.120895)
			(xy 359.73893 -225.094546) (xy 359.746804 -225.072448) (xy 359.541826 -224.71761) (xy 359.518966 -224.713292)
			(xy 359.494148 -224.708169) (xy 359.446405 -224.691172) (xy 359.401826 -224.667071) (xy 359.36146 -224.636431)
			(xy 359.326257 -224.599976) (xy 359.297048 -224.558564) (xy 359.274519 -224.51317) (xy 359.259201 -224.464863)
			(xy 359.251455 -224.414781) (xy 359.250996 -224.389442) (xy 358.970072 -224.389442) (xy 358.969564 -224.415329)
			(xy 358.961465 -224.466467) (xy 358.945466 -224.515707) (xy 358.92196 -224.561839) (xy 358.891528 -224.603726)
			(xy 358.854918 -224.640336) (xy 358.813031 -224.670768) (xy 358.766899 -224.694274) (xy 358.717659 -224.710273)
			(xy 358.666521 -224.718372) (xy 358.614747 -224.718372) (xy 358.563609 -224.710273) (xy 358.514369 -224.694274)
			(xy 358.468237 -224.670768) (xy 358.42635 -224.640336) (xy 358.38974 -224.603726) (xy 358.359308 -224.561839)
			(xy 358.335802 -224.515707) (xy 358.319803 -224.466467) (xy 358.311704 -224.415329) (xy 358.311196 -224.389442)
			(xy 358.030272 -224.389442) (xy 358.029725 -224.417149) (xy 358.020541 -224.471796) (xy 358.011984 -224.498154)
			(xy 358.00411 -224.520252) (xy 358.209088 -224.87509) (xy 358.231948 -224.879408) (xy 358.256771 -224.884565)
			(xy 358.304551 -224.90152) (xy 358.349171 -224.925592) (xy 358.389578 -224.956214) (xy 358.424819 -224.992662)
			(xy 358.454063 -225.034077) (xy 358.476619 -225.079482) (xy 358.491956 -225.127806) (xy 358.499711 -225.177908)
			(xy 358.500172 -225.203258) (xy 358.499664 -225.229165) (xy 358.491558 -225.280342) (xy 358.475546 -225.329621)
			(xy 358.452023 -225.375788) (xy 358.421567 -225.417707) (xy 358.384929 -225.454345) (xy 358.34301 -225.484801)
			(xy 358.296843 -225.508324) (xy 358.247564 -225.524336) (xy 358.196387 -225.532442) (xy 358.144573 -225.532442)
			(xy 358.093396 -225.524336) (xy 358.044117 -225.508324) (xy 357.99795 -225.484801) (xy 357.956031 -225.454345)
			(xy 357.919393 -225.417707) (xy 357.888937 -225.375788) (xy 357.865414 -225.329621) (xy 357.849402 -225.280342)
			(xy 357.841296 -225.229165) (xy 357.840788 -225.203258) (xy 357.841397 -225.175541) (xy 357.85071 -225.120895)
			(xy 357.85933 -225.094546) (xy 357.867204 -225.072448) (xy 357.662226 -224.71761) (xy 357.639366 -224.713292)
			(xy 357.614548 -224.708169) (xy 357.566805 -224.691172) (xy 357.522226 -224.667071) (xy 357.48186 -224.636431)
			(xy 357.446657 -224.599976) (xy 357.417448 -224.558564) (xy 357.394919 -224.51317) (xy 357.379601 -224.464863)
			(xy 357.371855 -224.414781) (xy 357.371396 -224.389442) (xy 357.090472 -224.389442) (xy 357.089964 -224.415329)
			(xy 357.081865 -224.466467) (xy 357.065866 -224.515707) (xy 357.04236 -224.561839) (xy 357.011928 -224.603726)
			(xy 356.975318 -224.640336) (xy 356.933431 -224.670768) (xy 356.887299 -224.694274) (xy 356.838059 -224.710273)
			(xy 356.786921 -224.718372) (xy 356.735147 -224.718372) (xy 356.684009 -224.710273) (xy 356.634769 -224.694274)
			(xy 356.588637 -224.670768) (xy 356.54675 -224.640336) (xy 356.51014 -224.603726) (xy 356.479708 -224.561839)
			(xy 356.456202 -224.515707) (xy 356.440203 -224.466467) (xy 356.432104 -224.415329) (xy 356.431596 -224.389442)
			(xy 356.150672 -224.389442) (xy 356.150125 -224.417149) (xy 356.140941 -224.471796) (xy 356.132384 -224.498154)
			(xy 356.12451 -224.520252) (xy 356.329488 -224.87509) (xy 356.352348 -224.879408) (xy 356.377171 -224.884565)
			(xy 356.424951 -224.90152) (xy 356.469571 -224.925592) (xy 356.509978 -224.956214) (xy 356.545219 -224.992662)
			(xy 356.574463 -225.034077) (xy 356.597019 -225.079482) (xy 356.612356 -225.127806) (xy 356.620111 -225.177908)
			(xy 356.620572 -225.203258) (xy 356.620064 -225.229165) (xy 356.611958 -225.280342) (xy 356.595946 -225.329621)
			(xy 356.572423 -225.375788) (xy 356.541967 -225.417707) (xy 356.505329 -225.454345) (xy 356.46341 -225.484801)
			(xy 356.417243 -225.508324) (xy 356.367964 -225.524336) (xy 356.316787 -225.532442) (xy 356.264973 -225.532442)
			(xy 356.213796 -225.524336) (xy 356.164517 -225.508324) (xy 356.11835 -225.484801) (xy 356.076431 -225.454345)
			(xy 356.039793 -225.417707) (xy 356.009337 -225.375788) (xy 355.985814 -225.329621) (xy 355.969802 -225.280342)
			(xy 355.961696 -225.229165) (xy 355.961188 -225.203258) (xy 355.961797 -225.175541) (xy 355.97111 -225.120895)
			(xy 355.97973 -225.094546) (xy 355.987604 -225.072448) (xy 355.782626 -224.71761) (xy 355.759766 -224.713292)
			(xy 355.734948 -224.708169) (xy 355.687205 -224.691172) (xy 355.642626 -224.667071) (xy 355.60226 -224.636431)
			(xy 355.567057 -224.599976) (xy 355.537848 -224.558564) (xy 355.515319 -224.51317) (xy 355.500001 -224.464863)
			(xy 355.492255 -224.414781) (xy 355.491796 -224.389442) (xy 355.210872 -224.389442) (xy 355.210364 -224.415329)
			(xy 355.202265 -224.466467) (xy 355.186266 -224.515707) (xy 355.16276 -224.561839) (xy 355.132328 -224.603726)
			(xy 355.095718 -224.640336) (xy 355.053831 -224.670768) (xy 355.007699 -224.694274) (xy 354.958459 -224.710273)
			(xy 354.907321 -224.718372) (xy 354.855547 -224.718372) (xy 354.804409 -224.710273) (xy 354.755169 -224.694274)
			(xy 354.709037 -224.670768) (xy 354.66715 -224.640336) (xy 354.63054 -224.603726) (xy 354.600108 -224.561839)
			(xy 354.576602 -224.515707) (xy 354.560603 -224.466467) (xy 354.552504 -224.415329) (xy 354.551996 -224.389442)
			(xy 354.271072 -224.389442) (xy 354.270525 -224.417149) (xy 354.261341 -224.471796) (xy 354.252784 -224.498154)
			(xy 354.24491 -224.520252) (xy 354.449888 -224.87509) (xy 354.472748 -224.879408) (xy 354.497571 -224.884565)
			(xy 354.545351 -224.90152) (xy 354.589971 -224.925592) (xy 354.630378 -224.956214) (xy 354.665619 -224.992662)
			(xy 354.694863 -225.034077) (xy 354.717419 -225.079482) (xy 354.732756 -225.127806) (xy 354.740511 -225.177908)
			(xy 354.740972 -225.203258) (xy 354.740464 -225.229165) (xy 354.732358 -225.280342) (xy 354.716346 -225.329621)
			(xy 354.692823 -225.375788) (xy 354.662367 -225.417707) (xy 354.625729 -225.454345) (xy 354.58381 -225.484801)
			(xy 354.537643 -225.508324) (xy 354.488364 -225.524336) (xy 354.437187 -225.532442) (xy 354.385373 -225.532442)
			(xy 354.334196 -225.524336) (xy 354.284917 -225.508324) (xy 354.23875 -225.484801) (xy 354.196831 -225.454345)
			(xy 354.160193 -225.417707) (xy 354.129737 -225.375788) (xy 354.106214 -225.329621) (xy 354.090202 -225.280342)
			(xy 354.082096 -225.229165) (xy 354.081588 -225.203258) (xy 354.082197 -225.175541) (xy 354.09151 -225.120895)
			(xy 354.10013 -225.094546) (xy 354.108004 -225.072448) (xy 353.903026 -224.71761) (xy 353.880166 -224.713292)
			(xy 353.855348 -224.708169) (xy 353.807605 -224.691172) (xy 353.763026 -224.667071) (xy 353.72266 -224.636431)
			(xy 353.687457 -224.599976) (xy 353.658248 -224.558564) (xy 353.635719 -224.51317) (xy 353.620401 -224.464863)
			(xy 353.612655 -224.414781) (xy 353.612196 -224.389442) (xy 353.331272 -224.389442) (xy 353.330764 -224.415329)
			(xy 353.322665 -224.466467) (xy 353.306666 -224.515707) (xy 353.28316 -224.561839) (xy 353.252728 -224.603726)
			(xy 353.216118 -224.640336) (xy 353.174231 -224.670768) (xy 353.128099 -224.694274) (xy 353.078859 -224.710273)
			(xy 353.027721 -224.718372) (xy 352.975947 -224.718372) (xy 352.924809 -224.710273) (xy 352.875569 -224.694274)
			(xy 352.829437 -224.670768) (xy 352.78755 -224.640336) (xy 352.75094 -224.603726) (xy 352.720508 -224.561839)
			(xy 352.697002 -224.515707) (xy 352.681003 -224.466467) (xy 352.672904 -224.415329) (xy 352.672396 -224.389442)
			(xy 352.391472 -224.389442) (xy 352.390948 -224.417151) (xy 352.381758 -224.4718) (xy 352.373184 -224.498154)
			(xy 352.36531 -224.520252) (xy 352.570288 -224.87509) (xy 352.593148 -224.879408) (xy 352.617962 -224.884594)
			(xy 352.66573 -224.901564) (xy 352.710338 -224.925644) (xy 352.750735 -224.956266) (xy 352.785972 -224.992709)
			(xy 352.815216 -225.034115) (xy 352.837781 -225.079509) (xy 352.853133 -225.12782) (xy 352.860911 -225.177912)
			(xy 352.861372 -225.203258) (xy 352.860893 -225.229163) (xy 352.85279 -225.280336) (xy 352.836779 -225.32961)
			(xy 352.813252 -225.375771) (xy 352.782791 -225.417681) (xy 352.746145 -225.454306) (xy 352.704219 -225.484745)
			(xy 352.658046 -225.508247) (xy 352.608763 -225.524232) (xy 352.557585 -225.532307) (xy 352.53168 -225.532696)
			(xy 352.504509 -225.532238) (xy 352.450888 -225.523432) (xy 352.425 -225.51517) (xy 352.411798 -225.511167)
			(xy 352.384266 -225.509604) (xy 352.357319 -225.515466) (xy 352.332924 -225.528325) (xy 352.31286 -225.547243)
			(xy 352.298589 -225.57084) (xy 352.291153 -225.597395) (xy 352.290634 -225.611182) (xy 352.290634 -225.78187)
			(xy 352.309121 -225.800545) (xy 352.340501 -225.84269) (xy 352.364765 -225.889296) (xy 352.381293 -225.939174)
			(xy 352.389662 -225.991047) (xy 352.389659 -226.043592) (xy 352.381283 -226.095464) (xy 352.36475 -226.14534)
			(xy 352.34048 -226.191944) (xy 352.309095 -226.234085) (xy 352.290634 -226.252786) (xy 352.290634 -227.409502)
			(xy 352.309124 -227.428176) (xy 352.34051 -227.47032) (xy 352.364777 -227.516928) (xy 352.381305 -227.566809)
			(xy 352.389672 -227.618686) (xy 352.390202 -227.64496) (xy 352.389726 -227.670753) (xy 352.381662 -227.721704)
			(xy 352.365727 -227.770766) (xy 352.342313 -227.816732) (xy 352.311997 -227.858469) (xy 352.275525 -227.894949)
			(xy 352.233795 -227.925275) (xy 352.187835 -227.948699) (xy 352.138776 -227.964645) (xy 352.087827 -227.97272)
			(xy 352.062034 -227.973128) (xy 352.025712 -227.971096) (xy 352.001582 -227.968302) (xy 350.01454 -229.955344)
			(xy 350.024192 -229.984808) (xy 350.031789 -230.009583) (xy 350.039952 -230.060753) (xy 350.040448 -230.086662)
			(xy 350.039972 -230.112453) (xy 350.031907 -230.163401) (xy 350.015972 -230.212459) (xy 349.992557 -230.258421)
			(xy 349.962239 -230.300153) (xy 349.925767 -230.336628) (xy 349.884036 -230.366947) (xy 349.838076 -230.390365)
			(xy 349.789018 -230.406303) (xy 349.738071 -230.41437) (xy 349.71228 -230.41483) (xy 349.686372 -230.414322)
			(xy 349.635203 -230.406161) (xy 349.610426 -230.398574) (xy 349.580962 -230.388922) (xy 348.14002 -231.829864)
			(xy 348.13621 -231.839262) (xy 348.125883 -231.863102) (xy 348.098819 -231.907448) (xy 348.065104 -231.946974)
			(xy 348.025582 -231.980694) (xy 347.98124 -232.007764) (xy 347.957394 -232.018078) (xy 347.947996 -232.021888)
			(xy 347.632528 -232.337356) (xy 347.650816 -232.37063) (xy 347.663517 -232.39496) (xy 347.681516 -232.446806)
			(xy 347.690637 -232.500923) (xy 347.691202 -232.528364) (xy 347.690725 -232.554156) (xy 347.682661 -232.605107)
			(xy 347.666726 -232.654169) (xy 347.643312 -232.700134) (xy 347.612996 -232.74187) (xy 347.576524 -232.77835)
			(xy 347.534794 -232.808675) (xy 347.488834 -232.832099) (xy 347.439775 -232.848045) (xy 347.388826 -232.85612)
			(xy 347.363034 -232.856532) (xy 347.335592 -232.855981) (xy 347.281473 -232.846858) (xy 347.229624 -232.828861)
			(xy 347.2053 -232.816146) (xy 347.172026 -232.797858) (xy 345.81211 -234.157774) (xy 345.81084 -234.176824)
			(xy 345.808667 -234.203098) (xy 345.796998 -234.254507) (xy 345.77726 -234.303388) (xy 345.749959 -234.348485)
			(xy 345.715798 -234.388635) (xy 345.675657 -234.422807) (xy 345.630568 -234.45012) (xy 345.581692 -234.469872)
			(xy 345.530286 -234.481554) (xy 345.504008 -234.483656) (xy 345.484958 -234.484926) (xy 344.926412 -235.043472)
			(xy 344.926412 -253.737364) (xy 344.939501 -253.757704) (xy 344.960201 -253.80142) (xy 344.974254 -253.847701)
			(xy 344.981356 -253.895546) (xy 344.981351 -253.943914) (xy 344.974241 -253.991757) (xy 344.96018 -254.038036)
			(xy 344.939472 -254.081748) (xy 344.926412 -254.102108) (xy 344.926412 -255.36525) (xy 344.939502 -255.38559)
			(xy 344.960204 -255.429306) (xy 344.974259 -255.475588) (xy 344.981363 -255.523433) (xy 344.98136 -255.571803)
			(xy 344.974251 -255.619647) (xy 344.960191 -255.665928) (xy 344.939484 -255.709641) (xy 344.926412 -255.729994)
			(xy 344.926412 -256.992882) (xy 344.939508 -257.013222) (xy 344.96022 -257.056939) (xy 344.974284 -257.103225)
			(xy 344.981397 -257.151074) (xy 344.981402 -257.199449) (xy 344.974301 -257.247301) (xy 344.960247 -257.293589)
			(xy 344.939546 -257.337311) (xy 344.926412 -257.357626) (xy 344.926412 -258.620768) (xy 344.939501 -258.641108)
			(xy 344.9602 -258.684823) (xy 344.974253 -258.731105) (xy 344.981354 -258.778949) (xy 344.981349 -258.827317)
			(xy 344.974238 -258.87516) (xy 344.960176 -258.921439) (xy 344.939468 -258.96515) (xy 344.926412 -258.985512)
			(xy 344.926412 -260.249162) (xy 344.93939 -260.269439) (xy 344.959903 -260.312991) (xy 344.973825 -260.359076)
			(xy 344.980857 -260.406701) (xy 344.981276 -260.430772) (xy 344.980768 -260.44906) (xy 344.979498 -260.471666)
			(xy 345.331288 -260.823456) (xy 350.3676 -260.823456) (xy 350.507808 -260.683248) (xy 350.511618 -260.67512)
			(xy 350.521692 -260.654226) (xy 350.546852 -260.615256) (xy 350.577249 -260.580219) (xy 350.612278 -260.549811)
			(xy 350.651239 -260.52464) (xy 350.672146 -260.514592) (xy 350.680274 -260.510782) (xy 350.777556 -260.4135)
			(xy 350.777556 -260.025896) (xy 350.737424 -260.01726) (xy 350.711882 -260.011232) (xy 350.662993 -259.992159)
			(xy 350.617762 -259.965548) (xy 350.577344 -259.932077) (xy 350.542769 -259.8926) (xy 350.514919 -259.848122)
			(xy 350.494503 -259.799778) (xy 350.482041 -259.748802) (xy 350.477853 -259.696491) (xy 350.482044 -259.644181)
			(xy 350.494508 -259.593205) (xy 350.514927 -259.544862) (xy 350.54278 -259.500386) (xy 350.577357 -259.46091)
			(xy 350.617777 -259.427442) (xy 350.663008 -259.400833) (xy 350.711899 -259.381763) (xy 350.737424 -259.375656)
			(xy 350.777556 -259.36702) (xy 350.777556 -256.135124) (xy 350.745552 -256.12217) (xy 350.723074 -256.112666)
			(xy 350.680975 -256.087982) (xy 350.642997 -256.057335) (xy 350.609974 -256.021403) (xy 350.582637 -255.980977)
			(xy 350.561588 -255.936948) (xy 350.547291 -255.890288) (xy 350.540061 -255.842025) (xy 350.539558 -255.817624)
			(xy 350.540004 -255.792916) (xy 350.547415 -255.744058) (xy 350.562073 -255.696865) (xy 350.583645 -255.652405)
			(xy 350.611644 -255.611686) (xy 350.628204 -255.593342) (xy 350.638252 -255.581837) (xy 350.651578 -255.554364)
			(xy 350.656193 -255.524181) (xy 350.651685 -255.493981) (xy 350.638456 -255.466462) (xy 350.628458 -255.454912)
			(xy 350.612021 -255.4366) (xy 350.58426 -255.395975) (xy 350.562875 -255.35166) (xy 350.548347 -255.304648)
			(xy 350.541002 -255.255995) (xy 350.540574 -255.231392) (xy 350.541018 -255.207037) (xy 350.548218 -255.158862)
			(xy 350.562459 -255.11228) (xy 350.583428 -255.068314) (xy 350.610664 -255.02793) (xy 350.643569 -254.992014)
			(xy 350.681421 -254.961356) (xy 350.723388 -254.936629) (xy 350.745806 -254.9271) (xy 350.777556 -254.9144)
			(xy 350.777556 -253.123954) (xy 350.741488 -253.113032) (xy 350.716482 -253.105016) (xy 350.669213 -253.08215)
			(xy 350.626193 -253.052042) (xy 350.588522 -253.015463) (xy 350.557162 -252.973348) (xy 350.532915 -252.926772)
			(xy 350.516401 -252.876928) (xy 350.508043 -252.825089) (xy 350.507554 -252.798834) (xy 350.508014 -252.774306)
			(xy 350.515321 -252.725796) (xy 350.529761 -252.678912) (xy 350.551014 -252.634698) (xy 350.578607 -252.594136)
			(xy 350.59493 -252.575822) (xy 350.604926 -252.56431) (xy 350.618158 -252.536858) (xy 350.622709 -252.506725)
			(xy 350.618173 -252.47659) (xy 350.604954 -252.449131) (xy 350.59493 -252.437646) (xy 350.578596 -252.41934)
			(xy 350.550991 -252.378784) (xy 350.529736 -252.334568) (xy 350.515305 -252.287679) (xy 350.508021 -252.239164)
			(xy 350.507554 -252.214634) (xy 350.508076 -252.188383) (xy 350.516448 -252.136554) (xy 350.532969 -252.08672)
			(xy 350.557216 -252.040153) (xy 350.58857 -251.998042) (xy 350.626231 -251.961463) (xy 350.669237 -251.931349)
			(xy 350.716491 -251.908469) (xy 350.741488 -251.900436) (xy 350.777556 -251.889514) (xy 350.777556 -248.504456)
			(xy 350.778132 -248.479498) (xy 350.78788 -248.430542) (xy 350.806992 -248.384429) (xy 350.834735 -248.342932)
			(xy 350.851978 -248.324878) (xy 351.334578 -247.842278) (xy 351.35262 -247.82502) (xy 351.394114 -247.797266)
			(xy 351.440232 -247.778157) (xy 351.489195 -247.768431) (xy 351.514156 -247.767856) (xy 352.3234 -247.767856)
			(xy 352.809556 -247.2817) (xy 352.809556 -246.298212) (xy 352.6282 -246.116856) (xy 351.514156 -246.116856)
			(xy 351.489198 -246.11628) (xy 351.440242 -246.106533) (xy 351.394128 -246.087421) (xy 351.35263 -246.059679)
			(xy 351.334578 -246.042434) (xy 350.94291 -245.650766) (xy 350.915478 -245.657116) (xy 350.897133 -245.661123)
			(xy 350.859831 -245.665446) (xy 350.841056 -245.665752) (xy 350.815271 -245.665243) (xy 350.764337 -245.657169)
			(xy 350.715293 -245.641228) (xy 350.669347 -245.61781) (xy 350.627629 -245.587494) (xy 350.591167 -245.551025)
			(xy 350.560858 -245.509302) (xy 350.537449 -245.463351) (xy 350.521517 -245.414304) (xy 350.513452 -245.363369)
			(xy 350.512888 -245.337584) (xy 350.513345 -245.313054) (xy 350.520645 -245.264541) (xy 350.535081 -245.217654)
			(xy 350.556331 -245.173436) (xy 350.583923 -245.132871) (xy 350.600264 -245.114572) (xy 350.6102 -245.103026)
			(xy 350.623406 -245.075594) (xy 350.62794 -245.045488) (xy 350.623399 -245.015384) (xy 350.610187 -244.987955)
			(xy 350.600264 -244.976396) (xy 350.58393 -244.958089) (xy 350.556324 -244.917533) (xy 350.535067 -244.873318)
			(xy 350.520632 -244.826429) (xy 350.513342 -244.777914) (xy 350.512888 -244.753384) (xy 350.513406 -244.727117)
			(xy 350.521777 -244.675254) (xy 350.538302 -244.625386) (xy 350.56256 -244.578788) (xy 350.593931 -244.536649)
			(xy 350.631613 -244.500044) (xy 350.674645 -244.46991) (xy 350.698054 -244.457982) (xy 350.726756 -244.444012)
			(xy 350.726756 -241.235992) (xy 350.698816 -241.221768) (xy 350.675955 -241.209665) (xy 350.634028 -241.179373)
			(xy 350.597372 -241.14288) (xy 350.566895 -241.101087) (xy 350.543351 -241.055032) (xy 350.527323 -241.005853)
			(xy 350.519208 -240.954768) (xy 350.51873 -240.928906) (xy 350.519185 -240.904376) (xy 350.526483 -240.855862)
			(xy 350.540918 -240.808974) (xy 350.562169 -240.764755) (xy 350.589761 -240.72419) (xy 350.606106 -240.705894)
			(xy 350.6161 -240.694383) (xy 350.629327 -240.666934) (xy 350.633872 -240.636804) (xy 350.62933 -240.606675)
			(xy 350.616105 -240.579224) (xy 350.606106 -240.567718) (xy 350.589769 -240.549413) (xy 350.562157 -240.508858)
			(xy 350.540894 -240.464643) (xy 350.526454 -240.417754) (xy 350.51916 -240.369237) (xy 350.51873 -240.344706)
			(xy 350.519215 -240.318844) (xy 350.527328 -240.267759) (xy 350.543354 -240.21858) (xy 350.566897 -240.172524)
			(xy 350.597373 -240.130731) (xy 350.634028 -240.094237) (xy 350.675954 -240.063944) (xy 350.698816 -240.051844)
			(xy 350.726756 -240.03762) (xy 350.726756 -239.597946) (xy 350.704853 -239.5855) (xy 350.664777 -239.554982)
			(xy 350.629828 -239.518704) (xy 350.600825 -239.477517) (xy 350.578448 -239.432385) (xy 350.563222 -239.384368)
			(xy 350.555503 -239.334589) (xy 350.555052 -239.309402) (xy 350.555531 -239.283613) (xy 350.5636 -239.232669)
			(xy 350.579539 -239.183616) (xy 350.602956 -239.137659) (xy 350.633273 -239.095932) (xy 350.669746 -239.059462)
			(xy 350.711475 -239.029146) (xy 350.757432 -239.005732) (xy 350.806487 -238.989796) (xy 350.857431 -238.98173)
			(xy 350.88322 -238.981234) (xy 350.883728 -238.981234) (xy 350.915674 -238.98202) (xy 350.978351 -238.99443)
			(xy 351.008188 -239.005872) (xy 351.03943 -239.018826) (xy 352.147378 -237.910878) (xy 352.16542 -237.89362)
			(xy 352.206914 -237.865866) (xy 352.253032 -237.846757) (xy 352.301995 -237.837031) (xy 352.326956 -237.836456)
			(xy 356.290372 -237.836456) (xy 356.298754 -237.79607) (xy 356.304656 -237.770363) (xy 356.323547 -237.721121)
			(xy 356.35007 -237.675533) (xy 356.383541 -237.634774) (xy 356.423099 -237.599891) (xy 356.467726 -237.571782)
			(xy 356.516274 -237.551172) (xy 356.567492 -237.538589) (xy 356.620064 -237.534359) (xy 356.672636 -237.538589)
			(xy 356.723854 -237.551172) (xy 356.772402 -237.571782) (xy 356.817029 -237.599891) (xy 356.856587 -237.634774)
			(xy 356.890058 -237.675533) (xy 356.916581 -237.721121) (xy 356.935472 -237.770363) (xy 356.941374 -237.79607)
			(xy 356.949756 -237.836456) (xy 363.274356 -237.836456) (xy 363.299314 -237.837033) (xy 363.348268 -237.846783)
			(xy 363.394379 -237.865897) (xy 363.435875 -237.893641) (xy 363.453934 -237.910878) (xy 363.961934 -238.418878)
			(xy 363.979192 -238.43692) (xy 364.006944 -238.478414) (xy 364.026052 -238.524532) (xy 364.035778 -238.573496)
			(xy 364.036356 -238.598456) (xy 364.036356 -239.9157) (xy 365.792512 -241.671856) (xy 368.405156 -241.671856)
			(xy 368.430114 -241.672433) (xy 368.479068 -241.682183) (xy 368.525179 -241.701297) (xy 368.566675 -241.729041)
			(xy 368.584734 -241.746278) (xy 369.143534 -242.305078) (xy 369.160792 -242.32312) (xy 369.188544 -242.364614)
			(xy 369.207652 -242.410732) (xy 369.217378 -242.459696) (xy 369.217956 -242.484656) (xy 369.217956 -243.322856)
			(xy 369.217379 -243.347814) (xy 369.20763 -243.396769) (xy 369.188516 -243.44288) (xy 369.160773 -243.484377)
			(xy 369.143534 -243.502434) (xy 368.864134 -243.781834) (xy 368.846093 -243.799093) (xy 368.804599 -243.826847)
			(xy 368.75848 -243.845957) (xy 368.709517 -243.855686) (xy 368.684556 -243.856256) (xy 368.129312 -243.856256)
			(xy 366.982756 -245.002812) (xy 366.982756 -246.7737) (xy 368.993928 -248.784872) (xy 369.007898 -248.788428)
			(xy 369.034038 -248.795492) (xy 369.083731 -248.816987) (xy 369.129227 -248.846342) (xy 369.169292 -248.88276)
			(xy 369.202843 -248.925256) (xy 369.22897 -248.972678) (xy 369.246966 -249.023743) (xy 369.252246 -249.050302)
			(xy 369.265312 -249.071193) (xy 369.283989 -249.116784) (xy 369.29355 -249.165115) (xy 369.294156 -249.189748)
			(xy 369.294156 -260.087364) (xy 369.294042 -260.097569) (xy 369.292387 -260.117914) (xy 369.290854 -260.128004)
			(xy 369.286536 -260.153658) (xy 369.511072 -260.37794) (xy 369.522395 -260.390055) (xy 369.538963 -260.418767)
			(xy 369.547583 -260.450775) (xy 369.548156 -260.467348) (xy 369.548156 -261.685278)
		)
		(stroke
			(width 0)
			(type solid)
		)
		(fill yes)
		(layer "In8.Cu")
		(net "PVCCD_HV_CPU0")
	)
	(gr_poly
		(pts
			(xy 67.751452 -334.284574) (xy 67.769493 -334.267314) (xy 67.810986 -334.239556) (xy 67.857104 -334.220443)
			(xy 67.906069 -334.210711) (xy 67.93103 -334.210152) (xy 72.12838 -334.210152) (xy 72.460358 -333.878174)
			(xy 72.460358 -296.49039) (xy 72.46093 -296.46543) (xy 72.470673 -296.416471) (xy 72.489781 -296.370354)
			(xy 72.517521 -296.328852) (xy 72.53478 -296.310812) (xy 79.978758 -288.866834) (xy 79.9968 -288.849577)
			(xy 80.038295 -288.821824) (xy 80.084413 -288.802715) (xy 80.133376 -288.792987) (xy 80.158336 -288.792412)
			(xy 87.48014 -288.792412) (xy 87.494364 -288.765234) (xy 87.506622 -288.742815) (xy 87.53701 -288.701739)
			(xy 87.573398 -288.665871) (xy 87.614906 -288.636076) (xy 87.660531 -288.613077) (xy 87.70917 -288.597427)
			(xy 87.759647 -288.589507) (xy 87.810741 -288.589507) (xy 87.861218 -288.597427) (xy 87.909857 -288.613077)
			(xy 87.955482 -288.636076) (xy 87.99699 -288.665871) (xy 88.033378 -288.701739) (xy 88.063766 -288.742815)
			(xy 88.076024 -288.765234) (xy 88.090248 -288.792412) (xy 88.41867 -288.792412) (xy 88.432894 -288.76498)
			(xy 88.444755 -288.743166) (xy 88.474023 -288.703058) (xy 88.508971 -288.66779) (xy 88.54881 -288.638157)
			(xy 88.59264 -288.614829) (xy 88.639471 -288.598334) (xy 88.66378 -288.593276) (xy 88.68664 -288.588958)
			(xy 88.891618 -288.233866) (xy 88.883744 -288.212022) (xy 88.875165 -288.185603) (xy 88.865969 -288.130828)
			(xy 88.865456 -288.103056) (xy 88.865964 -288.077169) (xy 88.874063 -288.026031) (xy 88.890062 -287.976791)
			(xy 88.913568 -287.930659) (xy 88.944 -287.888772) (xy 88.98061 -287.852162) (xy 89.022497 -287.82173)
			(xy 89.068629 -287.798224) (xy 89.117869 -287.782225) (xy 89.169007 -287.774126) (xy 89.220781 -287.774126)
			(xy 89.271919 -287.782225) (xy 89.321159 -287.798224) (xy 89.367291 -287.82173) (xy 89.409178 -287.852162)
			(xy 89.445788 -287.888772) (xy 89.47622 -287.930659) (xy 89.499726 -287.976791) (xy 89.515725 -288.026031)
			(xy 89.523824 -288.077169) (xy 89.524332 -288.103056) (xy 89.523871 -288.128392) (xy 89.516123 -288.178469)
			(xy 89.500803 -288.226771) (xy 89.478271 -288.272159) (xy 89.449059 -288.313564) (xy 89.413854 -288.350011)
			(xy 89.373487 -288.380641) (xy 89.328907 -288.404732) (xy 89.281166 -288.421717) (xy 89.256362 -288.426906)
			(xy 89.233502 -288.431224) (xy 89.112852 -288.640012) (xy 89.10567 -288.653469) (xy 89.098891 -288.683196)
			(xy 89.101184 -288.7136) (xy 89.112344 -288.741975) (xy 89.131379 -288.765793) (xy 89.156594 -288.782936)
			(xy 89.185744 -288.791877) (xy 89.20099 -288.792412) (xy 89.35974 -288.792412) (xy 89.373964 -288.765234)
			(xy 89.386222 -288.742815) (xy 89.41661 -288.701739) (xy 89.452998 -288.665871) (xy 89.494506 -288.636076)
			(xy 89.540131 -288.613077) (xy 89.58877 -288.597427) (xy 89.639247 -288.589507) (xy 89.690341 -288.589507)
			(xy 89.740818 -288.597427) (xy 89.789457 -288.613077) (xy 89.835082 -288.636076) (xy 89.87659 -288.665871)
			(xy 89.912978 -288.701739) (xy 89.943366 -288.742815) (xy 89.955624 -288.765234) (xy 89.969848 -288.792412)
			(xy 90.29827 -288.792412) (xy 90.312494 -288.76498) (xy 90.324355 -288.743166) (xy 90.353623 -288.703058)
			(xy 90.388571 -288.66779) (xy 90.42841 -288.638157) (xy 90.47224 -288.614829) (xy 90.519071 -288.598334)
			(xy 90.54338 -288.593276) (xy 90.56624 -288.588958) (xy 90.771218 -288.233866) (xy 90.763344 -288.212022)
			(xy 90.754765 -288.185603) (xy 90.745569 -288.130828) (xy 90.745056 -288.103056) (xy 90.745564 -288.077169)
			(xy 90.753663 -288.026031) (xy 90.769662 -287.976791) (xy 90.793168 -287.930659) (xy 90.8236 -287.888772)
			(xy 90.86021 -287.852162) (xy 90.902097 -287.82173) (xy 90.948229 -287.798224) (xy 90.997469 -287.782225)
			(xy 91.048607 -287.774126) (xy 91.100381 -287.774126) (xy 91.151519 -287.782225) (xy 91.200759 -287.798224)
			(xy 91.246891 -287.82173) (xy 91.288778 -287.852162) (xy 91.325388 -287.888772) (xy 91.35582 -287.930659)
			(xy 91.379326 -287.976791) (xy 91.395325 -288.026031) (xy 91.403424 -288.077169) (xy 91.403932 -288.103056)
			(xy 91.403471 -288.128392) (xy 91.395723 -288.178469) (xy 91.380403 -288.226771) (xy 91.357871 -288.272159)
			(xy 91.328659 -288.313564) (xy 91.293454 -288.350011) (xy 91.253087 -288.380641) (xy 91.208507 -288.404732)
			(xy 91.160766 -288.421717) (xy 91.135962 -288.426906) (xy 91.113102 -288.431224) (xy 90.992452 -288.640012)
			(xy 90.98527 -288.653469) (xy 90.978491 -288.683196) (xy 90.980784 -288.7136) (xy 90.991944 -288.741975)
			(xy 91.010979 -288.765793) (xy 91.036194 -288.782936) (xy 91.065344 -288.791877) (xy 91.08059 -288.792412)
			(xy 91.23807 -288.792412) (xy 91.252294 -288.76498) (xy 91.264604 -288.742428) (xy 91.295133 -288.701104)
			(xy 91.331703 -288.665016) (xy 91.373428 -288.635038) (xy 91.419298 -288.611896) (xy 91.468203 -288.596149)
			(xy 91.518959 -288.588179) (xy 91.570337 -288.588179) (xy 91.621093 -288.596149) (xy 91.669998 -288.611896)
			(xy 91.715868 -288.635038) (xy 91.757593 -288.665016) (xy 91.794163 -288.701104) (xy 91.824692 -288.742428)
			(xy 91.837002 -288.76498) (xy 91.851226 -288.792412) (xy 92.17787 -288.792412) (xy 92.192094 -288.76498)
			(xy 92.203955 -288.743166) (xy 92.233223 -288.703058) (xy 92.268171 -288.66779) (xy 92.30801 -288.638157)
			(xy 92.35184 -288.614829) (xy 92.398671 -288.598334) (xy 92.42298 -288.593276) (xy 92.44584 -288.588958)
			(xy 92.651072 -288.233866) (xy 92.643198 -288.211768) (xy 92.634576 -288.18542) (xy 92.625258 -288.130773)
			(xy 92.624656 -288.103056) (xy 92.625164 -288.077149) (xy 92.63327 -288.025972) (xy 92.649282 -287.976693)
			(xy 92.672805 -287.930526) (xy 92.703261 -287.888607) (xy 92.739899 -287.851969) (xy 92.781818 -287.821513)
			(xy 92.827985 -287.79799) (xy 92.877264 -287.781978) (xy 92.928441 -287.773872) (xy 92.980255 -287.773872)
			(xy 93.031432 -287.781978) (xy 93.080711 -287.79799) (xy 93.126878 -287.821513) (xy 93.168797 -287.851969)
			(xy 93.205435 -287.888607) (xy 93.235891 -287.930526) (xy 93.259414 -287.976693) (xy 93.275426 -288.025972)
			(xy 93.283532 -288.077149) (xy 93.28404 -288.103056) (xy 93.283578 -288.128404) (xy 93.275821 -288.178504)
			(xy 93.260482 -288.226824) (xy 93.237924 -288.272225) (xy 93.208679 -288.313636) (xy 93.173437 -288.35008)
			(xy 93.13303 -288.380696) (xy 93.08841 -288.404763) (xy 93.040631 -288.421713) (xy 93.015816 -288.426906)
			(xy 92.992956 -288.431224) (xy 92.872306 -288.640012) (xy 92.865188 -288.653476) (xy 92.858414 -288.683151)
			(xy 92.860682 -288.713506) (xy 92.871791 -288.741844) (xy 92.890756 -288.765653) (xy 92.915893 -288.782818)
			(xy 92.944971 -288.791817) (xy 92.96019 -288.792412) (xy 93.11767 -288.792412) (xy 93.131894 -288.76498)
			(xy 93.144204 -288.742428) (xy 93.174733 -288.701104) (xy 93.211303 -288.665016) (xy 93.253028 -288.635038)
			(xy 93.298898 -288.611896) (xy 93.347803 -288.596149) (xy 93.398559 -288.588179) (xy 93.449937 -288.588179)
			(xy 93.500693 -288.596149) (xy 93.549598 -288.611896) (xy 93.595468 -288.635038) (xy 93.637193 -288.665016)
			(xy 93.673763 -288.701104) (xy 93.704292 -288.742428) (xy 93.716602 -288.76498) (xy 93.730826 -288.792412)
			(xy 94.05747 -288.792412) (xy 94.071694 -288.76498) (xy 94.083555 -288.743166) (xy 94.112823 -288.703058)
			(xy 94.147771 -288.66779) (xy 94.18761 -288.638157) (xy 94.23144 -288.614829) (xy 94.278271 -288.598334)
			(xy 94.30258 -288.593276) (xy 94.32544 -288.588958) (xy 94.530672 -288.233866) (xy 94.522798 -288.211768)
			(xy 94.514176 -288.18542) (xy 94.504858 -288.130773) (xy 94.504256 -288.103056) (xy 94.504764 -288.077149)
			(xy 94.51287 -288.025972) (xy 94.528882 -287.976693) (xy 94.552405 -287.930526) (xy 94.582861 -287.888607)
			(xy 94.619499 -287.851969) (xy 94.661418 -287.821513) (xy 94.707585 -287.79799) (xy 94.756864 -287.781978)
			(xy 94.808041 -287.773872) (xy 94.859855 -287.773872) (xy 94.911032 -287.781978) (xy 94.960311 -287.79799)
			(xy 95.006478 -287.821513) (xy 95.048397 -287.851969) (xy 95.085035 -287.888607) (xy 95.115491 -287.930526)
			(xy 95.139014 -287.976693) (xy 95.155026 -288.025972) (xy 95.163132 -288.077149) (xy 95.16364 -288.103056)
			(xy 95.163178 -288.128404) (xy 95.155421 -288.178504) (xy 95.140082 -288.226824) (xy 95.117524 -288.272225)
			(xy 95.088279 -288.313636) (xy 95.053037 -288.35008) (xy 95.01263 -288.380696) (xy 94.96801 -288.404763)
			(xy 94.920231 -288.421713) (xy 94.895416 -288.426906) (xy 94.872556 -288.431224) (xy 94.751906 -288.640012)
			(xy 94.744788 -288.653476) (xy 94.738014 -288.683151) (xy 94.740282 -288.713506) (xy 94.751391 -288.741844)
			(xy 94.770356 -288.765653) (xy 94.795493 -288.782818) (xy 94.824571 -288.791817) (xy 94.83979 -288.792412)
			(xy 94.99727 -288.792412) (xy 95.011494 -288.76498) (xy 95.023804 -288.742428) (xy 95.054333 -288.701104)
			(xy 95.090903 -288.665016) (xy 95.132628 -288.635038) (xy 95.178498 -288.611896) (xy 95.227403 -288.596149)
			(xy 95.278159 -288.588179) (xy 95.329537 -288.588179) (xy 95.380293 -288.596149) (xy 95.429198 -288.611896)
			(xy 95.475068 -288.635038) (xy 95.516793 -288.665016) (xy 95.553363 -288.701104) (xy 95.583892 -288.742428)
			(xy 95.596202 -288.76498) (xy 95.610426 -288.792412) (xy 95.93707 -288.792412) (xy 95.951294 -288.76498)
			(xy 95.963155 -288.743166) (xy 95.992423 -288.703058) (xy 96.027371 -288.66779) (xy 96.06721 -288.638157)
			(xy 96.11104 -288.614829) (xy 96.157871 -288.598334) (xy 96.18218 -288.593276) (xy 96.20504 -288.588958)
			(xy 96.410272 -288.233866) (xy 96.402398 -288.211768) (xy 96.393776 -288.18542) (xy 96.384458 -288.130773)
			(xy 96.383856 -288.103056) (xy 96.384364 -288.077149) (xy 96.39247 -288.025972) (xy 96.408482 -287.976693)
			(xy 96.432005 -287.930526) (xy 96.462461 -287.888607) (xy 96.499099 -287.851969) (xy 96.541018 -287.821513)
			(xy 96.587185 -287.79799) (xy 96.636464 -287.781978) (xy 96.687641 -287.773872) (xy 96.739455 -287.773872)
			(xy 96.790632 -287.781978) (xy 96.839911 -287.79799) (xy 96.886078 -287.821513) (xy 96.927997 -287.851969)
			(xy 96.964635 -287.888607) (xy 96.995091 -287.930526) (xy 97.018614 -287.976693) (xy 97.034626 -288.025972)
			(xy 97.042732 -288.077149) (xy 97.04324 -288.103056) (xy 97.042778 -288.128404) (xy 97.035021 -288.178504)
			(xy 97.019682 -288.226824) (xy 96.997124 -288.272225) (xy 96.967879 -288.313636) (xy 96.932637 -288.35008)
			(xy 96.89223 -288.380696) (xy 96.84761 -288.404763) (xy 96.799831 -288.421713) (xy 96.775016 -288.426906)
			(xy 96.752156 -288.431224) (xy 96.631506 -288.640012) (xy 96.624388 -288.653476) (xy 96.617614 -288.683151)
			(xy 96.619882 -288.713506) (xy 96.630991 -288.741844) (xy 96.649956 -288.765653) (xy 96.675093 -288.782818)
			(xy 96.704171 -288.791817) (xy 96.71939 -288.792412) (xy 96.87687 -288.792412) (xy 96.891094 -288.76498)
			(xy 96.903404 -288.742428) (xy 96.933933 -288.701104) (xy 96.970503 -288.665016) (xy 97.012228 -288.635038)
			(xy 97.058098 -288.611896) (xy 97.107003 -288.596149) (xy 97.157759 -288.588179) (xy 97.209137 -288.588179)
			(xy 97.259893 -288.596149) (xy 97.308798 -288.611896) (xy 97.354668 -288.635038) (xy 97.396393 -288.665016)
			(xy 97.432963 -288.701104) (xy 97.463492 -288.742428) (xy 97.475802 -288.76498) (xy 97.490026 -288.792412)
			(xy 97.81667 -288.792412) (xy 97.830894 -288.76498) (xy 97.842755 -288.743166) (xy 97.872023 -288.703058)
			(xy 97.906971 -288.66779) (xy 97.94681 -288.638157) (xy 97.99064 -288.614829) (xy 98.037471 -288.598334)
			(xy 98.06178 -288.593276) (xy 98.08464 -288.588958) (xy 98.289872 -288.233866) (xy 98.281998 -288.211768)
			(xy 98.273376 -288.18542) (xy 98.264058 -288.130773) (xy 98.263456 -288.103056) (xy 98.263964 -288.077149)
			(xy 98.27207 -288.025972) (xy 98.288082 -287.976693) (xy 98.311605 -287.930526) (xy 98.342061 -287.888607)
			(xy 98.378699 -287.851969) (xy 98.420618 -287.821513) (xy 98.466785 -287.79799) (xy 98.516064 -287.781978)
			(xy 98.567241 -287.773872) (xy 98.619055 -287.773872) (xy 98.670232 -287.781978) (xy 98.719511 -287.79799)
			(xy 98.765678 -287.821513) (xy 98.807597 -287.851969) (xy 98.844235 -287.888607) (xy 98.874691 -287.930526)
			(xy 98.898214 -287.976693) (xy 98.914226 -288.025972) (xy 98.922332 -288.077149) (xy 98.92284 -288.103056)
			(xy 98.922378 -288.128404) (xy 98.914621 -288.178504) (xy 98.899282 -288.226824) (xy 98.876724 -288.272225)
			(xy 98.847479 -288.313636) (xy 98.812237 -288.35008) (xy 98.77183 -288.380696) (xy 98.72721 -288.404763)
			(xy 98.679431 -288.421713) (xy 98.654616 -288.426906) (xy 98.631756 -288.431224) (xy 98.511106 -288.640012)
			(xy 98.503988 -288.653476) (xy 98.497214 -288.683151) (xy 98.499482 -288.713506) (xy 98.510591 -288.741844)
			(xy 98.529556 -288.765653) (xy 98.554693 -288.782818) (xy 98.583771 -288.791817) (xy 98.59899 -288.792412)
			(xy 98.75647 -288.792412) (xy 98.770694 -288.76498) (xy 98.783004 -288.742428) (xy 98.813533 -288.701104)
			(xy 98.850103 -288.665016) (xy 98.891828 -288.635038) (xy 98.937698 -288.611896) (xy 98.986603 -288.596149)
			(xy 99.037359 -288.588179) (xy 99.088737 -288.588179) (xy 99.139493 -288.596149) (xy 99.188398 -288.611896)
			(xy 99.234268 -288.635038) (xy 99.275993 -288.665016) (xy 99.312563 -288.701104) (xy 99.343092 -288.742428)
			(xy 99.355402 -288.76498) (xy 99.369626 -288.792412) (xy 99.69627 -288.792412) (xy 99.710494 -288.76498)
			(xy 99.722355 -288.743166) (xy 99.751623 -288.703058) (xy 99.786571 -288.66779) (xy 99.82641 -288.638157)
			(xy 99.87024 -288.614829) (xy 99.917071 -288.598334) (xy 99.94138 -288.593276) (xy 99.96424 -288.588958)
			(xy 100.169472 -288.233866) (xy 100.161598 -288.211768) (xy 100.152976 -288.18542) (xy 100.143658 -288.130773)
			(xy 100.143056 -288.103056) (xy 100.143564 -288.077149) (xy 100.15167 -288.025972) (xy 100.167682 -287.976693)
			(xy 100.191205 -287.930526) (xy 100.221661 -287.888607) (xy 100.258299 -287.851969) (xy 100.300218 -287.821513)
			(xy 100.346385 -287.79799) (xy 100.395664 -287.781978) (xy 100.446841 -287.773872) (xy 100.498655 -287.773872)
			(xy 100.549832 -287.781978) (xy 100.599111 -287.79799) (xy 100.645278 -287.821513) (xy 100.687197 -287.851969)
			(xy 100.723835 -287.888607) (xy 100.754291 -287.930526) (xy 100.777814 -287.976693) (xy 100.793826 -288.025972)
			(xy 100.801932 -288.077149) (xy 100.80244 -288.103056) (xy 100.801978 -288.128404) (xy 100.794221 -288.178504)
			(xy 100.778882 -288.226824) (xy 100.756324 -288.272225) (xy 100.727079 -288.313636) (xy 100.691837 -288.35008)
			(xy 100.65143 -288.380696) (xy 100.60681 -288.404763) (xy 100.559031 -288.421713) (xy 100.534216 -288.426906)
			(xy 100.511356 -288.431224) (xy 100.390706 -288.640012) (xy 100.383588 -288.653476) (xy 100.376814 -288.683151)
			(xy 100.379082 -288.713506) (xy 100.390191 -288.741844) (xy 100.409156 -288.765653) (xy 100.434293 -288.782818)
			(xy 100.463371 -288.791817) (xy 100.47859 -288.792412) (xy 100.63607 -288.792412) (xy 100.650294 -288.76498)
			(xy 100.662604 -288.742428) (xy 100.693133 -288.701104) (xy 100.729703 -288.665016) (xy 100.771428 -288.635038)
			(xy 100.817298 -288.611896) (xy 100.866203 -288.596149) (xy 100.916959 -288.588179) (xy 100.968337 -288.588179)
			(xy 101.019093 -288.596149) (xy 101.067998 -288.611896) (xy 101.113868 -288.635038) (xy 101.155593 -288.665016)
			(xy 101.192163 -288.701104) (xy 101.222692 -288.742428) (xy 101.235002 -288.76498) (xy 101.249226 -288.792412)
			(xy 101.57587 -288.792412) (xy 101.590094 -288.76498) (xy 101.601955 -288.743166) (xy 101.631223 -288.703058)
			(xy 101.666171 -288.66779) (xy 101.70601 -288.638157) (xy 101.74984 -288.614829) (xy 101.796671 -288.598334)
			(xy 101.82098 -288.593276) (xy 101.84384 -288.588958) (xy 102.049072 -288.233866) (xy 102.041198 -288.211768)
			(xy 102.032576 -288.18542) (xy 102.023258 -288.130773) (xy 102.022656 -288.103056) (xy 102.023164 -288.077149)
			(xy 102.03127 -288.025972) (xy 102.047282 -287.976693) (xy 102.070805 -287.930526) (xy 102.101261 -287.888607)
			(xy 102.137899 -287.851969) (xy 102.179818 -287.821513) (xy 102.225985 -287.79799) (xy 102.275264 -287.781978)
			(xy 102.326441 -287.773872) (xy 102.378255 -287.773872) (xy 102.429432 -287.781978) (xy 102.478711 -287.79799)
			(xy 102.524878 -287.821513) (xy 102.566797 -287.851969) (xy 102.603435 -287.888607) (xy 102.633891 -287.930526)
			(xy 102.657414 -287.976693) (xy 102.673426 -288.025972) (xy 102.681532 -288.077149) (xy 102.68204 -288.103056)
			(xy 102.681578 -288.128404) (xy 102.673821 -288.178504) (xy 102.658482 -288.226824) (xy 102.635924 -288.272225)
			(xy 102.606679 -288.313636) (xy 102.571437 -288.35008) (xy 102.53103 -288.380696) (xy 102.48641 -288.404763)
			(xy 102.438631 -288.421713) (xy 102.413816 -288.426906) (xy 102.390956 -288.431224) (xy 102.270306 -288.640012)
			(xy 102.263188 -288.653476) (xy 102.256414 -288.683151) (xy 102.258682 -288.713506) (xy 102.269791 -288.741844)
			(xy 102.288756 -288.765653) (xy 102.313893 -288.782818) (xy 102.342971 -288.791817) (xy 102.35819 -288.792412)
			(xy 102.51567 -288.792412) (xy 102.529894 -288.76498) (xy 102.542204 -288.742428) (xy 102.572733 -288.701104)
			(xy 102.609303 -288.665016) (xy 102.651028 -288.635038) (xy 102.696898 -288.611896) (xy 102.745803 -288.596149)
			(xy 102.796559 -288.588179) (xy 102.847937 -288.588179) (xy 102.898693 -288.596149) (xy 102.947598 -288.611896)
			(xy 102.993468 -288.635038) (xy 103.035193 -288.665016) (xy 103.071763 -288.701104) (xy 103.102292 -288.742428)
			(xy 103.114602 -288.76498) (xy 103.128826 -288.792412) (xy 103.383334 -288.792412) (xy 103.910384 -288.265362)
			(xy 103.928672 -288.233866) (xy 103.920798 -288.211768) (xy 103.912176 -288.18542) (xy 103.902858 -288.130773)
			(xy 103.902256 -288.103056) (xy 103.902748 -288.076987) (xy 103.910953 -288.0255) (xy 103.927169 -287.975949)
			(xy 103.950989 -287.929571) (xy 103.981818 -287.887525) (xy 104.018887 -287.850862) (xy 104.061269 -287.820497)
			(xy 104.084374 -287.808416) (xy 104.112314 -287.794446) (xy 104.112314 -286.782764) (xy 104.084374 -286.76854)
			(xy 104.061425 -286.756481) (xy 104.019321 -286.726239) (xy 103.982498 -286.68975) (xy 103.951875 -286.647922)
			(xy 103.928214 -286.601797) (xy 103.912104 -286.552524) (xy 103.903947 -286.501331) (xy 103.903945 -286.449491)
			(xy 103.912099 -286.398297) (xy 103.928206 -286.349023) (xy 103.951864 -286.302896) (xy 103.982484 -286.261066)
			(xy 104.019304 -286.224575) (xy 104.061407 -286.19433) (xy 104.084374 -286.182308) (xy 104.112314 -286.168084)
			(xy 104.112314 -286.013398) (xy 104.11184 -285.999487) (xy 104.104335 -285.972695) (xy 104.089882 -285.948921)
			(xy 104.069552 -285.929926) (xy 104.044852 -285.917119) (xy 104.017613 -285.911449) (xy 103.989854 -285.913336)
			(xy 103.963633 -285.92264) (xy 103.95204 -285.93034) (xy 103.931056 -285.944595) (xy 103.885631 -285.967176)
			(xy 103.837285 -285.982538) (xy 103.787158 -285.990317) (xy 103.761794 -285.990792) (xy 103.735906 -285.99031)
			(xy 103.684768 -285.982209) (xy 103.635527 -285.966208) (xy 103.589396 -285.942699) (xy 103.547511 -285.912264)
			(xy 103.510903 -285.87565) (xy 103.480473 -285.83376) (xy 103.456972 -285.787625) (xy 103.440979 -285.738381)
			(xy 103.432886 -285.687242) (xy 103.432356 -285.661354) (xy 103.432816 -285.636017) (xy 103.440563 -285.585938)
			(xy 103.455882 -285.537635) (xy 103.478413 -285.492245) (xy 103.507624 -285.450838) (xy 103.542829 -285.414389)
			(xy 103.583196 -285.383756) (xy 103.627776 -285.359662) (xy 103.675518 -285.342674) (xy 103.700326 -285.337504)
			(xy 103.723186 -285.333186) (xy 103.928418 -284.97784) (xy 103.920798 -284.955996) (xy 103.912189 -284.929709)
			(xy 103.902867 -284.875191) (xy 103.902256 -284.847538) (xy 103.902749 -284.82147) (xy 103.910957 -284.769985)
			(xy 103.927174 -284.720435) (xy 103.950995 -284.67406) (xy 103.981825 -284.632016) (xy 104.018894 -284.595355)
			(xy 104.061276 -284.564993) (xy 104.084374 -284.552898) (xy 104.112314 -284.538928) (xy 104.112314 -283.765752)
			(xy 104.11293 -283.740797) (xy 104.122676 -283.691849) (xy 104.141784 -283.645742) (xy 104.169519 -283.604249)
			(xy 104.186736 -283.586174) (xy 105.315004 -282.457906) (xy 105.312972 -282.434284) (xy 105.311956 -282.405836)
			(xy 105.312461 -282.379941) (xy 105.320554 -282.328787) (xy 105.336548 -282.279528) (xy 105.360048 -282.233377)
			(xy 105.390476 -282.191468) (xy 105.427084 -282.154834) (xy 105.46897 -282.124375) (xy 105.515104 -282.100841)
			(xy 105.564351 -282.084811) (xy 105.615499 -282.07668) (xy 105.641394 -282.076144) (xy 105.669842 -282.077414)
			(xy 105.693464 -282.079446) (xy 105.91292 -281.85999) (xy 105.87736 -281.823922) (xy 105.859585 -281.805294)
			(xy 105.82946 -281.763543) (xy 105.806198 -281.717612) (xy 105.790367 -281.668621) (xy 105.782352 -281.617763)
			(xy 105.781856 -281.59202) (xy 105.782337 -281.566111) (xy 105.790441 -281.514931) (xy 105.806452 -281.465648)
			(xy 105.829977 -281.419478) (xy 105.860436 -281.377557) (xy 105.897078 -281.340918) (xy 105.939002 -281.310463)
			(xy 105.985174 -281.286942) (xy 106.034458 -281.270934) (xy 106.085639 -281.262834) (xy 106.111548 -281.262328)
			(xy 106.137287 -281.262848) (xy 106.188134 -281.270891) (xy 106.237116 -281.286729) (xy 106.283047 -281.309977)
			(xy 106.324814 -281.340071) (xy 106.34345 -281.357832) (xy 106.379518 -281.393392) (xy 106.514646 -281.258264)
			(xy 106.524689 -281.247466) (xy 106.538648 -281.221503) (xy 106.544614 -281.192636) (xy 106.542093 -281.163267)
			(xy 106.531294 -281.135839) (xy 106.513116 -281.112635) (xy 106.48907 -281.095584) (xy 106.475276 -281.09037)
			(xy 106.451956 -281.081986) (xy 106.407937 -281.059225) (xy 106.367813 -281.030142) (xy 106.332487 -280.995389)
			(xy 106.317288 -280.975816) (xy 105.9053 -280.975816) (xy 105.889626 -280.995951) (xy 105.853116 -281.031593)
			(xy 105.81155 -281.061185) (xy 105.765922 -281.08402) (xy 105.71732 -281.099553) (xy 105.666906 -281.107413)
			(xy 105.641394 -281.107896) (xy 105.615487 -281.107387) (xy 105.56431 -281.099281) (xy 105.515032 -281.083268)
			(xy 105.468865 -281.059744) (xy 105.426946 -281.029288) (xy 105.390308 -280.992649) (xy 105.359852 -280.95073)
			(xy 105.336329 -280.904563) (xy 105.320318 -280.855284) (xy 105.312212 -280.804107) (xy 105.312212 -280.752293)
			(xy 105.320318 -280.701116) (xy 105.336329 -280.651837) (xy 105.359852 -280.60567) (xy 105.390308 -280.563751)
			(xy 105.426946 -280.527112) (xy 105.468865 -280.496656) (xy 105.515032 -280.473132) (xy 105.56431 -280.457119)
			(xy 105.615487 -280.449013) (xy 105.641394 -280.448512) (xy 105.666906 -280.448989) (xy 105.717321 -280.456849)
			(xy 105.765924 -280.472383) (xy 105.811552 -280.495218) (xy 105.853118 -280.524811) (xy 105.889629 -280.560455)
			(xy 105.9053 -280.580592) (xy 106.317288 -280.580592) (xy 106.332961 -280.560456) (xy 106.369471 -280.524812)
			(xy 106.411036 -280.495218) (xy 106.456665 -280.47238) (xy 106.505267 -280.456845) (xy 106.555682 -280.448983)
			(xy 106.581194 -280.448512) (xy 106.606833 -280.448999) (xy 106.657493 -280.45694) (xy 106.706312 -280.472631)
			(xy 106.752111 -280.495693) (xy 106.793786 -280.52557) (xy 106.830332 -280.561541) (xy 106.860865 -280.602738)
			(xy 106.88465 -280.648166) (xy 106.89336 -280.672286) (xy 106.898542 -280.686105) (xy 106.915565 -280.710199)
			(xy 106.93877 -280.728415) (xy 106.966217 -280.739229) (xy 106.995611 -280.741738) (xy 107.024494 -280.735732)
			(xy 107.050451 -280.721713) (xy 107.061254 -280.711656) (xy 107.685332 -280.087578) (xy 107.676696 -280.058622)
			(xy 107.67017 -280.035547) (xy 107.663154 -279.98811) (xy 107.662726 -279.964134) (xy 107.663221 -279.938108)
			(xy 107.671432 -279.886709) (xy 107.687654 -279.837251) (xy 107.711479 -279.790973) (xy 107.742311 -279.749036)
			(xy 107.779377 -279.712492) (xy 107.821746 -279.682256) (xy 107.844844 -279.670256) (xy 107.873038 -279.656286)
			(xy 107.873038 -278.645874) (xy 107.844844 -278.631904) (xy 107.821617 -278.619832) (xy 107.778977 -278.589471)
			(xy 107.741668 -278.552756) (xy 107.710626 -278.510608) (xy 107.686633 -278.464087) (xy 107.670288 -278.414359)
			(xy 107.662004 -278.362674) (xy 107.661456 -278.336502) (xy 107.662044 -278.308784) (xy 107.671362 -278.254135)
			(xy 107.679998 -278.22779) (xy 107.687872 -278.205692) (xy 107.482894 -277.8506) (xy 107.45978 -277.846282)
			(xy 107.434965 -277.841098) (xy 107.387195 -277.82413) (xy 107.342584 -277.800052) (xy 107.302183 -277.769431)
			(xy 107.266945 -277.732987) (xy 107.237699 -277.69158) (xy 107.215133 -277.646186) (xy 107.199781 -277.597872)
			(xy 107.192003 -277.547779) (xy 107.191556 -277.522432) (xy 107.192061 -277.496537) (xy 107.200155 -277.445384)
			(xy 107.216149 -277.396126) (xy 107.239649 -277.349975) (xy 107.270078 -277.308066) (xy 107.306685 -277.271432)
			(xy 107.348571 -277.240974) (xy 107.394705 -277.21744) (xy 107.443952 -277.201411) (xy 107.495099 -277.19328)
			(xy 107.520994 -277.19274) (xy 107.546557 -277.193242) (xy 107.597064 -277.201171) (xy 107.645745 -277.216792)
			(xy 107.691435 -277.239733) (xy 107.71251 -277.254208) (xy 107.724112 -277.261929) (xy 107.750333 -277.271339)
			(xy 107.778122 -277.273314) (xy 107.805411 -277.267706) (xy 107.830169 -277.254934) (xy 107.850555 -277.235946)
			(xy 107.865052 -277.212156) (xy 107.872581 -277.185333) (xy 107.873038 -277.171404) (xy 107.873038 -277.016464)
			(xy 107.844844 -277.002494) (xy 107.821788 -276.990443) (xy 107.779476 -276.960178) (xy 107.742464 -276.923622)
			(xy 107.711679 -276.881687) (xy 107.687889 -276.835424) (xy 107.67169 -276.785989) (xy 107.663488 -276.734618)
			(xy 107.663487 -276.682596) (xy 107.671687 -276.631225) (xy 107.687883 -276.581789) (xy 107.711671 -276.535525)
			(xy 107.742455 -276.493589) (xy 107.779465 -276.457031) (xy 107.821776 -276.426765) (xy 107.844844 -276.414738)
			(xy 107.873038 -276.400768) (xy 107.873038 -276.245828) (xy 107.872609 -276.231892) (xy 107.865084 -276.205055)
			(xy 107.850585 -276.181251) (xy 107.830192 -276.162252) (xy 107.805423 -276.149471) (xy 107.778121 -276.143861)
			(xy 107.750319 -276.145838) (xy 107.724087 -276.155256) (xy 107.71251 -276.163024) (xy 107.691436 -276.177502)
			(xy 107.645752 -276.200461) (xy 107.59707 -276.216086) (xy 107.546558 -276.224) (xy 107.520994 -276.224492)
			(xy 107.495482 -276.224014) (xy 107.445068 -276.216152) (xy 107.396467 -276.200618) (xy 107.350839 -276.177781)
			(xy 107.309275 -276.148188) (xy 107.272765 -276.112544) (xy 107.257088 -276.092412) (xy 106.8451 -276.092412)
			(xy 106.829426 -276.112547) (xy 106.792916 -276.14819) (xy 106.75135 -276.177782) (xy 106.705722 -276.200617)
			(xy 106.65712 -276.21615) (xy 106.606706 -276.22401) (xy 106.581194 -276.224492) (xy 106.555287 -276.223983)
			(xy 106.504111 -276.215877) (xy 106.454833 -276.199865) (xy 106.408667 -276.176341) (xy 106.366749 -276.145885)
			(xy 106.330111 -276.109247) (xy 106.299656 -276.067328) (xy 106.276133 -276.021161) (xy 106.260122 -275.971883)
			(xy 106.252016 -275.920707) (xy 106.252016 -275.868893) (xy 106.260122 -275.817717) (xy 106.276133 -275.768439)
			(xy 106.299656 -275.722272) (xy 106.330111 -275.680353) (xy 106.366749 -275.643715) (xy 106.408667 -275.613259)
			(xy 106.454833 -275.589735) (xy 106.504111 -275.573723) (xy 106.555287 -275.565617) (xy 106.581194 -275.565108)
			(xy 106.606706 -275.565585) (xy 106.657121 -275.573445) (xy 106.705724 -275.588978) (xy 106.751353 -275.611814)
			(xy 106.792919 -275.641407) (xy 106.82943 -275.67705) (xy 106.8451 -275.697188) (xy 107.257088 -275.697188)
			(xy 107.272762 -275.677053) (xy 107.309271 -275.641408) (xy 107.350837 -275.611815) (xy 107.396465 -275.588978)
			(xy 107.445067 -275.573443) (xy 107.495482 -275.565581) (xy 107.520994 -275.565108) (xy 107.546557 -275.56561)
			(xy 107.597065 -275.573538) (xy 107.645746 -275.589158) (xy 107.691437 -275.612098) (xy 107.71251 -275.626576)
			(xy 107.72411 -275.634299) (xy 107.75033 -275.643712) (xy 107.778118 -275.645688) (xy 107.805406 -275.640081)
			(xy 107.830162 -275.627306) (xy 107.850545 -275.608317) (xy 107.865037 -275.584525) (xy 107.872559 -275.557701)
			(xy 107.873038 -275.543772) (xy 107.873038 -275.390102) (xy 107.844844 -275.376132) (xy 107.821615 -275.36406)
			(xy 107.778973 -275.3337) (xy 107.74166 -275.296986) (xy 107.710616 -275.254839) (xy 107.686618 -275.208317)
			(xy 107.67027 -275.158589) (xy 107.661981 -275.106903) (xy 107.661456 -275.08073) (xy 107.661957 -275.054554)
			(xy 107.670229 -275.00286) (xy 107.686571 -274.953124) (xy 107.71057 -274.906597) (xy 107.741624 -274.86445)
			(xy 107.77895 -274.827742) (xy 107.821611 -274.797398) (xy 107.844844 -274.785328) (xy 107.873038 -274.771358)
			(xy 107.873038 -273.760946) (xy 107.844844 -273.746976) (xy 107.82179 -273.734925) (xy 107.77948 -273.704661)
			(xy 107.742471 -273.668105) (xy 107.711688 -273.626172) (xy 107.687901 -273.57991) (xy 107.671704 -273.530477)
			(xy 107.663503 -273.479109) (xy 107.663503 -273.42709) (xy 107.671704 -273.375721) (xy 107.687901 -273.326288)
			(xy 107.711689 -273.280026) (xy 107.742472 -273.238093) (xy 107.779482 -273.201538) (xy 107.821791 -273.171275)
			(xy 107.844844 -273.15922) (xy 107.873038 -273.14525) (xy 107.873038 -272.13306) (xy 107.844844 -272.11909)
			(xy 107.821789 -272.107039) (xy 107.779477 -272.076774) (xy 107.742466 -272.040218) (xy 107.711681 -271.998284)
			(xy 107.687891 -271.952021) (xy 107.671693 -271.902586) (xy 107.663491 -271.851216) (xy 107.66349 -271.799195)
			(xy 107.671691 -271.747824) (xy 107.687887 -271.698389) (xy 107.711675 -271.652125) (xy 107.742459 -271.61019)
			(xy 107.779469 -271.573633) (xy 107.821779 -271.543367) (xy 107.844844 -271.531334) (xy 107.873038 -271.517364)
			(xy 107.873038 -270.505428) (xy 107.844844 -270.491458) (xy 107.821791 -270.479407) (xy 107.779484 -270.449143)
			(xy 107.742478 -270.412589) (xy 107.711697 -270.370657) (xy 107.687912 -270.324397) (xy 107.671718 -270.274966)
			(xy 107.663519 -270.223599) (xy 107.66352 -270.171583) (xy 107.671722 -270.120217) (xy 107.687919 -270.070787)
			(xy 107.711707 -270.024528) (xy 107.74249 -269.982598) (xy 107.779498 -269.946045) (xy 107.821806 -269.915784)
			(xy 107.844844 -269.903702) (xy 107.873038 -269.889732) (xy 107.873038 -268.877542) (xy 107.844844 -268.863572)
			(xy 107.82179 -268.851521) (xy 107.779481 -268.821257) (xy 107.742473 -268.784701) (xy 107.71169 -268.742769)
			(xy 107.687903 -268.696507) (xy 107.671707 -268.647075) (xy 107.663507 -268.595707) (xy 107.663507 -268.543688)
			(xy 107.671708 -268.49232) (xy 107.687905 -268.442888) (xy 107.711693 -268.396627) (xy 107.742476 -268.354694)
			(xy 107.779485 -268.31814) (xy 107.821795 -268.287877) (xy 107.844844 -268.275816) (xy 107.873038 -268.261846)
			(xy 107.873038 -267.249656) (xy 107.844844 -267.235686) (xy 107.821789 -267.223635) (xy 107.779478 -267.19337)
			(xy 107.742467 -267.156814) (xy 107.711683 -267.114881) (xy 107.687894 -267.068618) (xy 107.671696 -267.019184)
			(xy 107.663495 -266.967814) (xy 107.663494 -266.915793) (xy 107.671695 -266.864423) (xy 107.687891 -266.814989)
			(xy 107.711679 -266.768725) (xy 107.742463 -266.726791) (xy 107.779472 -266.690234) (xy 107.821783 -266.659969)
			(xy 107.844844 -266.64793) (xy 107.873038 -266.63396) (xy 107.873038 -265.622024) (xy 107.844844 -265.608054)
			(xy 107.821791 -265.596003) (xy 107.779485 -265.565739) (xy 107.74248 -265.529185) (xy 107.7117 -265.487253)
			(xy 107.687915 -265.440994) (xy 107.671721 -265.391563) (xy 107.663522 -265.340197) (xy 107.663524 -265.288181)
			(xy 107.671726 -265.236816) (xy 107.687923 -265.187386) (xy 107.711711 -265.141128) (xy 107.742494 -265.099199)
			(xy 107.779502 -265.062647) (xy 107.82181 -265.032386) (xy 107.844844 -265.020298) (xy 107.873038 -265.006328)
			(xy 107.873038 -264.922) (xy 107.717336 -264.766298) (xy 107.683808 -264.785602) (xy 107.658866 -264.799108)
			(xy 107.605486 -264.818267) (xy 107.549606 -264.82796) (xy 107.521248 -264.828528) (xy 107.495457 -264.828052)
			(xy 107.444509 -264.819989) (xy 107.395451 -264.804054) (xy 107.34949 -264.780639) (xy 107.307758 -264.750322)
			(xy 107.271284 -264.713848) (xy 107.240965 -264.672117) (xy 107.217549 -264.626157) (xy 107.201613 -264.577098)
			(xy 107.193549 -264.526151) (xy 107.19308 -264.50036) (xy 107.193654 -264.472002) (xy 107.203349 -264.416123)
			(xy 107.222495 -264.362738) (xy 107.236006 -264.3378) (xy 107.25531 -264.304272) (xy 106.735372 -263.784334)
			(xy 106.718113 -263.766293) (xy 106.690358 -263.724799) (xy 106.671247 -263.678681) (xy 106.661519 -263.629717)
			(xy 106.66095 -263.604756) (xy 106.66095 -262.118094) (xy 106.661522 -262.093134) (xy 106.671264 -262.044174)
			(xy 106.690371 -261.998056) (xy 106.71811 -261.956553) (xy 106.735372 -261.938516) (xy 107.069636 -261.604252)
			(xy 107.087677 -261.586992) (xy 107.129171 -261.559234) (xy 107.175289 -261.54012) (xy 107.224253 -261.530386)
			(xy 107.249214 -261.52983) (xy 107.45216 -261.52983) (xy 107.64393 -261.33806) (xy 107.64393 -261.1882)
			(xy 107.524042 -261.068312) (xy 105.571544 -261.068312) (xy 105.546589 -261.067695) (xy 105.497641 -261.057949)
			(xy 105.451534 -261.038841) (xy 105.41004 -261.011107) (xy 105.391966 -260.99389) (xy 105.297986 -260.89991)
			(xy 105.20045 -260.89991) (xy 105.20045 -260.900164) (xy 104.643936 -260.900164) (xy 104.328468 -261.215886)
			(xy 104.328468 -261.53999) (xy 104.412796 -261.624572) (xy 104.412796 -261.624826) (xy 104.502458 -261.714234)
			(xy 104.51313 -261.725559) (xy 104.529103 -261.752253) (xy 104.538104 -261.782031) (xy 104.539288 -261.797546)
			(xy 104.558301 -261.809008) (xy 104.592347 -261.837494) (xy 104.62092 -261.871467) (xy 104.643148 -261.909893)
			(xy 104.658354 -261.951599) (xy 104.666073 -261.995314) (xy 104.666542 -262.01751) (xy 104.666542 -266.33551)
			(xy 104.66597 -266.36047) (xy 104.656227 -266.409429) (xy 104.637119 -266.455546) (xy 104.609379 -266.497048)
			(xy 104.59212 -266.515088) (xy 102.89032 -268.216888) (xy 102.872279 -268.234148) (xy 102.830786 -268.261905)
			(xy 102.784668 -268.281016) (xy 102.735703 -268.290744) (xy 102.710742 -268.29131) (xy 96.640142 -268.29131)
			(xy 96.615188 -268.290693) (xy 96.566239 -268.280946) (xy 96.520133 -268.261838) (xy 96.478639 -268.234104)
			(xy 96.460564 -268.216888) (xy 96.319848 -268.076172) (xy 96.294194 -268.079982) (xy 96.281578 -268.081868)
			(xy 96.256149 -268.083906) (xy 96.243394 -268.084046) (xy 96.217605 -268.083566) (xy 96.166663 -268.075497)
			(xy 96.11761 -268.059557) (xy 96.071655 -268.03614) (xy 96.029929 -268.005822) (xy 95.99346 -267.969349)
			(xy 95.963146 -267.927621) (xy 95.939732 -267.881664) (xy 95.923797 -267.83261) (xy 95.915732 -267.781667)
			(xy 95.915226 -267.755878) (xy 95.91538 -267.743123) (xy 95.917413 -267.717695) (xy 95.91929 -267.705078)
			(xy 95.9231 -267.679424) (xy 93.886528 -265.642852) (xy 93.867732 -265.641328) (xy 93.842136 -265.638763)
			(xy 93.792137 -265.626682) (xy 93.744635 -265.606948) (xy 93.700793 -265.580046) (xy 93.661686 -265.546633)
			(xy 93.628269 -265.507527) (xy 93.601363 -265.463688) (xy 93.581626 -265.416187) (xy 93.569541 -265.366189)
			(xy 93.566996 -265.340592) (xy 93.565472 -265.321796) (xy 92.202 -263.958324) (xy 92.16898 -263.976104)
			(xy 92.145643 -263.987975) (xy 92.096122 -264.00497) (xy 92.044531 -264.013889) (xy 91.992178 -264.014505)
			(xy 91.940392 -264.006802) (xy 91.890485 -263.990976) (xy 91.843723 -263.967428) (xy 91.801292 -263.936756)
			(xy 91.764269 -263.899736) (xy 91.733592 -263.857309) (xy 91.710038 -263.81055) (xy 91.694207 -263.760645)
			(xy 91.686498 -263.70886) (xy 91.687108 -263.656507) (xy 91.69602 -263.604915) (xy 91.71301 -263.555392)
			(xy 91.724988 -263.532112) (xy 91.742768 -263.499092) (xy 91.419934 -263.176258) (xy 91.411298 -263.172448)
			(xy 91.389396 -263.16226) (xy 91.348592 -263.136406) (xy 91.31202 -263.10485) (xy 91.280469 -263.068274)
			(xy 91.25462 -263.027467) (xy 91.24442 -263.00557) (xy 91.24061 -262.996934) (xy 89.792302 -261.548626)
			(xy 89.763092 -261.558024) (xy 89.739126 -261.565037) (xy 89.689761 -261.572559) (xy 89.664794 -261.57301)
			(xy 89.639006 -261.572504) (xy 89.588064 -261.564435) (xy 89.539011 -261.548498) (xy 89.493055 -261.525083)
			(xy 89.451327 -261.494769) (xy 89.414855 -261.4583) (xy 89.384535 -261.416576) (xy 89.361116 -261.370623)
			(xy 89.345173 -261.321571) (xy 89.337099 -261.27063) (xy 89.336626 -261.244842) (xy 89.336967 -261.223188)
			(xy 89.342662 -261.180257) (xy 89.353971 -261.138452) (xy 89.362026 -261.11835) (xy 89.348564 -261.104888)
			(xy 89.331302 -261.086848) (xy 89.303538 -261.045355) (xy 89.284419 -260.999237) (xy 89.27468 -260.950272)
			(xy 89.274142 -260.92531) (xy 89.274142 -249.790712) (xy 89.267792 -249.779028) (xy 89.254879 -249.754533)
			(xy 89.236545 -249.702287) (xy 89.227219 -249.647708) (xy 89.226644 -249.620024) (xy 89.227212 -249.592337)
			(xy 89.236505 -249.537748) (xy 89.254847 -249.485501) (xy 89.267792 -249.46102) (xy 89.274142 -249.449336)
			(xy 89.274142 -248.162318) (xy 89.267792 -248.150888) (xy 89.254918 -248.126429) (xy 89.236665 -248.074263)
			(xy 89.22743 -248.019772) (xy 89.226898 -247.992138) (xy 89.227468 -247.964507) (xy 89.236712 -247.910023)
			(xy 89.254928 -247.857849) (xy 89.267792 -247.833388) (xy 89.274142 -247.821958) (xy 89.274142 -246.535194)
			(xy 89.267792 -246.52351) (xy 89.254881 -246.499014) (xy 89.236549 -246.446768) (xy 89.227226 -246.39219)
			(xy 89.226644 -246.364506) (xy 89.227213 -246.336819) (xy 89.236509 -246.282232) (xy 89.254854 -246.229986)
			(xy 89.267792 -246.205502) (xy 89.274142 -246.193818) (xy 89.274142 -244.907308) (xy 89.267792 -244.895624)
			(xy 89.254879 -244.871128) (xy 89.236546 -244.818882) (xy 89.227221 -244.764304) (xy 89.226644 -244.73662)
			(xy 89.227212 -244.708933) (xy 89.236506 -244.654345) (xy 89.254849 -244.602097) (xy 89.267792 -244.577616)
			(xy 89.274142 -244.565932) (xy 89.274142 -243.279676) (xy 89.267792 -243.267992) (xy 89.254882 -243.243496)
			(xy 89.236554 -243.191249) (xy 89.227234 -243.136671) (xy 89.226644 -243.108988) (xy 89.227215 -243.081302)
			(xy 89.236513 -243.026716) (xy 89.25486 -242.974471) (xy 89.267792 -242.949984) (xy 89.274142 -242.9383)
			(xy 89.274142 -241.65179) (xy 89.267792 -241.640106) (xy 89.254881 -241.61561) (xy 89.23655 -241.563364)
			(xy 89.227228 -241.508786) (xy 89.226644 -241.481102) (xy 89.227214 -241.453415) (xy 89.23651 -241.398828)
			(xy 89.254855 -241.346583) (xy 89.267792 -241.322098) (xy 89.274142 -241.310414) (xy 89.274142 -240.023904)
			(xy 89.267792 -240.01222) (xy 89.25488 -239.987724) (xy 89.236547 -239.935478) (xy 89.227222 -239.8809)
			(xy 89.226644 -239.853216) (xy 89.227213 -239.825529) (xy 89.236507 -239.770941) (xy 89.25485 -239.718694)
			(xy 89.267792 -239.694212) (xy 89.274142 -239.682528) (xy 89.274142 -238.396272) (xy 89.267792 -238.384588)
			(xy 89.254882 -238.360092) (xy 89.236555 -238.307845) (xy 89.227235 -238.253267) (xy 89.226644 -238.225584)
			(xy 89.227215 -238.197898) (xy 89.236514 -238.143312) (xy 89.254862 -238.091068) (xy 89.267792 -238.06658)
			(xy 89.274142 -238.054896) (xy 89.274142 -236.76864) (xy 89.267792 -236.756956) (xy 89.254885 -236.732459)
			(xy 89.236562 -236.680212) (xy 89.227248 -236.625635) (xy 89.226644 -236.597952) (xy 89.227218 -236.570267)
			(xy 89.236522 -236.515683) (xy 89.254874 -236.463442) (xy 89.267792 -236.438948) (xy 89.274142 -236.427264)
			(xy 89.274142 -235.140754) (xy 89.267792 -235.12907) (xy 89.254884 -235.104574) (xy 89.236559 -235.052327)
			(xy 89.227242 -234.997749) (xy 89.226644 -234.970066) (xy 89.227217 -234.94238) (xy 89.236519 -234.887796)
			(xy 89.254868 -234.835553) (xy 89.267792 -234.811062) (xy 89.274142 -234.799378) (xy 89.274142 -233.665522)
			(xy 89.274525 -233.645656) (xy 89.280709 -233.606409) (xy 89.292929 -233.568604) (xy 89.301574 -233.550714)
			(xy 89.284041 -233.528525) (xy 89.256075 -233.479377) (xy 89.236953 -233.426161) (xy 89.227241 -233.370454)
			(xy 89.226644 -233.34218) (xy 89.227151 -233.316394) (xy 89.235222 -233.265457) (xy 89.251161 -233.216409)
			(xy 89.274577 -233.170459) (xy 89.304893 -233.128738) (xy 89.341362 -233.092272) (xy 89.383086 -233.061961)
			(xy 89.429039 -233.038549) (xy 89.478088 -233.022614) (xy 89.529026 -233.014549) (xy 89.554812 -233.014012)
			(xy 89.58392 -233.014659) (xy 89.641216 -233.024968) (xy 89.695795 -233.045225) (xy 89.721182 -233.059478)
			(xy 89.755218 -233.07929) (xy 91.10599 -231.728518) (xy 91.106244 -231.708198) (xy 91.107208 -231.683054)
			(xy 91.115841 -231.633483) (xy 91.131939 -231.585811) (xy 91.155125 -231.541154) (xy 91.184855 -231.50056)
			(xy 91.220432 -231.464978) (xy 91.261023 -231.435244) (xy 91.305677 -231.412054) (xy 91.353347 -231.39595)
			(xy 91.402917 -231.387312) (xy 91.428062 -231.38638) (xy 91.448382 -231.386126) (xy 93.468444 -229.366064)
			(xy 93.462856 -229.339394) (xy 93.45965 -229.322944) (xy 93.456216 -229.289604) (xy 93.455998 -229.272846)
			(xy 93.456474 -229.247053) (xy 93.464537 -229.196101) (xy 93.480471 -229.147038) (xy 93.503885 -229.101072)
			(xy 93.534201 -229.059334) (xy 93.570673 -229.022853) (xy 93.612403 -228.992526) (xy 93.658364 -228.969102)
			(xy 93.707423 -228.953155) (xy 93.758373 -228.94508) (xy 93.784166 -228.944678) (xy 93.800923 -228.944904)
			(xy 93.834262 -228.948345) (xy 93.850714 -228.951536) (xy 93.877384 -228.957124) (xy 95.844614 -226.989894)
			(xy 95.831152 -226.958652) (xy 95.823018 -226.938391) (xy 95.811581 -226.896256) (xy 95.805841 -226.852974)
			(xy 95.805498 -226.831144) (xy 95.805974 -226.805351) (xy 95.814037 -226.754399) (xy 95.829972 -226.705337)
			(xy 95.853385 -226.659371) (xy 95.883701 -226.617633) (xy 95.920174 -226.581152) (xy 95.961904 -226.550826)
			(xy 96.007864 -226.527402) (xy 96.056924 -226.511455) (xy 96.107873 -226.50338) (xy 96.133666 -226.502976)
			(xy 96.155496 -226.503317) (xy 96.198776 -226.509066) (xy 96.240914 -226.520493) (xy 96.261174 -226.52863)
			(xy 96.292416 -226.542092) (xy 96.854518 -225.97999) (xy 96.854518 -225.449892) (xy 96.834028 -225.430965)
			(xy 96.799098 -225.387483) (xy 96.771989 -225.338739) (xy 96.753477 -225.286125) (xy 96.744091 -225.231146)
			(xy 96.74352 -225.203258) (xy 96.744111 -225.17554) (xy 96.753435 -225.120894) (xy 96.762062 -225.094546)
			(xy 96.769936 -225.072448) (xy 96.564958 -224.71761) (xy 96.542098 -224.713292) (xy 96.517295 -224.708095)
			(xy 96.469554 -224.691108) (xy 96.424973 -224.667016) (xy 96.384604 -224.636387) (xy 96.349396 -224.599942)
			(xy 96.320178 -224.55854) (xy 96.297639 -224.513155) (xy 96.282309 -224.464855) (xy 96.27455 -224.414779)
			(xy 96.274128 -224.389442) (xy 96.274606 -224.363549) (xy 96.282701 -224.312401) (xy 96.298697 -224.263148)
			(xy 96.322201 -224.217005) (xy 96.352635 -224.175106) (xy 96.389248 -224.138484) (xy 96.43114 -224.108041)
			(xy 96.477278 -224.084526) (xy 96.526527 -224.068518) (xy 96.577674 -224.060412) (xy 96.603566 -224.060004)
			(xy 96.6327 -224.060605) (xy 96.690061 -224.070832) (xy 96.717612 -224.080324) (xy 96.730891 -224.084773)
			(xy 96.758798 -224.087004) (xy 96.786261 -224.081569) (xy 96.811214 -224.068877) (xy 96.831781 -224.049883)
			(xy 96.846415 -224.026017) (xy 96.854013 -223.999072) (xy 96.854518 -223.985074) (xy 96.854518 -223.819974)
			(xy 96.836148 -223.802896) (xy 96.804301 -223.764149) (xy 96.778726 -223.721004) (xy 96.760019 -223.674468)
			(xy 96.748616 -223.625626) (xy 96.744784 -223.575617) (xy 96.748611 -223.525608) (xy 96.760009 -223.476765)
			(xy 96.778711 -223.430227) (xy 96.804281 -223.38708) (xy 96.836124 -223.348329) (xy 96.854518 -223.331278)
			(xy 96.854518 -222.194374) (xy 96.834029 -222.175447) (xy 96.799101 -222.131964) (xy 96.771995 -222.083219)
			(xy 96.753486 -222.030606) (xy 96.744103 -221.975627) (xy 96.74352 -221.94774) (xy 96.744113 -221.920023)
			(xy 96.753439 -221.865377) (xy 96.762062 -221.839028) (xy 96.769936 -221.81693) (xy 96.564958 -221.462092)
			(xy 96.542098 -221.457774) (xy 96.517296 -221.452577) (xy 96.469556 -221.435589) (xy 96.424977 -221.411497)
			(xy 96.384609 -221.380868) (xy 96.349403 -221.344423) (xy 96.320187 -221.30302) (xy 96.297651 -221.257635)
			(xy 96.282323 -221.209336) (xy 96.274567 -221.15926) (xy 96.274128 -221.133924) (xy 96.27489 -221.108524)
			(xy 96.276668 -221.085156) (xy 96.14408 -220.952568) (xy 96.13437 -220.943401) (xy 96.111261 -220.930035)
			(xy 96.085478 -220.923111) (xy 96.058782 -220.923103) (xy 96.032995 -220.930011) (xy 96.009878 -220.943364)
			(xy 95.99101 -220.962249) (xy 95.98406 -220.97365) (xy 95.967042 -221.003114) (xy 95.974916 -221.024958)
			(xy 95.983497 -221.051376) (xy 95.992697 -221.106152) (xy 95.993204 -221.133924) (xy 95.992696 -221.159811)
			(xy 95.984597 -221.210949) (xy 95.968598 -221.260189) (xy 95.945092 -221.306321) (xy 95.91466 -221.348208)
			(xy 95.87805 -221.384818) (xy 95.836163 -221.41525) (xy 95.790031 -221.438756) (xy 95.740791 -221.454755)
			(xy 95.689653 -221.462854) (xy 95.637879 -221.462854) (xy 95.586741 -221.454755) (xy 95.537501 -221.438756)
			(xy 95.491369 -221.41525) (xy 95.449482 -221.384818) (xy 95.412872 -221.348208) (xy 95.38244 -221.306321)
			(xy 95.358934 -221.260189) (xy 95.342935 -221.210949) (xy 95.334836 -221.159811) (xy 95.334328 -221.133924)
			(xy 95.33479 -221.108588) (xy 95.34254 -221.058511) (xy 95.357862 -221.01021) (xy 95.380394 -220.964822)
			(xy 95.409605 -220.923417) (xy 95.444809 -220.886969) (xy 95.485175 -220.856337) (xy 95.529753 -220.832242)
			(xy 95.577492 -220.815252) (xy 95.602298 -220.810074) (xy 95.625158 -220.805756) (xy 95.761302 -220.56979)
			(xy 94.98838 -219.796868) (xy 94.971118 -219.778828) (xy 94.943356 -219.737335) (xy 94.924239 -219.691217)
			(xy 94.914504 -219.642252) (xy 94.913958 -219.61729) (xy 94.913958 -218.867228) (xy 94.907354 -218.855544)
			(xy 94.893734 -218.830498) (xy 94.87438 -218.776876) (xy 94.864537 -218.720725) (xy 94.86392 -218.692222)
			(xy 94.864506 -218.664503) (xy 94.87382 -218.609853) (xy 94.882462 -218.58351) (xy 94.890336 -218.561412)
			(xy 94.685358 -218.206574) (xy 94.662498 -218.202256) (xy 94.637867 -218.197097) (xy 94.590431 -218.180303)
			(xy 94.546102 -218.156488) (xy 94.505912 -218.126206) (xy 94.488 -218.10853) (xy 94.020132 -218.10853)
			(xy 94.001383 -218.126991) (xy 93.959108 -218.158311) (xy 93.912392 -218.182515) (xy 93.862424 -218.198989)
			(xy 93.810473 -218.207312) (xy 93.784166 -218.207844) (xy 93.757857 -218.20735) (xy 93.705901 -218.199026)
			(xy 93.655931 -218.182547) (xy 93.609216 -218.158332) (xy 93.566945 -218.126998) (xy 93.5482 -218.10853)
			(xy 93.381068 -218.10853) (xy 93.365834 -218.1091) (xy 93.336718 -218.118079) (xy 93.311535 -218.135232)
			(xy 93.292519 -218.159038) (xy 93.281353 -218.187387) (xy 93.279028 -218.217767) (xy 93.285749 -218.247486)
			(xy 93.29293 -218.26093) (xy 93.35262 -218.364054) (xy 93.37548 -218.368372) (xy 93.40029 -218.373561)
			(xy 93.448049 -218.390535) (xy 93.492648 -218.414618) (xy 93.533036 -218.445243) (xy 93.568262 -218.481687)
			(xy 93.597496 -218.523092) (xy 93.62005 -218.568484) (xy 93.635391 -218.616792) (xy 93.643159 -218.666879)
			(xy 93.643704 -218.692222) (xy 93.643196 -218.718129) (xy 93.63509 -218.769306) (xy 93.619078 -218.818585)
			(xy 93.595555 -218.864752) (xy 93.565099 -218.906671) (xy 93.528461 -218.943309) (xy 93.486542 -218.973765)
			(xy 93.440375 -218.997288) (xy 93.391096 -219.0133) (xy 93.339919 -219.021406) (xy 93.288105 -219.021406)
			(xy 93.236928 -219.0133) (xy 93.187649 -218.997288) (xy 93.141482 -218.973765) (xy 93.099563 -218.943309)
			(xy 93.062925 -218.906671) (xy 93.032469 -218.864752) (xy 93.008946 -218.818585) (xy 92.992934 -218.769306)
			(xy 92.984828 -218.718129) (xy 92.98432 -218.692222) (xy 92.984906 -218.664503) (xy 92.99422 -218.609853)
			(xy 93.002862 -218.58351) (xy 93.010736 -218.561412) (xy 92.805758 -218.206574) (xy 92.782898 -218.202256)
			(xy 92.758267 -218.197097) (xy 92.710831 -218.180303) (xy 92.666502 -218.156488) (xy 92.626312 -218.126206)
			(xy 92.6084 -218.10853) (xy 92.140532 -218.10853) (xy 92.121783 -218.126991) (xy 92.079508 -218.158311)
			(xy 92.032792 -218.182515) (xy 91.982824 -218.198989) (xy 91.930873 -218.207312) (xy 91.904566 -218.207844)
			(xy 91.878257 -218.20735) (xy 91.826301 -218.199026) (xy 91.776331 -218.182547) (xy 91.729616 -218.158332)
			(xy 91.687345 -218.126998) (xy 91.6686 -218.10853) (xy 91.501468 -218.10853) (xy 91.486234 -218.1091)
			(xy 91.457118 -218.118079) (xy 91.431935 -218.135232) (xy 91.412919 -218.159038) (xy 91.401753 -218.187387)
			(xy 91.399428 -218.217767) (xy 91.406149 -218.247486) (xy 91.41333 -218.26093) (xy 91.47302 -218.364054)
			(xy 91.49588 -218.368372) (xy 91.52069 -218.373561) (xy 91.568449 -218.390535) (xy 91.613048 -218.414618)
			(xy 91.653436 -218.445243) (xy 91.688662 -218.481687) (xy 91.717896 -218.523092) (xy 91.74045 -218.568484)
			(xy 91.755791 -218.616792) (xy 91.763559 -218.666879) (xy 91.764104 -218.692222) (xy 91.763596 -218.718129)
			(xy 91.75549 -218.769306) (xy 91.739478 -218.818585) (xy 91.715955 -218.864752) (xy 91.685499 -218.906671)
			(xy 91.648861 -218.943309) (xy 91.606942 -218.973765) (xy 91.560775 -218.997288) (xy 91.511496 -219.0133)
			(xy 91.460319 -219.021406) (xy 91.408505 -219.021406) (xy 91.357328 -219.0133) (xy 91.308049 -218.997288)
			(xy 91.261882 -218.973765) (xy 91.219963 -218.943309) (xy 91.183325 -218.906671) (xy 91.152869 -218.864752)
			(xy 91.129346 -218.818585) (xy 91.113334 -218.769306) (xy 91.105228 -218.718129) (xy 91.10472 -218.692222)
			(xy 91.105306 -218.664503) (xy 91.11462 -218.609853) (xy 91.123262 -218.58351) (xy 91.131136 -218.561412)
			(xy 90.926158 -218.206574) (xy 90.903298 -218.202256) (xy 90.878667 -218.197097) (xy 90.831231 -218.180303)
			(xy 90.786902 -218.156488) (xy 90.746712 -218.126206) (xy 90.7288 -218.10853) (xy 90.260932 -218.10853)
			(xy 90.242183 -218.126991) (xy 90.199908 -218.158311) (xy 90.153192 -218.182515) (xy 90.103224 -218.198989)
			(xy 90.051273 -218.207312) (xy 90.024966 -218.207844) (xy 89.998657 -218.20735) (xy 89.946701 -218.199026)
			(xy 89.896731 -218.182547) (xy 89.850016 -218.158332) (xy 89.807745 -218.126998) (xy 89.789 -218.10853)
			(xy 89.669874 -218.10853) (xy 89.527888 -218.250516) (xy 89.59342 -218.364054) (xy 89.61628 -218.368372)
			(xy 89.64109 -218.373561) (xy 89.688849 -218.390535) (xy 89.733448 -218.414618) (xy 89.773836 -218.445243)
			(xy 89.809062 -218.481687) (xy 89.838296 -218.523092) (xy 89.86085 -218.568484) (xy 89.876191 -218.616792)
			(xy 89.883959 -218.666879) (xy 89.884504 -218.692222) (xy 89.883996 -218.718129) (xy 89.87589 -218.769306)
			(xy 89.859878 -218.818585) (xy 89.836355 -218.864752) (xy 89.805899 -218.906671) (xy 89.769261 -218.943309)
			(xy 89.727342 -218.973765) (xy 89.681175 -218.997288) (xy 89.631896 -219.0133) (xy 89.580719 -219.021406)
			(xy 89.528905 -219.021406) (xy 89.477728 -219.0133) (xy 89.428449 -218.997288) (xy 89.382282 -218.973765)
			(xy 89.340363 -218.943309) (xy 89.303725 -218.906671) (xy 89.273269 -218.864752) (xy 89.249746 -218.818585)
			(xy 89.233734 -218.769306) (xy 89.225628 -218.718129) (xy 89.22512 -218.692222) (xy 89.225628 -218.674696)
			(xy 89.225896 -218.660474) (xy 89.219484 -218.632772) (xy 89.205672 -218.607918) (xy 89.185536 -218.587842)
			(xy 89.16064 -218.574106) (xy 89.13292 -218.567777) (xy 89.118694 -218.568016) (xy 89.104978 -218.56827)
			(xy 74.484738 -218.56827) (xy 74.478642 -218.569794) (xy 74.463041 -218.573587) (xy 74.431195 -218.577666)
			(xy 74.415142 -218.577922) (xy 51.395122 -218.577922) (xy 51.388264 -218.62034) (xy 51.383584 -218.645583)
			(xy 51.36742 -218.694308) (xy 51.343867 -218.739923) (xy 51.313501 -218.781316) (xy 51.277061 -218.817476)
			(xy 51.235436 -218.847523) (xy 51.189641 -218.870724) (xy 51.140793 -218.886513) (xy 51.090082 -218.894505)
			(xy 51.038746 -218.894505) (xy 50.988035 -218.886513) (xy 50.939187 -218.870724) (xy 50.893392 -218.847523)
			(xy 50.851767 -218.817476) (xy 50.815327 -218.781316) (xy 50.784961 -218.739923) (xy 50.761408 -218.694308)
			(xy 50.745244 -218.645583) (xy 50.740564 -218.62034) (xy 50.733706 -218.577922) (xy 47.295054 -218.577922)
			(xy 47.288196 -218.62034) (xy 47.283516 -218.645583) (xy 47.267352 -218.694308) (xy 47.243799 -218.739923)
			(xy 47.213433 -218.781316) (xy 47.176993 -218.817476) (xy 47.135368 -218.847523) (xy 47.089573 -218.870724)
			(xy 47.040725 -218.886513) (xy 46.990014 -218.894505) (xy 46.938678 -218.894505) (xy 46.887967 -218.886513)
			(xy 46.839119 -218.870724) (xy 46.793324 -218.847523) (xy 46.751699 -218.817476) (xy 46.715259 -218.781316)
			(xy 46.684893 -218.739923) (xy 46.66134 -218.694308) (xy 46.645176 -218.645583) (xy 46.640496 -218.62034)
			(xy 46.633638 -218.577922) (xy 36.307522 -218.577922) (xy 36.300664 -218.62034) (xy 36.295984 -218.645583)
			(xy 36.27982 -218.694308) (xy 36.256267 -218.739923) (xy 36.225901 -218.781316) (xy 36.189461 -218.817476)
			(xy 36.147836 -218.847523) (xy 36.102041 -218.870724) (xy 36.053193 -218.886513) (xy 36.002482 -218.894505)
			(xy 35.951146 -218.894505) (xy 35.900435 -218.886513) (xy 35.851587 -218.870724) (xy 35.805792 -218.847523)
			(xy 35.764167 -218.817476) (xy 35.727727 -218.781316) (xy 35.697361 -218.739923) (xy 35.673808 -218.694308)
			(xy 35.657644 -218.645583) (xy 35.652964 -218.62034) (xy 35.646106 -218.577922) (xy 32.276542 -218.577922)
			(xy 32.190436 -218.664028) (xy 32.186626 -218.67495) (xy 32.1781 -218.69803) (xy 32.155127 -218.741537)
			(xy 32.125918 -218.781129) (xy 32.091129 -218.815918) (xy 32.051537 -218.845127) (xy 32.00803 -218.8681)
			(xy 31.98495 -218.876626) (xy 31.974028 -218.880436) (xy 31.743142 -219.111322) (xy 31.743142 -221.133924)
			(xy 88.755728 -221.133924) (xy 88.756236 -221.108037) (xy 88.764335 -221.056899) (xy 88.780334 -221.007659)
			(xy 88.80384 -220.961527) (xy 88.834272 -220.91964) (xy 88.870882 -220.88303) (xy 88.912769 -220.852598)
			(xy 88.958901 -220.829092) (xy 89.008141 -220.813093) (xy 89.059279 -220.804994) (xy 89.111053 -220.804994)
			(xy 89.162191 -220.813093) (xy 89.211431 -220.829092) (xy 89.257563 -220.852598) (xy 89.29945 -220.88303)
			(xy 89.33606 -220.91964) (xy 89.366492 -220.961527) (xy 89.389998 -221.007659) (xy 89.405997 -221.056899)
			(xy 89.414096 -221.108037) (xy 89.414604 -221.133924) (xy 89.695528 -221.133924) (xy 89.69601 -221.108589)
			(xy 89.70376 -221.058515) (xy 89.71908 -221.010217) (xy 89.741611 -220.964832) (xy 89.770821 -220.923429)
			(xy 89.806022 -220.886984) (xy 89.846386 -220.856354) (xy 89.890961 -220.83226) (xy 89.938698 -220.815272)
			(xy 89.963498 -220.810074) (xy 89.986358 -220.805756) (xy 90.191336 -220.450664) (xy 90.183462 -220.42882)
			(xy 90.174829 -220.402408) (xy 90.1655 -220.347635) (xy 90.16492 -220.319854) (xy 90.165428 -220.293947)
			(xy 90.173534 -220.24277) (xy 90.189546 -220.193491) (xy 90.213069 -220.147324) (xy 90.243525 -220.105405)
			(xy 90.280163 -220.068767) (xy 90.322082 -220.038311) (xy 90.368249 -220.014788) (xy 90.417528 -219.998776)
			(xy 90.468705 -219.99067) (xy 90.520519 -219.99067) (xy 90.571696 -219.998776) (xy 90.620975 -220.014788)
			(xy 90.667142 -220.038311) (xy 90.709061 -220.068767) (xy 90.745699 -220.105405) (xy 90.776155 -220.147324)
			(xy 90.799678 -220.193491) (xy 90.81569 -220.24277) (xy 90.823796 -220.293947) (xy 90.824304 -220.319854)
			(xy 90.823828 -220.345199) (xy 90.816049 -220.395289) (xy 90.800697 -220.443599) (xy 90.778134 -220.48899)
			(xy 90.748891 -220.530396) (xy 90.713657 -220.566839) (xy 90.673262 -220.597461) (xy 90.628657 -220.621543)
			(xy 90.580893 -220.638516) (xy 90.55608 -220.643704) (xy 90.53322 -220.648022) (xy 90.328242 -221.003114)
			(xy 90.336116 -221.024958) (xy 90.34471 -221.051373) (xy 90.353897 -221.106151) (xy 90.354404 -221.133924)
			(xy 90.635328 -221.133924) (xy 90.635836 -221.108037) (xy 90.643935 -221.056899) (xy 90.659934 -221.007659)
			(xy 90.68344 -220.961527) (xy 90.713872 -220.91964) (xy 90.750482 -220.88303) (xy 90.792369 -220.852598)
			(xy 90.838501 -220.829092) (xy 90.887741 -220.813093) (xy 90.938879 -220.804994) (xy 90.990653 -220.804994)
			(xy 91.041791 -220.813093) (xy 91.091031 -220.829092) (xy 91.137163 -220.852598) (xy 91.17905 -220.88303)
			(xy 91.21566 -220.91964) (xy 91.246092 -220.961527) (xy 91.269598 -221.007659) (xy 91.285597 -221.056899)
			(xy 91.293696 -221.108037) (xy 91.294204 -221.133924) (xy 91.575128 -221.133924) (xy 91.57561 -221.108589)
			(xy 91.58336 -221.058515) (xy 91.59868 -221.010217) (xy 91.621211 -220.964832) (xy 91.650421 -220.923429)
			(xy 91.685622 -220.886984) (xy 91.725986 -220.856354) (xy 91.770561 -220.83226) (xy 91.818298 -220.815272)
			(xy 91.843098 -220.810074) (xy 91.865958 -220.805756) (xy 92.070936 -220.450664) (xy 92.063062 -220.42882)
			(xy 92.054429 -220.402408) (xy 92.0451 -220.347635) (xy 92.04452 -220.319854) (xy 92.045028 -220.293947)
			(xy 92.053134 -220.24277) (xy 92.069146 -220.193491) (xy 92.092669 -220.147324) (xy 92.123125 -220.105405)
			(xy 92.159763 -220.068767) (xy 92.201682 -220.038311) (xy 92.247849 -220.014788) (xy 92.297128 -219.998776)
			(xy 92.348305 -219.99067) (xy 92.400119 -219.99067) (xy 92.451296 -219.998776) (xy 92.500575 -220.014788)
			(xy 92.546742 -220.038311) (xy 92.588661 -220.068767) (xy 92.625299 -220.105405) (xy 92.655755 -220.147324)
			(xy 92.679278 -220.193491) (xy 92.69529 -220.24277) (xy 92.703396 -220.293947) (xy 92.703904 -220.319854)
			(xy 92.703428 -220.345199) (xy 92.695649 -220.395289) (xy 92.680297 -220.443599) (xy 92.657734 -220.48899)
			(xy 92.628491 -220.530396) (xy 92.593257 -220.566839) (xy 92.552862 -220.597461) (xy 92.508257 -220.621543)
			(xy 92.460493 -220.638516) (xy 92.43568 -220.643704) (xy 92.41282 -220.648022) (xy 92.207842 -221.003114)
			(xy 92.215716 -221.024958) (xy 92.22431 -221.051373) (xy 92.233497 -221.106151) (xy 92.234004 -221.133924)
			(xy 92.514928 -221.133924) (xy 92.515436 -221.108037) (xy 92.523535 -221.056899) (xy 92.539534 -221.007659)
			(xy 92.56304 -220.961527) (xy 92.593472 -220.91964) (xy 92.630082 -220.88303) (xy 92.671969 -220.852598)
			(xy 92.718101 -220.829092) (xy 92.767341 -220.813093) (xy 92.818479 -220.804994) (xy 92.870253 -220.804994)
			(xy 92.921391 -220.813093) (xy 92.970631 -220.829092) (xy 93.016763 -220.852598) (xy 93.05865 -220.88303)
			(xy 93.09526 -220.91964) (xy 93.125692 -220.961527) (xy 93.149198 -221.007659) (xy 93.165197 -221.056899)
			(xy 93.173296 -221.108037) (xy 93.173804 -221.133924) (xy 93.454728 -221.133924) (xy 93.45521 -221.108589)
			(xy 93.46296 -221.058515) (xy 93.47828 -221.010217) (xy 93.500811 -220.964832) (xy 93.530021 -220.923429)
			(xy 93.565222 -220.886984) (xy 93.605586 -220.856354) (xy 93.650161 -220.83226) (xy 93.697898 -220.815272)
			(xy 93.722698 -220.810074) (xy 93.745558 -220.805756) (xy 93.950536 -220.450664) (xy 93.942662 -220.42882)
			(xy 93.934029 -220.402408) (xy 93.9247 -220.347635) (xy 93.92412 -220.319854) (xy 93.924628 -220.293947)
			(xy 93.932734 -220.24277) (xy 93.948746 -220.193491) (xy 93.972269 -220.147324) (xy 94.002725 -220.105405)
			(xy 94.039363 -220.068767) (xy 94.081282 -220.038311) (xy 94.127449 -220.014788) (xy 94.176728 -219.998776)
			(xy 94.227905 -219.99067) (xy 94.279719 -219.99067) (xy 94.330896 -219.998776) (xy 94.380175 -220.014788)
			(xy 94.426342 -220.038311) (xy 94.468261 -220.068767) (xy 94.504899 -220.105405) (xy 94.535355 -220.147324)
			(xy 94.558878 -220.193491) (xy 94.57489 -220.24277) (xy 94.582996 -220.293947) (xy 94.583504 -220.319854)
			(xy 94.583028 -220.345199) (xy 94.575249 -220.395289) (xy 94.559897 -220.443599) (xy 94.537334 -220.48899)
			(xy 94.508091 -220.530396) (xy 94.472857 -220.566839) (xy 94.432462 -220.597461) (xy 94.387857 -220.621543)
			(xy 94.340093 -220.638516) (xy 94.31528 -220.643704) (xy 94.29242 -220.648022) (xy 94.087442 -221.003114)
			(xy 94.095316 -221.024958) (xy 94.10391 -221.051373) (xy 94.113097 -221.106151) (xy 94.113604 -221.133924)
			(xy 94.394528 -221.133924) (xy 94.395036 -221.108037) (xy 94.403135 -221.056899) (xy 94.419134 -221.007659)
			(xy 94.44264 -220.961527) (xy 94.473072 -220.91964) (xy 94.509682 -220.88303) (xy 94.551569 -220.852598)
			(xy 94.597701 -220.829092) (xy 94.646941 -220.813093) (xy 94.698079 -220.804994) (xy 94.749853 -220.804994)
			(xy 94.800991 -220.813093) (xy 94.850231 -220.829092) (xy 94.896363 -220.852598) (xy 94.93825 -220.88303)
			(xy 94.97486 -220.91964) (xy 95.005292 -220.961527) (xy 95.028798 -221.007659) (xy 95.044797 -221.056899)
			(xy 95.052896 -221.108037) (xy 95.053404 -221.133924) (xy 95.05288 -221.161632) (xy 95.043681 -221.216279)
			(xy 95.035116 -221.242636) (xy 95.027242 -221.264734) (xy 95.23222 -221.619572) (xy 95.25508 -221.62389)
			(xy 95.279905 -221.629041) (xy 95.327683 -221.645999) (xy 95.372302 -221.670074) (xy 95.412707 -221.700696)
			(xy 95.447947 -221.737145) (xy 95.47719 -221.778561) (xy 95.499747 -221.823965) (xy 95.515085 -221.872289)
			(xy 95.522842 -221.92239) (xy 95.523304 -221.94774) (xy 95.522796 -221.973647) (xy 95.51469 -222.024824)
			(xy 95.498678 -222.074103) (xy 95.475155 -222.12027) (xy 95.444699 -222.162189) (xy 95.408061 -222.198827)
			(xy 95.366142 -222.229283) (xy 95.319975 -222.252806) (xy 95.270696 -222.268818) (xy 95.219519 -222.276924)
			(xy 95.167705 -222.276924) (xy 95.116528 -222.268818) (xy 95.067249 -222.252806) (xy 95.021082 -222.229283)
			(xy 94.979163 -222.198827) (xy 94.942525 -222.162189) (xy 94.912069 -222.12027) (xy 94.888546 -222.074103)
			(xy 94.872534 -222.024824) (xy 94.864428 -221.973647) (xy 94.86392 -221.94774) (xy 94.864523 -221.920023)
			(xy 94.87384 -221.865377) (xy 94.882462 -221.839028) (xy 94.890336 -221.81693) (xy 94.685358 -221.462092)
			(xy 94.662498 -221.457774) (xy 94.637703 -221.45255) (xy 94.589967 -221.435564) (xy 94.545392 -221.411474)
			(xy 94.505027 -221.380847) (xy 94.469824 -221.344405) (xy 94.440611 -221.303006) (xy 94.418076 -221.257625)
			(xy 94.40275 -221.20933) (xy 94.394994 -221.159258) (xy 94.394528 -221.133924) (xy 94.113604 -221.133924)
			(xy 94.113096 -221.159811) (xy 94.104997 -221.210949) (xy 94.088998 -221.260189) (xy 94.065492 -221.306321)
			(xy 94.03506 -221.348208) (xy 93.99845 -221.384818) (xy 93.956563 -221.41525) (xy 93.910431 -221.438756)
			(xy 93.861191 -221.454755) (xy 93.810053 -221.462854) (xy 93.758279 -221.462854) (xy 93.707141 -221.454755)
			(xy 93.657901 -221.438756) (xy 93.611769 -221.41525) (xy 93.569882 -221.384818) (xy 93.533272 -221.348208)
			(xy 93.50284 -221.306321) (xy 93.479334 -221.260189) (xy 93.463335 -221.210949) (xy 93.455236 -221.159811)
			(xy 93.454728 -221.133924) (xy 93.173804 -221.133924) (xy 93.17328 -221.161632) (xy 93.164081 -221.216279)
			(xy 93.155516 -221.242636) (xy 93.147642 -221.264734) (xy 93.35262 -221.619572) (xy 93.37548 -221.62389)
			(xy 93.400305 -221.629041) (xy 93.448083 -221.645999) (xy 93.492702 -221.670074) (xy 93.533107 -221.700696)
			(xy 93.568347 -221.737145) (xy 93.59759 -221.778561) (xy 93.620147 -221.823965) (xy 93.635485 -221.872289)
			(xy 93.643242 -221.92239) (xy 93.643704 -221.94774) (xy 93.643196 -221.973647) (xy 93.63509 -222.024824)
			(xy 93.619078 -222.074103) (xy 93.595555 -222.12027) (xy 93.565099 -222.162189) (xy 93.528461 -222.198827)
			(xy 93.486542 -222.229283) (xy 93.440375 -222.252806) (xy 93.391096 -222.268818) (xy 93.339919 -222.276924)
			(xy 93.288105 -222.276924) (xy 93.236928 -222.268818) (xy 93.187649 -222.252806) (xy 93.141482 -222.229283)
			(xy 93.099563 -222.198827) (xy 93.062925 -222.162189) (xy 93.032469 -222.12027) (xy 93.008946 -222.074103)
			(xy 92.992934 -222.024824) (xy 92.984828 -221.973647) (xy 92.98432 -221.94774) (xy 92.984923 -221.920023)
			(xy 92.99424 -221.865377) (xy 93.002862 -221.839028) (xy 93.010736 -221.81693) (xy 92.805758 -221.462092)
			(xy 92.782898 -221.457774) (xy 92.758103 -221.45255) (xy 92.710367 -221.435564) (xy 92.665792 -221.411474)
			(xy 92.625427 -221.380847) (xy 92.590224 -221.344405) (xy 92.561011 -221.303006) (xy 92.538476 -221.257625)
			(xy 92.52315 -221.20933) (xy 92.515394 -221.159258) (xy 92.514928 -221.133924) (xy 92.234004 -221.133924)
			(xy 92.233496 -221.159811) (xy 92.225397 -221.210949) (xy 92.209398 -221.260189) (xy 92.185892 -221.306321)
			(xy 92.15546 -221.348208) (xy 92.11885 -221.384818) (xy 92.076963 -221.41525) (xy 92.030831 -221.438756)
			(xy 91.981591 -221.454755) (xy 91.930453 -221.462854) (xy 91.878679 -221.462854) (xy 91.827541 -221.454755)
			(xy 91.778301 -221.438756) (xy 91.732169 -221.41525) (xy 91.690282 -221.384818) (xy 91.653672 -221.348208)
			(xy 91.62324 -221.306321) (xy 91.599734 -221.260189) (xy 91.583735 -221.210949) (xy 91.575636 -221.159811)
			(xy 91.575128 -221.133924) (xy 91.294204 -221.133924) (xy 91.29368 -221.161632) (xy 91.284481 -221.216279)
			(xy 91.275916 -221.242636) (xy 91.268042 -221.264734) (xy 91.47302 -221.619572) (xy 91.49588 -221.62389)
			(xy 91.520705 -221.629041) (xy 91.568483 -221.645999) (xy 91.613102 -221.670074) (xy 91.653507 -221.700696)
			(xy 91.688747 -221.737145) (xy 91.71799 -221.778561) (xy 91.740547 -221.823965) (xy 91.755885 -221.872289)
			(xy 91.763642 -221.92239) (xy 91.764104 -221.94774) (xy 91.763596 -221.973647) (xy 91.75549 -222.024824)
			(xy 91.739478 -222.074103) (xy 91.715955 -222.12027) (xy 91.685499 -222.162189) (xy 91.648861 -222.198827)
			(xy 91.606942 -222.229283) (xy 91.560775 -222.252806) (xy 91.511496 -222.268818) (xy 91.460319 -222.276924)
			(xy 91.408505 -222.276924) (xy 91.357328 -222.268818) (xy 91.308049 -222.252806) (xy 91.261882 -222.229283)
			(xy 91.219963 -222.198827) (xy 91.183325 -222.162189) (xy 91.152869 -222.12027) (xy 91.129346 -222.074103)
			(xy 91.113334 -222.024824) (xy 91.105228 -221.973647) (xy 91.10472 -221.94774) (xy 91.105323 -221.920023)
			(xy 91.11464 -221.865377) (xy 91.123262 -221.839028) (xy 91.131136 -221.81693) (xy 90.926158 -221.462092)
			(xy 90.903298 -221.457774) (xy 90.878503 -221.45255) (xy 90.830767 -221.435564) (xy 90.786192 -221.411474)
			(xy 90.745827 -221.380847) (xy 90.710624 -221.344405) (xy 90.681411 -221.303006) (xy 90.658876 -221.257625)
			(xy 90.64355 -221.20933) (xy 90.635794 -221.159258) (xy 90.635328 -221.133924) (xy 90.354404 -221.133924)
			(xy 90.353896 -221.159811) (xy 90.345797 -221.210949) (xy 90.329798 -221.260189) (xy 90.306292 -221.306321)
			(xy 90.27586 -221.348208) (xy 90.23925 -221.384818) (xy 90.197363 -221.41525) (xy 90.151231 -221.438756)
			(xy 90.101991 -221.454755) (xy 90.050853 -221.462854) (xy 89.999079 -221.462854) (xy 89.947941 -221.454755)
			(xy 89.898701 -221.438756) (xy 89.852569 -221.41525) (xy 89.810682 -221.384818) (xy 89.774072 -221.348208)
			(xy 89.74364 -221.306321) (xy 89.720134 -221.260189) (xy 89.704135 -221.210949) (xy 89.696036 -221.159811)
			(xy 89.695528 -221.133924) (xy 89.414604 -221.133924) (xy 89.41408 -221.161632) (xy 89.404881 -221.216279)
			(xy 89.396316 -221.242636) (xy 89.388442 -221.264734) (xy 89.59342 -221.619572) (xy 89.61628 -221.62389)
			(xy 89.641105 -221.629041) (xy 89.688883 -221.645999) (xy 89.733502 -221.670074) (xy 89.773907 -221.700696)
			(xy 89.809147 -221.737145) (xy 89.83839 -221.778561) (xy 89.860947 -221.823965) (xy 89.876285 -221.872289)
			(xy 89.884042 -221.92239) (xy 89.884504 -221.94774) (xy 89.883996 -221.973647) (xy 89.87589 -222.024824)
			(xy 89.859878 -222.074103) (xy 89.836355 -222.12027) (xy 89.805899 -222.162189) (xy 89.769261 -222.198827)
			(xy 89.727342 -222.229283) (xy 89.681175 -222.252806) (xy 89.631896 -222.268818) (xy 89.580719 -222.276924)
			(xy 89.528905 -222.276924) (xy 89.477728 -222.268818) (xy 89.428449 -222.252806) (xy 89.382282 -222.229283)
			(xy 89.340363 -222.198827) (xy 89.303725 -222.162189) (xy 89.273269 -222.12027) (xy 89.249746 -222.074103)
			(xy 89.233734 -222.024824) (xy 89.225628 -221.973647) (xy 89.22512 -221.94774) (xy 89.225723 -221.920023)
			(xy 89.23504 -221.865377) (xy 89.243662 -221.839028) (xy 89.251536 -221.81693) (xy 89.046558 -221.462092)
			(xy 89.023698 -221.457774) (xy 88.998903 -221.45255) (xy 88.951167 -221.435564) (xy 88.906592 -221.411474)
			(xy 88.866227 -221.380847) (xy 88.831024 -221.344405) (xy 88.801811 -221.303006) (xy 88.779276 -221.257625)
			(xy 88.76395 -221.20933) (xy 88.756194 -221.159258) (xy 88.755728 -221.133924) (xy 31.743142 -221.133924)
			(xy 31.743142 -224.389442) (xy 89.695528 -224.389442) (xy 89.695935 -224.364105) (xy 89.703697 -224.314028)
			(xy 89.719029 -224.265728) (xy 89.74157 -224.220343) (xy 89.770789 -224.17894) (xy 89.805999 -224.142496)
			(xy 89.84637 -224.111867) (xy 89.890952 -224.087776) (xy 89.938695 -224.070789) (xy 89.963498 -224.065592)
			(xy 89.986358 -224.061274) (xy 90.191082 -223.706182) (xy 90.183462 -223.684338) (xy 90.174817 -223.657995)
			(xy 90.165504 -223.603345) (xy 90.16492 -223.575626) (xy 90.165428 -223.549719) (xy 90.173534 -223.498542)
			(xy 90.189546 -223.449263) (xy 90.213069 -223.403096) (xy 90.243525 -223.361177) (xy 90.280163 -223.324539)
			(xy 90.322082 -223.294083) (xy 90.368249 -223.27056) (xy 90.417528 -223.254548) (xy 90.468705 -223.246442)
			(xy 90.520519 -223.246442) (xy 90.571696 -223.254548) (xy 90.620975 -223.27056) (xy 90.667142 -223.294083)
			(xy 90.709061 -223.324539) (xy 90.745699 -223.361177) (xy 90.776155 -223.403096) (xy 90.799678 -223.449263)
			(xy 90.81569 -223.498542) (xy 90.823796 -223.549719) (xy 90.824304 -223.575626) (xy 90.823803 -223.60097)
			(xy 90.816028 -223.651059) (xy 90.800679 -223.699368) (xy 90.77812 -223.74476) (xy 90.74888 -223.786165)
			(xy 90.713649 -223.822609) (xy 90.673257 -223.853232) (xy 90.628654 -223.877314) (xy 90.580892 -223.894288)
			(xy 90.55608 -223.899476) (xy 90.53322 -223.903794) (xy 90.328496 -224.258632) (xy 90.336116 -224.280476)
			(xy 90.344672 -224.306769) (xy 90.353865 -224.361289) (xy 90.354404 -224.388934) (xy 90.354404 -224.389442)
			(xy 90.635328 -224.389442) (xy 90.635836 -224.363555) (xy 90.643935 -224.312417) (xy 90.659934 -224.263177)
			(xy 90.68344 -224.217045) (xy 90.713872 -224.175158) (xy 90.750482 -224.138548) (xy 90.792369 -224.108116)
			(xy 90.838501 -224.08461) (xy 90.887741 -224.068611) (xy 90.938879 -224.060512) (xy 90.990653 -224.060512)
			(xy 91.041791 -224.068611) (xy 91.091031 -224.08461) (xy 91.137163 -224.108116) (xy 91.17905 -224.138548)
			(xy 91.21566 -224.175158) (xy 91.246092 -224.217045) (xy 91.269598 -224.263177) (xy 91.285597 -224.312417)
			(xy 91.293696 -224.363555) (xy 91.294204 -224.389442) (xy 91.575128 -224.389442) (xy 91.575535 -224.364105)
			(xy 91.583297 -224.314028) (xy 91.598629 -224.265728) (xy 91.62117 -224.220343) (xy 91.650389 -224.17894)
			(xy 91.685599 -224.142496) (xy 91.72597 -224.111867) (xy 91.770552 -224.087776) (xy 91.818295 -224.070789)
			(xy 91.843098 -224.065592) (xy 91.865958 -224.061274) (xy 92.070682 -223.706182) (xy 92.063062 -223.684338)
			(xy 92.054417 -223.657995) (xy 92.045104 -223.603345) (xy 92.04452 -223.575626) (xy 92.045028 -223.549719)
			(xy 92.053134 -223.498542) (xy 92.069146 -223.449263) (xy 92.092669 -223.403096) (xy 92.123125 -223.361177)
			(xy 92.159763 -223.324539) (xy 92.201682 -223.294083) (xy 92.247849 -223.27056) (xy 92.297128 -223.254548)
			(xy 92.348305 -223.246442) (xy 92.400119 -223.246442) (xy 92.451296 -223.254548) (xy 92.500575 -223.27056)
			(xy 92.546742 -223.294083) (xy 92.588661 -223.324539) (xy 92.625299 -223.361177) (xy 92.655755 -223.403096)
			(xy 92.679278 -223.449263) (xy 92.69529 -223.498542) (xy 92.703396 -223.549719) (xy 92.703904 -223.575626)
			(xy 92.703403 -223.60097) (xy 92.695628 -223.651059) (xy 92.680279 -223.699368) (xy 92.65772 -223.74476)
			(xy 92.62848 -223.786165) (xy 92.593249 -223.822609) (xy 92.552857 -223.853232) (xy 92.508254 -223.877314)
			(xy 92.460492 -223.894288) (xy 92.43568 -223.899476) (xy 92.41282 -223.903794) (xy 92.208096 -224.258632)
			(xy 92.215716 -224.280476) (xy 92.224272 -224.306769) (xy 92.233465 -224.361289) (xy 92.234004 -224.388934)
			(xy 92.234004 -224.389442) (xy 92.514928 -224.389442) (xy 92.515436 -224.363555) (xy 92.523535 -224.312417)
			(xy 92.539534 -224.263177) (xy 92.56304 -224.217045) (xy 92.593472 -224.175158) (xy 92.630082 -224.138548)
			(xy 92.671969 -224.108116) (xy 92.718101 -224.08461) (xy 92.767341 -224.068611) (xy 92.818479 -224.060512)
			(xy 92.870253 -224.060512) (xy 92.921391 -224.068611) (xy 92.970631 -224.08461) (xy 93.016763 -224.108116)
			(xy 93.05865 -224.138548) (xy 93.09526 -224.175158) (xy 93.125692 -224.217045) (xy 93.149198 -224.263177)
			(xy 93.165197 -224.312417) (xy 93.173296 -224.363555) (xy 93.173804 -224.389442) (xy 93.454728 -224.389442)
			(xy 93.455135 -224.364105) (xy 93.462897 -224.314028) (xy 93.478229 -224.265728) (xy 93.50077 -224.220343)
			(xy 93.529989 -224.17894) (xy 93.565199 -224.142496) (xy 93.60557 -224.111867) (xy 93.650152 -224.087776)
			(xy 93.697895 -224.070789) (xy 93.722698 -224.065592) (xy 93.745558 -224.061274) (xy 93.950282 -223.706436)
			(xy 93.942662 -223.684338) (xy 93.934031 -223.657991) (xy 93.92471 -223.603344) (xy 93.92412 -223.575626)
			(xy 93.924628 -223.549719) (xy 93.932734 -223.498542) (xy 93.948746 -223.449263) (xy 93.972269 -223.403096)
			(xy 94.002725 -223.361177) (xy 94.039363 -223.324539) (xy 94.081282 -223.294083) (xy 94.127449 -223.27056)
			(xy 94.176728 -223.254548) (xy 94.227905 -223.246442) (xy 94.279719 -223.246442) (xy 94.330896 -223.254548)
			(xy 94.380175 -223.27056) (xy 94.426342 -223.294083) (xy 94.468261 -223.324539) (xy 94.504899 -223.361177)
			(xy 94.535355 -223.403096) (xy 94.558878 -223.449263) (xy 94.57489 -223.498542) (xy 94.582996 -223.549719)
			(xy 94.583504 -223.575626) (xy 94.583087 -223.600992) (xy 94.575334 -223.651127) (xy 94.559985 -223.69948)
			(xy 94.537403 -223.744908) (xy 94.508122 -223.786336) (xy 94.472834 -223.822783) (xy 94.432375 -223.853388)
			(xy 94.387701 -223.877427) (xy 94.339869 -223.894332) (xy 94.315026 -223.899476) (xy 94.292166 -223.903794)
			(xy 94.087442 -224.258632) (xy 94.095316 -224.280476) (xy 94.10389 -224.306896) (xy 94.11309 -224.36167)
			(xy 94.113604 -224.389442) (xy 94.394528 -224.389442) (xy 94.395036 -224.363555) (xy 94.403135 -224.312417)
			(xy 94.419134 -224.263177) (xy 94.44264 -224.217045) (xy 94.473072 -224.175158) (xy 94.509682 -224.138548)
			(xy 94.551569 -224.108116) (xy 94.597701 -224.08461) (xy 94.646941 -224.068611) (xy 94.698079 -224.060512)
			(xy 94.749853 -224.060512) (xy 94.800991 -224.068611) (xy 94.850231 -224.08461) (xy 94.896363 -224.108116)
			(xy 94.93825 -224.138548) (xy 94.97486 -224.175158) (xy 95.005292 -224.217045) (xy 95.028798 -224.263177)
			(xy 95.044797 -224.312417) (xy 95.052896 -224.363555) (xy 95.053404 -224.389442) (xy 95.334328 -224.389442)
			(xy 95.334735 -224.364105) (xy 95.342497 -224.314028) (xy 95.357829 -224.265728) (xy 95.38037 -224.220343)
			(xy 95.409589 -224.17894) (xy 95.444799 -224.142496) (xy 95.48517 -224.111867) (xy 95.529752 -224.087776)
			(xy 95.577495 -224.070789) (xy 95.602298 -224.065592) (xy 95.625158 -224.061274) (xy 95.829882 -223.706436)
			(xy 95.822262 -223.684338) (xy 95.813631 -223.657991) (xy 95.80431 -223.603344) (xy 95.80372 -223.575626)
			(xy 95.804228 -223.549719) (xy 95.812334 -223.498542) (xy 95.828346 -223.449263) (xy 95.851869 -223.403096)
			(xy 95.882325 -223.361177) (xy 95.918963 -223.324539) (xy 95.960882 -223.294083) (xy 96.007049 -223.27056)
			(xy 96.056328 -223.254548) (xy 96.107505 -223.246442) (xy 96.159319 -223.246442) (xy 96.210496 -223.254548)
			(xy 96.259775 -223.27056) (xy 96.305942 -223.294083) (xy 96.347861 -223.324539) (xy 96.384499 -223.361177)
			(xy 96.414955 -223.403096) (xy 96.438478 -223.449263) (xy 96.45449 -223.498542) (xy 96.462596 -223.549719)
			(xy 96.463104 -223.575626) (xy 96.462687 -223.600992) (xy 96.454934 -223.651127) (xy 96.439585 -223.69948)
			(xy 96.417003 -223.744908) (xy 96.387722 -223.786336) (xy 96.352434 -223.822783) (xy 96.311975 -223.853388)
			(xy 96.267301 -223.877427) (xy 96.219469 -223.894332) (xy 96.194626 -223.899476) (xy 96.171766 -223.903794)
			(xy 95.967042 -224.258632) (xy 95.974916 -224.280476) (xy 95.98349 -224.306896) (xy 95.99269 -224.36167)
			(xy 95.993204 -224.389442) (xy 95.992696 -224.415329) (xy 95.984597 -224.466467) (xy 95.968598 -224.515707)
			(xy 95.945092 -224.561839) (xy 95.91466 -224.603726) (xy 95.87805 -224.640336) (xy 95.836163 -224.670768)
			(xy 95.790031 -224.694274) (xy 95.740791 -224.710273) (xy 95.689653 -224.718372) (xy 95.637879 -224.718372)
			(xy 95.586741 -224.710273) (xy 95.537501 -224.694274) (xy 95.491369 -224.670768) (xy 95.449482 -224.640336)
			(xy 95.412872 -224.603726) (xy 95.38244 -224.561839) (xy 95.358934 -224.515707) (xy 95.342935 -224.466467)
			(xy 95.334836 -224.415329) (xy 95.334328 -224.389442) (xy 95.053404 -224.389442) (xy 95.05286 -224.417149)
			(xy 95.043674 -224.471796) (xy 95.035116 -224.498154) (xy 95.027242 -224.520252) (xy 95.23222 -224.87509)
			(xy 95.25508 -224.879408) (xy 95.279909 -224.884542) (xy 95.327688 -224.901501) (xy 95.372308 -224.925578)
			(xy 95.412714 -224.956202) (xy 95.447954 -224.992654) (xy 95.477197 -225.034071) (xy 95.499752 -225.079478)
			(xy 95.515088 -225.127804) (xy 95.522843 -225.177908) (xy 95.523304 -225.203258) (xy 95.522796 -225.229165)
			(xy 95.51469 -225.280342) (xy 95.498678 -225.329621) (xy 95.475155 -225.375788) (xy 95.444699 -225.417707)
			(xy 95.408061 -225.454345) (xy 95.366142 -225.484801) (xy 95.319975 -225.508324) (xy 95.270696 -225.524336)
			(xy 95.219519 -225.532442) (xy 95.167705 -225.532442) (xy 95.116528 -225.524336) (xy 95.067249 -225.508324)
			(xy 95.021082 -225.484801) (xy 94.979163 -225.454345) (xy 94.942525 -225.417707) (xy 94.912069 -225.375788)
			(xy 94.888546 -225.329621) (xy 94.872534 -225.280342) (xy 94.864428 -225.229165) (xy 94.86392 -225.203258)
			(xy 94.864527 -225.175541) (xy 94.873842 -225.120895) (xy 94.882462 -225.094546) (xy 94.890336 -225.072448)
			(xy 94.685358 -224.71761) (xy 94.662498 -224.713292) (xy 94.637685 -224.708145) (xy 94.589943 -224.691153)
			(xy 94.545363 -224.667056) (xy 94.504996 -224.63642) (xy 94.469793 -224.599968) (xy 94.440582 -224.558558)
			(xy 94.418052 -224.513166) (xy 94.402734 -224.46486) (xy 94.394988 -224.41478) (xy 94.394528 -224.389442)
			(xy 94.113604 -224.389442) (xy 94.113096 -224.415329) (xy 94.104997 -224.466467) (xy 94.088998 -224.515707)
			(xy 94.065492 -224.561839) (xy 94.03506 -224.603726) (xy 93.99845 -224.640336) (xy 93.956563 -224.670768)
			(xy 93.910431 -224.694274) (xy 93.861191 -224.710273) (xy 93.810053 -224.718372) (xy 93.758279 -224.718372)
			(xy 93.707141 -224.710273) (xy 93.657901 -224.694274) (xy 93.611769 -224.670768) (xy 93.569882 -224.640336)
			(xy 93.533272 -224.603726) (xy 93.50284 -224.561839) (xy 93.479334 -224.515707) (xy 93.463335 -224.466467)
			(xy 93.455236 -224.415329) (xy 93.454728 -224.389442) (xy 93.173804 -224.389442) (xy 93.173804 -224.38995)
			(xy 93.173247 -224.417593) (xy 93.164056 -224.472111) (xy 93.155516 -224.498408) (xy 93.147896 -224.520252)
			(xy 93.35262 -224.87509) (xy 93.37548 -224.879408) (xy 93.400309 -224.884542) (xy 93.448088 -224.901501)
			(xy 93.492708 -224.925578) (xy 93.533114 -224.956202) (xy 93.568354 -224.992654) (xy 93.597597 -225.034071)
			(xy 93.620152 -225.079478) (xy 93.635488 -225.127804) (xy 93.643243 -225.177908) (xy 93.643704 -225.203258)
			(xy 93.643196 -225.229165) (xy 93.63509 -225.280342) (xy 93.619078 -225.329621) (xy 93.595555 -225.375788)
			(xy 93.565099 -225.417707) (xy 93.528461 -225.454345) (xy 93.486542 -225.484801) (xy 93.440375 -225.508324)
			(xy 93.391096 -225.524336) (xy 93.339919 -225.532442) (xy 93.288105 -225.532442) (xy 93.236928 -225.524336)
			(xy 93.187649 -225.508324) (xy 93.141482 -225.484801) (xy 93.099563 -225.454345) (xy 93.062925 -225.417707)
			(xy 93.032469 -225.375788) (xy 93.008946 -225.329621) (xy 92.992934 -225.280342) (xy 92.984828 -225.229165)
			(xy 92.98432 -225.203258) (xy 92.98432 -225.20275) (xy 92.98493 -225.175096) (xy 92.994253 -225.120579)
			(xy 93.002862 -225.094292) (xy 93.010482 -225.072448) (xy 92.805758 -224.71761) (xy 92.782898 -224.713292)
			(xy 92.758085 -224.708145) (xy 92.710343 -224.691153) (xy 92.665763 -224.667056) (xy 92.625396 -224.63642)
			(xy 92.590193 -224.599968) (xy 92.560982 -224.558558) (xy 92.538452 -224.513166) (xy 92.523134 -224.46486)
			(xy 92.515388 -224.41478) (xy 92.514928 -224.389442) (xy 92.234004 -224.389442) (xy 92.233496 -224.415329)
			(xy 92.225397 -224.466467) (xy 92.209398 -224.515707) (xy 92.185892 -224.561839) (xy 92.15546 -224.603726)
			(xy 92.11885 -224.640336) (xy 92.076963 -224.670768) (xy 92.030831 -224.694274) (xy 91.981591 -224.710273)
			(xy 91.930453 -224.718372) (xy 91.878679 -224.718372) (xy 91.827541 -224.710273) (xy 91.778301 -224.694274)
			(xy 91.732169 -224.670768) (xy 91.690282 -224.640336) (xy 91.653672 -224.603726) (xy 91.62324 -224.561839)
			(xy 91.599734 -224.515707) (xy 91.583735 -224.466467) (xy 91.575636 -224.415329) (xy 91.575128 -224.389442)
			(xy 91.294204 -224.389442) (xy 91.294204 -224.38995) (xy 91.293647 -224.417593) (xy 91.284456 -224.472111)
			(xy 91.275916 -224.498408) (xy 91.268296 -224.520252) (xy 91.47302 -224.87509) (xy 91.49588 -224.879408)
			(xy 91.520709 -224.884542) (xy 91.568488 -224.901501) (xy 91.613108 -224.925578) (xy 91.653514 -224.956202)
			(xy 91.688754 -224.992654) (xy 91.717997 -225.034071) (xy 91.740552 -225.079478) (xy 91.755888 -225.127804)
			(xy 91.763643 -225.177908) (xy 91.764104 -225.203258) (xy 91.763596 -225.229165) (xy 91.75549 -225.280342)
			(xy 91.739478 -225.329621) (xy 91.715955 -225.375788) (xy 91.685499 -225.417707) (xy 91.648861 -225.454345)
			(xy 91.606942 -225.484801) (xy 91.560775 -225.508324) (xy 91.511496 -225.524336) (xy 91.460319 -225.532442)
			(xy 91.408505 -225.532442) (xy 91.357328 -225.524336) (xy 91.308049 -225.508324) (xy 91.261882 -225.484801)
			(xy 91.219963 -225.454345) (xy 91.183325 -225.417707) (xy 91.152869 -225.375788) (xy 91.129346 -225.329621)
			(xy 91.113334 -225.280342) (xy 91.105228 -225.229165) (xy 91.10472 -225.203258) (xy 91.10472 -225.20275)
			(xy 91.10533 -225.175096) (xy 91.114653 -225.120579) (xy 91.123262 -225.094292) (xy 91.130882 -225.072448)
			(xy 90.926158 -224.71761) (xy 90.903298 -224.713292) (xy 90.878485 -224.708145) (xy 90.830743 -224.691153)
			(xy 90.786163 -224.667056) (xy 90.745796 -224.63642) (xy 90.710593 -224.599968) (xy 90.681382 -224.558558)
			(xy 90.658852 -224.513166) (xy 90.643534 -224.46486) (xy 90.635788 -224.41478) (xy 90.635328 -224.389442)
			(xy 90.354404 -224.389442) (xy 90.353896 -224.415329) (xy 90.345797 -224.466467) (xy 90.329798 -224.515707)
			(xy 90.306292 -224.561839) (xy 90.27586 -224.603726) (xy 90.23925 -224.640336) (xy 90.197363 -224.670768)
			(xy 90.151231 -224.694274) (xy 90.101991 -224.710273) (xy 90.050853 -224.718372) (xy 89.999079 -224.718372)
			(xy 89.947941 -224.710273) (xy 89.898701 -224.694274) (xy 89.852569 -224.670768) (xy 89.810682 -224.640336)
			(xy 89.774072 -224.603726) (xy 89.74364 -224.561839) (xy 89.720134 -224.515707) (xy 89.704135 -224.466467)
			(xy 89.696036 -224.415329) (xy 89.695528 -224.389442) (xy 31.743142 -224.389442) (xy 31.743142 -251.76988)
			(xy 75.695566 -251.76988) (xy 75.699547 -251.63686) (xy 75.711476 -251.504315) (xy 75.731311 -251.372722)
			(xy 75.75898 -251.24255) (xy 75.794384 -251.114265) (xy 75.837397 -250.988328) (xy 75.887864 -250.865189)
			(xy 75.945605 -250.745288) (xy 76.010414 -250.629055) (xy 76.082058 -250.516905) (xy 76.16028 -250.409241)
			(xy 76.244801 -250.306448) (xy 76.335319 -250.208893) (xy 76.431508 -250.116927) (xy 76.533026 -250.030877)
			(xy 76.639507 -249.951053) (xy 76.750572 -249.87774) (xy 76.865823 -249.8112) (xy 76.984847 -249.751671)
			(xy 77.107218 -249.699367) (xy 77.232497 -249.654475) (xy 77.360238 -249.617156) (xy 77.489981 -249.587543)
			(xy 77.621263 -249.565742) (xy 77.753614 -249.551832) (xy 77.88656 -249.545861) (xy 78.019625 -249.547852)
			(xy 78.152333 -249.557797) (xy 78.284209 -249.575661) (xy 78.41478 -249.601379) (xy 78.54358 -249.63486)
			(xy 78.670146 -249.675984) (xy 78.794027 -249.724604) (xy 78.914778 -249.780545) (xy 79.031968 -249.843607)
			(xy 79.145177 -249.913565) (xy 79.253999 -249.990169) (xy 79.358045 -250.073143) (xy 79.456943 -250.162191)
			(xy 79.550338 -250.256994) (xy 79.637896 -250.357212) (xy 79.719305 -250.462488) (xy 79.794271 -250.572444)
			(xy 79.862528 -250.686686) (xy 79.92383 -250.804806) (xy 79.977959 -250.926381) (xy 80.02472 -251.050975)
			(xy 80.063946 -251.178143) (xy 80.095496 -251.307429) (xy 80.119259 -251.43837) (xy 80.135148 -251.570498)
			(xy 80.143106 -251.70334) (xy 80.143604 -251.76988) (xy 80.143106 -251.83642) (xy 80.135148 -251.969262)
			(xy 80.119259 -252.10139) (xy 80.095496 -252.232331) (xy 80.063946 -252.361617) (xy 80.02472 -252.488785)
			(xy 79.977959 -252.613379) (xy 79.92383 -252.734954) (xy 79.862528 -252.853074) (xy 79.794271 -252.967316)
			(xy 79.719305 -253.077272) (xy 79.637896 -253.182548) (xy 79.550338 -253.282766) (xy 79.456943 -253.377569)
			(xy 79.358045 -253.466617) (xy 79.253999 -253.549591) (xy 79.145177 -253.626195) (xy 79.031968 -253.696153)
			(xy 78.914778 -253.759215) (xy 78.794027 -253.815156) (xy 78.670146 -253.863776) (xy 78.54358 -253.9049)
			(xy 78.41478 -253.938381) (xy 78.284209 -253.964099) (xy 78.152333 -253.981963) (xy 78.019625 -253.991908)
			(xy 77.88656 -253.993899) (xy 77.753614 -253.987928) (xy 77.621263 -253.974018) (xy 77.489981 -253.952217)
			(xy 77.360238 -253.922604) (xy 77.232497 -253.885285) (xy 77.107218 -253.840393) (xy 76.984847 -253.788089)
			(xy 76.865823 -253.72856) (xy 76.750572 -253.66202) (xy 76.639507 -253.588707) (xy 76.533026 -253.508883)
			(xy 76.431508 -253.422833) (xy 76.335319 -253.330867) (xy 76.244801 -253.233312) (xy 76.16028 -253.130519)
			(xy 76.082058 -253.022855) (xy 76.010414 -252.910705) (xy 75.945605 -252.794472) (xy 75.887864 -252.674571)
			(xy 75.837397 -252.551432) (xy 75.794384 -252.425495) (xy 75.75898 -252.29721) (xy 75.731311 -252.167038)
			(xy 75.711476 -252.035445) (xy 75.699547 -251.9029) (xy 75.695566 -251.76988) (xy 31.743142 -251.76988)
			(xy 31.743142 -274.266914) (xy 103.432356 -274.266914) (xy 103.432864 -274.241027) (xy 103.440963 -274.189889)
			(xy 103.456962 -274.140649) (xy 103.480468 -274.094517) (xy 103.5109 -274.05263) (xy 103.54751 -274.01602)
			(xy 103.589397 -273.985588) (xy 103.635529 -273.962082) (xy 103.684769 -273.946083) (xy 103.735907 -273.937984)
			(xy 103.787681 -273.937984) (xy 103.838819 -273.946083) (xy 103.888059 -273.962082) (xy 103.934191 -273.985588)
			(xy 103.976078 -274.01602) (xy 104.012688 -274.05263) (xy 104.04312 -274.094517) (xy 104.066626 -274.140649)
			(xy 104.082625 -274.189889) (xy 104.090724 -274.241027) (xy 104.091232 -274.266914) (xy 104.090675 -274.294558)
			(xy 104.081487 -274.349076) (xy 104.072944 -274.375372) (xy 104.065324 -274.397216) (xy 104.270556 -274.752562)
			(xy 104.293416 -274.75688) (xy 104.318228 -274.762086) (xy 104.366006 -274.779035) (xy 104.410625 -274.803101)
			(xy 104.451032 -274.833715) (xy 104.486274 -274.870157) (xy 104.515519 -274.911566) (xy 104.538078 -274.956966)
			(xy 104.553418 -275.005285) (xy 104.561177 -275.055382) (xy 104.56164 -275.08073) (xy 104.561132 -275.106637)
			(xy 104.553026 -275.157814) (xy 104.537014 -275.207093) (xy 104.513491 -275.25326) (xy 104.483035 -275.295179)
			(xy 104.446397 -275.331817) (xy 104.404478 -275.362273) (xy 104.358311 -275.385796) (xy 104.309032 -275.401808)
			(xy 104.257855 -275.409914) (xy 104.206041 -275.409914) (xy 104.154864 -275.401808) (xy 104.105585 -275.385796)
			(xy 104.059418 -275.362273) (xy 104.017499 -275.331817) (xy 103.980861 -275.295179) (xy 103.950405 -275.25326)
			(xy 103.926882 -275.207093) (xy 103.91087 -275.157814) (xy 103.902764 -275.106637) (xy 103.902256 -275.08073)
			(xy 103.902854 -275.053013) (xy 103.912174 -274.998366) (xy 103.920798 -274.972018) (xy 103.928672 -274.94992)
			(xy 103.723694 -274.595082) (xy 103.700834 -274.590764) (xy 103.676011 -274.585559) (xy 103.628206 -274.568629)
			(xy 103.583558 -274.544577) (xy 103.543121 -274.51397) (xy 103.507847 -274.477532) (xy 103.478571 -274.436121)
			(xy 103.455983 -274.390715) (xy 103.440615 -274.342385) (xy 103.43283 -274.292271) (xy 103.432356 -274.266914)
			(xy 31.743142 -274.266914) (xy 31.743142 -275.10659) (xy 102.023373 -275.10659) (xy 102.023373 -275.05481)
			(xy 102.031474 -275.003669) (xy 102.047476 -274.954425) (xy 102.070985 -274.90829) (xy 102.101423 -274.866402)
			(xy 102.138039 -274.829791) (xy 102.179931 -274.79936) (xy 102.226069 -274.775858) (xy 102.275316 -274.759863)
			(xy 102.326458 -274.75177) (xy 102.352348 -274.751292) (xy 102.377861 -274.751741) (xy 102.428277 -274.759608)
			(xy 102.476879 -274.775148) (xy 102.522507 -274.79799) (xy 102.564072 -274.827588) (xy 102.600581 -274.863235)
			(xy 102.616254 -274.883372) (xy 103.028242 -274.883372) (xy 103.043883 -274.86321) (xy 103.0804 -274.827569)
			(xy 103.121973 -274.797979) (xy 103.167607 -274.775148) (xy 103.216215 -274.75962) (xy 103.266634 -274.751765)
			(xy 103.292148 -274.751292) (xy 103.318035 -274.751743) (xy 103.369171 -274.759849) (xy 103.41841 -274.775854)
			(xy 103.464539 -274.799364) (xy 103.506423 -274.8298) (xy 103.543031 -274.866413) (xy 103.573461 -274.908302)
			(xy 103.596964 -274.954434) (xy 103.612962 -275.003675) (xy 103.62106 -275.054813) (xy 103.62106 -275.106587)
			(xy 103.612962 -275.157725) (xy 103.596964 -275.206966) (xy 103.573461 -275.253098) (xy 103.543031 -275.294987)
			(xy 103.506423 -275.3316) (xy 103.464539 -275.362036) (xy 103.41841 -275.385546) (xy 103.369171 -275.401551)
			(xy 103.318035 -275.409657) (xy 103.292148 -275.410168) (xy 103.266637 -275.409665) (xy 103.216223 -275.401811)
			(xy 103.167621 -275.386283) (xy 103.121992 -275.363452) (xy 103.080426 -275.333862) (xy 103.043916 -275.298222)
			(xy 103.028242 -275.278088) (xy 102.616254 -275.278088) (xy 102.600546 -275.298195) (xy 102.564044 -275.333841)
			(xy 102.522486 -275.363438) (xy 102.476864 -275.386279) (xy 102.428268 -275.401819) (xy 102.377858 -275.409687)
			(xy 102.352348 -275.410168) (xy 102.326458 -275.40963) (xy 102.275316 -275.401537) (xy 102.226069 -275.385542)
			(xy 102.179931 -275.36204) (xy 102.138039 -275.331609) (xy 102.101423 -275.294998) (xy 102.070985 -275.25311)
			(xy 102.047476 -275.206975) (xy 102.031474 -275.157731) (xy 102.023373 -275.10659) (xy 31.743142 -275.10659)
			(xy 31.743142 -276.708616) (xy 102.022656 -276.708616) (xy 102.023189 -276.683284) (xy 102.030938 -276.633215)
			(xy 102.046256 -276.584922) (xy 102.068781 -276.53954) (xy 102.097985 -276.498139) (xy 102.133179 -276.461694)
			(xy 102.173534 -276.431062) (xy 102.218101 -276.406964) (xy 102.265829 -276.389968) (xy 102.290626 -276.384766)
			(xy 102.313486 -276.380448) (xy 102.518464 -276.025356) (xy 102.510844 -276.003512) (xy 102.502285 -275.977153)
			(xy 102.493085 -275.922508) (xy 102.492556 -275.8948) (xy 102.493064 -275.868913) (xy 102.501163 -275.817775)
			(xy 102.517162 -275.768535) (xy 102.540668 -275.722403) (xy 102.5711 -275.680516) (xy 102.60771 -275.643906)
			(xy 102.649597 -275.613474) (xy 102.695729 -275.589968) (xy 102.744969 -275.573969) (xy 102.796107 -275.56587)
			(xy 102.847881 -275.56587) (xy 102.899019 -275.573969) (xy 102.948259 -275.589968) (xy 102.994391 -275.613474)
			(xy 103.036278 -275.643906) (xy 103.072888 -275.680516) (xy 103.10332 -275.722403) (xy 103.126826 -275.768535)
			(xy 103.142825 -275.817775) (xy 103.150924 -275.868913) (xy 103.151432 -275.8948) (xy 104.372156 -275.8948)
			(xy 104.372675 -275.869467) (xy 104.380426 -275.819398) (xy 104.395746 -275.771105) (xy 104.418273 -275.725723)
			(xy 104.447479 -275.684322) (xy 104.482674 -275.647877) (xy 104.523031 -275.617245) (xy 104.567599 -275.593147)
			(xy 104.615329 -275.576152) (xy 104.640126 -275.57095) (xy 104.662986 -275.566632) (xy 104.868218 -275.211286)
			(xy 104.860598 -275.189188) (xy 104.851972 -275.162906) (xy 104.842659 -275.108385) (xy 104.842056 -275.08073)
			(xy 104.842564 -275.054823) (xy 104.85067 -275.003646) (xy 104.866682 -274.954367) (xy 104.890205 -274.9082)
			(xy 104.920661 -274.866281) (xy 104.957299 -274.829643) (xy 104.999218 -274.799187) (xy 105.045385 -274.775664)
			(xy 105.094664 -274.759652) (xy 105.145841 -274.751546) (xy 105.197655 -274.751546) (xy 105.248832 -274.759652)
			(xy 105.298111 -274.775664) (xy 105.344278 -274.799187) (xy 105.386197 -274.829643) (xy 105.422835 -274.866281)
			(xy 105.453291 -274.9082) (xy 105.476814 -274.954367) (xy 105.492826 -275.003646) (xy 105.500932 -275.054823)
			(xy 105.50144 -275.08073) (xy 105.500998 -275.106094) (xy 105.493245 -275.156227) (xy 105.477898 -275.204578)
			(xy 105.455318 -275.250004) (xy 105.42604 -275.291431) (xy 105.390756 -275.327878) (xy 105.350301 -275.358484)
			(xy 105.305631 -275.382526) (xy 105.257803 -275.399433) (xy 105.232962 -275.40458) (xy 105.209848 -275.408898)
			(xy 105.00487 -275.76399) (xy 105.012744 -275.786088) (xy 105.021303 -275.812447) (xy 105.030503 -275.867092)
			(xy 105.031032 -275.8948) (xy 105.030524 -275.920687) (xy 105.022425 -275.971825) (xy 105.006426 -276.021065)
			(xy 104.98292 -276.067197) (xy 104.952488 -276.109084) (xy 104.915878 -276.145694) (xy 104.873991 -276.176126)
			(xy 104.827859 -276.199632) (xy 104.778619 -276.215631) (xy 104.727481 -276.22373) (xy 104.675707 -276.22373)
			(xy 104.624569 -276.215631) (xy 104.575329 -276.199632) (xy 104.529197 -276.176126) (xy 104.48731 -276.145694)
			(xy 104.4507 -276.109084) (xy 104.420268 -276.067197) (xy 104.396762 -276.021065) (xy 104.380763 -275.971825)
			(xy 104.372664 -275.920687) (xy 104.372156 -275.8948) (xy 103.151432 -275.8948) (xy 103.150966 -275.920146)
			(xy 103.143192 -275.97024) (xy 103.127843 -276.018553) (xy 103.105281 -276.063948) (xy 103.076038 -276.105356)
			(xy 103.040801 -276.1418) (xy 103.000402 -276.172421) (xy 102.955792 -276.196499) (xy 102.908023 -276.213466)
			(xy 102.883208 -276.21865) (xy 102.860348 -276.222968) (xy 102.65537 -276.577806) (xy 102.663244 -276.599904)
			(xy 102.671807 -276.626262) (xy 102.681004 -276.680908) (xy 102.681532 -276.708616) (xy 102.962456 -276.708616)
			(xy 102.962964 -276.682709) (xy 102.97107 -276.631532) (xy 102.987082 -276.582253) (xy 103.010605 -276.536086)
			(xy 103.041061 -276.494167) (xy 103.077699 -276.457529) (xy 103.119618 -276.427073) (xy 103.165785 -276.40355)
			(xy 103.215064 -276.387538) (xy 103.266241 -276.379432) (xy 103.318055 -276.379432) (xy 103.369232 -276.387538)
			(xy 103.418511 -276.40355) (xy 103.464678 -276.427073) (xy 103.506597 -276.457529) (xy 103.543235 -276.494167)
			(xy 103.573691 -276.536086) (xy 103.597214 -276.582253) (xy 103.613226 -276.631532) (xy 103.621332 -276.682709)
			(xy 103.62184 -276.708616) (xy 103.621308 -276.734511) (xy 103.902706 -276.734511) (xy 103.902706 -276.682689)
			(xy 103.910813 -276.631506) (xy 103.926828 -276.582222) (xy 103.950356 -276.53605) (xy 103.980818 -276.494128)
			(xy 104.017464 -276.457487) (xy 104.059391 -276.427031) (xy 104.105566 -276.40351) (xy 104.154853 -276.387502)
			(xy 104.206037 -276.379402) (xy 104.231948 -276.378924) (xy 104.257462 -276.37936) (xy 104.307879 -276.387228)
			(xy 104.356482 -276.40277) (xy 104.40211 -276.425614) (xy 104.443674 -276.455215) (xy 104.480182 -276.490865)
			(xy 104.495854 -276.511004) (xy 104.907842 -276.511004) (xy 104.923492 -276.490849) (xy 104.960006 -276.455206)
			(xy 105.001577 -276.425615) (xy 105.04721 -276.402782) (xy 105.095816 -276.387253) (xy 105.146235 -276.379398)
			(xy 105.171748 -276.378924) (xy 105.197654 -276.379404) (xy 105.248828 -276.387515) (xy 105.298102 -276.403532)
			(xy 105.344265 -276.427059) (xy 105.38618 -276.457517) (xy 105.422814 -276.494157) (xy 105.453266 -276.536076)
			(xy 105.476786 -276.582242) (xy 105.492796 -276.631519) (xy 105.5009 -276.682694) (xy 105.5009 -276.734506)
			(xy 105.492796 -276.785681) (xy 105.476786 -276.834958) (xy 105.453266 -276.881124) (xy 105.422814 -276.923043)
			(xy 105.38618 -276.959683) (xy 105.344265 -276.990141) (xy 105.298102 -277.013668) (xy 105.248828 -277.029685)
			(xy 105.197654 -277.037796) (xy 105.171748 -277.038308) (xy 105.146238 -277.037789) (xy 105.095825 -277.029936)
			(xy 105.047224 -277.01441) (xy 105.001596 -276.991582) (xy 104.960029 -276.961996) (xy 104.923517 -276.92636)
			(xy 104.907842 -276.906228) (xy 104.495854 -276.906228) (xy 104.480157 -276.926344) (xy 104.443651 -276.961988)
			(xy 104.40209 -276.991583) (xy 104.356467 -277.014422) (xy 104.307869 -277.029961) (xy 104.257458 -277.037827)
			(xy 104.231948 -277.038308) (xy 104.206037 -277.037798) (xy 104.154853 -277.029698) (xy 104.105566 -277.01369)
			(xy 104.059391 -276.990169) (xy 104.017464 -276.959713) (xy 103.980818 -276.923072) (xy 103.950356 -276.88115)
			(xy 103.926828 -276.834978) (xy 103.910813 -276.785694) (xy 103.902706 -276.734511) (xy 103.621308 -276.734511)
			(xy 103.621269 -276.736398) (xy 103.611945 -276.791174) (xy 103.603298 -276.817582) (xy 103.595424 -276.839426)
			(xy 103.800402 -277.194264) (xy 103.823262 -277.198582) (xy 103.848063 -277.203782) (xy 103.895803 -277.220766)
			(xy 103.940382 -277.244857) (xy 103.98075 -277.275485) (xy 104.015954 -277.311931) (xy 104.045167 -277.353334)
			(xy 104.067699 -277.398721) (xy 104.083021 -277.44702) (xy 104.09077 -277.497096) (xy 104.091232 -277.522432)
			(xy 106.251756 -277.522432) (xy 106.252213 -277.497097) (xy 106.259974 -277.447026) (xy 106.275303 -277.39873)
			(xy 106.297839 -277.353349) (xy 106.327053 -277.311948) (xy 106.362255 -277.275504) (xy 106.402618 -277.244873)
			(xy 106.447192 -277.220777) (xy 106.494926 -277.203783) (xy 106.519726 -277.198582) (xy 106.542586 -277.194264)
			(xy 106.747818 -276.838918) (xy 106.740198 -276.817074) (xy 106.731593 -276.790786) (xy 106.722266 -276.736269)
			(xy 106.721656 -276.708616) (xy 106.722164 -276.682709) (xy 106.73027 -276.631532) (xy 106.746282 -276.582253)
			(xy 106.769805 -276.536086) (xy 106.800261 -276.494167) (xy 106.836899 -276.457529) (xy 106.878818 -276.427073)
			(xy 106.924985 -276.40355) (xy 106.974264 -276.387538) (xy 107.025441 -276.379432) (xy 107.077255 -276.379432)
			(xy 107.128432 -276.387538) (xy 107.177711 -276.40355) (xy 107.223878 -276.427073) (xy 107.265797 -276.457529)
			(xy 107.302435 -276.494167) (xy 107.332891 -276.536086) (xy 107.356414 -276.582253) (xy 107.372426 -276.631532)
			(xy 107.380532 -276.682709) (xy 107.38104 -276.708616) (xy 107.380628 -276.733993) (xy 107.372856 -276.784149)
			(xy 107.357482 -276.832518) (xy 107.334871 -276.877958) (xy 107.305557 -276.91939) (xy 107.270234 -276.955836)
			(xy 107.229739 -276.986433) (xy 107.18503 -277.010456) (xy 107.137166 -277.027337) (xy 107.112308 -277.032466)
			(xy 107.089448 -277.036784) (xy 106.88447 -277.391622) (xy 106.892344 -277.41372) (xy 106.90091 -277.440076)
			(xy 106.910105 -277.494723) (xy 106.910632 -277.522432) (xy 106.910124 -277.548319) (xy 106.902025 -277.599457)
			(xy 106.886026 -277.648697) (xy 106.86252 -277.694829) (xy 106.832088 -277.736716) (xy 106.795478 -277.773326)
			(xy 106.753591 -277.803758) (xy 106.707459 -277.827264) (xy 106.658219 -277.843263) (xy 106.607081 -277.851362)
			(xy 106.555307 -277.851362) (xy 106.504169 -277.843263) (xy 106.454929 -277.827264) (xy 106.408797 -277.803758)
			(xy 106.36691 -277.773326) (xy 106.3303 -277.736716) (xy 106.299868 -277.694829) (xy 106.276362 -277.648697)
			(xy 106.260363 -277.599457) (xy 106.252264 -277.548319) (xy 106.251756 -277.522432) (xy 104.091232 -277.522432)
			(xy 104.090724 -277.548319) (xy 104.082625 -277.599457) (xy 104.066626 -277.648697) (xy 104.04312 -277.694829)
			(xy 104.012688 -277.736716) (xy 103.976078 -277.773326) (xy 103.934191 -277.803758) (xy 103.888059 -277.827264)
			(xy 103.838819 -277.843263) (xy 103.787681 -277.851362) (xy 103.735907 -277.851362) (xy 103.684769 -277.843263)
			(xy 103.635529 -277.827264) (xy 103.589397 -277.803758) (xy 103.54751 -277.773326) (xy 103.5109 -277.736716)
			(xy 103.480468 -277.694829) (xy 103.456962 -277.648697) (xy 103.440963 -277.599457) (xy 103.432864 -277.548319)
			(xy 103.432356 -277.522432) (xy 103.432895 -277.494724) (xy 103.442084 -277.440078) (xy 103.450644 -277.41372)
			(xy 103.458518 -277.391622) (xy 103.25354 -277.036784) (xy 103.23068 -277.032466) (xy 103.205855 -277.027313)
			(xy 103.158073 -277.01036) (xy 103.113452 -276.986289) (xy 103.073043 -276.955668) (xy 103.037801 -276.919219)
			(xy 103.008557 -276.877803) (xy 102.986002 -276.832396) (xy 102.970667 -276.78407) (xy 102.962915 -276.733966)
			(xy 102.962456 -276.708616) (xy 102.681532 -276.708616) (xy 102.681024 -276.734503) (xy 102.672925 -276.785641)
			(xy 102.656926 -276.834881) (xy 102.63342 -276.881013) (xy 102.602988 -276.9229) (xy 102.566378 -276.95951)
			(xy 102.524491 -276.989942) (xy 102.478359 -277.013448) (xy 102.429119 -277.029447) (xy 102.377981 -277.037546)
			(xy 102.326207 -277.037546) (xy 102.275069 -277.029447) (xy 102.225829 -277.013448) (xy 102.179697 -276.989942)
			(xy 102.13781 -276.95951) (xy 102.1012 -276.9229) (xy 102.070768 -276.881013) (xy 102.047262 -276.834881)
			(xy 102.031263 -276.785641) (xy 102.023164 -276.734503) (xy 102.022656 -276.708616) (xy 31.743142 -276.708616)
			(xy 31.743142 -279.150318) (xy 101.552756 -279.150318) (xy 101.553264 -279.124431) (xy 101.561363 -279.073293)
			(xy 101.577362 -279.024053) (xy 101.600868 -278.977921) (xy 101.6313 -278.936034) (xy 101.66791 -278.899424)
			(xy 101.709797 -278.868992) (xy 101.755929 -278.845486) (xy 101.805169 -278.829487) (xy 101.856307 -278.821388)
			(xy 101.908081 -278.821388) (xy 101.959219 -278.829487) (xy 102.008459 -278.845486) (xy 102.054591 -278.868992)
			(xy 102.096478 -278.899424) (xy 102.133088 -278.936034) (xy 102.16352 -278.977921) (xy 102.187026 -279.024053)
			(xy 102.203025 -279.073293) (xy 102.211124 -279.124431) (xy 102.211632 -279.150318) (xy 102.211112 -279.176186)
			(xy 102.493088 -279.176186) (xy 102.493088 -279.124414) (xy 102.501186 -279.07328) (xy 102.517184 -279.024043)
			(xy 102.540688 -278.977914) (xy 102.571118 -278.93603) (xy 102.607725 -278.899422) (xy 102.649609 -278.868991)
			(xy 102.695737 -278.845487) (xy 102.744975 -278.829488) (xy 102.796108 -278.821388) (xy 102.821994 -278.82088)
			(xy 102.847505 -278.821372) (xy 102.897919 -278.829232) (xy 102.94652 -278.844763) (xy 102.992148 -278.867597)
			(xy 103.033714 -278.897186) (xy 103.070226 -278.932826) (xy 103.0859 -278.95296) (xy 103.497888 -278.95296)
			(xy 103.513557 -278.932822) (xy 103.550069 -278.89718) (xy 103.591636 -278.867588) (xy 103.637265 -278.844752)
			(xy 103.685867 -278.829219) (xy 103.736282 -278.821357) (xy 103.761794 -278.82088) (xy 103.787685 -278.821325)
			(xy 103.83883 -278.829425) (xy 103.888078 -278.845425) (xy 103.934217 -278.868934) (xy 103.97611 -278.89937)
			(xy 104.012726 -278.935985) (xy 104.043163 -278.977878) (xy 104.066672 -279.024016) (xy 104.082674 -279.073264)
			(xy 104.090775 -279.124409) (xy 104.090775 -279.176191) (xy 104.082674 -279.227336) (xy 104.066672 -279.276584)
			(xy 104.043163 -279.322722) (xy 104.012726 -279.364615) (xy 103.97611 -279.40123) (xy 103.934217 -279.431666)
			(xy 103.888078 -279.455175) (xy 103.83883 -279.471175) (xy 103.787685 -279.479275) (xy 103.761794 -279.479756)
			(xy 103.736281 -279.479297) (xy 103.685865 -279.471435) (xy 103.637262 -279.455898) (xy 103.591633 -279.433058)
			(xy 103.550069 -279.403461) (xy 103.51356 -279.367813) (xy 103.497888 -279.347676) (xy 103.0859 -279.347676)
			(xy 103.07022 -279.367806) (xy 103.033713 -279.403452) (xy 102.992149 -279.433046) (xy 102.946521 -279.455884)
			(xy 102.89792 -279.471418) (xy 102.847506 -279.479279) (xy 102.821994 -279.479756) (xy 102.796108 -279.479212)
			(xy 102.744975 -279.471112) (xy 102.695737 -279.455113) (xy 102.649609 -279.431609) (xy 102.607725 -279.401178)
			(xy 102.571118 -279.36457) (xy 102.540688 -279.322686) (xy 102.517184 -279.276557) (xy 102.501186 -279.22732)
			(xy 102.493088 -279.176186) (xy 102.211112 -279.176186) (xy 102.211076 -279.177962) (xy 102.201888 -279.23248)
			(xy 102.193344 -279.258776) (xy 102.185724 -279.28062) (xy 102.390956 -279.635966) (xy 102.413816 -279.640284)
			(xy 102.438629 -279.645487) (xy 102.486407 -279.662435) (xy 102.531027 -279.686501) (xy 102.571434 -279.717117)
			(xy 102.606676 -279.753559) (xy 102.635921 -279.794969) (xy 102.658479 -279.840369) (xy 102.673819 -279.888688)
			(xy 102.681577 -279.938786) (xy 102.68204 -279.964134) (xy 102.681532 -279.990041) (xy 102.673426 -280.041218)
			(xy 102.657414 -280.090497) (xy 102.633891 -280.136664) (xy 102.603435 -280.178583) (xy 102.566797 -280.215221)
			(xy 102.524878 -280.245677) (xy 102.478711 -280.2692) (xy 102.429432 -280.285212) (xy 102.378255 -280.293318)
			(xy 102.326441 -280.293318) (xy 102.275264 -280.285212) (xy 102.225985 -280.2692) (xy 102.179818 -280.245677)
			(xy 102.137899 -280.215221) (xy 102.101261 -280.178583) (xy 102.070805 -280.136664) (xy 102.047282 -280.090497)
			(xy 102.03127 -280.041218) (xy 102.023164 -279.990041) (xy 102.022656 -279.964134) (xy 102.023255 -279.936417)
			(xy 102.032575 -279.88177) (xy 102.041198 -279.855422) (xy 102.049072 -279.833324) (xy 101.844094 -279.478486)
			(xy 101.821234 -279.474168) (xy 101.796412 -279.468959) (xy 101.748608 -279.452029) (xy 101.70396 -279.427978)
			(xy 101.663522 -279.397372) (xy 101.628249 -279.360934) (xy 101.598973 -279.319523) (xy 101.576384 -279.274117)
			(xy 101.561016 -279.225788) (xy 101.553231 -279.175675) (xy 101.552756 -279.150318) (xy 31.743142 -279.150318)
			(xy 31.743142 -279.989984) (xy 88.866003 -279.989984) (xy 88.866003 -279.938216) (xy 88.874102 -279.887084)
			(xy 88.890099 -279.837849) (xy 88.913601 -279.791722) (xy 88.94403 -279.74984) (xy 88.980636 -279.713234)
			(xy 89.022517 -279.682805) (xy 89.068643 -279.659301) (xy 89.117878 -279.643303) (xy 89.16901 -279.635204)
			(xy 89.194894 -279.634696) (xy 89.220406 -279.635183) (xy 89.27082 -279.643042) (xy 89.319421 -279.658575)
			(xy 89.365049 -279.681409) (xy 89.406615 -279.711) (xy 89.443126 -279.746642) (xy 89.4588 -279.766776)
			(xy 89.870788 -279.766776) (xy 89.886462 -279.746641) (xy 89.922972 -279.710998) (xy 89.964538 -279.681405)
			(xy 90.010166 -279.658569) (xy 90.058768 -279.643035) (xy 90.109182 -279.635173) (xy 90.134694 -279.634696)
			(xy 90.160586 -279.635109) (xy 90.211734 -279.643209) (xy 90.260984 -279.659211) (xy 90.307125 -279.68272)
			(xy 90.349021 -279.713158) (xy 90.385638 -279.749775) (xy 90.416077 -279.791669) (xy 90.439587 -279.83781)
			(xy 90.45559 -279.88706) (xy 90.463691 -279.938208) (xy 90.463691 -279.964134) (xy 96.383856 -279.964134)
			(xy 96.384364 -279.938227) (xy 96.39247 -279.88705) (xy 96.408482 -279.837771) (xy 96.432005 -279.791604)
			(xy 96.462461 -279.749685) (xy 96.499099 -279.713047) (xy 96.541018 -279.682591) (xy 96.587185 -279.659068)
			(xy 96.636464 -279.643056) (xy 96.687641 -279.63495) (xy 96.739455 -279.63495) (xy 96.790632 -279.643056)
			(xy 96.839911 -279.659068) (xy 96.886078 -279.682591) (xy 96.927997 -279.713047) (xy 96.964635 -279.749685)
			(xy 96.995091 -279.791604) (xy 97.018614 -279.837771) (xy 97.034626 -279.88705) (xy 97.042732 -279.938227)
			(xy 97.04324 -279.964134) (xy 97.042606 -279.991926) (xy 97.033158 -280.046702) (xy 97.024444 -280.0731)
			(xy 97.016824 -280.095198) (xy 97.221802 -280.450036) (xy 97.244662 -280.454354) (xy 97.269457 -280.45958)
			(xy 97.317195 -280.476563) (xy 97.361773 -280.50065) (xy 97.402139 -280.531276) (xy 97.437344 -280.567718)
			(xy 97.466557 -280.609118) (xy 97.489091 -280.6545) (xy 97.504415 -280.702797) (xy 97.512168 -280.752869)
			(xy 97.512632 -280.778204) (xy 97.512124 -280.804091) (xy 97.504025 -280.855229) (xy 97.488026 -280.904469)
			(xy 97.46452 -280.950601) (xy 97.434088 -280.992488) (xy 97.397478 -281.029098) (xy 97.355591 -281.05953)
			(xy 97.309459 -281.083036) (xy 97.260219 -281.099035) (xy 97.209081 -281.107134) (xy 97.157307 -281.107134)
			(xy 97.106169 -281.099035) (xy 97.056929 -281.083036) (xy 97.010797 -281.05953) (xy 96.96891 -281.029098)
			(xy 96.9323 -280.992488) (xy 96.901868 -280.950601) (xy 96.878362 -280.904469) (xy 96.862363 -280.855229)
			(xy 96.854264 -280.804091) (xy 96.853756 -280.778204) (xy 96.854288 -280.750496) (xy 96.863482 -280.695849)
			(xy 96.872044 -280.669492) (xy 96.879918 -280.647394) (xy 96.674686 -280.292302) (xy 96.651826 -280.287984)
			(xy 96.627038 -280.282731) (xy 96.579302 -280.265749) (xy 96.534727 -280.241664) (xy 96.494362 -280.211041)
			(xy 96.459158 -280.174603) (xy 96.429944 -280.133207) (xy 96.407407 -280.087828) (xy 96.39208 -280.039536)
			(xy 96.384322 -279.989467) (xy 96.383856 -279.964134) (xy 90.463691 -279.964134) (xy 90.463691 -279.989992)
			(xy 90.45559 -280.04114) (xy 90.439587 -280.09039) (xy 90.416077 -280.13653) (xy 90.385638 -280.178425)
			(xy 90.349021 -280.215042) (xy 90.307125 -280.24548) (xy 90.260984 -280.268989) (xy 90.211734 -280.284991)
			(xy 90.160586 -280.293091) (xy 90.134694 -280.293572) (xy 90.109181 -280.293107) (xy 90.058766 -280.285245)
			(xy 90.010163 -280.269709) (xy 89.964535 -280.24687) (xy 89.92297 -280.217275) (xy 89.886461 -280.181628)
			(xy 89.870788 -280.161492) (xy 89.4588 -280.161492) (xy 89.443124 -280.181626) (xy 89.406615 -280.21727)
			(xy 89.365051 -280.246864) (xy 89.319422 -280.269701) (xy 89.270821 -280.285235) (xy 89.220406 -280.293095)
			(xy 89.194894 -280.293572) (xy 89.16901 -280.292996) (xy 89.117878 -280.284897) (xy 89.068643 -280.268899)
			(xy 89.022517 -280.245395) (xy 88.980636 -280.214966) (xy 88.94403 -280.17836) (xy 88.913601 -280.136478)
			(xy 88.890099 -280.090351) (xy 88.874102 -280.041116) (xy 88.866003 -279.989984) (xy 31.743142 -279.989984)
			(xy 31.743142 -280.804107) (xy 86.51622 -280.804107) (xy 86.51622 -280.752293) (xy 86.524326 -280.701118)
			(xy 86.540337 -280.65184) (xy 86.563859 -280.605674) (xy 86.594314 -280.563756) (xy 86.630951 -280.527118)
			(xy 86.672869 -280.496662) (xy 86.719035 -280.473139) (xy 86.768312 -280.457127) (xy 86.819487 -280.449021)
			(xy 86.845394 -280.448512) (xy 86.870888 -280.448996) (xy 86.921265 -280.456856) (xy 86.969828 -280.472391)
			(xy 87.015416 -280.495227) (xy 87.056936 -280.52482) (xy 87.093398 -280.56046) (xy 87.109046 -280.580592)
			(xy 87.521542 -280.580592) (xy 87.537192 -280.560462) (xy 87.573653 -280.52482) (xy 87.615173 -280.495227)
			(xy 87.66076 -280.472389) (xy 87.709323 -280.456853) (xy 87.7597 -280.448991) (xy 87.785194 -280.448512)
			(xy 87.811104 -280.448985) (xy 87.862286 -280.457091) (xy 87.91157 -280.473103) (xy 87.957743 -280.496628)
			(xy 87.999666 -280.527087) (xy 88.036309 -280.563729) (xy 88.066768 -280.605652) (xy 88.090294 -280.651824)
			(xy 88.106308 -280.701108) (xy 88.114414 -280.75229) (xy 88.114414 -280.80411) (xy 88.106308 -280.855292)
			(xy 88.090294 -280.904576) (xy 88.066768 -280.950748) (xy 88.036309 -280.992671) (xy 87.999666 -281.029313)
			(xy 87.957743 -281.059772) (xy 87.91157 -281.083297) (xy 87.862286 -281.099309) (xy 87.811104 -281.107415)
			(xy 87.785194 -281.107896) (xy 87.7597 -281.107418) (xy 87.709323 -281.099555) (xy 87.660759 -281.08402)
			(xy 87.615172 -281.061182) (xy 87.573652 -281.031589) (xy 87.53719 -280.995948) (xy 87.521542 -280.975816)
			(xy 87.109046 -280.975816) (xy 87.093405 -280.995954) (xy 87.056942 -281.031594) (xy 87.01542 -281.061187)
			(xy 86.969831 -281.084023) (xy 86.921267 -281.099558) (xy 86.870888 -281.107418) (xy 86.845394 -281.107896)
			(xy 86.819487 -281.107379) (xy 86.768312 -281.099273) (xy 86.719035 -281.083261) (xy 86.672869 -281.059738)
			(xy 86.630951 -281.029282) (xy 86.594314 -280.992644) (xy 86.563859 -280.950726) (xy 86.540337 -280.90456)
			(xy 86.524326 -280.855282) (xy 86.51622 -280.804107) (xy 31.743142 -280.804107) (xy 31.743142 -282.405836)
			(xy 86.515956 -282.405836) (xy 86.516374 -282.380488) (xy 86.524157 -282.330393) (xy 86.539514 -282.282079)
			(xy 86.562083 -282.236685) (xy 86.591333 -282.195278) (xy 86.626575 -282.158835) (xy 86.666978 -282.128214)
			(xy 86.711591 -282.104137) (xy 86.759364 -282.08717) (xy 86.78418 -282.081986) (xy 86.80704 -282.077668)
			(xy 87.012018 -281.722576) (xy 87.004398 -281.700732) (xy 86.995753 -281.67439) (xy 86.986439 -281.619739)
			(xy 86.985856 -281.59202) (xy 86.986364 -281.566113) (xy 86.99447 -281.514936) (xy 87.010482 -281.465657)
			(xy 87.034005 -281.41949) (xy 87.064461 -281.377571) (xy 87.101099 -281.340933) (xy 87.143018 -281.310477)
			(xy 87.189185 -281.286954) (xy 87.238464 -281.270942) (xy 87.289641 -281.262836) (xy 87.341455 -281.262836)
			(xy 87.392632 -281.270942) (xy 87.441911 -281.286954) (xy 87.488078 -281.310477) (xy 87.529997 -281.340933)
			(xy 87.566635 -281.377571) (xy 87.597091 -281.41949) (xy 87.620614 -281.465657) (xy 87.636626 -281.514936)
			(xy 87.644732 -281.566113) (xy 87.64524 -281.59202) (xy 88.865456 -281.59202) (xy 88.86595 -281.566675)
			(xy 88.87372 -281.516583) (xy 88.889066 -281.468271) (xy 88.911624 -281.422876) (xy 88.940864 -281.381469)
			(xy 88.976098 -281.345025) (xy 89.016493 -281.314403) (xy 89.0611 -281.290323) (xy 89.108866 -281.273355)
			(xy 89.13368 -281.26817) (xy 89.15654 -281.263852) (xy 89.361518 -280.909014) (xy 89.353898 -280.88717)
			(xy 89.345254 -280.860761) (xy 89.335932 -280.805986) (xy 89.335356 -280.778204) (xy 89.335819 -280.752307)
			(xy 89.343918 -280.70115) (xy 89.359916 -280.651889) (xy 89.383421 -280.605736) (xy 89.413854 -280.563826)
			(xy 89.450466 -280.527191) (xy 89.492357 -280.496731) (xy 89.538495 -280.473197) (xy 89.587746 -280.457167)
			(xy 89.638897 -280.449036) (xy 89.664794 -280.448512) (xy 89.690698 -280.44895) (xy 89.741869 -280.457058)
			(xy 89.79114 -280.473077) (xy 89.837295 -280.49661) (xy 89.879199 -280.527077) (xy 89.915817 -280.563728)
			(xy 89.946246 -280.605659) (xy 89.969738 -280.651836) (xy 89.985711 -280.701121) (xy 89.993774 -280.752299)
			(xy 89.994232 -280.778204) (xy 92.154756 -280.778204) (xy 92.155193 -280.752292) (xy 92.163301 -280.701107)
			(xy 92.179316 -280.65182) (xy 92.202845 -280.605646) (xy 92.233308 -280.563722) (xy 92.269955 -280.527079)
			(xy 92.311884 -280.496622) (xy 92.358061 -280.473099) (xy 92.40735 -280.45709) (xy 92.458536 -280.44899)
			(xy 92.484448 -280.448512) (xy 92.510354 -280.4489) (xy 92.561526 -280.457017) (xy 92.610798 -280.473042)
			(xy 92.656954 -280.496582) (xy 92.698857 -280.527055) (xy 92.735474 -280.563712) (xy 92.765902 -280.605647)
			(xy 92.789393 -280.651828) (xy 92.805366 -280.701117) (xy 92.813428 -280.752298) (xy 92.813886 -280.778204)
			(xy 92.813354 -280.804107) (xy 94.97442 -280.804107) (xy 94.97442 -280.752293) (xy 94.982526 -280.701118)
			(xy 94.998537 -280.65184) (xy 95.022059 -280.605674) (xy 95.052514 -280.563756) (xy 95.089151 -280.527118)
			(xy 95.131069 -280.496662) (xy 95.177235 -280.473139) (xy 95.226512 -280.457127) (xy 95.277687 -280.449021)
			(xy 95.303594 -280.448512) (xy 95.329106 -280.448992) (xy 95.379521 -280.456852) (xy 95.428122 -280.472385)
			(xy 95.473751 -280.495221) (xy 95.515316 -280.524814) (xy 95.551826 -280.560457) (xy 95.5675 -280.580592)
			(xy 95.979742 -280.580592) (xy 95.995389 -280.560435) (xy 96.031904 -280.524793) (xy 96.073475 -280.495202)
			(xy 96.119109 -280.472369) (xy 96.167716 -280.45684) (xy 96.218134 -280.448986) (xy 96.243648 -280.448512)
			(xy 96.269553 -280.449016) (xy 96.320725 -280.457128) (xy 96.369997 -280.473144) (xy 96.416159 -280.49667)
			(xy 96.458071 -280.527127) (xy 96.494704 -280.563765) (xy 96.525155 -280.605682) (xy 96.548675 -280.651847)
			(xy 96.564684 -280.701122) (xy 96.572788 -280.752295) (xy 96.572788 -280.804105) (xy 96.564684 -280.855278)
			(xy 96.548675 -280.904553) (xy 96.525155 -280.950718) (xy 96.494704 -280.992635) (xy 96.458071 -281.029273)
			(xy 96.416159 -281.05973) (xy 96.369997 -281.083256) (xy 96.320725 -281.099272) (xy 96.269553 -281.107384)
			(xy 96.243648 -281.107896) (xy 96.218137 -281.107382) (xy 96.167724 -281.099529) (xy 96.119123 -281.084002)
			(xy 96.073495 -281.061173) (xy 96.031928 -281.031586) (xy 95.995417 -280.995948) (xy 95.979742 -280.975816)
			(xy 95.5675 -280.975816) (xy 95.551831 -280.995955) (xy 95.51532 -281.031598) (xy 95.473753 -281.06119)
			(xy 95.428124 -281.084026) (xy 95.379522 -281.099559) (xy 95.329106 -281.107419) (xy 95.303594 -281.107896)
			(xy 95.277687 -281.107379) (xy 95.226512 -281.099273) (xy 95.177235 -281.083261) (xy 95.131069 -281.059738)
			(xy 95.089151 -281.029282) (xy 95.052514 -280.992644) (xy 95.022059 -280.950726) (xy 94.998537 -280.90456)
			(xy 94.982526 -280.855282) (xy 94.97442 -280.804107) (xy 92.813354 -280.804107) (xy 92.813315 -280.805986)
			(xy 92.803991 -280.860762) (xy 92.795344 -280.88717) (xy 92.787724 -280.909014) (xy 92.992702 -281.263852)
			(xy 93.015562 -281.26817) (xy 93.04036 -281.273381) (xy 93.0881 -281.290365) (xy 93.132678 -281.314454)
			(xy 93.173045 -281.345081) (xy 93.20825 -281.381525) (xy 93.237463 -281.422927) (xy 93.259996 -281.468312)
			(xy 93.275318 -281.51661) (xy 93.283069 -281.566685) (xy 93.283532 -281.59202) (xy 93.283024 -281.617907)
			(xy 93.274925 -281.669045) (xy 93.258926 -281.718285) (xy 93.23542 -281.764417) (xy 93.204988 -281.806304)
			(xy 93.168378 -281.842914) (xy 93.126491 -281.873346) (xy 93.080359 -281.896852) (xy 93.031119 -281.912851)
			(xy 92.979981 -281.92095) (xy 92.928207 -281.92095) (xy 92.877069 -281.912851) (xy 92.827829 -281.896852)
			(xy 92.781697 -281.873346) (xy 92.73981 -281.842914) (xy 92.7032 -281.806304) (xy 92.672768 -281.764417)
			(xy 92.649262 -281.718285) (xy 92.633263 -281.669045) (xy 92.625164 -281.617907) (xy 92.624656 -281.59202)
			(xy 92.625203 -281.564313) (xy 92.634391 -281.509667) (xy 92.642944 -281.483308) (xy 92.650564 -281.461464)
			(xy 92.445586 -281.106372) (xy 92.422726 -281.102054) (xy 92.397931 -281.096829) (xy 92.350193 -281.079845)
			(xy 92.305616 -281.055757) (xy 92.265251 -281.025131) (xy 92.230046 -280.988689) (xy 92.200833 -280.947289)
			(xy 92.178299 -280.901907) (xy 92.162974 -280.853611) (xy 92.15522 -280.803539) (xy 92.154756 -280.778204)
			(xy 89.994232 -280.778204) (xy 89.993765 -280.803528) (xy 89.986033 -280.853583) (xy 89.970734 -280.901865)
			(xy 89.94823 -280.947239) (xy 89.91905 -280.988637) (xy 89.883881 -281.025084) (xy 89.843551 -281.055722)
			(xy 89.799008 -281.079831) (xy 89.751302 -281.096842) (xy 89.726516 -281.102054) (xy 89.703656 -281.106372)
			(xy 89.498678 -281.46121) (xy 89.506298 -281.483054) (xy 89.51491 -281.50934) (xy 89.524233 -281.563858)
			(xy 89.52484 -281.591512) (xy 89.52484 -281.59202) (xy 89.524332 -281.617905) (xy 90.745336 -281.617905)
			(xy 90.745336 -281.566095) (xy 90.753441 -281.514922) (xy 90.769451 -281.465646) (xy 90.792973 -281.419482)
			(xy 90.823426 -281.377566) (xy 90.860062 -281.34093) (xy 90.901977 -281.310476) (xy 90.948141 -281.286954)
			(xy 90.997416 -281.270943) (xy 91.048589 -281.262837) (xy 91.074494 -281.262328) (xy 91.100006 -281.262802)
			(xy 91.150421 -281.270662) (xy 91.199024 -281.286196) (xy 91.244652 -281.309033) (xy 91.286218 -281.338627)
			(xy 91.322727 -281.374272) (xy 91.3384 -281.394408) (xy 91.750388 -281.394408) (xy 91.766071 -281.37428)
			(xy 91.802578 -281.338635) (xy 91.844142 -281.309041) (xy 91.889768 -281.286203) (xy 91.938369 -281.270668)
			(xy 91.988782 -281.262806) (xy 92.014294 -281.262328) (xy 92.040205 -281.262769) (xy 92.09139 -281.270875)
			(xy 92.140676 -281.286888) (xy 92.186851 -281.310415) (xy 92.228777 -281.340875) (xy 92.265421 -281.377519)
			(xy 92.295882 -281.419444) (xy 92.319409 -281.465618) (xy 92.335423 -281.514904) (xy 92.34353 -281.566089)
			(xy 92.34353 -281.617911) (xy 92.335423 -281.669096) (xy 92.319409 -281.718382) (xy 92.295882 -281.764556)
			(xy 92.265421 -281.806481) (xy 92.228777 -281.843125) (xy 92.186851 -281.873585) (xy 92.140676 -281.897112)
			(xy 92.09139 -281.913125) (xy 92.040205 -281.921231) (xy 92.014294 -281.921712) (xy 91.988782 -281.921231)
			(xy 91.938368 -281.91337) (xy 91.889767 -281.897836) (xy 91.844138 -281.875001) (xy 91.802573 -281.845409)
			(xy 91.766062 -281.809767) (xy 91.750388 -281.789632) (xy 91.3384 -281.789632) (xy 91.322735 -281.809774)
			(xy 91.286223 -281.845417) (xy 91.244655 -281.875008) (xy 91.199025 -281.897843) (xy 91.150422 -281.913376)
			(xy 91.100006 -281.921235) (xy 91.074494 -281.921712) (xy 91.048589 -281.921163) (xy 90.997416 -281.913057)
			(xy 90.948141 -281.897046) (xy 90.901977 -281.873524) (xy 90.860062 -281.84307) (xy 90.823426 -281.806434)
			(xy 90.792973 -281.764518) (xy 90.769451 -281.718354) (xy 90.753441 -281.669078) (xy 90.745336 -281.617905)
			(xy 89.524332 -281.617905) (xy 89.524332 -281.617927) (xy 89.516226 -281.669104) (xy 89.500214 -281.718383)
			(xy 89.476691 -281.76455) (xy 89.446235 -281.806469) (xy 89.409597 -281.843107) (xy 89.367678 -281.873563)
			(xy 89.321511 -281.897086) (xy 89.272232 -281.913098) (xy 89.221055 -281.921204) (xy 89.169241 -281.921204)
			(xy 89.118064 -281.913098) (xy 89.068785 -281.897086) (xy 89.022618 -281.873563) (xy 88.980699 -281.843107)
			(xy 88.944061 -281.806469) (xy 88.913605 -281.76455) (xy 88.890082 -281.718383) (xy 88.87407 -281.669104)
			(xy 88.865964 -281.617927) (xy 88.865456 -281.59202) (xy 87.64524 -281.59202) (xy 87.644785 -281.617367)
			(xy 87.637009 -281.66746) (xy 87.621658 -281.715773) (xy 87.599094 -281.761168) (xy 87.569849 -281.802575)
			(xy 87.534611 -281.839019) (xy 87.494211 -281.86964) (xy 87.449601 -281.893718) (xy 87.401831 -281.910686)
			(xy 87.377016 -281.91587) (xy 87.354156 -281.920188) (xy 87.149178 -282.27528) (xy 87.156798 -282.297124)
			(xy 87.165433 -282.32347) (xy 87.174753 -282.378118) (xy 87.17534 -282.405836) (xy 87.455756 -282.405836)
			(xy 87.456264 -282.379949) (xy 87.464363 -282.328811) (xy 87.480362 -282.279571) (xy 87.503868 -282.233439)
			(xy 87.5343 -282.191552) (xy 87.57091 -282.154942) (xy 87.612797 -282.12451) (xy 87.658929 -282.101004)
			(xy 87.708169 -282.085005) (xy 87.759307 -282.076906) (xy 87.811081 -282.076906) (xy 87.862219 -282.085005)
			(xy 87.911459 -282.101004) (xy 87.957591 -282.12451) (xy 87.999478 -282.154942) (xy 88.036088 -282.191552)
			(xy 88.06652 -282.233439) (xy 88.090026 -282.279571) (xy 88.106025 -282.328811) (xy 88.114124 -282.379949)
			(xy 88.114632 -282.405836) (xy 88.114145 -282.431709) (xy 88.396026 -282.431709) (xy 88.396026 -282.379891)
			(xy 88.404133 -282.328711) (xy 88.420147 -282.27943) (xy 88.443674 -282.233261) (xy 88.474134 -282.191341)
			(xy 88.510778 -282.154703) (xy 88.552702 -282.124249) (xy 88.598874 -282.100729) (xy 88.648158 -282.084722)
			(xy 88.699339 -282.076622) (xy 88.725248 -282.076144) (xy 88.750741 -282.076648) (xy 88.801118 -282.084503)
			(xy 88.849682 -282.100032) (xy 88.895269 -282.122865) (xy 88.936791 -282.152454) (xy 88.973252 -282.188093)
			(xy 88.9889 -282.208224) (xy 89.401396 -282.208224) (xy 89.417024 -282.188075) (xy 89.453488 -282.152433)
			(xy 89.495013 -282.122841) (xy 89.540604 -282.100006) (xy 89.589171 -282.084474) (xy 89.639553 -282.076619)
			(xy 89.665048 -282.076144) (xy 89.690956 -282.076584) (xy 89.742132 -282.084696) (xy 89.79141 -282.100714)
			(xy 89.837576 -282.124242) (xy 89.879493 -282.154702) (xy 89.916129 -282.191344) (xy 89.946583 -282.233265)
			(xy 89.970105 -282.279434) (xy 89.986115 -282.328714) (xy 89.99422 -282.379892) (xy 89.99422 -282.431708)
			(xy 89.986115 -282.482886) (xy 89.970105 -282.532166) (xy 89.946583 -282.578335) (xy 89.916129 -282.620256)
			(xy 89.879493 -282.656898) (xy 89.837576 -282.687358) (xy 89.79141 -282.710886) (xy 89.742132 -282.726904)
			(xy 89.690956 -282.735016) (xy 89.665048 -282.735528) (xy 89.639556 -282.734998) (xy 89.589182 -282.727145)
			(xy 89.54062 -282.711619) (xy 89.495033 -282.688791) (xy 89.453511 -282.659207) (xy 89.417046 -282.623576)
			(xy 89.401396 -282.603448) (xy 88.9889 -282.603448) (xy 88.973236 -282.623567) (xy 88.936776 -282.659207)
			(xy 88.895259 -282.6888) (xy 88.849675 -282.71164) (xy 88.801115 -282.727179) (xy 88.750741 -282.735046)
			(xy 88.725248 -282.735528) (xy 88.699339 -282.734978) (xy 88.648158 -282.726878) (xy 88.598874 -282.710871)
			(xy 88.552702 -282.687351) (xy 88.510778 -282.656897) (xy 88.474134 -282.620259) (xy 88.443674 -282.578339)
			(xy 88.420147 -282.53217) (xy 88.404133 -282.482889) (xy 88.396026 -282.431709) (xy 88.114145 -282.431709)
			(xy 88.11411 -282.433545) (xy 88.10491 -282.488191) (xy 88.096344 -282.514548) (xy 88.08847 -282.536646)
			(xy 88.293702 -282.891738) (xy 88.316562 -282.896056) (xy 88.341357 -282.90128) (xy 88.389096 -282.918263)
			(xy 88.433673 -282.942351) (xy 88.47404 -282.972977) (xy 88.509244 -283.009419) (xy 88.538458 -283.050819)
			(xy 88.560992 -283.096202) (xy 88.576316 -283.144498) (xy 88.584068 -283.194571) (xy 88.584532 -283.219906)
			(xy 90.745056 -283.219906) (xy 90.74558 -283.194573) (xy 90.75333 -283.144505) (xy 90.768649 -283.096211)
			(xy 90.791176 -283.05083) (xy 90.820381 -283.009429) (xy 90.855576 -282.972983) (xy 90.895932 -282.942351)
			(xy 90.9405 -282.918254) (xy 90.988229 -282.901258) (xy 91.013026 -282.896056) (xy 91.035886 -282.891738)
			(xy 91.241118 -282.536392) (xy 91.233498 -282.514548) (xy 91.224857 -282.488204) (xy 91.215541 -282.433555)
			(xy 91.214956 -282.405836) (xy 91.215464 -282.379929) (xy 91.22357 -282.328752) (xy 91.239582 -282.279473)
			(xy 91.263105 -282.233306) (xy 91.293561 -282.191387) (xy 91.330199 -282.154749) (xy 91.372118 -282.124293)
			(xy 91.418285 -282.10077) (xy 91.467564 -282.084758) (xy 91.518741 -282.076652) (xy 91.570555 -282.076652)
			(xy 91.621732 -282.084758) (xy 91.671011 -282.10077) (xy 91.717178 -282.124293) (xy 91.759097 -282.154749)
			(xy 91.795735 -282.191387) (xy 91.826191 -282.233306) (xy 91.849714 -282.279473) (xy 91.865726 -282.328752)
			(xy 91.873832 -282.379929) (xy 91.87434 -282.405836) (xy 93.094556 -282.405836) (xy 93.094974 -282.380488)
			(xy 93.102757 -282.330393) (xy 93.118114 -282.282079) (xy 93.140683 -282.236685) (xy 93.169933 -282.195278)
			(xy 93.205175 -282.158835) (xy 93.245578 -282.128214) (xy 93.290191 -282.104137) (xy 93.337964 -282.08717)
			(xy 93.36278 -282.081986) (xy 93.38564 -282.077668) (xy 93.590618 -281.72283) (xy 93.582744 -281.700986)
			(xy 93.574162 -281.674568) (xy 93.564967 -281.619792) (xy 93.564456 -281.59202) (xy 93.564964 -281.566133)
			(xy 93.573063 -281.514995) (xy 93.589062 -281.465755) (xy 93.612568 -281.419623) (xy 93.643 -281.377736)
			(xy 93.67961 -281.341126) (xy 93.721497 -281.310694) (xy 93.767629 -281.287188) (xy 93.816869 -281.271189)
			(xy 93.868007 -281.26309) (xy 93.919781 -281.26309) (xy 93.970919 -281.271189) (xy 94.020159 -281.287188)
			(xy 94.066291 -281.310694) (xy 94.108178 -281.341126) (xy 94.144788 -281.377736) (xy 94.17522 -281.419623)
			(xy 94.198726 -281.465755) (xy 94.214725 -281.514995) (xy 94.222824 -281.566133) (xy 94.223332 -281.59202)
			(xy 94.222842 -281.617354) (xy 94.215087 -281.667425) (xy 94.199764 -281.71572) (xy 94.177233 -281.761102)
			(xy 94.148024 -281.802503) (xy 94.112825 -281.838948) (xy 94.072465 -281.869579) (xy 94.027893 -281.893676)
			(xy 93.980161 -281.910669) (xy 93.955362 -281.91587) (xy 93.932502 -281.920188) (xy 93.727524 -282.275026)
			(xy 93.735398 -282.297124) (xy 93.744018 -282.323474) (xy 93.753346 -282.378119) (xy 93.75394 -282.405836)
			(xy 94.974156 -282.405836) (xy 94.974616 -282.380501) (xy 94.982377 -282.33043) (xy 94.997705 -282.282135)
			(xy 95.020241 -282.236753) (xy 95.049454 -282.195352) (xy 95.084656 -282.158908) (xy 95.125019 -282.128277)
			(xy 95.169592 -282.104181) (xy 95.217327 -282.087187) (xy 95.242126 -282.081986) (xy 95.264986 -282.077668)
			(xy 95.470218 -281.722322) (xy 95.462598 -281.700478) (xy 95.45397 -281.674197) (xy 95.444658 -281.619675)
			(xy 95.444056 -281.59202) (xy 95.444564 -281.566113) (xy 95.45267 -281.514936) (xy 95.468682 -281.465657)
			(xy 95.492205 -281.41949) (xy 95.522661 -281.377571) (xy 95.559299 -281.340933) (xy 95.601218 -281.310477)
			(xy 95.647385 -281.286954) (xy 95.696664 -281.270942) (xy 95.747841 -281.262836) (xy 95.799655 -281.262836)
			(xy 95.850832 -281.270942) (xy 95.900111 -281.286954) (xy 95.946278 -281.310477) (xy 95.988197 -281.340933)
			(xy 96.024835 -281.377571) (xy 96.055291 -281.41949) (xy 96.078814 -281.465657) (xy 96.094826 -281.514936)
			(xy 96.102932 -281.566113) (xy 96.10344 -281.59202) (xy 97.323656 -281.59202) (xy 97.32415 -281.566675)
			(xy 97.33192 -281.516583) (xy 97.347266 -281.468271) (xy 97.369824 -281.422876) (xy 97.399064 -281.381469)
			(xy 97.434298 -281.345025) (xy 97.474693 -281.314403) (xy 97.5193 -281.290323) (xy 97.567066 -281.273355)
			(xy 97.59188 -281.26817) (xy 97.61474 -281.263852) (xy 97.819718 -280.909014) (xy 97.811844 -280.88717)
			(xy 97.803259 -280.860753) (xy 97.794066 -280.805977) (xy 97.793556 -280.778204) (xy 97.794064 -280.752317)
			(xy 97.802163 -280.701179) (xy 97.818162 -280.651939) (xy 97.841668 -280.605807) (xy 97.8721 -280.56392)
			(xy 97.90871 -280.52731) (xy 97.950597 -280.496878) (xy 97.996729 -280.473372) (xy 98.045969 -280.457373)
			(xy 98.097107 -280.449274) (xy 98.148881 -280.449274) (xy 98.200019 -280.457373) (xy 98.249259 -280.473372)
			(xy 98.295391 -280.496878) (xy 98.337278 -280.52731) (xy 98.373888 -280.56392) (xy 98.40432 -280.605807)
			(xy 98.427826 -280.651939) (xy 98.443825 -280.701179) (xy 98.451924 -280.752317) (xy 98.452432 -280.778204)
			(xy 100.612956 -280.778204) (xy 100.613464 -280.752317) (xy 100.621563 -280.701179) (xy 100.637562 -280.651939)
			(xy 100.661068 -280.605807) (xy 100.6915 -280.56392) (xy 100.72811 -280.52731) (xy 100.769997 -280.496878)
			(xy 100.816129 -280.473372) (xy 100.865369 -280.457373) (xy 100.916507 -280.449274) (xy 100.968281 -280.449274)
			(xy 101.019419 -280.457373) (xy 101.068659 -280.473372) (xy 101.114791 -280.496878) (xy 101.156678 -280.52731)
			(xy 101.193288 -280.56392) (xy 101.22372 -280.605807) (xy 101.247226 -280.651939) (xy 101.263225 -280.701179)
			(xy 101.271324 -280.752317) (xy 101.271832 -280.778204) (xy 103.432356 -280.778204) (xy 103.432864 -280.752317)
			(xy 103.440963 -280.701179) (xy 103.456962 -280.651939) (xy 103.480468 -280.605807) (xy 103.5109 -280.56392)
			(xy 103.54751 -280.52731) (xy 103.589397 -280.496878) (xy 103.635529 -280.473372) (xy 103.684769 -280.457373)
			(xy 103.735907 -280.449274) (xy 103.787681 -280.449274) (xy 103.838819 -280.457373) (xy 103.888059 -280.473372)
			(xy 103.934191 -280.496878) (xy 103.976078 -280.52731) (xy 104.012688 -280.56392) (xy 104.04312 -280.605807)
			(xy 104.066626 -280.651939) (xy 104.082625 -280.701179) (xy 104.090724 -280.752317) (xy 104.091232 -280.778204)
			(xy 104.372156 -280.778204) (xy 104.372678 -280.752871) (xy 104.380429 -280.702803) (xy 104.395748 -280.654509)
			(xy 104.418275 -280.609127) (xy 104.44748 -280.567726) (xy 104.482675 -280.531281) (xy 104.523032 -280.500649)
			(xy 104.567599 -280.476552) (xy 104.615329 -280.459556) (xy 104.640126 -280.454354) (xy 104.662986 -280.450036)
			(xy 104.868218 -280.09469) (xy 104.860598 -280.072592) (xy 104.851973 -280.04631) (xy 104.842659 -279.991789)
			(xy 104.842056 -279.964134) (xy 104.842564 -279.938227) (xy 104.85067 -279.88705) (xy 104.866682 -279.837771)
			(xy 104.890205 -279.791604) (xy 104.920661 -279.749685) (xy 104.957299 -279.713047) (xy 104.999218 -279.682591)
			(xy 105.045385 -279.659068) (xy 105.094664 -279.643056) (xy 105.145841 -279.63495) (xy 105.197655 -279.63495)
			(xy 105.248832 -279.643056) (xy 105.298111 -279.659068) (xy 105.344278 -279.682591) (xy 105.386197 -279.713047)
			(xy 105.422835 -279.749685) (xy 105.453291 -279.791604) (xy 105.476814 -279.837771) (xy 105.492826 -279.88705)
			(xy 105.500932 -279.938227) (xy 105.50144 -279.964134) (xy 105.501001 -279.989499) (xy 105.493248 -280.039631)
			(xy 105.4779 -280.087982) (xy 105.45532 -280.133408) (xy 105.426041 -280.174835) (xy 105.390757 -280.211282)
			(xy 105.350301 -280.241888) (xy 105.305631 -280.26593) (xy 105.257803 -280.282837) (xy 105.232962 -280.287984)
			(xy 105.209848 -280.292302) (xy 105.00487 -280.647394) (xy 105.012744 -280.669492) (xy 105.021304 -280.69585)
			(xy 105.030503 -280.750496) (xy 105.031032 -280.778204) (xy 105.030524 -280.804091) (xy 105.022425 -280.855229)
			(xy 105.006426 -280.904469) (xy 104.98292 -280.950601) (xy 104.952488 -280.992488) (xy 104.915878 -281.029098)
			(xy 104.873991 -281.05953) (xy 104.827859 -281.083036) (xy 104.778619 -281.099035) (xy 104.727481 -281.107134)
			(xy 104.675707 -281.107134) (xy 104.624569 -281.099035) (xy 104.575329 -281.083036) (xy 104.529197 -281.05953)
			(xy 104.48731 -281.029098) (xy 104.4507 -280.992488) (xy 104.420268 -280.950601) (xy 104.396762 -280.904469)
			(xy 104.380763 -280.855229) (xy 104.372664 -280.804091) (xy 104.372156 -280.778204) (xy 104.091232 -280.778204)
			(xy 104.090673 -280.805848) (xy 104.081487 -280.860366) (xy 104.072944 -280.886662) (xy 104.065324 -280.908506)
			(xy 104.270556 -281.263852) (xy 104.293416 -281.26817) (xy 104.318226 -281.273386) (xy 104.366003 -281.290334)
			(xy 104.410622 -281.314398) (xy 104.451028 -281.345012) (xy 104.48627 -281.381453) (xy 104.515516 -281.422861)
			(xy 104.538075 -281.468259) (xy 104.553416 -281.516576) (xy 104.561176 -281.566673) (xy 104.56164 -281.59202)
			(xy 104.561132 -281.617927) (xy 104.553026 -281.669104) (xy 104.537014 -281.718383) (xy 104.513491 -281.76455)
			(xy 104.483035 -281.806469) (xy 104.446397 -281.843107) (xy 104.404478 -281.873563) (xy 104.358311 -281.897086)
			(xy 104.309032 -281.913098) (xy 104.257855 -281.921204) (xy 104.206041 -281.921204) (xy 104.154864 -281.913098)
			(xy 104.105585 -281.897086) (xy 104.059418 -281.873563) (xy 104.017499 -281.843107) (xy 103.980861 -281.806469)
			(xy 103.950405 -281.76455) (xy 103.926882 -281.718383) (xy 103.91087 -281.669104) (xy 103.902764 -281.617927)
			(xy 103.902256 -281.59202) (xy 103.902852 -281.564303) (xy 103.912174 -281.509656) (xy 103.920798 -281.483308)
			(xy 103.928672 -281.46121) (xy 103.723694 -281.106372) (xy 103.700834 -281.102054) (xy 103.676009 -281.096858)
			(xy 103.628203 -281.079927) (xy 103.583555 -281.055874) (xy 103.543117 -281.025267) (xy 103.507844 -280.988827)
			(xy 103.478568 -280.947415) (xy 103.45598 -280.902007) (xy 103.440613 -280.853676) (xy 103.43283 -280.803562)
			(xy 103.432356 -280.778204) (xy 101.271832 -280.778204) (xy 101.271273 -280.805848) (xy 101.262087 -280.860366)
			(xy 101.253544 -280.886662) (xy 101.245924 -280.908506) (xy 101.451156 -281.263852) (xy 101.474016 -281.26817)
			(xy 101.498826 -281.273386) (xy 101.546603 -281.290334) (xy 101.591222 -281.314398) (xy 101.631628 -281.345012)
			(xy 101.66687 -281.381453) (xy 101.696116 -281.422861) (xy 101.718675 -281.468259) (xy 101.734016 -281.516576)
			(xy 101.741776 -281.566673) (xy 101.74224 -281.59202) (xy 101.741732 -281.617927) (xy 101.733626 -281.669104)
			(xy 101.717614 -281.718383) (xy 101.694091 -281.76455) (xy 101.663635 -281.806469) (xy 101.626997 -281.843107)
			(xy 101.585078 -281.873563) (xy 101.538911 -281.897086) (xy 101.489632 -281.913098) (xy 101.438455 -281.921204)
			(xy 101.386641 -281.921204) (xy 101.335464 -281.913098) (xy 101.286185 -281.897086) (xy 101.240018 -281.873563)
			(xy 101.198099 -281.843107) (xy 101.161461 -281.806469) (xy 101.131005 -281.76455) (xy 101.107482 -281.718383)
			(xy 101.09147 -281.669104) (xy 101.083364 -281.617927) (xy 101.082856 -281.59202) (xy 101.083452 -281.564303)
			(xy 101.092774 -281.509656) (xy 101.101398 -281.483308) (xy 101.109272 -281.46121) (xy 100.904294 -281.106372)
			(xy 100.881434 -281.102054) (xy 100.856609 -281.096858) (xy 100.808803 -281.079927) (xy 100.764155 -281.055874)
			(xy 100.723717 -281.025267) (xy 100.688444 -280.988827) (xy 100.659168 -280.947415) (xy 100.63658 -280.902007)
			(xy 100.621213 -280.853676) (xy 100.61343 -280.803562) (xy 100.612956 -280.778204) (xy 98.452432 -280.778204)
			(xy 98.451927 -280.803537) (xy 98.444175 -280.853607) (xy 98.428854 -280.901902) (xy 98.406324 -280.947284)
			(xy 98.377117 -280.988685) (xy 98.34192 -281.025131) (xy 98.301561 -281.055762) (xy 98.256992 -281.079859)
			(xy 98.20926 -281.096853) (xy 98.184462 -281.102054) (xy 98.161602 -281.106372) (xy 97.956624 -281.46121)
			(xy 97.964498 -281.483308) (xy 97.973138 -281.509652) (xy 97.982453 -281.564301) (xy 97.98304 -281.59202)
			(xy 97.982532 -281.61791) (xy 99.20371 -281.61791) (xy 99.20371 -281.56609) (xy 99.211817 -281.514907)
			(xy 99.227832 -281.465624) (xy 99.25136 -281.419452) (xy 99.281822 -281.37753) (xy 99.318467 -281.34089)
			(xy 99.360393 -281.310435) (xy 99.406568 -281.286913) (xy 99.455854 -281.270906) (xy 99.507038 -281.262806)
			(xy 99.532948 -281.262328) (xy 99.558462 -281.262762) (xy 99.608879 -281.270631) (xy 99.657482 -281.286173)
			(xy 99.70311 -281.309017) (xy 99.744675 -281.338618) (xy 99.781182 -281.374269) (xy 99.796854 -281.394408)
			(xy 100.208842 -281.394408) (xy 100.224493 -281.374254) (xy 100.261007 -281.338611) (xy 100.302577 -281.309019)
			(xy 100.34821 -281.286186) (xy 100.396816 -281.270657) (xy 100.447235 -281.262802) (xy 100.472748 -281.262328)
			(xy 100.498654 -281.2628) (xy 100.549829 -281.270912) (xy 100.599104 -281.286928) (xy 100.645267 -281.310456)
			(xy 100.687182 -281.340914) (xy 100.723817 -281.377554) (xy 100.754269 -281.419474) (xy 100.77779 -281.465641)
			(xy 100.7938 -281.514918) (xy 100.801904 -281.566093) (xy 100.801904 -281.617907) (xy 100.7938 -281.669082)
			(xy 100.77779 -281.718359) (xy 100.754269 -281.764526) (xy 100.723817 -281.806446) (xy 100.687182 -281.843086)
			(xy 100.645267 -281.873544) (xy 100.599104 -281.897072) (xy 100.549829 -281.913088) (xy 100.498654 -281.9212)
			(xy 100.472748 -281.921712) (xy 100.447238 -281.921192) (xy 100.396825 -281.913339) (xy 100.348225 -281.897813)
			(xy 100.302596 -281.874985) (xy 100.26103 -281.8454) (xy 100.224517 -281.809764) (xy 100.208842 -281.789632)
			(xy 99.796854 -281.789632) (xy 99.781158 -281.809749) (xy 99.744652 -281.845392) (xy 99.703091 -281.874987)
			(xy 99.657467 -281.897826) (xy 99.60887 -281.913365) (xy 99.558459 -281.921231) (xy 99.532948 -281.921712)
			(xy 99.507038 -281.921194) (xy 99.455854 -281.913094) (xy 99.406568 -281.897087) (xy 99.360393 -281.873565)
			(xy 99.318467 -281.84311) (xy 99.281822 -281.80647) (xy 99.25136 -281.764548) (xy 99.227832 -281.718376)
			(xy 99.211817 -281.669093) (xy 99.20371 -281.61791) (xy 97.982532 -281.61791) (xy 97.982532 -281.617927)
			(xy 97.974426 -281.669104) (xy 97.958414 -281.718383) (xy 97.934891 -281.76455) (xy 97.904435 -281.806469)
			(xy 97.867797 -281.843107) (xy 97.825878 -281.873563) (xy 97.779711 -281.897086) (xy 97.730432 -281.913098)
			(xy 97.679255 -281.921204) (xy 97.627441 -281.921204) (xy 97.576264 -281.913098) (xy 97.526985 -281.897086)
			(xy 97.480818 -281.873563) (xy 97.438899 -281.843107) (xy 97.402261 -281.806469) (xy 97.371805 -281.76455)
			(xy 97.348282 -281.718383) (xy 97.33227 -281.669104) (xy 97.324164 -281.617927) (xy 97.323656 -281.59202)
			(xy 96.10344 -281.59202) (xy 96.103032 -281.617397) (xy 96.095259 -281.667553) (xy 96.079885 -281.715923)
			(xy 96.057273 -281.761362) (xy 96.027958 -281.802795) (xy 95.992635 -281.839241) (xy 95.95214 -281.869837)
			(xy 95.907431 -281.89386) (xy 95.859566 -281.910741) (xy 95.834708 -281.91587) (xy 95.811848 -281.920188)
			(xy 95.60687 -282.275026) (xy 95.614744 -282.297124) (xy 95.623311 -282.32348) (xy 95.632506 -282.378127)
			(xy 95.633032 -282.405836) (xy 95.913956 -282.405836) (xy 95.914464 -282.379949) (xy 95.922563 -282.328811)
			(xy 95.938562 -282.279571) (xy 95.962068 -282.233439) (xy 95.9925 -282.191552) (xy 96.02911 -282.154942)
			(xy 96.070997 -282.12451) (xy 96.117129 -282.101004) (xy 96.166369 -282.085005) (xy 96.217507 -282.076906)
			(xy 96.269281 -282.076906) (xy 96.320419 -282.085005) (xy 96.369659 -282.101004) (xy 96.415791 -282.12451)
			(xy 96.457678 -282.154942) (xy 96.494288 -282.191552) (xy 96.52472 -282.233439) (xy 96.548226 -282.279571)
			(xy 96.564225 -282.328811) (xy 96.572324 -282.379949) (xy 96.572832 -282.405836) (xy 96.572316 -282.431704)
			(xy 96.854052 -282.431704) (xy 96.854052 -282.379896) (xy 96.862157 -282.328725) (xy 96.878166 -282.279453)
			(xy 96.901687 -282.233291) (xy 96.932138 -282.191377) (xy 96.968772 -282.154742) (xy 97.010686 -282.12429)
			(xy 97.056847 -282.100769) (xy 97.106119 -282.084758) (xy 97.15729 -282.076653) (xy 97.183194 -282.076144)
			(xy 97.208707 -282.076611) (xy 97.259122 -282.084472) (xy 97.307725 -282.100007) (xy 97.353354 -282.122845)
			(xy 97.394919 -282.152441) (xy 97.431427 -282.188087) (xy 97.4471 -282.208224) (xy 97.859088 -282.208224)
			(xy 97.874775 -282.188099) (xy 97.911281 -282.152454) (xy 97.952843 -282.122858) (xy 97.998469 -282.10002)
			(xy 98.047069 -282.084484) (xy 98.097483 -282.076622) (xy 98.122994 -282.076144) (xy 98.148907 -282.076553)
			(xy 98.200094 -282.08466) (xy 98.249383 -282.100674) (xy 98.295559 -282.124201) (xy 98.337487 -282.154663)
			(xy 98.374133 -282.191308) (xy 98.404596 -282.233235) (xy 98.428124 -282.279412) (xy 98.444139 -282.3287)
			(xy 98.452246 -282.379887) (xy 98.452246 -282.431713) (xy 98.444139 -282.4829) (xy 98.428124 -282.532188)
			(xy 98.404596 -282.578365) (xy 98.374133 -282.620292) (xy 98.337487 -282.656937) (xy 98.295559 -282.687399)
			(xy 98.249383 -282.710926) (xy 98.200094 -282.72694) (xy 98.148907 -282.735047) (xy 98.122994 -282.735528)
			(xy 98.097483 -282.735041) (xy 98.047069 -282.72718) (xy 97.998468 -282.711647) (xy 97.95284 -282.688813)
			(xy 97.911274 -282.659222) (xy 97.874762 -282.623582) (xy 97.859088 -282.603448) (xy 97.4471 -282.603448)
			(xy 97.43144 -282.623594) (xy 97.394926 -282.659235) (xy 97.353357 -282.688826) (xy 97.307726 -282.71166)
			(xy 97.259123 -282.727192) (xy 97.208707 -282.735052) (xy 97.183194 -282.735528) (xy 97.15729 -282.734947)
			(xy 97.106119 -282.726842) (xy 97.056847 -282.710831) (xy 97.010686 -282.68731) (xy 96.968772 -282.656858)
			(xy 96.932138 -282.620223) (xy 96.901687 -282.578309) (xy 96.878166 -282.532147) (xy 96.862157 -282.482875)
			(xy 96.854052 -282.431704) (xy 96.572316 -282.431704) (xy 96.572281 -282.43348) (xy 96.56309 -282.487998)
			(xy 96.554544 -282.514294) (xy 96.546924 -282.536392) (xy 96.752156 -282.891738) (xy 96.775016 -282.896056)
			(xy 96.799823 -282.901285) (xy 96.847599 -282.918232) (xy 96.892217 -282.942295) (xy 96.932623 -282.972907)
			(xy 96.967865 -283.009346) (xy 96.997111 -283.050752) (xy 97.019671 -283.096149) (xy 97.035013 -283.144464)
			(xy 97.042775 -283.194559) (xy 97.04324 -283.219906) (xy 99.203256 -283.219906) (xy 99.203737 -283.19456)
			(xy 99.21151 -283.144468) (xy 99.226857 -283.096156) (xy 99.249417 -283.050761) (xy 99.278659 -283.009354)
			(xy 99.313894 -282.97291) (xy 99.354291 -282.942288) (xy 99.398899 -282.918209) (xy 99.446666 -282.901241)
			(xy 99.47148 -282.896056) (xy 99.49434 -282.891738) (xy 99.699318 -282.5369) (xy 99.691698 -282.514802)
			(xy 99.683062 -282.488391) (xy 99.673735 -282.433617) (xy 99.673156 -282.405836) (xy 99.673664 -282.379949)
			(xy 99.681763 -282.328811) (xy 99.697762 -282.279571) (xy 99.721268 -282.233439) (xy 99.7517 -282.191552)
			(xy 99.78831 -282.154942) (xy 99.830197 -282.12451) (xy 99.876329 -282.101004) (xy 99.925569 -282.085005)
			(xy 99.976707 -282.076906) (xy 100.028481 -282.076906) (xy 100.079619 -282.085005) (xy 100.128859 -282.101004)
			(xy 100.174991 -282.12451) (xy 100.216878 -282.154942) (xy 100.253488 -282.191552) (xy 100.28392 -282.233439)
			(xy 100.307426 -282.279571) (xy 100.323425 -282.328811) (xy 100.331524 -282.379949) (xy 100.332032 -282.405836)
			(xy 101.552756 -282.405836) (xy 101.553216 -282.380501) (xy 101.560977 -282.33043) (xy 101.576305 -282.282135)
			(xy 101.598841 -282.236753) (xy 101.628054 -282.195352) (xy 101.663256 -282.158908) (xy 101.703619 -282.128277)
			(xy 101.748192 -282.104181) (xy 101.795927 -282.087187) (xy 101.820726 -282.081986) (xy 101.843586 -282.077668)
			(xy 102.048818 -281.722322) (xy 102.041198 -281.700478) (xy 102.03257 -281.674197) (xy 102.023258 -281.619675)
			(xy 102.022656 -281.59202) (xy 102.023164 -281.566113) (xy 102.03127 -281.514936) (xy 102.047282 -281.465657)
			(xy 102.070805 -281.41949) (xy 102.101261 -281.377571) (xy 102.137899 -281.340933) (xy 102.179818 -281.310477)
			(xy 102.225985 -281.286954) (xy 102.275264 -281.270942) (xy 102.326441 -281.262836) (xy 102.378255 -281.262836)
			(xy 102.429432 -281.270942) (xy 102.478711 -281.286954) (xy 102.524878 -281.310477) (xy 102.566797 -281.340933)
			(xy 102.603435 -281.377571) (xy 102.633891 -281.41949) (xy 102.657414 -281.465657) (xy 102.673426 -281.514936)
			(xy 102.681532 -281.566113) (xy 102.68204 -281.59202) (xy 102.681632 -281.617397) (xy 102.673859 -281.667553)
			(xy 102.658485 -281.715923) (xy 102.635873 -281.761362) (xy 102.606558 -281.802795) (xy 102.571235 -281.839241)
			(xy 102.53074 -281.869837) (xy 102.486031 -281.89386) (xy 102.438166 -281.910741) (xy 102.413308 -281.91587)
			(xy 102.390448 -281.920188) (xy 102.18547 -282.275026) (xy 102.193344 -282.297124) (xy 102.201911 -282.32348)
			(xy 102.211106 -282.378127) (xy 102.211632 -282.405836) (xy 102.211124 -282.431704) (xy 103.432652 -282.431704)
			(xy 103.432652 -282.379896) (xy 103.440757 -282.328725) (xy 103.456766 -282.279453) (xy 103.480287 -282.233291)
			(xy 103.510738 -282.191377) (xy 103.547372 -282.154742) (xy 103.589286 -282.12429) (xy 103.635447 -282.100769)
			(xy 103.684719 -282.084758) (xy 103.73589 -282.076653) (xy 103.761794 -282.076144) (xy 103.787307 -282.076611)
			(xy 103.837722 -282.084472) (xy 103.886325 -282.100007) (xy 103.931954 -282.122845) (xy 103.973519 -282.152441)
			(xy 104.010027 -282.188087) (xy 104.0257 -282.208224) (xy 104.437688 -282.208224) (xy 104.453375 -282.188099)
			(xy 104.489881 -282.152454) (xy 104.531443 -282.122858) (xy 104.577069 -282.10002) (xy 104.625669 -282.084484)
			(xy 104.676083 -282.076622) (xy 104.701594 -282.076144) (xy 104.727507 -282.076553) (xy 104.778694 -282.08466)
			(xy 104.827983 -282.100674) (xy 104.874159 -282.124201) (xy 104.916087 -282.154663) (xy 104.952733 -282.191308)
			(xy 104.983196 -282.233235) (xy 105.006724 -282.279412) (xy 105.022739 -282.3287) (xy 105.030846 -282.379887)
			(xy 105.030846 -282.431713) (xy 105.022739 -282.4829) (xy 105.006724 -282.532188) (xy 104.983196 -282.578365)
			(xy 104.952733 -282.620292) (xy 104.916087 -282.656937) (xy 104.874159 -282.687399) (xy 104.827983 -282.710926)
			(xy 104.778694 -282.72694) (xy 104.727507 -282.735047) (xy 104.701594 -282.735528) (xy 104.676083 -282.735041)
			(xy 104.625669 -282.72718) (xy 104.577068 -282.711647) (xy 104.53144 -282.688813) (xy 104.489874 -282.659222)
			(xy 104.453362 -282.623582) (xy 104.437688 -282.603448) (xy 104.0257 -282.603448) (xy 104.01004 -282.623594)
			(xy 103.973526 -282.659235) (xy 103.931957 -282.688826) (xy 103.886326 -282.71166) (xy 103.837723 -282.727192)
			(xy 103.787307 -282.735052) (xy 103.761794 -282.735528) (xy 103.73589 -282.734947) (xy 103.684719 -282.726842)
			(xy 103.635447 -282.710831) (xy 103.589286 -282.68731) (xy 103.547372 -282.656858) (xy 103.510738 -282.620223)
			(xy 103.480287 -282.578309) (xy 103.456766 -282.532147) (xy 103.440757 -282.482875) (xy 103.432652 -282.431704)
			(xy 102.211124 -282.431704) (xy 102.211124 -282.431723) (xy 102.203025 -282.482861) (xy 102.187026 -282.532101)
			(xy 102.16352 -282.578233) (xy 102.133088 -282.62012) (xy 102.096478 -282.65673) (xy 102.054591 -282.687162)
			(xy 102.008459 -282.710668) (xy 101.959219 -282.726667) (xy 101.908081 -282.734766) (xy 101.856307 -282.734766)
			(xy 101.805169 -282.726667) (xy 101.755929 -282.710668) (xy 101.709797 -282.687162) (xy 101.66791 -282.65673)
			(xy 101.6313 -282.62012) (xy 101.600868 -282.578233) (xy 101.577362 -282.532101) (xy 101.561363 -282.482861)
			(xy 101.553264 -282.431723) (xy 101.552756 -282.405836) (xy 100.332032 -282.405836) (xy 100.331594 -282.431161)
			(xy 100.323857 -282.481217) (xy 100.308554 -282.5295) (xy 100.286046 -282.574874) (xy 100.256862 -282.616272)
			(xy 100.22169 -282.652718) (xy 100.181356 -282.683356) (xy 100.136812 -282.707464) (xy 100.089103 -282.724474)
			(xy 100.064316 -282.729686) (xy 100.041456 -282.734004) (xy 99.836224 -283.089096) (xy 99.844098 -283.111194)
			(xy 99.852735 -283.137539) (xy 99.862052 -283.192188) (xy 99.86264 -283.219906) (xy 99.862132 -283.245791)
			(xy 101.083549 -283.245791) (xy 101.083549 -283.194009) (xy 101.091651 -283.142863) (xy 101.107654 -283.093616)
			(xy 101.131165 -283.047478) (xy 101.161604 -283.005586) (xy 101.198223 -282.968973) (xy 101.240119 -282.93854)
			(xy 101.28626 -282.915036) (xy 101.33551 -282.89904) (xy 101.386657 -282.890946) (xy 101.412548 -282.890468)
			(xy 101.43806 -282.890926) (xy 101.488475 -282.898793) (xy 101.537077 -282.914332) (xy 101.582705 -282.937172)
			(xy 101.62427 -282.966767) (xy 101.66078 -283.002412) (xy 101.676454 -283.022548) (xy 102.088442 -283.022548)
			(xy 102.104077 -283.002381) (xy 102.140596 -282.966741) (xy 102.18217 -282.937153) (xy 102.227806 -282.914323)
			(xy 102.276414 -282.898795) (xy 102.326834 -282.890941) (xy 102.352348 -282.890468) (xy 102.378233 -282.890967)
			(xy 102.429366 -282.899073) (xy 102.478601 -282.915077) (xy 102.524727 -282.938585) (xy 102.566608 -282.969019)
			(xy 102.603213 -283.005629) (xy 102.63364 -283.047514) (xy 102.657142 -283.093643) (xy 102.673139 -283.142881)
			(xy 102.681237 -283.194015) (xy 102.681237 -283.245785) (xy 102.673139 -283.296919) (xy 102.657142 -283.346157)
			(xy 102.63364 -283.392286) (xy 102.603213 -283.434171) (xy 102.566608 -283.470781) (xy 102.524727 -283.501215)
			(xy 102.478601 -283.524723) (xy 102.429366 -283.540727) (xy 102.378233 -283.548833) (xy 102.352348 -283.549344)
			(xy 102.326836 -283.548851) (xy 102.276422 -283.540996) (xy 102.227819 -283.525467) (xy 102.18219 -283.502633)
			(xy 102.140624 -283.473042) (xy 102.104115 -283.437399) (xy 102.088442 -283.417264) (xy 101.676454 -283.417264)
			(xy 101.660739 -283.437366) (xy 101.624239 -283.473014) (xy 101.582683 -283.502612) (xy 101.537062 -283.525454)
			(xy 101.488467 -283.540995) (xy 101.438058 -283.548863) (xy 101.412548 -283.549344) (xy 101.386657 -283.548854)
			(xy 101.33551 -283.54076) (xy 101.28626 -283.524764) (xy 101.240119 -283.50126) (xy 101.198223 -283.470827)
			(xy 101.161604 -283.434214) (xy 101.131165 -283.392322) (xy 101.107654 -283.346184) (xy 101.091651 -283.296937)
			(xy 101.083549 -283.245791) (xy 99.862132 -283.245791) (xy 99.862132 -283.245813) (xy 99.854026 -283.29699)
			(xy 99.838014 -283.346269) (xy 99.814491 -283.392436) (xy 99.784035 -283.434355) (xy 99.747397 -283.470993)
			(xy 99.705478 -283.501449) (xy 99.659311 -283.524972) (xy 99.610032 -283.540984) (xy 99.558855 -283.54909)
			(xy 99.507041 -283.54909) (xy 99.455864 -283.540984) (xy 99.406585 -283.524972) (xy 99.360418 -283.501449)
			(xy 99.318499 -283.470993) (xy 99.281861 -283.434355) (xy 99.251405 -283.392436) (xy 99.227882 -283.346269)
			(xy 99.21187 -283.29699) (xy 99.203764 -283.245813) (xy 99.203256 -283.219906) (xy 97.04324 -283.219906)
			(xy 97.042732 -283.245813) (xy 97.034626 -283.29699) (xy 97.018614 -283.346269) (xy 96.995091 -283.392436)
			(xy 96.964635 -283.434355) (xy 96.927997 -283.470993) (xy 96.886078 -283.501449) (xy 96.839911 -283.524972)
			(xy 96.790632 -283.540984) (xy 96.739455 -283.54909) (xy 96.687641 -283.54909) (xy 96.636464 -283.540984)
			(xy 96.587185 -283.524972) (xy 96.541018 -283.501449) (xy 96.499099 -283.470993) (xy 96.462461 -283.434355)
			(xy 96.432005 -283.392436) (xy 96.408482 -283.346269) (xy 96.39247 -283.29699) (xy 96.384364 -283.245813)
			(xy 96.383856 -283.219906) (xy 96.384448 -283.192189) (xy 96.393773 -283.137542) (xy 96.402398 -283.111194)
			(xy 96.410272 -283.089096) (xy 96.205294 -282.734004) (xy 96.18218 -282.729686) (xy 96.15736 -282.724514)
			(xy 96.109579 -282.707563) (xy 96.064958 -282.683494) (xy 96.024551 -282.652875) (xy 95.989309 -282.616428)
			(xy 95.960065 -282.575014) (xy 95.937508 -282.52961) (xy 95.922171 -282.481287) (xy 95.914416 -282.431185)
			(xy 95.913956 -282.405836) (xy 95.633032 -282.405836) (xy 95.632524 -282.431723) (xy 95.624425 -282.482861)
			(xy 95.608426 -282.532101) (xy 95.58492 -282.578233) (xy 95.554488 -282.62012) (xy 95.517878 -282.65673)
			(xy 95.475991 -282.687162) (xy 95.429859 -282.710668) (xy 95.380619 -282.726667) (xy 95.329481 -282.734766)
			(xy 95.277707 -282.734766) (xy 95.226569 -282.726667) (xy 95.177329 -282.710668) (xy 95.131197 -282.687162)
			(xy 95.08931 -282.65673) (xy 95.0527 -282.62012) (xy 95.022268 -282.578233) (xy 94.998762 -282.532101)
			(xy 94.982763 -282.482861) (xy 94.974664 -282.431723) (xy 94.974156 -282.405836) (xy 93.75394 -282.405836)
			(xy 93.753432 -282.431743) (xy 93.745326 -282.48292) (xy 93.729314 -282.532199) (xy 93.705791 -282.578366)
			(xy 93.675335 -282.620285) (xy 93.638697 -282.656923) (xy 93.596778 -282.687379) (xy 93.550611 -282.710902)
			(xy 93.501332 -282.726914) (xy 93.450155 -282.73502) (xy 93.398341 -282.73502) (xy 93.347164 -282.726914)
			(xy 93.297885 -282.710902) (xy 93.251718 -282.687379) (xy 93.209799 -282.656923) (xy 93.173161 -282.620285)
			(xy 93.142705 -282.578366) (xy 93.119182 -282.532199) (xy 93.10317 -282.48292) (xy 93.095064 -282.431743)
			(xy 93.094556 -282.405836) (xy 91.87434 -282.405836) (xy 91.873903 -282.431201) (xy 91.86615 -282.481333)
			(xy 91.850801 -282.529685) (xy 91.828221 -282.575111) (xy 91.798942 -282.616537) (xy 91.763657 -282.652984)
			(xy 91.723202 -282.683591) (xy 91.678531 -282.707632) (xy 91.630703 -282.724539) (xy 91.605862 -282.729686)
			(xy 91.583002 -282.734004) (xy 91.378024 -283.089096) (xy 91.385644 -283.11094) (xy 91.394193 -283.137235)
			(xy 91.40339 -283.191753) (xy 91.403932 -283.219398) (xy 91.403932 -283.219906) (xy 91.403424 -283.245787)
			(xy 92.625176 -283.245787) (xy 92.625176 -283.194013) (xy 92.633275 -283.142878) (xy 92.649273 -283.093638)
			(xy 92.672778 -283.047508) (xy 92.703209 -283.005622) (xy 92.739818 -282.969013) (xy 92.781703 -282.938581)
			(xy 92.827833 -282.915076) (xy 92.877072 -282.899076) (xy 92.928207 -282.890976) (xy 92.954094 -282.890468)
			(xy 92.979605 -282.890965) (xy 93.030018 -282.898824) (xy 93.078619 -282.914355) (xy 93.124247 -282.937187)
			(xy 93.165813 -282.966776) (xy 93.202325 -283.002415) (xy 93.218 -283.022548) (xy 93.629988 -283.022548)
			(xy 93.645654 -283.002407) (xy 93.682167 -282.966766) (xy 93.723734 -282.937174) (xy 93.769364 -282.91434)
			(xy 93.817967 -282.898806) (xy 93.868382 -282.890945) (xy 93.893894 -282.890468) (xy 93.919784 -282.890937)
			(xy 93.970927 -282.899036) (xy 94.020174 -282.915037) (xy 94.066311 -282.938544) (xy 94.108202 -282.968979)
			(xy 94.144817 -283.005593) (xy 94.175253 -283.047484) (xy 94.198761 -283.093621) (xy 94.214762 -283.142867)
			(xy 94.222863 -283.19401) (xy 94.222863 -283.24579) (xy 94.214762 -283.296933) (xy 94.198761 -283.346179)
			(xy 94.175253 -283.392316) (xy 94.144817 -283.434207) (xy 94.108202 -283.470821) (xy 94.066311 -283.501256)
			(xy 94.020174 -283.524763) (xy 93.970927 -283.540764) (xy 93.919784 -283.548863) (xy 93.893894 -283.549344)
			(xy 93.868381 -283.54889) (xy 93.817964 -283.541027) (xy 93.769361 -283.52549) (xy 93.723732 -283.502649)
			(xy 93.682168 -283.473051) (xy 93.64566 -283.437402) (xy 93.629988 -283.417264) (xy 93.218 -283.417264)
			(xy 93.202317 -283.437392) (xy 93.16581 -283.473038) (xy 93.124247 -283.502633) (xy 93.078621 -283.525471)
			(xy 93.03002 -283.541006) (xy 92.979606 -283.548867) (xy 92.954094 -283.549344) (xy 92.928207 -283.548824)
			(xy 92.877072 -283.540724) (xy 92.827833 -283.524724) (xy 92.781703 -283.501219) (xy 92.739818 -283.470787)
			(xy 92.703209 -283.434178) (xy 92.672778 -283.392292) (xy 92.649273 -283.346162) (xy 92.633275 -283.296922)
			(xy 92.625176 -283.245787) (xy 91.403424 -283.245787) (xy 91.403424 -283.245793) (xy 91.395325 -283.296931)
			(xy 91.379326 -283.346171) (xy 91.35582 -283.392303) (xy 91.325388 -283.43419) (xy 91.288778 -283.4708)
			(xy 91.246891 -283.501232) (xy 91.200759 -283.524738) (xy 91.151519 -283.540737) (xy 91.100381 -283.548836)
			(xy 91.048607 -283.548836) (xy 90.997469 -283.540737) (xy 90.948229 -283.524738) (xy 90.902097 -283.501232)
			(xy 90.86021 -283.4708) (xy 90.8236 -283.43419) (xy 90.793168 -283.392303) (xy 90.769662 -283.346171)
			(xy 90.753663 -283.296931) (xy 90.745564 -283.245793) (xy 90.745056 -283.219906) (xy 88.584532 -283.219906)
			(xy 88.584024 -283.245793) (xy 88.575925 -283.296931) (xy 88.559926 -283.346171) (xy 88.53642 -283.392303)
			(xy 88.505988 -283.43419) (xy 88.469378 -283.4708) (xy 88.427491 -283.501232) (xy 88.381359 -283.524738)
			(xy 88.332119 -283.540737) (xy 88.280981 -283.548836) (xy 88.229207 -283.548836) (xy 88.178069 -283.540737)
			(xy 88.128829 -283.524738) (xy 88.082697 -283.501232) (xy 88.04081 -283.4708) (xy 88.0042 -283.43419)
			(xy 87.973768 -283.392303) (xy 87.950262 -283.346171) (xy 87.934263 -283.296931) (xy 87.926164 -283.245793)
			(xy 87.925656 -283.219906) (xy 87.926189 -283.192198) (xy 87.935382 -283.137551) (xy 87.943944 -283.111194)
			(xy 87.951818 -283.089096) (xy 87.746586 -282.734004) (xy 87.723726 -282.729686) (xy 87.698938 -282.724431)
			(xy 87.651203 -282.70745) (xy 87.606628 -282.683364) (xy 87.566263 -282.652742) (xy 87.531059 -282.616304)
			(xy 87.501844 -282.574908) (xy 87.479308 -282.52953) (xy 87.463981 -282.481238) (xy 87.456223 -282.431169)
			(xy 87.455756 -282.405836) (xy 87.17534 -282.405836) (xy 87.174832 -282.431743) (xy 87.166726 -282.48292)
			(xy 87.150714 -282.532199) (xy 87.127191 -282.578366) (xy 87.096735 -282.620285) (xy 87.060097 -282.656923)
			(xy 87.018178 -282.687379) (xy 86.972011 -282.710902) (xy 86.922732 -282.726914) (xy 86.871555 -282.73502)
			(xy 86.819741 -282.73502) (xy 86.768564 -282.726914) (xy 86.719285 -282.710902) (xy 86.673118 -282.687379)
			(xy 86.631199 -282.656923) (xy 86.594561 -282.620285) (xy 86.564105 -282.578366) (xy 86.540582 -282.532199)
			(xy 86.52457 -282.48292) (xy 86.516464 -282.431743) (xy 86.515956 -282.405836) (xy 31.743142 -282.405836)
			(xy 31.743142 -284.033722) (xy 86.515956 -284.033722) (xy 86.516464 -284.007815) (xy 86.52457 -283.956638)
			(xy 86.540582 -283.907359) (xy 86.564105 -283.861192) (xy 86.594561 -283.819273) (xy 86.631199 -283.782635)
			(xy 86.673118 -283.752179) (xy 86.719285 -283.728656) (xy 86.768564 -283.712644) (xy 86.819741 -283.704538)
			(xy 86.871555 -283.704538) (xy 86.922732 -283.712644) (xy 86.972011 -283.728656) (xy 87.018178 -283.752179)
			(xy 87.060097 -283.782635) (xy 87.096735 -283.819273) (xy 87.127191 -283.861192) (xy 87.150714 -283.907359)
			(xy 87.166726 -283.956638) (xy 87.174832 -284.007815) (xy 87.17534 -284.033722) (xy 87.174755 -284.06144)
			(xy 87.165426 -284.116086) (xy 87.156798 -284.142434) (xy 87.148924 -284.164532) (xy 87.353902 -284.51937)
			(xy 87.376762 -284.523688) (xy 87.401564 -284.528882) (xy 87.449305 -284.545867) (xy 87.493884 -284.569958)
			(xy 87.534252 -284.600587) (xy 87.569457 -284.637033) (xy 87.598669 -284.678438) (xy 87.621201 -284.723825)
			(xy 87.636522 -284.772125) (xy 87.644271 -284.822202) (xy 87.644732 -284.847538) (xy 87.644224 -284.873425)
			(xy 87.636125 -284.924563) (xy 87.620126 -284.973803) (xy 87.59662 -285.019935) (xy 87.566188 -285.061822)
			(xy 87.529578 -285.098432) (xy 87.487691 -285.128864) (xy 87.441559 -285.15237) (xy 87.392319 -285.168369)
			(xy 87.341181 -285.176468) (xy 87.289407 -285.176468) (xy 87.238269 -285.168369) (xy 87.189029 -285.15237)
			(xy 87.142897 -285.128864) (xy 87.10101 -285.098432) (xy 87.0644 -285.061822) (xy 87.033968 -285.019935)
			(xy 87.010462 -284.973803) (xy 86.994463 -284.924563) (xy 86.986364 -284.873425) (xy 86.985856 -284.847538)
			(xy 86.986397 -284.81983) (xy 86.995584 -284.765184) (xy 87.004144 -284.738826) (xy 87.012018 -284.716728)
			(xy 86.80704 -284.36189) (xy 86.78418 -284.357572) (xy 86.759356 -284.352414) (xy 86.711575 -284.335461)
			(xy 86.666954 -284.311391) (xy 86.626545 -284.28077) (xy 86.591303 -284.244322) (xy 86.56206 -284.202906)
			(xy 86.539504 -284.1575) (xy 86.524169 -284.109175) (xy 86.516415 -284.059072) (xy 86.515956 -284.033722)
			(xy 31.743142 -284.033722) (xy 31.743142 -284.873384) (xy 85.106807 -284.873384) (xy 85.106807 -284.821616)
			(xy 85.114906 -284.770485) (xy 85.130903 -284.72125) (xy 85.154405 -284.675125) (xy 85.184833 -284.633243)
			(xy 85.221438 -284.596637) (xy 85.263319 -284.566208) (xy 85.309445 -284.542705) (xy 85.358679 -284.526707)
			(xy 85.40981 -284.518608) (xy 85.435694 -284.5181) (xy 85.461187 -284.518588) (xy 85.511565 -284.526449)
			(xy 85.560127 -284.541983) (xy 85.605714 -284.564818) (xy 85.647235 -284.594409) (xy 85.683698 -284.630049)
			(xy 85.699346 -284.65018) (xy 86.111842 -284.65018) (xy 86.127489 -284.630047) (xy 86.163951 -284.594407)
			(xy 86.205472 -284.564814) (xy 86.251059 -284.541976) (xy 86.299622 -284.526441) (xy 86.35 -284.518579)
			(xy 86.375494 -284.5181) (xy 86.401387 -284.518505) (xy 86.452535 -284.526605) (xy 86.501786 -284.542607)
			(xy 86.547927 -284.566116) (xy 86.589823 -284.596555) (xy 86.626441 -284.633172) (xy 86.65688 -284.675067)
			(xy 86.680391 -284.721208) (xy 86.696394 -284.770459) (xy 86.704495 -284.821607) (xy 86.704495 -284.873393)
			(xy 86.696394 -284.924541) (xy 86.680391 -284.973792) (xy 86.65688 -285.019933) (xy 86.626441 -285.061828)
			(xy 86.589823 -285.098445) (xy 86.547927 -285.128884) (xy 86.501786 -285.152393) (xy 86.452535 -285.168395)
			(xy 86.401387 -285.176495) (xy 86.375494 -285.176976) (xy 86.35 -285.176506) (xy 86.299621 -285.168643)
			(xy 86.251058 -285.153106) (xy 86.205471 -285.130267) (xy 86.16395 -285.100672) (xy 86.127489 -285.065029)
			(xy 86.111842 -285.044896) (xy 85.699346 -285.044896) (xy 85.683699 -285.065029) (xy 85.647238 -285.100671)
			(xy 85.605717 -285.130265) (xy 85.56013 -285.153102) (xy 85.511566 -285.168637) (xy 85.461188 -285.176498)
			(xy 85.435694 -285.176976) (xy 85.40981 -285.176392) (xy 85.358679 -285.168293) (xy 85.309445 -285.152295)
			(xy 85.263319 -285.128792) (xy 85.221438 -285.098363) (xy 85.184833 -285.061757) (xy 85.154405 -285.019875)
			(xy 85.130903 -284.97375) (xy 85.114906 -284.924515) (xy 85.106807 -284.873384) (xy 31.743142 -284.873384)
			(xy 31.743142 -285.661354) (xy 87.455756 -285.661354) (xy 87.456232 -285.63602) (xy 87.46399 -285.585949)
			(xy 87.479317 -285.537654) (xy 87.50185 -285.492273) (xy 87.531061 -285.450872) (xy 87.566261 -285.414427)
			(xy 87.606622 -285.383796) (xy 87.651194 -285.3597) (xy 87.698927 -285.342705) (xy 87.723726 -285.337504)
			(xy 87.746586 -285.333186) (xy 87.951564 -284.978094) (xy 87.943944 -284.95625) (xy 87.935376 -284.929894)
			(xy 87.926181 -284.875247) (xy 87.925656 -284.847538) (xy 87.926164 -284.821651) (xy 87.934263 -284.770513)
			(xy 87.950262 -284.721273) (xy 87.973768 -284.675141) (xy 88.0042 -284.633254) (xy 88.04081 -284.596644)
			(xy 88.082697 -284.566212) (xy 88.128829 -284.542706) (xy 88.178069 -284.526707) (xy 88.229207 -284.518608)
			(xy 88.280981 -284.518608) (xy 88.332119 -284.526707) (xy 88.381359 -284.542706) (xy 88.427491 -284.566212)
			(xy 88.469378 -284.596644) (xy 88.505988 -284.633254) (xy 88.53642 -284.675141) (xy 88.559926 -284.721273)
			(xy 88.575925 -284.770513) (xy 88.584024 -284.821651) (xy 88.584532 -284.847538) (xy 88.584058 -284.872872)
			(xy 88.576301 -284.922944) (xy 88.560975 -284.971239) (xy 88.538441 -285.016622) (xy 88.50923 -285.058022)
			(xy 88.47403 -285.094467) (xy 88.433668 -285.125098) (xy 88.389095 -285.149194) (xy 88.341361 -285.166187)
			(xy 88.316562 -285.171388) (xy 88.293702 -285.175706) (xy 88.088724 -285.530798) (xy 88.096344 -285.552642)
			(xy 88.104909 -285.578999) (xy 88.114106 -285.633646) (xy 88.114632 -285.661354) (xy 89.335356 -285.661354)
			(xy 89.335864 -285.635467) (xy 89.343963 -285.584329) (xy 89.359962 -285.535089) (xy 89.383468 -285.488957)
			(xy 89.4139 -285.44707) (xy 89.45051 -285.41046) (xy 89.492397 -285.380028) (xy 89.538529 -285.356522)
			(xy 89.587769 -285.340523) (xy 89.638907 -285.332424) (xy 89.690681 -285.332424) (xy 89.741819 -285.340523)
			(xy 89.791059 -285.356522) (xy 89.837191 -285.380028) (xy 89.879078 -285.41046) (xy 89.915688 -285.44707)
			(xy 89.94612 -285.488957) (xy 89.969626 -285.535089) (xy 89.985625 -285.584329) (xy 89.993724 -285.635467)
			(xy 89.994232 -285.661354) (xy 90.275156 -285.661354) (xy 90.27559 -285.636007) (xy 90.28337 -285.585913)
			(xy 90.298725 -285.537599) (xy 90.321292 -285.492204) (xy 90.35054 -285.450798) (xy 90.385779 -285.414354)
			(xy 90.426181 -285.383733) (xy 90.470793 -285.359656) (xy 90.518564 -285.342688) (xy 90.54338 -285.337504)
			(xy 90.56624 -285.333186) (xy 90.771218 -284.978348) (xy 90.763344 -284.956504) (xy 90.754767 -284.930085)
			(xy 90.745569 -284.87531) (xy 90.745056 -284.847538) (xy 90.745564 -284.821651) (xy 90.753663 -284.770513)
			(xy 90.769662 -284.721273) (xy 90.793168 -284.675141) (xy 90.8236 -284.633254) (xy 90.86021 -284.596644)
			(xy 90.902097 -284.566212) (xy 90.948229 -284.542706) (xy 90.997469 -284.526707) (xy 91.048607 -284.518608)
			(xy 91.100381 -284.518608) (xy 91.151519 -284.526707) (xy 91.200759 -284.542706) (xy 91.246891 -284.566212)
			(xy 91.288778 -284.596644) (xy 91.325388 -284.633254) (xy 91.35582 -284.675141) (xy 91.379326 -284.721273)
			(xy 91.395325 -284.770513) (xy 91.403424 -284.821651) (xy 91.403932 -284.847538) (xy 91.403458 -284.872872)
			(xy 91.395701 -284.922944) (xy 91.380375 -284.971239) (xy 91.357841 -285.016622) (xy 91.32863 -285.058022)
			(xy 91.29343 -285.094467) (xy 91.253068 -285.125098) (xy 91.208495 -285.149194) (xy 91.160761 -285.166187)
			(xy 91.135962 -285.171388) (xy 91.113102 -285.175706) (xy 90.908124 -285.530544) (xy 90.915998 -285.552642)
			(xy 90.924622 -285.57899) (xy 90.933948 -285.633636) (xy 90.93454 -285.661354) (xy 91.214956 -285.661354)
			(xy 91.215464 -285.635447) (xy 91.22357 -285.58427) (xy 91.239582 -285.534991) (xy 91.263105 -285.488824)
			(xy 91.293561 -285.446905) (xy 91.330199 -285.410267) (xy 91.372118 -285.379811) (xy 91.418285 -285.356288)
			(xy 91.467564 -285.340276) (xy 91.518741 -285.33217) (xy 91.570555 -285.33217) (xy 91.621732 -285.340276)
			(xy 91.671011 -285.356288) (xy 91.717178 -285.379811) (xy 91.759097 -285.410267) (xy 91.795735 -285.446905)
			(xy 91.826191 -285.488824) (xy 91.849714 -285.534991) (xy 91.865726 -285.58427) (xy 91.873832 -285.635447)
			(xy 91.87434 -285.661354) (xy 92.154756 -285.661354) (xy 92.155232 -285.63602) (xy 92.16299 -285.585949)
			(xy 92.178317 -285.537654) (xy 92.20085 -285.492273) (xy 92.230061 -285.450872) (xy 92.265261 -285.414427)
			(xy 92.305622 -285.383796) (xy 92.350194 -285.3597) (xy 92.397927 -285.342705) (xy 92.422726 -285.337504)
			(xy 92.445586 -285.333186) (xy 92.650818 -284.97784) (xy 92.643198 -284.955996) (xy 92.634574 -284.929714)
			(xy 92.625259 -284.875193) (xy 92.624656 -284.847538) (xy 92.625164 -284.821631) (xy 92.63327 -284.770454)
			(xy 92.649282 -284.721175) (xy 92.672805 -284.675008) (xy 92.703261 -284.633089) (xy 92.739899 -284.596451)
			(xy 92.781818 -284.565995) (xy 92.827985 -284.542472) (xy 92.877264 -284.52646) (xy 92.928441 -284.518354)
			(xy 92.980255 -284.518354) (xy 93.031432 -284.52646) (xy 93.080711 -284.542472) (xy 93.126878 -284.565995)
			(xy 93.168797 -284.596451) (xy 93.205435 -284.633089) (xy 93.235891 -284.675008) (xy 93.259414 -284.721175)
			(xy 93.275426 -284.770454) (xy 93.283532 -284.821631) (xy 93.28404 -284.847538) (xy 93.283648 -284.872916)
			(xy 93.275873 -284.923072) (xy 93.260496 -284.971442) (xy 93.237881 -285.016882) (xy 93.208565 -285.058314)
			(xy 93.17324 -285.09476) (xy 93.132743 -285.125356) (xy 93.088033 -285.149379) (xy 93.040166 -285.166259)
			(xy 93.015308 -285.171388) (xy 92.992448 -285.175706) (xy 92.78747 -285.530544) (xy 92.795344 -285.552642)
			(xy 92.803916 -285.578997) (xy 92.813107 -285.633645) (xy 92.813632 -285.661354) (xy 93.094556 -285.661354)
			(xy 93.095064 -285.635467) (xy 93.103163 -285.584329) (xy 93.119162 -285.535089) (xy 93.142668 -285.488957)
			(xy 93.1731 -285.44707) (xy 93.20971 -285.41046) (xy 93.251597 -285.380028) (xy 93.297729 -285.356522)
			(xy 93.346969 -285.340523) (xy 93.398107 -285.332424) (xy 93.449881 -285.332424) (xy 93.501019 -285.340523)
			(xy 93.550259 -285.356522) (xy 93.596391 -285.380028) (xy 93.638278 -285.41046) (xy 93.674888 -285.44707)
			(xy 93.70532 -285.488957) (xy 93.728826 -285.535089) (xy 93.744825 -285.584329) (xy 93.752924 -285.635467)
			(xy 93.753432 -285.661354) (xy 94.034356 -285.661354) (xy 94.034832 -285.63602) (xy 94.04259 -285.585949)
			(xy 94.057917 -285.537654) (xy 94.08045 -285.492273) (xy 94.109661 -285.450872) (xy 94.144861 -285.414427)
			(xy 94.185222 -285.383796) (xy 94.229794 -285.3597) (xy 94.277527 -285.342705) (xy 94.302326 -285.337504)
			(xy 94.325186 -285.333186) (xy 94.530418 -284.97784) (xy 94.522798 -284.955996) (xy 94.514174 -284.929714)
			(xy 94.504859 -284.875193) (xy 94.504256 -284.847538) (xy 94.504764 -284.821631) (xy 94.51287 -284.770454)
			(xy 94.528882 -284.721175) (xy 94.552405 -284.675008) (xy 94.582861 -284.633089) (xy 94.619499 -284.596451)
			(xy 94.661418 -284.565995) (xy 94.707585 -284.542472) (xy 94.756864 -284.52646) (xy 94.808041 -284.518354)
			(xy 94.859855 -284.518354) (xy 94.911032 -284.52646) (xy 94.960311 -284.542472) (xy 95.006478 -284.565995)
			(xy 95.048397 -284.596451) (xy 95.085035 -284.633089) (xy 95.115491 -284.675008) (xy 95.139014 -284.721175)
			(xy 95.155026 -284.770454) (xy 95.163132 -284.821631) (xy 95.16364 -284.847538) (xy 95.163248 -284.872916)
			(xy 95.155473 -284.923072) (xy 95.140096 -284.971442) (xy 95.117481 -285.016882) (xy 95.088165 -285.058314)
			(xy 95.05284 -285.09476) (xy 95.012343 -285.125356) (xy 94.967633 -285.149379) (xy 94.919766 -285.166259)
			(xy 94.894908 -285.171388) (xy 94.872048 -285.175706) (xy 94.66707 -285.530544) (xy 94.674944 -285.552642)
			(xy 94.683516 -285.578997) (xy 94.692707 -285.633645) (xy 94.693232 -285.661354) (xy 94.974156 -285.661354)
			(xy 94.974664 -285.635467) (xy 94.982763 -285.584329) (xy 94.998762 -285.535089) (xy 95.022268 -285.488957)
			(xy 95.0527 -285.44707) (xy 95.08931 -285.41046) (xy 95.131197 -285.380028) (xy 95.177329 -285.356522)
			(xy 95.226569 -285.340523) (xy 95.277707 -285.332424) (xy 95.329481 -285.332424) (xy 95.380619 -285.340523)
			(xy 95.429859 -285.356522) (xy 95.475991 -285.380028) (xy 95.517878 -285.41046) (xy 95.554488 -285.44707)
			(xy 95.58492 -285.488957) (xy 95.608426 -285.535089) (xy 95.624425 -285.584329) (xy 95.632524 -285.635467)
			(xy 95.633032 -285.661354) (xy 95.913956 -285.661354) (xy 95.914432 -285.63602) (xy 95.92219 -285.585949)
			(xy 95.937517 -285.537654) (xy 95.96005 -285.492273) (xy 95.989261 -285.450872) (xy 96.024461 -285.414427)
			(xy 96.064822 -285.383796) (xy 96.109394 -285.3597) (xy 96.157127 -285.342705) (xy 96.181926 -285.337504)
			(xy 96.204786 -285.333186) (xy 96.410018 -284.97784) (xy 96.402398 -284.955996) (xy 96.393774 -284.929714)
			(xy 96.384459 -284.875193) (xy 96.383856 -284.847538) (xy 96.384364 -284.821631) (xy 96.39247 -284.770454)
			(xy 96.408482 -284.721175) (xy 96.432005 -284.675008) (xy 96.462461 -284.633089) (xy 96.499099 -284.596451)
			(xy 96.541018 -284.565995) (xy 96.587185 -284.542472) (xy 96.636464 -284.52646) (xy 96.687641 -284.518354)
			(xy 96.739455 -284.518354) (xy 96.790632 -284.52646) (xy 96.839911 -284.542472) (xy 96.886078 -284.565995)
			(xy 96.927997 -284.596451) (xy 96.964635 -284.633089) (xy 96.995091 -284.675008) (xy 97.018614 -284.721175)
			(xy 97.034626 -284.770454) (xy 97.042732 -284.821631) (xy 97.04324 -284.847538) (xy 97.042848 -284.872916)
			(xy 97.035073 -284.923072) (xy 97.019696 -284.971442) (xy 96.997081 -285.016882) (xy 96.967765 -285.058314)
			(xy 96.93244 -285.09476) (xy 96.891943 -285.125356) (xy 96.847233 -285.149379) (xy 96.799366 -285.166259)
			(xy 96.774508 -285.171388) (xy 96.751648 -285.175706) (xy 96.54667 -285.530544) (xy 96.554544 -285.552642)
			(xy 96.563116 -285.578997) (xy 96.572307 -285.633645) (xy 96.572832 -285.661354) (xy 96.853756 -285.661354)
			(xy 96.854264 -285.635467) (xy 96.862363 -285.584329) (xy 96.878362 -285.535089) (xy 96.901868 -285.488957)
			(xy 96.9323 -285.44707) (xy 96.96891 -285.41046) (xy 97.010797 -285.380028) (xy 97.056929 -285.356522)
			(xy 97.106169 -285.340523) (xy 97.157307 -285.332424) (xy 97.209081 -285.332424) (xy 97.260219 -285.340523)
			(xy 97.309459 -285.356522) (xy 97.355591 -285.380028) (xy 97.397478 -285.41046) (xy 97.434088 -285.44707)
			(xy 97.46452 -285.488957) (xy 97.488026 -285.535089) (xy 97.504025 -285.584329) (xy 97.512124 -285.635467)
			(xy 97.512632 -285.661354) (xy 97.793556 -285.661354) (xy 97.794032 -285.63602) (xy 97.80179 -285.585949)
			(xy 97.817117 -285.537654) (xy 97.83965 -285.492273) (xy 97.868861 -285.450872) (xy 97.904061 -285.414427)
			(xy 97.944422 -285.383796) (xy 97.988994 -285.3597) (xy 98.036727 -285.342705) (xy 98.061526 -285.337504)
			(xy 98.084386 -285.333186) (xy 98.289618 -284.97784) (xy 98.281998 -284.955996) (xy 98.273374 -284.929714)
			(xy 98.264059 -284.875193) (xy 98.263456 -284.847538) (xy 98.263964 -284.821631) (xy 98.27207 -284.770454)
			(xy 98.288082 -284.721175) (xy 98.311605 -284.675008) (xy 98.342061 -284.633089) (xy 98.378699 -284.596451)
			(xy 98.420618 -284.565995) (xy 98.466785 -284.542472) (xy 98.516064 -284.52646) (xy 98.567241 -284.518354)
			(xy 98.619055 -284.518354) (xy 98.670232 -284.52646) (xy 98.719511 -284.542472) (xy 98.765678 -284.565995)
			(xy 98.807597 -284.596451) (xy 98.844235 -284.633089) (xy 98.874691 -284.675008) (xy 98.898214 -284.721175)
			(xy 98.914226 -284.770454) (xy 98.922332 -284.821631) (xy 98.92284 -284.847538) (xy 98.922448 -284.872916)
			(xy 98.914673 -284.923072) (xy 98.899296 -284.971442) (xy 98.876681 -285.016882) (xy 98.847365 -285.058314)
			(xy 98.81204 -285.09476) (xy 98.771543 -285.125356) (xy 98.726833 -285.149379) (xy 98.678966 -285.166259)
			(xy 98.654108 -285.171388) (xy 98.631248 -285.175706) (xy 98.42627 -285.530544) (xy 98.434144 -285.552642)
			(xy 98.442716 -285.578997) (xy 98.451907 -285.633645) (xy 98.452432 -285.661354) (xy 98.733356 -285.661354)
			(xy 98.733864 -285.635467) (xy 98.741963 -285.584329) (xy 98.757962 -285.535089) (xy 98.781468 -285.488957)
			(xy 98.8119 -285.44707) (xy 98.84851 -285.41046) (xy 98.890397 -285.380028) (xy 98.936529 -285.356522)
			(xy 98.985769 -285.340523) (xy 99.036907 -285.332424) (xy 99.088681 -285.332424) (xy 99.139819 -285.340523)
			(xy 99.189059 -285.356522) (xy 99.235191 -285.380028) (xy 99.277078 -285.41046) (xy 99.313688 -285.44707)
			(xy 99.34412 -285.488957) (xy 99.367626 -285.535089) (xy 99.383625 -285.584329) (xy 99.391724 -285.635467)
			(xy 99.392232 -285.661354) (xy 99.673156 -285.661354) (xy 99.673632 -285.63602) (xy 99.68139 -285.585949)
			(xy 99.696717 -285.537654) (xy 99.71925 -285.492273) (xy 99.748461 -285.450872) (xy 99.783661 -285.414427)
			(xy 99.824022 -285.383796) (xy 99.868594 -285.3597) (xy 99.916327 -285.342705) (xy 99.941126 -285.337504)
			(xy 99.963986 -285.333186) (xy 100.169218 -284.97784) (xy 100.161598 -284.955996) (xy 100.152974 -284.929714)
			(xy 100.143659 -284.875193) (xy 100.143056 -284.847538) (xy 100.143564 -284.821631) (xy 100.15167 -284.770454)
			(xy 100.167682 -284.721175) (xy 100.191205 -284.675008) (xy 100.221661 -284.633089) (xy 100.258299 -284.596451)
			(xy 100.300218 -284.565995) (xy 100.346385 -284.542472) (xy 100.395664 -284.52646) (xy 100.446841 -284.518354)
			(xy 100.498655 -284.518354) (xy 100.549832 -284.52646) (xy 100.599111 -284.542472) (xy 100.645278 -284.565995)
			(xy 100.687197 -284.596451) (xy 100.723835 -284.633089) (xy 100.754291 -284.675008) (xy 100.777814 -284.721175)
			(xy 100.793826 -284.770454) (xy 100.801932 -284.821631) (xy 100.80244 -284.847538) (xy 100.802048 -284.872916)
			(xy 100.794273 -284.923072) (xy 100.778896 -284.971442) (xy 100.756281 -285.016882) (xy 100.726965 -285.058314)
			(xy 100.69164 -285.09476) (xy 100.651143 -285.125356) (xy 100.606433 -285.149379) (xy 100.558566 -285.166259)
			(xy 100.533708 -285.171388) (xy 100.510848 -285.175706) (xy 100.30587 -285.530544) (xy 100.313744 -285.552642)
			(xy 100.322316 -285.578997) (xy 100.331507 -285.633645) (xy 100.332032 -285.661354) (xy 100.612956 -285.661354)
			(xy 100.613464 -285.635467) (xy 100.621563 -285.584329) (xy 100.637562 -285.535089) (xy 100.661068 -285.488957)
			(xy 100.6915 -285.44707) (xy 100.72811 -285.41046) (xy 100.769997 -285.380028) (xy 100.816129 -285.356522)
			(xy 100.865369 -285.340523) (xy 100.916507 -285.332424) (xy 100.968281 -285.332424) (xy 101.019419 -285.340523)
			(xy 101.068659 -285.356522) (xy 101.114791 -285.380028) (xy 101.156678 -285.41046) (xy 101.193288 -285.44707)
			(xy 101.22372 -285.488957) (xy 101.247226 -285.535089) (xy 101.263225 -285.584329) (xy 101.271324 -285.635467)
			(xy 101.271832 -285.661354) (xy 101.552756 -285.661354) (xy 101.553232 -285.63602) (xy 101.56099 -285.585949)
			(xy 101.576317 -285.537654) (xy 101.59885 -285.492273) (xy 101.628061 -285.450872) (xy 101.663261 -285.414427)
			(xy 101.703622 -285.383796) (xy 101.748194 -285.3597) (xy 101.795927 -285.342705) (xy 101.820726 -285.337504)
			(xy 101.843586 -285.333186) (xy 102.048818 -284.97784) (xy 102.041198 -284.955996) (xy 102.032574 -284.929714)
			(xy 102.023259 -284.875193) (xy 102.022656 -284.847538) (xy 102.023164 -284.821631) (xy 102.03127 -284.770454)
			(xy 102.047282 -284.721175) (xy 102.070805 -284.675008) (xy 102.101261 -284.633089) (xy 102.137899 -284.596451)
			(xy 102.179818 -284.565995) (xy 102.225985 -284.542472) (xy 102.275264 -284.52646) (xy 102.326441 -284.518354)
			(xy 102.378255 -284.518354) (xy 102.429432 -284.52646) (xy 102.478711 -284.542472) (xy 102.524878 -284.565995)
			(xy 102.566797 -284.596451) (xy 102.603435 -284.633089) (xy 102.633891 -284.675008) (xy 102.657414 -284.721175)
			(xy 102.673426 -284.770454) (xy 102.681532 -284.821631) (xy 102.68204 -284.847538) (xy 102.681648 -284.872916)
			(xy 102.673873 -284.923072) (xy 102.658496 -284.971442) (xy 102.635881 -285.016882) (xy 102.606565 -285.058314)
			(xy 102.57124 -285.09476) (xy 102.530743 -285.125356) (xy 102.486033 -285.149379) (xy 102.438166 -285.166259)
			(xy 102.413308 -285.171388) (xy 102.390448 -285.175706) (xy 102.18547 -285.530544) (xy 102.193344 -285.552642)
			(xy 102.201916 -285.578997) (xy 102.211107 -285.633645) (xy 102.211632 -285.661354) (xy 102.492556 -285.661354)
			(xy 102.493064 -285.635467) (xy 102.501163 -285.584329) (xy 102.517162 -285.535089) (xy 102.540668 -285.488957)
			(xy 102.5711 -285.44707) (xy 102.60771 -285.41046) (xy 102.649597 -285.380028) (xy 102.695729 -285.356522)
			(xy 102.744969 -285.340523) (xy 102.796107 -285.332424) (xy 102.847881 -285.332424) (xy 102.899019 -285.340523)
			(xy 102.948259 -285.356522) (xy 102.994391 -285.380028) (xy 103.036278 -285.41046) (xy 103.072888 -285.44707)
			(xy 103.10332 -285.488957) (xy 103.126826 -285.535089) (xy 103.142825 -285.584329) (xy 103.150924 -285.635467)
			(xy 103.151432 -285.661354) (xy 103.150885 -285.688998) (xy 103.141691 -285.743516) (xy 103.133144 -285.769812)
			(xy 103.125524 -285.79191) (xy 103.330756 -286.147256) (xy 103.353616 -286.151574) (xy 103.378427 -286.156786)
			(xy 103.426204 -286.173734) (xy 103.470823 -286.197799) (xy 103.51123 -286.228413) (xy 103.546472 -286.264855)
			(xy 103.575717 -286.306263) (xy 103.598276 -286.351662) (xy 103.613617 -286.399979) (xy 103.621377 -286.450077)
			(xy 103.62184 -286.475424) (xy 103.621332 -286.501331) (xy 103.613226 -286.552508) (xy 103.597214 -286.601787)
			(xy 103.573691 -286.647954) (xy 103.543235 -286.689873) (xy 103.506597 -286.726511) (xy 103.464678 -286.756967)
			(xy 103.418511 -286.78049) (xy 103.369232 -286.796502) (xy 103.318055 -286.804608) (xy 103.266241 -286.804608)
			(xy 103.215064 -286.796502) (xy 103.165785 -286.78049) (xy 103.119618 -286.756967) (xy 103.077699 -286.726511)
			(xy 103.041061 -286.689873) (xy 103.010605 -286.647954) (xy 102.987082 -286.601787) (xy 102.97107 -286.552508)
			(xy 102.962964 -286.501331) (xy 102.962456 -286.475424) (xy 102.963053 -286.447707) (xy 102.972374 -286.39306)
			(xy 102.980998 -286.366712) (xy 102.988872 -286.344614) (xy 102.783894 -285.989522) (xy 102.76078 -285.985204)
			(xy 102.735964 -285.980016) (xy 102.688184 -285.963065) (xy 102.643565 -285.938998) (xy 102.603157 -285.908381)
			(xy 102.567916 -285.871936) (xy 102.538671 -285.830525) (xy 102.516113 -285.785123) (xy 102.500775 -285.736802)
			(xy 102.493018 -285.686702) (xy 102.492556 -285.661354) (xy 102.211632 -285.661354) (xy 102.211124 -285.687241)
			(xy 102.203025 -285.738379) (xy 102.187026 -285.787619) (xy 102.16352 -285.833751) (xy 102.133088 -285.875638)
			(xy 102.096478 -285.912248) (xy 102.054591 -285.94268) (xy 102.008459 -285.966186) (xy 101.959219 -285.982185)
			(xy 101.908081 -285.990284) (xy 101.856307 -285.990284) (xy 101.805169 -285.982185) (xy 101.755929 -285.966186)
			(xy 101.709797 -285.94268) (xy 101.66791 -285.912248) (xy 101.6313 -285.875638) (xy 101.600868 -285.833751)
			(xy 101.577362 -285.787619) (xy 101.561363 -285.738379) (xy 101.553264 -285.687241) (xy 101.552756 -285.661354)
			(xy 101.271832 -285.661354) (xy 101.271285 -285.688998) (xy 101.262091 -285.743516) (xy 101.253544 -285.769812)
			(xy 101.245924 -285.79191) (xy 101.451156 -286.147256) (xy 101.474016 -286.151574) (xy 101.498827 -286.156786)
			(xy 101.546604 -286.173734) (xy 101.591223 -286.197799) (xy 101.63163 -286.228413) (xy 101.666872 -286.264855)
			(xy 101.696117 -286.306263) (xy 101.718676 -286.351662) (xy 101.734017 -286.399979) (xy 101.741777 -286.450077)
			(xy 101.74224 -286.475424) (xy 101.741732 -286.501331) (xy 101.733626 -286.552508) (xy 101.717614 -286.601787)
			(xy 101.694091 -286.647954) (xy 101.663635 -286.689873) (xy 101.626997 -286.726511) (xy 101.585078 -286.756967)
			(xy 101.538911 -286.78049) (xy 101.489632 -286.796502) (xy 101.438455 -286.804608) (xy 101.386641 -286.804608)
			(xy 101.335464 -286.796502) (xy 101.286185 -286.78049) (xy 101.240018 -286.756967) (xy 101.198099 -286.726511)
			(xy 101.161461 -286.689873) (xy 101.131005 -286.647954) (xy 101.107482 -286.601787) (xy 101.09147 -286.552508)
			(xy 101.083364 -286.501331) (xy 101.082856 -286.475424) (xy 101.083453 -286.447707) (xy 101.092774 -286.39306)
			(xy 101.101398 -286.366712) (xy 101.109272 -286.344614) (xy 100.904294 -285.989522) (xy 100.88118 -285.985204)
			(xy 100.856364 -285.980016) (xy 100.808584 -285.963065) (xy 100.763965 -285.938998) (xy 100.723557 -285.908381)
			(xy 100.688316 -285.871936) (xy 100.659071 -285.830525) (xy 100.636513 -285.785123) (xy 100.621175 -285.736802)
			(xy 100.613418 -285.686702) (xy 100.612956 -285.661354) (xy 100.332032 -285.661354) (xy 100.331524 -285.687241)
			(xy 100.323425 -285.738379) (xy 100.307426 -285.787619) (xy 100.28392 -285.833751) (xy 100.253488 -285.875638)
			(xy 100.216878 -285.912248) (xy 100.174991 -285.94268) (xy 100.128859 -285.966186) (xy 100.079619 -285.982185)
			(xy 100.028481 -285.990284) (xy 99.976707 -285.990284) (xy 99.925569 -285.982185) (xy 99.876329 -285.966186)
			(xy 99.830197 -285.94268) (xy 99.78831 -285.912248) (xy 99.7517 -285.875638) (xy 99.721268 -285.833751)
			(xy 99.697762 -285.787619) (xy 99.681763 -285.738379) (xy 99.673664 -285.687241) (xy 99.673156 -285.661354)
			(xy 99.392232 -285.661354) (xy 99.391685 -285.688998) (xy 99.382491 -285.743516) (xy 99.373944 -285.769812)
			(xy 99.366324 -285.79191) (xy 99.571556 -286.147256) (xy 99.594416 -286.151574) (xy 99.619227 -286.156786)
			(xy 99.667004 -286.173734) (xy 99.711623 -286.197799) (xy 99.75203 -286.228413) (xy 99.787272 -286.264855)
			(xy 99.816517 -286.306263) (xy 99.839076 -286.351662) (xy 99.854417 -286.399979) (xy 99.862177 -286.450077)
			(xy 99.86264 -286.475424) (xy 99.862132 -286.501331) (xy 99.854026 -286.552508) (xy 99.838014 -286.601787)
			(xy 99.814491 -286.647954) (xy 99.784035 -286.689873) (xy 99.747397 -286.726511) (xy 99.705478 -286.756967)
			(xy 99.659311 -286.78049) (xy 99.610032 -286.796502) (xy 99.558855 -286.804608) (xy 99.507041 -286.804608)
			(xy 99.455864 -286.796502) (xy 99.406585 -286.78049) (xy 99.360418 -286.756967) (xy 99.318499 -286.726511)
			(xy 99.281861 -286.689873) (xy 99.251405 -286.647954) (xy 99.227882 -286.601787) (xy 99.21187 -286.552508)
			(xy 99.203764 -286.501331) (xy 99.203256 -286.475424) (xy 99.203853 -286.447707) (xy 99.213174 -286.39306)
			(xy 99.221798 -286.366712) (xy 99.229672 -286.344614) (xy 99.024694 -285.989522) (xy 99.00158 -285.985204)
			(xy 98.976764 -285.980016) (xy 98.928984 -285.963065) (xy 98.884365 -285.938998) (xy 98.843957 -285.908381)
			(xy 98.808716 -285.871936) (xy 98.779471 -285.830525) (xy 98.756913 -285.785123) (xy 98.741575 -285.736802)
			(xy 98.733818 -285.686702) (xy 98.733356 -285.661354) (xy 98.452432 -285.661354) (xy 98.451924 -285.687241)
			(xy 98.443825 -285.738379) (xy 98.427826 -285.787619) (xy 98.40432 -285.833751) (xy 98.373888 -285.875638)
			(xy 98.337278 -285.912248) (xy 98.295391 -285.94268) (xy 98.249259 -285.966186) (xy 98.200019 -285.982185)
			(xy 98.148881 -285.990284) (xy 98.097107 -285.990284) (xy 98.045969 -285.982185) (xy 97.996729 -285.966186)
			(xy 97.950597 -285.94268) (xy 97.90871 -285.912248) (xy 97.8721 -285.875638) (xy 97.841668 -285.833751)
			(xy 97.818162 -285.787619) (xy 97.802163 -285.738379) (xy 97.794064 -285.687241) (xy 97.793556 -285.661354)
			(xy 97.512632 -285.661354) (xy 97.512085 -285.688998) (xy 97.502891 -285.743516) (xy 97.494344 -285.769812)
			(xy 97.486724 -285.79191) (xy 97.691956 -286.147256) (xy 97.714816 -286.151574) (xy 97.739627 -286.156786)
			(xy 97.787404 -286.173734) (xy 97.832023 -286.197799) (xy 97.87243 -286.228413) (xy 97.907672 -286.264855)
			(xy 97.936917 -286.306263) (xy 97.959476 -286.351662) (xy 97.974817 -286.399979) (xy 97.982577 -286.450077)
			(xy 97.98304 -286.475424) (xy 97.982532 -286.501331) (xy 97.974426 -286.552508) (xy 97.958414 -286.601787)
			(xy 97.934891 -286.647954) (xy 97.904435 -286.689873) (xy 97.867797 -286.726511) (xy 97.825878 -286.756967)
			(xy 97.779711 -286.78049) (xy 97.730432 -286.796502) (xy 97.679255 -286.804608) (xy 97.627441 -286.804608)
			(xy 97.576264 -286.796502) (xy 97.526985 -286.78049) (xy 97.480818 -286.756967) (xy 97.438899 -286.726511)
			(xy 97.402261 -286.689873) (xy 97.371805 -286.647954) (xy 97.348282 -286.601787) (xy 97.33227 -286.552508)
			(xy 97.324164 -286.501331) (xy 97.323656 -286.475424) (xy 97.324253 -286.447707) (xy 97.333574 -286.39306)
			(xy 97.342198 -286.366712) (xy 97.350072 -286.344614) (xy 97.145094 -285.989522) (xy 97.12198 -285.985204)
			(xy 97.097164 -285.980016) (xy 97.049384 -285.963065) (xy 97.004765 -285.938998) (xy 96.964357 -285.908381)
			(xy 96.929116 -285.871936) (xy 96.899871 -285.830525) (xy 96.877313 -285.785123) (xy 96.861975 -285.736802)
			(xy 96.854218 -285.686702) (xy 96.853756 -285.661354) (xy 96.572832 -285.661354) (xy 96.572324 -285.687241)
			(xy 96.564225 -285.738379) (xy 96.548226 -285.787619) (xy 96.52472 -285.833751) (xy 96.494288 -285.875638)
			(xy 96.457678 -285.912248) (xy 96.415791 -285.94268) (xy 96.369659 -285.966186) (xy 96.320419 -285.982185)
			(xy 96.269281 -285.990284) (xy 96.217507 -285.990284) (xy 96.166369 -285.982185) (xy 96.117129 -285.966186)
			(xy 96.070997 -285.94268) (xy 96.02911 -285.912248) (xy 95.9925 -285.875638) (xy 95.962068 -285.833751)
			(xy 95.938562 -285.787619) (xy 95.922563 -285.738379) (xy 95.914464 -285.687241) (xy 95.913956 -285.661354)
			(xy 95.633032 -285.661354) (xy 95.632485 -285.688998) (xy 95.623291 -285.743516) (xy 95.614744 -285.769812)
			(xy 95.607124 -285.79191) (xy 95.812356 -286.147256) (xy 95.835216 -286.151574) (xy 95.860027 -286.156786)
			(xy 95.907804 -286.173734) (xy 95.952423 -286.197799) (xy 95.99283 -286.228413) (xy 96.028072 -286.264855)
			(xy 96.057317 -286.306263) (xy 96.079876 -286.351662) (xy 96.095217 -286.399979) (xy 96.102977 -286.450077)
			(xy 96.10344 -286.475424) (xy 96.102932 -286.501331) (xy 96.094826 -286.552508) (xy 96.078814 -286.601787)
			(xy 96.055291 -286.647954) (xy 96.024835 -286.689873) (xy 95.988197 -286.726511) (xy 95.946278 -286.756967)
			(xy 95.900111 -286.78049) (xy 95.850832 -286.796502) (xy 95.799655 -286.804608) (xy 95.747841 -286.804608)
			(xy 95.696664 -286.796502) (xy 95.647385 -286.78049) (xy 95.601218 -286.756967) (xy 95.559299 -286.726511)
			(xy 95.522661 -286.689873) (xy 95.492205 -286.647954) (xy 95.468682 -286.601787) (xy 95.45267 -286.552508)
			(xy 95.444564 -286.501331) (xy 95.444056 -286.475424) (xy 95.444653 -286.447707) (xy 95.453974 -286.39306)
			(xy 95.462598 -286.366712) (xy 95.470472 -286.344614) (xy 95.265494 -285.989522) (xy 95.24238 -285.985204)
			(xy 95.217564 -285.980016) (xy 95.169784 -285.963065) (xy 95.125165 -285.938998) (xy 95.084757 -285.908381)
			(xy 95.049516 -285.871936) (xy 95.020271 -285.830525) (xy 94.997713 -285.785123) (xy 94.982375 -285.736802)
			(xy 94.974618 -285.686702) (xy 94.974156 -285.661354) (xy 94.693232 -285.661354) (xy 94.692724 -285.687241)
			(xy 94.684625 -285.738379) (xy 94.668626 -285.787619) (xy 94.64512 -285.833751) (xy 94.614688 -285.875638)
			(xy 94.578078 -285.912248) (xy 94.536191 -285.94268) (xy 94.490059 -285.966186) (xy 94.440819 -285.982185)
			(xy 94.389681 -285.990284) (xy 94.337907 -285.990284) (xy 94.286769 -285.982185) (xy 94.237529 -285.966186)
			(xy 94.191397 -285.94268) (xy 94.14951 -285.912248) (xy 94.1129 -285.875638) (xy 94.082468 -285.833751)
			(xy 94.058962 -285.787619) (xy 94.042963 -285.738379) (xy 94.034864 -285.687241) (xy 94.034356 -285.661354)
			(xy 93.753432 -285.661354) (xy 93.752885 -285.688998) (xy 93.743691 -285.743516) (xy 93.735144 -285.769812)
			(xy 93.727524 -285.79191) (xy 93.932756 -286.147256) (xy 93.955616 -286.151574) (xy 93.980427 -286.156786)
			(xy 94.028204 -286.173734) (xy 94.072823 -286.197799) (xy 94.11323 -286.228413) (xy 94.148472 -286.264855)
			(xy 94.177717 -286.306263) (xy 94.200276 -286.351662) (xy 94.215617 -286.399979) (xy 94.223377 -286.450077)
			(xy 94.22384 -286.475424) (xy 94.223332 -286.501331) (xy 94.215226 -286.552508) (xy 94.199214 -286.601787)
			(xy 94.175691 -286.647954) (xy 94.145235 -286.689873) (xy 94.108597 -286.726511) (xy 94.066678 -286.756967)
			(xy 94.020511 -286.78049) (xy 93.971232 -286.796502) (xy 93.920055 -286.804608) (xy 93.868241 -286.804608)
			(xy 93.817064 -286.796502) (xy 93.767785 -286.78049) (xy 93.721618 -286.756967) (xy 93.679699 -286.726511)
			(xy 93.643061 -286.689873) (xy 93.612605 -286.647954) (xy 93.589082 -286.601787) (xy 93.57307 -286.552508)
			(xy 93.564964 -286.501331) (xy 93.564456 -286.475424) (xy 93.565053 -286.447707) (xy 93.574374 -286.39306)
			(xy 93.582998 -286.366712) (xy 93.590872 -286.344614) (xy 93.385894 -285.989522) (xy 93.36278 -285.985204)
			(xy 93.337964 -285.980016) (xy 93.290184 -285.963065) (xy 93.245565 -285.938998) (xy 93.205157 -285.908381)
			(xy 93.169916 -285.871936) (xy 93.140671 -285.830525) (xy 93.118113 -285.785123) (xy 93.102775 -285.736802)
			(xy 93.095018 -285.686702) (xy 93.094556 -285.661354) (xy 92.813632 -285.661354) (xy 92.813124 -285.687241)
			(xy 92.805025 -285.738379) (xy 92.789026 -285.787619) (xy 92.76552 -285.833751) (xy 92.735088 -285.875638)
			(xy 92.698478 -285.912248) (xy 92.656591 -285.94268) (xy 92.610459 -285.966186) (xy 92.561219 -285.982185)
			(xy 92.510081 -285.990284) (xy 92.458307 -285.990284) (xy 92.407169 -285.982185) (xy 92.357929 -285.966186)
			(xy 92.311797 -285.94268) (xy 92.26991 -285.912248) (xy 92.2333 -285.875638) (xy 92.202868 -285.833751)
			(xy 92.179362 -285.787619) (xy 92.163363 -285.738379) (xy 92.155264 -285.687241) (xy 92.154756 -285.661354)
			(xy 91.87434 -285.661354) (xy 91.873738 -285.689071) (xy 91.86442 -285.743718) (xy 91.855798 -285.770066)
			(xy 91.847924 -285.792164) (xy 92.053156 -286.147256) (xy 92.076016 -286.151574) (xy 92.100827 -286.156786)
			(xy 92.148604 -286.173734) (xy 92.193223 -286.197799) (xy 92.23363 -286.228413) (xy 92.268872 -286.264855)
			(xy 92.298117 -286.306263) (xy 92.320676 -286.351662) (xy 92.336017 -286.399979) (xy 92.343777 -286.450077)
			(xy 92.34424 -286.475424) (xy 92.343732 -286.501331) (xy 92.335626 -286.552508) (xy 92.319614 -286.601787)
			(xy 92.296091 -286.647954) (xy 92.265635 -286.689873) (xy 92.228997 -286.726511) (xy 92.187078 -286.756967)
			(xy 92.140911 -286.78049) (xy 92.091632 -286.796502) (xy 92.040455 -286.804608) (xy 91.988641 -286.804608)
			(xy 91.937464 -286.796502) (xy 91.888185 -286.78049) (xy 91.842018 -286.756967) (xy 91.800099 -286.726511)
			(xy 91.763461 -286.689873) (xy 91.733005 -286.647954) (xy 91.709482 -286.601787) (xy 91.69347 -286.552508)
			(xy 91.685364 -286.501331) (xy 91.684856 -286.475424) (xy 91.685453 -286.447707) (xy 91.694774 -286.39306)
			(xy 91.703398 -286.366712) (xy 91.711272 -286.344614) (xy 91.50604 -285.989522) (xy 91.48318 -285.985204)
			(xy 91.458364 -285.980016) (xy 91.410584 -285.963065) (xy 91.365965 -285.938998) (xy 91.325557 -285.908381)
			(xy 91.290316 -285.871936) (xy 91.261071 -285.830525) (xy 91.238513 -285.785123) (xy 91.223175 -285.736802)
			(xy 91.215418 -285.686702) (xy 91.214956 -285.661354) (xy 90.93454 -285.661354) (xy 90.934032 -285.687261)
			(xy 90.925926 -285.738438) (xy 90.909914 -285.787717) (xy 90.886391 -285.833884) (xy 90.855935 -285.875803)
			(xy 90.819297 -285.912441) (xy 90.777378 -285.942897) (xy 90.731211 -285.96642) (xy 90.681932 -285.982432)
			(xy 90.630755 -285.990538) (xy 90.578941 -285.990538) (xy 90.527764 -285.982432) (xy 90.478485 -285.96642)
			(xy 90.432318 -285.942897) (xy 90.390399 -285.912441) (xy 90.353761 -285.875803) (xy 90.323305 -285.833884)
			(xy 90.299782 -285.787717) (xy 90.28377 -285.738438) (xy 90.275664 -285.687261) (xy 90.275156 -285.661354)
			(xy 89.994232 -285.661354) (xy 89.993689 -285.689062) (xy 89.984503 -285.743708) (xy 89.975944 -285.770066)
			(xy 89.96807 -285.792164) (xy 90.173302 -286.147256) (xy 90.196162 -286.151574) (xy 90.220961 -286.156781)
			(xy 90.268701 -286.173765) (xy 90.31328 -286.197855) (xy 90.353647 -286.228483) (xy 90.388851 -286.264927)
			(xy 90.418064 -286.30633) (xy 90.440597 -286.351715) (xy 90.455919 -286.400014) (xy 90.46367 -286.450088)
			(xy 90.464132 -286.475424) (xy 90.463624 -286.501311) (xy 90.455525 -286.552449) (xy 90.439526 -286.601689)
			(xy 90.41602 -286.647821) (xy 90.385588 -286.689708) (xy 90.348978 -286.726318) (xy 90.307091 -286.75675)
			(xy 90.260959 -286.780256) (xy 90.211719 -286.796255) (xy 90.160581 -286.804354) (xy 90.108807 -286.804354)
			(xy 90.057669 -286.796255) (xy 90.008429 -286.780256) (xy 89.962297 -286.75675) (xy 89.92041 -286.726318)
			(xy 89.8838 -286.689708) (xy 89.853368 -286.647821) (xy 89.829862 -286.601689) (xy 89.813863 -286.552449)
			(xy 89.805764 -286.501311) (xy 89.805256 -286.475424) (xy 89.805793 -286.447716) (xy 89.814983 -286.393069)
			(xy 89.823544 -286.366712) (xy 89.831418 -286.344614) (xy 89.626186 -285.989522) (xy 89.603326 -285.985204)
			(xy 89.57852 -285.980026) (xy 89.530779 -285.963039) (xy 89.486199 -285.938946) (xy 89.445832 -285.908314)
			(xy 89.410627 -285.871866) (xy 89.381416 -285.83046) (xy 89.358884 -285.785071) (xy 89.343564 -285.736769)
			(xy 89.335817 -285.686691) (xy 89.335356 -285.661354) (xy 88.114632 -285.661354) (xy 88.114124 -285.687241)
			(xy 88.106025 -285.738379) (xy 88.090026 -285.787619) (xy 88.06652 -285.833751) (xy 88.036088 -285.875638)
			(xy 87.999478 -285.912248) (xy 87.957591 -285.94268) (xy 87.911459 -285.966186) (xy 87.862219 -285.982185)
			(xy 87.811081 -285.990284) (xy 87.759307 -285.990284) (xy 87.708169 -285.982185) (xy 87.658929 -285.966186)
			(xy 87.612797 -285.94268) (xy 87.57091 -285.912248) (xy 87.5343 -285.875638) (xy 87.503868 -285.833751)
			(xy 87.480362 -285.787619) (xy 87.464363 -285.738379) (xy 87.456264 -285.687241) (xy 87.455756 -285.661354)
			(xy 31.743142 -285.661354) (xy 31.743142 -286.475424) (xy 86.046056 -286.475424) (xy 86.046564 -286.449537)
			(xy 86.054663 -286.398399) (xy 86.070662 -286.349159) (xy 86.094168 -286.303027) (xy 86.1246 -286.26114)
			(xy 86.16121 -286.22453) (xy 86.203097 -286.194098) (xy 86.249229 -286.170592) (xy 86.298469 -286.154593)
			(xy 86.349607 -286.146494) (xy 86.401381 -286.146494) (xy 86.452519 -286.154593) (xy 86.501759 -286.170592)
			(xy 86.547891 -286.194098) (xy 86.589778 -286.22453) (xy 86.626388 -286.26114) (xy 86.65682 -286.303027)
			(xy 86.680326 -286.349159) (xy 86.696325 -286.398399) (xy 86.704424 -286.449537) (xy 86.704932 -286.475424)
			(xy 86.704442 -286.501305) (xy 86.98614 -286.501305) (xy 86.98614 -286.449495) (xy 86.994245 -286.398322)
			(xy 87.010255 -286.349048) (xy 87.033776 -286.302885) (xy 87.064229 -286.260969) (xy 87.100864 -286.224333)
			(xy 87.142779 -286.193879) (xy 87.188942 -286.170357) (xy 87.238217 -286.154347) (xy 87.289389 -286.146241)
			(xy 87.315294 -286.145732) (xy 87.340788 -286.146208) (xy 87.391166 -286.154069) (xy 87.43973 -286.169604)
			(xy 87.485317 -286.192442) (xy 87.526838 -286.222037) (xy 87.563299 -286.257679) (xy 87.578946 -286.277812)
			(xy 87.991442 -286.277812) (xy 88.007098 -286.257686) (xy 88.043557 -286.222043) (xy 88.085076 -286.192449)
			(xy 88.130661 -286.16961) (xy 88.179224 -286.154073) (xy 88.229601 -286.146211) (xy 88.255094 -286.145732)
			(xy 88.281006 -286.146165) (xy 88.332191 -286.154271) (xy 88.381478 -286.170285) (xy 88.427653 -286.193811)
			(xy 88.469579 -286.224272) (xy 88.506224 -286.260916) (xy 88.536685 -286.302842) (xy 88.560213 -286.349016)
			(xy 88.576227 -286.398303) (xy 88.584334 -286.449488) (xy 88.584334 -286.501312) (xy 88.576227 -286.552497)
			(xy 88.560213 -286.601784) (xy 88.536685 -286.647958) (xy 88.506224 -286.689884) (xy 88.469579 -286.726528)
			(xy 88.427653 -286.756989) (xy 88.381478 -286.780515) (xy 88.332191 -286.796529) (xy 88.281006 -286.804635)
			(xy 88.255094 -286.805116) (xy 88.229601 -286.80463) (xy 88.179224 -286.796768) (xy 88.130661 -286.781233)
			(xy 88.085074 -286.758397) (xy 88.043553 -286.728806) (xy 88.007091 -286.693167) (xy 87.991442 -286.673036)
			(xy 87.578946 -286.673036) (xy 87.56331 -286.693178) (xy 87.526845 -286.728817) (xy 87.485322 -286.758409)
			(xy 87.439733 -286.781244) (xy 87.391168 -286.796778) (xy 87.340788 -286.804638) (xy 87.315294 -286.805116)
			(xy 87.289389 -286.804559) (xy 87.238217 -286.796453) (xy 87.188942 -286.780443) (xy 87.142779 -286.756921)
			(xy 87.100864 -286.726467) (xy 87.064229 -286.689831) (xy 87.033776 -286.647915) (xy 87.010255 -286.601752)
			(xy 86.994245 -286.552478) (xy 86.98614 -286.501305) (xy 86.704442 -286.501305) (xy 86.704407 -286.503132)
			(xy 86.695209 -286.557779) (xy 86.686644 -286.584136) (xy 86.679024 -286.60598) (xy 86.884002 -286.961072)
			(xy 86.906862 -286.96539) (xy 86.931665 -286.970582) (xy 86.979406 -286.987567) (xy 87.023985 -287.011659)
			(xy 87.064353 -287.042288) (xy 87.099557 -287.078734) (xy 87.12877 -287.120139) (xy 87.151302 -287.165526)
			(xy 87.166622 -287.213827) (xy 87.174371 -287.263904) (xy 87.174832 -287.28924) (xy 87.174324 -287.315127)
			(xy 87.166225 -287.366265) (xy 87.150226 -287.415505) (xy 87.12672 -287.461637) (xy 87.096288 -287.503524)
			(xy 87.059678 -287.540134) (xy 87.017791 -287.570566) (xy 86.971659 -287.594072) (xy 86.922419 -287.610071)
			(xy 86.871281 -287.61817) (xy 86.819507 -287.61817) (xy 86.768369 -287.610071) (xy 86.719129 -287.594072)
			(xy 86.672997 -287.570566) (xy 86.63111 -287.540134) (xy 86.5945 -287.503524) (xy 86.564068 -287.461637)
			(xy 86.540562 -287.415505) (xy 86.524563 -287.366265) (xy 86.516464 -287.315127) (xy 86.515956 -287.28924)
			(xy 86.516497 -287.261532) (xy 86.525685 -287.206886) (xy 86.534244 -287.180528) (xy 86.541864 -287.158684)
			(xy 86.336886 -286.803592) (xy 86.314026 -286.799274) (xy 86.289236 -286.79403) (xy 86.241499 -286.777048)
			(xy 86.196923 -286.752961) (xy 86.156558 -286.722338) (xy 86.121354 -286.685898) (xy 86.09214 -286.644501)
			(xy 86.069605 -286.599121) (xy 86.054278 -286.550828) (xy 86.046522 -286.500758) (xy 86.046056 -286.475424)
			(xy 31.743142 -286.475424) (xy 31.743142 -318.41567) (xy 33.585658 -320.258186) (xy 33.617916 -320.243454)
			(xy 33.641401 -320.233123) (xy 33.690591 -320.218547) (xy 33.741362 -320.211162) (xy 33.767014 -320.210688)
			(xy 33.794996 -320.211238) (xy 33.850272 -320.219995) (xy 33.903498 -320.23729) (xy 33.953362 -320.262699)
			(xy 33.998638 -320.295596) (xy 34.038211 -320.335169) (xy 34.071106 -320.380446) (xy 34.096513 -320.430312)
			(xy 34.113808 -320.483538) (xy 34.122563 -320.538813) (xy 34.123122 -320.566796) (xy 34.122678 -320.592451)
			(xy 34.115309 -320.643228) (xy 34.100708 -320.692416) (xy 34.090356 -320.715894) (xy 34.075624 -320.748152)
			(xy 36.479988 -323.152516) (xy 36.497253 -323.170555) (xy 36.525021 -323.212046) (xy 36.544143 -323.258164)
			(xy 36.553883 -323.307131) (xy 36.55441 -323.332094) (xy 36.55441 -341.442802) (xy 38.330632 -343.219024)
			(xy 58.817002 -343.219024)
		)
		(stroke
			(width 0)
			(type solid)
		)
		(fill yes)
		(layer "In8.Cu")
		(net "PVCCFA_EHV_FIVRA_CPU1")
	)
	(gr_poly
		(pts
			(xy 318.142874 -350.555306) (xy 318.142874 -339.272372) (xy 318.123647 -339.252729) (xy 318.090464 -339.20891)
			(xy 318.063913 -339.160782) (xy 318.044544 -339.109342) (xy 318.032758 -339.055655) (xy 318.028799 -339.000832)
			(xy 318.032748 -338.946009) (xy 318.044525 -338.89232) (xy 318.063886 -338.840876) (xy 318.090428 -338.792744)
			(xy 318.123604 -338.74892) (xy 318.142874 -338.72932) (xy 318.142874 -332.950058) (xy 318.143489 -332.925103)
			(xy 318.153233 -332.876153) (xy 318.172338 -332.830043) (xy 318.20007 -332.788546) (xy 318.217296 -332.77048)
			(xy 318.669162 -332.318614) (xy 318.687202 -332.301353) (xy 318.728695 -332.273592) (xy 318.774813 -332.254478)
			(xy 318.823778 -332.244747) (xy 318.84874 -332.244192) (xy 321.8815 -332.244192) (xy 322.221098 -331.904594)
			(xy 322.221098 -296.86885) (xy 322.221714 -296.843895) (xy 322.23146 -296.794947) (xy 322.250567 -296.748839)
			(xy 322.278302 -296.707345) (xy 322.29552 -296.689272) (xy 330.118212 -288.86658) (xy 330.136252 -288.849317)
			(xy 330.177744 -288.821552) (xy 330.223862 -288.802431) (xy 330.272827 -288.792691) (xy 330.29779 -288.792158)
			(xy 335.419954 -288.792158) (xy 335.434178 -288.76498) (xy 335.446448 -288.742575) (xy 335.476852 -288.701528)
			(xy 335.513247 -288.665687) (xy 335.554756 -288.635918) (xy 335.600375 -288.612938) (xy 335.649004 -288.597302)
			(xy 335.699468 -288.589389) (xy 335.750548 -288.589389) (xy 335.801012 -288.597302) (xy 335.849641 -288.612938)
			(xy 335.89526 -288.635918) (xy 335.936769 -288.665687) (xy 335.973164 -288.701528) (xy 336.003568 -288.742575)
			(xy 336.015838 -288.76498) (xy 336.030062 -288.792158) (xy 336.358738 -288.792158) (xy 336.372962 -288.764726)
			(xy 336.384825 -288.742926) (xy 336.414096 -288.702849) (xy 336.449047 -288.667617) (xy 336.488889 -288.638026)
			(xy 336.532719 -288.614747) (xy 336.579546 -288.598307) (xy 336.603848 -288.593276) (xy 336.626708 -288.588958)
			(xy 336.831686 -288.233866) (xy 336.823812 -288.212022) (xy 336.815234 -288.185603) (xy 336.806039 -288.130828)
			(xy 336.805524 -288.103056) (xy 336.806032 -288.077169) (xy 336.814131 -288.026031) (xy 336.83013 -287.976791)
			(xy 336.853636 -287.930659) (xy 336.884068 -287.888772) (xy 336.920678 -287.852162) (xy 336.962565 -287.82173)
			(xy 337.008697 -287.798224) (xy 337.057937 -287.782225) (xy 337.109075 -287.774126) (xy 337.160849 -287.774126)
			(xy 337.211987 -287.782225) (xy 337.261227 -287.798224) (xy 337.307359 -287.82173) (xy 337.349246 -287.852162)
			(xy 337.385856 -287.888772) (xy 337.416288 -287.930659) (xy 337.439794 -287.976791) (xy 337.455793 -288.026031)
			(xy 337.463892 -288.077169) (xy 337.4644 -288.103056) (xy 337.463939 -288.128394) (xy 337.456192 -288.178474)
			(xy 337.440873 -288.226779) (xy 337.418343 -288.272171) (xy 337.389133 -288.313581) (xy 337.35393 -288.350034)
			(xy 337.313564 -288.380672) (xy 337.268986 -288.404772) (xy 337.221244 -288.421767) (xy 337.19643 -288.426906)
			(xy 337.17357 -288.431224) (xy 337.053174 -288.639758) (xy 337.046049 -288.653227) (xy 337.039261 -288.682916)
			(xy 337.041521 -288.713287) (xy 337.052628 -288.741644) (xy 337.071596 -288.765471) (xy 337.09674 -288.782654)
			(xy 337.125831 -288.791666) (xy 337.141058 -288.792158) (xy 337.299554 -288.792158) (xy 337.313778 -288.76498)
			(xy 337.326048 -288.742575) (xy 337.356452 -288.701528) (xy 337.392847 -288.665687) (xy 337.434356 -288.635918)
			(xy 337.479975 -288.612938) (xy 337.528604 -288.597302) (xy 337.579068 -288.589389) (xy 337.630148 -288.589389)
			(xy 337.680612 -288.597302) (xy 337.729241 -288.612938) (xy 337.77486 -288.635918) (xy 337.816369 -288.665687)
			(xy 337.852764 -288.701528) (xy 337.883168 -288.742575) (xy 337.895438 -288.76498) (xy 337.909662 -288.792158)
			(xy 338.238338 -288.792158) (xy 338.252562 -288.764726) (xy 338.264425 -288.742926) (xy 338.293696 -288.702849)
			(xy 338.328647 -288.667617) (xy 338.368489 -288.638026) (xy 338.412319 -288.614747) (xy 338.459146 -288.598307)
			(xy 338.483448 -288.593276) (xy 338.506308 -288.588958) (xy 338.711286 -288.233866) (xy 338.703412 -288.212022)
			(xy 338.694834 -288.185603) (xy 338.685639 -288.130828) (xy 338.685124 -288.103056) (xy 338.685632 -288.077169)
			(xy 338.693731 -288.026031) (xy 338.70973 -287.976791) (xy 338.733236 -287.930659) (xy 338.763668 -287.888772)
			(xy 338.800278 -287.852162) (xy 338.842165 -287.82173) (xy 338.888297 -287.798224) (xy 338.937537 -287.782225)
			(xy 338.988675 -287.774126) (xy 339.040449 -287.774126) (xy 339.091587 -287.782225) (xy 339.140827 -287.798224)
			(xy 339.186959 -287.82173) (xy 339.228846 -287.852162) (xy 339.265456 -287.888772) (xy 339.295888 -287.930659)
			(xy 339.319394 -287.976791) (xy 339.335393 -288.026031) (xy 339.343492 -288.077169) (xy 339.344 -288.103056)
			(xy 339.343539 -288.128394) (xy 339.335792 -288.178474) (xy 339.320473 -288.226779) (xy 339.297943 -288.272171)
			(xy 339.268733 -288.313581) (xy 339.23353 -288.350034) (xy 339.193164 -288.380672) (xy 339.148586 -288.404772)
			(xy 339.100844 -288.421767) (xy 339.07603 -288.426906) (xy 339.05317 -288.431224) (xy 338.932774 -288.639758)
			(xy 338.925649 -288.653227) (xy 338.918861 -288.682916) (xy 338.921121 -288.713287) (xy 338.932228 -288.741644)
			(xy 338.951196 -288.765471) (xy 338.97634 -288.782654) (xy 339.005431 -288.791666) (xy 339.020658 -288.792158)
			(xy 339.178138 -288.792158) (xy 339.192362 -288.764726) (xy 339.204677 -288.742186) (xy 339.235214 -288.700891)
			(xy 339.271791 -288.664836) (xy 339.31352 -288.634895) (xy 339.35939 -288.611793) (xy 339.408291 -288.59609)
			(xy 339.459036 -288.588167) (xy 339.484716 -288.587688) (xy 339.510393 -288.588165) (xy 339.561131 -288.596103)
			(xy 339.610022 -288.611817) (xy 339.655883 -288.634925) (xy 339.697605 -288.664869) (xy 339.734175 -288.700922)
			(xy 339.76471 -288.742213) (xy 339.77707 -288.764726) (xy 339.791294 -288.792158) (xy 340.117938 -288.792158)
			(xy 340.132162 -288.764726) (xy 340.144025 -288.742926) (xy 340.173296 -288.702849) (xy 340.208247 -288.667617)
			(xy 340.248089 -288.638026) (xy 340.291919 -288.614747) (xy 340.338746 -288.598307) (xy 340.363048 -288.593276)
			(xy 340.385908 -288.588958) (xy 340.59114 -288.233866) (xy 340.583266 -288.211768) (xy 340.574644 -288.185419)
			(xy 340.565327 -288.130773) (xy 340.564724 -288.103056) (xy 340.565232 -288.077149) (xy 340.573338 -288.025972)
			(xy 340.58935 -287.976693) (xy 340.612873 -287.930526) (xy 340.643329 -287.888607) (xy 340.679967 -287.851969)
			(xy 340.721886 -287.821513) (xy 340.768053 -287.79799) (xy 340.817332 -287.781978) (xy 340.868509 -287.773872)
			(xy 340.920323 -287.773872) (xy 340.9715 -287.781978) (xy 341.020779 -287.79799) (xy 341.066946 -287.821513)
			(xy 341.108865 -287.851969) (xy 341.145503 -287.888607) (xy 341.175959 -287.930526) (xy 341.199482 -287.976693)
			(xy 341.215494 -288.025972) (xy 341.2236 -288.077149) (xy 341.224108 -288.103056) (xy 341.223646 -288.128406)
			(xy 341.215889 -288.178508) (xy 341.200552 -288.226832) (xy 341.177996 -288.272238) (xy 341.148753 -288.313654)
			(xy 341.113513 -288.350104) (xy 341.073107 -288.380727) (xy 341.028489 -288.404803) (xy 340.98071 -288.421762)
			(xy 340.955884 -288.426906) (xy 340.933024 -288.431224) (xy 340.812628 -288.639758) (xy 340.8055 -288.653225)
			(xy 340.798709 -288.68291) (xy 340.800967 -288.713279) (xy 340.812075 -288.741633) (xy 340.831046 -288.765454)
			(xy 340.856194 -288.782628) (xy 340.885286 -288.791627) (xy 340.900512 -288.792158) (xy 341.057738 -288.792158)
			(xy 341.071962 -288.764726) (xy 341.084277 -288.742186) (xy 341.114814 -288.700891) (xy 341.151391 -288.664836)
			(xy 341.19312 -288.634895) (xy 341.23899 -288.611793) (xy 341.287891 -288.59609) (xy 341.338636 -288.588167)
			(xy 341.364316 -288.587688) (xy 341.389993 -288.588165) (xy 341.440731 -288.596103) (xy 341.489622 -288.611817)
			(xy 341.535483 -288.634925) (xy 341.577205 -288.664869) (xy 341.613775 -288.700922) (xy 341.64431 -288.742213)
			(xy 341.65667 -288.764726) (xy 341.670894 -288.792158) (xy 341.997538 -288.792158) (xy 342.011762 -288.764726)
			(xy 342.023625 -288.742926) (xy 342.052896 -288.702849) (xy 342.087847 -288.667617) (xy 342.127689 -288.638026)
			(xy 342.171519 -288.614747) (xy 342.218346 -288.598307) (xy 342.242648 -288.593276) (xy 342.265508 -288.588958)
			(xy 342.47074 -288.233866) (xy 342.462866 -288.211768) (xy 342.454244 -288.185419) (xy 342.444927 -288.130773)
			(xy 342.444324 -288.103056) (xy 342.444832 -288.077149) (xy 342.452938 -288.025972) (xy 342.46895 -287.976693)
			(xy 342.492473 -287.930526) (xy 342.522929 -287.888607) (xy 342.559567 -287.851969) (xy 342.601486 -287.821513)
			(xy 342.647653 -287.79799) (xy 342.696932 -287.781978) (xy 342.748109 -287.773872) (xy 342.799923 -287.773872)
			(xy 342.8511 -287.781978) (xy 342.900379 -287.79799) (xy 342.946546 -287.821513) (xy 342.988465 -287.851969)
			(xy 343.025103 -287.888607) (xy 343.055559 -287.930526) (xy 343.079082 -287.976693) (xy 343.095094 -288.025972)
			(xy 343.1032 -288.077149) (xy 343.103708 -288.103056) (xy 343.103246 -288.128406) (xy 343.095489 -288.178508)
			(xy 343.080152 -288.226832) (xy 343.057596 -288.272238) (xy 343.028353 -288.313654) (xy 342.993113 -288.350104)
			(xy 342.952707 -288.380727) (xy 342.908089 -288.404803) (xy 342.86031 -288.421762) (xy 342.835484 -288.426906)
			(xy 342.812624 -288.431224) (xy 342.692228 -288.639758) (xy 342.6851 -288.653225) (xy 342.678309 -288.68291)
			(xy 342.680567 -288.713279) (xy 342.691675 -288.741633) (xy 342.710646 -288.765454) (xy 342.735794 -288.782628)
			(xy 342.764886 -288.791627) (xy 342.780112 -288.792158) (xy 342.937338 -288.792158) (xy 342.951562 -288.764726)
			(xy 342.963877 -288.742186) (xy 342.994414 -288.700891) (xy 343.030991 -288.664836) (xy 343.07272 -288.634895)
			(xy 343.11859 -288.611793) (xy 343.167491 -288.59609) (xy 343.218236 -288.588167) (xy 343.243916 -288.587688)
			(xy 343.269593 -288.588165) (xy 343.320331 -288.596103) (xy 343.369222 -288.611817) (xy 343.415083 -288.634925)
			(xy 343.456805 -288.664869) (xy 343.493375 -288.700922) (xy 343.52391 -288.742213) (xy 343.53627 -288.764726)
			(xy 343.550494 -288.792158) (xy 343.877138 -288.792158) (xy 343.891362 -288.764726) (xy 343.903225 -288.742926)
			(xy 343.932496 -288.702849) (xy 343.967447 -288.667617) (xy 344.007289 -288.638026) (xy 344.051119 -288.614747)
			(xy 344.097946 -288.598307) (xy 344.122248 -288.593276) (xy 344.145108 -288.588958) (xy 344.35034 -288.233866)
			(xy 344.342466 -288.211768) (xy 344.333844 -288.185419) (xy 344.324527 -288.130773) (xy 344.323924 -288.103056)
			(xy 344.324432 -288.077149) (xy 344.332538 -288.025972) (xy 344.34855 -287.976693) (xy 344.372073 -287.930526)
			(xy 344.402529 -287.888607) (xy 344.439167 -287.851969) (xy 344.481086 -287.821513) (xy 344.527253 -287.79799)
			(xy 344.576532 -287.781978) (xy 344.627709 -287.773872) (xy 344.679523 -287.773872) (xy 344.7307 -287.781978)
			(xy 344.779979 -287.79799) (xy 344.826146 -287.821513) (xy 344.868065 -287.851969) (xy 344.904703 -287.888607)
			(xy 344.935159 -287.930526) (xy 344.958682 -287.976693) (xy 344.974694 -288.025972) (xy 344.9828 -288.077149)
			(xy 344.983308 -288.103056) (xy 344.982846 -288.128406) (xy 344.975089 -288.178508) (xy 344.959752 -288.226832)
			(xy 344.937196 -288.272238) (xy 344.907953 -288.313654) (xy 344.872713 -288.350104) (xy 344.832307 -288.380727)
			(xy 344.787689 -288.404803) (xy 344.73991 -288.421762) (xy 344.715084 -288.426906) (xy 344.692224 -288.431224)
			(xy 344.571828 -288.639758) (xy 344.5647 -288.653225) (xy 344.557909 -288.68291) (xy 344.560167 -288.713279)
			(xy 344.571275 -288.741633) (xy 344.590246 -288.765454) (xy 344.615394 -288.782628) (xy 344.644486 -288.791627)
			(xy 344.659712 -288.792158) (xy 344.816938 -288.792158) (xy 344.831162 -288.764726) (xy 344.843477 -288.742186)
			(xy 344.874014 -288.700891) (xy 344.910591 -288.664836) (xy 344.95232 -288.634895) (xy 344.99819 -288.611793)
			(xy 345.047091 -288.59609) (xy 345.097836 -288.588167) (xy 345.123516 -288.587688) (xy 345.149193 -288.588165)
			(xy 345.199931 -288.596103) (xy 345.248822 -288.611817) (xy 345.294683 -288.634925) (xy 345.336405 -288.664869)
			(xy 345.372975 -288.700922) (xy 345.40351 -288.742213) (xy 345.41587 -288.764726) (xy 345.430094 -288.792158)
			(xy 345.756738 -288.792158) (xy 345.770962 -288.764726) (xy 345.782825 -288.742926) (xy 345.812096 -288.702849)
			(xy 345.847047 -288.667617) (xy 345.886889 -288.638026) (xy 345.930719 -288.614747) (xy 345.977546 -288.598307)
			(xy 346.001848 -288.593276) (xy 346.024708 -288.588958) (xy 346.22994 -288.233866) (xy 346.222066 -288.211768)
			(xy 346.213444 -288.185419) (xy 346.204127 -288.130773) (xy 346.203524 -288.103056) (xy 346.204032 -288.077149)
			(xy 346.212138 -288.025972) (xy 346.22815 -287.976693) (xy 346.251673 -287.930526) (xy 346.282129 -287.888607)
			(xy 346.318767 -287.851969) (xy 346.360686 -287.821513) (xy 346.406853 -287.79799) (xy 346.456132 -287.781978)
			(xy 346.507309 -287.773872) (xy 346.559123 -287.773872) (xy 346.6103 -287.781978) (xy 346.659579 -287.79799)
			(xy 346.705746 -287.821513) (xy 346.747665 -287.851969) (xy 346.784303 -287.888607) (xy 346.814759 -287.930526)
			(xy 346.838282 -287.976693) (xy 346.854294 -288.025972) (xy 346.8624 -288.077149) (xy 346.862908 -288.103056)
			(xy 346.862446 -288.128406) (xy 346.854689 -288.178508) (xy 346.839352 -288.226832) (xy 346.816796 -288.272238)
			(xy 346.787553 -288.313654) (xy 346.752313 -288.350104) (xy 346.711907 -288.380727) (xy 346.667289 -288.404803)
			(xy 346.61951 -288.421762) (xy 346.594684 -288.426906) (xy 346.571824 -288.431224) (xy 346.451428 -288.639758)
			(xy 346.4443 -288.653225) (xy 346.437509 -288.68291) (xy 346.439767 -288.713279) (xy 346.450875 -288.741633)
			(xy 346.469846 -288.765454) (xy 346.494994 -288.782628) (xy 346.524086 -288.791627) (xy 346.539312 -288.792158)
			(xy 346.696538 -288.792158) (xy 346.710762 -288.764726) (xy 346.723077 -288.742186) (xy 346.753614 -288.700891)
			(xy 346.790191 -288.664836) (xy 346.83192 -288.634895) (xy 346.87779 -288.611793) (xy 346.926691 -288.59609)
			(xy 346.977436 -288.588167) (xy 347.003116 -288.587688) (xy 347.028793 -288.588165) (xy 347.079531 -288.596103)
			(xy 347.128422 -288.611817) (xy 347.174283 -288.634925) (xy 347.216005 -288.664869) (xy 347.252575 -288.700922)
			(xy 347.28311 -288.742213) (xy 347.29547 -288.764726) (xy 347.309694 -288.792158) (xy 347.636338 -288.792158)
			(xy 347.650562 -288.764726) (xy 347.662425 -288.742926) (xy 347.691696 -288.702849) (xy 347.726647 -288.667617)
			(xy 347.766489 -288.638026) (xy 347.810319 -288.614747) (xy 347.857146 -288.598307) (xy 347.881448 -288.593276)
			(xy 347.904308 -288.588958) (xy 348.10954 -288.233866) (xy 348.101666 -288.211768) (xy 348.093044 -288.185419)
			(xy 348.083727 -288.130773) (xy 348.083124 -288.103056) (xy 348.083632 -288.077149) (xy 348.091738 -288.025972)
			(xy 348.10775 -287.976693) (xy 348.131273 -287.930526) (xy 348.161729 -287.888607) (xy 348.198367 -287.851969)
			(xy 348.240286 -287.821513) (xy 348.286453 -287.79799) (xy 348.335732 -287.781978) (xy 348.386909 -287.773872)
			(xy 348.438723 -287.773872) (xy 348.4899 -287.781978) (xy 348.539179 -287.79799) (xy 348.585346 -287.821513)
			(xy 348.627265 -287.851969) (xy 348.663903 -287.888607) (xy 348.694359 -287.930526) (xy 348.717882 -287.976693)
			(xy 348.733894 -288.025972) (xy 348.742 -288.077149) (xy 348.742508 -288.103056) (xy 348.742046 -288.128406)
			(xy 348.734289 -288.178508) (xy 348.718952 -288.226832) (xy 348.696396 -288.272238) (xy 348.667153 -288.313654)
			(xy 348.631913 -288.350104) (xy 348.591507 -288.380727) (xy 348.546889 -288.404803) (xy 348.49911 -288.421762)
			(xy 348.474284 -288.426906) (xy 348.451424 -288.431224) (xy 348.331028 -288.639758) (xy 348.3239 -288.653225)
			(xy 348.317109 -288.68291) (xy 348.319367 -288.713279) (xy 348.330475 -288.741633) (xy 348.349446 -288.765454)
			(xy 348.374594 -288.782628) (xy 348.403686 -288.791627) (xy 348.418912 -288.792158) (xy 348.576138 -288.792158)
			(xy 348.590362 -288.764726) (xy 348.602677 -288.742186) (xy 348.633214 -288.700891) (xy 348.669791 -288.664836)
			(xy 348.71152 -288.634895) (xy 348.75739 -288.611793) (xy 348.806291 -288.59609) (xy 348.857036 -288.588167)
			(xy 348.882716 -288.587688) (xy 348.908393 -288.588165) (xy 348.959131 -288.596103) (xy 349.008022 -288.611817)
			(xy 349.053883 -288.634925) (xy 349.095605 -288.664869) (xy 349.132175 -288.700922) (xy 349.16271 -288.742213)
			(xy 349.17507 -288.764726) (xy 349.189294 -288.792158) (xy 349.515938 -288.792158) (xy 349.530162 -288.764726)
			(xy 349.542025 -288.742926) (xy 349.571296 -288.702849) (xy 349.606247 -288.667617) (xy 349.646089 -288.638026)
			(xy 349.689919 -288.614747) (xy 349.736746 -288.598307) (xy 349.761048 -288.593276) (xy 349.783908 -288.588958)
			(xy 349.98914 -288.233866) (xy 349.981266 -288.211768) (xy 349.972644 -288.185419) (xy 349.963327 -288.130773)
			(xy 349.962724 -288.103056) (xy 349.963232 -288.077149) (xy 349.971338 -288.025972) (xy 349.98735 -287.976693)
			(xy 350.010873 -287.930526) (xy 350.041329 -287.888607) (xy 350.077967 -287.851969) (xy 350.119886 -287.821513)
			(xy 350.166053 -287.79799) (xy 350.215332 -287.781978) (xy 350.266509 -287.773872) (xy 350.318323 -287.773872)
			(xy 350.3695 -287.781978) (xy 350.418779 -287.79799) (xy 350.464946 -287.821513) (xy 350.506865 -287.851969)
			(xy 350.543503 -287.888607) (xy 350.573959 -287.930526) (xy 350.597482 -287.976693) (xy 350.613494 -288.025972)
			(xy 350.6216 -288.077149) (xy 350.622108 -288.103056) (xy 350.621646 -288.128406) (xy 350.613889 -288.178508)
			(xy 350.598552 -288.226832) (xy 350.575996 -288.272238) (xy 350.546753 -288.313654) (xy 350.511513 -288.350104)
			(xy 350.471107 -288.380727) (xy 350.426489 -288.404803) (xy 350.37871 -288.421762) (xy 350.353884 -288.426906)
			(xy 350.331024 -288.431224) (xy 350.210628 -288.639758) (xy 350.2035 -288.653225) (xy 350.196709 -288.68291)
			(xy 350.198967 -288.713279) (xy 350.210075 -288.741633) (xy 350.229046 -288.765454) (xy 350.254194 -288.782628)
			(xy 350.283286 -288.791627) (xy 350.298512 -288.792158) (xy 350.455738 -288.792158) (xy 350.469962 -288.764726)
			(xy 350.482277 -288.742186) (xy 350.512814 -288.700891) (xy 350.549391 -288.664836) (xy 350.59112 -288.634895)
			(xy 350.63699 -288.611793) (xy 350.685891 -288.59609) (xy 350.736636 -288.588167) (xy 350.762316 -288.587688)
			(xy 350.787993 -288.588165) (xy 350.838731 -288.596103) (xy 350.887622 -288.611817) (xy 350.933483 -288.634925)
			(xy 350.975205 -288.664869) (xy 351.011775 -288.700922) (xy 351.04231 -288.742213) (xy 351.05467 -288.764726)
			(xy 351.068894 -288.792158) (xy 351.323148 -288.792158) (xy 351.85096 -288.264346) (xy 351.86874 -288.233866)
			(xy 351.860866 -288.211768) (xy 351.852244 -288.185419) (xy 351.842927 -288.130773) (xy 351.842324 -288.103056)
			(xy 351.842813 -288.077) (xy 351.851006 -288.025536) (xy 351.867194 -287.976003) (xy 351.890976 -287.929634)
			(xy 351.921759 -287.887585) (xy 351.958775 -287.850905) (xy 352.001103 -287.820507) (xy 352.024188 -287.808416)
			(xy 352.052128 -287.794446) (xy 352.052128 -286.78251) (xy 352.024188 -286.76854) (xy 352.001272 -286.756454)
			(xy 351.959236 -286.726174) (xy 351.922479 -286.689666) (xy 351.891913 -286.647837) (xy 351.868299 -286.601726)
			(xy 351.852222 -286.552477) (xy 351.844081 -286.501314) (xy 351.844079 -286.449508) (xy 351.852217 -286.398344)
			(xy 351.86829 -286.349094) (xy 351.891902 -286.302981) (xy 351.922465 -286.26115) (xy 351.959219 -286.22464)
			(xy 352.001253 -286.194357) (xy 352.024188 -286.182308) (xy 352.052128 -286.168338) (xy 352.052128 -286.013652)
			(xy 352.051649 -285.999744) (xy 352.044136 -285.972962) (xy 352.02968 -285.949197) (xy 352.009352 -285.930209)
			(xy 351.984658 -285.917406) (xy 351.957425 -285.911736) (xy 351.929673 -285.913618) (xy 351.903456 -285.922913)
			(xy 351.891854 -285.930594) (xy 351.870886 -285.9448) (xy 351.825513 -285.967299) (xy 351.777234 -285.982601)
			(xy 351.727185 -285.990348) (xy 351.701862 -285.990792) (xy 351.675976 -285.990308) (xy 351.624842 -285.982203)
			(xy 351.575605 -285.966198) (xy 351.529478 -285.942689) (xy 351.487597 -285.912252) (xy 351.450993 -285.875639)
			(xy 351.420568 -285.83375) (xy 351.397069 -285.787617) (xy 351.381077 -285.738377) (xy 351.372985 -285.68724)
			(xy 351.372424 -285.661354) (xy 351.372884 -285.636016) (xy 351.38063 -285.585936) (xy 351.395949 -285.537631)
			(xy 351.418479 -285.492239) (xy 351.44769 -285.450829) (xy 351.482893 -285.414377) (xy 351.52326 -285.383742)
			(xy 351.567839 -285.359644) (xy 351.615581 -285.342651) (xy 351.640394 -285.337504) (xy 351.663254 -285.333186)
			(xy 351.868486 -284.97784) (xy 351.860866 -284.955996) (xy 351.852258 -284.929709) (xy 351.842937 -284.875191)
			(xy 351.842324 -284.847538) (xy 351.842815 -284.821483) (xy 351.851009 -284.770021) (xy 351.8672 -284.720489)
			(xy 351.890983 -284.674123) (xy 351.921767 -284.632077) (xy 351.958783 -284.595399) (xy 352.00111 -284.565003)
			(xy 352.024188 -284.552898) (xy 352.052128 -284.538928) (xy 352.052128 -283.765498) (xy 352.0527 -283.740538)
			(xy 352.06244 -283.691577) (xy 352.081546 -283.645457) (xy 352.109283 -283.603952) (xy 352.12655 -283.58592)
			(xy 353.255072 -282.457398) (xy 353.25304 -282.433776) (xy 353.252024 -282.405836) (xy 353.252529 -282.37994)
			(xy 353.260622 -282.328784) (xy 353.276615 -282.279524) (xy 353.300115 -282.23337) (xy 353.330542 -282.191458)
			(xy 353.36715 -282.154821) (xy 353.409036 -282.124358) (xy 353.45517 -282.10082) (xy 353.504417 -282.084786)
			(xy 353.555566 -282.07665) (xy 353.581462 -282.076144) (xy 353.609402 -282.077414) (xy 353.633024 -282.079446)
			(xy 353.817174 -281.895296) (xy 353.823854 -281.887884) (xy 353.831444 -281.869454) (xy 353.831439 -281.849521)
			(xy 353.82384 -281.831094) (xy 353.817174 -281.823668) (xy 353.799439 -281.80505) (xy 353.769386 -281.763332)
			(xy 353.746182 -281.71745) (xy 353.730391 -281.668519) (xy 353.722396 -281.617728) (xy 353.721924 -281.59202)
			(xy 353.722404 -281.56611) (xy 353.730508 -281.514928) (xy 353.746519 -281.465643) (xy 353.770044 -281.419471)
			(xy 353.800502 -281.377547) (xy 353.837144 -281.340905) (xy 353.879067 -281.310446) (xy 353.92524 -281.286921)
			(xy 353.974524 -281.270909) (xy 354.025706 -281.262804) (xy 354.051616 -281.262328) (xy 354.07732 -281.262843)
			(xy 354.128101 -281.270859) (xy 354.177025 -281.28665) (xy 354.22291 -281.309832) (xy 354.264648 -281.339847)
			(xy 354.283264 -281.357578) (xy 354.290676 -281.364262) (xy 354.309109 -281.371859) (xy 354.329047 -281.371859)
			(xy 354.34748 -281.364262) (xy 354.354892 -281.357578) (xy 354.454206 -281.258264) (xy 354.464285 -281.247476)
			(xy 354.478315 -281.221514) (xy 354.484345 -281.192626) (xy 354.481872 -281.163219) (xy 354.471103 -281.135744)
			(xy 354.452934 -281.11249) (xy 354.42888 -281.095393) (xy 354.41509 -281.090116) (xy 354.391813 -281.08175)
			(xy 354.347875 -281.059035) (xy 354.307824 -281.03001) (xy 354.27256 -280.995327) (xy 354.257356 -280.975816)
			(xy 353.845368 -280.975816) (xy 353.829693 -280.995949) (xy 353.793182 -281.031588) (xy 353.751616 -281.061176)
			(xy 353.705987 -281.084006) (xy 353.657386 -281.099535) (xy 353.606973 -281.107389) (xy 353.581462 -281.107896)
			(xy 353.555556 -281.107385) (xy 353.504384 -281.099274) (xy 353.455109 -281.083259) (xy 353.408947 -281.059734)
			(xy 353.367033 -281.029277) (xy 353.330399 -280.992638) (xy 353.299947 -280.950721) (xy 353.276426 -280.904555)
			(xy 353.260417 -280.855279) (xy 353.252312 -280.804106) (xy 353.252312 -280.752294) (xy 353.260417 -280.701121)
			(xy 353.276426 -280.651845) (xy 353.299947 -280.605679) (xy 353.330399 -280.563762) (xy 353.367033 -280.527123)
			(xy 353.408947 -280.496666) (xy 353.455109 -280.473141) (xy 353.504384 -280.457126) (xy 353.555556 -280.449015)
			(xy 353.581462 -280.448512) (xy 353.606975 -280.448987) (xy 353.657393 -280.456843) (xy 353.705999 -280.472373)
			(xy 353.751631 -280.495206) (xy 353.793201 -280.524797) (xy 353.829715 -280.56044) (xy 353.845368 -280.580592)
			(xy 354.257356 -280.580592) (xy 354.273028 -280.560454) (xy 354.309537 -280.524806) (xy 354.351102 -280.495208)
			(xy 354.39673 -280.472366) (xy 354.445333 -280.456827) (xy 354.495749 -280.44896) (xy 354.521262 -280.448512)
			(xy 354.546879 -280.448996) (xy 354.597495 -280.456922) (xy 354.646274 -280.472591) (xy 354.692039 -280.495622)
			(xy 354.733685 -280.525462) (xy 354.77021 -280.56139) (xy 354.80073 -280.60254) (xy 354.824512 -280.64792)
			(xy 354.833174 -280.672032) (xy 354.838398 -280.685846) (xy 354.855496 -280.709912) (xy 354.878759 -280.728088)
			(xy 354.906246 -280.738858) (xy 354.935665 -280.741322) (xy 354.964561 -280.735277) (xy 354.990524 -280.721225)
			(xy 355.001322 -280.711148) (xy 355.625146 -280.087324) (xy 355.61651 -280.058114) (xy 355.61009 -280.035152)
			(xy 355.603203 -279.987973) (xy 355.602794 -279.964134) (xy 355.603288 -279.938123) (xy 355.611487 -279.88675)
			(xy 355.627684 -279.837314) (xy 355.651476 -279.79105) (xy 355.682266 -279.749118) (xy 355.719283 -279.712566)
			(xy 355.761602 -279.682309) (xy 355.784658 -279.670256) (xy 355.812852 -279.656286) (xy 355.812852 -278.64562)
			(xy 355.784658 -278.63165) (xy 355.761456 -278.619586) (xy 355.718864 -278.589247) (xy 355.681599 -278.552561)
			(xy 355.650599 -278.510448) (xy 355.62664 -278.463967) (xy 355.610325 -278.414284) (xy 355.602064 -278.362648)
			(xy 355.601524 -278.336502) (xy 355.602112 -278.308784) (xy 355.611428 -278.254135) (xy 355.620066 -278.22779)
			(xy 355.62794 -278.205692) (xy 355.422962 -277.8506) (xy 355.399848 -277.846282) (xy 355.375034 -277.841096)
			(xy 355.327268 -277.824125) (xy 355.282661 -277.800045) (xy 355.242265 -277.769422) (xy 355.20703 -277.732979)
			(xy 355.177787 -277.691573) (xy 355.155225 -277.64618) (xy 355.139874 -277.597869) (xy 355.132097 -277.547777)
			(xy 355.131624 -277.522432) (xy 355.132129 -277.496536) (xy 355.140223 -277.445381) (xy 355.156216 -277.396121)
			(xy 355.179716 -277.349967) (xy 355.210144 -277.308057) (xy 355.246751 -277.27142) (xy 355.288637 -277.240957)
			(xy 355.334771 -277.21742) (xy 355.384018 -277.201386) (xy 355.435167 -277.19325) (xy 355.461062 -277.19274)
			(xy 355.486585 -277.193217) (xy 355.53702 -277.201087) (xy 355.585638 -277.216643) (xy 355.631273 -277.239514)
			(xy 355.652324 -277.253954) (xy 355.663908 -277.261668) (xy 355.690091 -277.271077) (xy 355.717842 -277.273067)
			(xy 355.7451 -277.26749) (xy 355.769839 -277.25476) (xy 355.790223 -277.235824) (xy 355.804737 -277.212088)
			(xy 355.812302 -277.185314) (xy 355.812852 -277.171404) (xy 355.812852 -277.01621) (xy 355.784658 -277.00224)
			(xy 355.761628 -276.990194) (xy 355.719366 -276.959948) (xy 355.682399 -276.92342) (xy 355.651651 -276.881522)
			(xy 355.62789 -276.835301) (xy 355.611712 -276.785913) (xy 355.60352 -276.734592) (xy 355.603519 -276.682622)
			(xy 355.611709 -276.631301) (xy 355.627885 -276.581912) (xy 355.651643 -276.535691) (xy 355.682389 -276.493791)
			(xy 355.719355 -276.457261) (xy 355.761616 -276.427013) (xy 355.784658 -276.414992) (xy 355.812852 -276.401022)
			(xy 355.812852 -276.245828) (xy 355.812385 -276.231912) (xy 355.804802 -276.205131) (xy 355.790272 -276.181391)
			(xy 355.769875 -276.162452) (xy 355.745123 -276.149721) (xy 355.717854 -276.144142) (xy 355.690091 -276.146129)
			(xy 355.663895 -276.155535) (xy 355.652324 -276.163278) (xy 355.631266 -276.177707) (xy 355.585633 -276.200582)
			(xy 355.537018 -276.216147) (xy 355.486585 -276.224028) (xy 355.461062 -276.224492) (xy 355.435551 -276.224012)
			(xy 355.38514 -276.216146) (xy 355.336542 -276.200608) (xy 355.290918 -276.177769) (xy 355.249357 -276.148173)
			(xy 355.212852 -276.112529) (xy 355.197156 -276.092412) (xy 354.785168 -276.092412) (xy 354.769494 -276.112545)
			(xy 354.732982 -276.148184) (xy 354.691416 -276.177773) (xy 354.645788 -276.200604) (xy 354.597186 -276.216132)
			(xy 354.546773 -276.223987) (xy 354.521262 -276.224492) (xy 354.495357 -276.223981) (xy 354.444185 -276.21587)
			(xy 354.394911 -276.199855) (xy 354.348749 -276.17633) (xy 354.306835 -276.145874) (xy 354.270202 -276.109236)
			(xy 354.23975 -276.067318) (xy 354.21623 -276.021154) (xy 354.200221 -275.971878) (xy 354.192116 -275.920705)
			(xy 354.192116 -275.868895) (xy 354.200221 -275.817722) (xy 354.21623 -275.768446) (xy 354.23975 -275.722282)
			(xy 354.270202 -275.680364) (xy 354.306835 -275.643726) (xy 354.348749 -275.61327) (xy 354.394911 -275.589745)
			(xy 354.444185 -275.57373) (xy 354.495357 -275.565619) (xy 354.521262 -275.565108) (xy 354.546775 -275.565583)
			(xy 354.597193 -275.573438) (xy 354.645799 -275.588968) (xy 354.691432 -275.611801) (xy 354.733002 -275.641392)
			(xy 354.769516 -275.677035) (xy 354.785168 -275.697188) (xy 355.197156 -275.697188) (xy 355.212829 -275.677051)
			(xy 355.249337 -275.641403) (xy 355.290902 -275.611805) (xy 355.336531 -275.588964) (xy 355.385133 -275.573424)
			(xy 355.435549 -275.565557) (xy 355.461062 -275.565108) (xy 355.486585 -275.565584) (xy 355.537021 -275.573453)
			(xy 355.585639 -275.589009) (xy 355.631276 -275.611878) (xy 355.652324 -275.626322) (xy 355.663907 -275.634038)
			(xy 355.690088 -275.643449) (xy 355.717838 -275.645441) (xy 355.745095 -275.639864) (xy 355.769832 -275.627133)
			(xy 355.790213 -275.608195) (xy 355.804722 -275.584457) (xy 355.812281 -275.557682) (xy 355.812852 -275.543772)
			(xy 355.812852 -275.389848) (xy 355.784658 -275.375878) (xy 355.761453 -275.363814) (xy 355.718857 -275.333474)
			(xy 355.681588 -275.296786) (xy 355.650583 -275.254671) (xy 355.626621 -275.208187) (xy 355.610303 -275.158502)
			(xy 355.602039 -275.106862) (xy 355.602037 -275.054565) (xy 355.610297 -275.002924) (xy 355.626611 -274.953237)
			(xy 355.650569 -274.906751) (xy 355.681571 -274.864634) (xy 355.718836 -274.827943) (xy 355.761431 -274.7976)
			(xy 355.784658 -274.785582) (xy 355.812852 -274.771612) (xy 355.812852 -273.760692) (xy 355.784658 -273.746722)
			(xy 355.76163 -273.734676) (xy 355.71937 -273.704431) (xy 355.682405 -273.667903) (xy 355.65166 -273.626006)
			(xy 355.627902 -273.579787) (xy 355.611726 -273.530401) (xy 355.603535 -273.479083) (xy 355.603536 -273.427115)
			(xy 355.611726 -273.375797) (xy 355.627903 -273.326411) (xy 355.651661 -273.280192) (xy 355.682407 -273.238295)
			(xy 355.719371 -273.201768) (xy 355.761631 -273.171523) (xy 355.784658 -273.159474) (xy 355.812852 -273.145504)
			(xy 355.812852 -272.132806) (xy 355.784658 -272.118836) (xy 355.761629 -272.10679) (xy 355.719367 -272.076545)
			(xy 355.6824 -272.040016) (xy 355.651653 -271.998118) (xy 355.627893 -271.951898) (xy 355.611715 -271.90251)
			(xy 355.603523 -271.85119) (xy 355.603523 -271.79922) (xy 355.611713 -271.7479) (xy 355.627889 -271.698512)
			(xy 355.651647 -271.652291) (xy 355.682393 -271.610392) (xy 355.719359 -271.573862) (xy 355.761619 -271.543615)
			(xy 355.784658 -271.531588) (xy 355.812852 -271.517618) (xy 355.812852 -270.505174) (xy 355.784658 -270.491204)
			(xy 355.761631 -270.479158) (xy 355.719374 -270.448913) (xy 355.682412 -270.412387) (xy 355.651669 -270.370491)
			(xy 355.627914 -270.324274) (xy 355.61174 -270.27489) (xy 355.603551 -270.223574) (xy 355.603552 -270.171608)
			(xy 355.611744 -270.120293) (xy 355.627921 -270.07091) (xy 355.651679 -270.024694) (xy 355.682424 -269.9828)
			(xy 355.719388 -269.946275) (xy 355.761646 -269.916033) (xy 355.784658 -269.903956) (xy 355.812852 -269.889986)
			(xy 355.812852 -268.877288) (xy 355.784658 -268.863318) (xy 355.76163 -268.851272) (xy 355.719371 -268.821027)
			(xy 355.682407 -268.7845) (xy 355.651662 -268.742603) (xy 355.627905 -268.696384) (xy 355.611729 -268.646999)
			(xy 355.603539 -268.595681) (xy 355.603539 -268.543714) (xy 355.61173 -268.492396) (xy 355.627907 -268.443011)
			(xy 355.651665 -268.396793) (xy 355.682411 -268.354896) (xy 355.719375 -268.318369) (xy 355.761635 -268.288125)
			(xy 355.784658 -268.27607) (xy 355.812852 -268.2621) (xy 355.812852 -267.249402) (xy 355.784658 -267.235432)
			(xy 355.761629 -267.223386) (xy 355.719368 -267.193141) (xy 355.682402 -267.156613) (xy 355.651655 -267.114715)
			(xy 355.627896 -267.068495) (xy 355.611718 -267.019108) (xy 355.603527 -266.967788) (xy 355.603526 -266.915819)
			(xy 355.611717 -266.864499) (xy 355.627893 -266.815112) (xy 355.651651 -266.768891) (xy 355.682397 -266.726993)
			(xy 355.719362 -266.690464) (xy 355.761623 -266.660218) (xy 355.784658 -266.648184) (xy 355.812852 -266.634214)
			(xy 355.812852 -265.62177) (xy 355.784658 -265.6078) (xy 355.761631 -265.595754) (xy 355.719375 -265.56551)
			(xy 355.682414 -265.528983) (xy 355.651672 -265.487088) (xy 355.627917 -265.440871) (xy 355.611743 -265.391487)
			(xy 355.603554 -265.340172) (xy 355.603556 -265.288207) (xy 355.611748 -265.236892) (xy 355.627925 -265.18751)
			(xy 355.651683 -265.141294) (xy 355.682428 -265.099401) (xy 355.719392 -265.062877) (xy 355.76165 -265.032635)
			(xy 355.784658 -265.020552) (xy 355.812852 -265.006582) (xy 355.812852 -264.921746) (xy 355.657404 -264.766298)
			(xy 355.623876 -264.785602) (xy 355.598934 -264.799105) (xy 355.545553 -264.818259) (xy 355.489673 -264.827947)
			(xy 355.461316 -264.828528) (xy 355.435527 -264.828049) (xy 355.384583 -264.819982) (xy 355.335529 -264.804044)
			(xy 355.289572 -264.780628) (xy 355.247844 -264.75031) (xy 355.211374 -264.713837) (xy 355.181059 -264.672108)
			(xy 355.157646 -264.626149) (xy 355.141712 -264.577094) (xy 355.133649 -264.526149) (xy 355.133148 -264.50036)
			(xy 355.133722 -264.472002) (xy 355.143416 -264.416122) (xy 355.16256 -264.362737) (xy 355.176074 -264.3378)
			(xy 355.195378 -264.304272) (xy 354.675186 -263.78408) (xy 354.657923 -263.76604) (xy 354.630159 -263.724548)
			(xy 354.611039 -263.67843) (xy 354.601301 -263.629464) (xy 354.600764 -263.604502) (xy 354.600764 -262.11784)
			(xy 354.601381 -262.092885) (xy 354.611127 -262.043937) (xy 354.630234 -261.997829) (xy 354.657967 -261.956334)
			(xy 354.675186 -261.938262) (xy 355.00945 -261.603998) (xy 355.02749 -261.586736) (xy 355.068983 -261.558976)
			(xy 355.115101 -261.53986) (xy 355.164066 -261.530127) (xy 355.189028 -261.529576) (xy 355.391974 -261.529576)
			(xy 355.583744 -261.337806) (xy 355.583744 -261.187946) (xy 355.463856 -261.068058) (xy 353.511358 -261.068058)
			(xy 353.486399 -261.067483) (xy 353.437443 -261.057735) (xy 353.39133 -261.038624) (xy 353.349831 -261.010882)
			(xy 353.33178 -260.993636) (xy 353.2378 -260.899656) (xy 352.93935 -260.899656) (xy 352.907854 -260.931406)
			(xy 352.900996 -260.937756) (xy 352.899218 -260.939026) (xy 352.479864 -261.358634) (xy 352.479864 -261.797546)
			(xy 352.498768 -261.80907) (xy 352.532626 -261.837589) (xy 352.561029 -261.871545) (xy 352.583117 -261.909909)
			(xy 352.598221 -261.951521) (xy 352.605884 -261.995122) (xy 352.606356 -262.017256) (xy 352.606356 -266.335256)
			(xy 352.605779 -266.360214) (xy 352.59603 -266.409169) (xy 352.576916 -266.45528) (xy 352.549173 -266.496777)
			(xy 352.531934 -266.514834) (xy 350.830134 -268.216634) (xy 350.812093 -268.233893) (xy 350.770599 -268.261647)
			(xy 350.72448 -268.280757) (xy 350.675517 -268.290486) (xy 350.650556 -268.291056) (xy 344.579956 -268.291056)
			(xy 344.554998 -268.29048) (xy 344.506042 -268.280733) (xy 344.459928 -268.261621) (xy 344.41843 -268.233879)
			(xy 344.400378 -268.216634) (xy 344.259916 -268.076172) (xy 344.234262 -268.079982) (xy 344.221646 -268.081867)
			(xy 344.196217 -268.083902) (xy 344.183462 -268.084046) (xy 344.157677 -268.083537) (xy 344.106743 -268.075464)
			(xy 344.057698 -268.059523) (xy 344.011751 -268.036106) (xy 343.970033 -268.00579) (xy 343.933571 -267.969321)
			(xy 343.903262 -267.927597) (xy 343.879854 -267.881646) (xy 343.863922 -267.832599) (xy 343.855858 -267.781663)
			(xy 343.855294 -267.755878) (xy 343.855448 -267.743123) (xy 343.857481 -267.717695) (xy 343.859358 -267.705078)
			(xy 343.863168 -267.679424) (xy 341.826596 -265.642852) (xy 341.8078 -265.641328) (xy 341.782206 -265.638761)
			(xy 341.732211 -265.626676) (xy 341.684713 -265.60694) (xy 341.640875 -265.580036) (xy 341.601772 -265.546622)
			(xy 341.568359 -265.507518) (xy 341.541456 -265.463679) (xy 341.521721 -265.416181) (xy 341.509638 -265.366185)
			(xy 341.507064 -265.340592) (xy 341.50554 -265.321796) (xy 340.142068 -263.958324) (xy 340.109048 -263.976104)
			(xy 340.085712 -263.987972) (xy 340.036194 -264.004962) (xy 339.984608 -264.013876) (xy 339.932261 -264.014488)
			(xy 339.88048 -264.006784) (xy 339.830578 -263.990957) (xy 339.783822 -263.96741) (xy 339.741396 -263.936739)
			(xy 339.704377 -263.899723) (xy 339.673703 -263.857299) (xy 339.650152 -263.810545) (xy 339.634322 -263.760645)
			(xy 339.626613 -263.708864) (xy 339.627222 -263.656517) (xy 339.636132 -263.60493) (xy 339.653118 -263.555411)
			(xy 339.665056 -263.532112) (xy 339.682836 -263.499092) (xy 339.360002 -263.176258) (xy 339.351366 -263.172448)
			(xy 339.329465 -263.162258) (xy 339.288665 -263.136402) (xy 339.252096 -263.104844) (xy 339.220548 -263.068267)
			(xy 339.194702 -263.02746) (xy 339.184488 -263.00557) (xy 339.180678 -262.996934) (xy 337.73237 -261.548626)
			(xy 337.70316 -261.558024) (xy 337.679194 -261.565042) (xy 337.62983 -261.572574) (xy 337.604862 -261.57301)
			(xy 337.579075 -261.572502) (xy 337.528137 -261.564429) (xy 337.479089 -261.548488) (xy 337.433137 -261.525073)
			(xy 337.391414 -261.494757) (xy 337.354945 -261.45829) (xy 337.32463 -261.416566) (xy 337.301213 -261.370615)
			(xy 337.285272 -261.321567) (xy 337.277199 -261.270629) (xy 337.276694 -261.244842) (xy 337.277035 -261.223188)
			(xy 337.282731 -261.180258) (xy 337.294043 -261.138454) (xy 337.302094 -261.11835) (xy 337.288378 -261.104634)
			(xy 337.271119 -261.086593) (xy 337.243363 -261.045099) (xy 337.224252 -260.998981) (xy 337.214523 -260.950017)
			(xy 337.213956 -260.925056) (xy 337.213956 -249.790204) (xy 337.207606 -249.778774) (xy 337.194733 -249.754315)
			(xy 337.176481 -249.702149) (xy 337.167248 -249.647658) (xy 337.166712 -249.620024) (xy 337.167284 -249.592393)
			(xy 337.17653 -249.53791) (xy 337.194749 -249.485738) (xy 337.207606 -249.461274) (xy 337.213956 -249.449844)
			(xy 337.213956 -248.16181) (xy 337.207606 -248.15038) (xy 337.194827 -248.125981) (xy 337.176707 -248.073973)
			(xy 337.167515 -248.019671) (xy 337.16751 -247.964596) (xy 337.17669 -247.910292) (xy 337.1948 -247.85828)
			(xy 337.207606 -247.833896) (xy 337.213956 -247.822466) (xy 337.213956 -246.534686) (xy 337.207606 -246.523256)
			(xy 337.194734 -246.498797) (xy 337.176486 -246.44663) (xy 337.167255 -246.39214) (xy 337.166712 -246.364506)
			(xy 337.167286 -246.336876) (xy 337.176534 -246.282394) (xy 337.194756 -246.230223) (xy 337.207606 -246.205756)
			(xy 337.213956 -246.194326) (xy 337.213956 -244.9068) (xy 337.207606 -244.89537) (xy 337.194733 -244.870911)
			(xy 337.176482 -244.818745) (xy 337.167249 -244.764254) (xy 337.166712 -244.73662) (xy 337.167284 -244.708989)
			(xy 337.176531 -244.654506) (xy 337.194751 -244.602335) (xy 337.207606 -244.57787) (xy 337.213956 -244.56644)
			(xy 337.213956 -243.279168) (xy 337.207606 -243.267738) (xy 337.194736 -243.243279) (xy 337.17649 -243.191112)
			(xy 337.167262 -243.136621) (xy 337.166712 -243.108988) (xy 337.167287 -243.081358) (xy 337.176538 -243.026877)
			(xy 337.194762 -242.974708) (xy 337.207606 -242.950238) (xy 337.213956 -242.938808) (xy 337.213956 -241.651282)
			(xy 337.207606 -241.639852) (xy 337.194734 -241.615393) (xy 337.176486 -241.563226) (xy 337.167257 -241.508736)
			(xy 337.166712 -241.481102) (xy 337.167286 -241.453472) (xy 337.176535 -241.39899) (xy 337.194757 -241.34682)
			(xy 337.207606 -241.322352) (xy 337.213956 -241.310922) (xy 337.213956 -240.023396) (xy 337.207606 -240.011966)
			(xy 337.194733 -239.987507) (xy 337.176483 -239.93534) (xy 337.167251 -239.88085) (xy 337.166712 -239.853216)
			(xy 337.167285 -239.825585) (xy 337.176532 -239.771103) (xy 337.194752 -239.718931) (xy 337.207606 -239.694466)
			(xy 337.213956 -239.683036) (xy 337.213956 -238.395764) (xy 337.207606 -238.384334) (xy 337.194736 -238.359875)
			(xy 337.176491 -238.307707) (xy 337.167264 -238.253217) (xy 337.166712 -238.225584) (xy 337.167287 -238.197954)
			(xy 337.176539 -238.143474) (xy 337.194764 -238.091305) (xy 337.207606 -238.066834) (xy 337.213956 -238.055404)
			(xy 337.213956 -236.768132) (xy 337.207606 -236.756702) (xy 337.194738 -236.732242) (xy 337.176498 -236.680074)
			(xy 337.167277 -236.625585) (xy 337.166712 -236.597952) (xy 337.16729 -236.570323) (xy 337.176547 -236.515845)
			(xy 337.194775 -236.463679) (xy 337.207606 -236.439202) (xy 337.213956 -236.427772) (xy 337.213956 -235.140246)
			(xy 337.207606 -235.128816) (xy 337.194737 -235.104356) (xy 337.176495 -235.052189) (xy 337.167271 -234.997699)
			(xy 337.166712 -234.970066) (xy 337.167289 -234.942436) (xy 337.176544 -234.887957) (xy 337.19477 -234.83579)
			(xy 337.207606 -234.811316) (xy 337.213956 -234.799886) (xy 337.213956 -233.51236) (xy 337.207606 -233.50093)
			(xy 337.194736 -233.476471) (xy 337.176492 -233.424303) (xy 337.167265 -233.369813) (xy 337.166712 -233.34218)
			(xy 337.167288 -233.31455) (xy 337.17654 -233.26007) (xy 337.194765 -233.207902) (xy 337.207606 -233.18343)
			(xy 337.213956 -233.172) (xy 337.213956 -232.578656) (xy 337.214532 -232.553698) (xy 337.22428 -232.504742)
			(xy 337.243392 -232.458629) (xy 337.271135 -232.417132) (xy 337.288378 -232.399078) (xy 338.18068 -231.506776)
			(xy 338.190825 -231.494618) (xy 338.213086 -231.472097) (xy 338.22513 -231.461818) (xy 338.227162 -231.460294)
			(xy 338.619846 -231.06761) (xy 338.605368 -231.035606) (xy 338.596192 -231.014275) (xy 338.583272 -230.969675)
			(xy 338.576784 -230.923696) (xy 338.576412 -230.900478) (xy 338.576919 -230.874691) (xy 338.58499 -230.823752)
			(xy 338.600929 -230.774703) (xy 338.624345 -230.728751) (xy 338.65466 -230.687027) (xy 338.691129 -230.650559)
			(xy 338.732853 -230.620244) (xy 338.778805 -230.596829) (xy 338.827854 -230.58089) (xy 338.878793 -230.572819)
			(xy 338.90458 -230.57231) (xy 338.927795 -230.572701) (xy 338.973766 -230.579212) (xy 339.018366 -230.592122)
			(xy 339.039708 -230.601266) (xy 339.071712 -230.615744) (xy 340.458806 -229.22865) (xy 340.461854 -229.213156)
			(xy 340.46679 -229.188932) (xy 340.482972 -229.14222) (xy 340.50598 -229.098466) (xy 340.535294 -229.05866)
			(xy 340.570249 -229.023703) (xy 340.610054 -228.994387) (xy 340.653807 -228.971377) (xy 340.700519 -228.955193)
			(xy 340.724744 -228.950266) (xy 340.740238 -228.947218) (xy 341.0077 -228.679756) (xy 340.98357 -228.644958)
			(xy 340.969932 -228.624336) (xy 340.948354 -228.579855) (xy 340.933709 -228.532635) (xy 340.926331 -228.48375)
			(xy 340.925912 -228.45903) (xy 340.926389 -228.433238) (xy 340.934454 -228.382289) (xy 340.95039 -228.333229)
			(xy 340.973805 -228.287266) (xy 341.004121 -228.245532) (xy 341.040593 -228.209054) (xy 341.082323 -228.178731)
			(xy 341.128283 -228.155309) (xy 341.17734 -228.139366) (xy 341.228288 -228.131293) (xy 341.25408 -228.130862)
			(xy 341.278797 -228.131312) (xy 341.327672 -228.138719) (xy 341.37489 -228.153354) (xy 341.419386 -228.174888)
			(xy 341.440008 -228.18852) (xy 341.474806 -228.21265) (xy 342.808306 -226.87915) (xy 342.806528 -226.856036)
			(xy 342.805512 -226.831144) (xy 342.805988 -226.805352) (xy 342.814051 -226.754401) (xy 342.829986 -226.705339)
			(xy 342.8534 -226.659374) (xy 342.883716 -226.617637) (xy 342.920189 -226.581158) (xy 342.961919 -226.550833)
			(xy 343.007879 -226.52741) (xy 343.056938 -226.511466) (xy 343.107888 -226.503393) (xy 343.13368 -226.502976)
			(xy 343.158572 -226.503992) (xy 343.181686 -226.50577) (xy 344.605356 -225.0821) (xy 344.605356 -224.891346)
			(xy 344.505026 -224.71761) (xy 344.482166 -224.713292) (xy 344.457365 -224.708093) (xy 344.409627 -224.691103)
			(xy 344.365051 -224.667009) (xy 344.324685 -224.636379) (xy 344.289481 -224.599934) (xy 344.260267 -224.558532)
			(xy 344.23773 -224.513149) (xy 344.222402 -224.464851) (xy 344.214644 -224.414778) (xy 344.214196 -224.389442)
			(xy 344.21474 -224.362368) (xy 344.223586 -224.308948) (xy 344.241047 -224.257694) (xy 344.266653 -224.209983)
			(xy 344.299715 -224.167102) (xy 344.339343 -224.130202) (xy 344.384471 -224.100279) (xy 344.433883 -224.078136)
			(xy 344.486251 -224.064369) (xy 344.513154 -224.061274) (xy 344.528081 -224.059341) (xy 344.555927 -224.047951)
			(xy 344.579254 -224.028953) (xy 344.596046 -224.003991) (xy 344.60485 -223.975223) (xy 344.605356 -223.960182)
			(xy 344.605356 -221.635828) (xy 344.505026 -221.462092) (xy 344.482166 -221.457774) (xy 344.457366 -221.452575)
			(xy 344.409629 -221.435584) (xy 344.365054 -221.41149) (xy 344.32469 -221.38086) (xy 344.289488 -221.344415)
			(xy 344.260275 -221.303013) (xy 344.237741 -221.257629) (xy 344.222416 -221.209332) (xy 344.21466 -221.159259)
			(xy 344.214196 -221.133924) (xy 344.214742 -221.106851) (xy 344.22359 -221.053434) (xy 344.241053 -221.002181)
			(xy 344.26666 -220.954474) (xy 344.299722 -220.911594) (xy 344.339349 -220.874697) (xy 344.384476 -220.844776)
			(xy 344.433887 -220.822634) (xy 344.486254 -220.808869) (xy 344.513154 -220.805756) (xy 344.52808 -220.803822)
			(xy 344.555923 -220.792432) (xy 344.579248 -220.773434) (xy 344.596035 -220.748472) (xy 344.604834 -220.719704)
			(xy 344.605356 -220.704664) (xy 344.605356 -220.597476) (xy 344.500454 -220.492574) (xy 344.48958 -220.482411)
			(xy 344.463385 -220.468308) (xy 344.434236 -220.462356) (xy 344.404609 -220.465059) (xy 344.377019 -220.476188)
			(xy 344.353808 -220.494798) (xy 344.345006 -220.506798) (xy 344.330007 -220.527717) (xy 344.294587 -220.565063)
			(xy 344.25379 -220.596446) (xy 344.208609 -220.621103) (xy 344.160143 -220.638435) (xy 344.134948 -220.643704)
			(xy 344.112088 -220.648022) (xy 343.90711 -221.003114) (xy 343.914984 -221.024958) (xy 343.923564 -221.051377)
			(xy 343.932762 -221.106152) (xy 343.933272 -221.133924) (xy 343.932764 -221.159811) (xy 343.924665 -221.210949)
			(xy 343.908666 -221.260189) (xy 343.88516 -221.306321) (xy 343.854728 -221.348208) (xy 343.818118 -221.384818)
			(xy 343.776231 -221.41525) (xy 343.730099 -221.438756) (xy 343.680859 -221.454755) (xy 343.629721 -221.462854)
			(xy 343.577947 -221.462854) (xy 343.526809 -221.454755) (xy 343.477569 -221.438756) (xy 343.431437 -221.41525)
			(xy 343.38955 -221.384818) (xy 343.35294 -221.348208) (xy 343.322508 -221.306321) (xy 343.299002 -221.260189)
			(xy 343.283003 -221.210949) (xy 343.274904 -221.159811) (xy 343.274396 -221.133924) (xy 343.274858 -221.108587)
			(xy 343.282608 -221.058509) (xy 343.297928 -221.010206) (xy 343.32046 -220.964816) (xy 343.34967 -220.923408)
			(xy 343.384873 -220.886957) (xy 343.425238 -220.856322) (xy 343.469816 -220.832223) (xy 343.517555 -220.815229)
			(xy 343.542366 -220.810074) (xy 343.565226 -220.805756) (xy 343.770204 -220.450664) (xy 343.76233 -220.42882)
			(xy 343.753687 -220.402411) (xy 343.744373 -220.347635) (xy 343.743788 -220.319854) (xy 343.744293 -220.293247)
			(xy 343.752836 -220.240723) (xy 343.769708 -220.190254) (xy 343.79447 -220.143153) (xy 343.826479 -220.100642)
			(xy 343.864904 -220.063828) (xy 343.886536 -220.048328) (xy 343.898463 -220.039458) (xy 343.917009 -220.016249)
			(xy 343.9281 -219.988687) (xy 343.9308 -219.959101) (xy 343.924881 -219.929987) (xy 343.910842 -219.903804)
			(xy 343.90076 -219.89288) (xy 343.787984 -219.780104) (xy 343.754964 -219.797376) (xy 343.731478 -219.808973)
			(xy 343.681738 -219.825385) (xy 343.630023 -219.833691) (xy 343.603834 -219.834206) (xy 343.578044 -219.833703)
			(xy 343.527097 -219.825639) (xy 343.478039 -219.809705) (xy 343.432078 -219.786293) (xy 343.390345 -219.755979)
			(xy 343.353868 -219.71951) (xy 343.323545 -219.677784) (xy 343.300123 -219.631827) (xy 343.284178 -219.582773)
			(xy 343.276103 -219.531828) (xy 343.275666 -219.506038) (xy 343.27618 -219.47985) (xy 343.2845 -219.428139)
			(xy 343.300918 -219.378404) (xy 343.312496 -219.354908) (xy 343.329768 -219.321888) (xy 343.002616 -218.994736)
			(xy 342.994488 -218.990926) (xy 342.968633 -218.978223) (xy 342.921443 -218.94519) (xy 342.880712 -218.904459)
			(xy 342.847678 -218.85727) (xy 342.834976 -218.831414) (xy 342.831166 -218.823286) (xy 342.447118 -218.439238)
			(xy 341.657686 -218.439238) (xy 341.643687 -218.439722) (xy 341.61676 -218.447406) (xy 341.59293 -218.462111)
			(xy 341.573987 -218.482732) (xy 341.561352 -218.50772) (xy 341.555974 -218.5352) (xy 341.558258 -218.563109)
			(xy 341.56269 -218.576398) (xy 341.572538 -218.604335) (xy 341.583153 -218.662607) (xy 341.583772 -218.692222)
			(xy 341.583264 -218.718129) (xy 341.575158 -218.769306) (xy 341.559146 -218.818585) (xy 341.535623 -218.864752)
			(xy 341.505167 -218.906671) (xy 341.468529 -218.943309) (xy 341.42661 -218.973765) (xy 341.380443 -218.997288)
			(xy 341.331164 -219.0133) (xy 341.279987 -219.021406) (xy 341.228173 -219.021406) (xy 341.176996 -219.0133)
			(xy 341.127717 -218.997288) (xy 341.08155 -218.973765) (xy 341.039631 -218.943309) (xy 341.002993 -218.906671)
			(xy 340.972537 -218.864752) (xy 340.949014 -218.818585) (xy 340.933002 -218.769306) (xy 340.924896 -218.718129)
			(xy 340.924388 -218.692222) (xy 340.924975 -218.664503) (xy 340.93429 -218.609854) (xy 340.94293 -218.58351)
			(xy 340.950804 -218.561412) (xy 340.880192 -218.439238) (xy 339.778086 -218.439238) (xy 339.764087 -218.439722)
			(xy 339.73716 -218.447406) (xy 339.71333 -218.462111) (xy 339.694387 -218.482732) (xy 339.681752 -218.50772)
			(xy 339.676374 -218.5352) (xy 339.678658 -218.563109) (xy 339.68309 -218.576398) (xy 339.692938 -218.604335)
			(xy 339.703553 -218.662607) (xy 339.704172 -218.692222) (xy 339.703664 -218.718129) (xy 339.695558 -218.769306)
			(xy 339.679546 -218.818585) (xy 339.656023 -218.864752) (xy 339.625567 -218.906671) (xy 339.588929 -218.943309)
			(xy 339.54701 -218.973765) (xy 339.500843 -218.997288) (xy 339.451564 -219.0133) (xy 339.400387 -219.021406)
			(xy 339.348573 -219.021406) (xy 339.297396 -219.0133) (xy 339.248117 -218.997288) (xy 339.20195 -218.973765)
			(xy 339.160031 -218.943309) (xy 339.123393 -218.906671) (xy 339.092937 -218.864752) (xy 339.069414 -218.818585)
			(xy 339.053402 -218.769306) (xy 339.045296 -218.718129) (xy 339.044788 -218.692222) (xy 339.045375 -218.664503)
			(xy 339.05469 -218.609854) (xy 339.06333 -218.58351) (xy 339.071204 -218.561412) (xy 339.000592 -218.439238)
			(xy 337.898486 -218.439238) (xy 337.884487 -218.439722) (xy 337.85756 -218.447406) (xy 337.83373 -218.462111)
			(xy 337.814787 -218.482732) (xy 337.802152 -218.50772) (xy 337.796774 -218.5352) (xy 337.799058 -218.563109)
			(xy 337.80349 -218.576398) (xy 337.813338 -218.604335) (xy 337.823953 -218.662607) (xy 337.824572 -218.692222)
			(xy 337.824064 -218.718129) (xy 337.815958 -218.769306) (xy 337.799946 -218.818585) (xy 337.776423 -218.864752)
			(xy 337.745967 -218.906671) (xy 337.709329 -218.943309) (xy 337.66741 -218.973765) (xy 337.621243 -218.997288)
			(xy 337.571964 -219.0133) (xy 337.520787 -219.021406) (xy 337.468973 -219.021406) (xy 337.417796 -219.0133)
			(xy 337.368517 -218.997288) (xy 337.32235 -218.973765) (xy 337.280431 -218.943309) (xy 337.243793 -218.906671)
			(xy 337.213337 -218.864752) (xy 337.189814 -218.818585) (xy 337.173802 -218.769306) (xy 337.165696 -218.718129)
			(xy 337.165188 -218.692222) (xy 337.165775 -218.664503) (xy 337.17509 -218.609854) (xy 337.18373 -218.58351)
			(xy 337.191604 -218.561412) (xy 337.120992 -218.439238) (xy 285.287466 -218.439238) (xy 284.8356 -218.891104)
			(xy 284.8356 -221.133924) (xy 336.695796 -221.133924) (xy 336.696304 -221.108037) (xy 336.704403 -221.056899)
			(xy 336.720402 -221.007659) (xy 336.743908 -220.961527) (xy 336.77434 -220.91964) (xy 336.81095 -220.88303)
			(xy 336.852837 -220.852598) (xy 336.898969 -220.829092) (xy 336.948209 -220.813093) (xy 336.999347 -220.804994)
			(xy 337.051121 -220.804994) (xy 337.102259 -220.813093) (xy 337.151499 -220.829092) (xy 337.197631 -220.852598)
			(xy 337.239518 -220.88303) (xy 337.276128 -220.91964) (xy 337.30656 -220.961527) (xy 337.330066 -221.007659)
			(xy 337.346065 -221.056899) (xy 337.354164 -221.108037) (xy 337.354672 -221.133924) (xy 337.635596 -221.133924)
			(xy 337.636104 -221.10859) (xy 337.643853 -221.058519) (xy 337.659172 -221.010223) (xy 337.6817 -220.96484)
			(xy 337.710906 -220.923438) (xy 337.746104 -220.886992) (xy 337.786463 -220.856361) (xy 337.831034 -220.832266)
			(xy 337.878767 -220.815274) (xy 337.903566 -220.810074) (xy 337.926426 -220.805756) (xy 338.131404 -220.450664)
			(xy 338.12353 -220.42882) (xy 338.114896 -220.402408) (xy 338.105568 -220.347635) (xy 338.104988 -220.319854)
			(xy 338.105496 -220.293947) (xy 338.113602 -220.24277) (xy 338.129614 -220.193491) (xy 338.153137 -220.147324)
			(xy 338.183593 -220.105405) (xy 338.220231 -220.068767) (xy 338.26215 -220.038311) (xy 338.308317 -220.014788)
			(xy 338.357596 -219.998776) (xy 338.408773 -219.99067) (xy 338.460587 -219.99067) (xy 338.511764 -219.998776)
			(xy 338.561043 -220.014788) (xy 338.60721 -220.038311) (xy 338.649129 -220.068767) (xy 338.685767 -220.105405)
			(xy 338.716223 -220.147324) (xy 338.739746 -220.193491) (xy 338.755758 -220.24277) (xy 338.763864 -220.293947)
			(xy 338.764372 -220.319854) (xy 338.763922 -220.3452) (xy 338.756142 -220.395293) (xy 338.740788 -220.443604)
			(xy 338.718222 -220.488998) (xy 338.688976 -220.530404) (xy 338.653739 -220.566847) (xy 338.61334 -220.597469)
			(xy 338.568731 -220.621548) (xy 338.520963 -220.638518) (xy 338.496148 -220.643704) (xy 338.473288 -220.648022)
			(xy 338.26831 -221.003114) (xy 338.276184 -221.024958) (xy 338.284777 -221.051373) (xy 338.293965 -221.106151)
			(xy 338.294472 -221.133924) (xy 338.575396 -221.133924) (xy 338.575904 -221.108037) (xy 338.584003 -221.056899)
			(xy 338.600002 -221.007659) (xy 338.623508 -220.961527) (xy 338.65394 -220.91964) (xy 338.69055 -220.88303)
			(xy 338.732437 -220.852598) (xy 338.778569 -220.829092) (xy 338.827809 -220.813093) (xy 338.878947 -220.804994)
			(xy 338.930721 -220.804994) (xy 338.981859 -220.813093) (xy 339.031099 -220.829092) (xy 339.077231 -220.852598)
			(xy 339.119118 -220.88303) (xy 339.155728 -220.91964) (xy 339.18616 -220.961527) (xy 339.209666 -221.007659)
			(xy 339.225665 -221.056899) (xy 339.233764 -221.108037) (xy 339.234272 -221.133924) (xy 339.515196 -221.133924)
			(xy 339.515704 -221.10859) (xy 339.523453 -221.058519) (xy 339.538772 -221.010223) (xy 339.5613 -220.96484)
			(xy 339.590506 -220.923438) (xy 339.625704 -220.886992) (xy 339.666063 -220.856361) (xy 339.710634 -220.832266)
			(xy 339.758367 -220.815274) (xy 339.783166 -220.810074) (xy 339.806026 -220.805756) (xy 340.011004 -220.450664)
			(xy 340.00313 -220.42882) (xy 339.994496 -220.402408) (xy 339.985168 -220.347635) (xy 339.984588 -220.319854)
			(xy 339.985096 -220.293947) (xy 339.993202 -220.24277) (xy 340.009214 -220.193491) (xy 340.032737 -220.147324)
			(xy 340.063193 -220.105405) (xy 340.099831 -220.068767) (xy 340.14175 -220.038311) (xy 340.187917 -220.014788)
			(xy 340.237196 -219.998776) (xy 340.288373 -219.99067) (xy 340.340187 -219.99067) (xy 340.391364 -219.998776)
			(xy 340.440643 -220.014788) (xy 340.48681 -220.038311) (xy 340.528729 -220.068767) (xy 340.565367 -220.105405)
			(xy 340.595823 -220.147324) (xy 340.619346 -220.193491) (xy 340.635358 -220.24277) (xy 340.643464 -220.293947)
			(xy 340.643972 -220.319854) (xy 340.643522 -220.3452) (xy 340.635742 -220.395293) (xy 340.620388 -220.443604)
			(xy 340.597822 -220.488998) (xy 340.568576 -220.530404) (xy 340.533339 -220.566847) (xy 340.49294 -220.597469)
			(xy 340.448331 -220.621548) (xy 340.400563 -220.638518) (xy 340.375748 -220.643704) (xy 340.352888 -220.648022)
			(xy 340.14791 -221.003114) (xy 340.155784 -221.024958) (xy 340.164377 -221.051373) (xy 340.173565 -221.106151)
			(xy 340.174072 -221.133924) (xy 340.454996 -221.133924) (xy 340.455504 -221.108037) (xy 340.463603 -221.056899)
			(xy 340.479602 -221.007659) (xy 340.503108 -220.961527) (xy 340.53354 -220.91964) (xy 340.57015 -220.88303)
			(xy 340.612037 -220.852598) (xy 340.658169 -220.829092) (xy 340.707409 -220.813093) (xy 340.758547 -220.804994)
			(xy 340.810321 -220.804994) (xy 340.861459 -220.813093) (xy 340.910699 -220.829092) (xy 340.956831 -220.852598)
			(xy 340.998718 -220.88303) (xy 341.035328 -220.91964) (xy 341.06576 -220.961527) (xy 341.089266 -221.007659)
			(xy 341.105265 -221.056899) (xy 341.113364 -221.108037) (xy 341.113872 -221.133924) (xy 341.394796 -221.133924)
			(xy 341.395304 -221.10859) (xy 341.403053 -221.058519) (xy 341.418372 -221.010223) (xy 341.4409 -220.96484)
			(xy 341.470106 -220.923438) (xy 341.505304 -220.886992) (xy 341.545663 -220.856361) (xy 341.590234 -220.832266)
			(xy 341.637967 -220.815274) (xy 341.662766 -220.810074) (xy 341.685626 -220.805756) (xy 341.890604 -220.450664)
			(xy 341.88273 -220.42882) (xy 341.874096 -220.402408) (xy 341.864768 -220.347635) (xy 341.864188 -220.319854)
			(xy 341.864696 -220.293947) (xy 341.872802 -220.24277) (xy 341.888814 -220.193491) (xy 341.912337 -220.147324)
			(xy 341.942793 -220.105405) (xy 341.979431 -220.068767) (xy 342.02135 -220.038311) (xy 342.067517 -220.014788)
			(xy 342.116796 -219.998776) (xy 342.167973 -219.99067) (xy 342.219787 -219.99067) (xy 342.270964 -219.998776)
			(xy 342.320243 -220.014788) (xy 342.36641 -220.038311) (xy 342.408329 -220.068767) (xy 342.444967 -220.105405)
			(xy 342.475423 -220.147324) (xy 342.498946 -220.193491) (xy 342.514958 -220.24277) (xy 342.523064 -220.293947)
			(xy 342.523572 -220.319854) (xy 342.523122 -220.3452) (xy 342.515342 -220.395293) (xy 342.499988 -220.443604)
			(xy 342.477422 -220.488998) (xy 342.448176 -220.530404) (xy 342.412939 -220.566847) (xy 342.37254 -220.597469)
			(xy 342.327931 -220.621548) (xy 342.280163 -220.638518) (xy 342.255348 -220.643704) (xy 342.232488 -220.648022)
			(xy 342.02751 -221.003114) (xy 342.035384 -221.024958) (xy 342.043977 -221.051373) (xy 342.053165 -221.106151)
			(xy 342.053672 -221.133924) (xy 342.334596 -221.133924) (xy 342.335104 -221.108037) (xy 342.343203 -221.056899)
			(xy 342.359202 -221.007659) (xy 342.382708 -220.961527) (xy 342.41314 -220.91964) (xy 342.44975 -220.88303)
			(xy 342.491637 -220.852598) (xy 342.537769 -220.829092) (xy 342.587009 -220.813093) (xy 342.638147 -220.804994)
			(xy 342.689921 -220.804994) (xy 342.741059 -220.813093) (xy 342.790299 -220.829092) (xy 342.836431 -220.852598)
			(xy 342.878318 -220.88303) (xy 342.914928 -220.91964) (xy 342.94536 -220.961527) (xy 342.968866 -221.007659)
			(xy 342.984865 -221.056899) (xy 342.992964 -221.108037) (xy 342.993472 -221.133924) (xy 342.992945 -221.161632)
			(xy 342.983748 -221.216279) (xy 342.975184 -221.242636) (xy 342.96731 -221.264734) (xy 343.172288 -221.619572)
			(xy 343.195148 -221.62389) (xy 343.219967 -221.629064) (xy 343.267746 -221.646018) (xy 343.312365 -221.670088)
			(xy 343.352772 -221.700708) (xy 343.388013 -221.737154) (xy 343.417257 -221.778566) (xy 343.439814 -221.823969)
			(xy 343.455152 -221.872291) (xy 343.46291 -221.922391) (xy 343.463372 -221.94774) (xy 343.462864 -221.973647)
			(xy 343.454758 -222.024824) (xy 343.438746 -222.074103) (xy 343.415223 -222.12027) (xy 343.384767 -222.162189)
			(xy 343.348129 -222.198827) (xy 343.30621 -222.229283) (xy 343.260043 -222.252806) (xy 343.210764 -222.268818)
			(xy 343.159587 -222.276924) (xy 343.107773 -222.276924) (xy 343.056596 -222.268818) (xy 343.007317 -222.252806)
			(xy 342.96115 -222.229283) (xy 342.919231 -222.198827) (xy 342.882593 -222.162189) (xy 342.852137 -222.12027)
			(xy 342.828614 -222.074103) (xy 342.812602 -222.024824) (xy 342.804496 -221.973647) (xy 342.803988 -221.94774)
			(xy 342.804592 -221.920023) (xy 342.813909 -221.865377) (xy 342.82253 -221.839028) (xy 342.830404 -221.81693)
			(xy 342.625426 -221.462092) (xy 342.602566 -221.457774) (xy 342.577766 -221.452574) (xy 342.53003 -221.435583)
			(xy 342.485455 -221.411489) (xy 342.445091 -221.380859) (xy 342.409889 -221.344414) (xy 342.380676 -221.303012)
			(xy 342.358142 -221.257629) (xy 342.342817 -221.209332) (xy 342.335061 -221.159259) (xy 342.334596 -221.133924)
			(xy 342.053672 -221.133924) (xy 342.053164 -221.159811) (xy 342.045065 -221.210949) (xy 342.029066 -221.260189)
			(xy 342.00556 -221.306321) (xy 341.975128 -221.348208) (xy 341.938518 -221.384818) (xy 341.896631 -221.41525)
			(xy 341.850499 -221.438756) (xy 341.801259 -221.454755) (xy 341.750121 -221.462854) (xy 341.698347 -221.462854)
			(xy 341.647209 -221.454755) (xy 341.597969 -221.438756) (xy 341.551837 -221.41525) (xy 341.50995 -221.384818)
			(xy 341.47334 -221.348208) (xy 341.442908 -221.306321) (xy 341.419402 -221.260189) (xy 341.403403 -221.210949)
			(xy 341.395304 -221.159811) (xy 341.394796 -221.133924) (xy 341.113872 -221.133924) (xy 341.113345 -221.161632)
			(xy 341.104148 -221.216279) (xy 341.095584 -221.242636) (xy 341.08771 -221.264734) (xy 341.292688 -221.619572)
			(xy 341.315548 -221.62389) (xy 341.340367 -221.629064) (xy 341.388146 -221.646018) (xy 341.432765 -221.670088)
			(xy 341.473172 -221.700708) (xy 341.508413 -221.737154) (xy 341.537657 -221.778566) (xy 341.560214 -221.823969)
			(xy 341.575552 -221.872291) (xy 341.58331 -221.922391) (xy 341.583772 -221.94774) (xy 341.583264 -221.973647)
			(xy 341.575158 -222.024824) (xy 341.559146 -222.074103) (xy 341.535623 -222.12027) (xy 341.505167 -222.162189)
			(xy 341.468529 -222.198827) (xy 341.42661 -222.229283) (xy 341.380443 -222.252806) (xy 341.331164 -222.268818)
			(xy 341.279987 -222.276924) (xy 341.228173 -222.276924) (xy 341.176996 -222.268818) (xy 341.127717 -222.252806)
			(xy 341.08155 -222.229283) (xy 341.039631 -222.198827) (xy 341.002993 -222.162189) (xy 340.972537 -222.12027)
			(xy 340.949014 -222.074103) (xy 340.933002 -222.024824) (xy 340.924896 -221.973647) (xy 340.924388 -221.94774)
			(xy 340.924992 -221.920023) (xy 340.934309 -221.865377) (xy 340.94293 -221.839028) (xy 340.950804 -221.81693)
			(xy 340.745826 -221.462092) (xy 340.722966 -221.457774) (xy 340.698166 -221.452574) (xy 340.65043 -221.435583)
			(xy 340.605855 -221.411489) (xy 340.565491 -221.380859) (xy 340.530289 -221.344414) (xy 340.501076 -221.303012)
			(xy 340.478542 -221.257629) (xy 340.463217 -221.209332) (xy 340.455461 -221.159259) (xy 340.454996 -221.133924)
			(xy 340.174072 -221.133924) (xy 340.173564 -221.159811) (xy 340.165465 -221.210949) (xy 340.149466 -221.260189)
			(xy 340.12596 -221.306321) (xy 340.095528 -221.348208) (xy 340.058918 -221.384818) (xy 340.017031 -221.41525)
			(xy 339.970899 -221.438756) (xy 339.921659 -221.454755) (xy 339.870521 -221.462854) (xy 339.818747 -221.462854)
			(xy 339.767609 -221.454755) (xy 339.718369 -221.438756) (xy 339.672237 -221.41525) (xy 339.63035 -221.384818)
			(xy 339.59374 -221.348208) (xy 339.563308 -221.306321) (xy 339.539802 -221.260189) (xy 339.523803 -221.210949)
			(xy 339.515704 -221.159811) (xy 339.515196 -221.133924) (xy 339.234272 -221.133924) (xy 339.233745 -221.161632)
			(xy 339.224548 -221.216279) (xy 339.215984 -221.242636) (xy 339.20811 -221.264734) (xy 339.413088 -221.619572)
			(xy 339.435948 -221.62389) (xy 339.460767 -221.629064) (xy 339.508546 -221.646018) (xy 339.553165 -221.670088)
			(xy 339.593572 -221.700708) (xy 339.628813 -221.737154) (xy 339.658057 -221.778566) (xy 339.680614 -221.823969)
			(xy 339.695952 -221.872291) (xy 339.70371 -221.922391) (xy 339.704172 -221.94774) (xy 339.703664 -221.973647)
			(xy 339.695558 -222.024824) (xy 339.679546 -222.074103) (xy 339.656023 -222.12027) (xy 339.625567 -222.162189)
			(xy 339.588929 -222.198827) (xy 339.54701 -222.229283) (xy 339.500843 -222.252806) (xy 339.451564 -222.268818)
			(xy 339.400387 -222.276924) (xy 339.348573 -222.276924) (xy 339.297396 -222.268818) (xy 339.248117 -222.252806)
			(xy 339.20195 -222.229283) (xy 339.160031 -222.198827) (xy 339.123393 -222.162189) (xy 339.092937 -222.12027)
			(xy 339.069414 -222.074103) (xy 339.053402 -222.024824) (xy 339.045296 -221.973647) (xy 339.044788 -221.94774)
			(xy 339.045392 -221.920023) (xy 339.054709 -221.865377) (xy 339.06333 -221.839028) (xy 339.071204 -221.81693)
			(xy 338.866226 -221.462092) (xy 338.843366 -221.457774) (xy 338.818566 -221.452574) (xy 338.77083 -221.435583)
			(xy 338.726255 -221.411489) (xy 338.685891 -221.380859) (xy 338.650689 -221.344414) (xy 338.621476 -221.303012)
			(xy 338.598942 -221.257629) (xy 338.583617 -221.209332) (xy 338.575861 -221.159259) (xy 338.575396 -221.133924)
			(xy 338.294472 -221.133924) (xy 338.293964 -221.159811) (xy 338.285865 -221.210949) (xy 338.269866 -221.260189)
			(xy 338.24636 -221.306321) (xy 338.215928 -221.348208) (xy 338.179318 -221.384818) (xy 338.137431 -221.41525)
			(xy 338.091299 -221.438756) (xy 338.042059 -221.454755) (xy 337.990921 -221.462854) (xy 337.939147 -221.462854)
			(xy 337.888009 -221.454755) (xy 337.838769 -221.438756) (xy 337.792637 -221.41525) (xy 337.75075 -221.384818)
			(xy 337.71414 -221.348208) (xy 337.683708 -221.306321) (xy 337.660202 -221.260189) (xy 337.644203 -221.210949)
			(xy 337.636104 -221.159811) (xy 337.635596 -221.133924) (xy 337.354672 -221.133924) (xy 337.354145 -221.161632)
			(xy 337.344948 -221.216279) (xy 337.336384 -221.242636) (xy 337.32851 -221.264734) (xy 337.533488 -221.619572)
			(xy 337.556348 -221.62389) (xy 337.581167 -221.629064) (xy 337.628946 -221.646018) (xy 337.673565 -221.670088)
			(xy 337.713972 -221.700708) (xy 337.749213 -221.737154) (xy 337.778457 -221.778566) (xy 337.801014 -221.823969)
			(xy 337.816352 -221.872291) (xy 337.82411 -221.922391) (xy 337.824572 -221.94774) (xy 337.824064 -221.973647)
			(xy 337.815958 -222.024824) (xy 337.799946 -222.074103) (xy 337.776423 -222.12027) (xy 337.745967 -222.162189)
			(xy 337.709329 -222.198827) (xy 337.66741 -222.229283) (xy 337.621243 -222.252806) (xy 337.571964 -222.268818)
			(xy 337.520787 -222.276924) (xy 337.468973 -222.276924) (xy 337.417796 -222.268818) (xy 337.368517 -222.252806)
			(xy 337.32235 -222.229283) (xy 337.280431 -222.198827) (xy 337.243793 -222.162189) (xy 337.213337 -222.12027)
			(xy 337.189814 -222.074103) (xy 337.173802 -222.024824) (xy 337.165696 -221.973647) (xy 337.165188 -221.94774)
			(xy 337.165792 -221.920023) (xy 337.175109 -221.865377) (xy 337.18373 -221.839028) (xy 337.191604 -221.81693)
			(xy 336.986626 -221.462092) (xy 336.963766 -221.457774) (xy 336.938966 -221.452574) (xy 336.89123 -221.435583)
			(xy 336.846655 -221.411489) (xy 336.806291 -221.380859) (xy 336.771089 -221.344414) (xy 336.741876 -221.303012)
			(xy 336.719342 -221.257629) (xy 336.704017 -221.209332) (xy 336.696261 -221.159259) (xy 336.695796 -221.133924)
			(xy 284.8356 -221.133924) (xy 284.8356 -224.389442) (xy 337.635596 -224.389442) (xy 337.636029 -224.364106)
			(xy 337.64379 -224.314032) (xy 337.65912 -224.265734) (xy 337.681659 -224.22035) (xy 337.710875 -224.178949)
			(xy 337.746081 -224.142504) (xy 337.786448 -224.111874) (xy 337.831026 -224.087781) (xy 337.878765 -224.070791)
			(xy 337.903566 -224.065592) (xy 337.926426 -224.061274) (xy 338.13115 -223.706182) (xy 338.12353 -223.684338)
			(xy 338.114887 -223.657995) (xy 338.105572 -223.603345) (xy 338.104988 -223.575626) (xy 338.105496 -223.549719)
			(xy 338.113602 -223.498542) (xy 338.129614 -223.449263) (xy 338.153137 -223.403096) (xy 338.183593 -223.361177)
			(xy 338.220231 -223.324539) (xy 338.26215 -223.294083) (xy 338.308317 -223.27056) (xy 338.357596 -223.254548)
			(xy 338.408773 -223.246442) (xy 338.460587 -223.246442) (xy 338.511764 -223.254548) (xy 338.561043 -223.27056)
			(xy 338.60721 -223.294083) (xy 338.649129 -223.324539) (xy 338.685767 -223.361177) (xy 338.716223 -223.403096)
			(xy 338.739746 -223.449263) (xy 338.755758 -223.498542) (xy 338.763864 -223.549719) (xy 338.764372 -223.575626)
			(xy 338.763897 -223.600971) (xy 338.756121 -223.651063) (xy 338.740771 -223.699374) (xy 338.718208 -223.744767)
			(xy 338.688966 -223.786173) (xy 338.653731 -223.822617) (xy 338.613335 -223.853239) (xy 338.568728 -223.877319)
			(xy 338.520962 -223.89429) (xy 338.496148 -223.899476) (xy 338.473288 -223.903794) (xy 338.268564 -224.258632)
			(xy 338.276184 -224.280476) (xy 338.284739 -224.306769) (xy 338.293932 -224.361289) (xy 338.294472 -224.388934)
			(xy 338.294472 -224.389442) (xy 338.575396 -224.389442) (xy 338.575904 -224.363555) (xy 338.584003 -224.312417)
			(xy 338.600002 -224.263177) (xy 338.623508 -224.217045) (xy 338.65394 -224.175158) (xy 338.69055 -224.138548)
			(xy 338.732437 -224.108116) (xy 338.778569 -224.08461) (xy 338.827809 -224.068611) (xy 338.878947 -224.060512)
			(xy 338.930721 -224.060512) (xy 338.981859 -224.068611) (xy 339.031099 -224.08461) (xy 339.077231 -224.108116)
			(xy 339.119118 -224.138548) (xy 339.155728 -224.175158) (xy 339.18616 -224.217045) (xy 339.209666 -224.263177)
			(xy 339.225665 -224.312417) (xy 339.233764 -224.363555) (xy 339.234272 -224.389442) (xy 339.515196 -224.389442)
			(xy 339.515629 -224.364106) (xy 339.52339 -224.314032) (xy 339.53872 -224.265734) (xy 339.561259 -224.22035)
			(xy 339.590475 -224.178949) (xy 339.625681 -224.142504) (xy 339.666048 -224.111874) (xy 339.710626 -224.087781)
			(xy 339.758365 -224.070791) (xy 339.783166 -224.065592) (xy 339.806026 -224.061274) (xy 340.01075 -223.706182)
			(xy 340.00313 -223.684338) (xy 339.994487 -223.657995) (xy 339.985172 -223.603345) (xy 339.984588 -223.575626)
			(xy 339.985096 -223.549719) (xy 339.993202 -223.498542) (xy 340.009214 -223.449263) (xy 340.032737 -223.403096)
			(xy 340.063193 -223.361177) (xy 340.099831 -223.324539) (xy 340.14175 -223.294083) (xy 340.187917 -223.27056)
			(xy 340.237196 -223.254548) (xy 340.288373 -223.246442) (xy 340.340187 -223.246442) (xy 340.391364 -223.254548)
			(xy 340.440643 -223.27056) (xy 340.48681 -223.294083) (xy 340.528729 -223.324539) (xy 340.565367 -223.361177)
			(xy 340.595823 -223.403096) (xy 340.619346 -223.449263) (xy 340.635358 -223.498542) (xy 340.643464 -223.549719)
			(xy 340.643972 -223.575626) (xy 340.643497 -223.600971) (xy 340.635721 -223.651063) (xy 340.620371 -223.699374)
			(xy 340.597808 -223.744767) (xy 340.568566 -223.786173) (xy 340.533331 -223.822617) (xy 340.492935 -223.853239)
			(xy 340.448328 -223.877319) (xy 340.400562 -223.89429) (xy 340.375748 -223.899476) (xy 340.352888 -223.903794)
			(xy 340.148164 -224.258632) (xy 340.155784 -224.280476) (xy 340.164339 -224.306769) (xy 340.173532 -224.361289)
			(xy 340.174072 -224.388934) (xy 340.174072 -224.389442) (xy 340.454996 -224.389442) (xy 340.455504 -224.363555)
			(xy 340.463603 -224.312417) (xy 340.479602 -224.263177) (xy 340.503108 -224.217045) (xy 340.53354 -224.175158)
			(xy 340.57015 -224.138548) (xy 340.612037 -224.108116) (xy 340.658169 -224.08461) (xy 340.707409 -224.068611)
			(xy 340.758547 -224.060512) (xy 340.810321 -224.060512) (xy 340.861459 -224.068611) (xy 340.910699 -224.08461)
			(xy 340.956831 -224.108116) (xy 340.998718 -224.138548) (xy 341.035328 -224.175158) (xy 341.06576 -224.217045)
			(xy 341.089266 -224.263177) (xy 341.105265 -224.312417) (xy 341.113364 -224.363555) (xy 341.113872 -224.389442)
			(xy 341.394796 -224.389442) (xy 341.395229 -224.364106) (xy 341.40299 -224.314032) (xy 341.41832 -224.265734)
			(xy 341.440859 -224.22035) (xy 341.470075 -224.178949) (xy 341.505281 -224.142504) (xy 341.545648 -224.111874)
			(xy 341.590226 -224.087781) (xy 341.637965 -224.070791) (xy 341.662766 -224.065592) (xy 341.685626 -224.061274)
			(xy 341.89035 -223.706436) (xy 341.88273 -223.684338) (xy 341.874102 -223.657991) (xy 341.864779 -223.603344)
			(xy 341.864188 -223.575626) (xy 341.864696 -223.549719) (xy 341.872802 -223.498542) (xy 341.888814 -223.449263)
			(xy 341.912337 -223.403096) (xy 341.942793 -223.361177) (xy 341.979431 -223.324539) (xy 342.02135 -223.294083)
			(xy 342.067517 -223.27056) (xy 342.116796 -223.254548) (xy 342.167973 -223.246442) (xy 342.219787 -223.246442)
			(xy 342.270964 -223.254548) (xy 342.320243 -223.27056) (xy 342.36641 -223.294083) (xy 342.408329 -223.324539)
			(xy 342.444967 -223.361177) (xy 342.475423 -223.403096) (xy 342.498946 -223.449263) (xy 342.514958 -223.498542)
			(xy 342.523064 -223.549719) (xy 342.523572 -223.575626) (xy 342.523181 -223.600993) (xy 342.515428 -223.651131)
			(xy 342.500077 -223.699486) (xy 342.477492 -223.744915) (xy 342.448207 -223.786344) (xy 342.412916 -223.822791)
			(xy 342.372452 -223.853396) (xy 342.327774 -223.877433) (xy 342.279939 -223.894334) (xy 342.255094 -223.899476)
			(xy 342.232234 -223.903794) (xy 342.02751 -224.258632) (xy 342.035384 -224.280476) (xy 342.043957 -224.306897)
			(xy 342.053158 -224.36167) (xy 342.053672 -224.389442) (xy 342.334596 -224.389442) (xy 342.335104 -224.363555)
			(xy 342.343203 -224.312417) (xy 342.359202 -224.263177) (xy 342.382708 -224.217045) (xy 342.41314 -224.175158)
			(xy 342.44975 -224.138548) (xy 342.491637 -224.108116) (xy 342.537769 -224.08461) (xy 342.587009 -224.068611)
			(xy 342.638147 -224.060512) (xy 342.689921 -224.060512) (xy 342.741059 -224.068611) (xy 342.790299 -224.08461)
			(xy 342.836431 -224.108116) (xy 342.878318 -224.138548) (xy 342.914928 -224.175158) (xy 342.94536 -224.217045)
			(xy 342.968866 -224.263177) (xy 342.984865 -224.312417) (xy 342.992964 -224.363555) (xy 342.993472 -224.389442)
			(xy 343.274396 -224.389442) (xy 343.274829 -224.364106) (xy 343.28259 -224.314032) (xy 343.29792 -224.265734)
			(xy 343.320459 -224.22035) (xy 343.349675 -224.178949) (xy 343.384881 -224.142504) (xy 343.425248 -224.111874)
			(xy 343.469826 -224.087781) (xy 343.517565 -224.070791) (xy 343.542366 -224.065592) (xy 343.565226 -224.061274)
			(xy 343.76995 -223.706436) (xy 343.76233 -223.684338) (xy 343.753702 -223.657991) (xy 343.744379 -223.603344)
			(xy 343.743788 -223.575626) (xy 343.744296 -223.549719) (xy 343.752402 -223.498542) (xy 343.768414 -223.449263)
			(xy 343.791937 -223.403096) (xy 343.822393 -223.361177) (xy 343.859031 -223.324539) (xy 343.90095 -223.294083)
			(xy 343.947117 -223.27056) (xy 343.996396 -223.254548) (xy 344.047573 -223.246442) (xy 344.099387 -223.246442)
			(xy 344.150564 -223.254548) (xy 344.199843 -223.27056) (xy 344.24601 -223.294083) (xy 344.287929 -223.324539)
			(xy 344.324567 -223.361177) (xy 344.355023 -223.403096) (xy 344.378546 -223.449263) (xy 344.394558 -223.498542)
			(xy 344.402664 -223.549719) (xy 344.403172 -223.575626) (xy 344.402781 -223.600993) (xy 344.395028 -223.651131)
			(xy 344.379677 -223.699486) (xy 344.357092 -223.744915) (xy 344.327807 -223.786344) (xy 344.292516 -223.822791)
			(xy 344.252052 -223.853396) (xy 344.207374 -223.877433) (xy 344.159539 -223.894334) (xy 344.134694 -223.899476)
			(xy 344.111834 -223.903794) (xy 343.90711 -224.258632) (xy 343.914984 -224.280476) (xy 343.923557 -224.306897)
			(xy 343.932758 -224.36167) (xy 343.933272 -224.389442) (xy 343.932764 -224.415329) (xy 343.924665 -224.466467)
			(xy 343.908666 -224.515707) (xy 343.88516 -224.561839) (xy 343.854728 -224.603726) (xy 343.818118 -224.640336)
			(xy 343.776231 -224.670768) (xy 343.730099 -224.694274) (xy 343.680859 -224.710273) (xy 343.629721 -224.718372)
			(xy 343.577947 -224.718372) (xy 343.526809 -224.710273) (xy 343.477569 -224.694274) (xy 343.431437 -224.670768)
			(xy 343.38955 -224.640336) (xy 343.35294 -224.603726) (xy 343.322508 -224.561839) (xy 343.299002 -224.515707)
			(xy 343.283003 -224.466467) (xy 343.274904 -224.415329) (xy 343.274396 -224.389442) (xy 342.993472 -224.389442)
			(xy 342.992925 -224.417149) (xy 342.983741 -224.471796) (xy 342.975184 -224.498154) (xy 342.96731 -224.520252)
			(xy 343.172288 -224.87509) (xy 343.195148 -224.879408) (xy 343.219971 -224.884565) (xy 343.267751 -224.90152)
			(xy 343.312371 -224.925592) (xy 343.352778 -224.956214) (xy 343.388019 -224.992662) (xy 343.417263 -225.034077)
			(xy 343.439819 -225.079482) (xy 343.455156 -225.127806) (xy 343.462911 -225.177908) (xy 343.463372 -225.203258)
			(xy 343.462864 -225.229165) (xy 343.454758 -225.280342) (xy 343.438746 -225.329621) (xy 343.415223 -225.375788)
			(xy 343.384767 -225.417707) (xy 343.348129 -225.454345) (xy 343.30621 -225.484801) (xy 343.260043 -225.508324)
			(xy 343.210764 -225.524336) (xy 343.159587 -225.532442) (xy 343.107773 -225.532442) (xy 343.056596 -225.524336)
			(xy 343.007317 -225.508324) (xy 342.96115 -225.484801) (xy 342.919231 -225.454345) (xy 342.882593 -225.417707)
			(xy 342.852137 -225.375788) (xy 342.828614 -225.329621) (xy 342.812602 -225.280342) (xy 342.804496 -225.229165)
			(xy 342.803988 -225.203258) (xy 342.804597 -225.175541) (xy 342.81391 -225.120895) (xy 342.82253 -225.094546)
			(xy 342.830404 -225.072448) (xy 342.625426 -224.71761) (xy 342.602566 -224.713292) (xy 342.577748 -224.708169)
			(xy 342.530005 -224.691172) (xy 342.485426 -224.667071) (xy 342.44506 -224.636431) (xy 342.409857 -224.599976)
			(xy 342.380648 -224.558564) (xy 342.358119 -224.51317) (xy 342.342801 -224.464863) (xy 342.335055 -224.414781)
			(xy 342.334596 -224.389442) (xy 342.053672 -224.389442) (xy 342.053164 -224.415329) (xy 342.045065 -224.466467)
			(xy 342.029066 -224.515707) (xy 342.00556 -224.561839) (xy 341.975128 -224.603726) (xy 341.938518 -224.640336)
			(xy 341.896631 -224.670768) (xy 341.850499 -224.694274) (xy 341.801259 -224.710273) (xy 341.750121 -224.718372)
			(xy 341.698347 -224.718372) (xy 341.647209 -224.710273) (xy 341.597969 -224.694274) (xy 341.551837 -224.670768)
			(xy 341.50995 -224.640336) (xy 341.47334 -224.603726) (xy 341.442908 -224.561839) (xy 341.419402 -224.515707)
			(xy 341.403403 -224.466467) (xy 341.395304 -224.415329) (xy 341.394796 -224.389442) (xy 341.113872 -224.389442)
			(xy 341.113872 -224.38995) (xy 341.113311 -224.417593) (xy 341.104122 -224.472111) (xy 341.095584 -224.498408)
			(xy 341.087964 -224.520252) (xy 341.292688 -224.87509) (xy 341.315548 -224.879408) (xy 341.340371 -224.884565)
			(xy 341.388151 -224.90152) (xy 341.432771 -224.925592) (xy 341.473178 -224.956214) (xy 341.508419 -224.992662)
			(xy 341.537663 -225.034077) (xy 341.560219 -225.079482) (xy 341.575556 -225.127806) (xy 341.583311 -225.177908)
			(xy 341.583772 -225.203258) (xy 341.583264 -225.229165) (xy 341.575158 -225.280342) (xy 341.559146 -225.329621)
			(xy 341.535623 -225.375788) (xy 341.505167 -225.417707) (xy 341.468529 -225.454345) (xy 341.42661 -225.484801)
			(xy 341.380443 -225.508324) (xy 341.331164 -225.524336) (xy 341.279987 -225.532442) (xy 341.228173 -225.532442)
			(xy 341.176996 -225.524336) (xy 341.127717 -225.508324) (xy 341.08155 -225.484801) (xy 341.039631 -225.454345)
			(xy 341.002993 -225.417707) (xy 340.972537 -225.375788) (xy 340.949014 -225.329621) (xy 340.933002 -225.280342)
			(xy 340.924896 -225.229165) (xy 340.924388 -225.203258) (xy 340.924388 -225.20275) (xy 340.924995 -225.175096)
			(xy 340.93432 -225.120578) (xy 340.94293 -225.094292) (xy 340.95055 -225.072448) (xy 340.745826 -224.71761)
			(xy 340.722966 -224.713292) (xy 340.698148 -224.708169) (xy 340.650405 -224.691172) (xy 340.605826 -224.667071)
			(xy 340.56546 -224.636431) (xy 340.530257 -224.599976) (xy 340.501048 -224.558564) (xy 340.478519 -224.51317)
			(xy 340.463201 -224.464863) (xy 340.455455 -224.414781) (xy 340.454996 -224.389442) (xy 340.174072 -224.389442)
			(xy 340.173564 -224.415329) (xy 340.165465 -224.466467) (xy 340.149466 -224.515707) (xy 340.12596 -224.561839)
			(xy 340.095528 -224.603726) (xy 340.058918 -224.640336) (xy 340.017031 -224.670768) (xy 339.970899 -224.694274)
			(xy 339.921659 -224.710273) (xy 339.870521 -224.718372) (xy 339.818747 -224.718372) (xy 339.767609 -224.710273)
			(xy 339.718369 -224.694274) (xy 339.672237 -224.670768) (xy 339.63035 -224.640336) (xy 339.59374 -224.603726)
			(xy 339.563308 -224.561839) (xy 339.539802 -224.515707) (xy 339.523803 -224.466467) (xy 339.515704 -224.415329)
			(xy 339.515196 -224.389442) (xy 339.234272 -224.389442) (xy 339.234272 -224.38995) (xy 339.233711 -224.417593)
			(xy 339.224522 -224.472111) (xy 339.215984 -224.498408) (xy 339.208364 -224.520252) (xy 339.413088 -224.87509)
			(xy 339.435948 -224.879408) (xy 339.460771 -224.884565) (xy 339.508551 -224.90152) (xy 339.553171 -224.925592)
			(xy 339.593578 -224.956214) (xy 339.628819 -224.992662) (xy 339.658063 -225.034077) (xy 339.680619 -225.079482)
			(xy 339.695956 -225.127806) (xy 339.703711 -225.177908) (xy 339.704172 -225.203258) (xy 339.703664 -225.229165)
			(xy 339.695558 -225.280342) (xy 339.679546 -225.329621) (xy 339.656023 -225.375788) (xy 339.625567 -225.417707)
			(xy 339.588929 -225.454345) (xy 339.54701 -225.484801) (xy 339.500843 -225.508324) (xy 339.451564 -225.524336)
			(xy 339.400387 -225.532442) (xy 339.348573 -225.532442) (xy 339.297396 -225.524336) (xy 339.248117 -225.508324)
			(xy 339.20195 -225.484801) (xy 339.160031 -225.454345) (xy 339.123393 -225.417707) (xy 339.092937 -225.375788)
			(xy 339.069414 -225.329621) (xy 339.053402 -225.280342) (xy 339.045296 -225.229165) (xy 339.044788 -225.203258)
			(xy 339.044788 -225.20275) (xy 339.045395 -225.175096) (xy 339.05472 -225.120578) (xy 339.06333 -225.094292)
			(xy 339.07095 -225.072448) (xy 338.866226 -224.71761) (xy 338.843366 -224.713292) (xy 338.818548 -224.708169)
			(xy 338.770805 -224.691172) (xy 338.726226 -224.667071) (xy 338.68586 -224.636431) (xy 338.650657 -224.599976)
			(xy 338.621448 -224.558564) (xy 338.598919 -224.51317) (xy 338.583601 -224.464863) (xy 338.575855 -224.414781)
			(xy 338.575396 -224.389442) (xy 338.294472 -224.389442) (xy 338.293964 -224.415329) (xy 338.285865 -224.466467)
			(xy 338.269866 -224.515707) (xy 338.24636 -224.561839) (xy 338.215928 -224.603726) (xy 338.179318 -224.640336)
			(xy 338.137431 -224.670768) (xy 338.091299 -224.694274) (xy 338.042059 -224.710273) (xy 337.990921 -224.718372)
			(xy 337.939147 -224.718372) (xy 337.888009 -224.710273) (xy 337.838769 -224.694274) (xy 337.792637 -224.670768)
			(xy 337.75075 -224.640336) (xy 337.71414 -224.603726) (xy 337.683708 -224.561839) (xy 337.660202 -224.515707)
			(xy 337.644203 -224.466467) (xy 337.636104 -224.415329) (xy 337.635596 -224.389442) (xy 284.8356 -224.389442)
			(xy 284.8356 -251.76988) (xy 323.635634 -251.76988) (xy 323.639615 -251.63686) (xy 323.651544 -251.504315)
			(xy 323.671379 -251.372722) (xy 323.699048 -251.24255) (xy 323.734452 -251.114265) (xy 323.777465 -250.988328)
			(xy 323.827932 -250.865189) (xy 323.885673 -250.745288) (xy 323.950482 -250.629055) (xy 324.022126 -250.516905)
			(xy 324.100348 -250.409241) (xy 324.184869 -250.306448) (xy 324.275387 -250.208893) (xy 324.371576 -250.116927)
			(xy 324.473094 -250.030877) (xy 324.579575 -249.951053) (xy 324.69064 -249.87774) (xy 324.805891 -249.8112)
			(xy 324.924915 -249.751671) (xy 325.047286 -249.699367) (xy 325.172565 -249.654475) (xy 325.300306 -249.617156)
			(xy 325.430049 -249.587543) (xy 325.561331 -249.565742) (xy 325.693682 -249.551832) (xy 325.826628 -249.545861)
			(xy 325.959693 -249.547852) (xy 326.092401 -249.557797) (xy 326.224277 -249.575661) (xy 326.354848 -249.601379)
			(xy 326.483648 -249.63486) (xy 326.610214 -249.675984) (xy 326.734095 -249.724604) (xy 326.854846 -249.780545)
			(xy 326.972036 -249.843607) (xy 327.085245 -249.913565) (xy 327.194067 -249.990169) (xy 327.298113 -250.073143)
			(xy 327.397011 -250.162191) (xy 327.490406 -250.256994) (xy 327.577964 -250.357212) (xy 327.659373 -250.462488)
			(xy 327.734339 -250.572444) (xy 327.802596 -250.686686) (xy 327.863898 -250.804806) (xy 327.918027 -250.926381)
			(xy 327.964788 -251.050975) (xy 328.004014 -251.178143) (xy 328.035564 -251.307429) (xy 328.059327 -251.43837)
			(xy 328.075216 -251.570498) (xy 328.083174 -251.70334) (xy 328.083672 -251.76988) (xy 328.083174 -251.83642)
			(xy 328.075216 -251.969262) (xy 328.059327 -252.10139) (xy 328.035564 -252.232331) (xy 328.004014 -252.361617)
			(xy 327.964788 -252.488785) (xy 327.918027 -252.613379) (xy 327.863898 -252.734954) (xy 327.802596 -252.853074)
			(xy 327.734339 -252.967316) (xy 327.659373 -253.077272) (xy 327.577964 -253.182548) (xy 327.490406 -253.282766)
			(xy 327.397011 -253.377569) (xy 327.298113 -253.466617) (xy 327.194067 -253.549591) (xy 327.085245 -253.626195)
			(xy 326.972036 -253.696153) (xy 326.854846 -253.759215) (xy 326.734095 -253.815156) (xy 326.610214 -253.863776)
			(xy 326.483648 -253.9049) (xy 326.354848 -253.938381) (xy 326.224277 -253.964099) (xy 326.092401 -253.981963)
			(xy 325.959693 -253.991908) (xy 325.826628 -253.993899) (xy 325.693682 -253.987928) (xy 325.561331 -253.974018)
			(xy 325.430049 -253.952217) (xy 325.300306 -253.922604) (xy 325.172565 -253.885285) (xy 325.047286 -253.840393)
			(xy 324.924915 -253.788089) (xy 324.805891 -253.72856) (xy 324.69064 -253.66202) (xy 324.579575 -253.588707)
			(xy 324.473094 -253.508883) (xy 324.371576 -253.422833) (xy 324.275387 -253.330867) (xy 324.184869 -253.233312)
			(xy 324.100348 -253.130519) (xy 324.022126 -253.022855) (xy 323.950482 -252.910705) (xy 323.885673 -252.794472)
			(xy 323.827932 -252.674571) (xy 323.777465 -252.551432) (xy 323.734452 -252.425495) (xy 323.699048 -252.29721)
			(xy 323.671379 -252.167038) (xy 323.651544 -252.035445) (xy 323.639615 -251.9029) (xy 323.635634 -251.76988)
			(xy 284.8356 -251.76988) (xy 284.8356 -274.266914) (xy 351.372424 -274.266914) (xy 351.372932 -274.241027)
			(xy 351.381031 -274.189889) (xy 351.39703 -274.140649) (xy 351.420536 -274.094517) (xy 351.450968 -274.05263)
			(xy 351.487578 -274.01602) (xy 351.529465 -273.985588) (xy 351.575597 -273.962082) (xy 351.624837 -273.946083)
			(xy 351.675975 -273.937984) (xy 351.727749 -273.937984) (xy 351.778887 -273.946083) (xy 351.828127 -273.962082)
			(xy 351.874259 -273.985588) (xy 351.916146 -274.01602) (xy 351.952756 -274.05263) (xy 351.983188 -274.094517)
			(xy 352.006694 -274.140649) (xy 352.022693 -274.189889) (xy 352.030792 -274.241027) (xy 352.0313 -274.266914)
			(xy 352.030745 -274.294558) (xy 352.021556 -274.349076) (xy 352.013012 -274.375372) (xy 352.005392 -274.397216)
			(xy 352.210624 -274.752562) (xy 352.233484 -274.75688) (xy 352.258307 -274.762037) (xy 352.306085 -274.778995)
			(xy 352.350703 -274.80307) (xy 352.391108 -274.833692) (xy 352.426348 -274.87014) (xy 352.455591 -274.911554)
			(xy 352.478148 -274.956958) (xy 352.493487 -275.00528) (xy 352.501245 -275.055381) (xy 352.501708 -275.08073)
			(xy 352.5012 -275.106637) (xy 352.493094 -275.157814) (xy 352.477082 -275.207093) (xy 352.453559 -275.25326)
			(xy 352.423103 -275.295179) (xy 352.386465 -275.331817) (xy 352.344546 -275.362273) (xy 352.298379 -275.385796)
			(xy 352.2491 -275.401808) (xy 352.197923 -275.409914) (xy 352.146109 -275.409914) (xy 352.094932 -275.401808)
			(xy 352.045653 -275.385796) (xy 351.999486 -275.362273) (xy 351.957567 -275.331817) (xy 351.920929 -275.295179)
			(xy 351.890473 -275.25326) (xy 351.86695 -275.207093) (xy 351.850938 -275.157814) (xy 351.842832 -275.106637)
			(xy 351.842324 -275.08073) (xy 351.842924 -275.053013) (xy 351.852243 -274.998366) (xy 351.860866 -274.972018)
			(xy 351.86874 -274.94992) (xy 351.663762 -274.595082) (xy 351.640902 -274.590764) (xy 351.616074 -274.585582)
			(xy 351.568269 -274.568647) (xy 351.523622 -274.544591) (xy 351.483185 -274.513981) (xy 351.447913 -274.47754)
			(xy 351.418638 -274.436127) (xy 351.39605 -274.390718) (xy 351.380683 -274.342387) (xy 351.372898 -274.292272)
			(xy 351.372424 -274.266914) (xy 284.8356 -274.266914) (xy 284.8356 -275.106588) (xy 349.963473 -275.106588)
			(xy 349.963473 -275.054812) (xy 349.971573 -275.003674) (xy 349.987573 -274.954432) (xy 350.011079 -274.9083)
			(xy 350.041513 -274.866413) (xy 350.078125 -274.829803) (xy 350.120014 -274.799371) (xy 350.166147 -274.775867)
			(xy 350.215389 -274.759869) (xy 350.266528 -274.751772) (xy 350.292416 -274.751292) (xy 350.317928 -274.751764)
			(xy 350.368343 -274.759627) (xy 350.416945 -274.775162) (xy 350.462573 -274.797999) (xy 350.504138 -274.827593)
			(xy 350.540648 -274.863237) (xy 350.556322 -274.883372) (xy 350.96831 -274.883372) (xy 350.98397 -274.863226)
			(xy 351.020483 -274.827584) (xy 351.062052 -274.797992) (xy 351.107683 -274.775158) (xy 351.156287 -274.759626)
			(xy 351.206703 -274.751768) (xy 351.232216 -274.751292) (xy 351.258105 -274.751741) (xy 351.309245 -274.759843)
			(xy 351.358488 -274.775845) (xy 351.404622 -274.799353) (xy 351.44651 -274.829789) (xy 351.483122 -274.866402)
			(xy 351.513555 -274.908292) (xy 351.537061 -274.954427) (xy 351.553061 -275.003671) (xy 351.56116 -275.054811)
			(xy 351.56116 -275.106589) (xy 351.553061 -275.157729) (xy 351.537061 -275.206973) (xy 351.513555 -275.253108)
			(xy 351.483122 -275.294998) (xy 351.44651 -275.331611) (xy 351.404622 -275.362047) (xy 351.358488 -275.385555)
			(xy 351.309245 -275.401557) (xy 351.258105 -275.409659) (xy 351.232216 -275.410168) (xy 351.206704 -275.409689)
			(xy 351.156289 -275.401829) (xy 351.107687 -275.386297) (xy 351.062058 -275.363461) (xy 351.020493 -275.333868)
			(xy 350.983983 -275.298224) (xy 350.96831 -275.278088) (xy 350.556322 -275.278088) (xy 350.540633 -275.29821)
			(xy 350.504126 -275.333856) (xy 350.462565 -275.363451) (xy 350.416939 -275.386289) (xy 350.36834 -275.401826)
			(xy 350.317927 -275.409689) (xy 350.292416 -275.410168) (xy 350.266528 -275.409628) (xy 350.215389 -275.401531)
			(xy 350.166147 -275.385533) (xy 350.120014 -275.362029) (xy 350.078125 -275.331597) (xy 350.041513 -275.294987)
			(xy 350.011079 -275.2531) (xy 349.987573 -275.206968) (xy 349.971573 -275.157726) (xy 349.963473 -275.106588)
			(xy 284.8356 -275.106588) (xy 284.8356 -276.708616) (xy 349.962724 -276.708616) (xy 349.963202 -276.683281)
			(xy 349.970953 -276.633207) (xy 349.986274 -276.584909) (xy 350.008806 -276.539525) (xy 350.038016 -276.498122)
			(xy 350.073218 -276.461676) (xy 350.113581 -276.431046) (xy 350.158157 -276.406953) (xy 350.205894 -276.389964)
			(xy 350.230694 -276.384766) (xy 350.253554 -276.380448) (xy 350.458532 -276.025356) (xy 350.450912 -276.003512)
			(xy 350.442352 -275.977154) (xy 350.433153 -275.922508) (xy 350.432624 -275.8948) (xy 350.433132 -275.868913)
			(xy 350.441231 -275.817775) (xy 350.45723 -275.768535) (xy 350.480736 -275.722403) (xy 350.511168 -275.680516)
			(xy 350.547778 -275.643906) (xy 350.589665 -275.613474) (xy 350.635797 -275.589968) (xy 350.685037 -275.573969)
			(xy 350.736175 -275.56587) (xy 350.787949 -275.56587) (xy 350.839087 -275.573969) (xy 350.888327 -275.589968)
			(xy 350.934459 -275.613474) (xy 350.976346 -275.643906) (xy 351.012956 -275.680516) (xy 351.043388 -275.722403)
			(xy 351.066894 -275.768535) (xy 351.082893 -275.817775) (xy 351.090992 -275.868913) (xy 351.0915 -275.8948)
			(xy 352.312224 -275.8948) (xy 352.312688 -275.869465) (xy 352.320441 -275.81939) (xy 352.335764 -275.771092)
			(xy 352.358298 -275.725707) (xy 352.38751 -275.684304) (xy 352.422713 -275.647859) (xy 352.463078 -275.617229)
			(xy 352.507655 -275.593136) (xy 352.555393 -275.576148) (xy 352.580194 -275.57095) (xy 352.603054 -275.566632)
			(xy 352.808286 -275.211286) (xy 352.800666 -275.189188) (xy 352.792042 -275.162906) (xy 352.782727 -275.108385)
			(xy 352.782124 -275.08073) (xy 352.782632 -275.054823) (xy 352.790738 -275.003646) (xy 352.80675 -274.954367)
			(xy 352.830273 -274.9082) (xy 352.860729 -274.866281) (xy 352.897367 -274.829643) (xy 352.939286 -274.799187)
			(xy 352.985453 -274.775664) (xy 353.034732 -274.759652) (xy 353.085909 -274.751546) (xy 353.137723 -274.751546)
			(xy 353.1889 -274.759652) (xy 353.238179 -274.775664) (xy 353.284346 -274.799187) (xy 353.326265 -274.829643)
			(xy 353.362903 -274.866281) (xy 353.393359 -274.9082) (xy 353.416882 -274.954367) (xy 353.432894 -275.003646)
			(xy 353.441 -275.054823) (xy 353.441508 -275.08073) (xy 353.441092 -275.106096) (xy 353.433338 -275.156231)
			(xy 353.417989 -275.204584) (xy 353.395406 -275.250011) (xy 353.366125 -275.291439) (xy 353.330837 -275.327886)
			(xy 353.290378 -275.358492) (xy 353.245704 -275.382531) (xy 353.197873 -275.399435) (xy 353.17303 -275.40458)
			(xy 353.149916 -275.408898) (xy 352.944938 -275.76399) (xy 352.952812 -275.786088) (xy 352.96137 -275.812447)
			(xy 352.97057 -275.867092) (xy 352.9711 -275.8948) (xy 352.970592 -275.920687) (xy 352.962493 -275.971825)
			(xy 352.946494 -276.021065) (xy 352.922988 -276.067197) (xy 352.892556 -276.109084) (xy 352.855946 -276.145694)
			(xy 352.814059 -276.176126) (xy 352.767927 -276.199632) (xy 352.718687 -276.215631) (xy 352.667549 -276.22373)
			(xy 352.615775 -276.22373) (xy 352.564637 -276.215631) (xy 352.515397 -276.199632) (xy 352.469265 -276.176126)
			(xy 352.427378 -276.145694) (xy 352.390768 -276.109084) (xy 352.360336 -276.067197) (xy 352.33683 -276.021065)
			(xy 352.320831 -275.971825) (xy 352.312732 -275.920687) (xy 352.312224 -275.8948) (xy 351.0915 -275.8948)
			(xy 351.090979 -275.920144) (xy 351.083207 -275.970232) (xy 351.067862 -276.018541) (xy 351.045306 -276.063932)
			(xy 351.016069 -276.105338) (xy 350.98084 -276.141782) (xy 350.940449 -276.172406) (xy 350.895848 -276.196488)
			(xy 350.848087 -276.213462) (xy 350.823276 -276.21865) (xy 350.800416 -276.222968) (xy 350.595438 -276.577806)
			(xy 350.603312 -276.599904) (xy 350.611874 -276.626262) (xy 350.621072 -276.680908) (xy 350.6216 -276.708616)
			(xy 350.902524 -276.708616) (xy 350.903032 -276.682709) (xy 350.911138 -276.631532) (xy 350.92715 -276.582253)
			(xy 350.950673 -276.536086) (xy 350.981129 -276.494167) (xy 351.017767 -276.457529) (xy 351.059686 -276.427073)
			(xy 351.105853 -276.40355) (xy 351.155132 -276.387538) (xy 351.206309 -276.379432) (xy 351.258123 -276.379432)
			(xy 351.3093 -276.387538) (xy 351.358579 -276.40355) (xy 351.404746 -276.427073) (xy 351.446665 -276.457529)
			(xy 351.483303 -276.494167) (xy 351.513759 -276.536086) (xy 351.537282 -276.582253) (xy 351.553294 -276.631532)
			(xy 351.5614 -276.682709) (xy 351.561908 -276.708616) (xy 351.561377 -276.734509) (xy 351.842805 -276.734509)
			(xy 351.842805 -276.682691) (xy 351.850912 -276.631511) (xy 351.866925 -276.582229) (xy 351.89045 -276.53606)
			(xy 351.920909 -276.494139) (xy 351.957551 -276.457499) (xy 351.999473 -276.427042) (xy 352.045644 -276.403519)
			(xy 352.094927 -276.387508) (xy 352.146107 -276.379404) (xy 352.172016 -276.378924) (xy 352.197529 -276.379383)
			(xy 352.247945 -276.387247) (xy 352.296547 -276.402784) (xy 352.342175 -276.425624) (xy 352.38374 -276.45522)
			(xy 352.420249 -276.490867) (xy 352.435922 -276.511004) (xy 352.84791 -276.511004) (xy 352.863579 -276.490865)
			(xy 352.900089 -276.455221) (xy 352.941656 -276.425628) (xy 352.987285 -276.402792) (xy 353.035888 -276.387259)
			(xy 353.086304 -276.3794) (xy 353.111816 -276.378924) (xy 353.137724 -276.379401) (xy 353.188901 -276.387509)
			(xy 353.23818 -276.403523) (xy 353.284347 -276.427048) (xy 353.326266 -276.457506) (xy 353.362904 -276.494146)
			(xy 353.39336 -276.536066) (xy 353.416883 -276.582235) (xy 353.432895 -276.631514) (xy 353.441 -276.682692)
			(xy 353.441 -276.734508) (xy 353.432895 -276.785686) (xy 353.416883 -276.834965) (xy 353.39336 -276.881134)
			(xy 353.362904 -276.923054) (xy 353.326266 -276.959694) (xy 353.284347 -276.990152) (xy 353.23818 -277.013677)
			(xy 353.188901 -277.029691) (xy 353.137724 -277.037799) (xy 353.111816 -277.038308) (xy 353.086305 -277.037813)
			(xy 353.035891 -277.029955) (xy 352.98729 -277.014424) (xy 352.941662 -276.991591) (xy 352.900096 -276.962001)
			(xy 352.863585 -276.926361) (xy 352.84791 -276.906228) (xy 352.435922 -276.906228) (xy 352.420244 -276.926359)
			(xy 352.383734 -276.962002) (xy 352.342169 -276.991595) (xy 352.296542 -277.014432) (xy 352.247941 -277.029967)
			(xy 352.197528 -277.03783) (xy 352.172016 -277.038308) (xy 352.146107 -277.037796) (xy 352.094927 -277.029692)
			(xy 352.045644 -277.013681) (xy 351.999473 -276.990158) (xy 351.957551 -276.959701) (xy 351.920909 -276.923061)
			(xy 351.89045 -276.88114) (xy 351.866925 -276.834971) (xy 351.850912 -276.785689) (xy 351.842805 -276.734509)
			(xy 351.561377 -276.734509) (xy 351.561338 -276.736398) (xy 351.552014 -276.791174) (xy 351.543366 -276.817582)
			(xy 351.535492 -276.839426) (xy 351.74047 -277.194264) (xy 351.76333 -277.198582) (xy 351.788142 -277.203733)
			(xy 351.835882 -277.220727) (xy 351.88046 -277.244826) (xy 351.920825 -277.275462) (xy 351.956028 -277.311913)
			(xy 351.985239 -277.353322) (xy 352.007769 -277.398712) (xy 352.02309 -277.447016) (xy 352.030838 -277.497095)
			(xy 352.0313 -277.522432) (xy 354.191824 -277.522432) (xy 354.192226 -277.497095) (xy 354.199989 -277.447018)
			(xy 354.215322 -277.398718) (xy 354.237864 -277.353333) (xy 354.267084 -277.31193) (xy 354.302294 -277.275486)
			(xy 354.342666 -277.244857) (xy 354.387248 -277.220766) (xy 354.434991 -277.203779) (xy 354.459794 -277.198582)
			(xy 354.482654 -277.194264) (xy 354.687886 -276.838918) (xy 354.680266 -276.817074) (xy 354.671663 -276.790785)
			(xy 354.662334 -276.736269) (xy 354.661724 -276.708616) (xy 354.662232 -276.682709) (xy 354.670338 -276.631532)
			(xy 354.68635 -276.582253) (xy 354.709873 -276.536086) (xy 354.740329 -276.494167) (xy 354.776967 -276.457529)
			(xy 354.818886 -276.427073) (xy 354.865053 -276.40355) (xy 354.914332 -276.387538) (xy 354.965509 -276.379432)
			(xy 355.017323 -276.379432) (xy 355.0685 -276.387538) (xy 355.117779 -276.40355) (xy 355.163946 -276.427073)
			(xy 355.205865 -276.457529) (xy 355.242503 -276.494167) (xy 355.272959 -276.536086) (xy 355.296482 -276.582253)
			(xy 355.312494 -276.631532) (xy 355.3206 -276.682709) (xy 355.321108 -276.708616) (xy 355.320641 -276.73399)
			(xy 355.312871 -276.784141) (xy 355.297501 -276.832506) (xy 355.274895 -276.877942) (xy 355.245588 -276.919373)
			(xy 355.210273 -276.955819) (xy 355.169787 -276.986418) (xy 355.125087 -277.010445) (xy 355.07723 -277.027332)
			(xy 355.052376 -277.032466) (xy 355.029516 -277.036784) (xy 354.824538 -277.391622) (xy 354.832412 -277.41372)
			(xy 354.840977 -277.440077) (xy 354.850173 -277.494724) (xy 354.8507 -277.522432) (xy 354.850192 -277.548319)
			(xy 354.842093 -277.599457) (xy 354.826094 -277.648697) (xy 354.802588 -277.694829) (xy 354.772156 -277.736716)
			(xy 354.735546 -277.773326) (xy 354.693659 -277.803758) (xy 354.647527 -277.827264) (xy 354.598287 -277.843263)
			(xy 354.547149 -277.851362) (xy 354.495375 -277.851362) (xy 354.444237 -277.843263) (xy 354.394997 -277.827264)
			(xy 354.348865 -277.803758) (xy 354.306978 -277.773326) (xy 354.270368 -277.736716) (xy 354.239936 -277.694829)
			(xy 354.21643 -277.648697) (xy 354.200431 -277.599457) (xy 354.192332 -277.548319) (xy 354.191824 -277.522432)
			(xy 352.0313 -277.522432) (xy 352.030792 -277.548319) (xy 352.022693 -277.599457) (xy 352.006694 -277.648697)
			(xy 351.983188 -277.694829) (xy 351.952756 -277.736716) (xy 351.916146 -277.773326) (xy 351.874259 -277.803758)
			(xy 351.828127 -277.827264) (xy 351.778887 -277.843263) (xy 351.727749 -277.851362) (xy 351.675975 -277.851362)
			(xy 351.624837 -277.843263) (xy 351.575597 -277.827264) (xy 351.529465 -277.803758) (xy 351.487578 -277.773326)
			(xy 351.450968 -277.736716) (xy 351.420536 -277.694829) (xy 351.39703 -277.648697) (xy 351.381031 -277.599457)
			(xy 351.372932 -277.548319) (xy 351.372424 -277.522432) (xy 351.37296 -277.494724) (xy 351.382151 -277.440077)
			(xy 351.390712 -277.41372) (xy 351.398586 -277.391622) (xy 351.193608 -277.036784) (xy 351.170748 -277.032466)
			(xy 351.145918 -277.027336) (xy 351.098136 -277.010379) (xy 351.053515 -276.986304) (xy 351.013107 -276.955679)
			(xy 350.977866 -276.919227) (xy 350.948624 -276.877808) (xy 350.926069 -276.8324) (xy 350.910735 -276.784072)
			(xy 350.902983 -276.733967) (xy 350.902524 -276.708616) (xy 350.6216 -276.708616) (xy 350.621092 -276.734503)
			(xy 350.612993 -276.785641) (xy 350.596994 -276.834881) (xy 350.573488 -276.881013) (xy 350.543056 -276.9229)
			(xy 350.506446 -276.95951) (xy 350.464559 -276.989942) (xy 350.418427 -277.013448) (xy 350.369187 -277.029447)
			(xy 350.318049 -277.037546) (xy 350.266275 -277.037546) (xy 350.215137 -277.029447) (xy 350.165897 -277.013448)
			(xy 350.119765 -276.989942) (xy 350.077878 -276.95951) (xy 350.041268 -276.9229) (xy 350.010836 -276.881013)
			(xy 349.98733 -276.834881) (xy 349.971331 -276.785641) (xy 349.963232 -276.734503) (xy 349.962724 -276.708616)
			(xy 284.8356 -276.708616) (xy 284.8356 -279.150318) (xy 349.492824 -279.150318) (xy 349.493332 -279.124431)
			(xy 349.501431 -279.073293) (xy 349.51743 -279.024053) (xy 349.540936 -278.977921) (xy 349.571368 -278.936034)
			(xy 349.607978 -278.899424) (xy 349.649865 -278.868992) (xy 349.695997 -278.845486) (xy 349.745237 -278.829487)
			(xy 349.796375 -278.821388) (xy 349.848149 -278.821388) (xy 349.899287 -278.829487) (xy 349.948527 -278.845486)
			(xy 349.994659 -278.868992) (xy 350.036546 -278.899424) (xy 350.073156 -278.936034) (xy 350.103588 -278.977921)
			(xy 350.127094 -279.024053) (xy 350.143093 -279.073293) (xy 350.151192 -279.124431) (xy 350.1517 -279.150318)
			(xy 350.151182 -279.176184) (xy 350.433187 -279.176184) (xy 350.433187 -279.124416) (xy 350.441285 -279.073285)
			(xy 350.457281 -279.02405) (xy 350.480782 -278.977924) (xy 350.511209 -278.936041) (xy 350.547812 -278.899433)
			(xy 350.589691 -278.869002) (xy 350.635815 -278.845496) (xy 350.685048 -278.829494) (xy 350.736178 -278.82139)
			(xy 350.762062 -278.82088) (xy 350.787572 -278.821396) (xy 350.837985 -278.82925) (xy 350.886585 -278.844777)
			(xy 350.932214 -278.867606) (xy 350.97378 -278.897192) (xy 351.010293 -278.932828) (xy 351.025968 -278.95296)
			(xy 351.437956 -278.95296) (xy 351.453644 -278.932837) (xy 351.490152 -278.897194) (xy 351.531715 -278.8676)
			(xy 351.57734 -278.844762) (xy 351.625939 -278.829225) (xy 351.676351 -278.82136) (xy 351.701862 -278.82088)
			(xy 351.727755 -278.821322) (xy 351.778904 -278.829418) (xy 351.828156 -278.845416) (xy 351.874299 -278.868923)
			(xy 351.916197 -278.899359) (xy 351.952817 -278.935974) (xy 351.983257 -278.977868) (xy 352.006769 -279.024009)
			(xy 352.022773 -279.073259) (xy 352.030875 -279.124407) (xy 352.030875 -279.176193) (xy 352.022773 -279.227341)
			(xy 352.006769 -279.276591) (xy 351.983257 -279.322732) (xy 351.952817 -279.364626) (xy 351.916197 -279.401241)
			(xy 351.874299 -279.431677) (xy 351.828156 -279.455184) (xy 351.778904 -279.471182) (xy 351.727755 -279.479278)
			(xy 351.701862 -279.479756) (xy 351.676348 -279.47932) (xy 351.625931 -279.471453) (xy 351.577328 -279.455912)
			(xy 351.531699 -279.433068) (xy 351.490135 -279.403466) (xy 351.453628 -279.367815) (xy 351.437956 -279.347676)
			(xy 351.025968 -279.347676) (xy 351.010307 -279.367822) (xy 350.973795 -279.403466) (xy 350.932228 -279.433059)
			(xy 350.886597 -279.455894) (xy 350.837992 -279.471425) (xy 350.787575 -279.479281) (xy 350.762062 -279.479756)
			(xy 350.736178 -279.47921) (xy 350.685048 -279.471106) (xy 350.635815 -279.455104) (xy 350.589691 -279.431598)
			(xy 350.547812 -279.401167) (xy 350.511209 -279.364559) (xy 350.480782 -279.322676) (xy 350.457281 -279.27655)
			(xy 350.441285 -279.227315) (xy 350.433187 -279.176184) (xy 350.151182 -279.176184) (xy 350.151146 -279.177962)
			(xy 350.141956 -279.23248) (xy 350.133412 -279.258776) (xy 350.125792 -279.28062) (xy 350.331024 -279.635966)
			(xy 350.353884 -279.640284) (xy 350.378708 -279.645438) (xy 350.426486 -279.662396) (xy 350.471104 -279.68647)
			(xy 350.511509 -279.717093) (xy 350.546749 -279.753542) (xy 350.575992 -279.794956) (xy 350.598549 -279.84036)
			(xy 350.613887 -279.888683) (xy 350.621645 -279.938785) (xy 350.622108 -279.964134) (xy 350.6216 -279.990041)
			(xy 350.613494 -280.041218) (xy 350.597482 -280.090497) (xy 350.573959 -280.136664) (xy 350.543503 -280.178583)
			(xy 350.506865 -280.215221) (xy 350.464946 -280.245677) (xy 350.418779 -280.2692) (xy 350.3695 -280.285212)
			(xy 350.318323 -280.293318) (xy 350.266509 -280.293318) (xy 350.215332 -280.285212) (xy 350.166053 -280.2692)
			(xy 350.119886 -280.245677) (xy 350.077967 -280.215221) (xy 350.041329 -280.178583) (xy 350.010873 -280.136664)
			(xy 349.98735 -280.090497) (xy 349.971338 -280.041218) (xy 349.963232 -279.990041) (xy 349.962724 -279.964134)
			(xy 349.963325 -279.936417) (xy 349.972644 -279.88177) (xy 349.981266 -279.855422) (xy 349.98914 -279.833324)
			(xy 349.784162 -279.478486) (xy 349.761302 -279.474168) (xy 349.736475 -279.468982) (xy 349.688671 -279.452048)
			(xy 349.644023 -279.427992) (xy 349.603586 -279.397383) (xy 349.568314 -279.360942) (xy 349.539039 -279.319529)
			(xy 349.516451 -279.274121) (xy 349.501083 -279.22579) (xy 349.493299 -279.175676) (xy 349.492824 -279.150318)
			(xy 284.8356 -279.150318) (xy 284.8356 -279.989983) (xy 336.806103 -279.989983) (xy 336.806103 -279.938217)
			(xy 336.814201 -279.887089) (xy 336.830196 -279.837856) (xy 336.853696 -279.791732) (xy 336.884121 -279.749851)
			(xy 336.920722 -279.713245) (xy 336.9626 -279.682815) (xy 337.008721 -279.659311) (xy 337.057952 -279.64331)
			(xy 337.109079 -279.635206) (xy 337.134962 -279.634696) (xy 337.160473 -279.635206) (xy 337.210886 -279.64306)
			(xy 337.259487 -279.658588) (xy 337.305115 -279.681418) (xy 337.346681 -279.711006) (xy 337.383193 -279.746643)
			(xy 337.398868 -279.766776) (xy 337.810856 -279.766776) (xy 337.826548 -279.746656) (xy 337.863055 -279.711012)
			(xy 337.904617 -279.681418) (xy 337.950241 -279.658579) (xy 337.998839 -279.643041) (xy 338.049251 -279.635176)
			(xy 338.074762 -279.634696) (xy 338.100656 -279.635106) (xy 338.151807 -279.643203) (xy 338.201062 -279.659201)
			(xy 338.247208 -279.682709) (xy 338.289107 -279.713146) (xy 338.325729 -279.749764) (xy 338.356171 -279.79166)
			(xy 338.379684 -279.837803) (xy 338.395689 -279.887056) (xy 338.403791 -279.938206) (xy 338.403791 -279.964134)
			(xy 344.323924 -279.964134) (xy 344.324432 -279.938227) (xy 344.332538 -279.88705) (xy 344.34855 -279.837771)
			(xy 344.372073 -279.791604) (xy 344.402529 -279.749685) (xy 344.439167 -279.713047) (xy 344.481086 -279.682591)
			(xy 344.527253 -279.659068) (xy 344.576532 -279.643056) (xy 344.627709 -279.63495) (xy 344.679523 -279.63495)
			(xy 344.7307 -279.643056) (xy 344.779979 -279.659068) (xy 344.826146 -279.682591) (xy 344.868065 -279.713047)
			(xy 344.904703 -279.749685) (xy 344.935159 -279.791604) (xy 344.958682 -279.837771) (xy 344.974694 -279.88705)
			(xy 344.9828 -279.938227) (xy 344.983308 -279.964134) (xy 344.982671 -279.991925) (xy 344.973225 -280.046702)
			(xy 344.964512 -280.0731) (xy 344.956892 -280.095198) (xy 345.16187 -280.450036) (xy 345.18473 -280.454354)
			(xy 345.209535 -280.459531) (xy 345.257274 -280.476523) (xy 345.30185 -280.500619) (xy 345.342215 -280.531252)
			(xy 345.377417 -280.5677) (xy 345.406629 -280.609105) (xy 345.429161 -280.654492) (xy 345.444484 -280.702792)
			(xy 345.452236 -280.752868) (xy 345.4527 -280.778204) (xy 345.452192 -280.804091) (xy 345.444093 -280.855229)
			(xy 345.428094 -280.904469) (xy 345.404588 -280.950601) (xy 345.374156 -280.992488) (xy 345.337546 -281.029098)
			(xy 345.295659 -281.05953) (xy 345.249527 -281.083036) (xy 345.200287 -281.099035) (xy 345.149149 -281.107134)
			(xy 345.097375 -281.107134) (xy 345.046237 -281.099035) (xy 344.996997 -281.083036) (xy 344.950865 -281.05953)
			(xy 344.908978 -281.029098) (xy 344.872368 -280.992488) (xy 344.841936 -280.950601) (xy 344.81843 -280.904469)
			(xy 344.802431 -280.855229) (xy 344.794332 -280.804091) (xy 344.793824 -280.778204) (xy 344.794353 -280.750496)
			(xy 344.803549 -280.695849) (xy 344.812112 -280.669492) (xy 344.819986 -280.647394) (xy 344.614754 -280.292302)
			(xy 344.591894 -280.287984) (xy 344.567101 -280.282754) (xy 344.519365 -280.265768) (xy 344.47479 -280.241678)
			(xy 344.434426 -280.211052) (xy 344.399223 -280.174611) (xy 344.37001 -280.133213) (xy 344.347475 -280.087832)
			(xy 344.332148 -280.039538) (xy 344.32439 -279.989468) (xy 344.323924 -279.964134) (xy 338.403791 -279.964134)
			(xy 338.403791 -279.989994) (xy 338.395689 -280.041144) (xy 338.379684 -280.090397) (xy 338.356171 -280.13654)
			(xy 338.325729 -280.178436) (xy 338.289107 -280.215054) (xy 338.247208 -280.245491) (xy 338.201062 -280.268999)
			(xy 338.151807 -280.284997) (xy 338.100656 -280.293094) (xy 338.074762 -280.293572) (xy 338.049249 -280.293131)
			(xy 337.998832 -280.285263) (xy 337.950229 -280.269723) (xy 337.9046 -280.24688) (xy 337.863036 -280.21728)
			(xy 337.826528 -280.18163) (xy 337.810856 -280.161492) (xy 337.398868 -280.161492) (xy 337.383211 -280.181641)
			(xy 337.346698 -280.217284) (xy 337.305129 -280.246877) (xy 337.259498 -280.269711) (xy 337.210893 -280.285241)
			(xy 337.160475 -280.293097) (xy 337.134962 -280.293572) (xy 337.109079 -280.292994) (xy 337.057952 -280.28489)
			(xy 337.008721 -280.268889) (xy 336.9626 -280.245385) (xy 336.920722 -280.214955) (xy 336.884121 -280.178349)
			(xy 336.853696 -280.136468) (xy 336.830196 -280.090344) (xy 336.814201 -280.041111) (xy 336.806103 -279.989983)
			(xy 284.8356 -279.989983) (xy 284.8356 -280.804105) (xy 334.45632 -280.804105) (xy 334.45632 -280.752295)
			(xy 334.464425 -280.701122) (xy 334.480434 -280.651848) (xy 334.503953 -280.605684) (xy 334.534405 -280.563767)
			(xy 334.571038 -280.527129) (xy 334.612951 -280.496673) (xy 334.659113 -280.473148) (xy 334.708385 -280.457133)
			(xy 334.759557 -280.449023) (xy 334.785462 -280.448512) (xy 334.810955 -280.449019) (xy 334.861331 -280.456875)
			(xy 334.909894 -280.472404) (xy 334.955481 -280.495237) (xy 334.997003 -280.524825) (xy 335.033465 -280.560462)
			(xy 335.049114 -280.580592) (xy 335.46161 -280.580592) (xy 335.477279 -280.560477) (xy 335.513736 -280.524835)
			(xy 335.555252 -280.495239) (xy 335.600835 -280.472399) (xy 335.649395 -280.45686) (xy 335.699769 -280.448993)
			(xy 335.725262 -280.448512) (xy 335.751174 -280.448983) (xy 335.80236 -280.457084) (xy 335.851648 -280.473094)
			(xy 335.897825 -280.496618) (xy 335.939753 -280.527076) (xy 335.9764 -280.563718) (xy 336.006863 -280.605643)
			(xy 336.030391 -280.651817) (xy 336.046407 -280.701103) (xy 336.054514 -280.752288) (xy 336.054514 -280.804112)
			(xy 336.046407 -280.855297) (xy 336.030391 -280.904583) (xy 336.006863 -280.950757) (xy 335.9764 -280.992682)
			(xy 335.939753 -281.029324) (xy 335.897825 -281.059782) (xy 335.851648 -281.083306) (xy 335.80236 -281.099316)
			(xy 335.751174 -281.107417) (xy 335.725262 -281.107896) (xy 335.699767 -281.107441) (xy 335.649389 -281.099574)
			(xy 335.600825 -281.084033) (xy 335.555238 -281.061192) (xy 335.513718 -281.031594) (xy 335.477257 -280.99595)
			(xy 335.46161 -280.975816) (xy 335.049114 -280.975816) (xy 335.033491 -280.995969) (xy 334.997025 -281.031609)
			(xy 334.955498 -281.061199) (xy 334.909906 -281.084033) (xy 334.861339 -281.099564) (xy 334.810957 -281.107421)
			(xy 334.785462 -281.107896) (xy 334.759557 -281.107377) (xy 334.708385 -281.099267) (xy 334.659113 -281.083252)
			(xy 334.612951 -281.059727) (xy 334.571038 -281.029271) (xy 334.534405 -280.992633) (xy 334.503953 -280.950716)
			(xy 334.480434 -280.904552) (xy 334.464425 -280.855278) (xy 334.45632 -280.804105) (xy 284.8356 -280.804105)
			(xy 284.8356 -282.405836) (xy 334.456024 -282.405836) (xy 334.456468 -282.38049) (xy 334.46425 -282.330397)
			(xy 334.479605 -282.282085) (xy 334.502171 -282.236692) (xy 334.531418 -282.195286) (xy 334.566656 -282.158843)
			(xy 334.607056 -282.128222) (xy 334.651665 -282.104142) (xy 334.699433 -282.087172) (xy 334.724248 -282.081986)
			(xy 334.747108 -282.077668) (xy 334.952086 -281.722576) (xy 334.944466 -281.700732) (xy 334.93582 -281.67439)
			(xy 334.926507 -281.619739) (xy 334.925924 -281.59202) (xy 334.926432 -281.566113) (xy 334.934538 -281.514936)
			(xy 334.95055 -281.465657) (xy 334.974073 -281.41949) (xy 335.004529 -281.377571) (xy 335.041167 -281.340933)
			(xy 335.083086 -281.310477) (xy 335.129253 -281.286954) (xy 335.178532 -281.270942) (xy 335.229709 -281.262836)
			(xy 335.281523 -281.262836) (xy 335.3327 -281.270942) (xy 335.381979 -281.286954) (xy 335.428146 -281.310477)
			(xy 335.470065 -281.340933) (xy 335.506703 -281.377571) (xy 335.537159 -281.41949) (xy 335.560682 -281.465657)
			(xy 335.576694 -281.514936) (xy 335.5848 -281.566113) (xy 335.585308 -281.59202) (xy 336.805524 -281.59202)
			(xy 336.806044 -281.566676) (xy 336.813813 -281.516587) (xy 336.829157 -281.468277) (xy 336.851713 -281.422884)
			(xy 336.88095 -281.381477) (xy 336.916179 -281.345033) (xy 336.956571 -281.31441) (xy 337.001174 -281.290329)
			(xy 337.048936 -281.273357) (xy 337.073748 -281.26817) (xy 337.096608 -281.263852) (xy 337.301586 -280.909014)
			(xy 337.293966 -280.88717) (xy 337.285321 -280.860761) (xy 337.276 -280.805986) (xy 337.275424 -280.778204)
			(xy 337.275919 -280.752309) (xy 337.284017 -280.701155) (xy 337.300013 -280.651897) (xy 337.323515 -280.605746)
			(xy 337.353945 -280.563837) (xy 337.390553 -280.527202) (xy 337.432439 -280.496742) (xy 337.478573 -280.473206)
			(xy 337.527819 -280.457173) (xy 337.578967 -280.449038) (xy 337.604862 -280.448512) (xy 337.630766 -280.448979)
			(xy 337.681935 -280.457083) (xy 337.731205 -280.473097) (xy 337.777361 -280.496626) (xy 337.819265 -280.52709)
			(xy 337.855883 -280.563738) (xy 337.886313 -280.605666) (xy 337.909805 -280.651841) (xy 337.925779 -280.701124)
			(xy 337.933841 -280.7523) (xy 337.9343 -280.778204) (xy 340.094824 -280.778204) (xy 340.095293 -280.752294)
			(xy 340.103399 -280.701112) (xy 340.119413 -280.651828) (xy 340.142939 -280.605656) (xy 340.173399 -280.563733)
			(xy 340.210042 -280.527091) (xy 340.251966 -280.496633) (xy 340.298139 -280.473108) (xy 340.347423 -280.457097)
			(xy 340.398606 -280.448992) (xy 340.424516 -280.448512) (xy 340.450421 -280.448929) (xy 340.501592 -280.457041)
			(xy 340.550863 -280.473063) (xy 340.597019 -280.496598) (xy 340.638922 -280.527068) (xy 340.67554 -280.563721)
			(xy 340.705969 -280.605654) (xy 340.72946 -280.651833) (xy 340.745433 -280.701119) (xy 340.753496 -280.752298)
			(xy 340.753954 -280.778204) (xy 340.753418 -280.804105) (xy 342.91452 -280.804105) (xy 342.91452 -280.752295)
			(xy 342.922625 -280.701122) (xy 342.938634 -280.651848) (xy 342.962153 -280.605684) (xy 342.992605 -280.563767)
			(xy 343.029238 -280.527129) (xy 343.071151 -280.496673) (xy 343.117313 -280.473148) (xy 343.166585 -280.457133)
			(xy 343.217757 -280.449023) (xy 343.243662 -280.448512) (xy 343.269173 -280.449015) (xy 343.319587 -280.45687)
			(xy 343.368188 -280.472399) (xy 343.413817 -280.49523) (xy 343.455383 -280.524819) (xy 343.491894 -280.560459)
			(xy 343.507568 -280.580592) (xy 343.91981 -280.580592) (xy 343.935476 -280.56045) (xy 343.971987 -280.524807)
			(xy 344.013554 -280.495214) (xy 344.059184 -280.472379) (xy 344.107788 -280.456847) (xy 344.158204 -280.448988)
			(xy 344.183716 -280.448512) (xy 344.209623 -280.449014) (xy 344.260798 -280.457121) (xy 344.310075 -280.473134)
			(xy 344.356241 -280.496659) (xy 344.398158 -280.527115) (xy 344.434795 -280.563754) (xy 344.465249 -280.605673)
			(xy 344.488772 -280.65184) (xy 344.504782 -280.701117) (xy 344.512888 -280.752293) (xy 344.512888 -280.804107)
			(xy 344.504782 -280.855283) (xy 344.488772 -280.90456) (xy 344.465249 -280.950727) (xy 344.434795 -280.992646)
			(xy 344.398158 -281.029285) (xy 344.356241 -281.059741) (xy 344.310075 -281.083266) (xy 344.260798 -281.099279)
			(xy 344.209623 -281.107386) (xy 344.183716 -281.107896) (xy 344.158205 -281.107405) (xy 344.107791 -281.099547)
			(xy 344.059189 -281.084016) (xy 344.013561 -281.061182) (xy 343.971995 -281.031591) (xy 343.935484 -280.99595)
			(xy 343.91981 -280.975816) (xy 343.507568 -280.975816) (xy 343.491917 -280.99597) (xy 343.455403 -281.031612)
			(xy 343.413832 -281.061203) (xy 343.368199 -281.084036) (xy 343.319593 -281.099566) (xy 343.269175 -281.107421)
			(xy 343.243662 -281.107896) (xy 343.217757 -281.107377) (xy 343.166585 -281.099267) (xy 343.117313 -281.083252)
			(xy 343.071151 -281.059727) (xy 343.029238 -281.029271) (xy 342.992605 -280.992633) (xy 342.962153 -280.950716)
			(xy 342.938634 -280.904552) (xy 342.922625 -280.855278) (xy 342.91452 -280.804105) (xy 340.753418 -280.804105)
			(xy 340.753379 -280.805986) (xy 340.744058 -280.860762) (xy 340.735412 -280.88717) (xy 340.727792 -280.909014)
			(xy 340.93277 -281.263852) (xy 340.95563 -281.26817) (xy 340.980439 -281.273332) (xy 341.028178 -281.290325)
			(xy 341.072756 -281.314423) (xy 341.113121 -281.345058) (xy 341.148323 -281.381508) (xy 341.177534 -281.422915)
			(xy 341.200066 -281.468304) (xy 341.215387 -281.516606) (xy 341.223138 -281.566683) (xy 341.2236 -281.59202)
			(xy 341.223092 -281.617907) (xy 341.214993 -281.669045) (xy 341.198994 -281.718285) (xy 341.175488 -281.764417)
			(xy 341.145056 -281.806304) (xy 341.108446 -281.842914) (xy 341.066559 -281.873346) (xy 341.020427 -281.896852)
			(xy 340.971187 -281.912851) (xy 340.920049 -281.92095) (xy 340.868275 -281.92095) (xy 340.817137 -281.912851)
			(xy 340.767897 -281.896852) (xy 340.721765 -281.873346) (xy 340.679878 -281.842914) (xy 340.643268 -281.806304)
			(xy 340.612836 -281.764417) (xy 340.58933 -281.718285) (xy 340.573331 -281.669045) (xy 340.565232 -281.617907)
			(xy 340.564724 -281.59202) (xy 340.565273 -281.564313) (xy 340.574459 -281.509667) (xy 340.583012 -281.483308)
			(xy 340.590632 -281.461464) (xy 340.385654 -281.106372) (xy 340.362794 -281.102054) (xy 340.337994 -281.096852)
			(xy 340.290256 -281.079864) (xy 340.24568 -281.055771) (xy 340.205315 -281.025142) (xy 340.170112 -280.988697)
			(xy 340.140899 -280.947295) (xy 340.118366 -280.901911) (xy 340.103042 -280.853613) (xy 340.095288 -280.803539)
			(xy 340.094824 -280.778204) (xy 337.9343 -280.778204) (xy 337.933779 -280.803526) (xy 337.926048 -280.853575)
			(xy 337.910753 -280.901853) (xy 337.888254 -280.947223) (xy 337.859081 -280.988619) (xy 337.82392 -281.025066)
			(xy 337.783598 -281.055707) (xy 337.739064 -281.07982) (xy 337.691367 -281.096838) (xy 337.666584 -281.102054)
			(xy 337.643724 -281.106372) (xy 337.438746 -281.46121) (xy 337.446366 -281.483054) (xy 337.454977 -281.50934)
			(xy 337.464301 -281.563858) (xy 337.464908 -281.591512) (xy 337.464908 -281.59202) (xy 337.4644 -281.617904)
			(xy 338.685436 -281.617904) (xy 338.685436 -281.566096) (xy 338.69354 -281.514926) (xy 338.709548 -281.465654)
			(xy 338.733067 -281.419492) (xy 338.763517 -281.377577) (xy 338.800148 -281.340942) (xy 338.84206 -281.310487)
			(xy 338.888219 -281.286963) (xy 338.937489 -281.270949) (xy 338.988658 -281.262839) (xy 339.014562 -281.262328)
			(xy 339.040073 -281.262825) (xy 339.090487 -281.270681) (xy 339.139089 -281.28621) (xy 339.184718 -281.309042)
			(xy 339.226284 -281.338633) (xy 339.262794 -281.374274) (xy 339.278468 -281.394408) (xy 339.690456 -281.394408)
			(xy 339.706157 -281.374295) (xy 339.742661 -281.33865) (xy 339.784221 -281.309053) (xy 339.829844 -281.286213)
			(xy 339.878441 -281.270675) (xy 339.928852 -281.262808) (xy 339.954362 -281.262328) (xy 339.980275 -281.262767)
			(xy 340.031464 -281.270869) (xy 340.080754 -281.286879) (xy 340.126933 -281.310404) (xy 340.168863 -281.340863)
			(xy 340.205512 -281.377508) (xy 340.235976 -281.419434) (xy 340.259506 -281.465611) (xy 340.275522 -281.514899)
			(xy 340.28363 -281.566087) (xy 340.28363 -281.617913) (xy 340.275522 -281.669101) (xy 340.259506 -281.718389)
			(xy 340.235976 -281.764566) (xy 340.205512 -281.806492) (xy 340.168863 -281.843137) (xy 340.126933 -281.873596)
			(xy 340.080754 -281.897121) (xy 340.031464 -281.913131) (xy 339.980275 -281.921233) (xy 339.954362 -281.921712)
			(xy 339.928849 -281.921255) (xy 339.878434 -281.913389) (xy 339.829832 -281.89785) (xy 339.784204 -281.87501)
			(xy 339.742639 -281.845414) (xy 339.706129 -281.809768) (xy 339.690456 -281.789632) (xy 339.278468 -281.789632)
			(xy 339.262822 -281.80979) (xy 339.226306 -281.845431) (xy 339.184734 -281.875021) (xy 339.139101 -281.897853)
			(xy 339.090494 -281.913382) (xy 339.040076 -281.921238) (xy 339.014562 -281.921712) (xy 338.988658 -281.921161)
			(xy 338.937489 -281.913051) (xy 338.888219 -281.897037) (xy 338.84206 -281.873513) (xy 338.800148 -281.843058)
			(xy 338.763517 -281.806423) (xy 338.733067 -281.764508) (xy 338.709548 -281.718346) (xy 338.69354 -281.669074)
			(xy 338.685436 -281.617904) (xy 337.4644 -281.617904) (xy 337.4644 -281.617927) (xy 337.456294 -281.669104)
			(xy 337.440282 -281.718383) (xy 337.416759 -281.76455) (xy 337.386303 -281.806469) (xy 337.349665 -281.843107)
			(xy 337.307746 -281.873563) (xy 337.261579 -281.897086) (xy 337.2123 -281.913098) (xy 337.161123 -281.921204)
			(xy 337.109309 -281.921204) (xy 337.058132 -281.913098) (xy 337.008853 -281.897086) (xy 336.962686 -281.873563)
			(xy 336.920767 -281.843107) (xy 336.884129 -281.806469) (xy 336.853673 -281.76455) (xy 336.83015 -281.718383)
			(xy 336.814138 -281.669104) (xy 336.806032 -281.617927) (xy 336.805524 -281.59202) (xy 335.585308 -281.59202)
			(xy 335.584798 -281.617364) (xy 335.577024 -281.667452) (xy 335.561677 -281.715761) (xy 335.539118 -281.761152)
			(xy 335.50988 -281.802558) (xy 335.47465 -281.839001) (xy 335.434259 -281.869625) (xy 335.389657 -281.893707)
			(xy 335.341896 -281.910681) (xy 335.317084 -281.91587) (xy 335.294224 -281.920188) (xy 335.089246 -282.27528)
			(xy 335.096866 -282.297124) (xy 335.1055 -282.32347) (xy 335.114821 -282.378118) (xy 335.115408 -282.405836)
			(xy 335.395824 -282.405836) (xy 335.396332 -282.379949) (xy 335.404431 -282.328811) (xy 335.42043 -282.279571)
			(xy 335.443936 -282.233439) (xy 335.474368 -282.191552) (xy 335.510978 -282.154942) (xy 335.552865 -282.12451)
			(xy 335.598997 -282.101004) (xy 335.648237 -282.085005) (xy 335.699375 -282.076906) (xy 335.751149 -282.076906)
			(xy 335.802287 -282.085005) (xy 335.851527 -282.101004) (xy 335.897659 -282.12451) (xy 335.939546 -282.154942)
			(xy 335.976156 -282.191552) (xy 336.006588 -282.233439) (xy 336.030094 -282.279571) (xy 336.046093 -282.328811)
			(xy 336.054192 -282.379949) (xy 336.0547 -282.405836) (xy 336.054214 -282.431707) (xy 336.336126 -282.431707)
			(xy 336.336126 -282.379893) (xy 336.344232 -282.328716) (xy 336.360244 -282.279437) (xy 336.383768 -282.23327)
			(xy 336.414225 -282.191352) (xy 336.450864 -282.154714) (xy 336.492784 -282.12426) (xy 336.538952 -282.100738)
			(xy 336.588231 -282.084728) (xy 336.639409 -282.076625) (xy 336.665316 -282.076144) (xy 336.690811 -282.076599)
			(xy 336.74119 -282.084464) (xy 336.789755 -282.100003) (xy 336.835342 -282.122845) (xy 336.876862 -282.152443)
			(xy 336.913321 -282.188089) (xy 336.928968 -282.208224) (xy 337.341464 -282.208224) (xy 337.35711 -282.18809)
			(xy 337.393571 -282.152447) (xy 337.435092 -282.122853) (xy 337.480679 -282.100016) (xy 337.529243 -282.084481)
			(xy 337.579622 -282.076621) (xy 337.605116 -282.076144) (xy 337.631025 -282.076581) (xy 337.682206 -282.08469)
			(xy 337.731488 -282.100704) (xy 337.777658 -282.124231) (xy 337.819579 -282.154691) (xy 337.85622 -282.191333)
			(xy 337.886677 -282.233256) (xy 337.910202 -282.279427) (xy 337.926214 -282.32871) (xy 337.93432 -282.379891)
			(xy 337.93432 -282.431709) (xy 337.926214 -282.48289) (xy 337.910202 -282.532173) (xy 337.886677 -282.578344)
			(xy 337.85622 -282.620267) (xy 337.819579 -282.656909) (xy 337.777658 -282.687369) (xy 337.731488 -282.710896)
			(xy 337.682206 -282.72691) (xy 337.631025 -282.735019) (xy 337.605116 -282.735528) (xy 337.579623 -282.735021)
			(xy 337.529248 -282.727163) (xy 337.480686 -282.711632) (xy 337.435099 -282.6888) (xy 337.393577 -282.659213)
			(xy 337.357114 -282.623577) (xy 337.341464 -282.603448) (xy 336.928968 -282.603448) (xy 336.913322 -282.623582)
			(xy 336.876859 -282.659221) (xy 336.835338 -282.688813) (xy 336.78975 -282.71165) (xy 336.741187 -282.727186)
			(xy 336.69081 -282.735049) (xy 336.665316 -282.735528) (xy 336.639409 -282.734975) (xy 336.588231 -282.726872)
			(xy 336.538952 -282.710862) (xy 336.492784 -282.68734) (xy 336.450864 -282.656886) (xy 336.414225 -282.620248)
			(xy 336.383768 -282.57833) (xy 336.360244 -282.532163) (xy 336.344232 -282.482884) (xy 336.336126 -282.431707)
			(xy 336.054214 -282.431707) (xy 336.054179 -282.433545) (xy 336.044978 -282.488191) (xy 336.036412 -282.514548)
			(xy 336.028538 -282.536646) (xy 336.23377 -282.891738) (xy 336.25663 -282.896056) (xy 336.281436 -282.901231)
			(xy 336.329174 -282.918223) (xy 336.373751 -282.94232) (xy 336.414116 -282.972953) (xy 336.449318 -283.009401)
			(xy 336.478529 -283.050806) (xy 336.501062 -283.096194) (xy 336.516384 -283.144494) (xy 336.524137 -283.19457)
			(xy 336.5246 -283.219906) (xy 338.685124 -283.219906) (xy 338.685593 -283.194571) (xy 338.693345 -283.144497)
			(xy 338.708668 -283.096199) (xy 338.731201 -283.050814) (xy 338.760412 -283.009411) (xy 338.795615 -282.972966)
			(xy 338.83598 -282.942336) (xy 338.880556 -282.918243) (xy 338.928293 -282.901254) (xy 338.953094 -282.896056)
			(xy 338.975954 -282.891738) (xy 339.181186 -282.536392) (xy 339.173566 -282.514548) (xy 339.164924 -282.488205)
			(xy 339.155609 -282.433555) (xy 339.155024 -282.405836) (xy 339.155532 -282.379929) (xy 339.163638 -282.328752)
			(xy 339.17965 -282.279473) (xy 339.203173 -282.233306) (xy 339.233629 -282.191387) (xy 339.270267 -282.154749)
			(xy 339.312186 -282.124293) (xy 339.358353 -282.10077) (xy 339.407632 -282.084758) (xy 339.458809 -282.076652)
			(xy 339.510623 -282.076652) (xy 339.5618 -282.084758) (xy 339.611079 -282.10077) (xy 339.657246 -282.124293)
			(xy 339.699165 -282.154749) (xy 339.735803 -282.191387) (xy 339.766259 -282.233306) (xy 339.789782 -282.279473)
			(xy 339.805794 -282.328752) (xy 339.8139 -282.379929) (xy 339.814408 -282.405836) (xy 341.034624 -282.405836)
			(xy 341.035068 -282.38049) (xy 341.04285 -282.330397) (xy 341.058205 -282.282085) (xy 341.080771 -282.236692)
			(xy 341.110018 -282.195286) (xy 341.145256 -282.158843) (xy 341.185656 -282.128222) (xy 341.230265 -282.104142)
			(xy 341.278033 -282.087172) (xy 341.302848 -282.081986) (xy 341.325708 -282.077668) (xy 341.530686 -281.72283)
			(xy 341.522812 -281.700986) (xy 341.514229 -281.674568) (xy 341.505035 -281.619792) (xy 341.504524 -281.59202)
			(xy 341.505032 -281.566133) (xy 341.513131 -281.514995) (xy 341.52913 -281.465755) (xy 341.552636 -281.419623)
			(xy 341.583068 -281.377736) (xy 341.619678 -281.341126) (xy 341.661565 -281.310694) (xy 341.707697 -281.287188)
			(xy 341.756937 -281.271189) (xy 341.808075 -281.26309) (xy 341.859849 -281.26309) (xy 341.910987 -281.271189)
			(xy 341.960227 -281.287188) (xy 342.006359 -281.310694) (xy 342.048246 -281.341126) (xy 342.084856 -281.377736)
			(xy 342.115288 -281.419623) (xy 342.138794 -281.465755) (xy 342.154793 -281.514995) (xy 342.162892 -281.566133)
			(xy 342.1634 -281.59202) (xy 342.162935 -281.617355) (xy 342.15518 -281.667428) (xy 342.139855 -281.715725)
			(xy 342.117321 -281.761109) (xy 342.088109 -281.802511) (xy 342.052906 -281.838956) (xy 342.012542 -281.869586)
			(xy 341.967967 -281.89368) (xy 341.92023 -281.910671) (xy 341.89543 -281.91587) (xy 341.87257 -281.920188)
			(xy 341.667592 -282.275026) (xy 341.675466 -282.297124) (xy 341.684085 -282.323474) (xy 341.693414 -282.378119)
			(xy 341.694008 -282.405836) (xy 342.914224 -282.405836) (xy 342.914629 -282.380499) (xy 342.922392 -282.330422)
			(xy 342.937724 -282.282122) (xy 342.960266 -282.236737) (xy 342.989485 -282.195335) (xy 343.024695 -282.15889)
			(xy 343.065066 -282.128262) (xy 343.109648 -282.10417) (xy 343.157391 -282.087183) (xy 343.182194 -282.081986)
			(xy 343.205054 -282.077668) (xy 343.410286 -281.722322) (xy 343.402666 -281.700478) (xy 343.39404 -281.674196)
			(xy 343.384726 -281.619675) (xy 343.384124 -281.59202) (xy 343.384632 -281.566113) (xy 343.392738 -281.514936)
			(xy 343.40875 -281.465657) (xy 343.432273 -281.41949) (xy 343.462729 -281.377571) (xy 343.499367 -281.340933)
			(xy 343.541286 -281.310477) (xy 343.587453 -281.286954) (xy 343.636732 -281.270942) (xy 343.687909 -281.262836)
			(xy 343.739723 -281.262836) (xy 343.7909 -281.270942) (xy 343.840179 -281.286954) (xy 343.886346 -281.310477)
			(xy 343.928265 -281.340933) (xy 343.964903 -281.377571) (xy 343.995359 -281.41949) (xy 344.018882 -281.465657)
			(xy 344.034894 -281.514936) (xy 344.043 -281.566113) (xy 344.043508 -281.59202) (xy 345.263724 -281.59202)
			(xy 345.264244 -281.566676) (xy 345.272013 -281.516587) (xy 345.287357 -281.468277) (xy 345.309913 -281.422884)
			(xy 345.33915 -281.381477) (xy 345.374379 -281.345033) (xy 345.414771 -281.31441) (xy 345.459374 -281.290329)
			(xy 345.507136 -281.273357) (xy 345.531948 -281.26817) (xy 345.554808 -281.263852) (xy 345.759786 -280.909014)
			(xy 345.751912 -280.88717) (xy 345.743326 -280.860753) (xy 345.734134 -280.805977) (xy 345.733624 -280.778204)
			(xy 345.734132 -280.752317) (xy 345.742231 -280.701179) (xy 345.75823 -280.651939) (xy 345.781736 -280.605807)
			(xy 345.812168 -280.56392) (xy 345.848778 -280.52731) (xy 345.890665 -280.496878) (xy 345.936797 -280.473372)
			(xy 345.986037 -280.457373) (xy 346.037175 -280.449274) (xy 346.088949 -280.449274) (xy 346.140087 -280.457373)
			(xy 346.189327 -280.473372) (xy 346.235459 -280.496878) (xy 346.277346 -280.52731) (xy 346.313956 -280.56392)
			(xy 346.344388 -280.605807) (xy 346.367894 -280.651939) (xy 346.383893 -280.701179) (xy 346.391992 -280.752317)
			(xy 346.3925 -280.778204) (xy 348.553024 -280.778204) (xy 348.553532 -280.752317) (xy 348.561631 -280.701179)
			(xy 348.57763 -280.651939) (xy 348.601136 -280.605807) (xy 348.631568 -280.56392) (xy 348.668178 -280.52731)
			(xy 348.710065 -280.496878) (xy 348.756197 -280.473372) (xy 348.805437 -280.457373) (xy 348.856575 -280.449274)
			(xy 348.908349 -280.449274) (xy 348.959487 -280.457373) (xy 349.008727 -280.473372) (xy 349.054859 -280.496878)
			(xy 349.096746 -280.52731) (xy 349.133356 -280.56392) (xy 349.163788 -280.605807) (xy 349.187294 -280.651939)
			(xy 349.203293 -280.701179) (xy 349.211392 -280.752317) (xy 349.2119 -280.778204) (xy 351.372424 -280.778204)
			(xy 351.372932 -280.752317) (xy 351.381031 -280.701179) (xy 351.39703 -280.651939) (xy 351.420536 -280.605807)
			(xy 351.450968 -280.56392) (xy 351.487578 -280.52731) (xy 351.529465 -280.496878) (xy 351.575597 -280.473372)
			(xy 351.624837 -280.457373) (xy 351.675975 -280.449274) (xy 351.727749 -280.449274) (xy 351.778887 -280.457373)
			(xy 351.828127 -280.473372) (xy 351.874259 -280.496878) (xy 351.916146 -280.52731) (xy 351.952756 -280.56392)
			(xy 351.983188 -280.605807) (xy 352.006694 -280.651939) (xy 352.022693 -280.701179) (xy 352.030792 -280.752317)
			(xy 352.0313 -280.778204) (xy 352.312224 -280.778204) (xy 352.312691 -280.752869) (xy 352.320444 -280.702795)
			(xy 352.335767 -280.654496) (xy 352.3583 -280.609112) (xy 352.387511 -280.567709) (xy 352.422714 -280.531263)
			(xy 352.463079 -280.500633) (xy 352.507655 -280.47654) (xy 352.555393 -280.459552) (xy 352.580194 -280.454354)
			(xy 352.603054 -280.450036) (xy 352.808286 -280.09469) (xy 352.800666 -280.072592) (xy 352.792043 -280.046309)
			(xy 352.782727 -279.991789) (xy 352.782124 -279.964134) (xy 352.782632 -279.938227) (xy 352.790738 -279.88705)
			(xy 352.80675 -279.837771) (xy 352.830273 -279.791604) (xy 352.860729 -279.749685) (xy 352.897367 -279.713047)
			(xy 352.939286 -279.682591) (xy 352.985453 -279.659068) (xy 353.034732 -279.643056) (xy 353.085909 -279.63495)
			(xy 353.137723 -279.63495) (xy 353.1889 -279.643056) (xy 353.238179 -279.659068) (xy 353.284346 -279.682591)
			(xy 353.326265 -279.713047) (xy 353.362903 -279.749685) (xy 353.393359 -279.791604) (xy 353.416882 -279.837771)
			(xy 353.432894 -279.88705) (xy 353.441 -279.938227) (xy 353.441508 -279.964134) (xy 353.441095 -279.9895)
			(xy 353.433341 -280.039635) (xy 353.417991 -280.087988) (xy 353.395408 -280.133416) (xy 353.366127 -280.174843)
			(xy 353.330839 -280.211291) (xy 353.290379 -280.241896) (xy 353.245705 -280.265935) (xy 353.197873 -280.282839)
			(xy 353.17303 -280.287984) (xy 353.149916 -280.292302) (xy 352.944938 -280.647394) (xy 352.952812 -280.669492)
			(xy 352.961371 -280.695851) (xy 352.970571 -280.750496) (xy 352.9711 -280.778204) (xy 352.970592 -280.804091)
			(xy 352.962493 -280.855229) (xy 352.946494 -280.904469) (xy 352.922988 -280.950601) (xy 352.892556 -280.992488)
			(xy 352.855946 -281.029098) (xy 352.814059 -281.05953) (xy 352.767927 -281.083036) (xy 352.718687 -281.099035)
			(xy 352.667549 -281.107134) (xy 352.615775 -281.107134) (xy 352.564637 -281.099035) (xy 352.515397 -281.083036)
			(xy 352.469265 -281.05953) (xy 352.427378 -281.029098) (xy 352.390768 -280.992488) (xy 352.360336 -280.950601)
			(xy 352.33683 -280.904469) (xy 352.320831 -280.855229) (xy 352.312732 -280.804091) (xy 352.312224 -280.778204)
			(xy 352.0313 -280.778204) (xy 352.030742 -280.805848) (xy 352.021555 -280.860366) (xy 352.013012 -280.886662)
			(xy 352.005392 -280.908506) (xy 352.210624 -281.263852) (xy 352.233484 -281.26817) (xy 352.258305 -281.273337)
			(xy 352.306082 -281.290294) (xy 352.350699 -281.314367) (xy 352.391104 -281.344988) (xy 352.426344 -281.381435)
			(xy 352.455588 -281.422848) (xy 352.478145 -281.46825) (xy 352.493485 -281.516571) (xy 352.501244 -281.566671)
			(xy 352.501708 -281.59202) (xy 352.5012 -281.617927) (xy 352.493094 -281.669104) (xy 352.477082 -281.718383)
			(xy 352.453559 -281.76455) (xy 352.423103 -281.806469) (xy 352.386465 -281.843107) (xy 352.344546 -281.873563)
			(xy 352.298379 -281.897086) (xy 352.2491 -281.913098) (xy 352.197923 -281.921204) (xy 352.146109 -281.921204)
			(xy 352.094932 -281.913098) (xy 352.045653 -281.897086) (xy 351.999486 -281.873563) (xy 351.957567 -281.843107)
			(xy 351.920929 -281.806469) (xy 351.890473 -281.76455) (xy 351.86695 -281.718383) (xy 351.850938 -281.669104)
			(xy 351.842832 -281.617927) (xy 351.842324 -281.59202) (xy 351.842922 -281.564303) (xy 351.852242 -281.509656)
			(xy 351.860866 -281.483308) (xy 351.86874 -281.46121) (xy 351.663762 -281.106372) (xy 351.640902 -281.102054)
			(xy 351.616072 -281.096882) (xy 351.568266 -281.079946) (xy 351.523618 -281.055889) (xy 351.483181 -281.025278)
			(xy 351.447909 -280.988835) (xy 351.418634 -280.947421) (xy 351.396047 -280.902011) (xy 351.380681 -280.853678)
			(xy 351.372898 -280.803562) (xy 351.372424 -280.778204) (xy 349.2119 -280.778204) (xy 349.211342 -280.805848)
			(xy 349.202155 -280.860366) (xy 349.193612 -280.886662) (xy 349.185992 -280.908506) (xy 349.391224 -281.263852)
			(xy 349.414084 -281.26817) (xy 349.438905 -281.273337) (xy 349.486682 -281.290294) (xy 349.531299 -281.314367)
			(xy 349.571704 -281.344988) (xy 349.606944 -281.381435) (xy 349.636188 -281.422848) (xy 349.658745 -281.46825)
			(xy 349.674085 -281.516571) (xy 349.681844 -281.566671) (xy 349.682308 -281.59202) (xy 349.6818 -281.617927)
			(xy 349.673694 -281.669104) (xy 349.657682 -281.718383) (xy 349.634159 -281.76455) (xy 349.603703 -281.806469)
			(xy 349.567065 -281.843107) (xy 349.525146 -281.873563) (xy 349.478979 -281.897086) (xy 349.4297 -281.913098)
			(xy 349.378523 -281.921204) (xy 349.326709 -281.921204) (xy 349.275532 -281.913098) (xy 349.226253 -281.897086)
			(xy 349.180086 -281.873563) (xy 349.138167 -281.843107) (xy 349.101529 -281.806469) (xy 349.071073 -281.76455)
			(xy 349.04755 -281.718383) (xy 349.031538 -281.669104) (xy 349.023432 -281.617927) (xy 349.022924 -281.59202)
			(xy 349.023522 -281.564303) (xy 349.032842 -281.509656) (xy 349.041466 -281.483308) (xy 349.04934 -281.46121)
			(xy 348.844362 -281.106372) (xy 348.821502 -281.102054) (xy 348.796672 -281.096882) (xy 348.748866 -281.079946)
			(xy 348.704218 -281.055889) (xy 348.663781 -281.025278) (xy 348.628509 -280.988835) (xy 348.599234 -280.947421)
			(xy 348.576647 -280.902011) (xy 348.561281 -280.853678) (xy 348.553498 -280.803562) (xy 348.553024 -280.778204)
			(xy 346.3925 -280.778204) (xy 346.392021 -280.803539) (xy 346.384268 -280.853611) (xy 346.368945 -280.901908)
			(xy 346.346413 -280.947292) (xy 346.317203 -280.988694) (xy 346.282002 -281.025139) (xy 346.241639 -281.055769)
			(xy 346.197065 -281.079864) (xy 346.14933 -281.096855) (xy 346.12453 -281.102054) (xy 346.10167 -281.106372)
			(xy 345.896692 -281.46121) (xy 345.904566 -281.483308) (xy 345.913205 -281.509652) (xy 345.922521 -281.564301)
			(xy 345.923108 -281.59202) (xy 345.9226 -281.617909) (xy 347.143809 -281.617909) (xy 347.143809 -281.566091)
			(xy 347.151916 -281.514912) (xy 347.167929 -281.465631) (xy 347.191454 -281.419462) (xy 347.221912 -281.377541)
			(xy 347.258553 -281.340902) (xy 347.300475 -281.310446) (xy 347.346646 -281.286923) (xy 347.395928 -281.270912)
			(xy 347.447107 -281.262808) (xy 347.473016 -281.262328) (xy 347.498529 -281.262786) (xy 347.548945 -281.27065)
			(xy 347.597547 -281.286187) (xy 347.643176 -281.309027) (xy 347.684741 -281.338624) (xy 347.721249 -281.374271)
			(xy 347.736922 -281.394408) (xy 348.14891 -281.394408) (xy 348.16458 -281.37427) (xy 348.20109 -281.338625)
			(xy 348.242656 -281.309032) (xy 348.288285 -281.286196) (xy 348.336888 -281.270663) (xy 348.387304 -281.262804)
			(xy 348.412816 -281.262328) (xy 348.438724 -281.262797) (xy 348.489902 -281.270905) (xy 348.539182 -281.286919)
			(xy 348.585349 -281.310445) (xy 348.627269 -281.340903) (xy 348.663907 -281.377543) (xy 348.694363 -281.419464)
			(xy 348.717887 -281.465633) (xy 348.733899 -281.514914) (xy 348.742004 -281.566092) (xy 348.742004 -281.617908)
			(xy 348.733899 -281.669086) (xy 348.717887 -281.718367) (xy 348.694363 -281.764536) (xy 348.663907 -281.806457)
			(xy 348.627269 -281.843097) (xy 348.585349 -281.873555) (xy 348.539182 -281.897081) (xy 348.489902 -281.913095)
			(xy 348.438724 -281.921203) (xy 348.412816 -281.921712) (xy 348.387305 -281.921215) (xy 348.336891 -281.913357)
			(xy 348.28829 -281.897827) (xy 348.242662 -281.874994) (xy 348.201096 -281.845405) (xy 348.164585 -281.809765)
			(xy 348.14891 -281.789632) (xy 347.736922 -281.789632) (xy 347.721245 -281.809764) (xy 347.684735 -281.845407)
			(xy 347.64317 -281.875) (xy 347.597542 -281.897836) (xy 347.548942 -281.913371) (xy 347.498528 -281.921234)
			(xy 347.473016 -281.921712) (xy 347.447107 -281.921192) (xy 347.395928 -281.913088) (xy 347.346646 -281.897077)
			(xy 347.300475 -281.873554) (xy 347.258553 -281.843098) (xy 347.221912 -281.806459) (xy 347.191454 -281.764538)
			(xy 347.167929 -281.718369) (xy 347.151916 -281.669088) (xy 347.143809 -281.617909) (xy 345.9226 -281.617909)
			(xy 345.9226 -281.617927) (xy 345.914494 -281.669104) (xy 345.898482 -281.718383) (xy 345.874959 -281.76455)
			(xy 345.844503 -281.806469) (xy 345.807865 -281.843107) (xy 345.765946 -281.873563) (xy 345.719779 -281.897086)
			(xy 345.6705 -281.913098) (xy 345.619323 -281.921204) (xy 345.567509 -281.921204) (xy 345.516332 -281.913098)
			(xy 345.467053 -281.897086) (xy 345.420886 -281.873563) (xy 345.378967 -281.843107) (xy 345.342329 -281.806469)
			(xy 345.311873 -281.76455) (xy 345.28835 -281.718383) (xy 345.272338 -281.669104) (xy 345.264232 -281.617927)
			(xy 345.263724 -281.59202) (xy 344.043508 -281.59202) (xy 344.043045 -281.617395) (xy 344.035274 -281.667545)
			(xy 344.019903 -281.71591) (xy 343.997297 -281.761346) (xy 343.967989 -281.802777) (xy 343.932674 -281.839223)
			(xy 343.892188 -281.869822) (xy 343.847487 -281.893849) (xy 343.79963 -281.910736) (xy 343.774776 -281.91587)
			(xy 343.751916 -281.920188) (xy 343.546938 -282.275026) (xy 343.554812 -282.297124) (xy 343.563378 -282.32348)
			(xy 343.572573 -282.378127) (xy 343.5731 -282.405836) (xy 343.854024 -282.405836) (xy 343.854532 -282.379949)
			(xy 343.862631 -282.328811) (xy 343.87863 -282.279571) (xy 343.902136 -282.233439) (xy 343.932568 -282.191552)
			(xy 343.969178 -282.154942) (xy 344.011065 -282.12451) (xy 344.057197 -282.101004) (xy 344.106437 -282.085005)
			(xy 344.157575 -282.076906) (xy 344.209349 -282.076906) (xy 344.260487 -282.085005) (xy 344.309727 -282.101004)
			(xy 344.355859 -282.12451) (xy 344.397746 -282.154942) (xy 344.434356 -282.191552) (xy 344.464788 -282.233439)
			(xy 344.488294 -282.279571) (xy 344.504293 -282.328811) (xy 344.512392 -282.379949) (xy 344.5129 -282.405836)
			(xy 344.512385 -282.431703) (xy 344.794152 -282.431703) (xy 344.794152 -282.379897) (xy 344.802256 -282.32873)
			(xy 344.818263 -282.27946) (xy 344.841781 -282.2333) (xy 344.872229 -282.191388) (xy 344.908859 -282.154754)
			(xy 344.950768 -282.124301) (xy 344.996925 -282.100778) (xy 345.046193 -282.084765) (xy 345.097359 -282.076655)
			(xy 345.123262 -282.076144) (xy 345.148774 -282.076635) (xy 345.199188 -282.084491) (xy 345.247791 -282.100021)
			(xy 345.293419 -282.122855) (xy 345.334985 -282.152446) (xy 345.371495 -282.188089) (xy 345.387168 -282.208224)
			(xy 345.799156 -282.208224) (xy 345.814861 -282.188115) (xy 345.851364 -282.152468) (xy 345.892922 -282.122871)
			(xy 345.938545 -282.10003) (xy 345.987141 -282.084491) (xy 346.037552 -282.076624) (xy 346.063062 -282.076144)
			(xy 346.088976 -282.076551) (xy 346.140167 -282.084653) (xy 346.18946 -282.100664) (xy 346.235642 -282.12419)
			(xy 346.277574 -282.154651) (xy 346.314224 -282.191297) (xy 346.34469 -282.233226) (xy 346.368221 -282.279404)
			(xy 346.384238 -282.328696) (xy 346.392346 -282.379886) (xy 346.392346 -282.431714) (xy 346.384238 -282.482904)
			(xy 346.368221 -282.532196) (xy 346.34469 -282.578374) (xy 346.314224 -282.620303) (xy 346.277574 -282.656949)
			(xy 346.235642 -282.68741) (xy 346.18946 -282.710936) (xy 346.140167 -282.726947) (xy 346.088976 -282.735049)
			(xy 346.063062 -282.735528) (xy 346.03755 -282.735064) (xy 345.987135 -282.727199) (xy 345.938534 -282.711661)
			(xy 345.892906 -282.688822) (xy 345.85134 -282.659228) (xy 345.81483 -282.623584) (xy 345.799156 -282.603448)
			(xy 345.387168 -282.603448) (xy 345.371526 -282.623609) (xy 345.335009 -282.659249) (xy 345.293436 -282.688839)
			(xy 345.247802 -282.71167) (xy 345.199195 -282.727199) (xy 345.148776 -282.735054) (xy 345.123262 -282.735528)
			(xy 345.097359 -282.734945) (xy 345.046193 -282.726835) (xy 344.996925 -282.710822) (xy 344.950768 -282.687299)
			(xy 344.908859 -282.656846) (xy 344.872229 -282.620212) (xy 344.841781 -282.5783) (xy 344.818263 -282.53214)
			(xy 344.802256 -282.48287) (xy 344.794152 -282.431703) (xy 344.512385 -282.431703) (xy 344.51235 -282.43348)
			(xy 344.503158 -282.487998) (xy 344.494612 -282.514294) (xy 344.486992 -282.536392) (xy 344.692224 -282.891738)
			(xy 344.715084 -282.896056) (xy 344.739902 -282.901236) (xy 344.787678 -282.918192) (xy 344.832294 -282.942264)
			(xy 344.872699 -282.972884) (xy 344.907939 -283.009329) (xy 344.937183 -283.05074) (xy 344.959741 -283.09614)
			(xy 344.975082 -283.14446) (xy 344.982843 -283.194558) (xy 344.983308 -283.219906) (xy 347.143324 -283.219906)
			(xy 347.143831 -283.194562) (xy 347.151603 -283.144472) (xy 347.166948 -283.096161) (xy 347.189506 -283.050768)
			(xy 347.218745 -283.009362) (xy 347.253975 -282.972918) (xy 347.294368 -282.942295) (xy 347.338972 -282.918214)
			(xy 347.386736 -282.901243) (xy 347.411548 -282.896056) (xy 347.434408 -282.891738) (xy 347.639386 -282.5369)
			(xy 347.631766 -282.514802) (xy 347.623129 -282.488391) (xy 347.613803 -282.433617) (xy 347.613224 -282.405836)
			(xy 347.613732 -282.379949) (xy 347.621831 -282.328811) (xy 347.63783 -282.279571) (xy 347.661336 -282.233439)
			(xy 347.691768 -282.191552) (xy 347.728378 -282.154942) (xy 347.770265 -282.12451) (xy 347.816397 -282.101004)
			(xy 347.865637 -282.085005) (xy 347.916775 -282.076906) (xy 347.968549 -282.076906) (xy 348.019687 -282.085005)
			(xy 348.068927 -282.101004) (xy 348.115059 -282.12451) (xy 348.156946 -282.154942) (xy 348.193556 -282.191552)
			(xy 348.223988 -282.233439) (xy 348.247494 -282.279571) (xy 348.263493 -282.328811) (xy 348.271592 -282.379949)
			(xy 348.2721 -282.405836) (xy 349.492824 -282.405836) (xy 349.493229 -282.380499) (xy 349.500992 -282.330422)
			(xy 349.516324 -282.282122) (xy 349.538866 -282.236737) (xy 349.568085 -282.195335) (xy 349.603295 -282.15889)
			(xy 349.643666 -282.128262) (xy 349.688248 -282.10417) (xy 349.735991 -282.087183) (xy 349.760794 -282.081986)
			(xy 349.783654 -282.077668) (xy 349.988886 -281.722322) (xy 349.981266 -281.700478) (xy 349.97264 -281.674196)
			(xy 349.963326 -281.619675) (xy 349.962724 -281.59202) (xy 349.963232 -281.566113) (xy 349.971338 -281.514936)
			(xy 349.98735 -281.465657) (xy 350.010873 -281.41949) (xy 350.041329 -281.377571) (xy 350.077967 -281.340933)
			(xy 350.119886 -281.310477) (xy 350.166053 -281.286954) (xy 350.215332 -281.270942) (xy 350.266509 -281.262836)
			(xy 350.318323 -281.262836) (xy 350.3695 -281.270942) (xy 350.418779 -281.286954) (xy 350.464946 -281.310477)
			(xy 350.506865 -281.340933) (xy 350.543503 -281.377571) (xy 350.573959 -281.41949) (xy 350.597482 -281.465657)
			(xy 350.613494 -281.514936) (xy 350.6216 -281.566113) (xy 350.622108 -281.59202) (xy 350.621645 -281.617395)
			(xy 350.613874 -281.667545) (xy 350.598503 -281.71591) (xy 350.575897 -281.761346) (xy 350.546589 -281.802777)
			(xy 350.511274 -281.839223) (xy 350.470788 -281.869822) (xy 350.426087 -281.893849) (xy 350.37823 -281.910736)
			(xy 350.353376 -281.91587) (xy 350.330516 -281.920188) (xy 350.125538 -282.275026) (xy 350.133412 -282.297124)
			(xy 350.141978 -282.32348) (xy 350.151173 -282.378127) (xy 350.1517 -282.405836) (xy 350.151192 -282.431703)
			(xy 351.372752 -282.431703) (xy 351.372752 -282.379897) (xy 351.380856 -282.32873) (xy 351.396863 -282.27946)
			(xy 351.420381 -282.2333) (xy 351.450829 -282.191388) (xy 351.487459 -282.154754) (xy 351.529368 -282.124301)
			(xy 351.575525 -282.100778) (xy 351.624793 -282.084765) (xy 351.675959 -282.076655) (xy 351.701862 -282.076144)
			(xy 351.727374 -282.076635) (xy 351.777788 -282.084491) (xy 351.826391 -282.100021) (xy 351.872019 -282.122855)
			(xy 351.913585 -282.152446) (xy 351.950095 -282.188089) (xy 351.965768 -282.208224) (xy 352.377756 -282.208224)
			(xy 352.393461 -282.188115) (xy 352.429964 -282.152468) (xy 352.471522 -282.122871) (xy 352.517145 -282.10003)
			(xy 352.565741 -282.084491) (xy 352.616152 -282.076624) (xy 352.641662 -282.076144) (xy 352.667576 -282.076551)
			(xy 352.718767 -282.084653) (xy 352.76806 -282.100664) (xy 352.814242 -282.12419) (xy 352.856174 -282.154651)
			(xy 352.892824 -282.191297) (xy 352.92329 -282.233226) (xy 352.946821 -282.279404) (xy 352.962838 -282.328696)
			(xy 352.970946 -282.379886) (xy 352.970946 -282.431714) (xy 352.962838 -282.482904) (xy 352.946821 -282.532196)
			(xy 352.92329 -282.578374) (xy 352.892824 -282.620303) (xy 352.856174 -282.656949) (xy 352.814242 -282.68741)
			(xy 352.76806 -282.710936) (xy 352.718767 -282.726947) (xy 352.667576 -282.735049) (xy 352.641662 -282.735528)
			(xy 352.61615 -282.735064) (xy 352.565735 -282.727199) (xy 352.517134 -282.711661) (xy 352.471506 -282.688822)
			(xy 352.42994 -282.659228) (xy 352.39343 -282.623584) (xy 352.377756 -282.603448) (xy 351.965768 -282.603448)
			(xy 351.950126 -282.623609) (xy 351.913609 -282.659249) (xy 351.872036 -282.688839) (xy 351.826402 -282.71167)
			(xy 351.777795 -282.727199) (xy 351.727376 -282.735054) (xy 351.701862 -282.735528) (xy 351.675959 -282.734945)
			(xy 351.624793 -282.726835) (xy 351.575525 -282.710822) (xy 351.529368 -282.687299) (xy 351.487459 -282.656846)
			(xy 351.450829 -282.620212) (xy 351.420381 -282.5783) (xy 351.396863 -282.53214) (xy 351.380856 -282.48287)
			(xy 351.372752 -282.431703) (xy 350.151192 -282.431703) (xy 350.151192 -282.431723) (xy 350.143093 -282.482861)
			(xy 350.127094 -282.532101) (xy 350.103588 -282.578233) (xy 350.073156 -282.62012) (xy 350.036546 -282.65673)
			(xy 349.994659 -282.687162) (xy 349.948527 -282.710668) (xy 349.899287 -282.726667) (xy 349.848149 -282.734766)
			(xy 349.796375 -282.734766) (xy 349.745237 -282.726667) (xy 349.695997 -282.710668) (xy 349.649865 -282.687162)
			(xy 349.607978 -282.65673) (xy 349.571368 -282.62012) (xy 349.540936 -282.578233) (xy 349.51743 -282.532101)
			(xy 349.501431 -282.482861) (xy 349.493332 -282.431723) (xy 349.492824 -282.405836) (xy 348.2721 -282.405836)
			(xy 348.271608 -282.431158) (xy 348.263872 -282.481209) (xy 348.248573 -282.529487) (xy 348.22607 -282.574858)
			(xy 348.196893 -282.616254) (xy 348.161729 -282.6527) (xy 348.121404 -282.68334) (xy 348.076868 -282.707453)
			(xy 348.029168 -282.72447) (xy 348.004384 -282.729686) (xy 347.981524 -282.734004) (xy 347.776292 -283.089096)
			(xy 347.784166 -283.111194) (xy 347.792802 -283.137539) (xy 347.80212 -283.192188) (xy 347.802708 -283.219906)
			(xy 347.8022 -283.24579) (xy 349.023649 -283.24579) (xy 349.023649 -283.19401) (xy 349.03175 -283.142868)
			(xy 349.047751 -283.093623) (xy 349.071259 -283.047487) (xy 349.101695 -283.005597) (xy 349.13831 -282.968985)
			(xy 349.180201 -282.938551) (xy 349.226338 -282.915045) (xy 349.275584 -282.899046) (xy 349.326726 -282.890948)
			(xy 349.352616 -282.890468) (xy 349.378128 -282.890949) (xy 349.428541 -282.898811) (xy 349.477143 -282.914346)
			(xy 349.522771 -282.937181) (xy 349.564336 -282.966773) (xy 349.600848 -283.002414) (xy 349.616522 -283.022548)
			(xy 350.02851 -283.022548) (xy 350.044163 -283.002397) (xy 350.080679 -282.966756) (xy 350.122249 -282.937166)
			(xy 350.167881 -282.914333) (xy 350.216486 -282.898802) (xy 350.266903 -282.890944) (xy 350.292416 -282.890468)
			(xy 350.318303 -282.890965) (xy 350.369439 -282.899066) (xy 350.418679 -282.915067) (xy 350.464809 -282.938574)
			(xy 350.506694 -282.969007) (xy 350.543303 -283.005618) (xy 350.573735 -283.047505) (xy 350.597239 -283.093636)
			(xy 350.613237 -283.142876) (xy 350.621336 -283.194013) (xy 350.621336 -283.245787) (xy 350.613237 -283.296924)
			(xy 350.597239 -283.346164) (xy 350.573735 -283.392295) (xy 350.543303 -283.434182) (xy 350.506694 -283.470793)
			(xy 350.464809 -283.501226) (xy 350.418679 -283.524733) (xy 350.369439 -283.540734) (xy 350.318303 -283.548835)
			(xy 350.292416 -283.549344) (xy 350.266904 -283.548874) (xy 350.216488 -283.541014) (xy 350.167885 -283.52548)
			(xy 350.122256 -283.502643) (xy 350.080691 -283.473047) (xy 350.044182 -283.437401) (xy 350.02851 -283.417264)
			(xy 349.616522 -283.417264) (xy 349.600826 -283.437381) (xy 349.564322 -283.473028) (xy 349.522762 -283.502625)
			(xy 349.477138 -283.525464) (xy 349.428539 -283.541001) (xy 349.378127 -283.548865) (xy 349.352616 -283.549344)
			(xy 349.326726 -283.548852) (xy 349.275584 -283.540754) (xy 349.226338 -283.524755) (xy 349.180201 -283.501249)
			(xy 349.13831 -283.470815) (xy 349.101695 -283.434203) (xy 349.071259 -283.392313) (xy 349.047751 -283.346177)
			(xy 349.03175 -283.296932) (xy 349.023649 -283.24579) (xy 347.8022 -283.24579) (xy 347.8022 -283.245813)
			(xy 347.794094 -283.29699) (xy 347.778082 -283.346269) (xy 347.754559 -283.392436) (xy 347.724103 -283.434355)
			(xy 347.687465 -283.470993) (xy 347.645546 -283.501449) (xy 347.599379 -283.524972) (xy 347.5501 -283.540984)
			(xy 347.498923 -283.54909) (xy 347.447109 -283.54909) (xy 347.395932 -283.540984) (xy 347.346653 -283.524972)
			(xy 347.300486 -283.501449) (xy 347.258567 -283.470993) (xy 347.221929 -283.434355) (xy 347.191473 -283.392436)
			(xy 347.16795 -283.346269) (xy 347.151938 -283.29699) (xy 347.143832 -283.245813) (xy 347.143324 -283.219906)
			(xy 344.983308 -283.219906) (xy 344.9828 -283.245813) (xy 344.974694 -283.29699) (xy 344.958682 -283.346269)
			(xy 344.935159 -283.392436) (xy 344.904703 -283.434355) (xy 344.868065 -283.470993) (xy 344.826146 -283.501449)
			(xy 344.779979 -283.524972) (xy 344.7307 -283.540984) (xy 344.679523 -283.54909) (xy 344.627709 -283.54909)
			(xy 344.576532 -283.540984) (xy 344.527253 -283.524972) (xy 344.481086 -283.501449) (xy 344.439167 -283.470993)
			(xy 344.402529 -283.434355) (xy 344.372073 -283.392436) (xy 344.34855 -283.346269) (xy 344.332538 -283.29699)
			(xy 344.324432 -283.245813) (xy 344.323924 -283.219906) (xy 344.324518 -283.192189) (xy 344.333841 -283.137542)
			(xy 344.342466 -283.111194) (xy 344.35034 -283.089096) (xy 344.145362 -282.734004) (xy 344.122248 -282.729686)
			(xy 344.097423 -282.724538) (xy 344.049642 -282.707582) (xy 344.005022 -282.683508) (xy 343.964615 -282.652886)
			(xy 343.929374 -282.616436) (xy 343.900131 -282.57502) (xy 343.877575 -282.529614) (xy 343.862239 -282.481289)
			(xy 343.854484 -282.431186) (xy 343.854024 -282.405836) (xy 343.5731 -282.405836) (xy 343.572592 -282.431723)
			(xy 343.564493 -282.482861) (xy 343.548494 -282.532101) (xy 343.524988 -282.578233) (xy 343.494556 -282.62012)
			(xy 343.457946 -282.65673) (xy 343.416059 -282.687162) (xy 343.369927 -282.710668) (xy 343.320687 -282.726667)
			(xy 343.269549 -282.734766) (xy 343.217775 -282.734766) (xy 343.166637 -282.726667) (xy 343.117397 -282.710668)
			(xy 343.071265 -282.687162) (xy 343.029378 -282.65673) (xy 342.992768 -282.62012) (xy 342.962336 -282.578233)
			(xy 342.93883 -282.532101) (xy 342.922831 -282.482861) (xy 342.914732 -282.431723) (xy 342.914224 -282.405836)
			(xy 341.694008 -282.405836) (xy 341.6935 -282.431743) (xy 341.685394 -282.48292) (xy 341.669382 -282.532199)
			(xy 341.645859 -282.578366) (xy 341.615403 -282.620285) (xy 341.578765 -282.656923) (xy 341.536846 -282.687379)
			(xy 341.490679 -282.710902) (xy 341.4414 -282.726914) (xy 341.390223 -282.73502) (xy 341.338409 -282.73502)
			(xy 341.287232 -282.726914) (xy 341.237953 -282.710902) (xy 341.191786 -282.687379) (xy 341.149867 -282.656923)
			(xy 341.113229 -282.620285) (xy 341.082773 -282.578366) (xy 341.05925 -282.532199) (xy 341.043238 -282.48292)
			(xy 341.035132 -282.431743) (xy 341.034624 -282.405836) (xy 339.814408 -282.405836) (xy 339.813997 -282.431202)
			(xy 339.806243 -282.481337) (xy 339.790893 -282.52969) (xy 339.768309 -282.575118) (xy 339.739027 -282.616545)
			(xy 339.703739 -282.652993) (xy 339.663279 -282.683598) (xy 339.618605 -282.707637) (xy 339.570773 -282.724541)
			(xy 339.54593 -282.729686) (xy 339.52307 -282.734004) (xy 339.318092 -283.089096) (xy 339.325712 -283.11094)
			(xy 339.33426 -283.137236) (xy 339.343458 -283.191753) (xy 339.344 -283.219398) (xy 339.344 -283.219906)
			(xy 339.343492 -283.245785) (xy 340.565275 -283.245785) (xy 340.565275 -283.194015) (xy 340.573373 -283.142882)
			(xy 340.58937 -283.093646) (xy 340.612872 -283.047517) (xy 340.643299 -283.005633) (xy 340.679904 -282.969024)
			(xy 340.721785 -282.938592) (xy 340.76791 -282.915085) (xy 340.817145 -282.899082) (xy 340.868277 -282.890978)
			(xy 340.894162 -282.890468) (xy 340.919672 -282.890989) (xy 340.970084 -282.898843) (xy 341.018684 -282.914369)
			(xy 341.064312 -282.937197) (xy 341.105879 -282.966782) (xy 341.142392 -283.002417) (xy 341.158068 -283.022548)
			(xy 341.570056 -283.022548) (xy 341.585741 -283.002422) (xy 341.62225 -282.96678) (xy 341.663813 -282.937187)
			(xy 341.709439 -282.91435) (xy 341.758039 -282.898813) (xy 341.808451 -282.890948) (xy 341.833962 -282.890468)
			(xy 341.859854 -282.890934) (xy 341.911001 -282.89903) (xy 341.960252 -282.915027) (xy 342.006393 -282.938533)
			(xy 342.048289 -282.968968) (xy 342.084908 -283.005582) (xy 342.115347 -283.047475) (xy 342.138858 -283.093613)
			(xy 342.154861 -283.142862) (xy 342.162963 -283.194008) (xy 342.162963 -283.245792) (xy 342.154861 -283.296938)
			(xy 342.138858 -283.346187) (xy 342.115347 -283.392325) (xy 342.084908 -283.434218) (xy 342.048289 -283.470832)
			(xy 342.006393 -283.501267) (xy 341.960252 -283.524773) (xy 341.911001 -283.54077) (xy 341.859854 -283.548866)
			(xy 341.833962 -283.549344) (xy 341.808448 -283.548913) (xy 341.75803 -283.541045) (xy 341.709427 -283.525503)
			(xy 341.663798 -283.502658) (xy 341.622234 -283.473056) (xy 341.585727 -283.437404) (xy 341.570056 -283.417264)
			(xy 341.158068 -283.417264) (xy 341.142404 -283.437407) (xy 341.105893 -283.473052) (xy 341.064326 -283.502646)
			(xy 341.018696 -283.525481) (xy 340.970092 -283.541013) (xy 340.919675 -283.548869) (xy 340.894162 -283.549344)
			(xy 340.868277 -283.548822) (xy 340.817145 -283.540718) (xy 340.76791 -283.524715) (xy 340.721785 -283.501208)
			(xy 340.679904 -283.470776) (xy 340.643299 -283.434167) (xy 340.612872 -283.392283) (xy 340.58937 -283.346154)
			(xy 340.573373 -283.296918) (xy 340.565275 -283.245785) (xy 339.343492 -283.245785) (xy 339.343492 -283.245793)
			(xy 339.335393 -283.296931) (xy 339.319394 -283.346171) (xy 339.295888 -283.392303) (xy 339.265456 -283.43419)
			(xy 339.228846 -283.4708) (xy 339.186959 -283.501232) (xy 339.140827 -283.524738) (xy 339.091587 -283.540737)
			(xy 339.040449 -283.548836) (xy 338.988675 -283.548836) (xy 338.937537 -283.540737) (xy 338.888297 -283.524738)
			(xy 338.842165 -283.501232) (xy 338.800278 -283.4708) (xy 338.763668 -283.43419) (xy 338.733236 -283.392303)
			(xy 338.70973 -283.346171) (xy 338.693731 -283.296931) (xy 338.685632 -283.245793) (xy 338.685124 -283.219906)
			(xy 336.5246 -283.219906) (xy 336.524092 -283.245793) (xy 336.515993 -283.296931) (xy 336.499994 -283.346171)
			(xy 336.476488 -283.392303) (xy 336.446056 -283.43419) (xy 336.409446 -283.4708) (xy 336.367559 -283.501232)
			(xy 336.321427 -283.524738) (xy 336.272187 -283.540737) (xy 336.221049 -283.548836) (xy 336.169275 -283.548836)
			(xy 336.118137 -283.540737) (xy 336.068897 -283.524738) (xy 336.022765 -283.501232) (xy 335.980878 -283.4708)
			(xy 335.944268 -283.43419) (xy 335.913836 -283.392303) (xy 335.89033 -283.346171) (xy 335.874331 -283.296931)
			(xy 335.866232 -283.245793) (xy 335.865724 -283.219906) (xy 335.866254 -283.192198) (xy 335.875449 -283.137551)
			(xy 335.884012 -283.111194) (xy 335.891886 -283.089096) (xy 335.686654 -282.734004) (xy 335.663794 -282.729686)
			(xy 335.639001 -282.724454) (xy 335.591266 -282.707468) (xy 335.546691 -282.683379) (xy 335.506327 -282.652753)
			(xy 335.471124 -282.616312) (xy 335.441911 -282.574914) (xy 335.419375 -282.529534) (xy 335.404048 -282.48124)
			(xy 335.396291 -282.43117) (xy 335.395824 -282.405836) (xy 335.115408 -282.405836) (xy 335.1149 -282.431743)
			(xy 335.106794 -282.48292) (xy 335.090782 -282.532199) (xy 335.067259 -282.578366) (xy 335.036803 -282.620285)
			(xy 335.000165 -282.656923) (xy 334.958246 -282.687379) (xy 334.912079 -282.710902) (xy 334.8628 -282.726914)
			(xy 334.811623 -282.73502) (xy 334.759809 -282.73502) (xy 334.708632 -282.726914) (xy 334.659353 -282.710902)
			(xy 334.613186 -282.687379) (xy 334.571267 -282.656923) (xy 334.534629 -282.620285) (xy 334.504173 -282.578366)
			(xy 334.48065 -282.532199) (xy 334.464638 -282.48292) (xy 334.456532 -282.431743) (xy 334.456024 -282.405836)
			(xy 284.8356 -282.405836) (xy 284.8356 -284.033722) (xy 334.456024 -284.033722) (xy 334.456532 -284.007815)
			(xy 334.464638 -283.956638) (xy 334.48065 -283.907359) (xy 334.504173 -283.861192) (xy 334.534629 -283.819273)
			(xy 334.571267 -283.782635) (xy 334.613186 -283.752179) (xy 334.659353 -283.728656) (xy 334.708632 -283.712644)
			(xy 334.759809 -283.704538) (xy 334.811623 -283.704538) (xy 334.8628 -283.712644) (xy 334.912079 -283.728656)
			(xy 334.958246 -283.752179) (xy 335.000165 -283.782635) (xy 335.036803 -283.819273) (xy 335.067259 -283.861192)
			(xy 335.090782 -283.907359) (xy 335.106794 -283.956638) (xy 335.1149 -284.007815) (xy 335.115408 -284.033722)
			(xy 335.114819 -284.06144) (xy 335.105492 -284.116086) (xy 335.096866 -284.142434) (xy 335.088992 -284.164532)
			(xy 335.29397 -284.51937) (xy 335.31683 -284.523688) (xy 335.341643 -284.528833) (xy 335.389384 -284.545828)
			(xy 335.433962 -284.569927) (xy 335.474328 -284.600564) (xy 335.50953 -284.637016) (xy 335.538741 -284.678425)
			(xy 335.561271 -284.723817) (xy 335.576591 -284.772121) (xy 335.584339 -284.8222) (xy 335.5848 -284.847538)
			(xy 335.584292 -284.873425) (xy 335.576193 -284.924563) (xy 335.560194 -284.973803) (xy 335.536688 -285.019935)
			(xy 335.506256 -285.061822) (xy 335.469646 -285.098432) (xy 335.427759 -285.128864) (xy 335.381627 -285.15237)
			(xy 335.332387 -285.168369) (xy 335.281249 -285.176468) (xy 335.229475 -285.176468) (xy 335.178337 -285.168369)
			(xy 335.129097 -285.15237) (xy 335.082965 -285.128864) (xy 335.041078 -285.098432) (xy 335.004468 -285.061822)
			(xy 334.974036 -285.019935) (xy 334.95053 -284.973803) (xy 334.934531 -284.924563) (xy 334.926432 -284.873425)
			(xy 334.925924 -284.847538) (xy 334.926462 -284.81983) (xy 334.935651 -284.765183) (xy 334.944212 -284.738826)
			(xy 334.952086 -284.716728) (xy 334.747108 -284.36189) (xy 334.724248 -284.357572) (xy 334.699419 -284.352437)
			(xy 334.651638 -284.33548) (xy 334.607017 -284.311405) (xy 334.56661 -284.280781) (xy 334.531369 -284.24433)
			(xy 334.502126 -284.202912) (xy 334.479571 -284.157504) (xy 334.464236 -284.109178) (xy 334.456483 -284.059073)
			(xy 334.456024 -284.033722) (xy 284.8356 -284.033722) (xy 284.8356 -284.873383) (xy 333.046907 -284.873383)
			(xy 333.046907 -284.821618) (xy 333.055005 -284.77049) (xy 333.071 -284.721258) (xy 333.094499 -284.675134)
			(xy 333.124924 -284.633254) (xy 333.161525 -284.596648) (xy 333.203402 -284.566219) (xy 333.249523 -284.542714)
			(xy 333.298753 -284.526713) (xy 333.34988 -284.51861) (xy 333.375762 -284.5181) (xy 333.401254 -284.518612)
			(xy 333.451631 -284.526467) (xy 333.500193 -284.541996) (xy 333.54578 -284.564827) (xy 333.587302 -284.594415)
			(xy 333.623765 -284.63005) (xy 333.639414 -284.65018) (xy 334.05191 -284.65018) (xy 334.067576 -284.630063)
			(xy 334.104034 -284.594421) (xy 334.145551 -284.564826) (xy 334.191135 -284.541986) (xy 334.239694 -284.526447)
			(xy 334.290069 -284.518581) (xy 334.315562 -284.5181) (xy 334.341456 -284.518502) (xy 334.392608 -284.526599)
			(xy 334.441864 -284.542598) (xy 334.48801 -284.566106) (xy 334.52991 -284.596543) (xy 334.566532 -284.633161)
			(xy 334.596975 -284.675058) (xy 334.620488 -284.721201) (xy 334.636492 -284.770455) (xy 334.644595 -284.821606)
			(xy 334.644595 -284.873394) (xy 334.636492 -284.924545) (xy 334.620488 -284.973799) (xy 334.596975 -285.019942)
			(xy 334.566532 -285.061839) (xy 334.52991 -285.098457) (xy 334.48801 -285.128894) (xy 334.441864 -285.152402)
			(xy 334.392608 -285.168401) (xy 334.341456 -285.176498) (xy 334.315562 -285.176976) (xy 334.290067 -285.176529)
			(xy 334.239687 -285.168661) (xy 334.191123 -285.15312) (xy 334.145536 -285.130277) (xy 334.104016 -285.100678)
			(xy 334.067557 -285.065031) (xy 334.05191 -285.044896) (xy 333.639414 -285.044896) (xy 333.623786 -285.065045)
			(xy 333.587321 -285.100686) (xy 333.545796 -285.130277) (xy 333.500205 -285.153112) (xy 333.451638 -285.168644)
			(xy 333.401257 -285.176501) (xy 333.375762 -285.176976) (xy 333.34988 -285.17639) (xy 333.298753 -285.168287)
			(xy 333.249523 -285.152286) (xy 333.203402 -285.128781) (xy 333.161525 -285.098352) (xy 333.124924 -285.061746)
			(xy 333.094499 -285.019866) (xy 333.071 -284.973742) (xy 333.055005 -284.92451) (xy 333.046907 -284.873383)
			(xy 284.8356 -284.873383) (xy 284.8356 -285.661354) (xy 335.395824 -285.661354) (xy 335.396245 -285.636017)
			(xy 335.404005 -285.585941) (xy 335.419335 -285.537642) (xy 335.441875 -285.492257) (xy 335.471092 -285.450854)
			(xy 335.5063 -285.41441) (xy 335.54667 -285.383781) (xy 335.59125 -285.359689) (xy 335.638992 -285.342701)
			(xy 335.663794 -285.337504) (xy 335.686654 -285.333186) (xy 335.891632 -284.978094) (xy 335.884012 -284.95625)
			(xy 335.875447 -284.929893) (xy 335.86625 -284.875247) (xy 335.865724 -284.847538) (xy 335.866232 -284.821651)
			(xy 335.874331 -284.770513) (xy 335.89033 -284.721273) (xy 335.913836 -284.675141) (xy 335.944268 -284.633254)
			(xy 335.980878 -284.596644) (xy 336.022765 -284.566212) (xy 336.068897 -284.542706) (xy 336.118137 -284.526707)
			(xy 336.169275 -284.518608) (xy 336.221049 -284.518608) (xy 336.272187 -284.526707) (xy 336.321427 -284.542706)
			(xy 336.367559 -284.566212) (xy 336.409446 -284.596644) (xy 336.446056 -284.633254) (xy 336.476488 -284.675141)
			(xy 336.499994 -284.721273) (xy 336.515993 -284.770513) (xy 336.524092 -284.821651) (xy 336.5246 -284.847538)
			(xy 336.524152 -284.872874) (xy 336.516394 -284.922948) (xy 336.501066 -284.971245) (xy 336.47853 -285.016629)
			(xy 336.449316 -285.058031) (xy 336.414111 -285.094476) (xy 336.373746 -285.125106) (xy 336.329169 -285.149199)
			(xy 336.281431 -285.16619) (xy 336.25663 -285.171388) (xy 336.23377 -285.175706) (xy 336.028792 -285.530798)
			(xy 336.036412 -285.552642) (xy 336.044976 -285.578999) (xy 336.054174 -285.633646) (xy 336.0547 -285.661354)
			(xy 337.275424 -285.661354) (xy 337.275932 -285.635467) (xy 337.284031 -285.584329) (xy 337.30003 -285.535089)
			(xy 337.323536 -285.488957) (xy 337.353968 -285.44707) (xy 337.390578 -285.41046) (xy 337.432465 -285.380028)
			(xy 337.478597 -285.356522) (xy 337.527837 -285.340523) (xy 337.578975 -285.332424) (xy 337.630749 -285.332424)
			(xy 337.681887 -285.340523) (xy 337.731127 -285.356522) (xy 337.777259 -285.380028) (xy 337.819146 -285.41046)
			(xy 337.855756 -285.44707) (xy 337.886188 -285.488957) (xy 337.909694 -285.535089) (xy 337.925693 -285.584329)
			(xy 337.933792 -285.635467) (xy 337.9343 -285.661354) (xy 338.215224 -285.661354) (xy 338.215684 -285.636008)
			(xy 338.223463 -285.585916) (xy 338.238816 -285.537605) (xy 338.26138 -285.492212) (xy 338.290625 -285.450806)
			(xy 338.325861 -285.414363) (xy 338.366259 -285.383741) (xy 338.410867 -285.359661) (xy 338.458634 -285.34269)
			(xy 338.483448 -285.337504) (xy 338.506308 -285.333186) (xy 338.711286 -284.978348) (xy 338.703412 -284.956504)
			(xy 338.694834 -284.930085) (xy 338.685636 -284.87531) (xy 338.685124 -284.847538) (xy 338.685632 -284.821651)
			(xy 338.693731 -284.770513) (xy 338.70973 -284.721273) (xy 338.733236 -284.675141) (xy 338.763668 -284.633254)
			(xy 338.800278 -284.596644) (xy 338.842165 -284.566212) (xy 338.888297 -284.542706) (xy 338.937537 -284.526707)
			(xy 338.988675 -284.518608) (xy 339.040449 -284.518608) (xy 339.091587 -284.526707) (xy 339.140827 -284.542706)
			(xy 339.186959 -284.566212) (xy 339.228846 -284.596644) (xy 339.265456 -284.633254) (xy 339.295888 -284.675141)
			(xy 339.319394 -284.721273) (xy 339.335393 -284.770513) (xy 339.343492 -284.821651) (xy 339.344 -284.847538)
			(xy 339.343552 -284.872874) (xy 339.335794 -284.922948) (xy 339.320466 -284.971245) (xy 339.29793 -285.016629)
			(xy 339.268716 -285.058031) (xy 339.233511 -285.094476) (xy 339.193146 -285.125106) (xy 339.148569 -285.149199)
			(xy 339.100831 -285.16619) (xy 339.07603 -285.171388) (xy 339.05317 -285.175706) (xy 338.848192 -285.530544)
			(xy 338.856066 -285.552642) (xy 338.86469 -285.578991) (xy 338.874015 -285.633637) (xy 338.874608 -285.661354)
			(xy 339.155024 -285.661354) (xy 339.155532 -285.635447) (xy 339.163638 -285.58427) (xy 339.17965 -285.534991)
			(xy 339.203173 -285.488824) (xy 339.233629 -285.446905) (xy 339.270267 -285.410267) (xy 339.312186 -285.379811)
			(xy 339.358353 -285.356288) (xy 339.407632 -285.340276) (xy 339.458809 -285.33217) (xy 339.510623 -285.33217)
			(xy 339.5618 -285.340276) (xy 339.611079 -285.356288) (xy 339.657246 -285.379811) (xy 339.699165 -285.410267)
			(xy 339.735803 -285.446905) (xy 339.766259 -285.488824) (xy 339.789782 -285.534991) (xy 339.805794 -285.58427)
			(xy 339.8139 -285.635447) (xy 339.814408 -285.661354) (xy 340.094824 -285.661354) (xy 340.095245 -285.636017)
			(xy 340.103005 -285.585941) (xy 340.118335 -285.537642) (xy 340.140875 -285.492257) (xy 340.170092 -285.450854)
			(xy 340.2053 -285.41441) (xy 340.24567 -285.383781) (xy 340.29025 -285.359689) (xy 340.337992 -285.342701)
			(xy 340.362794 -285.337504) (xy 340.385654 -285.333186) (xy 340.590886 -284.97784) (xy 340.583266 -284.955996)
			(xy 340.574644 -284.929713) (xy 340.565327 -284.875193) (xy 340.564724 -284.847538) (xy 340.565232 -284.821631)
			(xy 340.573338 -284.770454) (xy 340.58935 -284.721175) (xy 340.612873 -284.675008) (xy 340.643329 -284.633089)
			(xy 340.679967 -284.596451) (xy 340.721886 -284.565995) (xy 340.768053 -284.542472) (xy 340.817332 -284.52646)
			(xy 340.868509 -284.518354) (xy 340.920323 -284.518354) (xy 340.9715 -284.52646) (xy 341.020779 -284.542472)
			(xy 341.066946 -284.565995) (xy 341.108865 -284.596451) (xy 341.145503 -284.633089) (xy 341.175959 -284.675008)
			(xy 341.199482 -284.721175) (xy 341.215494 -284.770454) (xy 341.2236 -284.821631) (xy 341.224108 -284.847538)
			(xy 341.223661 -284.872913) (xy 341.215887 -284.923064) (xy 341.200514 -284.97143) (xy 341.177905 -285.016866)
			(xy 341.148596 -285.058297) (xy 341.113279 -285.094742) (xy 341.072791 -285.125341) (xy 341.028089 -285.149367)
			(xy 340.980231 -285.166254) (xy 340.955376 -285.171388) (xy 340.932516 -285.175706) (xy 340.727538 -285.530544)
			(xy 340.735412 -285.552642) (xy 340.743983 -285.578997) (xy 340.753175 -285.633645) (xy 340.7537 -285.661354)
			(xy 341.034624 -285.661354) (xy 341.035132 -285.635467) (xy 341.043231 -285.584329) (xy 341.05923 -285.535089)
			(xy 341.082736 -285.488957) (xy 341.113168 -285.44707) (xy 341.149778 -285.41046) (xy 341.191665 -285.380028)
			(xy 341.237797 -285.356522) (xy 341.287037 -285.340523) (xy 341.338175 -285.332424) (xy 341.389949 -285.332424)
			(xy 341.441087 -285.340523) (xy 341.490327 -285.356522) (xy 341.536459 -285.380028) (xy 341.578346 -285.41046)
			(xy 341.614956 -285.44707) (xy 341.645388 -285.488957) (xy 341.668894 -285.535089) (xy 341.684893 -285.584329)
			(xy 341.692992 -285.635467) (xy 341.6935 -285.661354) (xy 341.974424 -285.661354) (xy 341.974845 -285.636017)
			(xy 341.982605 -285.585941) (xy 341.997935 -285.537642) (xy 342.020475 -285.492257) (xy 342.049692 -285.450854)
			(xy 342.0849 -285.41441) (xy 342.12527 -285.383781) (xy 342.16985 -285.359689) (xy 342.217592 -285.342701)
			(xy 342.242394 -285.337504) (xy 342.265254 -285.333186) (xy 342.470486 -284.97784) (xy 342.462866 -284.955996)
			(xy 342.454244 -284.929713) (xy 342.444927 -284.875193) (xy 342.444324 -284.847538) (xy 342.444832 -284.821631)
			(xy 342.452938 -284.770454) (xy 342.46895 -284.721175) (xy 342.492473 -284.675008) (xy 342.522929 -284.633089)
			(xy 342.559567 -284.596451) (xy 342.601486 -284.565995) (xy 342.647653 -284.542472) (xy 342.696932 -284.52646)
			(xy 342.748109 -284.518354) (xy 342.799923 -284.518354) (xy 342.8511 -284.52646) (xy 342.900379 -284.542472)
			(xy 342.946546 -284.565995) (xy 342.988465 -284.596451) (xy 343.025103 -284.633089) (xy 343.055559 -284.675008)
			(xy 343.079082 -284.721175) (xy 343.095094 -284.770454) (xy 343.1032 -284.821631) (xy 343.103708 -284.847538)
			(xy 343.103261 -284.872913) (xy 343.095487 -284.923064) (xy 343.080114 -284.97143) (xy 343.057505 -285.016866)
			(xy 343.028196 -285.058297) (xy 342.992879 -285.094742) (xy 342.952391 -285.125341) (xy 342.907689 -285.149367)
			(xy 342.859831 -285.166254) (xy 342.834976 -285.171388) (xy 342.812116 -285.175706) (xy 342.607138 -285.530544)
			(xy 342.615012 -285.552642) (xy 342.623583 -285.578997) (xy 342.632775 -285.633645) (xy 342.6333 -285.661354)
			(xy 342.914224 -285.661354) (xy 342.914732 -285.635467) (xy 342.922831 -285.584329) (xy 342.93883 -285.535089)
			(xy 342.962336 -285.488957) (xy 342.992768 -285.44707) (xy 343.029378 -285.41046) (xy 343.071265 -285.380028)
			(xy 343.117397 -285.356522) (xy 343.166637 -285.340523) (xy 343.217775 -285.332424) (xy 343.269549 -285.332424)
			(xy 343.320687 -285.340523) (xy 343.369927 -285.356522) (xy 343.416059 -285.380028) (xy 343.457946 -285.41046)
			(xy 343.494556 -285.44707) (xy 343.524988 -285.488957) (xy 343.548494 -285.535089) (xy 343.564493 -285.584329)
			(xy 343.572592 -285.635467) (xy 343.5731 -285.661354) (xy 343.854024 -285.661354) (xy 343.854445 -285.636017)
			(xy 343.862205 -285.585941) (xy 343.877535 -285.537642) (xy 343.900075 -285.492257) (xy 343.929292 -285.450854)
			(xy 343.9645 -285.41441) (xy 344.00487 -285.383781) (xy 344.04945 -285.359689) (xy 344.097192 -285.342701)
			(xy 344.121994 -285.337504) (xy 344.144854 -285.333186) (xy 344.350086 -284.97784) (xy 344.342466 -284.955996)
			(xy 344.333844 -284.929713) (xy 344.324527 -284.875193) (xy 344.323924 -284.847538) (xy 344.324432 -284.821631)
			(xy 344.332538 -284.770454) (xy 344.34855 -284.721175) (xy 344.372073 -284.675008) (xy 344.402529 -284.633089)
			(xy 344.439167 -284.596451) (xy 344.481086 -284.565995) (xy 344.527253 -284.542472) (xy 344.576532 -284.52646)
			(xy 344.627709 -284.518354) (xy 344.679523 -284.518354) (xy 344.7307 -284.52646) (xy 344.779979 -284.542472)
			(xy 344.826146 -284.565995) (xy 344.868065 -284.596451) (xy 344.904703 -284.633089) (xy 344.935159 -284.675008)
			(xy 344.958682 -284.721175) (xy 344.974694 -284.770454) (xy 344.9828 -284.821631) (xy 344.983308 -284.847538)
			(xy 344.982861 -284.872913) (xy 344.975087 -284.923064) (xy 344.959714 -284.97143) (xy 344.937105 -285.016866)
			(xy 344.907796 -285.058297) (xy 344.872479 -285.094742) (xy 344.831991 -285.125341) (xy 344.787289 -285.149367)
			(xy 344.739431 -285.166254) (xy 344.714576 -285.171388) (xy 344.691716 -285.175706) (xy 344.486738 -285.530544)
			(xy 344.494612 -285.552642) (xy 344.503183 -285.578997) (xy 344.512375 -285.633645) (xy 344.5129 -285.661354)
			(xy 344.793824 -285.661354) (xy 344.794332 -285.635467) (xy 344.802431 -285.584329) (xy 344.81843 -285.535089)
			(xy 344.841936 -285.488957) (xy 344.872368 -285.44707) (xy 344.908978 -285.41046) (xy 344.950865 -285.380028)
			(xy 344.996997 -285.356522) (xy 345.046237 -285.340523) (xy 345.097375 -285.332424) (xy 345.149149 -285.332424)
			(xy 345.200287 -285.340523) (xy 345.249527 -285.356522) (xy 345.295659 -285.380028) (xy 345.337546 -285.41046)
			(xy 345.374156 -285.44707) (xy 345.404588 -285.488957) (xy 345.428094 -285.535089) (xy 345.444093 -285.584329)
			(xy 345.452192 -285.635467) (xy 345.4527 -285.661354) (xy 345.733624 -285.661354) (xy 345.734045 -285.636017)
			(xy 345.741805 -285.585941) (xy 345.757135 -285.537642) (xy 345.779675 -285.492257) (xy 345.808892 -285.450854)
			(xy 345.8441 -285.41441) (xy 345.88447 -285.383781) (xy 345.92905 -285.359689) (xy 345.976792 -285.342701)
			(xy 346.001594 -285.337504) (xy 346.024454 -285.333186) (xy 346.229686 -284.97784) (xy 346.222066 -284.955996)
			(xy 346.213444 -284.929713) (xy 346.204127 -284.875193) (xy 346.203524 -284.847538) (xy 346.204032 -284.821631)
			(xy 346.212138 -284.770454) (xy 346.22815 -284.721175) (xy 346.251673 -284.675008) (xy 346.282129 -284.633089)
			(xy 346.318767 -284.596451) (xy 346.360686 -284.565995) (xy 346.406853 -284.542472) (xy 346.456132 -284.52646)
			(xy 346.507309 -284.518354) (xy 346.559123 -284.518354) (xy 346.6103 -284.52646) (xy 346.659579 -284.542472)
			(xy 346.705746 -284.565995) (xy 346.747665 -284.596451) (xy 346.784303 -284.633089) (xy 346.814759 -284.675008)
			(xy 346.838282 -284.721175) (xy 346.854294 -284.770454) (xy 346.8624 -284.821631) (xy 346.862908 -284.847538)
			(xy 346.862461 -284.872913) (xy 346.854687 -284.923064) (xy 346.839314 -284.97143) (xy 346.816705 -285.016866)
			(xy 346.787396 -285.058297) (xy 346.752079 -285.094742) (xy 346.711591 -285.125341) (xy 346.666889 -285.149367)
			(xy 346.619031 -285.166254) (xy 346.594176 -285.171388) (xy 346.571316 -285.175706) (xy 346.366338 -285.530544)
			(xy 346.374212 -285.552642) (xy 346.382783 -285.578997) (xy 346.391975 -285.633645) (xy 346.3925 -285.661354)
			(xy 346.673424 -285.661354) (xy 346.673932 -285.635467) (xy 346.682031 -285.584329) (xy 346.69803 -285.535089)
			(xy 346.721536 -285.488957) (xy 346.751968 -285.44707) (xy 346.788578 -285.41046) (xy 346.830465 -285.380028)
			(xy 346.876597 -285.356522) (xy 346.925837 -285.340523) (xy 346.976975 -285.332424) (xy 347.028749 -285.332424)
			(xy 347.079887 -285.340523) (xy 347.129127 -285.356522) (xy 347.175259 -285.380028) (xy 347.217146 -285.41046)
			(xy 347.253756 -285.44707) (xy 347.284188 -285.488957) (xy 347.307694 -285.535089) (xy 347.323693 -285.584329)
			(xy 347.331792 -285.635467) (xy 347.3323 -285.661354) (xy 347.613224 -285.661354) (xy 347.613645 -285.636017)
			(xy 347.621405 -285.585941) (xy 347.636735 -285.537642) (xy 347.659275 -285.492257) (xy 347.688492 -285.450854)
			(xy 347.7237 -285.41441) (xy 347.76407 -285.383781) (xy 347.80865 -285.359689) (xy 347.856392 -285.342701)
			(xy 347.881194 -285.337504) (xy 347.904054 -285.333186) (xy 348.109286 -284.97784) (xy 348.101666 -284.955996)
			(xy 348.093044 -284.929713) (xy 348.083727 -284.875193) (xy 348.083124 -284.847538) (xy 348.083632 -284.821631)
			(xy 348.091738 -284.770454) (xy 348.10775 -284.721175) (xy 348.131273 -284.675008) (xy 348.161729 -284.633089)
			(xy 348.198367 -284.596451) (xy 348.240286 -284.565995) (xy 348.286453 -284.542472) (xy 348.335732 -284.52646)
			(xy 348.386909 -284.518354) (xy 348.438723 -284.518354) (xy 348.4899 -284.52646) (xy 348.539179 -284.542472)
			(xy 348.585346 -284.565995) (xy 348.627265 -284.596451) (xy 348.663903 -284.633089) (xy 348.694359 -284.675008)
			(xy 348.717882 -284.721175) (xy 348.733894 -284.770454) (xy 348.742 -284.821631) (xy 348.742508 -284.847538)
			(xy 348.742061 -284.872913) (xy 348.734287 -284.923064) (xy 348.718914 -284.97143) (xy 348.696305 -285.016866)
			(xy 348.666996 -285.058297) (xy 348.631679 -285.094742) (xy 348.591191 -285.125341) (xy 348.546489 -285.149367)
			(xy 348.498631 -285.166254) (xy 348.473776 -285.171388) (xy 348.450916 -285.175706) (xy 348.245938 -285.530544)
			(xy 348.253812 -285.552642) (xy 348.262383 -285.578997) (xy 348.271575 -285.633645) (xy 348.2721 -285.661354)
			(xy 348.553024 -285.661354) (xy 348.553532 -285.635467) (xy 348.561631 -285.584329) (xy 348.57763 -285.535089)
			(xy 348.601136 -285.488957) (xy 348.631568 -285.44707) (xy 348.668178 -285.41046) (xy 348.710065 -285.380028)
			(xy 348.756197 -285.356522) (xy 348.805437 -285.340523) (xy 348.856575 -285.332424) (xy 348.908349 -285.332424)
			(xy 348.959487 -285.340523) (xy 349.008727 -285.356522) (xy 349.054859 -285.380028) (xy 349.096746 -285.41046)
			(xy 349.133356 -285.44707) (xy 349.163788 -285.488957) (xy 349.187294 -285.535089) (xy 349.203293 -285.584329)
			(xy 349.211392 -285.635467) (xy 349.2119 -285.661354) (xy 349.492824 -285.661354) (xy 349.493245 -285.636017)
			(xy 349.501005 -285.585941) (xy 349.516335 -285.537642) (xy 349.538875 -285.492257) (xy 349.568092 -285.450854)
			(xy 349.6033 -285.41441) (xy 349.64367 -285.383781) (xy 349.68825 -285.359689) (xy 349.735992 -285.342701)
			(xy 349.760794 -285.337504) (xy 349.783654 -285.333186) (xy 349.988886 -284.97784) (xy 349.981266 -284.955996)
			(xy 349.972644 -284.929713) (xy 349.963327 -284.875193) (xy 349.962724 -284.847538) (xy 349.963232 -284.821631)
			(xy 349.971338 -284.770454) (xy 349.98735 -284.721175) (xy 350.010873 -284.675008) (xy 350.041329 -284.633089)
			(xy 350.077967 -284.596451) (xy 350.119886 -284.565995) (xy 350.166053 -284.542472) (xy 350.215332 -284.52646)
			(xy 350.266509 -284.518354) (xy 350.318323 -284.518354) (xy 350.3695 -284.52646) (xy 350.418779 -284.542472)
			(xy 350.464946 -284.565995) (xy 350.506865 -284.596451) (xy 350.543503 -284.633089) (xy 350.573959 -284.675008)
			(xy 350.597482 -284.721175) (xy 350.613494 -284.770454) (xy 350.6216 -284.821631) (xy 350.622108 -284.847538)
			(xy 350.621661 -284.872913) (xy 350.613887 -284.923064) (xy 350.598514 -284.97143) (xy 350.575905 -285.016866)
			(xy 350.546596 -285.058297) (xy 350.511279 -285.094742) (xy 350.470791 -285.125341) (xy 350.426089 -285.149367)
			(xy 350.378231 -285.166254) (xy 350.353376 -285.171388) (xy 350.330516 -285.175706) (xy 350.125538 -285.530544)
			(xy 350.133412 -285.552642) (xy 350.141983 -285.578997) (xy 350.151175 -285.633645) (xy 350.1517 -285.661354)
			(xy 350.432624 -285.661354) (xy 350.433132 -285.635467) (xy 350.441231 -285.584329) (xy 350.45723 -285.535089)
			(xy 350.480736 -285.488957) (xy 350.511168 -285.44707) (xy 350.547778 -285.41046) (xy 350.589665 -285.380028)
			(xy 350.635797 -285.356522) (xy 350.685037 -285.340523) (xy 350.736175 -285.332424) (xy 350.787949 -285.332424)
			(xy 350.839087 -285.340523) (xy 350.888327 -285.356522) (xy 350.934459 -285.380028) (xy 350.976346 -285.41046)
			(xy 351.012956 -285.44707) (xy 351.043388 -285.488957) (xy 351.066894 -285.535089) (xy 351.082893 -285.584329)
			(xy 351.090992 -285.635467) (xy 351.0915 -285.661354) (xy 351.090955 -285.688998) (xy 351.081759 -285.743516)
			(xy 351.073212 -285.769812) (xy 351.065592 -285.79191) (xy 351.270824 -286.147256) (xy 351.293684 -286.151574)
			(xy 351.318506 -286.156737) (xy 351.366283 -286.173695) (xy 351.410901 -286.197768) (xy 351.451306 -286.22839)
			(xy 351.486546 -286.264837) (xy 351.515789 -286.30625) (xy 351.538346 -286.351653) (xy 351.553685 -286.399975)
			(xy 351.561445 -286.450075) (xy 351.561908 -286.475424) (xy 351.5614 -286.501331) (xy 351.553294 -286.552508)
			(xy 351.537282 -286.601787) (xy 351.513759 -286.647954) (xy 351.483303 -286.689873) (xy 351.446665 -286.726511)
			(xy 351.404746 -286.756967) (xy 351.358579 -286.78049) (xy 351.3093 -286.796502) (xy 351.258123 -286.804608)
			(xy 351.206309 -286.804608) (xy 351.155132 -286.796502) (xy 351.105853 -286.78049) (xy 351.059686 -286.756967)
			(xy 351.017767 -286.726511) (xy 350.981129 -286.689873) (xy 350.950673 -286.647954) (xy 350.92715 -286.601787)
			(xy 350.911138 -286.552508) (xy 350.903032 -286.501331) (xy 350.902524 -286.475424) (xy 350.903123 -286.447707)
			(xy 350.912443 -286.39306) (xy 350.921066 -286.366712) (xy 350.92894 -286.344614) (xy 350.723962 -285.989522)
			(xy 350.700848 -285.985204) (xy 350.676027 -285.980039) (xy 350.628247 -285.963084) (xy 350.583628 -285.939012)
			(xy 350.543222 -285.908392) (xy 350.507981 -285.871945) (xy 350.478737 -285.830531) (xy 350.45618 -285.785127)
			(xy 350.440843 -285.736804) (xy 350.433086 -285.686703) (xy 350.432624 -285.661354) (xy 350.1517 -285.661354)
			(xy 350.151192 -285.687241) (xy 350.143093 -285.738379) (xy 350.127094 -285.787619) (xy 350.103588 -285.833751)
			(xy 350.073156 -285.875638) (xy 350.036546 -285.912248) (xy 349.994659 -285.94268) (xy 349.948527 -285.966186)
			(xy 349.899287 -285.982185) (xy 349.848149 -285.990284) (xy 349.796375 -285.990284) (xy 349.745237 -285.982185)
			(xy 349.695997 -285.966186) (xy 349.649865 -285.94268) (xy 349.607978 -285.912248) (xy 349.571368 -285.875638)
			(xy 349.540936 -285.833751) (xy 349.51743 -285.787619) (xy 349.501431 -285.738379) (xy 349.493332 -285.687241)
			(xy 349.492824 -285.661354) (xy 349.2119 -285.661354) (xy 349.211355 -285.688998) (xy 349.202159 -285.743516)
			(xy 349.193612 -285.769812) (xy 349.185992 -285.79191) (xy 349.391224 -286.147256) (xy 349.414084 -286.151574)
			(xy 349.438906 -286.156737) (xy 349.486683 -286.173695) (xy 349.531301 -286.197768) (xy 349.571706 -286.22839)
			(xy 349.606946 -286.264837) (xy 349.636189 -286.30625) (xy 349.658746 -286.351653) (xy 349.674085 -286.399975)
			(xy 349.681845 -286.450075) (xy 349.682308 -286.475424) (xy 349.6818 -286.501331) (xy 349.673694 -286.552508)
			(xy 349.657682 -286.601787) (xy 349.634159 -286.647954) (xy 349.603703 -286.689873) (xy 349.567065 -286.726511)
			(xy 349.525146 -286.756967) (xy 349.478979 -286.78049) (xy 349.4297 -286.796502) (xy 349.378523 -286.804608)
			(xy 349.326709 -286.804608) (xy 349.275532 -286.796502) (xy 349.226253 -286.78049) (xy 349.180086 -286.756967)
			(xy 349.138167 -286.726511) (xy 349.101529 -286.689873) (xy 349.071073 -286.647954) (xy 349.04755 -286.601787)
			(xy 349.031538 -286.552508) (xy 349.023432 -286.501331) (xy 349.022924 -286.475424) (xy 349.023523 -286.447707)
			(xy 349.032843 -286.39306) (xy 349.041466 -286.366712) (xy 349.04934 -286.344614) (xy 348.844362 -285.989522)
			(xy 348.821248 -285.985204) (xy 348.796427 -285.980039) (xy 348.748647 -285.963084) (xy 348.704028 -285.939012)
			(xy 348.663622 -285.908392) (xy 348.628381 -285.871945) (xy 348.599137 -285.830531) (xy 348.57658 -285.785127)
			(xy 348.561243 -285.736804) (xy 348.553486 -285.686703) (xy 348.553024 -285.661354) (xy 348.2721 -285.661354)
			(xy 348.271592 -285.687241) (xy 348.263493 -285.738379) (xy 348.247494 -285.787619) (xy 348.223988 -285.833751)
			(xy 348.193556 -285.875638) (xy 348.156946 -285.912248) (xy 348.115059 -285.94268) (xy 348.068927 -285.966186)
			(xy 348.019687 -285.982185) (xy 347.968549 -285.990284) (xy 347.916775 -285.990284) (xy 347.865637 -285.982185)
			(xy 347.816397 -285.966186) (xy 347.770265 -285.94268) (xy 347.728378 -285.912248) (xy 347.691768 -285.875638)
			(xy 347.661336 -285.833751) (xy 347.63783 -285.787619) (xy 347.621831 -285.738379) (xy 347.613732 -285.687241)
			(xy 347.613224 -285.661354) (xy 347.3323 -285.661354) (xy 347.331755 -285.688998) (xy 347.322559 -285.743516)
			(xy 347.314012 -285.769812) (xy 347.306392 -285.79191) (xy 347.511624 -286.147256) (xy 347.534484 -286.151574)
			(xy 347.559306 -286.156737) (xy 347.607083 -286.173695) (xy 347.651701 -286.197768) (xy 347.692106 -286.22839)
			(xy 347.727346 -286.264837) (xy 347.756589 -286.30625) (xy 347.779146 -286.351653) (xy 347.794485 -286.399975)
			(xy 347.802245 -286.450075) (xy 347.802708 -286.475424) (xy 347.8022 -286.501331) (xy 347.794094 -286.552508)
			(xy 347.778082 -286.601787) (xy 347.754559 -286.647954) (xy 347.724103 -286.689873) (xy 347.687465 -286.726511)
			(xy 347.645546 -286.756967) (xy 347.599379 -286.78049) (xy 347.5501 -286.796502) (xy 347.498923 -286.804608)
			(xy 347.447109 -286.804608) (xy 347.395932 -286.796502) (xy 347.346653 -286.78049) (xy 347.300486 -286.756967)
			(xy 347.258567 -286.726511) (xy 347.221929 -286.689873) (xy 347.191473 -286.647954) (xy 347.16795 -286.601787)
			(xy 347.151938 -286.552508) (xy 347.143832 -286.501331) (xy 347.143324 -286.475424) (xy 347.143923 -286.447707)
			(xy 347.153243 -286.39306) (xy 347.161866 -286.366712) (xy 347.16974 -286.344614) (xy 346.964762 -285.989522)
			(xy 346.941648 -285.985204) (xy 346.916827 -285.980039) (xy 346.869047 -285.963084) (xy 346.824428 -285.939012)
			(xy 346.784022 -285.908392) (xy 346.748781 -285.871945) (xy 346.719537 -285.830531) (xy 346.69698 -285.785127)
			(xy 346.681643 -285.736804) (xy 346.673886 -285.686703) (xy 346.673424 -285.661354) (xy 346.3925 -285.661354)
			(xy 346.391992 -285.687241) (xy 346.383893 -285.738379) (xy 346.367894 -285.787619) (xy 346.344388 -285.833751)
			(xy 346.313956 -285.875638) (xy 346.277346 -285.912248) (xy 346.235459 -285.94268) (xy 346.189327 -285.966186)
			(xy 346.140087 -285.982185) (xy 346.088949 -285.990284) (xy 346.037175 -285.990284) (xy 345.986037 -285.982185)
			(xy 345.936797 -285.966186) (xy 345.890665 -285.94268) (xy 345.848778 -285.912248) (xy 345.812168 -285.875638)
			(xy 345.781736 -285.833751) (xy 345.75823 -285.787619) (xy 345.742231 -285.738379) (xy 345.734132 -285.687241)
			(xy 345.733624 -285.661354) (xy 345.4527 -285.661354) (xy 345.452155 -285.688998) (xy 345.442959 -285.743516)
			(xy 345.434412 -285.769812) (xy 345.426792 -285.79191) (xy 345.632024 -286.147256) (xy 345.654884 -286.151574)
			(xy 345.679706 -286.156737) (xy 345.727483 -286.173695) (xy 345.772101 -286.197768) (xy 345.812506 -286.22839)
			(xy 345.847746 -286.264837) (xy 345.876989 -286.30625) (xy 345.899546 -286.351653) (xy 345.914885 -286.399975)
			(xy 345.922645 -286.450075) (xy 345.923108 -286.475424) (xy 345.9226 -286.501331) (xy 345.914494 -286.552508)
			(xy 345.898482 -286.601787) (xy 345.874959 -286.647954) (xy 345.844503 -286.689873) (xy 345.807865 -286.726511)
			(xy 345.765946 -286.756967) (xy 345.719779 -286.78049) (xy 345.6705 -286.796502) (xy 345.619323 -286.804608)
			(xy 345.567509 -286.804608) (xy 345.516332 -286.796502) (xy 345.467053 -286.78049) (xy 345.420886 -286.756967)
			(xy 345.378967 -286.726511) (xy 345.342329 -286.689873) (xy 345.311873 -286.647954) (xy 345.28835 -286.601787)
			(xy 345.272338 -286.552508) (xy 345.264232 -286.501331) (xy 345.263724 -286.475424) (xy 345.264323 -286.447707)
			(xy 345.273643 -286.39306) (xy 345.282266 -286.366712) (xy 345.29014 -286.344614) (xy 345.085162 -285.989522)
			(xy 345.062048 -285.985204) (xy 345.037227 -285.980039) (xy 344.989447 -285.963084) (xy 344.944828 -285.939012)
			(xy 344.904422 -285.908392) (xy 344.869181 -285.871945) (xy 344.839937 -285.830531) (xy 344.81738 -285.785127)
			(xy 344.802043 -285.736804) (xy 344.794286 -285.686703) (xy 344.793824 -285.661354) (xy 344.5129 -285.661354)
			(xy 344.512392 -285.687241) (xy 344.504293 -285.738379) (xy 344.488294 -285.787619) (xy 344.464788 -285.833751)
			(xy 344.434356 -285.875638) (xy 344.397746 -285.912248) (xy 344.355859 -285.94268) (xy 344.309727 -285.966186)
			(xy 344.260487 -285.982185) (xy 344.209349 -285.990284) (xy 344.157575 -285.990284) (xy 344.106437 -285.982185)
			(xy 344.057197 -285.966186) (xy 344.011065 -285.94268) (xy 343.969178 -285.912248) (xy 343.932568 -285.875638)
			(xy 343.902136 -285.833751) (xy 343.87863 -285.787619) (xy 343.862631 -285.738379) (xy 343.854532 -285.687241)
			(xy 343.854024 -285.661354) (xy 343.5731 -285.661354) (xy 343.572555 -285.688998) (xy 343.563359 -285.743516)
			(xy 343.554812 -285.769812) (xy 343.547192 -285.79191) (xy 343.752424 -286.147256) (xy 343.775284 -286.151574)
			(xy 343.800106 -286.156737) (xy 343.847883 -286.173695) (xy 343.892501 -286.197768) (xy 343.932906 -286.22839)
			(xy 343.968146 -286.264837) (xy 343.997389 -286.30625) (xy 344.019946 -286.351653) (xy 344.035285 -286.399975)
			(xy 344.043045 -286.450075) (xy 344.043508 -286.475424) (xy 344.043 -286.501331) (xy 344.034894 -286.552508)
			(xy 344.018882 -286.601787) (xy 343.995359 -286.647954) (xy 343.964903 -286.689873) (xy 343.928265 -286.726511)
			(xy 343.886346 -286.756967) (xy 343.840179 -286.78049) (xy 343.7909 -286.796502) (xy 343.739723 -286.804608)
			(xy 343.687909 -286.804608) (xy 343.636732 -286.796502) (xy 343.587453 -286.78049) (xy 343.541286 -286.756967)
			(xy 343.499367 -286.726511) (xy 343.462729 -286.689873) (xy 343.432273 -286.647954) (xy 343.40875 -286.601787)
			(xy 343.392738 -286.552508) (xy 343.384632 -286.501331) (xy 343.384124 -286.475424) (xy 343.384723 -286.447707)
			(xy 343.394043 -286.39306) (xy 343.402666 -286.366712) (xy 343.41054 -286.344614) (xy 343.205562 -285.989522)
			(xy 343.182448 -285.985204) (xy 343.157627 -285.980039) (xy 343.109847 -285.963084) (xy 343.065228 -285.939012)
			(xy 343.024822 -285.908392) (xy 342.989581 -285.871945) (xy 342.960337 -285.830531) (xy 342.93778 -285.785127)
			(xy 342.922443 -285.736804) (xy 342.914686 -285.686703) (xy 342.914224 -285.661354) (xy 342.6333 -285.661354)
			(xy 342.632792 -285.687241) (xy 342.624693 -285.738379) (xy 342.608694 -285.787619) (xy 342.585188 -285.833751)
			(xy 342.554756 -285.875638) (xy 342.518146 -285.912248) (xy 342.476259 -285.94268) (xy 342.430127 -285.966186)
			(xy 342.380887 -285.982185) (xy 342.329749 -285.990284) (xy 342.277975 -285.990284) (xy 342.226837 -285.982185)
			(xy 342.177597 -285.966186) (xy 342.131465 -285.94268) (xy 342.089578 -285.912248) (xy 342.052968 -285.875638)
			(xy 342.022536 -285.833751) (xy 341.99903 -285.787619) (xy 341.983031 -285.738379) (xy 341.974932 -285.687241)
			(xy 341.974424 -285.661354) (xy 341.6935 -285.661354) (xy 341.692955 -285.688998) (xy 341.683759 -285.743516)
			(xy 341.675212 -285.769812) (xy 341.667592 -285.79191) (xy 341.872824 -286.147256) (xy 341.895684 -286.151574)
			(xy 341.920506 -286.156737) (xy 341.968283 -286.173695) (xy 342.012901 -286.197768) (xy 342.053306 -286.22839)
			(xy 342.088546 -286.264837) (xy 342.117789 -286.30625) (xy 342.140346 -286.351653) (xy 342.155685 -286.399975)
			(xy 342.163445 -286.450075) (xy 342.163908 -286.475424) (xy 342.1634 -286.501331) (xy 342.155294 -286.552508)
			(xy 342.139282 -286.601787) (xy 342.115759 -286.647954) (xy 342.085303 -286.689873) (xy 342.048665 -286.726511)
			(xy 342.006746 -286.756967) (xy 341.960579 -286.78049) (xy 341.9113 -286.796502) (xy 341.860123 -286.804608)
			(xy 341.808309 -286.804608) (xy 341.757132 -286.796502) (xy 341.707853 -286.78049) (xy 341.661686 -286.756967)
			(xy 341.619767 -286.726511) (xy 341.583129 -286.689873) (xy 341.552673 -286.647954) (xy 341.52915 -286.601787)
			(xy 341.513138 -286.552508) (xy 341.505032 -286.501331) (xy 341.504524 -286.475424) (xy 341.505123 -286.447707)
			(xy 341.514443 -286.39306) (xy 341.523066 -286.366712) (xy 341.53094 -286.344614) (xy 341.325962 -285.989522)
			(xy 341.302848 -285.985204) (xy 341.278027 -285.980039) (xy 341.230247 -285.963084) (xy 341.185628 -285.939012)
			(xy 341.145222 -285.908392) (xy 341.109981 -285.871945) (xy 341.080737 -285.830531) (xy 341.05818 -285.785127)
			(xy 341.042843 -285.736804) (xy 341.035086 -285.686703) (xy 341.034624 -285.661354) (xy 340.7537 -285.661354)
			(xy 340.753192 -285.687241) (xy 340.745093 -285.738379) (xy 340.729094 -285.787619) (xy 340.705588 -285.833751)
			(xy 340.675156 -285.875638) (xy 340.638546 -285.912248) (xy 340.596659 -285.94268) (xy 340.550527 -285.966186)
			(xy 340.501287 -285.982185) (xy 340.450149 -285.990284) (xy 340.398375 -285.990284) (xy 340.347237 -285.982185)
			(xy 340.297997 -285.966186) (xy 340.251865 -285.94268) (xy 340.209978 -285.912248) (xy 340.173368 -285.875638)
			(xy 340.142936 -285.833751) (xy 340.11943 -285.787619) (xy 340.103431 -285.738379) (xy 340.095332 -285.687241)
			(xy 340.094824 -285.661354) (xy 339.814408 -285.661354) (xy 339.813802 -285.689071) (xy 339.804487 -285.743717)
			(xy 339.795866 -285.770066) (xy 339.787992 -285.792164) (xy 339.993224 -286.147256) (xy 340.016084 -286.151574)
			(xy 340.040906 -286.156737) (xy 340.088683 -286.173695) (xy 340.133301 -286.197768) (xy 340.173706 -286.22839)
			(xy 340.208946 -286.264837) (xy 340.238189 -286.30625) (xy 340.260746 -286.351653) (xy 340.276085 -286.399975)
			(xy 340.283845 -286.450075) (xy 340.284308 -286.475424) (xy 340.2838 -286.501331) (xy 340.275694 -286.552508)
			(xy 340.259682 -286.601787) (xy 340.236159 -286.647954) (xy 340.205703 -286.689873) (xy 340.169065 -286.726511)
			(xy 340.127146 -286.756967) (xy 340.080979 -286.78049) (xy 340.0317 -286.796502) (xy 339.980523 -286.804608)
			(xy 339.928709 -286.804608) (xy 339.877532 -286.796502) (xy 339.828253 -286.78049) (xy 339.782086 -286.756967)
			(xy 339.740167 -286.726511) (xy 339.703529 -286.689873) (xy 339.673073 -286.647954) (xy 339.64955 -286.601787)
			(xy 339.633538 -286.552508) (xy 339.625432 -286.501331) (xy 339.624924 -286.475424) (xy 339.625523 -286.447707)
			(xy 339.634843 -286.39306) (xy 339.643466 -286.366712) (xy 339.65134 -286.344614) (xy 339.446108 -285.989522)
			(xy 339.423248 -285.985204) (xy 339.398427 -285.980039) (xy 339.350647 -285.963084) (xy 339.306028 -285.939012)
			(xy 339.265622 -285.908392) (xy 339.230381 -285.871945) (xy 339.201137 -285.830531) (xy 339.17858 -285.785127)
			(xy 339.163243 -285.736804) (xy 339.155486 -285.686703) (xy 339.155024 -285.661354) (xy 338.874608 -285.661354)
			(xy 338.8741 -285.687261) (xy 338.865994 -285.738438) (xy 338.849982 -285.787717) (xy 338.826459 -285.833884)
			(xy 338.796003 -285.875803) (xy 338.759365 -285.912441) (xy 338.717446 -285.942897) (xy 338.671279 -285.96642)
			(xy 338.622 -285.982432) (xy 338.570823 -285.990538) (xy 338.519009 -285.990538) (xy 338.467832 -285.982432)
			(xy 338.418553 -285.96642) (xy 338.372386 -285.942897) (xy 338.330467 -285.912441) (xy 338.293829 -285.875803)
			(xy 338.263373 -285.833884) (xy 338.23985 -285.787717) (xy 338.223838 -285.738438) (xy 338.215732 -285.687261)
			(xy 338.215224 -285.661354) (xy 337.9343 -285.661354) (xy 337.933759 -285.689062) (xy 337.924571 -285.743708)
			(xy 337.916012 -285.770066) (xy 337.908138 -285.792164) (xy 338.11337 -286.147256) (xy 338.13623 -286.151574)
			(xy 338.16104 -286.156732) (xy 338.20878 -286.173726) (xy 338.253357 -286.197824) (xy 338.293722 -286.228459)
			(xy 338.328925 -286.264909) (xy 338.358136 -286.306317) (xy 338.380667 -286.351707) (xy 338.395988 -286.400009)
			(xy 338.403738 -286.450087) (xy 338.4042 -286.475424) (xy 338.403692 -286.501311) (xy 338.395593 -286.552449)
			(xy 338.379594 -286.601689) (xy 338.356088 -286.647821) (xy 338.325656 -286.689708) (xy 338.289046 -286.726318)
			(xy 338.247159 -286.75675) (xy 338.201027 -286.780256) (xy 338.151787 -286.796255) (xy 338.100649 -286.804354)
			(xy 338.048875 -286.804354) (xy 337.997737 -286.796255) (xy 337.948497 -286.780256) (xy 337.902365 -286.75675)
			(xy 337.860478 -286.726318) (xy 337.823868 -286.689708) (xy 337.793436 -286.647821) (xy 337.76993 -286.601689)
			(xy 337.753931 -286.552449) (xy 337.745832 -286.501311) (xy 337.745324 -286.475424) (xy 337.745858 -286.447716)
			(xy 337.75505 -286.393069) (xy 337.763612 -286.366712) (xy 337.771486 -286.344614) (xy 337.566254 -285.989522)
			(xy 337.543394 -285.985204) (xy 337.518583 -285.980049) (xy 337.470842 -285.963057) (xy 337.426263 -285.93896)
			(xy 337.385896 -285.908325) (xy 337.350693 -285.871874) (xy 337.321482 -285.830466) (xy 337.298951 -285.785075)
			(xy 337.283632 -285.736771) (xy 337.275885 -285.686692) (xy 337.275424 -285.661354) (xy 336.0547 -285.661354)
			(xy 336.054192 -285.687241) (xy 336.046093 -285.738379) (xy 336.030094 -285.787619) (xy 336.006588 -285.833751)
			(xy 335.976156 -285.875638) (xy 335.939546 -285.912248) (xy 335.897659 -285.94268) (xy 335.851527 -285.966186)
			(xy 335.802287 -285.982185) (xy 335.751149 -285.990284) (xy 335.699375 -285.990284) (xy 335.648237 -285.982185)
			(xy 335.598997 -285.966186) (xy 335.552865 -285.94268) (xy 335.510978 -285.912248) (xy 335.474368 -285.875638)
			(xy 335.443936 -285.833751) (xy 335.42043 -285.787619) (xy 335.404431 -285.738379) (xy 335.396332 -285.687241)
			(xy 335.395824 -285.661354) (xy 284.8356 -285.661354) (xy 284.8356 -286.475424) (xy 333.986124 -286.475424)
			(xy 333.986632 -286.449537) (xy 333.994731 -286.398399) (xy 334.01073 -286.349159) (xy 334.034236 -286.303027)
			(xy 334.064668 -286.26114) (xy 334.101278 -286.22453) (xy 334.143165 -286.194098) (xy 334.189297 -286.170592)
			(xy 334.238537 -286.154593) (xy 334.289675 -286.146494) (xy 334.341449 -286.146494) (xy 334.392587 -286.154593)
			(xy 334.441827 -286.170592) (xy 334.487959 -286.194098) (xy 334.529846 -286.22453) (xy 334.566456 -286.26114)
			(xy 334.596888 -286.303027) (xy 334.620394 -286.349159) (xy 334.636393 -286.398399) (xy 334.644492 -286.449537)
			(xy 334.645 -286.475424) (xy 334.644511 -286.501304) (xy 334.92624 -286.501304) (xy 334.92624 -286.449496)
			(xy 334.934344 -286.398327) (xy 334.950352 -286.349055) (xy 334.97387 -286.302894) (xy 335.00432 -286.26098)
			(xy 335.040951 -286.224345) (xy 335.082862 -286.19389) (xy 335.12902 -286.170367) (xy 335.17829 -286.154353)
			(xy 335.229459 -286.146243) (xy 335.255362 -286.145732) (xy 335.280855 -286.146231) (xy 335.331232 -286.154087)
			(xy 335.379796 -286.169618) (xy 335.425383 -286.192452) (xy 335.466904 -286.222042) (xy 335.503366 -286.257681)
			(xy 335.519014 -286.277812) (xy 335.93151 -286.277812) (xy 335.947185 -286.257701) (xy 335.98364 -286.222058)
			(xy 336.025155 -286.192461) (xy 336.070737 -286.16962) (xy 336.119296 -286.15408) (xy 336.16967 -286.146213)
			(xy 336.195162 -286.145732) (xy 336.221075 -286.146163) (xy 336.272264 -286.154265) (xy 336.321556 -286.170276)
			(xy 336.367735 -286.193801) (xy 336.409666 -286.22426) (xy 336.446315 -286.260905) (xy 336.47678 -286.302832)
			(xy 336.50031 -286.349009) (xy 336.516326 -286.398299) (xy 336.524434 -286.449487) (xy 336.524434 -286.501313)
			(xy 336.516326 -286.552501) (xy 336.50031 -286.601791) (xy 336.47678 -286.647968) (xy 336.446315 -286.689895)
			(xy 336.409666 -286.72654) (xy 336.367735 -286.756999) (xy 336.321556 -286.780524) (xy 336.272264 -286.796535)
			(xy 336.221075 -286.804637) (xy 336.195162 -286.805116) (xy 336.169668 -286.804653) (xy 336.11929 -286.796786)
			(xy 336.070727 -286.781247) (xy 336.02514 -286.758407) (xy 335.98362 -286.728811) (xy 335.947158 -286.693169)
			(xy 335.93151 -286.673036) (xy 335.519014 -286.673036) (xy 335.503397 -286.693193) (xy 335.466928 -286.728832)
			(xy 335.425401 -286.758421) (xy 335.379808 -286.781254) (xy 335.33124 -286.796785) (xy 335.280857 -286.804641)
			(xy 335.255362 -286.805116) (xy 335.229459 -286.804557) (xy 335.17829 -286.796447) (xy 335.12902 -286.780433)
			(xy 335.082862 -286.75691) (xy 335.040951 -286.726455) (xy 335.00432 -286.68982) (xy 334.97387 -286.647906)
			(xy 334.950352 -286.601745) (xy 334.934344 -286.552473) (xy 334.92624 -286.501304) (xy 334.644511 -286.501304)
			(xy 334.644476 -286.503132) (xy 334.635277 -286.557779) (xy 334.626712 -286.584136) (xy 334.619092 -286.60598)
			(xy 334.82407 -286.961072) (xy 334.84693 -286.96539) (xy 334.871744 -286.970533) (xy 334.919484 -286.987528)
			(xy 334.964063 -287.011628) (xy 335.004428 -287.042264) (xy 335.039631 -287.078717) (xy 335.068841 -287.120126)
			(xy 335.091372 -287.165518) (xy 335.106691 -287.213822) (xy 335.114439 -287.263902) (xy 335.1149 -287.28924)
			(xy 335.114392 -287.315127) (xy 335.106293 -287.366265) (xy 335.090294 -287.415505) (xy 335.066788 -287.461637)
			(xy 335.036356 -287.503524) (xy 334.999746 -287.540134) (xy 334.957859 -287.570566) (xy 334.911727 -287.594072)
			(xy 334.862487 -287.610071) (xy 334.811349 -287.61817) (xy 334.759575 -287.61817) (xy 334.708437 -287.610071)
			(xy 334.659197 -287.594072) (xy 334.613065 -287.570566) (xy 334.571178 -287.540134) (xy 334.534568 -287.503524)
			(xy 334.504136 -287.461637) (xy 334.48063 -287.415505) (xy 334.464631 -287.366265) (xy 334.456532 -287.315127)
			(xy 334.456024 -287.28924) (xy 334.456562 -287.261532) (xy 334.465751 -287.206885) (xy 334.474312 -287.180528)
			(xy 334.481932 -287.158684) (xy 334.276954 -286.803592) (xy 334.254094 -286.799274) (xy 334.229299 -286.794053)
			(xy 334.181562 -286.777067) (xy 334.136987 -286.752976) (xy 334.096622 -286.722349) (xy 334.061419 -286.685906)
			(xy 334.032206 -286.644507) (xy 334.009672 -286.599125) (xy 333.994346 -286.55083) (xy 333.98659 -286.500758)
			(xy 333.986124 -286.475424) (xy 284.8356 -286.475424) (xy 284.8356 -319.065148) (xy 284.834984 -319.090103)
			(xy 284.825238 -319.139052) (xy 284.806131 -319.185159) (xy 284.778397 -319.226653) (xy 284.761178 -319.244726)
			(xy 284.516576 -319.489328) (xy 284.497341 -319.507583) (xy 284.452907 -319.536509) (xy 284.428438 -319.546732)
			(xy 284.420139 -319.550394) (xy 284.406633 -319.562484) (xy 284.39817 -319.578514) (xy 284.395803 -319.596486)
			(xy 284.39745 -319.605406) (xy 284.400427 -319.619377) (xy 284.403615 -319.647765) (xy 284.4038 -319.662048)
			(xy 284.4038 -351.068132) (xy 285.047436 -351.711768) (xy 285.334964 -351.711768) (xy 285.348934 -351.68332)
			(xy 285.361964 -351.658163) (xy 285.394765 -351.611972) (xy 285.434461 -351.571552) (xy 285.480051 -351.537922)
			(xy 285.530387 -351.511927) (xy 285.584202 -351.494222) (xy 285.64014 -351.485254) (xy 285.668466 -351.484692)
			(xy 285.695792 -351.485166) (xy 285.749807 -351.493477) (xy 285.801915 -351.509953) (xy 285.850888 -351.534208)
			(xy 285.895575 -351.565669) (xy 285.915608 -351.58426) (xy 285.92723 -351.594657) (xy 285.955164 -351.608481)
			(xy 285.985966 -351.613237) (xy 286.016768 -351.608481) (xy 286.044702 -351.594657) (xy 286.056324 -351.58426)
			(xy 286.076376 -351.565695) (xy 286.121074 -351.534265) (xy 286.170046 -351.510023) (xy 286.222142 -351.493537)
			(xy 286.276145 -351.485194) (xy 286.303466 -351.484692) (xy 286.331471 -351.485211) (xy 286.386792 -351.493971)
			(xy 286.44006 -351.511281) (xy 286.489963 -351.536714) (xy 286.535271 -351.569644) (xy 286.555434 -351.589086)
			(xy 286.565131 -351.598252) (xy 286.588217 -351.611617) (xy 286.613979 -351.618536) (xy 286.640653 -351.618536)
			(xy 286.666415 -351.611617) (xy 286.689501 -351.598252) (xy 286.699198 -351.589086) (xy 286.719387 -351.569674)
			(xy 286.764694 -351.536752) (xy 286.814591 -351.51132) (xy 286.867851 -351.494002) (xy 286.923164 -351.485225)
			(xy 286.951166 -351.484692) (xy 286.979494 -351.485236) (xy 287.035438 -351.494197) (xy 287.089259 -351.511898)
			(xy 287.1396 -351.537893) (xy 287.185193 -351.571527) (xy 287.224889 -351.611952) (xy 287.257688 -351.65815)
			(xy 287.270698 -351.68332) (xy 287.284668 -351.711768) (xy 290.305236 -351.711768) (xy 290.319206 -351.68332)
			(xy 290.332235 -351.658161) (xy 290.365035 -351.611968) (xy 290.40473 -351.571545) (xy 290.45032 -351.53791)
			(xy 290.500656 -351.511912) (xy 290.554472 -351.494203) (xy 290.610411 -351.485231) (xy 290.638738 -351.484692)
			(xy 290.666744 -351.485208) (xy 290.722067 -351.493965) (xy 290.775338 -351.511272) (xy 290.825244 -351.536703)
			(xy 290.870555 -351.569631) (xy 290.890706 -351.589086) (xy 290.900403 -351.598252) (xy 290.923489 -351.611617)
			(xy 290.949251 -351.618536) (xy 290.975925 -351.618536) (xy 291.001687 -351.611617) (xy 291.024773 -351.598252)
			(xy 291.03447 -351.589086) (xy 291.054661 -351.569678) (xy 291.09997 -351.536766) (xy 291.149868 -351.511343)
			(xy 291.203127 -351.494036) (xy 291.258438 -351.48527) (xy 291.286438 -351.484692) (xy 291.313765 -351.485164)
			(xy 291.367782 -351.493471) (xy 291.419892 -351.509944) (xy 291.468869 -351.534196) (xy 291.513558 -351.565656)
			(xy 291.53358 -351.58426) (xy 291.545202 -351.594657) (xy 291.573136 -351.608481) (xy 291.603938 -351.613237)
			(xy 291.63474 -351.608481) (xy 291.662674 -351.594657) (xy 291.674296 -351.58426) (xy 291.694349 -351.565699)
			(xy 291.73905 -351.534278) (xy 291.788022 -351.510046) (xy 291.840118 -351.493571) (xy 291.894118 -351.485239)
			(xy 291.921438 -351.484692) (xy 291.949768 -351.485234) (xy 292.005714 -351.494191) (xy 292.059538 -351.511889)
			(xy 292.109883 -351.537882) (xy 292.15548 -351.571515) (xy 292.195179 -351.61194) (xy 292.227981 -351.658139)
			(xy 292.24097 -351.68332) (xy 292.25494 -351.711768) (xy 295.012364 -351.711768) (xy 295.026334 -351.68332)
			(xy 295.039364 -351.658163) (xy 295.072165 -351.611972) (xy 295.111861 -351.571552) (xy 295.157451 -351.537922)
			(xy 295.207787 -351.511927) (xy 295.261602 -351.494222) (xy 295.31754 -351.485254) (xy 295.345866 -351.484692)
			(xy 295.373192 -351.485166) (xy 295.427207 -351.493477) (xy 295.479315 -351.509953) (xy 295.528288 -351.534208)
			(xy 295.572975 -351.565669) (xy 295.593008 -351.58426) (xy 295.60463 -351.594657) (xy 295.632564 -351.608481)
			(xy 295.663366 -351.613237) (xy 295.694168 -351.608481) (xy 295.722102 -351.594657) (xy 295.733724 -351.58426)
			(xy 295.753776 -351.565695) (xy 295.798474 -351.534265) (xy 295.847446 -351.510023) (xy 295.899542 -351.493537)
			(xy 295.953545 -351.485194) (xy 295.980866 -351.484692) (xy 296.008871 -351.485211) (xy 296.064192 -351.493971)
			(xy 296.11746 -351.511281) (xy 296.167363 -351.536714) (xy 296.212671 -351.569644) (xy 296.232834 -351.589086)
			(xy 296.242531 -351.598252) (xy 296.265617 -351.611617) (xy 296.291379 -351.618536) (xy 296.318053 -351.618536)
			(xy 296.343815 -351.611617) (xy 296.366901 -351.598252) (xy 296.376598 -351.589086) (xy 296.396787 -351.569674)
			(xy 296.442094 -351.536752) (xy 296.491991 -351.51132) (xy 296.545251 -351.494002) (xy 296.600564 -351.485225)
			(xy 296.628566 -351.484692) (xy 296.656894 -351.485236) (xy 296.712838 -351.494197) (xy 296.766659 -351.511898)
			(xy 296.817 -351.537893) (xy 296.862593 -351.571527) (xy 296.902289 -351.611952) (xy 296.935088 -351.65815)
			(xy 296.948098 -351.68332) (xy 296.962068 -351.711768) (xy 300.084236 -351.711768) (xy 300.098206 -351.68332)
			(xy 300.111235 -351.658161) (xy 300.144035 -351.611968) (xy 300.18373 -351.571545) (xy 300.22932 -351.53791)
			(xy 300.279656 -351.511912) (xy 300.333472 -351.494203) (xy 300.389411 -351.485231) (xy 300.417738 -351.484692)
			(xy 300.445744 -351.485208) (xy 300.501067 -351.493965) (xy 300.554338 -351.511272) (xy 300.604244 -351.536703)
			(xy 300.649555 -351.569631) (xy 300.669706 -351.589086) (xy 300.679403 -351.598252) (xy 300.702489 -351.611617)
			(xy 300.728251 -351.618536) (xy 300.754925 -351.618536) (xy 300.780687 -351.611617) (xy 300.803773 -351.598252)
			(xy 300.81347 -351.589086) (xy 300.833661 -351.569678) (xy 300.87897 -351.536766) (xy 300.928868 -351.511343)
			(xy 300.982127 -351.494036) (xy 301.037438 -351.48527) (xy 301.065438 -351.484692) (xy 301.092765 -351.485164)
			(xy 301.146782 -351.493471) (xy 301.198892 -351.509944) (xy 301.247869 -351.534196) (xy 301.292558 -351.565656)
			(xy 301.31258 -351.58426) (xy 301.324202 -351.594657) (xy 301.352136 -351.608481) (xy 301.382938 -351.613237)
			(xy 301.41374 -351.608481) (xy 301.441674 -351.594657) (xy 301.453296 -351.58426) (xy 301.473349 -351.565699)
			(xy 301.51805 -351.534278) (xy 301.567022 -351.510046) (xy 301.619118 -351.493571) (xy 301.673118 -351.485239)
			(xy 301.700438 -351.484692) (xy 301.727178 -351.485168) (xy 301.780058 -351.493158) (xy 301.831147 -351.508968)
			(xy 301.879297 -351.532241) (xy 301.923424 -351.562456) (xy 301.962535 -351.59893) (xy 301.995751 -351.640845)
			(xy 302.022323 -351.687256) (xy 302.032416 -351.712022) (xy 302.053757 -351.711477) (xy 302.096128 -351.716673)
			(xy 302.137032 -351.728882) (xy 302.156368 -351.73793) (xy 302.167036 -351.743264) (xy 316.954916 -351.743264)
		)
		(stroke
			(width 0)
			(type solid)
		)
		(fill yes)
		(layer "In8.Cu")
		(net "PVCCFA_EHV_FIVRA_CPU0")
	)
	(gr_poly
		(pts
			(xy 256.292096 -31.120588) (xy 256.292096 -11.780012) (xy 256.29258 -11.709658) (xy 256.300469 -11.56917)
			(xy 256.316223 -11.429347) (xy 256.339792 -11.290626) (xy 256.371101 -11.153445) (xy 256.410054 -11.018236)
			(xy 256.456527 -10.885423) (xy 256.510373 -10.755425) (xy 256.571423 -10.628651) (xy 256.639486 -10.505499)
			(xy 256.714347 -10.386357) (xy 256.795771 -10.2716) (xy 256.883501 -10.16159) (xy 256.977261 -10.056671)
			(xy 257.076757 -9.957175) (xy 257.181674 -9.863414) (xy 257.291684 -9.775683) (xy 257.406441 -9.694258)
			(xy 257.525582 -9.619396) (xy 257.648733 -9.551333) (xy 257.775507 -9.490281) (xy 257.905504 -9.436434)
			(xy 258.038317 -9.38996) (xy 258.173526 -9.351006) (xy 258.310706 -9.319695) (xy 258.449427 -9.296125)
			(xy 258.589251 -9.280371) (xy 258.729738 -9.272481) (xy 258.800092 -9.272016) (xy 383.601976 -9.272016)
			(xy 383.657784 -9.271508) (xy 383.769089 -9.263168) (xy 383.879459 -9.246534) (xy 383.988278 -9.221699)
			(xy 384.094936 -9.188801) (xy 384.198838 -9.148025) (xy 384.299402 -9.099598) (xy 384.396066 -9.043791)
			(xy 384.488289 -8.980916) (xy 384.575555 -8.911326) (xy 384.657377 -8.835408) (xy 384.733297 -8.753588)
			(xy 384.80289 -8.666324) (xy 384.865767 -8.574103) (xy 384.921577 -8.477441) (xy 384.970007 -8.376878)
			(xy 385.010787 -8.272978) (xy 385.043688 -8.16632) (xy 385.068526 -8.057503) (xy 385.085163 -7.947133)
			(xy 385.093506 -7.835828) (xy 385.093972 -7.78002) (xy 385.093972 0.999998) (xy 385.094465 1.070352)
			(xy 385.102355 1.210839) (xy 385.118109 1.350662) (xy 385.141678 1.489383) (xy 385.172988 1.626563)
			(xy 385.211941 1.761772) (xy 385.258413 1.894584) (xy 385.312259 2.024582) (xy 385.37331 2.151356)
			(xy 385.441373 2.274507) (xy 385.516233 2.393649) (xy 385.597656 2.508405) (xy 385.685386 2.618416)
			(xy 385.779146 2.723335) (xy 385.878641 2.822831) (xy 385.983558 2.916592) (xy 386.093567 3.004323)
			(xy 386.208323 3.085748) (xy 386.327463 3.16061) (xy 386.450614 3.228674) (xy 386.577387 3.289727)
			(xy 386.707384 3.343575) (xy 386.840195 3.390049) (xy 386.975404 3.429003) (xy 387.112584 3.460315)
			(xy 387.251304 3.483887) (xy 387.391127 3.499643) (xy 387.531614 3.507534) (xy 387.601968 3.507994)
			(xy 456.202034 3.507994) (xy 456.272387 3.5075) (xy 456.412872 3.499608) (xy 456.552693 3.483853)
			(xy 456.691411 3.460282) (xy 456.828589 3.42897) (xy 456.963796 3.390016) (xy 457.096605 3.343542)
			(xy 457.226601 3.289695) (xy 457.353372 3.228644) (xy 457.476521 3.16058) (xy 457.595659 3.085719)
			(xy 457.710413 3.004295) (xy 457.820421 2.916565) (xy 457.925337 2.822806) (xy 458.02483 2.723311)
			(xy 458.118589 2.618393) (xy 458.206317 2.508384) (xy 458.287739 2.393629) (xy 458.362598 2.27449)
			(xy 458.43066 2.15134) (xy 458.49171 2.024568) (xy 458.545555 1.894572) (xy 458.592027 1.761761)
			(xy 458.630979 1.626554) (xy 458.662289 1.489376) (xy 458.685858 1.350658) (xy 458.701612 1.210836)
			(xy 458.709501 1.070351) (xy 458.71003 0.999998) (xy 458.71003 -7.78002) (xy 458.71054 -7.835827)
			(xy 458.718882 -7.947128) (xy 458.735519 -8.057494) (xy 458.760357 -8.166309) (xy 458.793257 -8.272963)
			(xy 458.834035 -8.37686) (xy 458.882464 -8.47742) (xy 458.938272 -8.574079) (xy 459.001148 -8.666297)
			(xy 459.070739 -8.753559) (xy 459.146656 -8.835376) (xy 459.228476 -8.911291) (xy 459.31574 -8.98088)
			(xy 459.40796 -9.043752) (xy 459.504621 -9.099557) (xy 459.605182 -9.147983) (xy 459.70908 -9.188758)
			(xy 459.815736 -9.221655) (xy 459.924551 -9.24649) (xy 460.034918 -9.263123) (xy 460.146219 -9.271462)
			(xy 460.202026 -9.272016) (xy 464.327748 -9.272016) (xy 464.332574 -9.271) (xy 464.357024 -9.266474)
			(xy 464.406516 -9.261643) (xy 464.43138 -9.261348) (xy 464.456244 -9.26164) (xy 464.505735 -9.266479)
			(xy 464.530186 -9.271) (xy 464.535012 -9.272016) (xy 469.799924 -9.272016) (xy 469.855731 -9.271493)
			(xy 469.967032 -9.263151) (xy 470.077399 -9.246514) (xy 470.186213 -9.221677) (xy 470.292868 -9.188777)
			(xy 470.396765 -9.147999) (xy 470.497325 -9.099571) (xy 470.593985 -9.043764) (xy 470.686204 -8.980889)
			(xy 470.773467 -8.911299) (xy 470.855285 -8.835382) (xy 470.931202 -8.753564) (xy 471.000791 -8.666301)
			(xy 471.063666 -8.574082) (xy 471.119473 -8.477422) (xy 471.167901 -8.376862) (xy 471.208678 -8.272964)
			(xy 471.241578 -8.166309) (xy 471.266415 -8.057495) (xy 471.283051 -7.947128) (xy 471.291394 -7.835827)
			(xy 471.29192 -7.78002) (xy 471.29192 10.40003) (xy 471.291397 10.455837) (xy 471.283054 10.567138)
			(xy 471.266417 10.677504) (xy 471.241579 10.786319) (xy 471.208679 10.892973) (xy 471.167901 10.99687)
			(xy 471.119473 11.09743) (xy 471.063666 11.194089) (xy 471.000791 11.286308) (xy 470.931201 11.373571)
			(xy 470.855284 11.455389) (xy 470.773466 11.531305) (xy 470.686203 11.600895) (xy 470.593984 11.663769)
			(xy 470.497324 11.719576) (xy 470.396765 11.768004) (xy 470.292867 11.808781) (xy 470.186213 11.841681)
			(xy 470.077398 11.866518) (xy 469.967032 11.883155) (xy 469.855731 11.891497) (xy 469.799924 11.892026)
			(xy 1.999996 11.892026) (xy 1.944189 11.891504) (xy 1.832887 11.883163) (xy 1.72252 11.866527) (xy 1.613705 11.841691)
			(xy 1.50705 11.808792) (xy 1.403151 11.768014) (xy 1.302591 11.719587) (xy 1.20593 11.66378) (xy 1.113711 11.600905)
			(xy 1.026448 11.531315) (xy 0.944629 11.455398) (xy 0.868712 11.373579) (xy 0.799122 11.286316) (xy 0.736248 11.194096)
			(xy 0.680441 11.097436) (xy 0.632014 10.996875) (xy 0.591237 10.892977) (xy 0.558338 10.786321) (xy 0.533502 10.677506)
			(xy 0.516867 10.567139) (xy 0.508526 10.455837) (xy 0.508 10.40003) (xy 0.508 7.335466) (xy 2.904225 7.335466)
			(xy 2.904225 7.464606) (xy 2.912175 7.593501) (xy 2.928045 7.721661) (xy 2.951774 7.848602) (xy 2.983273 7.973841)
			(xy 3.022422 8.096904) (xy 3.069073 8.217323) (xy 3.123048 8.334642) (xy 3.184143 8.448416) (xy 3.252126 8.558213)
			(xy 3.32674 8.663616) (xy 3.407701 8.764226) (xy 3.494701 8.859661) (xy 3.587412 8.94956) (xy 3.685482 9.033581)
			(xy 3.788537 9.111405) (xy 3.896188 9.182737) (xy 4.008027 9.247307) (xy 4.123628 9.304869) (xy 4.242553 9.355206)
			(xy 4.364352 9.398126) (xy 4.488562 9.433467) (xy 4.614711 9.461094) (xy 4.742323 9.480903) (xy 4.870912 9.492819)
			(xy 4.99999 9.496796) (xy 5.129068 9.492819) (xy 5.257657 9.480903) (xy 5.385269 9.461094) (xy 5.511418 9.433467)
			(xy 5.635628 9.398126) (xy 5.757427 9.355206) (xy 5.876352 9.304869) (xy 5.991953 9.247307) (xy 6.020338 9.230919)
			(xy 256.921241 9.230919) (xy 256.921241 9.316669) (xy 256.929153 9.402052) (xy 256.944909 9.486342)
			(xy 256.968376 9.568818) (xy 256.999352 9.648777) (xy 257.037574 9.725537) (xy 257.082715 9.798443)
			(xy 257.134391 9.866872) (xy 257.19216 9.930242) (xy 257.25553 9.988011) (xy 257.323959 10.039687)
			(xy 257.396865 10.084828) (xy 257.473625 10.12305) (xy 257.553584 10.154026) (xy 257.63606 10.177493)
			(xy 257.72035 10.193249) (xy 257.805733 10.201161) (xy 257.891483 10.201161) (xy 257.976866 10.193249)
			(xy 258.061156 10.177493) (xy 258.143632 10.154026) (xy 258.223591 10.12305) (xy 258.300351 10.084828)
			(xy 258.373257 10.039687) (xy 258.441686 9.988011) (xy 258.505056 9.930242) (xy 258.562825 9.866872)
			(xy 258.614501 9.798443) (xy 258.659642 9.725537) (xy 258.697864 9.648777) (xy 258.72884 9.568818)
			(xy 258.752307 9.486342) (xy 258.768063 9.402052) (xy 258.775975 9.316669) (xy 258.77647 9.273794)
			(xy 258.775975 9.230919) (xy 263.271241 9.230919) (xy 263.271241 9.316669) (xy 263.279153 9.402052)
			(xy 263.294909 9.486342) (xy 263.318376 9.568818) (xy 263.349352 9.648777) (xy 263.387574 9.725537)
			(xy 263.432715 9.798443) (xy 263.484391 9.866872) (xy 263.54216 9.930242) (xy 263.60553 9.988011)
			(xy 263.673959 10.039687) (xy 263.746865 10.084828) (xy 263.823625 10.12305) (xy 263.903584 10.154026)
			(xy 263.98606 10.177493) (xy 264.07035 10.193249) (xy 264.155733 10.201161) (xy 264.241483 10.201161)
			(xy 264.326866 10.193249) (xy 264.411156 10.177493) (xy 264.493632 10.154026) (xy 264.573591 10.12305)
			(xy 264.650351 10.084828) (xy 264.723257 10.039687) (xy 264.791686 9.988011) (xy 264.855056 9.930242)
			(xy 264.912825 9.866872) (xy 264.964501 9.798443) (xy 265.009642 9.725537) (xy 265.047864 9.648777)
			(xy 265.07884 9.568818) (xy 265.102307 9.486342) (xy 265.118063 9.402052) (xy 265.125975 9.316669)
			(xy 265.12647 9.273794) (xy 265.125975 9.230919) (xy 324.845921 9.230919) (xy 324.845921 9.316669)
			(xy 324.853833 9.402052) (xy 324.869589 9.486342) (xy 324.893056 9.568818) (xy 324.924032 9.648777)
			(xy 324.962254 9.725537) (xy 325.007395 9.798443) (xy 325.059071 9.866872) (xy 325.11684 9.930242)
			(xy 325.18021 9.988011) (xy 325.248639 10.039687) (xy 325.321545 10.084828) (xy 325.398305 10.12305)
			(xy 325.478264 10.154026) (xy 325.56074 10.177493) (xy 325.64503 10.193249) (xy 325.730413 10.201161)
			(xy 325.816163 10.201161) (xy 325.901546 10.193249) (xy 325.985836 10.177493) (xy 326.068312 10.154026)
			(xy 326.148271 10.12305) (xy 326.225031 10.084828) (xy 326.297937 10.039687) (xy 326.366366 9.988011)
			(xy 326.429736 9.930242) (xy 326.487505 9.866872) (xy 326.539181 9.798443) (xy 326.584322 9.725537)
			(xy 326.622544 9.648777) (xy 326.65352 9.568818) (xy 326.676987 9.486342) (xy 326.692743 9.402052)
			(xy 326.700655 9.316669) (xy 326.70115 9.273794) (xy 326.700655 9.230919) (xy 331.195921 9.230919)
			(xy 331.195921 9.316669) (xy 331.203833 9.402052) (xy 331.219589 9.486342) (xy 331.243056 9.568818)
			(xy 331.274032 9.648777) (xy 331.312254 9.725537) (xy 331.357395 9.798443) (xy 331.409071 9.866872)
			(xy 331.46684 9.930242) (xy 331.53021 9.988011) (xy 331.598639 10.039687) (xy 331.671545 10.084828)
			(xy 331.748305 10.12305) (xy 331.828264 10.154026) (xy 331.91074 10.177493) (xy 331.99503 10.193249)
			(xy 332.080413 10.201161) (xy 332.166163 10.201161) (xy 332.251546 10.193249) (xy 332.335836 10.177493)
			(xy 332.418312 10.154026) (xy 332.498271 10.12305) (xy 332.575031 10.084828) (xy 332.647937 10.039687)
			(xy 332.716366 9.988011) (xy 332.779736 9.930242) (xy 332.837505 9.866872) (xy 332.889181 9.798443)
			(xy 332.934322 9.725537) (xy 332.972544 9.648777) (xy 333.00352 9.568818) (xy 333.026987 9.486342)
			(xy 333.042743 9.402052) (xy 333.050655 9.316669) (xy 333.05115 9.273794) (xy 333.050655 9.230919)
			(xy 335.488267 9.230919) (xy 335.488267 9.316669) (xy 335.496179 9.402052) (xy 335.511935 9.486342)
			(xy 335.535402 9.568818) (xy 335.566378 9.648777) (xy 335.6046 9.725537) (xy 335.649741 9.798443)
			(xy 335.701417 9.866872) (xy 335.759186 9.930242) (xy 335.822556 9.988011) (xy 335.890985 10.039687)
			(xy 335.963891 10.084828) (xy 336.040651 10.12305) (xy 336.12061 10.154026) (xy 336.203086 10.177493)
			(xy 336.287376 10.193249) (xy 336.372759 10.201161) (xy 336.458509 10.201161) (xy 336.543892 10.193249)
			(xy 336.628182 10.177493) (xy 336.710658 10.154026) (xy 336.790617 10.12305) (xy 336.867377 10.084828)
			(xy 336.940283 10.039687) (xy 337.008712 9.988011) (xy 337.072082 9.930242) (xy 337.129851 9.866872)
			(xy 337.181527 9.798443) (xy 337.226668 9.725537) (xy 337.26489 9.648777) (xy 337.295866 9.568818)
			(xy 337.319333 9.486342) (xy 337.335089 9.402052) (xy 337.343001 9.316669) (xy 337.343496 9.273794)
			(xy 337.343001 9.230919) (xy 341.838267 9.230919) (xy 341.838267 9.316669) (xy 341.846179 9.402052)
			(xy 341.861935 9.486342) (xy 341.885402 9.568818) (xy 341.916378 9.648777) (xy 341.9546 9.725537)
			(xy 341.999741 9.798443) (xy 342.051417 9.866872) (xy 342.109186 9.930242) (xy 342.172556 9.988011)
			(xy 342.240985 10.039687) (xy 342.313891 10.084828) (xy 342.390651 10.12305) (xy 342.47061 10.154026)
			(xy 342.553086 10.177493) (xy 342.637376 10.193249) (xy 342.722759 10.201161) (xy 342.808509 10.201161)
			(xy 342.893892 10.193249) (xy 342.978182 10.177493) (xy 343.060658 10.154026) (xy 343.140617 10.12305)
			(xy 343.217377 10.084828) (xy 343.290283 10.039687) (xy 343.358712 9.988011) (xy 343.422082 9.930242)
			(xy 343.479851 9.866872) (xy 343.531527 9.798443) (xy 343.576668 9.725537) (xy 343.61489 9.648777)
			(xy 343.645866 9.568818) (xy 343.669333 9.486342) (xy 343.685089 9.402052) (xy 343.693001 9.316669)
			(xy 343.693496 9.273794) (xy 343.693001 9.230919) (xy 373.705107 9.230919) (xy 373.705107 9.316669)
			(xy 373.713019 9.402052) (xy 373.728775 9.486342) (xy 373.752242 9.568818) (xy 373.783218 9.648777)
			(xy 373.82144 9.725537) (xy 373.866581 9.798443) (xy 373.918257 9.866872) (xy 373.976026 9.930242)
			(xy 374.039396 9.988011) (xy 374.107825 10.039687) (xy 374.180731 10.084828) (xy 374.257491 10.12305)
			(xy 374.33745 10.154026) (xy 374.419926 10.177493) (xy 374.504216 10.193249) (xy 374.589599 10.201161)
			(xy 374.675349 10.201161) (xy 374.760732 10.193249) (xy 374.845022 10.177493) (xy 374.927498 10.154026)
			(xy 375.007457 10.12305) (xy 375.084217 10.084828) (xy 375.157123 10.039687) (xy 375.225552 9.988011)
			(xy 375.288922 9.930242) (xy 375.346691 9.866872) (xy 375.398367 9.798443) (xy 375.443508 9.725537)
			(xy 375.48173 9.648777) (xy 375.512706 9.568818) (xy 375.536173 9.486342) (xy 375.551929 9.402052)
			(xy 375.559841 9.316669) (xy 375.560336 9.273794) (xy 375.559841 9.230919) (xy 380.055107 9.230919)
			(xy 380.055107 9.316669) (xy 380.063019 9.402052) (xy 380.078775 9.486342) (xy 380.102242 9.568818)
			(xy 380.133218 9.648777) (xy 380.17144 9.725537) (xy 380.216581 9.798443) (xy 380.268257 9.866872)
			(xy 380.326026 9.930242) (xy 380.389396 9.988011) (xy 380.457825 10.039687) (xy 380.530731 10.084828)
			(xy 380.607491 10.12305) (xy 380.68745 10.154026) (xy 380.769926 10.177493) (xy 380.854216 10.193249)
			(xy 380.939599 10.201161) (xy 381.025349 10.201161) (xy 381.110732 10.193249) (xy 381.195022 10.177493)
			(xy 381.277498 10.154026) (xy 381.357457 10.12305) (xy 381.434217 10.084828) (xy 381.507123 10.039687)
			(xy 381.575552 9.988011) (xy 381.638922 9.930242) (xy 381.696691 9.866872) (xy 381.748367 9.798443)
			(xy 381.793508 9.725537) (xy 381.83173 9.648777) (xy 381.862706 9.568818) (xy 381.886173 9.486342)
			(xy 381.901929 9.402052) (xy 381.909841 9.316669) (xy 381.910336 9.273794) (xy 381.909841 9.230919)
			(xy 381.901929 9.145536) (xy 381.886173 9.061246) (xy 381.862706 8.97877) (xy 381.83173 8.898811)
			(xy 381.793508 8.822051) (xy 381.748367 8.749145) (xy 381.696691 8.680716) (xy 381.638922 8.617346)
			(xy 381.575552 8.559577) (xy 381.507123 8.507901) (xy 381.434217 8.46276) (xy 381.357457 8.424538)
			(xy 381.277498 8.393562) (xy 381.195022 8.370095) (xy 381.110732 8.354339) (xy 381.025349 8.346427)
			(xy 380.939599 8.346427) (xy 380.854216 8.354339) (xy 380.769926 8.370095) (xy 380.68745 8.393562)
			(xy 380.607491 8.424538) (xy 380.530731 8.46276) (xy 380.457825 8.507901) (xy 380.389396 8.559577)
			(xy 380.326026 8.617346) (xy 380.268257 8.680716) (xy 380.216581 8.749145) (xy 380.17144 8.822051)
			(xy 380.133218 8.898811) (xy 380.102242 8.97877) (xy 380.078775 9.061246) (xy 380.063019 9.145536)
			(xy 380.055107 9.230919) (xy 375.559841 9.230919) (xy 375.551929 9.145536) (xy 375.536173 9.061246)
			(xy 375.512706 8.97877) (xy 375.48173 8.898811) (xy 375.443508 8.822051) (xy 375.398367 8.749145)
			(xy 375.346691 8.680716) (xy 375.288922 8.617346) (xy 375.225552 8.559577) (xy 375.157123 8.507901)
			(xy 375.084217 8.46276) (xy 375.007457 8.424538) (xy 374.927498 8.393562) (xy 374.845022 8.370095)
			(xy 374.760732 8.354339) (xy 374.675349 8.346427) (xy 374.589599 8.346427) (xy 374.504216 8.354339)
			(xy 374.419926 8.370095) (xy 374.33745 8.393562) (xy 374.257491 8.424538) (xy 374.180731 8.46276)
			(xy 374.107825 8.507901) (xy 374.039396 8.559577) (xy 373.976026 8.617346) (xy 373.918257 8.680716)
			(xy 373.866581 8.749145) (xy 373.82144 8.822051) (xy 373.783218 8.898811) (xy 373.752242 8.97877)
			(xy 373.728775 9.061246) (xy 373.713019 9.145536) (xy 373.705107 9.230919) (xy 343.693001 9.230919)
			(xy 343.685089 9.145536) (xy 343.669333 9.061246) (xy 343.645866 8.97877) (xy 343.61489 8.898811)
			(xy 343.576668 8.822051) (xy 343.531527 8.749145) (xy 343.479851 8.680716) (xy 343.422082 8.617346)
			(xy 343.358712 8.559577) (xy 343.290283 8.507901) (xy 343.217377 8.46276) (xy 343.140617 8.424538)
			(xy 343.060658 8.393562) (xy 342.978182 8.370095) (xy 342.893892 8.354339) (xy 342.808509 8.346427)
			(xy 342.722759 8.346427) (xy 342.637376 8.354339) (xy 342.553086 8.370095) (xy 342.47061 8.393562)
			(xy 342.390651 8.424538) (xy 342.313891 8.46276) (xy 342.240985 8.507901) (xy 342.172556 8.559577)
			(xy 342.109186 8.617346) (xy 342.051417 8.680716) (xy 341.999741 8.749145) (xy 341.9546 8.822051)
			(xy 341.916378 8.898811) (xy 341.885402 8.97877) (xy 341.861935 9.061246) (xy 341.846179 9.145536)
			(xy 341.838267 9.230919) (xy 337.343001 9.230919) (xy 337.335089 9.145536) (xy 337.319333 9.061246)
			(xy 337.295866 8.97877) (xy 337.26489 8.898811) (xy 337.226668 8.822051) (xy 337.181527 8.749145)
			(xy 337.129851 8.680716) (xy 337.072082 8.617346) (xy 337.008712 8.559577) (xy 336.940283 8.507901)
			(xy 336.867377 8.46276) (xy 336.790617 8.424538) (xy 336.710658 8.393562) (xy 336.628182 8.370095)
			(xy 336.543892 8.354339) (xy 336.458509 8.346427) (xy 336.372759 8.346427) (xy 336.287376 8.354339)
			(xy 336.203086 8.370095) (xy 336.12061 8.393562) (xy 336.040651 8.424538) (xy 335.963891 8.46276)
			(xy 335.890985 8.507901) (xy 335.822556 8.559577) (xy 335.759186 8.617346) (xy 335.701417 8.680716)
			(xy 335.649741 8.749145) (xy 335.6046 8.822051) (xy 335.566378 8.898811) (xy 335.535402 8.97877)
			(xy 335.511935 9.061246) (xy 335.496179 9.145536) (xy 335.488267 9.230919) (xy 333.050655 9.230919)
			(xy 333.042743 9.145536) (xy 333.026987 9.061246) (xy 333.00352 8.97877) (xy 332.972544 8.898811)
			(xy 332.934322 8.822051) (xy 332.889181 8.749145) (xy 332.837505 8.680716) (xy 332.779736 8.617346)
			(xy 332.716366 8.559577) (xy 332.647937 8.507901) (xy 332.575031 8.46276) (xy 332.498271 8.424538)
			(xy 332.418312 8.393562) (xy 332.335836 8.370095) (xy 332.251546 8.354339) (xy 332.166163 8.346427)
			(xy 332.080413 8.346427) (xy 331.99503 8.354339) (xy 331.91074 8.370095) (xy 331.828264 8.393562)
			(xy 331.748305 8.424538) (xy 331.671545 8.46276) (xy 331.598639 8.507901) (xy 331.53021 8.559577)
			(xy 331.46684 8.617346) (xy 331.409071 8.680716) (xy 331.357395 8.749145) (xy 331.312254 8.822051)
			(xy 331.274032 8.898811) (xy 331.243056 8.97877) (xy 331.219589 9.061246) (xy 331.203833 9.145536)
			(xy 331.195921 9.230919) (xy 326.700655 9.230919) (xy 326.692743 9.145536) (xy 326.676987 9.061246)
			(xy 326.65352 8.97877) (xy 326.622544 8.898811) (xy 326.584322 8.822051) (xy 326.539181 8.749145)
			(xy 326.487505 8.680716) (xy 326.429736 8.617346) (xy 326.366366 8.559577) (xy 326.297937 8.507901)
			(xy 326.225031 8.46276) (xy 326.148271 8.424538) (xy 326.068312 8.393562) (xy 325.985836 8.370095)
			(xy 325.901546 8.354339) (xy 325.816163 8.346427) (xy 325.730413 8.346427) (xy 325.64503 8.354339)
			(xy 325.56074 8.370095) (xy 325.478264 8.393562) (xy 325.398305 8.424538) (xy 325.321545 8.46276)
			(xy 325.248639 8.507901) (xy 325.18021 8.559577) (xy 325.11684 8.617346) (xy 325.059071 8.680716)
			(xy 325.007395 8.749145) (xy 324.962254 8.822051) (xy 324.924032 8.898811) (xy 324.893056 8.97877)
			(xy 324.869589 9.061246) (xy 324.853833 9.145536) (xy 324.845921 9.230919) (xy 265.125975 9.230919)
			(xy 265.118063 9.145536) (xy 265.102307 9.061246) (xy 265.07884 8.97877) (xy 265.047864 8.898811)
			(xy 265.009642 8.822051) (xy 264.964501 8.749145) (xy 264.912825 8.680716) (xy 264.855056 8.617346)
			(xy 264.791686 8.559577) (xy 264.723257 8.507901) (xy 264.650351 8.46276) (xy 264.573591 8.424538)
			(xy 264.493632 8.393562) (xy 264.411156 8.370095) (xy 264.326866 8.354339) (xy 264.241483 8.346427)
			(xy 264.155733 8.346427) (xy 264.07035 8.354339) (xy 263.98606 8.370095) (xy 263.903584 8.393562)
			(xy 263.823625 8.424538) (xy 263.746865 8.46276) (xy 263.673959 8.507901) (xy 263.60553 8.559577)
			(xy 263.54216 8.617346) (xy 263.484391 8.680716) (xy 263.432715 8.749145) (xy 263.387574 8.822051)
			(xy 263.349352 8.898811) (xy 263.318376 8.97877) (xy 263.294909 9.061246) (xy 263.279153 9.145536)
			(xy 263.271241 9.230919) (xy 258.775975 9.230919) (xy 258.768063 9.145536) (xy 258.752307 9.061246)
			(xy 258.72884 8.97877) (xy 258.697864 8.898811) (xy 258.659642 8.822051) (xy 258.614501 8.749145)
			(xy 258.562825 8.680716) (xy 258.505056 8.617346) (xy 258.441686 8.559577) (xy 258.373257 8.507901)
			(xy 258.300351 8.46276) (xy 258.223591 8.424538) (xy 258.143632 8.393562) (xy 258.061156 8.370095)
			(xy 257.976866 8.354339) (xy 257.891483 8.346427) (xy 257.805733 8.346427) (xy 257.72035 8.354339)
			(xy 257.63606 8.370095) (xy 257.553584 8.393562) (xy 257.473625 8.424538) (xy 257.396865 8.46276)
			(xy 257.323959 8.507901) (xy 257.25553 8.559577) (xy 257.19216 8.617346) (xy 257.134391 8.680716)
			(xy 257.082715 8.749145) (xy 257.037574 8.822051) (xy 256.999352 8.898811) (xy 256.968376 8.97877)
			(xy 256.944909 9.061246) (xy 256.929153 9.145536) (xy 256.921241 9.230919) (xy 6.020338 9.230919)
			(xy 6.103792 9.182737) (xy 6.211443 9.111405) (xy 6.314498 9.033581) (xy 6.412568 8.94956) (xy 6.505279 8.859661)
			(xy 6.592279 8.764226) (xy 6.67324 8.663616) (xy 6.747854 8.558213) (xy 6.815837 8.448416) (xy 6.876932 8.334642)
			(xy 6.930907 8.217323) (xy 6.977558 8.096904) (xy 7.016707 7.973841) (xy 7.048206 7.848602) (xy 7.071935 7.721661)
			(xy 7.087805 7.593501) (xy 7.095755 7.464606) (xy 7.096252 7.400036) (xy 7.095755 7.335466) (xy 7.087805 7.206571)
			(xy 7.071935 7.078411) (xy 7.048206 6.95147) (xy 7.016707 6.826231) (xy 6.977558 6.703168) (xy 6.97173 6.688125)
			(xy 178.335673 6.688125) (xy 178.335673 6.773875) (xy 178.343585 6.859258) (xy 178.359341 6.943548)
			(xy 178.382808 7.026024) (xy 178.413784 7.105983) (xy 178.452006 7.182743) (xy 178.497147 7.255649)
			(xy 178.548823 7.324078) (xy 178.606592 7.387448) (xy 178.669962 7.445217) (xy 178.738391 7.496893)
			(xy 178.811297 7.542034) (xy 178.888057 7.580256) (xy 178.968016 7.611232) (xy 179.050492 7.634699)
			(xy 179.134782 7.650455) (xy 179.220165 7.658367) (xy 179.305915 7.658367) (xy 179.391298 7.650455)
			(xy 179.475588 7.634699) (xy 179.558064 7.611232) (xy 179.638023 7.580256) (xy 179.714783 7.542034)
			(xy 179.787689 7.496893) (xy 179.856118 7.445217) (xy 179.919488 7.387448) (xy 179.977257 7.324078)
			(xy 180.028933 7.255649) (xy 180.074074 7.182743) (xy 180.112296 7.105983) (xy 180.143272 7.026024)
			(xy 180.166739 6.943548) (xy 180.182495 6.859258) (xy 180.190407 6.773875) (xy 180.190902 6.731)
			(xy 180.190407 6.688125) (xy 184.685673 6.688125) (xy 184.685673 6.773875) (xy 184.693585 6.859258)
			(xy 184.709341 6.943548) (xy 184.732808 7.026024) (xy 184.763784 7.105983) (xy 184.802006 7.182743)
			(xy 184.847147 7.255649) (xy 184.898823 7.324078) (xy 184.956592 7.387448) (xy 185.019962 7.445217)
			(xy 185.088391 7.496893) (xy 185.161297 7.542034) (xy 185.238057 7.580256) (xy 185.318016 7.611232)
			(xy 185.400492 7.634699) (xy 185.484782 7.650455) (xy 185.570165 7.658367) (xy 185.655915 7.658367)
			(xy 185.741298 7.650455) (xy 185.825588 7.634699) (xy 185.908064 7.611232) (xy 185.988023 7.580256)
			(xy 186.064783 7.542034) (xy 186.137689 7.496893) (xy 186.206118 7.445217) (xy 186.269488 7.387448)
			(xy 186.327257 7.324078) (xy 186.378933 7.255649) (xy 186.424074 7.182743) (xy 186.462296 7.105983)
			(xy 186.493272 7.026024) (xy 186.516739 6.943548) (xy 186.532495 6.859258) (xy 186.540407 6.773875)
			(xy 186.540902 6.731) (xy 186.540407 6.688125) (xy 246.260353 6.688125) (xy 246.260353 6.773875)
			(xy 246.268265 6.859258) (xy 246.284021 6.943548) (xy 246.307488 7.026024) (xy 246.338464 7.105983)
			(xy 246.376686 7.182743) (xy 246.421827 7.255649) (xy 246.473503 7.324078) (xy 246.531272 7.387448)
			(xy 246.594642 7.445217) (xy 246.663071 7.496893) (xy 246.735977 7.542034) (xy 246.812737 7.580256)
			(xy 246.892696 7.611232) (xy 246.975172 7.634699) (xy 247.059462 7.650455) (xy 247.144845 7.658367)
			(xy 247.230595 7.658367) (xy 247.315978 7.650455) (xy 247.400268 7.634699) (xy 247.482744 7.611232)
			(xy 247.562703 7.580256) (xy 247.639463 7.542034) (xy 247.712369 7.496893) (xy 247.780798 7.445217)
			(xy 247.844168 7.387448) (xy 247.901937 7.324078) (xy 247.953613 7.255649) (xy 247.998754 7.182743)
			(xy 248.036976 7.105983) (xy 248.067952 7.026024) (xy 248.091419 6.943548) (xy 248.107175 6.859258)
			(xy 248.115087 6.773875) (xy 248.115582 6.731) (xy 248.115087 6.688125) (xy 252.610353 6.688125)
			(xy 252.610353 6.773875) (xy 252.618265 6.859258) (xy 252.634021 6.943548) (xy 252.657488 7.026024)
			(xy 252.688464 7.105983) (xy 252.726686 7.182743) (xy 252.771827 7.255649) (xy 252.823503 7.324078)
			(xy 252.881272 7.387448) (xy 252.944642 7.445217) (xy 253.013071 7.496893) (xy 253.085977 7.542034)
			(xy 253.162737 7.580256) (xy 253.242696 7.611232) (xy 253.325172 7.634699) (xy 253.409462 7.650455)
			(xy 253.494845 7.658367) (xy 253.580595 7.658367) (xy 253.665978 7.650455) (xy 253.750268 7.634699)
			(xy 253.832744 7.611232) (xy 253.912703 7.580256) (xy 253.989463 7.542034) (xy 254.062369 7.496893)
			(xy 254.130798 7.445217) (xy 254.194168 7.387448) (xy 254.251937 7.324078) (xy 254.303613 7.255649)
			(xy 254.348754 7.182743) (xy 254.386976 7.105983) (xy 254.417952 7.026024) (xy 254.441419 6.943548)
			(xy 254.457175 6.859258) (xy 254.465087 6.773875) (xy 254.465582 6.731) (xy 254.465119 6.690919)
			(xy 256.921241 6.690919) (xy 256.921241 6.776669) (xy 256.929153 6.862052) (xy 256.944909 6.946342)
			(xy 256.968376 7.028818) (xy 256.999352 7.108777) (xy 257.037574 7.185537) (xy 257.082715 7.258443)
			(xy 257.134391 7.326872) (xy 257.19216 7.390242) (xy 257.25553 7.448011) (xy 257.323959 7.499687)
			(xy 257.396865 7.544828) (xy 257.473625 7.58305) (xy 257.553584 7.614026) (xy 257.63606 7.637493)
			(xy 257.72035 7.653249) (xy 257.805733 7.661161) (xy 257.891483 7.661161) (xy 257.976866 7.653249)
			(xy 258.061156 7.637493) (xy 258.143632 7.614026) (xy 258.223591 7.58305) (xy 258.245794 7.571994)
			(xy 261.85622 7.571994) (xy 261.85622 8.435594) (xy 261.856706 8.462863) (xy 261.864468 8.516847)
			(xy 261.879833 8.569177) (xy 261.90249 8.618787) (xy 261.931976 8.664668) (xy 261.967691 8.705885)
			(xy 262.008908 8.7416) (xy 262.054789 8.771086) (xy 262.104399 8.793743) (xy 262.156729 8.809108)
			(xy 262.210713 8.81687) (xy 262.265251 8.81687) (xy 262.319235 8.809108) (xy 262.371565 8.793743)
			(xy 262.421175 8.771086) (xy 262.467056 8.7416) (xy 262.508273 8.705885) (xy 262.543988 8.664668)
			(xy 262.573474 8.618787) (xy 262.596131 8.569177) (xy 262.611496 8.516847) (xy 262.619258 8.462863)
			(xy 262.619744 8.435594) (xy 262.619744 7.571994) (xy 262.619258 7.544725) (xy 262.611496 7.490741)
			(xy 262.596131 7.438411) (xy 262.573474 7.388801) (xy 262.543988 7.34292) (xy 262.508273 7.301703)
			(xy 262.467056 7.265988) (xy 262.421175 7.236502) (xy 262.371565 7.213845) (xy 262.319235 7.19848)
			(xy 262.265251 7.190718) (xy 262.210713 7.190718) (xy 262.156729 7.19848) (xy 262.104399 7.213845)
			(xy 262.054789 7.236502) (xy 262.008908 7.265988) (xy 261.967691 7.301703) (xy 261.931976 7.34292)
			(xy 261.90249 7.388801) (xy 261.879833 7.438411) (xy 261.864468 7.490741) (xy 261.856706 7.544725)
			(xy 261.85622 7.571994) (xy 258.245794 7.571994) (xy 258.300351 7.544828) (xy 258.373257 7.499687)
			(xy 258.441686 7.448011) (xy 258.505056 7.390242) (xy 258.562825 7.326872) (xy 258.614501 7.258443)
			(xy 258.659642 7.185537) (xy 258.697864 7.108777) (xy 258.72884 7.028818) (xy 258.752307 6.946342)
			(xy 258.768063 6.862052) (xy 258.775975 6.776669) (xy 258.77647 6.733794) (xy 258.775975 6.690919)
			(xy 263.271241 6.690919) (xy 263.271241 6.776669) (xy 263.279153 6.862052) (xy 263.294909 6.946342)
			(xy 263.318376 7.028818) (xy 263.349352 7.108777) (xy 263.387574 7.185537) (xy 263.432715 7.258443)
			(xy 263.484391 7.326872) (xy 263.54216 7.390242) (xy 263.60553 7.448011) (xy 263.673959 7.499687)
			(xy 263.746865 7.544828) (xy 263.823625 7.58305) (xy 263.903584 7.614026) (xy 263.98606 7.637493)
			(xy 264.07035 7.653249) (xy 264.155733 7.661161) (xy 264.241483 7.661161) (xy 264.326866 7.653249)
			(xy 264.411156 7.637493) (xy 264.493632 7.614026) (xy 264.573591 7.58305) (xy 264.650351 7.544828)
			(xy 264.723257 7.499687) (xy 264.791686 7.448011) (xy 264.855056 7.390242) (xy 264.912825 7.326872)
			(xy 264.964501 7.258443) (xy 265.009642 7.185537) (xy 265.047864 7.108777) (xy 265.07884 7.028818)
			(xy 265.102307 6.946342) (xy 265.118063 6.862052) (xy 265.125975 6.776669) (xy 265.12647 6.733794)
			(xy 265.125975 6.690919) (xy 324.845921 6.690919) (xy 324.845921 6.776669) (xy 324.853833 6.862052)
			(xy 324.869589 6.946342) (xy 324.893056 7.028818) (xy 324.924032 7.108777) (xy 324.962254 7.185537)
			(xy 325.007395 7.258443) (xy 325.059071 7.326872) (xy 325.11684 7.390242) (xy 325.18021 7.448011)
			(xy 325.248639 7.499687) (xy 325.321545 7.544828) (xy 325.398305 7.58305) (xy 325.478264 7.614026)
			(xy 325.56074 7.637493) (xy 325.64503 7.653249) (xy 325.730413 7.661161) (xy 325.816163 7.661161)
			(xy 325.901546 7.653249) (xy 325.985836 7.637493) (xy 326.068312 7.614026) (xy 326.148271 7.58305)
			(xy 326.170474 7.571994) (xy 327.352152 7.571994) (xy 327.352152 8.435594) (xy 327.352638 8.462863)
			(xy 327.3604 8.516847) (xy 327.375765 8.569177) (xy 327.398422 8.618787) (xy 327.427908 8.664668)
			(xy 327.463623 8.705885) (xy 327.50484 8.7416) (xy 327.550721 8.771086) (xy 327.600331 8.793743)
			(xy 327.652661 8.809108) (xy 327.706645 8.81687) (xy 327.761183 8.81687) (xy 327.815167 8.809108)
			(xy 327.867497 8.793743) (xy 327.917107 8.771086) (xy 327.962988 8.7416) (xy 328.004205 8.705885)
			(xy 328.03992 8.664668) (xy 328.069406 8.618787) (xy 328.092063 8.569177) (xy 328.107428 8.516847)
			(xy 328.11519 8.462863) (xy 328.115676 8.435594) (xy 328.115676 7.571994) (xy 328.11519 7.544725)
			(xy 328.107428 7.490741) (xy 328.092063 7.438411) (xy 328.069406 7.388801) (xy 328.03992 7.34292)
			(xy 328.004205 7.301703) (xy 327.962988 7.265988) (xy 327.917107 7.236502) (xy 327.867497 7.213845)
			(xy 327.815167 7.19848) (xy 327.761183 7.190718) (xy 327.706645 7.190718) (xy 327.652661 7.19848)
			(xy 327.600331 7.213845) (xy 327.550721 7.236502) (xy 327.50484 7.265988) (xy 327.463623 7.301703)
			(xy 327.427908 7.34292) (xy 327.398422 7.388801) (xy 327.375765 7.438411) (xy 327.3604 7.490741)
			(xy 327.352638 7.544725) (xy 327.352152 7.571994) (xy 326.170474 7.571994) (xy 326.225031 7.544828)
			(xy 326.297937 7.499687) (xy 326.366366 7.448011) (xy 326.429736 7.390242) (xy 326.487505 7.326872)
			(xy 326.539181 7.258443) (xy 326.584322 7.185537) (xy 326.622544 7.108777) (xy 326.65352 7.028818)
			(xy 326.676987 6.946342) (xy 326.692743 6.862052) (xy 326.700655 6.776669) (xy 326.70115 6.733794)
			(xy 326.700655 6.690919) (xy 331.195921 6.690919) (xy 331.195921 6.776669) (xy 331.203833 6.862052)
			(xy 331.219589 6.946342) (xy 331.243056 7.028818) (xy 331.274032 7.108777) (xy 331.312254 7.185537)
			(xy 331.357395 7.258443) (xy 331.409071 7.326872) (xy 331.46684 7.390242) (xy 331.53021 7.448011)
			(xy 331.598639 7.499687) (xy 331.671545 7.544828) (xy 331.748305 7.58305) (xy 331.828264 7.614026)
			(xy 331.91074 7.637493) (xy 331.99503 7.653249) (xy 332.080413 7.661161) (xy 332.166163 7.661161)
			(xy 332.251546 7.653249) (xy 332.335836 7.637493) (xy 332.418312 7.614026) (xy 332.498271 7.58305)
			(xy 332.575031 7.544828) (xy 332.647937 7.499687) (xy 332.716366 7.448011) (xy 332.779736 7.390242)
			(xy 332.837505 7.326872) (xy 332.889181 7.258443) (xy 332.934322 7.185537) (xy 332.972544 7.108777)
			(xy 333.00352 7.028818) (xy 333.026987 6.946342) (xy 333.042743 6.862052) (xy 333.050655 6.776669)
			(xy 333.05115 6.733794) (xy 333.050655 6.690919) (xy 335.488267 6.690919) (xy 335.488267 6.776669)
			(xy 335.496179 6.862052) (xy 335.511935 6.946342) (xy 335.535402 7.028818) (xy 335.566378 7.108777)
			(xy 335.6046 7.185537) (xy 335.649741 7.258443) (xy 335.701417 7.326872) (xy 335.759186 7.390242)
			(xy 335.822556 7.448011) (xy 335.890985 7.499687) (xy 335.963891 7.544828) (xy 336.040651 7.58305)
			(xy 336.12061 7.614026) (xy 336.203086 7.637493) (xy 336.287376 7.653249) (xy 336.372759 7.661161)
			(xy 336.458509 7.661161) (xy 336.543892 7.653249) (xy 336.628182 7.637493) (xy 336.710658 7.614026)
			(xy 336.790617 7.58305) (xy 336.81282 7.571994) (xy 340.4235 7.571994) (xy 340.4235 8.435594) (xy 340.423986 8.462845)
			(xy 340.431742 8.516793) (xy 340.447097 8.569088) (xy 340.469739 8.618665) (xy 340.499205 8.664515)
			(xy 340.534896 8.705706) (xy 340.576087 8.741397) (xy 340.621937 8.770863) (xy 340.671514 8.793505)
			(xy 340.723809 8.80886) (xy 340.777757 8.816616) (xy 340.832259 8.816616) (xy 340.886207 8.80886)
			(xy 340.938502 8.793505) (xy 340.988079 8.770863) (xy 341.033929 8.741397) (xy 341.07512 8.705706)
			(xy 341.110811 8.664515) (xy 341.140277 8.618665) (xy 341.162919 8.569088) (xy 341.178274 8.516793)
			(xy 341.18603 8.462845) (xy 341.186516 8.435594) (xy 341.186516 7.571994) (xy 341.18603 7.544743)
			(xy 341.178274 7.490795) (xy 341.162919 7.4385) (xy 341.140277 7.388923) (xy 341.110811 7.343073)
			(xy 341.07512 7.301882) (xy 341.033929 7.266191) (xy 340.988079 7.236725) (xy 340.938502 7.214083)
			(xy 340.886207 7.198728) (xy 340.832259 7.190972) (xy 340.777757 7.190972) (xy 340.723809 7.198728)
			(xy 340.671514 7.214083) (xy 340.621937 7.236725) (xy 340.576087 7.266191) (xy 340.534896 7.301882)
			(xy 340.499205 7.343073) (xy 340.469739 7.388923) (xy 340.447097 7.4385) (xy 340.431742 7.490795)
			(xy 340.423986 7.544743) (xy 340.4235 7.571994) (xy 336.81282 7.571994) (xy 336.867377 7.544828)
			(xy 336.940283 7.499687) (xy 337.008712 7.448011) (xy 337.072082 7.390242) (xy 337.129851 7.326872)
			(xy 337.181527 7.258443) (xy 337.226668 7.185537) (xy 337.26489 7.108777) (xy 337.295866 7.028818)
			(xy 337.319333 6.946342) (xy 337.335089 6.862052) (xy 337.343001 6.776669) (xy 337.343496 6.733794)
			(xy 337.343001 6.690919) (xy 341.838267 6.690919) (xy 341.838267 6.776669) (xy 341.846179 6.862052)
			(xy 341.861935 6.946342) (xy 341.885402 7.028818) (xy 341.916378 7.108777) (xy 341.9546 7.185537)
			(xy 341.999741 7.258443) (xy 342.051417 7.326872) (xy 342.109186 7.390242) (xy 342.172556 7.448011)
			(xy 342.240985 7.499687) (xy 342.313891 7.544828) (xy 342.390651 7.58305) (xy 342.47061 7.614026)
			(xy 342.553086 7.637493) (xy 342.637376 7.653249) (xy 342.722759 7.661161) (xy 342.808509 7.661161)
			(xy 342.893892 7.653249) (xy 342.978182 7.637493) (xy 343.060658 7.614026) (xy 343.140617 7.58305)
			(xy 343.217377 7.544828) (xy 343.290283 7.499687) (xy 343.358712 7.448011) (xy 343.422082 7.390242)
			(xy 343.479851 7.326872) (xy 343.531527 7.258443) (xy 343.576668 7.185537) (xy 343.61489 7.108777)
			(xy 343.645866 7.028818) (xy 343.669333 6.946342) (xy 343.685089 6.862052) (xy 343.693001 6.776669)
			(xy 343.693496 6.733794) (xy 343.693001 6.690919) (xy 373.705107 6.690919) (xy 373.705107 6.776669)
			(xy 373.713019 6.862052) (xy 373.728775 6.946342) (xy 373.752242 7.028818) (xy 373.783218 7.108777)
			(xy 373.82144 7.185537) (xy 373.866581 7.258443) (xy 373.918257 7.326872) (xy 373.976026 7.390242)
			(xy 374.039396 7.448011) (xy 374.107825 7.499687) (xy 374.180731 7.544828) (xy 374.257491 7.58305)
			(xy 374.33745 7.614026) (xy 374.419926 7.637493) (xy 374.504216 7.653249) (xy 374.589599 7.661161)
			(xy 374.675349 7.661161) (xy 374.760732 7.653249) (xy 374.845022 7.637493) (xy 374.927498 7.614026)
			(xy 375.007457 7.58305) (xy 375.02966 7.571994) (xy 376.211592 7.571994) (xy 376.211592 8.435594)
			(xy 376.212078 8.462845) (xy 376.219834 8.516793) (xy 376.235189 8.569088) (xy 376.257831 8.618665)
			(xy 376.287297 8.664515) (xy 376.322988 8.705706) (xy 376.364179 8.741397) (xy 376.410029 8.770863)
			(xy 376.459606 8.793505) (xy 376.511901 8.80886) (xy 376.565849 8.816616) (xy 376.620351 8.816616)
			(xy 376.674299 8.80886) (xy 376.726594 8.793505) (xy 376.776171 8.770863) (xy 376.822021 8.741397)
			(xy 376.863212 8.705706) (xy 376.898903 8.664515) (xy 376.928369 8.618665) (xy 376.951011 8.569088)
			(xy 376.966366 8.516793) (xy 376.974122 8.462845) (xy 376.974608 8.435594) (xy 376.974608 7.571994)
			(xy 376.974122 7.544743) (xy 376.966366 7.490795) (xy 376.951011 7.4385) (xy 376.928369 7.388923)
			(xy 376.898903 7.343073) (xy 376.863212 7.301882) (xy 376.822021 7.266191) (xy 376.776171 7.236725)
			(xy 376.726594 7.214083) (xy 376.674299 7.198728) (xy 376.620351 7.190972) (xy 376.565849 7.190972)
			(xy 376.511901 7.198728) (xy 376.459606 7.214083) (xy 376.410029 7.236725) (xy 376.364179 7.266191)
			(xy 376.322988 7.301882) (xy 376.287297 7.343073) (xy 376.257831 7.388923) (xy 376.235189 7.4385)
			(xy 376.219834 7.490795) (xy 376.212078 7.544743) (xy 376.211592 7.571994) (xy 375.02966 7.571994)
			(xy 375.084217 7.544828) (xy 375.157123 7.499687) (xy 375.225552 7.448011) (xy 375.288922 7.390242)
			(xy 375.346691 7.326872) (xy 375.398367 7.258443) (xy 375.443508 7.185537) (xy 375.48173 7.108777)
			(xy 375.512706 7.028818) (xy 375.536173 6.946342) (xy 375.551929 6.862052) (xy 375.559841 6.776669)
			(xy 375.560336 6.733794) (xy 375.559841 6.690919) (xy 380.055107 6.690919) (xy 380.055107 6.776669)
			(xy 380.063019 6.862052) (xy 380.078775 6.946342) (xy 380.102242 7.028818) (xy 380.133218 7.108777)
			(xy 380.17144 7.185537) (xy 380.216581 7.258443) (xy 380.268257 7.326872) (xy 380.326026 7.390242)
			(xy 380.389396 7.448011) (xy 380.457825 7.499687) (xy 380.530731 7.544828) (xy 380.607491 7.58305)
			(xy 380.68745 7.614026) (xy 380.769926 7.637493) (xy 380.854216 7.653249) (xy 380.939599 7.661161)
			(xy 381.025349 7.661161) (xy 381.110732 7.653249) (xy 381.195022 7.637493) (xy 381.277498 7.614026)
			(xy 381.357457 7.58305) (xy 381.434217 7.544828) (xy 381.507123 7.499687) (xy 381.575552 7.448011)
			(xy 381.638922 7.390242) (xy 381.688857 7.335466) (xy 464.704165 7.335466) (xy 464.704165 7.464606)
			(xy 464.712115 7.593501) (xy 464.727985 7.721661) (xy 464.751714 7.848602) (xy 464.783213 7.973841)
			(xy 464.822362 8.096904) (xy 464.869013 8.217323) (xy 464.922988 8.334642) (xy 464.984083 8.448416)
			(xy 465.052066 8.558213) (xy 465.12668 8.663616) (xy 465.207641 8.764226) (xy 465.294641 8.859661)
			(xy 465.387352 8.94956) (xy 465.485422 9.033581) (xy 465.588477 9.111405) (xy 465.696128 9.182737)
			(xy 465.807967 9.247307) (xy 465.923568 9.304869) (xy 466.042493 9.355206) (xy 466.164292 9.398126)
			(xy 466.288502 9.433467) (xy 466.414651 9.461094) (xy 466.542263 9.480903) (xy 466.670852 9.492819)
			(xy 466.79993 9.496796) (xy 466.929008 9.492819) (xy 467.057597 9.480903) (xy 467.185209 9.461094)
			(xy 467.311358 9.433467) (xy 467.435568 9.398126) (xy 467.557367 9.355206) (xy 467.676292 9.304869)
			(xy 467.791893 9.247307) (xy 467.903732 9.182737) (xy 468.011383 9.111405) (xy 468.114438 9.033581)
			(xy 468.212508 8.94956) (xy 468.305219 8.859661) (xy 468.392219 8.764226) (xy 468.47318 8.663616)
			(xy 468.547794 8.558213) (xy 468.615777 8.448416) (xy 468.676872 8.334642) (xy 468.730847 8.217323)
			(xy 468.777498 8.096904) (xy 468.816647 7.973841) (xy 468.848146 7.848602) (xy 468.871875 7.721661)
			(xy 468.887745 7.593501) (xy 468.895695 7.464606) (xy 468.896192 7.400036) (xy 468.895695 7.335466)
			(xy 468.887745 7.206571) (xy 468.871875 7.078411) (xy 468.848146 6.95147) (xy 468.816647 6.826231)
			(xy 468.777498 6.703168) (xy 468.730847 6.582749) (xy 468.676872 6.46543) (xy 468.615777 6.351656)
			(xy 468.547794 6.241859) (xy 468.47318 6.136456) (xy 468.392219 6.035846) (xy 468.305219 5.940411)
			(xy 468.212508 5.850512) (xy 468.114438 5.766491) (xy 468.011383 5.688667) (xy 467.903732 5.617335)
			(xy 467.791893 5.552765) (xy 467.676292 5.495203) (xy 467.557367 5.444866) (xy 467.435568 5.401946)
			(xy 467.311358 5.366605) (xy 467.185209 5.338978) (xy 467.057597 5.319169) (xy 466.929008 5.307253)
			(xy 466.79993 5.303277) (xy 466.670852 5.307253) (xy 466.542263 5.319169) (xy 466.414651 5.338978)
			(xy 466.288502 5.366605) (xy 466.164292 5.401946) (xy 466.042493 5.444866) (xy 465.923568 5.495203)
			(xy 465.807967 5.552765) (xy 465.696128 5.617335) (xy 465.588477 5.688667) (xy 465.485422 5.766491)
			(xy 465.387352 5.850512) (xy 465.294641 5.940411) (xy 465.207641 6.035846) (xy 465.12668 6.136456)
			(xy 465.052066 6.241859) (xy 464.984083 6.351656) (xy 464.922988 6.46543) (xy 464.869013 6.582749)
			(xy 464.822362 6.703168) (xy 464.783213 6.826231) (xy 464.751714 6.95147) (xy 464.727985 7.078411)
			(xy 464.712115 7.206571) (xy 464.704165 7.335466) (xy 381.688857 7.335466) (xy 381.696691 7.326872)
			(xy 381.748367 7.258443) (xy 381.793508 7.185537) (xy 381.83173 7.108777) (xy 381.862706 7.028818)
			(xy 381.886173 6.946342) (xy 381.901929 6.862052) (xy 381.909841 6.776669) (xy 381.910336 6.733794)
			(xy 381.909841 6.690919) (xy 381.901929 6.605536) (xy 381.886173 6.521246) (xy 381.862706 6.43877)
			(xy 381.83173 6.358811) (xy 381.793508 6.282051) (xy 381.748367 6.209145) (xy 381.696691 6.140716)
			(xy 381.638922 6.077346) (xy 381.575552 6.019577) (xy 381.507123 5.967901) (xy 381.434217 5.92276)
			(xy 381.357457 5.884538) (xy 381.277498 5.853562) (xy 381.195022 5.830095) (xy 381.110732 5.814339)
			(xy 381.025349 5.806427) (xy 380.939599 5.806427) (xy 380.854216 5.814339) (xy 380.769926 5.830095)
			(xy 380.68745 5.853562) (xy 380.607491 5.884538) (xy 380.530731 5.92276) (xy 380.457825 5.967901)
			(xy 380.389396 6.019577) (xy 380.326026 6.077346) (xy 380.268257 6.140716) (xy 380.216581 6.209145)
			(xy 380.17144 6.282051) (xy 380.133218 6.358811) (xy 380.102242 6.43877) (xy 380.078775 6.521246)
			(xy 380.063019 6.605536) (xy 380.055107 6.690919) (xy 375.559841 6.690919) (xy 375.551929 6.605536)
			(xy 375.536173 6.521246) (xy 375.512706 6.43877) (xy 375.48173 6.358811) (xy 375.443508 6.282051)
			(xy 375.398367 6.209145) (xy 375.346691 6.140716) (xy 375.288922 6.077346) (xy 375.225552 6.019577)
			(xy 375.157123 5.967901) (xy 375.084217 5.92276) (xy 375.007457 5.884538) (xy 374.927498 5.853562)
			(xy 374.845022 5.830095) (xy 374.760732 5.814339) (xy 374.675349 5.806427) (xy 374.589599 5.806427)
			(xy 374.504216 5.814339) (xy 374.419926 5.830095) (xy 374.33745 5.853562) (xy 374.257491 5.884538)
			(xy 374.180731 5.92276) (xy 374.107825 5.967901) (xy 374.039396 6.019577) (xy 373.976026 6.077346)
			(xy 373.918257 6.140716) (xy 373.866581 6.209145) (xy 373.82144 6.282051) (xy 373.783218 6.358811)
			(xy 373.752242 6.43877) (xy 373.728775 6.521246) (xy 373.713019 6.605536) (xy 373.705107 6.690919)
			(xy 343.693001 6.690919) (xy 343.685089 6.605536) (xy 343.669333 6.521246) (xy 343.645866 6.43877)
			(xy 343.61489 6.358811) (xy 343.576668 6.282051) (xy 343.531527 6.209145) (xy 343.479851 6.140716)
			(xy 343.422082 6.077346) (xy 343.358712 6.019577) (xy 343.290283 5.967901) (xy 343.217377 5.92276)
			(xy 343.140617 5.884538) (xy 343.060658 5.853562) (xy 342.978182 5.830095) (xy 342.893892 5.814339)
			(xy 342.808509 5.806427) (xy 342.722759 5.806427) (xy 342.637376 5.814339) (xy 342.553086 5.830095)
			(xy 342.47061 5.853562) (xy 342.390651 5.884538) (xy 342.313891 5.92276) (xy 342.240985 5.967901)
			(xy 342.172556 6.019577) (xy 342.109186 6.077346) (xy 342.051417 6.140716) (xy 341.999741 6.209145)
			(xy 341.9546 6.282051) (xy 341.916378 6.358811) (xy 341.885402 6.43877) (xy 341.861935 6.521246)
			(xy 341.846179 6.605536) (xy 341.838267 6.690919) (xy 337.343001 6.690919) (xy 337.335089 6.605536)
			(xy 337.319333 6.521246) (xy 337.295866 6.43877) (xy 337.26489 6.358811) (xy 337.226668 6.282051)
			(xy 337.181527 6.209145) (xy 337.129851 6.140716) (xy 337.072082 6.077346) (xy 337.008712 6.019577)
			(xy 336.940283 5.967901) (xy 336.867377 5.92276) (xy 336.790617 5.884538) (xy 336.710658 5.853562)
			(xy 336.628182 5.830095) (xy 336.543892 5.814339) (xy 336.458509 5.806427) (xy 336.372759 5.806427)
			(xy 336.287376 5.814339) (xy 336.203086 5.830095) (xy 336.12061 5.853562) (xy 336.040651 5.884538)
			(xy 335.963891 5.92276) (xy 335.890985 5.967901) (xy 335.822556 6.019577) (xy 335.759186 6.077346)
			(xy 335.701417 6.140716) (xy 335.649741 6.209145) (xy 335.6046 6.282051) (xy 335.566378 6.358811)
			(xy 335.535402 6.43877) (xy 335.511935 6.521246) (xy 335.496179 6.605536) (xy 335.488267 6.690919)
			(xy 333.050655 6.690919) (xy 333.042743 6.605536) (xy 333.026987 6.521246) (xy 333.00352 6.43877)
			(xy 332.972544 6.358811) (xy 332.934322 6.282051) (xy 332.889181 6.209145) (xy 332.837505 6.140716)
			(xy 332.779736 6.077346) (xy 332.716366 6.019577) (xy 332.647937 5.967901) (xy 332.575031 5.92276)
			(xy 332.498271 5.884538) (xy 332.418312 5.853562) (xy 332.335836 5.830095) (xy 332.251546 5.814339)
			(xy 332.166163 5.806427) (xy 332.080413 5.806427) (xy 331.99503 5.814339) (xy 331.91074 5.830095)
			(xy 331.828264 5.853562) (xy 331.748305 5.884538) (xy 331.671545 5.92276) (xy 331.598639 5.967901)
			(xy 331.53021 6.019577) (xy 331.46684 6.077346) (xy 331.409071 6.140716) (xy 331.357395 6.209145)
			(xy 331.312254 6.282051) (xy 331.274032 6.358811) (xy 331.243056 6.43877) (xy 331.219589 6.521246)
			(xy 331.203833 6.605536) (xy 331.195921 6.690919) (xy 326.700655 6.690919) (xy 326.692743 6.605536)
			(xy 326.676987 6.521246) (xy 326.65352 6.43877) (xy 326.622544 6.358811) (xy 326.584322 6.282051)
			(xy 326.539181 6.209145) (xy 326.487505 6.140716) (xy 326.429736 6.077346) (xy 326.366366 6.019577)
			(xy 326.297937 5.967901) (xy 326.225031 5.92276) (xy 326.148271 5.884538) (xy 326.068312 5.853562)
			(xy 325.985836 5.830095) (xy 325.901546 5.814339) (xy 325.816163 5.806427) (xy 325.730413 5.806427)
			(xy 325.64503 5.814339) (xy 325.56074 5.830095) (xy 325.478264 5.853562) (xy 325.398305 5.884538)
			(xy 325.321545 5.92276) (xy 325.248639 5.967901) (xy 325.18021 6.019577) (xy 325.11684 6.077346)
			(xy 325.059071 6.140716) (xy 325.007395 6.209145) (xy 324.962254 6.282051) (xy 324.924032 6.358811)
			(xy 324.893056 6.43877) (xy 324.869589 6.521246) (xy 324.853833 6.605536) (xy 324.845921 6.690919)
			(xy 265.125975 6.690919) (xy 265.118063 6.605536) (xy 265.102307 6.521246) (xy 265.07884 6.43877)
			(xy 265.047864 6.358811) (xy 265.009642 6.282051) (xy 264.964501 6.209145) (xy 264.912825 6.140716)
			(xy 264.855056 6.077346) (xy 264.791686 6.019577) (xy 264.723257 5.967901) (xy 264.650351 5.92276)
			(xy 264.573591 5.884538) (xy 264.493632 5.853562) (xy 264.411156 5.830095) (xy 264.326866 5.814339)
			(xy 264.241483 5.806427) (xy 264.155733 5.806427) (xy 264.07035 5.814339) (xy 263.98606 5.830095)
			(xy 263.903584 5.853562) (xy 263.823625 5.884538) (xy 263.746865 5.92276) (xy 263.673959 5.967901)
			(xy 263.60553 6.019577) (xy 263.54216 6.077346) (xy 263.484391 6.140716) (xy 263.432715 6.209145)
			(xy 263.387574 6.282051) (xy 263.349352 6.358811) (xy 263.318376 6.43877) (xy 263.294909 6.521246)
			(xy 263.279153 6.605536) (xy 263.271241 6.690919) (xy 258.775975 6.690919) (xy 258.768063 6.605536)
			(xy 258.752307 6.521246) (xy 258.72884 6.43877) (xy 258.697864 6.358811) (xy 258.659642 6.282051)
			(xy 258.614501 6.209145) (xy 258.562825 6.140716) (xy 258.505056 6.077346) (xy 258.441686 6.019577)
			(xy 258.373257 5.967901) (xy 258.300351 5.92276) (xy 258.223591 5.884538) (xy 258.143632 5.853562)
			(xy 258.061156 5.830095) (xy 257.976866 5.814339) (xy 257.891483 5.806427) (xy 257.805733 5.806427)
			(xy 257.72035 5.814339) (xy 257.63606 5.830095) (xy 257.553584 5.853562) (xy 257.473625 5.884538)
			(xy 257.396865 5.92276) (xy 257.323959 5.967901) (xy 257.25553 6.019577) (xy 257.19216 6.077346)
			(xy 257.134391 6.140716) (xy 257.082715 6.209145) (xy 257.037574 6.282051) (xy 256.999352 6.358811)
			(xy 256.968376 6.43877) (xy 256.944909 6.521246) (xy 256.929153 6.605536) (xy 256.921241 6.690919)
			(xy 254.465119 6.690919) (xy 254.465087 6.688125) (xy 254.457175 6.602742) (xy 254.441419 6.518452)
			(xy 254.417952 6.435976) (xy 254.386976 6.356017) (xy 254.348754 6.279257) (xy 254.303613 6.206351)
			(xy 254.251937 6.137922) (xy 254.194168 6.074552) (xy 254.130798 6.016783) (xy 254.062369 5.965107)
			(xy 253.989463 5.919966) (xy 253.912703 5.881744) (xy 253.832744 5.850768) (xy 253.750268 5.827301)
			(xy 253.665978 5.811545) (xy 253.580595 5.803633) (xy 253.494845 5.803633) (xy 253.409462 5.811545)
			(xy 253.325172 5.827301) (xy 253.242696 5.850768) (xy 253.162737 5.881744) (xy 253.085977 5.919966)
			(xy 253.013071 5.965107) (xy 252.944642 6.016783) (xy 252.881272 6.074552) (xy 252.823503 6.137922)
			(xy 252.771827 6.206351) (xy 252.726686 6.279257) (xy 252.688464 6.356017) (xy 252.657488 6.435976)
			(xy 252.634021 6.518452) (xy 252.618265 6.602742) (xy 252.610353 6.688125) (xy 248.115087 6.688125)
			(xy 248.107175 6.602742) (xy 248.091419 6.518452) (xy 248.067952 6.435976) (xy 248.036976 6.356017)
			(xy 247.998754 6.279257) (xy 247.953613 6.206351) (xy 247.901937 6.137922) (xy 247.844168 6.074552)
			(xy 247.780798 6.016783) (xy 247.712369 5.965107) (xy 247.639463 5.919966) (xy 247.562703 5.881744)
			(xy 247.482744 5.850768) (xy 247.400268 5.827301) (xy 247.315978 5.811545) (xy 247.230595 5.803633)
			(xy 247.144845 5.803633) (xy 247.059462 5.811545) (xy 246.975172 5.827301) (xy 246.892696 5.850768)
			(xy 246.812737 5.881744) (xy 246.735977 5.919966) (xy 246.663071 5.965107) (xy 246.594642 6.016783)
			(xy 246.531272 6.074552) (xy 246.473503 6.137922) (xy 246.421827 6.206351) (xy 246.376686 6.279257)
			(xy 246.338464 6.356017) (xy 246.307488 6.435976) (xy 246.284021 6.518452) (xy 246.268265 6.602742)
			(xy 246.260353 6.688125) (xy 186.540407 6.688125) (xy 186.532495 6.602742) (xy 186.516739 6.518452)
			(xy 186.493272 6.435976) (xy 186.462296 6.356017) (xy 186.424074 6.279257) (xy 186.378933 6.206351)
			(xy 186.327257 6.137922) (xy 186.269488 6.074552) (xy 186.206118 6.016783) (xy 186.137689 5.965107)
			(xy 186.064783 5.919966) (xy 185.988023 5.881744) (xy 185.908064 5.850768) (xy 185.825588 5.827301)
			(xy 185.741298 5.811545) (xy 185.655915 5.803633) (xy 185.570165 5.803633) (xy 185.484782 5.811545)
			(xy 185.400492 5.827301) (xy 185.318016 5.850768) (xy 185.238057 5.881744) (xy 185.161297 5.919966)
			(xy 185.088391 5.965107) (xy 185.019962 6.016783) (xy 184.956592 6.074552) (xy 184.898823 6.137922)
			(xy 184.847147 6.206351) (xy 184.802006 6.279257) (xy 184.763784 6.356017) (xy 184.732808 6.435976)
			(xy 184.709341 6.518452) (xy 184.693585 6.602742) (xy 184.685673 6.688125) (xy 180.190407 6.688125)
			(xy 180.182495 6.602742) (xy 180.166739 6.518452) (xy 180.143272 6.435976) (xy 180.112296 6.356017)
			(xy 180.074074 6.279257) (xy 180.028933 6.206351) (xy 179.977257 6.137922) (xy 179.919488 6.074552)
			(xy 179.856118 6.016783) (xy 179.787689 5.965107) (xy 179.714783 5.919966) (xy 179.638023 5.881744)
			(xy 179.558064 5.850768) (xy 179.475588 5.827301) (xy 179.391298 5.811545) (xy 179.305915 5.803633)
			(xy 179.220165 5.803633) (xy 179.134782 5.811545) (xy 179.050492 5.827301) (xy 178.968016 5.850768)
			(xy 178.888057 5.881744) (xy 178.811297 5.919966) (xy 178.738391 5.965107) (xy 178.669962 6.016783)
			(xy 178.606592 6.074552) (xy 178.548823 6.137922) (xy 178.497147 6.206351) (xy 178.452006 6.279257)
			(xy 178.413784 6.356017) (xy 178.382808 6.435976) (xy 178.359341 6.518452) (xy 178.343585 6.602742)
			(xy 178.335673 6.688125) (xy 6.97173 6.688125) (xy 6.930907 6.582749) (xy 6.876932 6.46543) (xy 6.815837 6.351656)
			(xy 6.747854 6.241859) (xy 6.67324 6.136456) (xy 6.592279 6.035846) (xy 6.505279 5.940411) (xy 6.412568 5.850512)
			(xy 6.314498 5.766491) (xy 6.211443 5.688667) (xy 6.103792 5.617335) (xy 5.991953 5.552765) (xy 5.876352 5.495203)
			(xy 5.757427 5.444866) (xy 5.635628 5.401946) (xy 5.511418 5.366605) (xy 5.385269 5.338978) (xy 5.257657 5.319169)
			(xy 5.129068 5.307253) (xy 4.99999 5.303277) (xy 4.870912 5.307253) (xy 4.742323 5.319169) (xy 4.614711 5.338978)
			(xy 4.488562 5.366605) (xy 4.364352 5.401946) (xy 4.242553 5.444866) (xy 4.123628 5.495203) (xy 4.008027 5.552765)
			(xy 3.896188 5.617335) (xy 3.788537 5.688667) (xy 3.685482 5.766491) (xy 3.587412 5.850512) (xy 3.494701 5.940411)
			(xy 3.407701 6.035846) (xy 3.32674 6.136456) (xy 3.252126 6.241859) (xy 3.184143 6.351656) (xy 3.123048 6.46543)
			(xy 3.069073 6.582749) (xy 3.022422 6.703168) (xy 2.983273 6.826231) (xy 2.951774 6.95147) (xy 2.928045 7.078411)
			(xy 2.912175 7.206571) (xy 2.904225 7.335466) (xy 0.508 7.335466) (xy 0.508 4.148125) (xy 178.335673 4.148125)
			(xy 178.335673 4.233875) (xy 178.343585 4.319258) (xy 178.359341 4.403548) (xy 178.382808 4.486024)
			(xy 178.413784 4.565983) (xy 178.452006 4.642743) (xy 178.497147 4.715649) (xy 178.548823 4.784078)
			(xy 178.606592 4.847448) (xy 178.669962 4.905217) (xy 178.738391 4.956893) (xy 178.811297 5.002034)
			(xy 178.888057 5.040256) (xy 178.968016 5.071232) (xy 179.050492 5.094699) (xy 179.134782 5.110455)
			(xy 179.220165 5.118367) (xy 179.305915 5.118367) (xy 179.391298 5.110455) (xy 179.475588 5.094699)
			(xy 179.558064 5.071232) (xy 179.638023 5.040256) (xy 179.660226 5.0292) (xy 183.270652 5.0292) (xy 183.270652 5.8928)
			(xy 183.271138 5.920069) (xy 183.2789 5.974053) (xy 183.294265 6.026383) (xy 183.316922 6.075993)
			(xy 183.346408 6.121874) (xy 183.382123 6.163091) (xy 183.42334 6.198806) (xy 183.469221 6.228292)
			(xy 183.518831 6.250949) (xy 183.571161 6.266314) (xy 183.625145 6.274076) (xy 183.679683 6.274076)
			(xy 183.733667 6.266314) (xy 183.785997 6.250949) (xy 183.835607 6.228292) (xy 183.881488 6.198806)
			(xy 183.922705 6.163091) (xy 183.95842 6.121874) (xy 183.987906 6.075993) (xy 184.010563 6.026383)
			(xy 184.025928 5.974053) (xy 184.03369 5.920069) (xy 184.034176 5.8928) (xy 184.034176 5.0292) (xy 184.03369 5.001931)
			(xy 184.025928 4.947947) (xy 184.010563 4.895617) (xy 183.987906 4.846007) (xy 183.95842 4.800126)
			(xy 183.922705 4.758909) (xy 183.881488 4.723194) (xy 183.835607 4.693708) (xy 183.785997 4.671051)
			(xy 183.733667 4.655686) (xy 183.679683 4.647924) (xy 183.625145 4.647924) (xy 183.571161 4.655686)
			(xy 183.518831 4.671051) (xy 183.469221 4.693708) (xy 183.42334 4.723194) (xy 183.382123 4.758909)
			(xy 183.346408 4.800126) (xy 183.316922 4.846007) (xy 183.294265 4.895617) (xy 183.2789 4.947947)
			(xy 183.271138 5.001931) (xy 183.270652 5.0292) (xy 179.660226 5.0292) (xy 179.714783 5.002034) (xy 179.787689 4.956893)
			(xy 179.856118 4.905217) (xy 179.919488 4.847448) (xy 179.977257 4.784078) (xy 180.028933 4.715649)
			(xy 180.074074 4.642743) (xy 180.112296 4.565983) (xy 180.143272 4.486024) (xy 180.166739 4.403548)
			(xy 180.182495 4.319258) (xy 180.190407 4.233875) (xy 180.190902 4.191) (xy 180.190407 4.148125)
			(xy 184.685673 4.148125) (xy 184.685673 4.233875) (xy 184.693585 4.319258) (xy 184.709341 4.403548)
			(xy 184.732808 4.486024) (xy 184.763784 4.565983) (xy 184.802006 4.642743) (xy 184.847147 4.715649)
			(xy 184.898823 4.784078) (xy 184.956592 4.847448) (xy 185.019962 4.905217) (xy 185.088391 4.956893)
			(xy 185.161297 5.002034) (xy 185.238057 5.040256) (xy 185.318016 5.071232) (xy 185.400492 5.094699)
			(xy 185.484782 5.110455) (xy 185.570165 5.118367) (xy 185.655915 5.118367) (xy 185.741298 5.110455)
			(xy 185.825588 5.094699) (xy 185.908064 5.071232) (xy 185.988023 5.040256) (xy 186.064783 5.002034)
			(xy 186.137689 4.956893) (xy 186.206118 4.905217) (xy 186.269488 4.847448) (xy 186.327257 4.784078)
			(xy 186.378933 4.715649) (xy 186.424074 4.642743) (xy 186.462296 4.565983) (xy 186.493272 4.486024)
			(xy 186.516739 4.403548) (xy 186.532495 4.319258) (xy 186.540407 4.233875) (xy 186.540902 4.191)
			(xy 186.540407 4.148125) (xy 246.260353 4.148125) (xy 246.260353 4.233875) (xy 246.268265 4.319258)
			(xy 246.284021 4.403548) (xy 246.307488 4.486024) (xy 246.338464 4.565983) (xy 246.376686 4.642743)
			(xy 246.421827 4.715649) (xy 246.473503 4.784078) (xy 246.531272 4.847448) (xy 246.594642 4.905217)
			(xy 246.663071 4.956893) (xy 246.735977 5.002034) (xy 246.812737 5.040256) (xy 246.892696 5.071232)
			(xy 246.975172 5.094699) (xy 247.059462 5.110455) (xy 247.144845 5.118367) (xy 247.230595 5.118367)
			(xy 247.315978 5.110455) (xy 247.400268 5.094699) (xy 247.482744 5.071232) (xy 247.562703 5.040256)
			(xy 247.584906 5.0292) (xy 248.766584 5.0292) (xy 248.766584 5.8928) (xy 248.76707 5.920069) (xy 248.774832 5.974053)
			(xy 248.790197 6.026383) (xy 248.812854 6.075993) (xy 248.84234 6.121874) (xy 248.878055 6.163091)
			(xy 248.919272 6.198806) (xy 248.965153 6.228292) (xy 249.014763 6.250949) (xy 249.067093 6.266314)
			(xy 249.121077 6.274076) (xy 249.175615 6.274076) (xy 249.229599 6.266314) (xy 249.281929 6.250949)
			(xy 249.331539 6.228292) (xy 249.37742 6.198806) (xy 249.418637 6.163091) (xy 249.454352 6.121874)
			(xy 249.483838 6.075993) (xy 249.506495 6.026383) (xy 249.52186 5.974053) (xy 249.529622 5.920069)
			(xy 249.530108 5.8928) (xy 249.530108 5.0292) (xy 249.529622 5.001931) (xy 249.52186 4.947947) (xy 249.506495 4.895617)
			(xy 249.483838 4.846007) (xy 249.454352 4.800126) (xy 249.418637 4.758909) (xy 249.37742 4.723194)
			(xy 249.331539 4.693708) (xy 249.281929 4.671051) (xy 249.229599 4.655686) (xy 249.175615 4.647924)
			(xy 249.121077 4.647924) (xy 249.067093 4.655686) (xy 249.014763 4.671051) (xy 248.965153 4.693708)
			(xy 248.919272 4.723194) (xy 248.878055 4.758909) (xy 248.84234 4.800126) (xy 248.812854 4.846007)
			(xy 248.790197 4.895617) (xy 248.774832 4.947947) (xy 248.76707 5.001931) (xy 248.766584 5.0292)
			(xy 247.584906 5.0292) (xy 247.639463 5.002034) (xy 247.712369 4.956893) (xy 247.780798 4.905217)
			(xy 247.844168 4.847448) (xy 247.901937 4.784078) (xy 247.953613 4.715649) (xy 247.998754 4.642743)
			(xy 248.036976 4.565983) (xy 248.067952 4.486024) (xy 248.091419 4.403548) (xy 248.107175 4.319258)
			(xy 248.115087 4.233875) (xy 248.115582 4.191) (xy 248.115087 4.148125) (xy 252.610353 4.148125)
			(xy 252.610353 4.233875) (xy 252.618265 4.319258) (xy 252.634021 4.403548) (xy 252.657488 4.486024)
			(xy 252.688464 4.565983) (xy 252.726686 4.642743) (xy 252.771827 4.715649) (xy 252.823503 4.784078)
			(xy 252.881272 4.847448) (xy 252.944642 4.905217) (xy 253.013071 4.956893) (xy 253.085977 5.002034)
			(xy 253.162737 5.040256) (xy 253.242696 5.071232) (xy 253.325172 5.094699) (xy 253.409462 5.110455)
			(xy 253.494845 5.118367) (xy 253.580595 5.118367) (xy 253.665978 5.110455) (xy 253.750268 5.094699)
			(xy 253.832744 5.071232) (xy 253.912703 5.040256) (xy 253.989463 5.002034) (xy 254.062369 4.956893)
			(xy 254.130798 4.905217) (xy 254.194168 4.847448) (xy 254.251937 4.784078) (xy 254.303613 4.715649)
			(xy 254.348754 4.642743) (xy 254.386976 4.565983) (xy 254.417952 4.486024) (xy 254.441419 4.403548)
			(xy 254.457175 4.319258) (xy 254.465087 4.233875) (xy 254.465582 4.191) (xy 254.465119 4.150919)
			(xy 256.921241 4.150919) (xy 256.921241 4.236669) (xy 256.929153 4.322052) (xy 256.944909 4.406342)
			(xy 256.968376 4.488818) (xy 256.999352 4.568777) (xy 257.037574 4.645537) (xy 257.082715 4.718443)
			(xy 257.134391 4.786872) (xy 257.19216 4.850242) (xy 257.25553 4.908011) (xy 257.323959 4.959687)
			(xy 257.396865 5.004828) (xy 257.473625 5.04305) (xy 257.553584 5.074026) (xy 257.63606 5.097493)
			(xy 257.72035 5.113249) (xy 257.805733 5.121161) (xy 257.891483 5.121161) (xy 257.976866 5.113249)
			(xy 258.061156 5.097493) (xy 258.143632 5.074026) (xy 258.223591 5.04305) (xy 258.245794 5.031994)
			(xy 261.85622 5.031994) (xy 261.85622 5.895594) (xy 261.856706 5.922863) (xy 261.864468 5.976847)
			(xy 261.879833 6.029177) (xy 261.90249 6.078787) (xy 261.931976 6.124668) (xy 261.967691 6.165885)
			(xy 262.008908 6.2016) (xy 262.054789 6.231086) (xy 262.104399 6.253743) (xy 262.156729 6.269108)
			(xy 262.210713 6.27687) (xy 262.265251 6.27687) (xy 262.319235 6.269108) (xy 262.371565 6.253743)
			(xy 262.421175 6.231086) (xy 262.467056 6.2016) (xy 262.508273 6.165885) (xy 262.543988 6.124668)
			(xy 262.573474 6.078787) (xy 262.596131 6.029177) (xy 262.611496 5.976847) (xy 262.619258 5.922863)
			(xy 262.619744 5.895594) (xy 262.619744 5.031994) (xy 262.619258 5.004725) (xy 262.611496 4.950741)
			(xy 262.596131 4.898411) (xy 262.573474 4.848801) (xy 262.543988 4.80292) (xy 262.508273 4.761703)
			(xy 262.467056 4.725988) (xy 262.421175 4.696502) (xy 262.371565 4.673845) (xy 262.319235 4.65848)
			(xy 262.265251 4.650718) (xy 262.210713 4.650718) (xy 262.156729 4.65848) (xy 262.104399 4.673845)
			(xy 262.054789 4.696502) (xy 262.008908 4.725988) (xy 261.967691 4.761703) (xy 261.931976 4.80292)
			(xy 261.90249 4.848801) (xy 261.879833 4.898411) (xy 261.864468 4.950741) (xy 261.856706 5.004725)
			(xy 261.85622 5.031994) (xy 258.245794 5.031994) (xy 258.300351 5.004828) (xy 258.373257 4.959687)
			(xy 258.441686 4.908011) (xy 258.505056 4.850242) (xy 258.562825 4.786872) (xy 258.614501 4.718443)
			(xy 258.659642 4.645537) (xy 258.697864 4.568777) (xy 258.72884 4.488818) (xy 258.752307 4.406342)
			(xy 258.768063 4.322052) (xy 258.775975 4.236669) (xy 258.77647 4.193794) (xy 258.775975 4.150919)
			(xy 263.271241 4.150919) (xy 263.271241 4.236669) (xy 263.279153 4.322052) (xy 263.294909 4.406342)
			(xy 263.318376 4.488818) (xy 263.349352 4.568777) (xy 263.387574 4.645537) (xy 263.432715 4.718443)
			(xy 263.484391 4.786872) (xy 263.54216 4.850242) (xy 263.60553 4.908011) (xy 263.673959 4.959687)
			(xy 263.746865 5.004828) (xy 263.823625 5.04305) (xy 263.903584 5.074026) (xy 263.98606 5.097493)
			(xy 264.07035 5.113249) (xy 264.155733 5.121161) (xy 264.241483 5.121161) (xy 264.326866 5.113249)
			(xy 264.411156 5.097493) (xy 264.493632 5.074026) (xy 264.573591 5.04305) (xy 264.650351 5.004828)
			(xy 264.723257 4.959687) (xy 264.791686 4.908011) (xy 264.855056 4.850242) (xy 264.912825 4.786872)
			(xy 264.964501 4.718443) (xy 265.009642 4.645537) (xy 265.047864 4.568777) (xy 265.07884 4.488818)
			(xy 265.102307 4.406342) (xy 265.118063 4.322052) (xy 265.125975 4.236669) (xy 265.12647 4.193794)
			(xy 265.125975 4.150919) (xy 324.845921 4.150919) (xy 324.845921 4.236669) (xy 324.853833 4.322052)
			(xy 324.869589 4.406342) (xy 324.893056 4.488818) (xy 324.924032 4.568777) (xy 324.962254 4.645537)
			(xy 325.007395 4.718443) (xy 325.059071 4.786872) (xy 325.11684 4.850242) (xy 325.18021 4.908011)
			(xy 325.248639 4.959687) (xy 325.321545 5.004828) (xy 325.398305 5.04305) (xy 325.478264 5.074026)
			(xy 325.56074 5.097493) (xy 325.64503 5.113249) (xy 325.730413 5.121161) (xy 325.816163 5.121161)
			(xy 325.901546 5.113249) (xy 325.985836 5.097493) (xy 326.068312 5.074026) (xy 326.148271 5.04305)
			(xy 326.170474 5.031994) (xy 327.352152 5.031994) (xy 327.352152 5.895594) (xy 327.352638 5.922863)
			(xy 327.3604 5.976847) (xy 327.375765 6.029177) (xy 327.398422 6.078787) (xy 327.427908 6.124668)
			(xy 327.463623 6.165885) (xy 327.50484 6.2016) (xy 327.550721 6.231086) (xy 327.600331 6.253743)
			(xy 327.652661 6.269108) (xy 327.706645 6.27687) (xy 327.761183 6.27687) (xy 327.815167 6.269108)
			(xy 327.867497 6.253743) (xy 327.917107 6.231086) (xy 327.962988 6.2016) (xy 328.004205 6.165885)
			(xy 328.03992 6.124668) (xy 328.069406 6.078787) (xy 328.092063 6.029177) (xy 328.107428 5.976847)
			(xy 328.11519 5.922863) (xy 328.115676 5.895594) (xy 328.115676 5.031994) (xy 328.11519 5.004725)
			(xy 328.107428 4.950741) (xy 328.092063 4.898411) (xy 328.069406 4.848801) (xy 328.03992 4.80292)
			(xy 328.004205 4.761703) (xy 327.962988 4.725988) (xy 327.917107 4.696502) (xy 327.867497 4.673845)
			(xy 327.815167 4.65848) (xy 327.761183 4.650718) (xy 327.706645 4.650718) (xy 327.652661 4.65848)
			(xy 327.600331 4.673845) (xy 327.550721 4.696502) (xy 327.50484 4.725988) (xy 327.463623 4.761703)
			(xy 327.427908 4.80292) (xy 327.398422 4.848801) (xy 327.375765 4.898411) (xy 327.3604 4.950741)
			(xy 327.352638 5.004725) (xy 327.352152 5.031994) (xy 326.170474 5.031994) (xy 326.225031 5.004828)
			(xy 326.297937 4.959687) (xy 326.366366 4.908011) (xy 326.429736 4.850242) (xy 326.487505 4.786872)
			(xy 326.539181 4.718443) (xy 326.584322 4.645537) (xy 326.622544 4.568777) (xy 326.65352 4.488818)
			(xy 326.676987 4.406342) (xy 326.692743 4.322052) (xy 326.700655 4.236669) (xy 326.70115 4.193794)
			(xy 326.700655 4.150919) (xy 331.195921 4.150919) (xy 331.195921 4.236669) (xy 331.203833 4.322052)
			(xy 331.219589 4.406342) (xy 331.243056 4.488818) (xy 331.274032 4.568777) (xy 331.312254 4.645537)
			(xy 331.357395 4.718443) (xy 331.409071 4.786872) (xy 331.46684 4.850242) (xy 331.53021 4.908011)
			(xy 331.598639 4.959687) (xy 331.671545 5.004828) (xy 331.748305 5.04305) (xy 331.828264 5.074026)
			(xy 331.91074 5.097493) (xy 331.99503 5.113249) (xy 332.080413 5.121161) (xy 332.166163 5.121161)
			(xy 332.251546 5.113249) (xy 332.335836 5.097493) (xy 332.418312 5.074026) (xy 332.498271 5.04305)
			(xy 332.575031 5.004828) (xy 332.647937 4.959687) (xy 332.716366 4.908011) (xy 332.779736 4.850242)
			(xy 332.837505 4.786872) (xy 332.889181 4.718443) (xy 332.934322 4.645537) (xy 332.972544 4.568777)
			(xy 333.00352 4.488818) (xy 333.026987 4.406342) (xy 333.042743 4.322052) (xy 333.050655 4.236669)
			(xy 333.05115 4.193794) (xy 333.050655 4.150919) (xy 335.488267 4.150919) (xy 335.488267 4.236669)
			(xy 335.496179 4.322052) (xy 335.511935 4.406342) (xy 335.535402 4.488818) (xy 335.566378 4.568777)
			(xy 335.6046 4.645537) (xy 335.649741 4.718443) (xy 335.701417 4.786872) (xy 335.759186 4.850242)
			(xy 335.822556 4.908011) (xy 335.890985 4.959687) (xy 335.963891 5.004828) (xy 336.040651 5.04305)
			(xy 336.12061 5.074026) (xy 336.203086 5.097493) (xy 336.287376 5.113249) (xy 336.372759 5.121161)
			(xy 336.458509 5.121161) (xy 336.543892 5.113249) (xy 336.628182 5.097493) (xy 336.710658 5.074026)
			(xy 336.790617 5.04305) (xy 336.81282 5.031994) (xy 340.4235 5.031994) (xy 340.4235 5.895594) (xy 340.423986 5.922845)
			(xy 340.431742 5.976793) (xy 340.447097 6.029088) (xy 340.469739 6.078665) (xy 340.499205 6.124515)
			(xy 340.534896 6.165706) (xy 340.576087 6.201397) (xy 340.621937 6.230863) (xy 340.671514 6.253505)
			(xy 340.723809 6.26886) (xy 340.777757 6.276616) (xy 340.832259 6.276616) (xy 340.886207 6.26886)
			(xy 340.938502 6.253505) (xy 340.988079 6.230863) (xy 341.033929 6.201397) (xy 341.07512 6.165706)
			(xy 341.110811 6.124515) (xy 341.140277 6.078665) (xy 341.162919 6.029088) (xy 341.178274 5.976793)
			(xy 341.18603 5.922845) (xy 341.186516 5.895594) (xy 341.186516 5.031994) (xy 341.18603 5.004743)
			(xy 341.178274 4.950795) (xy 341.162919 4.8985) (xy 341.140277 4.848923) (xy 341.110811 4.803073)
			(xy 341.07512 4.761882) (xy 341.033929 4.726191) (xy 340.988079 4.696725) (xy 340.938502 4.674083)
			(xy 340.886207 4.658728) (xy 340.832259 4.650972) (xy 340.777757 4.650972) (xy 340.723809 4.658728)
			(xy 340.671514 4.674083) (xy 340.621937 4.696725) (xy 340.576087 4.726191) (xy 340.534896 4.761882)
			(xy 340.499205 4.803073) (xy 340.469739 4.848923) (xy 340.447097 4.8985) (xy 340.431742 4.950795)
			(xy 340.423986 5.004743) (xy 340.4235 5.031994) (xy 336.81282 5.031994) (xy 336.867377 5.004828)
			(xy 336.940283 4.959687) (xy 337.008712 4.908011) (xy 337.072082 4.850242) (xy 337.129851 4.786872)
			(xy 337.181527 4.718443) (xy 337.226668 4.645537) (xy 337.26489 4.568777) (xy 337.295866 4.488818)
			(xy 337.319333 4.406342) (xy 337.335089 4.322052) (xy 337.343001 4.236669) (xy 337.343496 4.193794)
			(xy 337.343001 4.150919) (xy 341.838267 4.150919) (xy 341.838267 4.236669) (xy 341.846179 4.322052)
			(xy 341.861935 4.406342) (xy 341.885402 4.488818) (xy 341.916378 4.568777) (xy 341.9546 4.645537)
			(xy 341.999741 4.718443) (xy 342.051417 4.786872) (xy 342.109186 4.850242) (xy 342.172556 4.908011)
			(xy 342.240985 4.959687) (xy 342.313891 5.004828) (xy 342.390651 5.04305) (xy 342.47061 5.074026)
			(xy 342.553086 5.097493) (xy 342.637376 5.113249) (xy 342.722759 5.121161) (xy 342.808509 5.121161)
			(xy 342.893892 5.113249) (xy 342.978182 5.097493) (xy 343.060658 5.074026) (xy 343.140617 5.04305)
			(xy 343.217377 5.004828) (xy 343.290283 4.959687) (xy 343.358712 4.908011) (xy 343.422082 4.850242)
			(xy 343.479851 4.786872) (xy 343.531527 4.718443) (xy 343.576668 4.645537) (xy 343.61489 4.568777)
			(xy 343.645866 4.488818) (xy 343.669333 4.406342) (xy 343.685089 4.322052) (xy 343.693001 4.236669)
			(xy 343.693496 4.193794) (xy 343.693001 4.150919) (xy 373.705107 4.150919) (xy 373.705107 4.236669)
			(xy 373.713019 4.322052) (xy 373.728775 4.406342) (xy 373.752242 4.488818) (xy 373.783218 4.568777)
			(xy 373.82144 4.645537) (xy 373.866581 4.718443) (xy 373.918257 4.786872) (xy 373.976026 4.850242)
			(xy 374.039396 4.908011) (xy 374.107825 4.959687) (xy 374.180731 5.004828) (xy 374.257491 5.04305)
			(xy 374.33745 5.074026) (xy 374.419926 5.097493) (xy 374.504216 5.113249) (xy 374.589599 5.121161)
			(xy 374.675349 5.121161) (xy 374.760732 5.113249) (xy 374.845022 5.097493) (xy 374.927498 5.074026)
			(xy 375.007457 5.04305) (xy 375.02966 5.031994) (xy 376.211592 5.031994) (xy 376.211592 5.895594)
			(xy 376.212078 5.922845) (xy 376.219834 5.976793) (xy 376.235189 6.029088) (xy 376.257831 6.078665)
			(xy 376.287297 6.124515) (xy 376.322988 6.165706) (xy 376.364179 6.201397) (xy 376.410029 6.230863)
			(xy 376.459606 6.253505) (xy 376.511901 6.26886) (xy 376.565849 6.276616) (xy 376.620351 6.276616)
			(xy 376.674299 6.26886) (xy 376.726594 6.253505) (xy 376.776171 6.230863) (xy 376.822021 6.201397)
			(xy 376.863212 6.165706) (xy 376.898903 6.124515) (xy 376.928369 6.078665) (xy 376.951011 6.029088)
			(xy 376.966366 5.976793) (xy 376.974122 5.922845) (xy 376.974608 5.895594) (xy 376.974608 5.031994)
			(xy 376.974122 5.004743) (xy 376.966366 4.950795) (xy 376.951011 4.8985) (xy 376.928369 4.848923)
			(xy 376.898903 4.803073) (xy 376.863212 4.761882) (xy 376.822021 4.726191) (xy 376.776171 4.696725)
			(xy 376.726594 4.674083) (xy 376.674299 4.658728) (xy 376.620351 4.650972) (xy 376.565849 4.650972)
			(xy 376.511901 4.658728) (xy 376.459606 4.674083) (xy 376.410029 4.696725) (xy 376.364179 4.726191)
			(xy 376.322988 4.761882) (xy 376.287297 4.803073) (xy 376.257831 4.848923) (xy 376.235189 4.8985)
			(xy 376.219834 4.950795) (xy 376.212078 5.004743) (xy 376.211592 5.031994) (xy 375.02966 5.031994)
			(xy 375.084217 5.004828) (xy 375.157123 4.959687) (xy 375.225552 4.908011) (xy 375.288922 4.850242)
			(xy 375.346691 4.786872) (xy 375.398367 4.718443) (xy 375.443508 4.645537) (xy 375.48173 4.568777)
			(xy 375.512706 4.488818) (xy 375.536173 4.406342) (xy 375.551929 4.322052) (xy 375.559841 4.236669)
			(xy 375.560336 4.193794) (xy 375.559841 4.150919) (xy 380.055107 4.150919) (xy 380.055107 4.236669)
			(xy 380.063019 4.322052) (xy 380.078775 4.406342) (xy 380.102242 4.488818) (xy 380.133218 4.568777)
			(xy 380.17144 4.645537) (xy 380.216581 4.718443) (xy 380.268257 4.786872) (xy 380.326026 4.850242)
			(xy 380.389396 4.908011) (xy 380.457825 4.959687) (xy 380.530731 5.004828) (xy 380.607491 5.04305)
			(xy 380.68745 5.074026) (xy 380.769926 5.097493) (xy 380.854216 5.113249) (xy 380.939599 5.121161)
			(xy 381.025349 5.121161) (xy 381.110732 5.113249) (xy 381.195022 5.097493) (xy 381.277498 5.074026)
			(xy 381.357457 5.04305) (xy 381.434217 5.004828) (xy 381.507123 4.959687) (xy 381.575552 4.908011)
			(xy 381.638922 4.850242) (xy 381.696691 4.786872) (xy 381.748367 4.718443) (xy 381.793508 4.645537)
			(xy 381.83173 4.568777) (xy 381.862706 4.488818) (xy 381.886173 4.406342) (xy 381.901929 4.322052)
			(xy 381.909841 4.236669) (xy 381.910336 4.193794) (xy 381.909841 4.150919) (xy 381.901929 4.065536)
			(xy 381.886173 3.981246) (xy 381.862706 3.89877) (xy 381.83173 3.818811) (xy 381.793508 3.742051)
			(xy 381.748367 3.669145) (xy 381.696691 3.600716) (xy 381.638922 3.537346) (xy 381.575552 3.479577)
			(xy 381.507123 3.427901) (xy 381.434217 3.38276) (xy 381.357457 3.344538) (xy 381.277498 3.313562)
			(xy 381.195022 3.290095) (xy 381.110732 3.274339) (xy 381.025349 3.266427) (xy 380.939599 3.266427)
			(xy 380.854216 3.274339) (xy 380.769926 3.290095) (xy 380.68745 3.313562) (xy 380.607491 3.344538)
			(xy 380.530731 3.38276) (xy 380.457825 3.427901) (xy 380.389396 3.479577) (xy 380.326026 3.537346)
			(xy 380.268257 3.600716) (xy 380.216581 3.669145) (xy 380.17144 3.742051) (xy 380.133218 3.818811)
			(xy 380.102242 3.89877) (xy 380.078775 3.981246) (xy 380.063019 4.065536) (xy 380.055107 4.150919)
			(xy 375.559841 4.150919) (xy 375.551929 4.065536) (xy 375.536173 3.981246) (xy 375.512706 3.89877)
			(xy 375.48173 3.818811) (xy 375.443508 3.742051) (xy 375.398367 3.669145) (xy 375.346691 3.600716)
			(xy 375.288922 3.537346) (xy 375.225552 3.479577) (xy 375.157123 3.427901) (xy 375.084217 3.38276)
			(xy 375.007457 3.344538) (xy 374.927498 3.313562) (xy 374.845022 3.290095) (xy 374.760732 3.274339)
			(xy 374.675349 3.266427) (xy 374.589599 3.266427) (xy 374.504216 3.274339) (xy 374.419926 3.290095)
			(xy 374.33745 3.313562) (xy 374.257491 3.344538) (xy 374.180731 3.38276) (xy 374.107825 3.427901)
			(xy 374.039396 3.479577) (xy 373.976026 3.537346) (xy 373.918257 3.600716) (xy 373.866581 3.669145)
			(xy 373.82144 3.742051) (xy 373.783218 3.818811) (xy 373.752242 3.89877) (xy 373.728775 3.981246)
			(xy 373.713019 4.065536) (xy 373.705107 4.150919) (xy 343.693001 4.150919) (xy 343.685089 4.065536)
			(xy 343.669333 3.981246) (xy 343.645866 3.89877) (xy 343.61489 3.818811) (xy 343.576668 3.742051)
			(xy 343.531527 3.669145) (xy 343.479851 3.600716) (xy 343.422082 3.537346) (xy 343.358712 3.479577)
			(xy 343.290283 3.427901) (xy 343.217377 3.38276) (xy 343.140617 3.344538) (xy 343.060658 3.313562)
			(xy 342.978182 3.290095) (xy 342.893892 3.274339) (xy 342.808509 3.266427) (xy 342.722759 3.266427)
			(xy 342.637376 3.274339) (xy 342.553086 3.290095) (xy 342.47061 3.313562) (xy 342.390651 3.344538)
			(xy 342.313891 3.38276) (xy 342.240985 3.427901) (xy 342.172556 3.479577) (xy 342.109186 3.537346)
			(xy 342.051417 3.600716) (xy 341.999741 3.669145) (xy 341.9546 3.742051) (xy 341.916378 3.818811)
			(xy 341.885402 3.89877) (xy 341.861935 3.981246) (xy 341.846179 4.065536) (xy 341.838267 4.150919)
			(xy 337.343001 4.150919) (xy 337.335089 4.065536) (xy 337.319333 3.981246) (xy 337.295866 3.89877)
			(xy 337.26489 3.818811) (xy 337.226668 3.742051) (xy 337.181527 3.669145) (xy 337.129851 3.600716)
			(xy 337.072082 3.537346) (xy 337.008712 3.479577) (xy 336.940283 3.427901) (xy 336.867377 3.38276)
			(xy 336.790617 3.344538) (xy 336.710658 3.313562) (xy 336.628182 3.290095) (xy 336.543892 3.274339)
			(xy 336.458509 3.266427) (xy 336.372759 3.266427) (xy 336.287376 3.274339) (xy 336.203086 3.290095)
			(xy 336.12061 3.313562) (xy 336.040651 3.344538) (xy 335.963891 3.38276) (xy 335.890985 3.427901)
			(xy 335.822556 3.479577) (xy 335.759186 3.537346) (xy 335.701417 3.600716) (xy 335.649741 3.669145)
			(xy 335.6046 3.742051) (xy 335.566378 3.818811) (xy 335.535402 3.89877) (xy 335.511935 3.981246)
			(xy 335.496179 4.065536) (xy 335.488267 4.150919) (xy 333.050655 4.150919) (xy 333.042743 4.065536)
			(xy 333.026987 3.981246) (xy 333.00352 3.89877) (xy 332.972544 3.818811) (xy 332.934322 3.742051)
			(xy 332.889181 3.669145) (xy 332.837505 3.600716) (xy 332.779736 3.537346) (xy 332.716366 3.479577)
			(xy 332.647937 3.427901) (xy 332.575031 3.38276) (xy 332.498271 3.344538) (xy 332.418312 3.313562)
			(xy 332.335836 3.290095) (xy 332.251546 3.274339) (xy 332.166163 3.266427) (xy 332.080413 3.266427)
			(xy 331.99503 3.274339) (xy 331.91074 3.290095) (xy 331.828264 3.313562) (xy 331.748305 3.344538)
			(xy 331.671545 3.38276) (xy 331.598639 3.427901) (xy 331.53021 3.479577) (xy 331.46684 3.537346)
			(xy 331.409071 3.600716) (xy 331.357395 3.669145) (xy 331.312254 3.742051) (xy 331.274032 3.818811)
			(xy 331.243056 3.89877) (xy 331.219589 3.981246) (xy 331.203833 4.065536) (xy 331.195921 4.150919)
			(xy 326.700655 4.150919) (xy 326.692743 4.065536) (xy 326.676987 3.981246) (xy 326.65352 3.89877)
			(xy 326.622544 3.818811) (xy 326.584322 3.742051) (xy 326.539181 3.669145) (xy 326.487505 3.600716)
			(xy 326.429736 3.537346) (xy 326.366366 3.479577) (xy 326.297937 3.427901) (xy 326.225031 3.38276)
			(xy 326.148271 3.344538) (xy 326.068312 3.313562) (xy 325.985836 3.290095) (xy 325.901546 3.274339)
			(xy 325.816163 3.266427) (xy 325.730413 3.266427) (xy 325.64503 3.274339) (xy 325.56074 3.290095)
			(xy 325.478264 3.313562) (xy 325.398305 3.344538) (xy 325.321545 3.38276) (xy 325.248639 3.427901)
			(xy 325.18021 3.479577) (xy 325.11684 3.537346) (xy 325.059071 3.600716) (xy 325.007395 3.669145)
			(xy 324.962254 3.742051) (xy 324.924032 3.818811) (xy 324.893056 3.89877) (xy 324.869589 3.981246)
			(xy 324.853833 4.065536) (xy 324.845921 4.150919) (xy 265.125975 4.150919) (xy 265.118063 4.065536)
			(xy 265.102307 3.981246) (xy 265.07884 3.89877) (xy 265.047864 3.818811) (xy 265.009642 3.742051)
			(xy 264.964501 3.669145) (xy 264.912825 3.600716) (xy 264.855056 3.537346) (xy 264.791686 3.479577)
			(xy 264.723257 3.427901) (xy 264.650351 3.38276) (xy 264.573591 3.344538) (xy 264.493632 3.313562)
			(xy 264.411156 3.290095) (xy 264.326866 3.274339) (xy 264.241483 3.266427) (xy 264.155733 3.266427)
			(xy 264.07035 3.274339) (xy 263.98606 3.290095) (xy 263.903584 3.313562) (xy 263.823625 3.344538)
			(xy 263.746865 3.38276) (xy 263.673959 3.427901) (xy 263.60553 3.479577) (xy 263.54216 3.537346)
			(xy 263.484391 3.600716) (xy 263.432715 3.669145) (xy 263.387574 3.742051) (xy 263.349352 3.818811)
			(xy 263.318376 3.89877) (xy 263.294909 3.981246) (xy 263.279153 4.065536) (xy 263.271241 4.150919)
			(xy 258.775975 4.150919) (xy 258.768063 4.065536) (xy 258.752307 3.981246) (xy 258.72884 3.89877)
			(xy 258.697864 3.818811) (xy 258.659642 3.742051) (xy 258.614501 3.669145) (xy 258.562825 3.600716)
			(xy 258.505056 3.537346) (xy 258.441686 3.479577) (xy 258.373257 3.427901) (xy 258.300351 3.38276)
			(xy 258.223591 3.344538) (xy 258.143632 3.313562) (xy 258.061156 3.290095) (xy 257.976866 3.274339)
			(xy 257.891483 3.266427) (xy 257.805733 3.266427) (xy 257.72035 3.274339) (xy 257.63606 3.290095)
			(xy 257.553584 3.313562) (xy 257.473625 3.344538) (xy 257.396865 3.38276) (xy 257.323959 3.427901)
			(xy 257.25553 3.479577) (xy 257.19216 3.537346) (xy 257.134391 3.600716) (xy 257.082715 3.669145)
			(xy 257.037574 3.742051) (xy 256.999352 3.818811) (xy 256.968376 3.89877) (xy 256.944909 3.981246)
			(xy 256.929153 4.065536) (xy 256.921241 4.150919) (xy 254.465119 4.150919) (xy 254.465087 4.148125)
			(xy 254.457175 4.062742) (xy 254.441419 3.978452) (xy 254.417952 3.895976) (xy 254.386976 3.816017)
			(xy 254.348754 3.739257) (xy 254.303613 3.666351) (xy 254.251937 3.597922) (xy 254.194168 3.534552)
			(xy 254.130798 3.476783) (xy 254.062369 3.425107) (xy 253.989463 3.379966) (xy 253.912703 3.341744)
			(xy 253.832744 3.310768) (xy 253.750268 3.287301) (xy 253.665978 3.271545) (xy 253.580595 3.263633)
			(xy 253.494845 3.263633) (xy 253.409462 3.271545) (xy 253.325172 3.287301) (xy 253.242696 3.310768)
			(xy 253.162737 3.341744) (xy 253.085977 3.379966) (xy 253.013071 3.425107) (xy 252.944642 3.476783)
			(xy 252.881272 3.534552) (xy 252.823503 3.597922) (xy 252.771827 3.666351) (xy 252.726686 3.739257)
			(xy 252.688464 3.816017) (xy 252.657488 3.895976) (xy 252.634021 3.978452) (xy 252.618265 4.062742)
			(xy 252.610353 4.148125) (xy 248.115087 4.148125) (xy 248.107175 4.062742) (xy 248.091419 3.978452)
			(xy 248.067952 3.895976) (xy 248.036976 3.816017) (xy 247.998754 3.739257) (xy 247.953613 3.666351)
			(xy 247.901937 3.597922) (xy 247.844168 3.534552) (xy 247.780798 3.476783) (xy 247.712369 3.425107)
			(xy 247.639463 3.379966) (xy 247.562703 3.341744) (xy 247.482744 3.310768) (xy 247.400268 3.287301)
			(xy 247.315978 3.271545) (xy 247.230595 3.263633) (xy 247.144845 3.263633) (xy 247.059462 3.271545)
			(xy 246.975172 3.287301) (xy 246.892696 3.310768) (xy 246.812737 3.341744) (xy 246.735977 3.379966)
			(xy 246.663071 3.425107) (xy 246.594642 3.476783) (xy 246.531272 3.534552) (xy 246.473503 3.597922)
			(xy 246.421827 3.666351) (xy 246.376686 3.739257) (xy 246.338464 3.816017) (xy 246.307488 3.895976)
			(xy 246.284021 3.978452) (xy 246.268265 4.062742) (xy 246.260353 4.148125) (xy 186.540407 4.148125)
			(xy 186.532495 4.062742) (xy 186.516739 3.978452) (xy 186.493272 3.895976) (xy 186.462296 3.816017)
			(xy 186.424074 3.739257) (xy 186.378933 3.666351) (xy 186.327257 3.597922) (xy 186.269488 3.534552)
			(xy 186.206118 3.476783) (xy 186.137689 3.425107) (xy 186.064783 3.379966) (xy 185.988023 3.341744)
			(xy 185.908064 3.310768) (xy 185.825588 3.287301) (xy 185.741298 3.271545) (xy 185.655915 3.263633)
			(xy 185.570165 3.263633) (xy 185.484782 3.271545) (xy 185.400492 3.287301) (xy 185.318016 3.310768)
			(xy 185.238057 3.341744) (xy 185.161297 3.379966) (xy 185.088391 3.425107) (xy 185.019962 3.476783)
			(xy 184.956592 3.534552) (xy 184.898823 3.597922) (xy 184.847147 3.666351) (xy 184.802006 3.739257)
			(xy 184.763784 3.816017) (xy 184.732808 3.895976) (xy 184.709341 3.978452) (xy 184.693585 4.062742)
			(xy 184.685673 4.148125) (xy 180.190407 4.148125) (xy 180.182495 4.062742) (xy 180.166739 3.978452)
			(xy 180.143272 3.895976) (xy 180.112296 3.816017) (xy 180.074074 3.739257) (xy 180.028933 3.666351)
			(xy 179.977257 3.597922) (xy 179.919488 3.534552) (xy 179.856118 3.476783) (xy 179.787689 3.425107)
			(xy 179.714783 3.379966) (xy 179.638023 3.341744) (xy 179.558064 3.310768) (xy 179.475588 3.287301)
			(xy 179.391298 3.271545) (xy 179.305915 3.263633) (xy 179.220165 3.263633) (xy 179.134782 3.271545)
			(xy 179.050492 3.287301) (xy 178.968016 3.310768) (xy 178.888057 3.341744) (xy 178.811297 3.379966)
			(xy 178.738391 3.425107) (xy 178.669962 3.476783) (xy 178.606592 3.534552) (xy 178.548823 3.597922)
			(xy 178.497147 3.666351) (xy 178.452006 3.739257) (xy 178.413784 3.816017) (xy 178.382808 3.895976)
			(xy 178.359341 3.978452) (xy 178.343585 4.062742) (xy 178.335673 4.148125) (xy 0.508 4.148125) (xy 0.508 -7.78002)
			(xy 0.508522 -7.835827) (xy 0.516863 -7.947129) (xy 0.533498 -8.057497) (xy 0.558334 -8.166312) (xy 0.591233 -8.272968)
			(xy 0.63201 -8.376867) (xy 0.680438 -8.477428) (xy 0.736245 -8.574088) (xy 0.799119 -8.666308) (xy 0.868709 -8.753572)
			(xy 0.944626 -8.835391) (xy 1.026445 -8.911308) (xy 1.113708 -8.980898) (xy 1.205928 -9.043773) (xy 1.302589 -9.09958)
			(xy 1.40315 -9.148008) (xy 1.507048 -9.188786) (xy 1.613704 -9.221685) (xy 1.722519 -9.246521) (xy 1.832887 -9.263157)
			(xy 1.944189 -9.271498) (xy 1.999996 -9.272016) (xy 9.10209 -9.272016) (xy 9.157898 -9.271495) (xy 9.269201 -9.263154)
			(xy 9.379569 -9.24652) (xy 9.488386 -9.221684) (xy 9.595043 -9.188786) (xy 9.698942 -9.148009) (xy 9.799505 -9.099582)
			(xy 9.896167 -9.043775) (xy 9.988388 -8.980901) (xy 10.075653 -8.911311) (xy 10.157473 -8.835394)
			(xy 10.233392 -8.753575) (xy 10.302983 -8.666312) (xy 10.365859 -8.574092) (xy 10.421668 -8.477431)
			(xy 10.470097 -8.37687) (xy 10.510876 -8.272971) (xy 10.543776 -8.166315) (xy 10.568614 -8.057499)
			(xy 10.585251 -7.94713) (xy 10.593594 -7.835828) (xy 10.594086 -7.78002) (xy 10.594086 0.999998)
			(xy 10.59457 1.070352) (xy 10.60246 1.210839) (xy 10.618214 1.350662) (xy 10.641783 1.489382) (xy 10.673094 1.626562)
			(xy 10.712047 1.761771) (xy 10.758519 1.894583) (xy 10.812366 2.02458) (xy 10.873417 2.151354) (xy 10.94148 2.274505)
			(xy 11.016341 2.393646) (xy 11.097765 2.508402) (xy 11.185495 2.618411) (xy 11.279255 2.723329) (xy 11.378751 2.822825)
			(xy 11.483669 2.916585) (xy 11.593678 3.004315) (xy 11.708434 3.085739) (xy 11.827575 3.1606) (xy 11.950726 3.228663)
			(xy 12.0775 3.289714) (xy 12.207497 3.343561) (xy 12.340309 3.390033) (xy 12.475518 3.428986) (xy 12.612698 3.460297)
			(xy 12.751418 3.483866) (xy 12.891241 3.49962) (xy 13.031728 3.50751) (xy 13.102082 3.507994) (xy 81.701894 3.507994)
			(xy 81.772248 3.50751) (xy 81.912735 3.499621) (xy 82.052558 3.483867) (xy 82.191278 3.460297) (xy 82.328459 3.428987)
			(xy 82.463668 3.390034) (xy 82.59648 3.343562) (xy 82.726477 3.289715) (xy 82.853251 3.228664) (xy 82.976402 3.160601)
			(xy 83.095543 3.08574) (xy 83.2103 3.004317) (xy 83.32031 2.916587) (xy 83.425228 2.822826) (xy 83.524724 2.723331)
			(xy 83.618484 2.618413) (xy 83.706214 2.508403) (xy 83.787638 2.393647) (xy 83.862499 2.274506) (xy 83.930563 2.151355)
			(xy 83.991614 2.024581) (xy 84.04546 1.894584) (xy 84.091933 1.761772) (xy 84.130886 1.626563) (xy 84.135094 1.608125)
			(xy 178.335673 1.608125) (xy 178.335673 1.693875) (xy 178.343585 1.779258) (xy 178.359341 1.863548)
			(xy 178.382808 1.946024) (xy 178.413784 2.025983) (xy 178.452006 2.102743) (xy 178.497147 2.175649)
			(xy 178.548823 2.244078) (xy 178.606592 2.307448) (xy 178.669962 2.365217) (xy 178.738391 2.416893)
			(xy 178.811297 2.462034) (xy 178.888057 2.500256) (xy 178.968016 2.531232) (xy 179.050492 2.554699)
			(xy 179.134782 2.570455) (xy 179.220165 2.578367) (xy 179.305915 2.578367) (xy 179.391298 2.570455)
			(xy 179.475588 2.554699) (xy 179.558064 2.531232) (xy 179.638023 2.500256) (xy 179.660226 2.4892)
			(xy 183.270652 2.4892) (xy 183.270652 3.3528) (xy 183.271138 3.380069) (xy 183.2789 3.434053) (xy 183.294265 3.486383)
			(xy 183.316922 3.535993) (xy 183.346408 3.581874) (xy 183.382123 3.623091) (xy 183.42334 3.658806)
			(xy 183.469221 3.688292) (xy 183.518831 3.710949) (xy 183.571161 3.726314) (xy 183.625145 3.734076)
			(xy 183.679683 3.734076) (xy 183.733667 3.726314) (xy 183.785997 3.710949) (xy 183.835607 3.688292)
			(xy 183.881488 3.658806) (xy 183.922705 3.623091) (xy 183.95842 3.581874) (xy 183.987906 3.535993)
			(xy 184.010563 3.486383) (xy 184.025928 3.434053) (xy 184.03369 3.380069) (xy 184.034176 3.3528)
			(xy 184.034176 2.4892) (xy 184.03369 2.461931) (xy 184.025928 2.407947) (xy 184.010563 2.355617)
			(xy 183.987906 2.306007) (xy 183.95842 2.260126) (xy 183.922705 2.218909) (xy 183.881488 2.183194)
			(xy 183.835607 2.153708) (xy 183.785997 2.131051) (xy 183.733667 2.115686) (xy 183.679683 2.107924)
			(xy 183.625145 2.107924) (xy 183.571161 2.115686) (xy 183.518831 2.131051) (xy 183.469221 2.153708)
			(xy 183.42334 2.183194) (xy 183.382123 2.218909) (xy 183.346408 2.260126) (xy 183.316922 2.306007)
			(xy 183.294265 2.355617) (xy 183.2789 2.407947) (xy 183.271138 2.461931) (xy 183.270652 2.4892) (xy 179.660226 2.4892)
			(xy 179.714783 2.462034) (xy 179.787689 2.416893) (xy 179.856118 2.365217) (xy 179.919488 2.307448)
			(xy 179.977257 2.244078) (xy 180.028933 2.175649) (xy 180.074074 2.102743) (xy 180.112296 2.025983)
			(xy 180.143272 1.946024) (xy 180.166739 1.863548) (xy 180.182495 1.779258) (xy 180.190407 1.693875)
			(xy 180.190902 1.651) (xy 180.190407 1.608125) (xy 184.685673 1.608125) (xy 184.685673 1.693875)
			(xy 184.693585 1.779258) (xy 184.709341 1.863548) (xy 184.732808 1.946024) (xy 184.763784 2.025983)
			(xy 184.802006 2.102743) (xy 184.847147 2.175649) (xy 184.898823 2.244078) (xy 184.956592 2.307448)
			(xy 185.019962 2.365217) (xy 185.088391 2.416893) (xy 185.161297 2.462034) (xy 185.238057 2.500256)
			(xy 185.318016 2.531232) (xy 185.400492 2.554699) (xy 185.484782 2.570455) (xy 185.570165 2.578367)
			(xy 185.655915 2.578367) (xy 185.741298 2.570455) (xy 185.825588 2.554699) (xy 185.908064 2.531232)
			(xy 185.988023 2.500256) (xy 186.064783 2.462034) (xy 186.137689 2.416893) (xy 186.206118 2.365217)
			(xy 186.269488 2.307448) (xy 186.327257 2.244078) (xy 186.378933 2.175649) (xy 186.424074 2.102743)
			(xy 186.462296 2.025983) (xy 186.493272 1.946024) (xy 186.516739 1.863548) (xy 186.532495 1.779258)
			(xy 186.540407 1.693875) (xy 186.540902 1.651) (xy 186.540407 1.608125) (xy 246.260353 1.608125)
			(xy 246.260353 1.693875) (xy 246.268265 1.779258) (xy 246.284021 1.863548) (xy 246.307488 1.946024)
			(xy 246.338464 2.025983) (xy 246.376686 2.102743) (xy 246.421827 2.175649) (xy 246.473503 2.244078)
			(xy 246.531272 2.307448) (xy 246.594642 2.365217) (xy 246.663071 2.416893) (xy 246.735977 2.462034)
			(xy 246.812737 2.500256) (xy 246.892696 2.531232) (xy 246.975172 2.554699) (xy 247.059462 2.570455)
			(xy 247.144845 2.578367) (xy 247.230595 2.578367) (xy 247.315978 2.570455) (xy 247.400268 2.554699)
			(xy 247.482744 2.531232) (xy 247.562703 2.500256) (xy 247.584906 2.4892) (xy 248.766584 2.4892) (xy 248.766584 3.3528)
			(xy 248.76707 3.380069) (xy 248.774832 3.434053) (xy 248.790197 3.486383) (xy 248.812854 3.535993)
			(xy 248.84234 3.581874) (xy 248.878055 3.623091) (xy 248.919272 3.658806) (xy 248.965153 3.688292)
			(xy 249.014763 3.710949) (xy 249.067093 3.726314) (xy 249.121077 3.734076) (xy 249.175615 3.734076)
			(xy 249.229599 3.726314) (xy 249.281929 3.710949) (xy 249.331539 3.688292) (xy 249.37742 3.658806)
			(xy 249.418637 3.623091) (xy 249.454352 3.581874) (xy 249.483838 3.535993) (xy 249.506495 3.486383)
			(xy 249.52186 3.434053) (xy 249.529622 3.380069) (xy 249.530108 3.3528) (xy 249.530108 2.4892) (xy 249.529622 2.461931)
			(xy 249.52186 2.407947) (xy 249.506495 2.355617) (xy 249.483838 2.306007) (xy 249.454352 2.260126)
			(xy 249.418637 2.218909) (xy 249.37742 2.183194) (xy 249.331539 2.153708) (xy 249.281929 2.131051)
			(xy 249.229599 2.115686) (xy 249.175615 2.107924) (xy 249.121077 2.107924) (xy 249.067093 2.115686)
			(xy 249.014763 2.131051) (xy 248.965153 2.153708) (xy 248.919272 2.183194) (xy 248.878055 2.218909)
			(xy 248.84234 2.260126) (xy 248.812854 2.306007) (xy 248.790197 2.355617) (xy 248.774832 2.407947)
			(xy 248.76707 2.461931) (xy 248.766584 2.4892) (xy 247.584906 2.4892) (xy 247.639463 2.462034) (xy 247.712369 2.416893)
			(xy 247.780798 2.365217) (xy 247.844168 2.307448) (xy 247.901937 2.244078) (xy 247.953613 2.175649)
			(xy 247.998754 2.102743) (xy 248.036976 2.025983) (xy 248.067952 1.946024) (xy 248.091419 1.863548)
			(xy 248.107175 1.779258) (xy 248.115087 1.693875) (xy 248.115582 1.651) (xy 248.115087 1.608125)
			(xy 252.610353 1.608125) (xy 252.610353 1.693875) (xy 252.618265 1.779258) (xy 252.634021 1.863548)
			(xy 252.657488 1.946024) (xy 252.688464 2.025983) (xy 252.726686 2.102743) (xy 252.771827 2.175649)
			(xy 252.823503 2.244078) (xy 252.881272 2.307448) (xy 252.944642 2.365217) (xy 253.013071 2.416893)
			(xy 253.085977 2.462034) (xy 253.162737 2.500256) (xy 253.242696 2.531232) (xy 253.325172 2.554699)
			(xy 253.409462 2.570455) (xy 253.494845 2.578367) (xy 253.580595 2.578367) (xy 253.665978 2.570455)
			(xy 253.750268 2.554699) (xy 253.832744 2.531232) (xy 253.912703 2.500256) (xy 253.989463 2.462034)
			(xy 254.062369 2.416893) (xy 254.130798 2.365217) (xy 254.194168 2.307448) (xy 254.251937 2.244078)
			(xy 254.303613 2.175649) (xy 254.348754 2.102743) (xy 254.386976 2.025983) (xy 254.417952 1.946024)
			(xy 254.441419 1.863548) (xy 254.457175 1.779258) (xy 254.465087 1.693875) (xy 254.465582 1.651)
			(xy 254.465119 1.610919) (xy 256.921241 1.610919) (xy 256.921241 1.696669) (xy 256.929153 1.782052)
			(xy 256.944909 1.866342) (xy 256.968376 1.948818) (xy 256.999352 2.028777) (xy 257.037574 2.105537)
			(xy 257.082715 2.178443) (xy 257.134391 2.246872) (xy 257.19216 2.310242) (xy 257.25553 2.368011)
			(xy 257.323959 2.419687) (xy 257.396865 2.464828) (xy 257.473625 2.50305) (xy 257.553584 2.534026)
			(xy 257.63606 2.557493) (xy 257.72035 2.573249) (xy 257.805733 2.581161) (xy 257.891483 2.581161)
			(xy 257.976866 2.573249) (xy 258.061156 2.557493) (xy 258.143632 2.534026) (xy 258.223591 2.50305)
			(xy 258.245794 2.491994) (xy 261.85622 2.491994) (xy 261.85622 3.355594) (xy 261.856706 3.382863)
			(xy 261.864468 3.436847) (xy 261.879833 3.489177) (xy 261.90249 3.538787) (xy 261.931976 3.584668)
			(xy 261.967691 3.625885) (xy 262.008908 3.6616) (xy 262.054789 3.691086) (xy 262.104399 3.713743)
			(xy 262.156729 3.729108) (xy 262.210713 3.73687) (xy 262.265251 3.73687) (xy 262.319235 3.729108)
			(xy 262.371565 3.713743) (xy 262.421175 3.691086) (xy 262.467056 3.6616) (xy 262.508273 3.625885)
			(xy 262.543988 3.584668) (xy 262.573474 3.538787) (xy 262.596131 3.489177) (xy 262.611496 3.436847)
			(xy 262.619258 3.382863) (xy 262.619744 3.355594) (xy 262.619744 2.491994) (xy 262.619258 2.464725)
			(xy 262.611496 2.410741) (xy 262.596131 2.358411) (xy 262.573474 2.308801) (xy 262.543988 2.26292)
			(xy 262.508273 2.221703) (xy 262.467056 2.185988) (xy 262.421175 2.156502) (xy 262.371565 2.133845)
			(xy 262.319235 2.11848) (xy 262.265251 2.110718) (xy 262.210713 2.110718) (xy 262.156729 2.11848)
			(xy 262.104399 2.133845) (xy 262.054789 2.156502) (xy 262.008908 2.185988) (xy 261.967691 2.221703)
			(xy 261.931976 2.26292) (xy 261.90249 2.308801) (xy 261.879833 2.358411) (xy 261.864468 2.410741)
			(xy 261.856706 2.464725) (xy 261.85622 2.491994) (xy 258.245794 2.491994) (xy 258.300351 2.464828)
			(xy 258.373257 2.419687) (xy 258.441686 2.368011) (xy 258.505056 2.310242) (xy 258.562825 2.246872)
			(xy 258.614501 2.178443) (xy 258.659642 2.105537) (xy 258.697864 2.028777) (xy 258.72884 1.948818)
			(xy 258.752307 1.866342) (xy 258.768063 1.782052) (xy 258.775975 1.696669) (xy 258.77647 1.653794)
			(xy 258.775975 1.610919) (xy 263.271241 1.610919) (xy 263.271241 1.696669) (xy 263.279153 1.782052)
			(xy 263.294909 1.866342) (xy 263.318376 1.948818) (xy 263.349352 2.028777) (xy 263.387574 2.105537)
			(xy 263.432715 2.178443) (xy 263.484391 2.246872) (xy 263.54216 2.310242) (xy 263.60553 2.368011)
			(xy 263.673959 2.419687) (xy 263.746865 2.464828) (xy 263.823625 2.50305) (xy 263.903584 2.534026)
			(xy 263.98606 2.557493) (xy 264.07035 2.573249) (xy 264.155733 2.581161) (xy 264.241483 2.581161)
			(xy 264.326866 2.573249) (xy 264.411156 2.557493) (xy 264.493632 2.534026) (xy 264.573591 2.50305)
			(xy 264.650351 2.464828) (xy 264.723257 2.419687) (xy 264.791686 2.368011) (xy 264.855056 2.310242)
			(xy 264.912825 2.246872) (xy 264.964501 2.178443) (xy 265.009642 2.105537) (xy 265.047864 2.028777)
			(xy 265.07884 1.948818) (xy 265.102307 1.866342) (xy 265.118063 1.782052) (xy 265.125975 1.696669)
			(xy 265.12647 1.653794) (xy 265.125975 1.610919) (xy 324.845921 1.610919) (xy 324.845921 1.696669)
			(xy 324.853833 1.782052) (xy 324.869589 1.866342) (xy 324.893056 1.948818) (xy 324.924032 2.028777)
			(xy 324.962254 2.105537) (xy 325.007395 2.178443) (xy 325.059071 2.246872) (xy 325.11684 2.310242)
			(xy 325.18021 2.368011) (xy 325.248639 2.419687) (xy 325.321545 2.464828) (xy 325.398305 2.50305)
			(xy 325.478264 2.534026) (xy 325.56074 2.557493) (xy 325.64503 2.573249) (xy 325.730413 2.581161)
			(xy 325.816163 2.581161) (xy 325.901546 2.573249) (xy 325.985836 2.557493) (xy 326.068312 2.534026)
			(xy 326.148271 2.50305) (xy 326.170474 2.491994) (xy 327.352152 2.491994) (xy 327.352152 3.355594)
			(xy 327.352638 3.382863) (xy 327.3604 3.436847) (xy 327.375765 3.489177) (xy 327.398422 3.538787)
			(xy 327.427908 3.584668) (xy 327.463623 3.625885) (xy 327.50484 3.6616) (xy 327.550721 3.691086)
			(xy 327.600331 3.713743) (xy 327.652661 3.729108) (xy 327.706645 3.73687) (xy 327.761183 3.73687)
			(xy 327.815167 3.729108) (xy 327.867497 3.713743) (xy 327.917107 3.691086) (xy 327.962988 3.6616)
			(xy 328.004205 3.625885) (xy 328.03992 3.584668) (xy 328.069406 3.538787) (xy 328.092063 3.489177)
			(xy 328.107428 3.436847) (xy 328.11519 3.382863) (xy 328.115676 3.355594) (xy 328.115676 2.491994)
			(xy 328.11519 2.464725) (xy 328.107428 2.410741) (xy 328.092063 2.358411) (xy 328.069406 2.308801)
			(xy 328.03992 2.26292) (xy 328.004205 2.221703) (xy 327.962988 2.185988) (xy 327.917107 2.156502)
			(xy 327.867497 2.133845) (xy 327.815167 2.11848) (xy 327.761183 2.110718) (xy 327.706645 2.110718)
			(xy 327.652661 2.11848) (xy 327.600331 2.133845) (xy 327.550721 2.156502) (xy 327.50484 2.185988)
			(xy 327.463623 2.221703) (xy 327.427908 2.26292) (xy 327.398422 2.308801) (xy 327.375765 2.358411)
			(xy 327.3604 2.410741) (xy 327.352638 2.464725) (xy 327.352152 2.491994) (xy 326.170474 2.491994)
			(xy 326.225031 2.464828) (xy 326.297937 2.419687) (xy 326.366366 2.368011) (xy 326.429736 2.310242)
			(xy 326.487505 2.246872) (xy 326.539181 2.178443) (xy 326.584322 2.105537) (xy 326.622544 2.028777)
			(xy 326.65352 1.948818) (xy 326.676987 1.866342) (xy 326.692743 1.782052) (xy 326.700655 1.696669)
			(xy 326.70115 1.653794) (xy 326.700655 1.610919) (xy 331.195921 1.610919) (xy 331.195921 1.696669)
			(xy 331.203833 1.782052) (xy 331.219589 1.866342) (xy 331.243056 1.948818) (xy 331.274032 2.028777)
			(xy 331.312254 2.105537) (xy 331.357395 2.178443) (xy 331.409071 2.246872) (xy 331.46684 2.310242)
			(xy 331.53021 2.368011) (xy 331.598639 2.419687) (xy 331.671545 2.464828) (xy 331.748305 2.50305)
			(xy 331.828264 2.534026) (xy 331.91074 2.557493) (xy 331.99503 2.573249) (xy 332.080413 2.581161)
			(xy 332.166163 2.581161) (xy 332.251546 2.573249) (xy 332.335836 2.557493) (xy 332.418312 2.534026)
			(xy 332.498271 2.50305) (xy 332.575031 2.464828) (xy 332.647937 2.419687) (xy 332.716366 2.368011)
			(xy 332.779736 2.310242) (xy 332.837505 2.246872) (xy 332.889181 2.178443) (xy 332.934322 2.105537)
			(xy 332.972544 2.028777) (xy 333.00352 1.948818) (xy 333.026987 1.866342) (xy 333.042743 1.782052)
			(xy 333.050655 1.696669) (xy 333.05115 1.653794) (xy 333.050655 1.610919) (xy 335.488267 1.610919)
			(xy 335.488267 1.696669) (xy 335.496179 1.782052) (xy 335.511935 1.866342) (xy 335.535402 1.948818)
			(xy 335.566378 2.028777) (xy 335.6046 2.105537) (xy 335.649741 2.178443) (xy 335.701417 2.246872)
			(xy 335.759186 2.310242) (xy 335.822556 2.368011) (xy 335.890985 2.419687) (xy 335.963891 2.464828)
			(xy 336.040651 2.50305) (xy 336.12061 2.534026) (xy 336.203086 2.557493) (xy 336.287376 2.573249)
			(xy 336.372759 2.581161) (xy 336.458509 2.581161) (xy 336.543892 2.573249) (xy 336.628182 2.557493)
			(xy 336.710658 2.534026) (xy 336.790617 2.50305) (xy 336.81282 2.491994) (xy 340.4235 2.491994) (xy 340.4235 3.355594)
			(xy 340.423986 3.382845) (xy 340.431742 3.436793) (xy 340.447097 3.489088) (xy 340.469739 3.538665)
			(xy 340.499205 3.584515) (xy 340.534896 3.625706) (xy 340.576087 3.661397) (xy 340.621937 3.690863)
			(xy 340.671514 3.713505) (xy 340.723809 3.72886) (xy 340.777757 3.736616) (xy 340.832259 3.736616)
			(xy 340.886207 3.72886) (xy 340.938502 3.713505) (xy 340.988079 3.690863) (xy 341.033929 3.661397)
			(xy 341.07512 3.625706) (xy 341.110811 3.584515) (xy 341.140277 3.538665) (xy 341.162919 3.489088)
			(xy 341.178274 3.436793) (xy 341.18603 3.382845) (xy 341.186516 3.355594) (xy 341.186516 2.491994)
			(xy 341.18603 2.464743) (xy 341.178274 2.410795) (xy 341.162919 2.3585) (xy 341.140277 2.308923)
			(xy 341.110811 2.263073) (xy 341.07512 2.221882) (xy 341.033929 2.186191) (xy 340.988079 2.156725)
			(xy 340.938502 2.134083) (xy 340.886207 2.118728) (xy 340.832259 2.110972) (xy 340.777757 2.110972)
			(xy 340.723809 2.118728) (xy 340.671514 2.134083) (xy 340.621937 2.156725) (xy 340.576087 2.186191)
			(xy 340.534896 2.221882) (xy 340.499205 2.263073) (xy 340.469739 2.308923) (xy 340.447097 2.3585)
			(xy 340.431742 2.410795) (xy 340.423986 2.464743) (xy 340.4235 2.491994) (xy 336.81282 2.491994)
			(xy 336.867377 2.464828) (xy 336.940283 2.419687) (xy 337.008712 2.368011) (xy 337.072082 2.310242)
			(xy 337.129851 2.246872) (xy 337.181527 2.178443) (xy 337.226668 2.105537) (xy 337.26489 2.028777)
			(xy 337.295866 1.948818) (xy 337.319333 1.866342) (xy 337.335089 1.782052) (xy 337.343001 1.696669)
			(xy 337.343496 1.653794) (xy 337.343001 1.610919) (xy 341.838267 1.610919) (xy 341.838267 1.696669)
			(xy 341.846179 1.782052) (xy 341.861935 1.866342) (xy 341.885402 1.948818) (xy 341.916378 2.028777)
			(xy 341.9546 2.105537) (xy 341.999741 2.178443) (xy 342.051417 2.246872) (xy 342.109186 2.310242)
			(xy 342.172556 2.368011) (xy 342.240985 2.419687) (xy 342.313891 2.464828) (xy 342.390651 2.50305)
			(xy 342.47061 2.534026) (xy 342.553086 2.557493) (xy 342.637376 2.573249) (xy 342.722759 2.581161)
			(xy 342.808509 2.581161) (xy 342.893892 2.573249) (xy 342.978182 2.557493) (xy 343.060658 2.534026)
			(xy 343.140617 2.50305) (xy 343.217377 2.464828) (xy 343.290283 2.419687) (xy 343.358712 2.368011)
			(xy 343.422082 2.310242) (xy 343.479851 2.246872) (xy 343.531527 2.178443) (xy 343.576668 2.105537)
			(xy 343.61489 2.028777) (xy 343.645866 1.948818) (xy 343.669333 1.866342) (xy 343.685089 1.782052)
			(xy 343.693001 1.696669) (xy 343.693496 1.653794) (xy 343.693001 1.610919) (xy 373.705107 1.610919)
			(xy 373.705107 1.696669) (xy 373.713019 1.782052) (xy 373.728775 1.866342) (xy 373.752242 1.948818)
			(xy 373.783218 2.028777) (xy 373.82144 2.105537) (xy 373.866581 2.178443) (xy 373.918257 2.246872)
			(xy 373.976026 2.310242) (xy 374.039396 2.368011) (xy 374.107825 2.419687) (xy 374.180731 2.464828)
			(xy 374.257491 2.50305) (xy 374.33745 2.534026) (xy 374.419926 2.557493) (xy 374.504216 2.573249)
			(xy 374.589599 2.581161) (xy 374.675349 2.581161) (xy 374.760732 2.573249) (xy 374.845022 2.557493)
			(xy 374.927498 2.534026) (xy 375.007457 2.50305) (xy 375.02966 2.491994) (xy 376.211592 2.491994)
			(xy 376.211592 3.355594) (xy 376.212078 3.382845) (xy 376.219834 3.436793) (xy 376.235189 3.489088)
			(xy 376.257831 3.538665) (xy 376.287297 3.584515) (xy 376.322988 3.625706) (xy 376.364179 3.661397)
			(xy 376.410029 3.690863) (xy 376.459606 3.713505) (xy 376.511901 3.72886) (xy 376.565849 3.736616)
			(xy 376.620351 3.736616) (xy 376.674299 3.72886) (xy 376.726594 3.713505) (xy 376.776171 3.690863)
			(xy 376.822021 3.661397) (xy 376.863212 3.625706) (xy 376.898903 3.584515) (xy 376.928369 3.538665)
			(xy 376.951011 3.489088) (xy 376.966366 3.436793) (xy 376.974122 3.382845) (xy 376.974608 3.355594)
			(xy 376.974608 2.491994) (xy 376.974122 2.464743) (xy 376.966366 2.410795) (xy 376.951011 2.3585)
			(xy 376.928369 2.308923) (xy 376.898903 2.263073) (xy 376.863212 2.221882) (xy 376.822021 2.186191)
			(xy 376.776171 2.156725) (xy 376.726594 2.134083) (xy 376.674299 2.118728) (xy 376.620351 2.110972)
			(xy 376.565849 2.110972) (xy 376.511901 2.118728) (xy 376.459606 2.134083) (xy 376.410029 2.156725)
			(xy 376.364179 2.186191) (xy 376.322988 2.221882) (xy 376.287297 2.263073) (xy 376.257831 2.308923)
			(xy 376.235189 2.3585) (xy 376.219834 2.410795) (xy 376.212078 2.464743) (xy 376.211592 2.491994)
			(xy 375.02966 2.491994) (xy 375.084217 2.464828) (xy 375.157123 2.419687) (xy 375.225552 2.368011)
			(xy 375.288922 2.310242) (xy 375.346691 2.246872) (xy 375.398367 2.178443) (xy 375.443508 2.105537)
			(xy 375.48173 2.028777) (xy 375.512706 1.948818) (xy 375.536173 1.866342) (xy 375.551929 1.782052)
			(xy 375.559841 1.696669) (xy 375.560336 1.653794) (xy 375.559841 1.610919) (xy 380.055107 1.610919)
			(xy 380.055107 1.696669) (xy 380.063019 1.782052) (xy 380.078775 1.866342) (xy 380.102242 1.948818)
			(xy 380.133218 2.028777) (xy 380.17144 2.105537) (xy 380.216581 2.178443) (xy 380.268257 2.246872)
			(xy 380.326026 2.310242) (xy 380.389396 2.368011) (xy 380.457825 2.419687) (xy 380.530731 2.464828)
			(xy 380.607491 2.50305) (xy 380.68745 2.534026) (xy 380.769926 2.557493) (xy 380.854216 2.573249)
			(xy 380.939599 2.581161) (xy 381.025349 2.581161) (xy 381.110732 2.573249) (xy 381.195022 2.557493)
			(xy 381.277498 2.534026) (xy 381.357457 2.50305) (xy 381.434217 2.464828) (xy 381.507123 2.419687)
			(xy 381.575552 2.368011) (xy 381.638922 2.310242) (xy 381.696691 2.246872) (xy 381.748367 2.178443)
			(xy 381.793508 2.105537) (xy 381.83173 2.028777) (xy 381.862706 1.948818) (xy 381.886173 1.866342)
			(xy 381.901929 1.782052) (xy 381.909841 1.696669) (xy 381.910336 1.653794) (xy 381.909841 1.610919)
			(xy 381.901929 1.525536) (xy 381.886173 1.441246) (xy 381.862706 1.35877) (xy 381.83173 1.278811)
			(xy 381.793508 1.202051) (xy 381.748367 1.129145) (xy 381.696691 1.060716) (xy 381.638922 0.997346)
			(xy 381.575552 0.939577) (xy 381.507123 0.887901) (xy 381.434217 0.84276) (xy 381.357457 0.804538)
			(xy 381.277498 0.773562) (xy 381.195022 0.750095) (xy 381.110732 0.734339) (xy 381.025349 0.726427)
			(xy 380.939599 0.726427) (xy 380.854216 0.734339) (xy 380.769926 0.750095) (xy 380.68745 0.773562)
			(xy 380.607491 0.804538) (xy 380.530731 0.84276) (xy 380.457825 0.887901) (xy 380.389396 0.939577)
			(xy 380.326026 0.997346) (xy 380.268257 1.060716) (xy 380.216581 1.129145) (xy 380.17144 1.202051)
			(xy 380.133218 1.278811) (xy 380.102242 1.35877) (xy 380.078775 1.441246) (xy 380.063019 1.525536)
			(xy 380.055107 1.610919) (xy 375.559841 1.610919) (xy 375.551929 1.525536) (xy 375.536173 1.441246)
			(xy 375.512706 1.35877) (xy 375.48173 1.278811) (xy 375.443508 1.202051) (xy 375.398367 1.129145)
			(xy 375.346691 1.060716) (xy 375.288922 0.997346) (xy 375.225552 0.939577) (xy 375.157123 0.887901)
			(xy 375.084217 0.84276) (xy 375.007457 0.804538) (xy 374.927498 0.773562) (xy 374.845022 0.750095)
			(xy 374.760732 0.734339) (xy 374.675349 0.726427) (xy 374.589599 0.726427) (xy 374.504216 0.734339)
			(xy 374.419926 0.750095) (xy 374.33745 0.773562) (xy 374.257491 0.804538) (xy 374.180731 0.84276)
			(xy 374.107825 0.887901) (xy 374.039396 0.939577) (xy 373.976026 0.997346) (xy 373.918257 1.060716)
			(xy 373.866581 1.129145) (xy 373.82144 1.202051) (xy 373.783218 1.278811) (xy 373.752242 1.35877)
			(xy 373.728775 1.441246) (xy 373.713019 1.525536) (xy 373.705107 1.610919) (xy 343.693001 1.610919)
			(xy 343.685089 1.525536) (xy 343.669333 1.441246) (xy 343.645866 1.35877) (xy 343.61489 1.278811)
			(xy 343.576668 1.202051) (xy 343.531527 1.129145) (xy 343.479851 1.060716) (xy 343.422082 0.997346)
			(xy 343.358712 0.939577) (xy 343.290283 0.887901) (xy 343.217377 0.84276) (xy 343.140617 0.804538)
			(xy 343.060658 0.773562) (xy 342.978182 0.750095) (xy 342.893892 0.734339) (xy 342.808509 0.726427)
			(xy 342.722759 0.726427) (xy 342.637376 0.734339) (xy 342.553086 0.750095) (xy 342.47061 0.773562)
			(xy 342.390651 0.804538) (xy 342.313891 0.84276) (xy 342.240985 0.887901) (xy 342.172556 0.939577)
			(xy 342.109186 0.997346) (xy 342.051417 1.060716) (xy 341.999741 1.129145) (xy 341.9546 1.202051)
			(xy 341.916378 1.278811) (xy 341.885402 1.35877) (xy 341.861935 1.441246) (xy 341.846179 1.525536)
			(xy 341.838267 1.610919) (xy 337.343001 1.610919) (xy 337.335089 1.525536) (xy 337.319333 1.441246)
			(xy 337.295866 1.35877) (xy 337.26489 1.278811) (xy 337.226668 1.202051) (xy 337.181527 1.129145)
			(xy 337.129851 1.060716) (xy 337.072082 0.997346) (xy 337.008712 0.939577) (xy 336.940283 0.887901)
			(xy 336.867377 0.84276) (xy 336.790617 0.804538) (xy 336.710658 0.773562) (xy 336.628182 0.750095)
			(xy 336.543892 0.734339) (xy 336.458509 0.726427) (xy 336.372759 0.726427) (xy 336.287376 0.734339)
			(xy 336.203086 0.750095) (xy 336.12061 0.773562) (xy 336.040651 0.804538) (xy 335.963891 0.84276)
			(xy 335.890985 0.887901) (xy 335.822556 0.939577) (xy 335.759186 0.997346) (xy 335.701417 1.060716)
			(xy 335.649741 1.129145) (xy 335.6046 1.202051) (xy 335.566378 1.278811) (xy 335.535402 1.35877)
			(xy 335.511935 1.441246) (xy 335.496179 1.525536) (xy 335.488267 1.610919) (xy 333.050655 1.610919)
			(xy 333.042743 1.525536) (xy 333.026987 1.441246) (xy 333.00352 1.35877) (xy 332.972544 1.278811)
			(xy 332.934322 1.202051) (xy 332.889181 1.129145) (xy 332.837505 1.060716) (xy 332.779736 0.997346)
			(xy 332.716366 0.939577) (xy 332.647937 0.887901) (xy 332.575031 0.84276) (xy 332.498271 0.804538)
			(xy 332.418312 0.773562) (xy 332.335836 0.750095) (xy 332.251546 0.734339) (xy 332.166163 0.726427)
			(xy 332.080413 0.726427) (xy 331.99503 0.734339) (xy 331.91074 0.750095) (xy 331.828264 0.773562)
			(xy 331.748305 0.804538) (xy 331.671545 0.84276) (xy 331.598639 0.887901) (xy 331.53021 0.939577)
			(xy 331.46684 0.997346) (xy 331.409071 1.060716) (xy 331.357395 1.129145) (xy 331.312254 1.202051)
			(xy 331.274032 1.278811) (xy 331.243056 1.35877) (xy 331.219589 1.441246) (xy 331.203833 1.525536)
			(xy 331.195921 1.610919) (xy 326.700655 1.610919) (xy 326.692743 1.525536) (xy 326.676987 1.441246)
			(xy 326.65352 1.35877) (xy 326.622544 1.278811) (xy 326.584322 1.202051) (xy 326.539181 1.129145)
			(xy 326.487505 1.060716) (xy 326.429736 0.997346) (xy 326.366366 0.939577) (xy 326.297937 0.887901)
			(xy 326.225031 0.84276) (xy 326.148271 0.804538) (xy 326.068312 0.773562) (xy 325.985836 0.750095)
			(xy 325.901546 0.734339) (xy 325.816163 0.726427) (xy 325.730413 0.726427) (xy 325.64503 0.734339)
			(xy 325.56074 0.750095) (xy 325.478264 0.773562) (xy 325.398305 0.804538) (xy 325.321545 0.84276)
			(xy 325.248639 0.887901) (xy 325.18021 0.939577) (xy 325.11684 0.997346) (xy 325.059071 1.060716)
			(xy 325.007395 1.129145) (xy 324.962254 1.202051) (xy 324.924032 1.278811) (xy 324.893056 1.35877)
			(xy 324.869589 1.441246) (xy 324.853833 1.525536) (xy 324.845921 1.610919) (xy 265.125975 1.610919)
			(xy 265.118063 1.525536) (xy 265.102307 1.441246) (xy 265.07884 1.35877) (xy 265.047864 1.278811)
			(xy 265.009642 1.202051) (xy 264.964501 1.129145) (xy 264.912825 1.060716) (xy 264.855056 0.997346)
			(xy 264.791686 0.939577) (xy 264.723257 0.887901) (xy 264.650351 0.84276) (xy 264.573591 0.804538)
			(xy 264.493632 0.773562) (xy 264.411156 0.750095) (xy 264.326866 0.734339) (xy 264.241483 0.726427)
			(xy 264.155733 0.726427) (xy 264.07035 0.734339) (xy 263.98606 0.750095) (xy 263.903584 0.773562)
			(xy 263.823625 0.804538) (xy 263.746865 0.84276) (xy 263.673959 0.887901) (xy 263.60553 0.939577)
			(xy 263.54216 0.997346) (xy 263.484391 1.060716) (xy 263.432715 1.129145) (xy 263.387574 1.202051)
			(xy 263.349352 1.278811) (xy 263.318376 1.35877) (xy 263.294909 1.441246) (xy 263.279153 1.525536)
			(xy 263.271241 1.610919) (xy 258.775975 1.610919) (xy 258.768063 1.525536) (xy 258.752307 1.441246)
			(xy 258.72884 1.35877) (xy 258.697864 1.278811) (xy 258.659642 1.202051) (xy 258.614501 1.129145)
			(xy 258.562825 1.060716) (xy 258.505056 0.997346) (xy 258.441686 0.939577) (xy 258.373257 0.887901)
			(xy 258.300351 0.84276) (xy 258.223591 0.804538) (xy 258.143632 0.773562) (xy 258.061156 0.750095)
			(xy 257.976866 0.734339) (xy 257.891483 0.726427) (xy 257.805733 0.726427) (xy 257.72035 0.734339)
			(xy 257.63606 0.750095) (xy 257.553584 0.773562) (xy 257.473625 0.804538) (xy 257.396865 0.84276)
			(xy 257.323959 0.887901) (xy 257.25553 0.939577) (xy 257.19216 0.997346) (xy 257.134391 1.060716)
			(xy 257.082715 1.129145) (xy 257.037574 1.202051) (xy 256.999352 1.278811) (xy 256.968376 1.35877)
			(xy 256.944909 1.441246) (xy 256.929153 1.525536) (xy 256.921241 1.610919) (xy 254.465119 1.610919)
			(xy 254.465087 1.608125) (xy 254.457175 1.522742) (xy 254.441419 1.438452) (xy 254.417952 1.355976)
			(xy 254.386976 1.276017) (xy 254.348754 1.199257) (xy 254.303613 1.126351) (xy 254.251937 1.057922)
			(xy 254.194168 0.994552) (xy 254.130798 0.936783) (xy 254.062369 0.885107) (xy 253.989463 0.839966)
			(xy 253.912703 0.801744) (xy 253.832744 0.770768) (xy 253.750268 0.747301) (xy 253.665978 0.731545)
			(xy 253.580595 0.723633) (xy 253.494845 0.723633) (xy 253.409462 0.731545) (xy 253.325172 0.747301)
			(xy 253.242696 0.770768) (xy 253.162737 0.801744) (xy 253.085977 0.839966) (xy 253.013071 0.885107)
			(xy 252.944642 0.936783) (xy 252.881272 0.994552) (xy 252.823503 1.057922) (xy 252.771827 1.126351)
			(xy 252.726686 1.199257) (xy 252.688464 1.276017) (xy 252.657488 1.355976) (xy 252.634021 1.438452)
			(xy 252.618265 1.522742) (xy 252.610353 1.608125) (xy 248.115087 1.608125) (xy 248.107175 1.522742)
			(xy 248.091419 1.438452) (xy 248.067952 1.355976) (xy 248.036976 1.276017) (xy 247.998754 1.199257)
			(xy 247.953613 1.126351) (xy 247.901937 1.057922) (xy 247.844168 0.994552) (xy 247.780798 0.936783)
			(xy 247.712369 0.885107) (xy 247.639463 0.839966) (xy 247.562703 0.801744) (xy 247.482744 0.770768)
			(xy 247.400268 0.747301) (xy 247.315978 0.731545) (xy 247.230595 0.723633) (xy 247.144845 0.723633)
			(xy 247.059462 0.731545) (xy 246.975172 0.747301) (xy 246.892696 0.770768) (xy 246.812737 0.801744)
			(xy 246.735977 0.839966) (xy 246.663071 0.885107) (xy 246.594642 0.936783) (xy 246.531272 0.994552)
			(xy 246.473503 1.057922) (xy 246.421827 1.126351) (xy 246.376686 1.199257) (xy 246.338464 1.276017)
			(xy 246.307488 1.355976) (xy 246.284021 1.438452) (xy 246.268265 1.522742) (xy 246.260353 1.608125)
			(xy 186.540407 1.608125) (xy 186.532495 1.522742) (xy 186.516739 1.438452) (xy 186.493272 1.355976)
			(xy 186.462296 1.276017) (xy 186.424074 1.199257) (xy 186.378933 1.126351) (xy 186.327257 1.057922)
			(xy 186.269488 0.994552) (xy 186.206118 0.936783) (xy 186.137689 0.885107) (xy 186.064783 0.839966)
			(xy 185.988023 0.801744) (xy 185.908064 0.770768) (xy 185.825588 0.747301) (xy 185.741298 0.731545)
			(xy 185.655915 0.723633) (xy 185.570165 0.723633) (xy 185.484782 0.731545) (xy 185.400492 0.747301)
			(xy 185.318016 0.770768) (xy 185.238057 0.801744) (xy 185.161297 0.839966) (xy 185.088391 0.885107)
			(xy 185.019962 0.936783) (xy 184.956592 0.994552) (xy 184.898823 1.057922) (xy 184.847147 1.126351)
			(xy 184.802006 1.199257) (xy 184.763784 1.276017) (xy 184.732808 1.355976) (xy 184.709341 1.438452)
			(xy 184.693585 1.522742) (xy 184.685673 1.608125) (xy 180.190407 1.608125) (xy 180.182495 1.522742)
			(xy 180.166739 1.438452) (xy 180.143272 1.355976) (xy 180.112296 1.276017) (xy 180.074074 1.199257)
			(xy 180.028933 1.126351) (xy 179.977257 1.057922) (xy 179.919488 0.994552) (xy 179.856118 0.936783)
			(xy 179.787689 0.885107) (xy 179.714783 0.839966) (xy 179.638023 0.801744) (xy 179.558064 0.770768)
			(xy 179.475588 0.747301) (xy 179.391298 0.731545) (xy 179.305915 0.723633) (xy 179.220165 0.723633)
			(xy 179.134782 0.731545) (xy 179.050492 0.747301) (xy 178.968016 0.770768) (xy 178.888057 0.801744)
			(xy 178.811297 0.839966) (xy 178.738391 0.885107) (xy 178.669962 0.936783) (xy 178.606592 0.994552)
			(xy 178.548823 1.057922) (xy 178.497147 1.126351) (xy 178.452006 1.199257) (xy 178.413784 1.276017)
			(xy 178.382808 1.355976) (xy 178.359341 1.438452) (xy 178.343585 1.522742) (xy 178.335673 1.608125)
			(xy 84.135094 1.608125) (xy 84.162197 1.489382) (xy 84.185766 1.350662) (xy 84.20152 1.210839) (xy 84.20941 1.070352)
			(xy 84.20989 0.999998) (xy 84.20989 -0.931875) (xy 208.043513 -0.931875) (xy 208.043513 -0.846125)
			(xy 208.051425 -0.760742) (xy 208.067181 -0.676452) (xy 208.090648 -0.593976) (xy 208.121624 -0.514017)
			(xy 208.159846 -0.437257) (xy 208.204987 -0.364351) (xy 208.256663 -0.295922) (xy 208.314432 -0.232552)
			(xy 208.377802 -0.174783) (xy 208.446231 -0.123107) (xy 208.519137 -0.077966) (xy 208.595897 -0.039744)
			(xy 208.675856 -0.008768) (xy 208.758332 0.014699) (xy 208.842622 0.030455) (xy 208.928005 0.038367)
			(xy 209.013755 0.038367) (xy 209.099138 0.030455) (xy 209.183428 0.014699) (xy 209.265904 -0.008768)
			(xy 209.345863 -0.039744) (xy 209.422623 -0.077966) (xy 209.495529 -0.123107) (xy 209.563958 -0.174783)
			(xy 209.627328 -0.232552) (xy 209.685097 -0.295922) (xy 209.736773 -0.364351) (xy 209.781914 -0.437257)
			(xy 209.820136 -0.514017) (xy 209.851112 -0.593976) (xy 209.874579 -0.676452) (xy 209.890335 -0.760742)
			(xy 209.898247 -0.846125) (xy 209.898742 -0.889) (xy 209.898247 -0.931875) (xy 214.393513 -0.931875)
			(xy 214.393513 -0.846125) (xy 214.401425 -0.760742) (xy 214.417181 -0.676452) (xy 214.440648 -0.593976)
			(xy 214.471624 -0.514017) (xy 214.509846 -0.437257) (xy 214.554987 -0.364351) (xy 214.606663 -0.295922)
			(xy 214.664432 -0.232552) (xy 214.727802 -0.174783) (xy 214.796231 -0.123107) (xy 214.869137 -0.077966)
			(xy 214.945897 -0.039744) (xy 215.025856 -0.008768) (xy 215.108332 0.014699) (xy 215.192622 0.030455)
			(xy 215.278005 0.038367) (xy 215.363755 0.038367) (xy 215.449138 0.030455) (xy 215.533428 0.014699)
			(xy 215.615904 -0.008768) (xy 215.695863 -0.039744) (xy 215.772623 -0.077966) (xy 215.845529 -0.123107)
			(xy 215.913958 -0.174783) (xy 215.977328 -0.232552) (xy 216.035097 -0.295922) (xy 216.086773 -0.364351)
			(xy 216.131914 -0.437257) (xy 216.170136 -0.514017) (xy 216.201112 -0.593976) (xy 216.224579 -0.676452)
			(xy 216.240335 -0.760742) (xy 216.248247 -0.846125) (xy 216.248742 -0.889) (xy 216.248247 -0.931875)
			(xy 246.260353 -0.931875) (xy 246.260353 -0.846125) (xy 246.268265 -0.760742) (xy 246.284021 -0.676452)
			(xy 246.307488 -0.593976) (xy 246.338464 -0.514017) (xy 246.376686 -0.437257) (xy 246.421827 -0.364351)
			(xy 246.473503 -0.295922) (xy 246.531272 -0.232552) (xy 246.594642 -0.174783) (xy 246.663071 -0.123107)
			(xy 246.735977 -0.077966) (xy 246.812737 -0.039744) (xy 246.892696 -0.008768) (xy 246.975172 0.014699)
			(xy 247.059462 0.030455) (xy 247.144845 0.038367) (xy 247.230595 0.038367) (xy 247.315978 0.030455)
			(xy 247.400268 0.014699) (xy 247.482744 -0.008768) (xy 247.562703 -0.039744) (xy 247.639463 -0.077966)
			(xy 247.712369 -0.123107) (xy 247.780798 -0.174783) (xy 247.844168 -0.232552) (xy 247.901937 -0.295922)
			(xy 247.953613 -0.364351) (xy 247.998754 -0.437257) (xy 248.036976 -0.514017) (xy 248.067952 -0.593976)
			(xy 248.091419 -0.676452) (xy 248.107175 -0.760742) (xy 248.115087 -0.846125) (xy 248.115582 -0.889)
			(xy 248.115087 -0.931875) (xy 252.610353 -0.931875) (xy 252.610353 -0.846125) (xy 252.618265 -0.760742)
			(xy 252.634021 -0.676452) (xy 252.657488 -0.593976) (xy 252.688464 -0.514017) (xy 252.726686 -0.437257)
			(xy 252.771827 -0.364351) (xy 252.823503 -0.295922) (xy 252.881272 -0.232552) (xy 252.944642 -0.174783)
			(xy 253.013071 -0.123107) (xy 253.085977 -0.077966) (xy 253.162737 -0.039744) (xy 253.242696 -0.008768)
			(xy 253.325172 0.014699) (xy 253.409462 0.030455) (xy 253.494845 0.038367) (xy 253.580595 0.038367)
			(xy 253.665978 0.030455) (xy 253.750268 0.014699) (xy 253.832744 -0.008768) (xy 253.912703 -0.039744)
			(xy 253.989463 -0.077966) (xy 254.062369 -0.123107) (xy 254.130798 -0.174783) (xy 254.194168 -0.232552)
			(xy 254.251937 -0.295922) (xy 254.303613 -0.364351) (xy 254.348754 -0.437257) (xy 254.386976 -0.514017)
			(xy 254.417952 -0.593976) (xy 254.441419 -0.676452) (xy 254.457175 -0.760742) (xy 254.465087 -0.846125)
			(xy 254.465582 -0.889) (xy 254.465119 -0.929081) (xy 256.921241 -0.929081) (xy 256.921241 -0.843331)
			(xy 256.929153 -0.757948) (xy 256.944909 -0.673658) (xy 256.968376 -0.591182) (xy 256.999352 -0.511223)
			(xy 257.037574 -0.434463) (xy 257.082715 -0.361557) (xy 257.134391 -0.293128) (xy 257.19216 -0.229758)
			(xy 257.25553 -0.171989) (xy 257.323959 -0.120313) (xy 257.396865 -0.075172) (xy 257.473625 -0.03695)
			(xy 257.553584 -0.005974) (xy 257.63606 0.017493) (xy 257.72035 0.033249) (xy 257.805733 0.041161)
			(xy 257.891483 0.041161) (xy 257.976866 0.033249) (xy 258.061156 0.017493) (xy 258.143632 -0.005974)
			(xy 258.223591 -0.03695) (xy 258.245794 -0.048006) (xy 261.85622 -0.048006) (xy 261.85622 0.815594)
			(xy 261.856706 0.842863) (xy 261.864468 0.896847) (xy 261.879833 0.949177) (xy 261.90249 0.998787)
			(xy 261.931976 1.044668) (xy 261.967691 1.085885) (xy 262.008908 1.1216) (xy 262.054789 1.151086)
			(xy 262.104399 1.173743) (xy 262.156729 1.189108) (xy 262.210713 1.19687) (xy 262.265251 1.19687)
			(xy 262.319235 1.189108) (xy 262.371565 1.173743) (xy 262.421175 1.151086) (xy 262.467056 1.1216)
			(xy 262.508273 1.085885) (xy 262.543988 1.044668) (xy 262.573474 0.998787) (xy 262.596131 0.949177)
			(xy 262.611496 0.896847) (xy 262.619258 0.842863) (xy 262.619744 0.815594) (xy 262.619744 -0.048006)
			(xy 262.619258 -0.075275) (xy 262.611496 -0.129259) (xy 262.596131 -0.181589) (xy 262.573474 -0.231199)
			(xy 262.543988 -0.27708) (xy 262.508273 -0.318297) (xy 262.467056 -0.354012) (xy 262.421175 -0.383498)
			(xy 262.371565 -0.406155) (xy 262.319235 -0.42152) (xy 262.265251 -0.429282) (xy 262.210713 -0.429282)
			(xy 262.156729 -0.42152) (xy 262.104399 -0.406155) (xy 262.054789 -0.383498) (xy 262.008908 -0.354012)
			(xy 261.967691 -0.318297) (xy 261.931976 -0.27708) (xy 261.90249 -0.231199) (xy 261.879833 -0.181589)
			(xy 261.864468 -0.129259) (xy 261.856706 -0.075275) (xy 261.85622 -0.048006) (xy 258.245794 -0.048006)
			(xy 258.300351 -0.075172) (xy 258.373257 -0.120313) (xy 258.441686 -0.171989) (xy 258.505056 -0.229758)
			(xy 258.562825 -0.293128) (xy 258.614501 -0.361557) (xy 258.659642 -0.434463) (xy 258.697864 -0.511223)
			(xy 258.72884 -0.591182) (xy 258.752307 -0.673658) (xy 258.768063 -0.757948) (xy 258.775975 -0.843331)
			(xy 258.77647 -0.886206) (xy 258.775975 -0.929081) (xy 263.271241 -0.929081) (xy 263.271241 -0.843331)
			(xy 263.279153 -0.757948) (xy 263.294909 -0.673658) (xy 263.318376 -0.591182) (xy 263.349352 -0.511223)
			(xy 263.387574 -0.434463) (xy 263.432715 -0.361557) (xy 263.484391 -0.293128) (xy 263.54216 -0.229758)
			(xy 263.60553 -0.171989) (xy 263.673959 -0.120313) (xy 263.746865 -0.075172) (xy 263.823625 -0.03695)
			(xy 263.903584 -0.005974) (xy 263.98606 0.017493) (xy 264.07035 0.033249) (xy 264.155733 0.041161)
			(xy 264.241483 0.041161) (xy 264.326866 0.033249) (xy 264.411156 0.017493) (xy 264.493632 -0.005974)
			(xy 264.573591 -0.03695) (xy 264.650351 -0.075172) (xy 264.723257 -0.120313) (xy 264.791686 -0.171989)
			(xy 264.855056 -0.229758) (xy 264.912825 -0.293128) (xy 264.964501 -0.361557) (xy 265.009642 -0.434463)
			(xy 265.047864 -0.511223) (xy 265.07884 -0.591182) (xy 265.102307 -0.673658) (xy 265.118063 -0.757948)
			(xy 265.125975 -0.843331) (xy 265.12647 -0.886206) (xy 265.125975 -0.929081) (xy 324.845921 -0.929081)
			(xy 324.845921 -0.843331) (xy 324.853833 -0.757948) (xy 324.869589 -0.673658) (xy 324.893056 -0.591182)
			(xy 324.924032 -0.511223) (xy 324.962254 -0.434463) (xy 325.007395 -0.361557) (xy 325.059071 -0.293128)
			(xy 325.11684 -0.229758) (xy 325.18021 -0.171989) (xy 325.248639 -0.120313) (xy 325.321545 -0.075172)
			(xy 325.398305 -0.03695) (xy 325.478264 -0.005974) (xy 325.56074 0.017493) (xy 325.64503 0.033249)
			(xy 325.730413 0.041161) (xy 325.816163 0.041161) (xy 325.901546 0.033249) (xy 325.985836 0.017493)
			(xy 326.068312 -0.005974) (xy 326.148271 -0.03695) (xy 326.170474 -0.048006) (xy 327.352152 -0.048006)
			(xy 327.352152 0.815594) (xy 327.352638 0.842863) (xy 327.3604 0.896847) (xy 327.375765 0.949177)
			(xy 327.398422 0.998787) (xy 327.427908 1.044668) (xy 327.463623 1.085885) (xy 327.50484 1.1216)
			(xy 327.550721 1.151086) (xy 327.600331 1.173743) (xy 327.652661 1.189108) (xy 327.706645 1.19687)
			(xy 327.761183 1.19687) (xy 327.815167 1.189108) (xy 327.867497 1.173743) (xy 327.917107 1.151086)
			(xy 327.962988 1.1216) (xy 328.004205 1.085885) (xy 328.03992 1.044668) (xy 328.069406 0.998787)
			(xy 328.092063 0.949177) (xy 328.107428 0.896847) (xy 328.11519 0.842863) (xy 328.115676 0.815594)
			(xy 328.115676 -0.048006) (xy 328.11519 -0.075275) (xy 328.107428 -0.129259) (xy 328.092063 -0.181589)
			(xy 328.069406 -0.231199) (xy 328.03992 -0.27708) (xy 328.004205 -0.318297) (xy 327.962988 -0.354012)
			(xy 327.917107 -0.383498) (xy 327.867497 -0.406155) (xy 327.815167 -0.42152) (xy 327.761183 -0.429282)
			(xy 327.706645 -0.429282) (xy 327.652661 -0.42152) (xy 327.600331 -0.406155) (xy 327.550721 -0.383498)
			(xy 327.50484 -0.354012) (xy 327.463623 -0.318297) (xy 327.427908 -0.27708) (xy 327.398422 -0.231199)
			(xy 327.375765 -0.181589) (xy 327.3604 -0.129259) (xy 327.352638 -0.075275) (xy 327.352152 -0.048006)
			(xy 326.170474 -0.048006) (xy 326.225031 -0.075172) (xy 326.297937 -0.120313) (xy 326.366366 -0.171989)
			(xy 326.429736 -0.229758) (xy 326.487505 -0.293128) (xy 326.539181 -0.361557) (xy 326.584322 -0.434463)
			(xy 326.622544 -0.511223) (xy 326.65352 -0.591182) (xy 326.676987 -0.673658) (xy 326.692743 -0.757948)
			(xy 326.700655 -0.843331) (xy 326.70115 -0.886206) (xy 326.700655 -0.929081) (xy 331.195921 -0.929081)
			(xy 331.195921 -0.843331) (xy 331.203833 -0.757948) (xy 331.219589 -0.673658) (xy 331.243056 -0.591182)
			(xy 331.274032 -0.511223) (xy 331.312254 -0.434463) (xy 331.357395 -0.361557) (xy 331.409071 -0.293128)
			(xy 331.46684 -0.229758) (xy 331.53021 -0.171989) (xy 331.598639 -0.120313) (xy 331.671545 -0.075172)
			(xy 331.748305 -0.03695) (xy 331.828264 -0.005974) (xy 331.91074 0.017493) (xy 331.99503 0.033249)
			(xy 332.080413 0.041161) (xy 332.166163 0.041161) (xy 332.251546 0.033249) (xy 332.335836 0.017493)
			(xy 332.418312 -0.005974) (xy 332.498271 -0.03695) (xy 332.575031 -0.075172) (xy 332.647937 -0.120313)
			(xy 332.716366 -0.171989) (xy 332.779736 -0.229758) (xy 332.837505 -0.293128) (xy 332.889181 -0.361557)
			(xy 332.934322 -0.434463) (xy 332.972544 -0.511223) (xy 333.00352 -0.591182) (xy 333.026987 -0.673658)
			(xy 333.042743 -0.757948) (xy 333.050655 -0.843331) (xy 333.05115 -0.886206) (xy 333.050655 -0.929081)
			(xy 335.488267 -0.929081) (xy 335.488267 -0.843331) (xy 335.496179 -0.757948) (xy 335.511935 -0.673658)
			(xy 335.535402 -0.591182) (xy 335.566378 -0.511223) (xy 335.6046 -0.434463) (xy 335.649741 -0.361557)
			(xy 335.701417 -0.293128) (xy 335.759186 -0.229758) (xy 335.822556 -0.171989) (xy 335.890985 -0.120313)
			(xy 335.963891 -0.075172) (xy 336.040651 -0.03695) (xy 336.12061 -0.005974) (xy 336.203086 0.017493)
			(xy 336.287376 0.033249) (xy 336.372759 0.041161) (xy 336.458509 0.041161) (xy 336.543892 0.033249)
			(xy 336.628182 0.017493) (xy 336.710658 -0.005974) (xy 336.790617 -0.03695) (xy 336.81282 -0.048006)
			(xy 340.4235 -0.048006) (xy 340.4235 0.815594) (xy 340.423986 0.842845) (xy 340.431742 0.896793)
			(xy 340.447097 0.949088) (xy 340.469739 0.998665) (xy 340.499205 1.044515) (xy 340.534896 1.085706)
			(xy 340.576087 1.121397) (xy 340.621937 1.150863) (xy 340.671514 1.173505) (xy 340.723809 1.18886)
			(xy 340.777757 1.196616) (xy 340.832259 1.196616) (xy 340.886207 1.18886) (xy 340.938502 1.173505)
			(xy 340.988079 1.150863) (xy 341.033929 1.121397) (xy 341.07512 1.085706) (xy 341.110811 1.044515)
			(xy 341.140277 0.998665) (xy 341.162919 0.949088) (xy 341.178274 0.896793) (xy 341.18603 0.842845)
			(xy 341.186516 0.815594) (xy 341.186516 -0.048006) (xy 341.18603 -0.075257) (xy 341.178274 -0.129205)
			(xy 341.162919 -0.1815) (xy 341.140277 -0.231077) (xy 341.110811 -0.276927) (xy 341.07512 -0.318118)
			(xy 341.033929 -0.353809) (xy 340.988079 -0.383275) (xy 340.938502 -0.405917) (xy 340.886207 -0.421272)
			(xy 340.832259 -0.429028) (xy 340.777757 -0.429028) (xy 340.723809 -0.421272) (xy 340.671514 -0.405917)
			(xy 340.621937 -0.383275) (xy 340.576087 -0.353809) (xy 340.534896 -0.318118) (xy 340.499205 -0.276927)
			(xy 340.469739 -0.231077) (xy 340.447097 -0.1815) (xy 340.431742 -0.129205) (xy 340.423986 -0.075257)
			(xy 340.4235 -0.048006) (xy 336.81282 -0.048006) (xy 336.867377 -0.075172) (xy 336.940283 -0.120313)
			(xy 337.008712 -0.171989) (xy 337.072082 -0.229758) (xy 337.129851 -0.293128) (xy 337.181527 -0.361557)
			(xy 337.226668 -0.434463) (xy 337.26489 -0.511223) (xy 337.295866 -0.591182) (xy 337.319333 -0.673658)
			(xy 337.335089 -0.757948) (xy 337.343001 -0.843331) (xy 337.343496 -0.886206) (xy 337.343001 -0.929081)
			(xy 341.838267 -0.929081) (xy 341.838267 -0.843331) (xy 341.846179 -0.757948) (xy 341.861935 -0.673658)
			(xy 341.885402 -0.591182) (xy 341.916378 -0.511223) (xy 341.9546 -0.434463) (xy 341.999741 -0.361557)
			(xy 342.051417 -0.293128) (xy 342.109186 -0.229758) (xy 342.172556 -0.171989) (xy 342.240985 -0.120313)
			(xy 342.313891 -0.075172) (xy 342.390651 -0.03695) (xy 342.47061 -0.005974) (xy 342.553086 0.017493)
			(xy 342.637376 0.033249) (xy 342.722759 0.041161) (xy 342.808509 0.041161) (xy 342.893892 0.033249)
			(xy 342.978182 0.017493) (xy 343.060658 -0.005974) (xy 343.140617 -0.03695) (xy 343.217377 -0.075172)
			(xy 343.290283 -0.120313) (xy 343.358712 -0.171989) (xy 343.422082 -0.229758) (xy 343.479851 -0.293128)
			(xy 343.531527 -0.361557) (xy 343.576668 -0.434463) (xy 343.61489 -0.511223) (xy 343.645866 -0.591182)
			(xy 343.669333 -0.673658) (xy 343.685089 -0.757948) (xy 343.693001 -0.843331) (xy 343.693496 -0.886206)
			(xy 343.693001 -0.929081) (xy 373.705107 -0.929081) (xy 373.705107 -0.843331) (xy 373.713019 -0.757948)
			(xy 373.728775 -0.673658) (xy 373.752242 -0.591182) (xy 373.783218 -0.511223) (xy 373.82144 -0.434463)
			(xy 373.866581 -0.361557) (xy 373.918257 -0.293128) (xy 373.976026 -0.229758) (xy 374.039396 -0.171989)
			(xy 374.107825 -0.120313) (xy 374.180731 -0.075172) (xy 374.257491 -0.03695) (xy 374.33745 -0.005974)
			(xy 374.419926 0.017493) (xy 374.504216 0.033249) (xy 374.589599 0.041161) (xy 374.675349 0.041161)
			(xy 374.760732 0.033249) (xy 374.845022 0.017493) (xy 374.927498 -0.005974) (xy 375.007457 -0.03695)
			(xy 375.02966 -0.048006) (xy 376.211592 -0.048006) (xy 376.211592 0.815594) (xy 376.212078 0.842845)
			(xy 376.219834 0.896793) (xy 376.235189 0.949088) (xy 376.257831 0.998665) (xy 376.287297 1.044515)
			(xy 376.322988 1.085706) (xy 376.364179 1.121397) (xy 376.410029 1.150863) (xy 376.459606 1.173505)
			(xy 376.511901 1.18886) (xy 376.565849 1.196616) (xy 376.620351 1.196616) (xy 376.674299 1.18886)
			(xy 376.726594 1.173505) (xy 376.776171 1.150863) (xy 376.822021 1.121397) (xy 376.863212 1.085706)
			(xy 376.898903 1.044515) (xy 376.928369 0.998665) (xy 376.951011 0.949088) (xy 376.966366 0.896793)
			(xy 376.974122 0.842845) (xy 376.974608 0.815594) (xy 376.974608 -0.048006) (xy 376.974122 -0.075257)
			(xy 376.966366 -0.129205) (xy 376.951011 -0.1815) (xy 376.928369 -0.231077) (xy 376.898903 -0.276927)
			(xy 376.863212 -0.318118) (xy 376.822021 -0.353809) (xy 376.776171 -0.383275) (xy 376.726594 -0.405917)
			(xy 376.674299 -0.421272) (xy 376.620351 -0.429028) (xy 376.565849 -0.429028) (xy 376.511901 -0.421272)
			(xy 376.459606 -0.405917) (xy 376.410029 -0.383275) (xy 376.364179 -0.353809) (xy 376.322988 -0.318118)
			(xy 376.287297 -0.276927) (xy 376.257831 -0.231077) (xy 376.235189 -0.1815) (xy 376.219834 -0.129205)
			(xy 376.212078 -0.075257) (xy 376.211592 -0.048006) (xy 375.02966 -0.048006) (xy 375.084217 -0.075172)
			(xy 375.157123 -0.120313) (xy 375.225552 -0.171989) (xy 375.288922 -0.229758) (xy 375.346691 -0.293128)
			(xy 375.398367 -0.361557) (xy 375.443508 -0.434463) (xy 375.48173 -0.511223) (xy 375.512706 -0.591182)
			(xy 375.536173 -0.673658) (xy 375.551929 -0.757948) (xy 375.559841 -0.843331) (xy 375.560336 -0.886206)
			(xy 375.559841 -0.929081) (xy 380.055107 -0.929081) (xy 380.055107 -0.843331) (xy 380.063019 -0.757948)
			(xy 380.078775 -0.673658) (xy 380.102242 -0.591182) (xy 380.133218 -0.511223) (xy 380.17144 -0.434463)
			(xy 380.216581 -0.361557) (xy 380.268257 -0.293128) (xy 380.326026 -0.229758) (xy 380.389396 -0.171989)
			(xy 380.457825 -0.120313) (xy 380.530731 -0.075172) (xy 380.607491 -0.03695) (xy 380.68745 -0.005974)
			(xy 380.769926 0.017493) (xy 380.854216 0.033249) (xy 380.939599 0.041161) (xy 381.025349 0.041161)
			(xy 381.110732 0.033249) (xy 381.195022 0.017493) (xy 381.277498 -0.005974) (xy 381.357457 -0.03695)
			(xy 381.434217 -0.075172) (xy 381.507123 -0.120313) (xy 381.575552 -0.171989) (xy 381.638922 -0.229758)
			(xy 381.696691 -0.293128) (xy 381.748367 -0.361557) (xy 381.793508 -0.434463) (xy 381.83173 -0.511223)
			(xy 381.862706 -0.591182) (xy 381.886173 -0.673658) (xy 381.901929 -0.757948) (xy 381.909841 -0.843331)
			(xy 381.910336 -0.886206) (xy 381.909841 -0.929081) (xy 381.901929 -1.014464) (xy 381.886173 -1.098754)
			(xy 381.862706 -1.18123) (xy 381.83173 -1.261189) (xy 381.793508 -1.337949) (xy 381.748367 -1.410855)
			(xy 381.696691 -1.479284) (xy 381.638922 -1.542654) (xy 381.575552 -1.600423) (xy 381.507123 -1.652099)
			(xy 381.434217 -1.69724) (xy 381.357457 -1.735462) (xy 381.277498 -1.766438) (xy 381.195022 -1.789905)
			(xy 381.110732 -1.805661) (xy 381.025349 -1.813573) (xy 380.939599 -1.813573) (xy 380.854216 -1.805661)
			(xy 380.769926 -1.789905) (xy 380.68745 -1.766438) (xy 380.607491 -1.735462) (xy 380.530731 -1.69724)
			(xy 380.457825 -1.652099) (xy 380.389396 -1.600423) (xy 380.326026 -1.542654) (xy 380.268257 -1.479284)
			(xy 380.216581 -1.410855) (xy 380.17144 -1.337949) (xy 380.133218 -1.261189) (xy 380.102242 -1.18123)
			(xy 380.078775 -1.098754) (xy 380.063019 -1.014464) (xy 380.055107 -0.929081) (xy 375.559841 -0.929081)
			(xy 375.551929 -1.014464) (xy 375.536173 -1.098754) (xy 375.512706 -1.18123) (xy 375.48173 -1.261189)
			(xy 375.443508 -1.337949) (xy 375.398367 -1.410855) (xy 375.346691 -1.479284) (xy 375.288922 -1.542654)
			(xy 375.225552 -1.600423) (xy 375.157123 -1.652099) (xy 375.084217 -1.69724) (xy 375.007457 -1.735462)
			(xy 374.927498 -1.766438) (xy 374.845022 -1.789905) (xy 374.760732 -1.805661) (xy 374.675349 -1.813573)
			(xy 374.589599 -1.813573) (xy 374.504216 -1.805661) (xy 374.419926 -1.789905) (xy 374.33745 -1.766438)
			(xy 374.257491 -1.735462) (xy 374.180731 -1.69724) (xy 374.107825 -1.652099) (xy 374.039396 -1.600423)
			(xy 373.976026 -1.542654) (xy 373.918257 -1.479284) (xy 373.866581 -1.410855) (xy 373.82144 -1.337949)
			(xy 373.783218 -1.261189) (xy 373.752242 -1.18123) (xy 373.728775 -1.098754) (xy 373.713019 -1.014464)
			(xy 373.705107 -0.929081) (xy 343.693001 -0.929081) (xy 343.685089 -1.014464) (xy 343.669333 -1.098754)
			(xy 343.645866 -1.18123) (xy 343.61489 -1.261189) (xy 343.576668 -1.337949) (xy 343.531527 -1.410855)
			(xy 343.479851 -1.479284) (xy 343.422082 -1.542654) (xy 343.358712 -1.600423) (xy 343.290283 -1.652099)
			(xy 343.217377 -1.69724) (xy 343.140617 -1.735462) (xy 343.060658 -1.766438) (xy 342.978182 -1.789905)
			(xy 342.893892 -1.805661) (xy 342.808509 -1.813573) (xy 342.722759 -1.813573) (xy 342.637376 -1.805661)
			(xy 342.553086 -1.789905) (xy 342.47061 -1.766438) (xy 342.390651 -1.735462) (xy 342.313891 -1.69724)
			(xy 342.240985 -1.652099) (xy 342.172556 -1.600423) (xy 342.109186 -1.542654) (xy 342.051417 -1.479284)
			(xy 341.999741 -1.410855) (xy 341.9546 -1.337949) (xy 341.916378 -1.261189) (xy 341.885402 -1.18123)
			(xy 341.861935 -1.098754) (xy 341.846179 -1.014464) (xy 341.838267 -0.929081) (xy 337.343001 -0.929081)
			(xy 337.335089 -1.014464) (xy 337.319333 -1.098754) (xy 337.295866 -1.18123) (xy 337.26489 -1.261189)
			(xy 337.226668 -1.337949) (xy 337.181527 -1.410855) (xy 337.129851 -1.479284) (xy 337.072082 -1.542654)
			(xy 337.008712 -1.600423) (xy 336.940283 -1.652099) (xy 336.867377 -1.69724) (xy 336.790617 -1.735462)
			(xy 336.710658 -1.766438) (xy 336.628182 -1.789905) (xy 336.543892 -1.805661) (xy 336.458509 -1.813573)
			(xy 336.372759 -1.813573) (xy 336.287376 -1.805661) (xy 336.203086 -1.789905) (xy 336.12061 -1.766438)
			(xy 336.040651 -1.735462) (xy 335.963891 -1.69724) (xy 335.890985 -1.652099) (xy 335.822556 -1.600423)
			(xy 335.759186 -1.542654) (xy 335.701417 -1.479284) (xy 335.649741 -1.410855) (xy 335.6046 -1.337949)
			(xy 335.566378 -1.261189) (xy 335.535402 -1.18123) (xy 335.511935 -1.098754) (xy 335.496179 -1.014464)
			(xy 335.488267 -0.929081) (xy 333.050655 -0.929081) (xy 333.042743 -1.014464) (xy 333.026987 -1.098754)
			(xy 333.00352 -1.18123) (xy 332.972544 -1.261189) (xy 332.934322 -1.337949) (xy 332.889181 -1.410855)
			(xy 332.837505 -1.479284) (xy 332.779736 -1.542654) (xy 332.716366 -1.600423) (xy 332.647937 -1.652099)
			(xy 332.575031 -1.69724) (xy 332.498271 -1.735462) (xy 332.418312 -1.766438) (xy 332.335836 -1.789905)
			(xy 332.251546 -1.805661) (xy 332.166163 -1.813573) (xy 332.080413 -1.813573) (xy 331.99503 -1.805661)
			(xy 331.91074 -1.789905) (xy 331.828264 -1.766438) (xy 331.748305 -1.735462) (xy 331.671545 -1.69724)
			(xy 331.598639 -1.652099) (xy 331.53021 -1.600423) (xy 331.46684 -1.542654) (xy 331.409071 -1.479284)
			(xy 331.357395 -1.410855) (xy 331.312254 -1.337949) (xy 331.274032 -1.261189) (xy 331.243056 -1.18123)
			(xy 331.219589 -1.098754) (xy 331.203833 -1.014464) (xy 331.195921 -0.929081) (xy 326.700655 -0.929081)
			(xy 326.692743 -1.014464) (xy 326.676987 -1.098754) (xy 326.65352 -1.18123) (xy 326.622544 -1.261189)
			(xy 326.584322 -1.337949) (xy 326.539181 -1.410855) (xy 326.487505 -1.479284) (xy 326.429736 -1.542654)
			(xy 326.366366 -1.600423) (xy 326.297937 -1.652099) (xy 326.225031 -1.69724) (xy 326.148271 -1.735462)
			(xy 326.068312 -1.766438) (xy 325.985836 -1.789905) (xy 325.901546 -1.805661) (xy 325.816163 -1.813573)
			(xy 325.730413 -1.813573) (xy 325.64503 -1.805661) (xy 325.56074 -1.789905) (xy 325.478264 -1.766438)
			(xy 325.398305 -1.735462) (xy 325.321545 -1.69724) (xy 325.248639 -1.652099) (xy 325.18021 -1.600423)
			(xy 325.11684 -1.542654) (xy 325.059071 -1.479284) (xy 325.007395 -1.410855) (xy 324.962254 -1.337949)
			(xy 324.924032 -1.261189) (xy 324.893056 -1.18123) (xy 324.869589 -1.098754) (xy 324.853833 -1.014464)
			(xy 324.845921 -0.929081) (xy 265.125975 -0.929081) (xy 265.118063 -1.014464) (xy 265.102307 -1.098754)
			(xy 265.07884 -1.18123) (xy 265.047864 -1.261189) (xy 265.009642 -1.337949) (xy 264.964501 -1.410855)
			(xy 264.912825 -1.479284) (xy 264.855056 -1.542654) (xy 264.791686 -1.600423) (xy 264.723257 -1.652099)
			(xy 264.650351 -1.69724) (xy 264.573591 -1.735462) (xy 264.493632 -1.766438) (xy 264.411156 -1.789905)
			(xy 264.326866 -1.805661) (xy 264.241483 -1.813573) (xy 264.155733 -1.813573) (xy 264.07035 -1.805661)
			(xy 263.98606 -1.789905) (xy 263.903584 -1.766438) (xy 263.823625 -1.735462) (xy 263.746865 -1.69724)
			(xy 263.673959 -1.652099) (xy 263.60553 -1.600423) (xy 263.54216 -1.542654) (xy 263.484391 -1.479284)
			(xy 263.432715 -1.410855) (xy 263.387574 -1.337949) (xy 263.349352 -1.261189) (xy 263.318376 -1.18123)
			(xy 263.294909 -1.098754) (xy 263.279153 -1.014464) (xy 263.271241 -0.929081) (xy 258.775975 -0.929081)
			(xy 258.768063 -1.014464) (xy 258.752307 -1.098754) (xy 258.72884 -1.18123) (xy 258.697864 -1.261189)
			(xy 258.659642 -1.337949) (xy 258.614501 -1.410855) (xy 258.562825 -1.479284) (xy 258.505056 -1.542654)
			(xy 258.441686 -1.600423) (xy 258.373257 -1.652099) (xy 258.300351 -1.69724) (xy 258.223591 -1.735462)
			(xy 258.143632 -1.766438) (xy 258.061156 -1.789905) (xy 257.976866 -1.805661) (xy 257.891483 -1.813573)
			(xy 257.805733 -1.813573) (xy 257.72035 -1.805661) (xy 257.63606 -1.789905) (xy 257.553584 -1.766438)
			(xy 257.473625 -1.735462) (xy 257.396865 -1.69724) (xy 257.323959 -1.652099) (xy 257.25553 -1.600423)
			(xy 257.19216 -1.542654) (xy 257.134391 -1.479284) (xy 257.082715 -1.410855) (xy 257.037574 -1.337949)
			(xy 256.999352 -1.261189) (xy 256.968376 -1.18123) (xy 256.944909 -1.098754) (xy 256.929153 -1.014464)
			(xy 256.921241 -0.929081) (xy 254.465119 -0.929081) (xy 254.465087 -0.931875) (xy 254.457175 -1.017258)
			(xy 254.441419 -1.101548) (xy 254.417952 -1.184024) (xy 254.386976 -1.263983) (xy 254.348754 -1.340743)
			(xy 254.303613 -1.413649) (xy 254.251937 -1.482078) (xy 254.194168 -1.545448) (xy 254.130798 -1.603217)
			(xy 254.062369 -1.654893) (xy 253.989463 -1.700034) (xy 253.912703 -1.738256) (xy 253.832744 -1.769232)
			(xy 253.750268 -1.792699) (xy 253.665978 -1.808455) (xy 253.580595 -1.816367) (xy 253.494845 -1.816367)
			(xy 253.409462 -1.808455) (xy 253.325172 -1.792699) (xy 253.242696 -1.769232) (xy 253.162737 -1.738256)
			(xy 253.085977 -1.700034) (xy 253.013071 -1.654893) (xy 252.944642 -1.603217) (xy 252.881272 -1.545448)
			(xy 252.823503 -1.482078) (xy 252.771827 -1.413649) (xy 252.726686 -1.340743) (xy 252.688464 -1.263983)
			(xy 252.657488 -1.184024) (xy 252.634021 -1.101548) (xy 252.618265 -1.017258) (xy 252.610353 -0.931875)
			(xy 248.115087 -0.931875) (xy 248.107175 -1.017258) (xy 248.091419 -1.101548) (xy 248.067952 -1.184024)
			(xy 248.036976 -1.263983) (xy 247.998754 -1.340743) (xy 247.953613 -1.413649) (xy 247.901937 -1.482078)
			(xy 247.844168 -1.545448) (xy 247.780798 -1.603217) (xy 247.712369 -1.654893) (xy 247.639463 -1.700034)
			(xy 247.562703 -1.738256) (xy 247.482744 -1.769232) (xy 247.400268 -1.792699) (xy 247.315978 -1.808455)
			(xy 247.230595 -1.816367) (xy 247.144845 -1.816367) (xy 247.059462 -1.808455) (xy 246.975172 -1.792699)
			(xy 246.892696 -1.769232) (xy 246.812737 -1.738256) (xy 246.735977 -1.700034) (xy 246.663071 -1.654893)
			(xy 246.594642 -1.603217) (xy 246.531272 -1.545448) (xy 246.473503 -1.482078) (xy 246.421827 -1.413649)
			(xy 246.376686 -1.340743) (xy 246.338464 -1.263983) (xy 246.307488 -1.184024) (xy 246.284021 -1.101548)
			(xy 246.268265 -1.017258) (xy 246.260353 -0.931875) (xy 216.248247 -0.931875) (xy 216.240335 -1.017258)
			(xy 216.224579 -1.101548) (xy 216.201112 -1.184024) (xy 216.170136 -1.263983) (xy 216.131914 -1.340743)
			(xy 216.086773 -1.413649) (xy 216.035097 -1.482078) (xy 215.977328 -1.545448) (xy 215.913958 -1.603217)
			(xy 215.845529 -1.654893) (xy 215.772623 -1.700034) (xy 215.695863 -1.738256) (xy 215.615904 -1.769232)
			(xy 215.533428 -1.792699) (xy 215.449138 -1.808455) (xy 215.363755 -1.816367) (xy 215.278005 -1.816367)
			(xy 215.192622 -1.808455) (xy 215.108332 -1.792699) (xy 215.025856 -1.769232) (xy 214.945897 -1.738256)
			(xy 214.869137 -1.700034) (xy 214.796231 -1.654893) (xy 214.727802 -1.603217) (xy 214.664432 -1.545448)
			(xy 214.606663 -1.482078) (xy 214.554987 -1.413649) (xy 214.509846 -1.340743) (xy 214.471624 -1.263983)
			(xy 214.440648 -1.184024) (xy 214.417181 -1.101548) (xy 214.401425 -1.017258) (xy 214.393513 -0.931875)
			(xy 209.898247 -0.931875) (xy 209.890335 -1.017258) (xy 209.874579 -1.101548) (xy 209.851112 -1.184024)
			(xy 209.820136 -1.263983) (xy 209.781914 -1.340743) (xy 209.736773 -1.413649) (xy 209.685097 -1.482078)
			(xy 209.627328 -1.545448) (xy 209.563958 -1.603217) (xy 209.495529 -1.654893) (xy 209.422623 -1.700034)
			(xy 209.345863 -1.738256) (xy 209.265904 -1.769232) (xy 209.183428 -1.792699) (xy 209.099138 -1.808455)
			(xy 209.013755 -1.816367) (xy 208.928005 -1.816367) (xy 208.842622 -1.808455) (xy 208.758332 -1.792699)
			(xy 208.675856 -1.769232) (xy 208.595897 -1.738256) (xy 208.519137 -1.700034) (xy 208.446231 -1.654893)
			(xy 208.377802 -1.603217) (xy 208.314432 -1.545448) (xy 208.256663 -1.482078) (xy 208.204987 -1.413649)
			(xy 208.159846 -1.340743) (xy 208.121624 -1.263983) (xy 208.090648 -1.184024) (xy 208.067181 -1.101548)
			(xy 208.051425 -1.017258) (xy 208.043513 -0.931875) (xy 84.20989 -0.931875) (xy 84.20989 -7.78002)
			(xy 84.210412 -7.835827) (xy 84.218755 -7.947128) (xy 84.235391 -8.057495) (xy 84.260229 -8.16631)
			(xy 84.293128 -8.272964) (xy 84.333906 -8.376862) (xy 84.382334 -8.477422) (xy 84.438141 -8.574082)
			(xy 84.501016 -8.666301) (xy 84.570606 -8.753563) (xy 84.646523 -8.835382) (xy 84.728341 -8.911298)
			(xy 84.815604 -8.980888) (xy 84.907824 -9.043762) (xy 85.004484 -9.099569) (xy 85.105044 -9.147996)
			(xy 85.208942 -9.188774) (xy 85.315596 -9.221673) (xy 85.424411 -9.24651) (xy 85.534778 -9.263146)
			(xy 85.646079 -9.271488) (xy 85.701886 -9.272016) (xy 122.102118 -9.272016) (xy 122.157925 -9.271494)
			(xy 122.269226 -9.263152) (xy 122.379593 -9.246515) (xy 122.488409 -9.221678) (xy 122.595063 -9.188778)
			(xy 122.698961 -9.148001) (xy 122.799522 -9.099573) (xy 122.896182 -9.043766) (xy 122.988401 -8.980891)
			(xy 123.075664 -8.911301) (xy 123.157483 -8.835384) (xy 123.2334 -8.753566) (xy 123.30299 -8.666303)
			(xy 123.365865 -8.574084) (xy 123.421672 -8.477423) (xy 123.4701 -8.376863) (xy 123.510878 -8.272965)
			(xy 123.543777 -8.16631) (xy 123.568615 -8.057495) (xy 123.585251 -7.947128) (xy 123.593594 -7.835827)
			(xy 123.594114 -7.78002) (xy 123.594114 -4.2799) (xy 123.594598 -4.209546) (xy 123.602488 -4.06906)
			(xy 123.618242 -3.929237) (xy 123.641812 -3.790517) (xy 123.673122 -3.653337) (xy 123.712075 -3.518129)
			(xy 123.758548 -3.385317) (xy 123.812395 -3.25532) (xy 123.873446 -3.128547) (xy 123.941509 -3.005396)
			(xy 124.01637 -2.886255) (xy 124.097794 -2.7715) (xy 124.185524 -2.66149) (xy 124.279284 -2.556573)
			(xy 124.37878 -2.457077) (xy 124.483698 -2.363317) (xy 124.593708 -2.275588) (xy 124.708464 -2.194165)
			(xy 124.827605 -2.119304) (xy 124.950755 -2.051241) (xy 125.077529 -1.990191) (xy 125.207526 -1.936345)
			(xy 125.340338 -1.889872) (xy 125.475547 -1.85092) (xy 125.612727 -1.81961) (xy 125.751447 -1.796041)
			(xy 125.89127 -1.780287) (xy 126.031756 -1.772398) (xy 126.10211 -1.771904) (xy 194.701922 -1.771904)
			(xy 194.772275 -1.772398) (xy 194.912761 -1.780289) (xy 195.052582 -1.796044) (xy 195.191301 -1.819614)
			(xy 195.32848 -1.850925) (xy 195.463687 -1.889879) (xy 195.596497 -1.936352) (xy 195.726493 -1.990199)
			(xy 195.853265 -2.05125) (xy 195.976414 -2.119314) (xy 196.095554 -2.194175) (xy 196.210308 -2.275598)
			(xy 196.320316 -2.363328) (xy 196.425233 -2.457088) (xy 196.524727 -2.556583) (xy 196.618486 -2.6615)
			(xy 196.706215 -2.77151) (xy 196.787637 -2.886265) (xy 196.862497 -3.005405) (xy 196.93056 -3.128555)
			(xy 196.99161 -3.255327) (xy 197.045455 -3.385323) (xy 197.075741 -3.471875) (xy 208.043513 -3.471875)
			(xy 208.043513 -3.386125) (xy 208.051425 -3.300742) (xy 208.067181 -3.216452) (xy 208.090648 -3.133976)
			(xy 208.121624 -3.054017) (xy 208.159846 -2.977257) (xy 208.204987 -2.904351) (xy 208.256663 -2.835922)
			(xy 208.314432 -2.772552) (xy 208.377802 -2.714783) (xy 208.446231 -2.663107) (xy 208.519137 -2.617966)
			(xy 208.595897 -2.579744) (xy 208.675856 -2.548768) (xy 208.758332 -2.525301) (xy 208.842622 -2.509545)
			(xy 208.928005 -2.501633) (xy 209.013755 -2.501633) (xy 209.099138 -2.509545) (xy 209.183428 -2.525301)
			(xy 209.265904 -2.548768) (xy 209.345863 -2.579744) (xy 209.368066 -2.5908) (xy 212.978492 -2.5908)
			(xy 212.978492 -1.7272) (xy 212.978978 -1.699931) (xy 212.98674 -1.645947) (xy 213.002105 -1.593617)
			(xy 213.024762 -1.544007) (xy 213.054248 -1.498126) (xy 213.089963 -1.456909) (xy 213.13118 -1.421194)
			(xy 213.177061 -1.391708) (xy 213.226671 -1.369051) (xy 213.279001 -1.353686) (xy 213.332985 -1.345924)
			(xy 213.387523 -1.345924) (xy 213.441507 -1.353686) (xy 213.493837 -1.369051) (xy 213.543447 -1.391708)
			(xy 213.589328 -1.421194) (xy 213.630545 -1.456909) (xy 213.66626 -1.498126) (xy 213.695746 -1.544007)
			(xy 213.718403 -1.593617) (xy 213.733768 -1.645947) (xy 213.74153 -1.699931) (xy 213.742016 -1.7272)
			(xy 213.742016 -2.5908) (xy 213.74153 -2.618069) (xy 213.733768 -2.672053) (xy 213.718403 -2.724383)
			(xy 213.695746 -2.773993) (xy 213.66626 -2.819874) (xy 213.630545 -2.861091) (xy 213.589328 -2.896806)
			(xy 213.543447 -2.926292) (xy 213.493837 -2.948949) (xy 213.441507 -2.964314) (xy 213.387523 -2.972076)
			(xy 213.332985 -2.972076) (xy 213.279001 -2.964314) (xy 213.226671 -2.948949) (xy 213.177061 -2.926292)
			(xy 213.13118 -2.896806) (xy 213.089963 -2.861091) (xy 213.054248 -2.819874) (xy 213.024762 -2.773993)
			(xy 213.002105 -2.724383) (xy 212.98674 -2.672053) (xy 212.978978 -2.618069) (xy 212.978492 -2.5908)
			(xy 209.368066 -2.5908) (xy 209.422623 -2.617966) (xy 209.495529 -2.663107) (xy 209.563958 -2.714783)
			(xy 209.627328 -2.772552) (xy 209.685097 -2.835922) (xy 209.736773 -2.904351) (xy 209.781914 -2.977257)
			(xy 209.820136 -3.054017) (xy 209.851112 -3.133976) (xy 209.874579 -3.216452) (xy 209.890335 -3.300742)
			(xy 209.898247 -3.386125) (xy 209.898742 -3.429) (xy 209.898247 -3.471875) (xy 214.393513 -3.471875)
			(xy 214.393513 -3.386125) (xy 214.401425 -3.300742) (xy 214.417181 -3.216452) (xy 214.440648 -3.133976)
			(xy 214.471624 -3.054017) (xy 214.509846 -2.977257) (xy 214.554987 -2.904351) (xy 214.606663 -2.835922)
			(xy 214.664432 -2.772552) (xy 214.727802 -2.714783) (xy 214.796231 -2.663107) (xy 214.869137 -2.617966)
			(xy 214.945897 -2.579744) (xy 215.025856 -2.548768) (xy 215.108332 -2.525301) (xy 215.192622 -2.509545)
			(xy 215.278005 -2.501633) (xy 215.363755 -2.501633) (xy 215.449138 -2.509545) (xy 215.533428 -2.525301)
			(xy 215.615904 -2.548768) (xy 215.695863 -2.579744) (xy 215.772623 -2.617966) (xy 215.845529 -2.663107)
			(xy 215.913958 -2.714783) (xy 215.977328 -2.772552) (xy 216.035097 -2.835922) (xy 216.086773 -2.904351)
			(xy 216.131914 -2.977257) (xy 216.170136 -3.054017) (xy 216.201112 -3.133976) (xy 216.224579 -3.216452)
			(xy 216.240335 -3.300742) (xy 216.248247 -3.386125) (xy 216.248742 -3.429) (xy 216.248247 -3.471875)
			(xy 246.260353 -3.471875) (xy 246.260353 -3.386125) (xy 246.268265 -3.300742) (xy 246.284021 -3.216452)
			(xy 246.307488 -3.133976) (xy 246.338464 -3.054017) (xy 246.376686 -2.977257) (xy 246.421827 -2.904351)
			(xy 246.473503 -2.835922) (xy 246.531272 -2.772552) (xy 246.594642 -2.714783) (xy 246.663071 -2.663107)
			(xy 246.735977 -2.617966) (xy 246.812737 -2.579744) (xy 246.892696 -2.548768) (xy 246.975172 -2.525301)
			(xy 247.059462 -2.509545) (xy 247.144845 -2.501633) (xy 247.230595 -2.501633) (xy 247.315978 -2.509545)
			(xy 247.400268 -2.525301) (xy 247.482744 -2.548768) (xy 247.562703 -2.579744) (xy 247.584906 -2.5908)
			(xy 248.766584 -2.5908) (xy 248.766584 -1.7272) (xy 248.76707 -1.699931) (xy 248.774832 -1.645947)
			(xy 248.790197 -1.593617) (xy 248.812854 -1.544007) (xy 248.84234 -1.498126) (xy 248.878055 -1.456909)
			(xy 248.919272 -1.421194) (xy 248.965153 -1.391708) (xy 249.014763 -1.369051) (xy 249.067093 -1.353686)
			(xy 249.121077 -1.345924) (xy 249.175615 -1.345924) (xy 249.229599 -1.353686) (xy 249.281929 -1.369051)
			(xy 249.331539 -1.391708) (xy 249.37742 -1.421194) (xy 249.418637 -1.456909) (xy 249.454352 -1.498126)
			(xy 249.483838 -1.544007) (xy 249.506495 -1.593617) (xy 249.52186 -1.645947) (xy 249.529622 -1.699931)
			(xy 249.530108 -1.7272) (xy 249.530108 -2.5908) (xy 249.529622 -2.618069) (xy 249.52186 -2.672053)
			(xy 249.506495 -2.724383) (xy 249.483838 -2.773993) (xy 249.454352 -2.819874) (xy 249.418637 -2.861091)
			(xy 249.37742 -2.896806) (xy 249.331539 -2.926292) (xy 249.281929 -2.948949) (xy 249.229599 -2.964314)
			(xy 249.175615 -2.972076) (xy 249.121077 -2.972076) (xy 249.067093 -2.964314) (xy 249.014763 -2.948949)
			(xy 248.965153 -2.926292) (xy 248.919272 -2.896806) (xy 248.878055 -2.861091) (xy 248.84234 -2.819874)
			(xy 248.812854 -2.773993) (xy 248.790197 -2.724383) (xy 248.774832 -2.672053) (xy 248.76707 -2.618069)
			(xy 248.766584 -2.5908) (xy 247.584906 -2.5908) (xy 247.639463 -2.617966) (xy 247.712369 -2.663107)
			(xy 247.780798 -2.714783) (xy 247.844168 -2.772552) (xy 247.901937 -2.835922) (xy 247.953613 -2.904351)
			(xy 247.998754 -2.977257) (xy 248.036976 -3.054017) (xy 248.067952 -3.133976) (xy 248.091419 -3.216452)
			(xy 248.107175 -3.300742) (xy 248.115087 -3.386125) (xy 248.115582 -3.429) (xy 248.115087 -3.471875)
			(xy 252.610353 -3.471875) (xy 252.610353 -3.386125) (xy 252.618265 -3.300742) (xy 252.634021 -3.216452)
			(xy 252.657488 -3.133976) (xy 252.688464 -3.054017) (xy 252.726686 -2.977257) (xy 252.771827 -2.904351)
			(xy 252.823503 -2.835922) (xy 252.881272 -2.772552) (xy 252.944642 -2.714783) (xy 253.013071 -2.663107)
			(xy 253.085977 -2.617966) (xy 253.162737 -2.579744) (xy 253.242696 -2.548768) (xy 253.325172 -2.525301)
			(xy 253.409462 -2.509545) (xy 253.494845 -2.501633) (xy 253.580595 -2.501633) (xy 253.665978 -2.509545)
			(xy 253.750268 -2.525301) (xy 253.832744 -2.548768) (xy 253.912703 -2.579744) (xy 253.989463 -2.617966)
			(xy 254.062369 -2.663107) (xy 254.130798 -2.714783) (xy 254.194168 -2.772552) (xy 254.251937 -2.835922)
			(xy 254.303613 -2.904351) (xy 254.348754 -2.977257) (xy 254.386976 -3.054017) (xy 254.417952 -3.133976)
			(xy 254.441419 -3.216452) (xy 254.457175 -3.300742) (xy 254.465087 -3.386125) (xy 254.465582 -3.429)
			(xy 254.465119 -3.469081) (xy 256.921241 -3.469081) (xy 256.921241 -3.383331) (xy 256.929153 -3.297948)
			(xy 256.944909 -3.213658) (xy 256.968376 -3.131182) (xy 256.999352 -3.051223) (xy 257.037574 -2.974463)
			(xy 257.082715 -2.901557) (xy 257.134391 -2.833128) (xy 257.19216 -2.769758) (xy 257.25553 -2.711989)
			(xy 257.323959 -2.660313) (xy 257.396865 -2.615172) (xy 257.473625 -2.57695) (xy 257.553584 -2.545974)
			(xy 257.63606 -2.522507) (xy 257.72035 -2.506751) (xy 257.805733 -2.498839) (xy 257.891483 -2.498839)
			(xy 257.976866 -2.506751) (xy 258.061156 -2.522507) (xy 258.143632 -2.545974) (xy 258.223591 -2.57695)
			(xy 258.300351 -2.615172) (xy 258.373257 -2.660313) (xy 258.441686 -2.711989) (xy 258.505056 -2.769758)
			(xy 258.562825 -2.833128) (xy 258.614501 -2.901557) (xy 258.659642 -2.974463) (xy 258.697864 -3.051223)
			(xy 258.72884 -3.131182) (xy 258.752307 -3.213658) (xy 258.768063 -3.297948) (xy 258.775975 -3.383331)
			(xy 258.77647 -3.426206) (xy 258.775975 -3.469081) (xy 263.271241 -3.469081) (xy 263.271241 -3.383331)
			(xy 263.279153 -3.297948) (xy 263.294909 -3.213658) (xy 263.318376 -3.131182) (xy 263.349352 -3.051223)
			(xy 263.387574 -2.974463) (xy 263.432715 -2.901557) (xy 263.484391 -2.833128) (xy 263.54216 -2.769758)
			(xy 263.60553 -2.711989) (xy 263.673959 -2.660313) (xy 263.746865 -2.615172) (xy 263.823625 -2.57695)
			(xy 263.903584 -2.545974) (xy 263.98606 -2.522507) (xy 264.07035 -2.506751) (xy 264.155733 -2.498839)
			(xy 264.241483 -2.498839) (xy 264.326866 -2.506751) (xy 264.411156 -2.522507) (xy 264.493632 -2.545974)
			(xy 264.573591 -2.57695) (xy 264.650351 -2.615172) (xy 264.723257 -2.660313) (xy 264.791686 -2.711989)
			(xy 264.855056 -2.769758) (xy 264.912825 -2.833128) (xy 264.964501 -2.901557) (xy 265.009642 -2.974463)
			(xy 265.047864 -3.051223) (xy 265.07884 -3.131182) (xy 265.102307 -3.213658) (xy 265.118063 -3.297948)
			(xy 265.125975 -3.383331) (xy 265.12647 -3.426206) (xy 265.125975 -3.469081) (xy 324.845921 -3.469081)
			(xy 324.845921 -3.383331) (xy 324.853833 -3.297948) (xy 324.869589 -3.213658) (xy 324.893056 -3.131182)
			(xy 324.924032 -3.051223) (xy 324.962254 -2.974463) (xy 325.007395 -2.901557) (xy 325.059071 -2.833128)
			(xy 325.11684 -2.769758) (xy 325.18021 -2.711989) (xy 325.248639 -2.660313) (xy 325.321545 -2.615172)
			(xy 325.398305 -2.57695) (xy 325.478264 -2.545974) (xy 325.56074 -2.522507) (xy 325.64503 -2.506751)
			(xy 325.730413 -2.498839) (xy 325.816163 -2.498839) (xy 325.901546 -2.506751) (xy 325.985836 -2.522507)
			(xy 326.068312 -2.545974) (xy 326.148271 -2.57695) (xy 326.225031 -2.615172) (xy 326.297937 -2.660313)
			(xy 326.366366 -2.711989) (xy 326.429736 -2.769758) (xy 326.487505 -2.833128) (xy 326.539181 -2.901557)
			(xy 326.584322 -2.974463) (xy 326.622544 -3.051223) (xy 326.65352 -3.131182) (xy 326.676987 -3.213658)
			(xy 326.692743 -3.297948) (xy 326.700655 -3.383331) (xy 326.70115 -3.426206) (xy 326.700655 -3.469081)
			(xy 331.195921 -3.469081) (xy 331.195921 -3.383331) (xy 331.203833 -3.297948) (xy 331.219589 -3.213658)
			(xy 331.243056 -3.131182) (xy 331.274032 -3.051223) (xy 331.312254 -2.974463) (xy 331.357395 -2.901557)
			(xy 331.409071 -2.833128) (xy 331.46684 -2.769758) (xy 331.53021 -2.711989) (xy 331.598639 -2.660313)
			(xy 331.671545 -2.615172) (xy 331.748305 -2.57695) (xy 331.828264 -2.545974) (xy 331.91074 -2.522507)
			(xy 331.99503 -2.506751) (xy 332.080413 -2.498839) (xy 332.166163 -2.498839) (xy 332.251546 -2.506751)
			(xy 332.335836 -2.522507) (xy 332.418312 -2.545974) (xy 332.498271 -2.57695) (xy 332.575031 -2.615172)
			(xy 332.647937 -2.660313) (xy 332.716366 -2.711989) (xy 332.779736 -2.769758) (xy 332.837505 -2.833128)
			(xy 332.889181 -2.901557) (xy 332.934322 -2.974463) (xy 332.972544 -3.051223) (xy 333.00352 -3.131182)
			(xy 333.026987 -3.213658) (xy 333.042743 -3.297948) (xy 333.050655 -3.383331) (xy 333.05115 -3.426206)
			(xy 333.050655 -3.469081) (xy 335.488267 -3.469081) (xy 335.488267 -3.383331) (xy 335.496179 -3.297948)
			(xy 335.511935 -3.213658) (xy 335.535402 -3.131182) (xy 335.566378 -3.051223) (xy 335.6046 -2.974463)
			(xy 335.649741 -2.901557) (xy 335.701417 -2.833128) (xy 335.759186 -2.769758) (xy 335.822556 -2.711989)
			(xy 335.890985 -2.660313) (xy 335.963891 -2.615172) (xy 336.040651 -2.57695) (xy 336.12061 -2.545974)
			(xy 336.203086 -2.522507) (xy 336.287376 -2.506751) (xy 336.372759 -2.498839) (xy 336.458509 -2.498839)
			(xy 336.543892 -2.506751) (xy 336.628182 -2.522507) (xy 336.710658 -2.545974) (xy 336.790617 -2.57695)
			(xy 336.867377 -2.615172) (xy 336.940283 -2.660313) (xy 337.008712 -2.711989) (xy 337.072082 -2.769758)
			(xy 337.129851 -2.833128) (xy 337.181527 -2.901557) (xy 337.226668 -2.974463) (xy 337.26489 -3.051223)
			(xy 337.295866 -3.131182) (xy 337.319333 -3.213658) (xy 337.335089 -3.297948) (xy 337.343001 -3.383331)
			(xy 337.343496 -3.426206) (xy 337.343001 -3.469081) (xy 341.838267 -3.469081) (xy 341.838267 -3.383331)
			(xy 341.846179 -3.297948) (xy 341.861935 -3.213658) (xy 341.885402 -3.131182) (xy 341.916378 -3.051223)
			(xy 341.9546 -2.974463) (xy 341.999741 -2.901557) (xy 342.051417 -2.833128) (xy 342.109186 -2.769758)
			(xy 342.172556 -2.711989) (xy 342.240985 -2.660313) (xy 342.313891 -2.615172) (xy 342.390651 -2.57695)
			(xy 342.47061 -2.545974) (xy 342.553086 -2.522507) (xy 342.637376 -2.506751) (xy 342.722759 -2.498839)
			(xy 342.808509 -2.498839) (xy 342.893892 -2.506751) (xy 342.978182 -2.522507) (xy 343.060658 -2.545974)
			(xy 343.140617 -2.57695) (xy 343.217377 -2.615172) (xy 343.290283 -2.660313) (xy 343.358712 -2.711989)
			(xy 343.422082 -2.769758) (xy 343.479851 -2.833128) (xy 343.531527 -2.901557) (xy 343.576668 -2.974463)
			(xy 343.61489 -3.051223) (xy 343.645866 -3.131182) (xy 343.669333 -3.213658) (xy 343.685089 -3.297948)
			(xy 343.693001 -3.383331) (xy 343.693496 -3.426206) (xy 343.693001 -3.469081) (xy 373.705107 -3.469081)
			(xy 373.705107 -3.383331) (xy 373.713019 -3.297948) (xy 373.728775 -3.213658) (xy 373.752242 -3.131182)
			(xy 373.783218 -3.051223) (xy 373.82144 -2.974463) (xy 373.866581 -2.901557) (xy 373.918257 -2.833128)
			(xy 373.976026 -2.769758) (xy 374.039396 -2.711989) (xy 374.107825 -2.660313) (xy 374.180731 -2.615172)
			(xy 374.257491 -2.57695) (xy 374.33745 -2.545974) (xy 374.419926 -2.522507) (xy 374.504216 -2.506751)
			(xy 374.589599 -2.498839) (xy 374.675349 -2.498839) (xy 374.760732 -2.506751) (xy 374.845022 -2.522507)
			(xy 374.927498 -2.545974) (xy 375.007457 -2.57695) (xy 375.084217 -2.615172) (xy 375.157123 -2.660313)
			(xy 375.225552 -2.711989) (xy 375.288922 -2.769758) (xy 375.346691 -2.833128) (xy 375.398367 -2.901557)
			(xy 375.443508 -2.974463) (xy 375.48173 -3.051223) (xy 375.512706 -3.131182) (xy 375.536173 -3.213658)
			(xy 375.551929 -3.297948) (xy 375.559841 -3.383331) (xy 375.560336 -3.426206) (xy 375.559841 -3.469081)
			(xy 380.055107 -3.469081) (xy 380.055107 -3.383331) (xy 380.063019 -3.297948) (xy 380.078775 -3.213658)
			(xy 380.102242 -3.131182) (xy 380.133218 -3.051223) (xy 380.17144 -2.974463) (xy 380.216581 -2.901557)
			(xy 380.268257 -2.833128) (xy 380.326026 -2.769758) (xy 380.389396 -2.711989) (xy 380.457825 -2.660313)
			(xy 380.530731 -2.615172) (xy 380.607491 -2.57695) (xy 380.68745 -2.545974) (xy 380.769926 -2.522507)
			(xy 380.854216 -2.506751) (xy 380.939599 -2.498839) (xy 381.025349 -2.498839) (xy 381.110732 -2.506751)
			(xy 381.195022 -2.522507) (xy 381.277498 -2.545974) (xy 381.357457 -2.57695) (xy 381.434217 -2.615172)
			(xy 381.507123 -2.660313) (xy 381.575552 -2.711989) (xy 381.638922 -2.769758) (xy 381.696691 -2.833128)
			(xy 381.748367 -2.901557) (xy 381.793508 -2.974463) (xy 381.83173 -3.051223) (xy 381.862706 -3.131182)
			(xy 381.886173 -3.213658) (xy 381.901929 -3.297948) (xy 381.909841 -3.383331) (xy 381.910336 -3.426206)
			(xy 381.909841 -3.469081) (xy 381.901929 -3.554464) (xy 381.886173 -3.638754) (xy 381.862706 -3.72123)
			(xy 381.83173 -3.801189) (xy 381.793508 -3.877949) (xy 381.748367 -3.950855) (xy 381.696691 -4.019284)
			(xy 381.638922 -4.082654) (xy 381.575552 -4.140423) (xy 381.507123 -4.192099) (xy 381.434217 -4.23724)
			(xy 381.357457 -4.275462) (xy 381.277498 -4.306438) (xy 381.195022 -4.329905) (xy 381.110732 -4.345661)
			(xy 381.025349 -4.353573) (xy 380.939599 -4.353573) (xy 380.854216 -4.345661) (xy 380.769926 -4.329905)
			(xy 380.68745 -4.306438) (xy 380.607491 -4.275462) (xy 380.530731 -4.23724) (xy 380.457825 -4.192099)
			(xy 380.389396 -4.140423) (xy 380.326026 -4.082654) (xy 380.268257 -4.019284) (xy 380.216581 -3.950855)
			(xy 380.17144 -3.877949) (xy 380.133218 -3.801189) (xy 380.102242 -3.72123) (xy 380.078775 -3.638754)
			(xy 380.063019 -3.554464) (xy 380.055107 -3.469081) (xy 375.559841 -3.469081) (xy 375.551929 -3.554464)
			(xy 375.536173 -3.638754) (xy 375.512706 -3.72123) (xy 375.48173 -3.801189) (xy 375.443508 -3.877949)
			(xy 375.398367 -3.950855) (xy 375.346691 -4.019284) (xy 375.288922 -4.082654) (xy 375.225552 -4.140423)
			(xy 375.157123 -4.192099) (xy 375.084217 -4.23724) (xy 375.007457 -4.275462) (xy 374.927498 -4.306438)
			(xy 374.845022 -4.329905) (xy 374.760732 -4.345661) (xy 374.675349 -4.353573) (xy 374.589599 -4.353573)
			(xy 374.504216 -4.345661) (xy 374.419926 -4.329905) (xy 374.33745 -4.306438) (xy 374.257491 -4.275462)
			(xy 374.180731 -4.23724) (xy 374.107825 -4.192099) (xy 374.039396 -4.140423) (xy 373.976026 -4.082654)
			(xy 373.918257 -4.019284) (xy 373.866581 -3.950855) (xy 373.82144 -3.877949) (xy 373.783218 -3.801189)
			(xy 373.752242 -3.72123) (xy 373.728775 -3.638754) (xy 373.713019 -3.554464) (xy 373.705107 -3.469081)
			(xy 343.693001 -3.469081) (xy 343.685089 -3.554464) (xy 343.669333 -3.638754) (xy 343.645866 -3.72123)
			(xy 343.61489 -3.801189) (xy 343.576668 -3.877949) (xy 343.531527 -3.950855) (xy 343.479851 -4.019284)
			(xy 343.422082 -4.082654) (xy 343.358712 -4.140423) (xy 343.290283 -4.192099) (xy 343.217377 -4.23724)
			(xy 343.140617 -4.275462) (xy 343.060658 -4.306438) (xy 342.978182 -4.329905) (xy 342.893892 -4.345661)
			(xy 342.808509 -4.353573) (xy 342.722759 -4.353573) (xy 342.637376 -4.345661) (xy 342.553086 -4.329905)
			(xy 342.47061 -4.306438) (xy 342.390651 -4.275462) (xy 342.313891 -4.23724) (xy 342.240985 -4.192099)
			(xy 342.172556 -4.140423) (xy 342.109186 -4.082654) (xy 342.051417 -4.019284) (xy 341.999741 -3.950855)
			(xy 341.9546 -3.877949) (xy 341.916378 -3.801189) (xy 341.885402 -3.72123) (xy 341.861935 -3.638754)
			(xy 341.846179 -3.554464) (xy 341.838267 -3.469081) (xy 337.343001 -3.469081) (xy 337.335089 -3.554464)
			(xy 337.319333 -3.638754) (xy 337.295866 -3.72123) (xy 337.26489 -3.801189) (xy 337.226668 -3.877949)
			(xy 337.181527 -3.950855) (xy 337.129851 -4.019284) (xy 337.072082 -4.082654) (xy 337.008712 -4.140423)
			(xy 336.940283 -4.192099) (xy 336.867377 -4.23724) (xy 336.790617 -4.275462) (xy 336.710658 -4.306438)
			(xy 336.628182 -4.329905) (xy 336.543892 -4.345661) (xy 336.458509 -4.353573) (xy 336.372759 -4.353573)
			(xy 336.287376 -4.345661) (xy 336.203086 -4.329905) (xy 336.12061 -4.306438) (xy 336.040651 -4.275462)
			(xy 335.963891 -4.23724) (xy 335.890985 -4.192099) (xy 335.822556 -4.140423) (xy 335.759186 -4.082654)
			(xy 335.701417 -4.019284) (xy 335.649741 -3.950855) (xy 335.6046 -3.877949) (xy 335.566378 -3.801189)
			(xy 335.535402 -3.72123) (xy 335.511935 -3.638754) (xy 335.496179 -3.554464) (xy 335.488267 -3.469081)
			(xy 333.050655 -3.469081) (xy 333.042743 -3.554464) (xy 333.026987 -3.638754) (xy 333.00352 -3.72123)
			(xy 332.972544 -3.801189) (xy 332.934322 -3.877949) (xy 332.889181 -3.950855) (xy 332.837505 -4.019284)
			(xy 332.779736 -4.082654) (xy 332.716366 -4.140423) (xy 332.647937 -4.192099) (xy 332.575031 -4.23724)
			(xy 332.498271 -4.275462) (xy 332.418312 -4.306438) (xy 332.335836 -4.329905) (xy 332.251546 -4.345661)
			(xy 332.166163 -4.353573) (xy 332.080413 -4.353573) (xy 331.99503 -4.345661) (xy 331.91074 -4.329905)
			(xy 331.828264 -4.306438) (xy 331.748305 -4.275462) (xy 331.671545 -4.23724) (xy 331.598639 -4.192099)
			(xy 331.53021 -4.140423) (xy 331.46684 -4.082654) (xy 331.409071 -4.019284) (xy 331.357395 -3.950855)
			(xy 331.312254 -3.877949) (xy 331.274032 -3.801189) (xy 331.243056 -3.72123) (xy 331.219589 -3.638754)
			(xy 331.203833 -3.554464) (xy 331.195921 -3.469081) (xy 326.700655 -3.469081) (xy 326.692743 -3.554464)
			(xy 326.676987 -3.638754) (xy 326.65352 -3.72123) (xy 326.622544 -3.801189) (xy 326.584322 -3.877949)
			(xy 326.539181 -3.950855) (xy 326.487505 -4.019284) (xy 326.429736 -4.082654) (xy 326.366366 -4.140423)
			(xy 326.297937 -4.192099) (xy 326.225031 -4.23724) (xy 326.148271 -4.275462) (xy 326.068312 -4.306438)
			(xy 325.985836 -4.329905) (xy 325.901546 -4.345661) (xy 325.816163 -4.353573) (xy 325.730413 -4.353573)
			(xy 325.64503 -4.345661) (xy 325.56074 -4.329905) (xy 325.478264 -4.306438) (xy 325.398305 -4.275462)
			(xy 325.321545 -4.23724) (xy 325.248639 -4.192099) (xy 325.18021 -4.140423) (xy 325.11684 -4.082654)
			(xy 325.059071 -4.019284) (xy 325.007395 -3.950855) (xy 324.962254 -3.877949) (xy 324.924032 -3.801189)
			(xy 324.893056 -3.72123) (xy 324.869589 -3.638754) (xy 324.853833 -3.554464) (xy 324.845921 -3.469081)
			(xy 265.125975 -3.469081) (xy 265.118063 -3.554464) (xy 265.102307 -3.638754) (xy 265.07884 -3.72123)
			(xy 265.047864 -3.801189) (xy 265.009642 -3.877949) (xy 264.964501 -3.950855) (xy 264.912825 -4.019284)
			(xy 264.855056 -4.082654) (xy 264.791686 -4.140423) (xy 264.723257 -4.192099) (xy 264.650351 -4.23724)
			(xy 264.573591 -4.275462) (xy 264.493632 -4.306438) (xy 264.411156 -4.329905) (xy 264.326866 -4.345661)
			(xy 264.241483 -4.353573) (xy 264.155733 -4.353573) (xy 264.07035 -4.345661) (xy 263.98606 -4.329905)
			(xy 263.903584 -4.306438) (xy 263.823625 -4.275462) (xy 263.746865 -4.23724) (xy 263.673959 -4.192099)
			(xy 263.60553 -4.140423) (xy 263.54216 -4.082654) (xy 263.484391 -4.019284) (xy 263.432715 -3.950855)
			(xy 263.387574 -3.877949) (xy 263.349352 -3.801189) (xy 263.318376 -3.72123) (xy 263.294909 -3.638754)
			(xy 263.279153 -3.554464) (xy 263.271241 -3.469081) (xy 258.775975 -3.469081) (xy 258.768063 -3.554464)
			(xy 258.752307 -3.638754) (xy 258.72884 -3.72123) (xy 258.697864 -3.801189) (xy 258.659642 -3.877949)
			(xy 258.614501 -3.950855) (xy 258.562825 -4.019284) (xy 258.505056 -4.082654) (xy 258.441686 -4.140423)
			(xy 258.373257 -4.192099) (xy 258.300351 -4.23724) (xy 258.223591 -4.275462) (xy 258.143632 -4.306438)
			(xy 258.061156 -4.329905) (xy 257.976866 -4.345661) (xy 257.891483 -4.353573) (xy 257.805733 -4.353573)
			(xy 257.72035 -4.345661) (xy 257.63606 -4.329905) (xy 257.553584 -4.306438) (xy 257.473625 -4.275462)
			(xy 257.396865 -4.23724) (xy 257.323959 -4.192099) (xy 257.25553 -4.140423) (xy 257.19216 -4.082654)
			(xy 257.134391 -4.019284) (xy 257.082715 -3.950855) (xy 257.037574 -3.877949) (xy 256.999352 -3.801189)
			(xy 256.968376 -3.72123) (xy 256.944909 -3.638754) (xy 256.929153 -3.554464) (xy 256.921241 -3.469081)
			(xy 254.465119 -3.469081) (xy 254.465087 -3.471875) (xy 254.457175 -3.557258) (xy 254.441419 -3.641548)
			(xy 254.417952 -3.724024) (xy 254.386976 -3.803983) (xy 254.348754 -3.880743) (xy 254.303613 -3.953649)
			(xy 254.251937 -4.022078) (xy 254.194168 -4.085448) (xy 254.130798 -4.143217) (xy 254.062369 -4.194893)
			(xy 253.989463 -4.240034) (xy 253.912703 -4.278256) (xy 253.832744 -4.309232) (xy 253.750268 -4.332699)
			(xy 253.665978 -4.348455) (xy 253.580595 -4.356367) (xy 253.494845 -4.356367) (xy 253.409462 -4.348455)
			(xy 253.325172 -4.332699) (xy 253.242696 -4.309232) (xy 253.162737 -4.278256) (xy 253.085977 -4.240034)
			(xy 253.013071 -4.194893) (xy 252.944642 -4.143217) (xy 252.881272 -4.085448) (xy 252.823503 -4.022078)
			(xy 252.771827 -3.953649) (xy 252.726686 -3.880743) (xy 252.688464 -3.803983) (xy 252.657488 -3.724024)
			(xy 252.634021 -3.641548) (xy 252.618265 -3.557258) (xy 252.610353 -3.471875) (xy 248.115087 -3.471875)
			(xy 248.107175 -3.557258) (xy 248.091419 -3.641548) (xy 248.067952 -3.724024) (xy 248.036976 -3.803983)
			(xy 247.998754 -3.880743) (xy 247.953613 -3.953649) (xy 247.901937 -4.022078) (xy 247.844168 -4.085448)
			(xy 247.780798 -4.143217) (xy 247.712369 -4.194893) (xy 247.639463 -4.240034) (xy 247.562703 -4.278256)
			(xy 247.482744 -4.309232) (xy 247.400268 -4.332699) (xy 247.315978 -4.348455) (xy 247.230595 -4.356367)
			(xy 247.144845 -4.356367) (xy 247.059462 -4.348455) (xy 246.975172 -4.332699) (xy 246.892696 -4.309232)
			(xy 246.812737 -4.278256) (xy 246.735977 -4.240034) (xy 246.663071 -4.194893) (xy 246.594642 -4.143217)
			(xy 246.531272 -4.085448) (xy 246.473503 -4.022078) (xy 246.421827 -3.953649) (xy 246.376686 -3.880743)
			(xy 246.338464 -3.803983) (xy 246.307488 -3.724024) (xy 246.284021 -3.641548) (xy 246.268265 -3.557258)
			(xy 246.260353 -3.471875) (xy 216.248247 -3.471875) (xy 216.240335 -3.557258) (xy 216.224579 -3.641548)
			(xy 216.201112 -3.724024) (xy 216.170136 -3.803983) (xy 216.131914 -3.880743) (xy 216.086773 -3.953649)
			(xy 216.035097 -4.022078) (xy 215.977328 -4.085448) (xy 215.913958 -4.143217) (xy 215.845529 -4.194893)
			(xy 215.772623 -4.240034) (xy 215.695863 -4.278256) (xy 215.615904 -4.309232) (xy 215.533428 -4.332699)
			(xy 215.449138 -4.348455) (xy 215.363755 -4.356367) (xy 215.278005 -4.356367) (xy 215.192622 -4.348455)
			(xy 215.108332 -4.332699) (xy 215.025856 -4.309232) (xy 214.945897 -4.278256) (xy 214.869137 -4.240034)
			(xy 214.796231 -4.194893) (xy 214.727802 -4.143217) (xy 214.664432 -4.085448) (xy 214.606663 -4.022078)
			(xy 214.554987 -3.953649) (xy 214.509846 -3.880743) (xy 214.471624 -3.803983) (xy 214.440648 -3.724024)
			(xy 214.417181 -3.641548) (xy 214.401425 -3.557258) (xy 214.393513 -3.471875) (xy 209.898247 -3.471875)
			(xy 209.890335 -3.557258) (xy 209.874579 -3.641548) (xy 209.851112 -3.724024) (xy 209.820136 -3.803983)
			(xy 209.781914 -3.880743) (xy 209.736773 -3.953649) (xy 209.685097 -4.022078) (xy 209.627328 -4.085448)
			(xy 209.563958 -4.143217) (xy 209.495529 -4.194893) (xy 209.422623 -4.240034) (xy 209.345863 -4.278256)
			(xy 209.265904 -4.309232) (xy 209.183428 -4.332699) (xy 209.099138 -4.348455) (xy 209.013755 -4.356367)
			(xy 208.928005 -4.356367) (xy 208.842622 -4.348455) (xy 208.758332 -4.332699) (xy 208.675856 -4.309232)
			(xy 208.595897 -4.278256) (xy 208.519137 -4.240034) (xy 208.446231 -4.194893) (xy 208.377802 -4.143217)
			(xy 208.314432 -4.085448) (xy 208.256663 -4.022078) (xy 208.204987 -3.953649) (xy 208.159846 -3.880743)
			(xy 208.121624 -3.803983) (xy 208.090648 -3.724024) (xy 208.067181 -3.641548) (xy 208.051425 -3.557258)
			(xy 208.043513 -3.471875) (xy 197.075741 -3.471875) (xy 197.091928 -3.518134) (xy 197.13088 -3.653342)
			(xy 197.16219 -3.790521) (xy 197.185759 -3.929239) (xy 197.201513 -4.069061) (xy 197.209403 -4.209547)
			(xy 197.209918 -4.2799) (xy 197.209918 -6.011875) (xy 208.043513 -6.011875) (xy 208.043513 -5.926125)
			(xy 208.051425 -5.840742) (xy 208.067181 -5.756452) (xy 208.090648 -5.673976) (xy 208.121624 -5.594017)
			(xy 208.159846 -5.517257) (xy 208.204987 -5.444351) (xy 208.256663 -5.375922) (xy 208.314432 -5.312552)
			(xy 208.377802 -5.254783) (xy 208.446231 -5.203107) (xy 208.519137 -5.157966) (xy 208.595897 -5.119744)
			(xy 208.675856 -5.088768) (xy 208.758332 -5.065301) (xy 208.842622 -5.049545) (xy 208.928005 -5.041633)
			(xy 209.013755 -5.041633) (xy 209.099138 -5.049545) (xy 209.183428 -5.065301) (xy 209.265904 -5.088768)
			(xy 209.345863 -5.119744) (xy 209.368066 -5.1308) (xy 212.978492 -5.1308) (xy 212.978492 -4.2672)
			(xy 212.978978 -4.239931) (xy 212.98674 -4.185947) (xy 213.002105 -4.133617) (xy 213.024762 -4.084007)
			(xy 213.054248 -4.038126) (xy 213.089963 -3.996909) (xy 213.13118 -3.961194) (xy 213.177061 -3.931708)
			(xy 213.226671 -3.909051) (xy 213.279001 -3.893686) (xy 213.332985 -3.885924) (xy 213.387523 -3.885924)
			(xy 213.441507 -3.893686) (xy 213.493837 -3.909051) (xy 213.543447 -3.931708) (xy 213.589328 -3.961194)
			(xy 213.630545 -3.996909) (xy 213.66626 -4.038126) (xy 213.695746 -4.084007) (xy 213.718403 -4.133617)
			(xy 213.733768 -4.185947) (xy 213.74153 -4.239931) (xy 213.742016 -4.2672) (xy 213.742016 -5.1308)
			(xy 213.74153 -5.158069) (xy 213.733768 -5.212053) (xy 213.718403 -5.264383) (xy 213.695746 -5.313993)
			(xy 213.66626 -5.359874) (xy 213.630545 -5.401091) (xy 213.589328 -5.436806) (xy 213.543447 -5.466292)
			(xy 213.493837 -5.488949) (xy 213.441507 -5.504314) (xy 213.387523 -5.512076) (xy 213.332985 -5.512076)
			(xy 213.279001 -5.504314) (xy 213.226671 -5.488949) (xy 213.177061 -5.466292) (xy 213.13118 -5.436806)
			(xy 213.089963 -5.401091) (xy 213.054248 -5.359874) (xy 213.024762 -5.313993) (xy 213.002105 -5.264383)
			(xy 212.98674 -5.212053) (xy 212.978978 -5.158069) (xy 212.978492 -5.1308) (xy 209.368066 -5.1308)
			(xy 209.422623 -5.157966) (xy 209.495529 -5.203107) (xy 209.563958 -5.254783) (xy 209.627328 -5.312552)
			(xy 209.685097 -5.375922) (xy 209.736773 -5.444351) (xy 209.781914 -5.517257) (xy 209.820136 -5.594017)
			(xy 209.851112 -5.673976) (xy 209.874579 -5.756452) (xy 209.890335 -5.840742) (xy 209.898247 -5.926125)
			(xy 209.898742 -5.969) (xy 209.898247 -6.011875) (xy 214.393513 -6.011875) (xy 214.393513 -5.926125)
			(xy 214.401425 -5.840742) (xy 214.417181 -5.756452) (xy 214.440648 -5.673976) (xy 214.471624 -5.594017)
			(xy 214.509846 -5.517257) (xy 214.554987 -5.444351) (xy 214.606663 -5.375922) (xy 214.664432 -5.312552)
			(xy 214.727802 -5.254783) (xy 214.796231 -5.203107) (xy 214.869137 -5.157966) (xy 214.945897 -5.119744)
			(xy 215.025856 -5.088768) (xy 215.108332 -5.065301) (xy 215.192622 -5.049545) (xy 215.278005 -5.041633)
			(xy 215.363755 -5.041633) (xy 215.449138 -5.049545) (xy 215.533428 -5.065301) (xy 215.615904 -5.088768)
			(xy 215.695863 -5.119744) (xy 215.772623 -5.157966) (xy 215.845529 -5.203107) (xy 215.913958 -5.254783)
			(xy 215.977328 -5.312552) (xy 216.035097 -5.375922) (xy 216.086773 -5.444351) (xy 216.131914 -5.517257)
			(xy 216.170136 -5.594017) (xy 216.201112 -5.673976) (xy 216.224579 -5.756452) (xy 216.240335 -5.840742)
			(xy 216.248247 -5.926125) (xy 216.248742 -5.969) (xy 216.248247 -6.011875) (xy 246.260353 -6.011875)
			(xy 246.260353 -5.926125) (xy 246.268265 -5.840742) (xy 246.284021 -5.756452) (xy 246.307488 -5.673976)
			(xy 246.338464 -5.594017) (xy 246.376686 -5.517257) (xy 246.421827 -5.444351) (xy 246.473503 -5.375922)
			(xy 246.531272 -5.312552) (xy 246.594642 -5.254783) (xy 246.663071 -5.203107) (xy 246.735977 -5.157966)
			(xy 246.812737 -5.119744) (xy 246.892696 -5.088768) (xy 246.975172 -5.065301) (xy 247.059462 -5.049545)
			(xy 247.144845 -5.041633) (xy 247.230595 -5.041633) (xy 247.315978 -5.049545) (xy 247.400268 -5.065301)
			(xy 247.482744 -5.088768) (xy 247.562703 -5.119744) (xy 247.584906 -5.1308) (xy 248.766584 -5.1308)
			(xy 248.766584 -4.2672) (xy 248.76707 -4.239931) (xy 248.774832 -4.185947) (xy 248.790197 -4.133617)
			(xy 248.812854 -4.084007) (xy 248.84234 -4.038126) (xy 248.878055 -3.996909) (xy 248.919272 -3.961194)
			(xy 248.965153 -3.931708) (xy 249.014763 -3.909051) (xy 249.067093 -3.893686) (xy 249.121077 -3.885924)
			(xy 249.175615 -3.885924) (xy 249.229599 -3.893686) (xy 249.281929 -3.909051) (xy 249.331539 -3.931708)
			(xy 249.37742 -3.961194) (xy 249.418637 -3.996909) (xy 249.454352 -4.038126) (xy 249.483838 -4.084007)
			(xy 249.506495 -4.133617) (xy 249.52186 -4.185947) (xy 249.529622 -4.239931) (xy 249.530108 -4.2672)
			(xy 249.530108 -5.1308) (xy 249.529622 -5.158069) (xy 249.52186 -5.212053) (xy 249.506495 -5.264383)
			(xy 249.483838 -5.313993) (xy 249.454352 -5.359874) (xy 249.418637 -5.401091) (xy 249.37742 -5.436806)
			(xy 249.331539 -5.466292) (xy 249.281929 -5.488949) (xy 249.229599 -5.504314) (xy 249.175615 -5.512076)
			(xy 249.121077 -5.512076) (xy 249.067093 -5.504314) (xy 249.014763 -5.488949) (xy 248.965153 -5.466292)
			(xy 248.919272 -5.436806) (xy 248.878055 -5.401091) (xy 248.84234 -5.359874) (xy 248.812854 -5.313993)
			(xy 248.790197 -5.264383) (xy 248.774832 -5.212053) (xy 248.76707 -5.158069) (xy 248.766584 -5.1308)
			(xy 247.584906 -5.1308) (xy 247.639463 -5.157966) (xy 247.712369 -5.203107) (xy 247.780798 -5.254783)
			(xy 247.844168 -5.312552) (xy 247.901937 -5.375922) (xy 247.953613 -5.444351) (xy 247.998754 -5.517257)
			(xy 248.036976 -5.594017) (xy 248.067952 -5.673976) (xy 248.091419 -5.756452) (xy 248.107175 -5.840742)
			(xy 248.115087 -5.926125) (xy 248.115582 -5.969) (xy 248.115087 -6.011875) (xy 252.610353 -6.011875)
			(xy 252.610353 -5.926125) (xy 252.618265 -5.840742) (xy 252.634021 -5.756452) (xy 252.657488 -5.673976)
			(xy 252.688464 -5.594017) (xy 252.726686 -5.517257) (xy 252.771827 -5.444351) (xy 252.823503 -5.375922)
			(xy 252.881272 -5.312552) (xy 252.944642 -5.254783) (xy 253.013071 -5.203107) (xy 253.085977 -5.157966)
			(xy 253.162737 -5.119744) (xy 253.242696 -5.088768) (xy 253.325172 -5.065301) (xy 253.409462 -5.049545)
			(xy 253.494845 -5.041633) (xy 253.580595 -5.041633) (xy 253.665978 -5.049545) (xy 253.750268 -5.065301)
			(xy 253.832744 -5.088768) (xy 253.912703 -5.119744) (xy 253.989463 -5.157966) (xy 254.062369 -5.203107)
			(xy 254.130798 -5.254783) (xy 254.194168 -5.312552) (xy 254.251937 -5.375922) (xy 254.303613 -5.444351)
			(xy 254.348754 -5.517257) (xy 254.386976 -5.594017) (xy 254.417952 -5.673976) (xy 254.441419 -5.756452)
			(xy 254.457175 -5.840742) (xy 254.465087 -5.926125) (xy 254.465582 -5.969) (xy 254.465119 -6.009081)
			(xy 256.921241 -6.009081) (xy 256.921241 -5.923331) (xy 256.929153 -5.837948) (xy 256.944909 -5.753658)
			(xy 256.968376 -5.671182) (xy 256.999352 -5.591223) (xy 257.037574 -5.514463) (xy 257.082715 -5.441557)
			(xy 257.134391 -5.373128) (xy 257.19216 -5.309758) (xy 257.25553 -5.251989) (xy 257.323959 -5.200313)
			(xy 257.396865 -5.155172) (xy 257.473625 -5.11695) (xy 257.553584 -5.085974) (xy 257.63606 -5.062507)
			(xy 257.72035 -5.046751) (xy 257.805733 -5.038839) (xy 257.891483 -5.038839) (xy 257.976866 -5.046751)
			(xy 258.061156 -5.062507) (xy 258.143632 -5.085974) (xy 258.223591 -5.11695) (xy 258.300351 -5.155172)
			(xy 258.373257 -5.200313) (xy 258.441686 -5.251989) (xy 258.505056 -5.309758) (xy 258.562825 -5.373128)
			(xy 258.614501 -5.441557) (xy 258.659642 -5.514463) (xy 258.697864 -5.591223) (xy 258.72884 -5.671182)
			(xy 258.752307 -5.753658) (xy 258.768063 -5.837948) (xy 258.775975 -5.923331) (xy 258.77647 -5.966206)
			(xy 258.775975 -6.009081) (xy 263.271241 -6.009081) (xy 263.271241 -5.923331) (xy 263.279153 -5.837948)
			(xy 263.294909 -5.753658) (xy 263.318376 -5.671182) (xy 263.349352 -5.591223) (xy 263.387574 -5.514463)
			(xy 263.432715 -5.441557) (xy 263.484391 -5.373128) (xy 263.54216 -5.309758) (xy 263.60553 -5.251989)
			(xy 263.673959 -5.200313) (xy 263.746865 -5.155172) (xy 263.823625 -5.11695) (xy 263.903584 -5.085974)
			(xy 263.98606 -5.062507) (xy 264.07035 -5.046751) (xy 264.155733 -5.038839) (xy 264.241483 -5.038839)
			(xy 264.326866 -5.046751) (xy 264.411156 -5.062507) (xy 264.493632 -5.085974) (xy 264.573591 -5.11695)
			(xy 264.650351 -5.155172) (xy 264.723257 -5.200313) (xy 264.791686 -5.251989) (xy 264.855056 -5.309758)
			(xy 264.912825 -5.373128) (xy 264.964501 -5.441557) (xy 265.009642 -5.514463) (xy 265.047864 -5.591223)
			(xy 265.07884 -5.671182) (xy 265.102307 -5.753658) (xy 265.118063 -5.837948) (xy 265.125975 -5.923331)
			(xy 265.12647 -5.966206) (xy 265.125975 -6.009081) (xy 324.845921 -6.009081) (xy 324.845921 -5.923331)
			(xy 324.853833 -5.837948) (xy 324.869589 -5.753658) (xy 324.893056 -5.671182) (xy 324.924032 -5.591223)
			(xy 324.962254 -5.514463) (xy 325.007395 -5.441557) (xy 325.059071 -5.373128) (xy 325.11684 -5.309758)
			(xy 325.18021 -5.251989) (xy 325.248639 -5.200313) (xy 325.321545 -5.155172) (xy 325.398305 -5.11695)
			(xy 325.478264 -5.085974) (xy 325.56074 -5.062507) (xy 325.64503 -5.046751) (xy 325.730413 -5.038839)
			(xy 325.816163 -5.038839) (xy 325.901546 -5.046751) (xy 325.985836 -5.062507) (xy 326.068312 -5.085974)
			(xy 326.148271 -5.11695) (xy 326.225031 -5.155172) (xy 326.297937 -5.200313) (xy 326.366366 -5.251989)
			(xy 326.429736 -5.309758) (xy 326.487505 -5.373128) (xy 326.539181 -5.441557) (xy 326.584322 -5.514463)
			(xy 326.622544 -5.591223) (xy 326.65352 -5.671182) (xy 326.676987 -5.753658) (xy 326.692743 -5.837948)
			(xy 326.700655 -5.923331) (xy 326.70115 -5.966206) (xy 326.700655 -6.009081) (xy 331.195921 -6.009081)
			(xy 331.195921 -5.923331) (xy 331.203833 -5.837948) (xy 331.219589 -5.753658) (xy 331.243056 -5.671182)
			(xy 331.274032 -5.591223) (xy 331.312254 -5.514463) (xy 331.357395 -5.441557) (xy 331.409071 -5.373128)
			(xy 331.46684 -5.309758) (xy 331.53021 -5.251989) (xy 331.598639 -5.200313) (xy 331.671545 -5.155172)
			(xy 331.748305 -5.11695) (xy 331.828264 -5.085974) (xy 331.91074 -5.062507) (xy 331.99503 -5.046751)
			(xy 332.080413 -5.038839) (xy 332.166163 -5.038839) (xy 332.251546 -5.046751) (xy 332.335836 -5.062507)
			(xy 332.418312 -5.085974) (xy 332.498271 -5.11695) (xy 332.575031 -5.155172) (xy 332.647937 -5.200313)
			(xy 332.716366 -5.251989) (xy 332.779736 -5.309758) (xy 332.837505 -5.373128) (xy 332.889181 -5.441557)
			(xy 332.934322 -5.514463) (xy 332.972544 -5.591223) (xy 333.00352 -5.671182) (xy 333.026987 -5.753658)
			(xy 333.042743 -5.837948) (xy 333.050655 -5.923331) (xy 333.05115 -5.966206) (xy 333.050655 -6.009081)
			(xy 335.488267 -6.009081) (xy 335.488267 -5.923331) (xy 335.496179 -5.837948) (xy 335.511935 -5.753658)
			(xy 335.535402 -5.671182) (xy 335.566378 -5.591223) (xy 335.6046 -5.514463) (xy 335.649741 -5.441557)
			(xy 335.701417 -5.373128) (xy 335.759186 -5.309758) (xy 335.822556 -5.251989) (xy 335.890985 -5.200313)
			(xy 335.963891 -5.155172) (xy 336.040651 -5.11695) (xy 336.12061 -5.085974) (xy 336.203086 -5.062507)
			(xy 336.287376 -5.046751) (xy 336.372759 -5.038839) (xy 336.458509 -5.038839) (xy 336.543892 -5.046751)
			(xy 336.628182 -5.062507) (xy 336.710658 -5.085974) (xy 336.790617 -5.11695) (xy 336.867377 -5.155172)
			(xy 336.940283 -5.200313) (xy 337.008712 -5.251989) (xy 337.072082 -5.309758) (xy 337.129851 -5.373128)
			(xy 337.181527 -5.441557) (xy 337.226668 -5.514463) (xy 337.26489 -5.591223) (xy 337.295866 -5.671182)
			(xy 337.319333 -5.753658) (xy 337.335089 -5.837948) (xy 337.343001 -5.923331) (xy 337.343496 -5.966206)
			(xy 337.343001 -6.009081) (xy 341.838267 -6.009081) (xy 341.838267 -5.923331) (xy 341.846179 -5.837948)
			(xy 341.861935 -5.753658) (xy 341.885402 -5.671182) (xy 341.916378 -5.591223) (xy 341.9546 -5.514463)
			(xy 341.999741 -5.441557) (xy 342.051417 -5.373128) (xy 342.109186 -5.309758) (xy 342.172556 -5.251989)
			(xy 342.240985 -5.200313) (xy 342.313891 -5.155172) (xy 342.390651 -5.11695) (xy 342.47061 -5.085974)
			(xy 342.553086 -5.062507) (xy 342.637376 -5.046751) (xy 342.722759 -5.038839) (xy 342.808509 -5.038839)
			(xy 342.893892 -5.046751) (xy 342.978182 -5.062507) (xy 343.060658 -5.085974) (xy 343.140617 -5.11695)
			(xy 343.217377 -5.155172) (xy 343.290283 -5.200313) (xy 343.358712 -5.251989) (xy 343.422082 -5.309758)
			(xy 343.479851 -5.373128) (xy 343.531527 -5.441557) (xy 343.576668 -5.514463) (xy 343.61489 -5.591223)
			(xy 343.645866 -5.671182) (xy 343.669333 -5.753658) (xy 343.685089 -5.837948) (xy 343.693001 -5.923331)
			(xy 343.693496 -5.966206) (xy 343.693001 -6.009081) (xy 373.705107 -6.009081) (xy 373.705107 -5.923331)
			(xy 373.713019 -5.837948) (xy 373.728775 -5.753658) (xy 373.752242 -5.671182) (xy 373.783218 -5.591223)
			(xy 373.82144 -5.514463) (xy 373.866581 -5.441557) (xy 373.918257 -5.373128) (xy 373.976026 -5.309758)
			(xy 374.039396 -5.251989) (xy 374.107825 -5.200313) (xy 374.180731 -5.155172) (xy 374.257491 -5.11695)
			(xy 374.33745 -5.085974) (xy 374.419926 -5.062507) (xy 374.504216 -5.046751) (xy 374.589599 -5.038839)
			(xy 374.675349 -5.038839) (xy 374.760732 -5.046751) (xy 374.845022 -5.062507) (xy 374.927498 -5.085974)
			(xy 375.007457 -5.11695) (xy 375.084217 -5.155172) (xy 375.157123 -5.200313) (xy 375.225552 -5.251989)
			(xy 375.288922 -5.309758) (xy 375.346691 -5.373128) (xy 375.398367 -5.441557) (xy 375.443508 -5.514463)
			(xy 375.48173 -5.591223) (xy 375.512706 -5.671182) (xy 375.536173 -5.753658) (xy 375.551929 -5.837948)
			(xy 375.559841 -5.923331) (xy 375.560336 -5.966206) (xy 375.559841 -6.009081) (xy 380.055107 -6.009081)
			(xy 380.055107 -5.923331) (xy 380.063019 -5.837948) (xy 380.078775 -5.753658) (xy 380.102242 -5.671182)
			(xy 380.133218 -5.591223) (xy 380.17144 -5.514463) (xy 380.216581 -5.441557) (xy 380.268257 -5.373128)
			(xy 380.326026 -5.309758) (xy 380.389396 -5.251989) (xy 380.457825 -5.200313) (xy 380.530731 -5.155172)
			(xy 380.607491 -5.11695) (xy 380.68745 -5.085974) (xy 380.769926 -5.062507) (xy 380.854216 -5.046751)
			(xy 380.939599 -5.038839) (xy 381.025349 -5.038839) (xy 381.110732 -5.046751) (xy 381.195022 -5.062507)
			(xy 381.277498 -5.085974) (xy 381.357457 -5.11695) (xy 381.434217 -5.155172) (xy 381.507123 -5.200313)
			(xy 381.575552 -5.251989) (xy 381.638922 -5.309758) (xy 381.696691 -5.373128) (xy 381.748367 -5.441557)
			(xy 381.793508 -5.514463) (xy 381.83173 -5.591223) (xy 381.862706 -5.671182) (xy 381.886173 -5.753658)
			(xy 381.901929 -5.837948) (xy 381.909841 -5.923331) (xy 381.910336 -5.966206) (xy 381.909841 -6.009081)
			(xy 381.901929 -6.094464) (xy 381.886173 -6.178754) (xy 381.862706 -6.26123) (xy 381.83173 -6.341189)
			(xy 381.793508 -6.417949) (xy 381.748367 -6.490855) (xy 381.696691 -6.559284) (xy 381.638922 -6.622654)
			(xy 381.575552 -6.680423) (xy 381.507123 -6.732099) (xy 381.434217 -6.77724) (xy 381.357457 -6.815462)
			(xy 381.277498 -6.846438) (xy 381.195022 -6.869905) (xy 381.110732 -6.885661) (xy 381.025349 -6.893573)
			(xy 380.939599 -6.893573) (xy 380.854216 -6.885661) (xy 380.769926 -6.869905) (xy 380.68745 -6.846438)
			(xy 380.607491 -6.815462) (xy 380.530731 -6.77724) (xy 380.457825 -6.732099) (xy 380.389396 -6.680423)
			(xy 380.326026 -6.622654) (xy 380.268257 -6.559284) (xy 380.216581 -6.490855) (xy 380.17144 -6.417949)
			(xy 380.133218 -6.341189) (xy 380.102242 -6.26123) (xy 380.078775 -6.178754) (xy 380.063019 -6.094464)
			(xy 380.055107 -6.009081) (xy 375.559841 -6.009081) (xy 375.551929 -6.094464) (xy 375.536173 -6.178754)
			(xy 375.512706 -6.26123) (xy 375.48173 -6.341189) (xy 375.443508 -6.417949) (xy 375.398367 -6.490855)
			(xy 375.346691 -6.559284) (xy 375.288922 -6.622654) (xy 375.225552 -6.680423) (xy 375.157123 -6.732099)
			(xy 375.084217 -6.77724) (xy 375.007457 -6.815462) (xy 374.927498 -6.846438) (xy 374.845022 -6.869905)
			(xy 374.760732 -6.885661) (xy 374.675349 -6.893573) (xy 374.589599 -6.893573) (xy 374.504216 -6.885661)
			(xy 374.419926 -6.869905) (xy 374.33745 -6.846438) (xy 374.257491 -6.815462) (xy 374.180731 -6.77724)
			(xy 374.107825 -6.732099) (xy 374.039396 -6.680423) (xy 373.976026 -6.622654) (xy 373.918257 -6.559284)
			(xy 373.866581 -6.490855) (xy 373.82144 -6.417949) (xy 373.783218 -6.341189) (xy 373.752242 -6.26123)
			(xy 373.728775 -6.178754) (xy 373.713019 -6.094464) (xy 373.705107 -6.009081) (xy 343.693001 -6.009081)
			(xy 343.685089 -6.094464) (xy 343.669333 -6.178754) (xy 343.645866 -6.26123) (xy 343.61489 -6.341189)
			(xy 343.576668 -6.417949) (xy 343.531527 -6.490855) (xy 343.479851 -6.559284) (xy 343.422082 -6.622654)
			(xy 343.358712 -6.680423) (xy 343.290283 -6.732099) (xy 343.217377 -6.77724) (xy 343.140617 -6.815462)
			(xy 343.060658 -6.846438) (xy 342.978182 -6.869905) (xy 342.893892 -6.885661) (xy 342.808509 -6.893573)
			(xy 342.722759 -6.893573) (xy 342.637376 -6.885661) (xy 342.553086 -6.869905) (xy 342.47061 -6.846438)
			(xy 342.390651 -6.815462) (xy 342.313891 -6.77724) (xy 342.240985 -6.732099) (xy 342.172556 -6.680423)
			(xy 342.109186 -6.622654) (xy 342.051417 -6.559284) (xy 341.999741 -6.490855) (xy 341.9546 -6.417949)
			(xy 341.916378 -6.341189) (xy 341.885402 -6.26123) (xy 341.861935 -6.178754) (xy 341.846179 -6.094464)
			(xy 341.838267 -6.009081) (xy 337.343001 -6.009081) (xy 337.335089 -6.094464) (xy 337.319333 -6.178754)
			(xy 337.295866 -6.26123) (xy 337.26489 -6.341189) (xy 337.226668 -6.417949) (xy 337.181527 -6.490855)
			(xy 337.129851 -6.559284) (xy 337.072082 -6.622654) (xy 337.008712 -6.680423) (xy 336.940283 -6.732099)
			(xy 336.867377 -6.77724) (xy 336.790617 -6.815462) (xy 336.710658 -6.846438) (xy 336.628182 -6.869905)
			(xy 336.543892 -6.885661) (xy 336.458509 -6.893573) (xy 336.372759 -6.893573) (xy 336.287376 -6.885661)
			(xy 336.203086 -6.869905) (xy 336.12061 -6.846438) (xy 336.040651 -6.815462) (xy 335.963891 -6.77724)
			(xy 335.890985 -6.732099) (xy 335.822556 -6.680423) (xy 335.759186 -6.622654) (xy 335.701417 -6.559284)
			(xy 335.649741 -6.490855) (xy 335.6046 -6.417949) (xy 335.566378 -6.341189) (xy 335.535402 -6.26123)
			(xy 335.511935 -6.178754) (xy 335.496179 -6.094464) (xy 335.488267 -6.009081) (xy 333.050655 -6.009081)
			(xy 333.042743 -6.094464) (xy 333.026987 -6.178754) (xy 333.00352 -6.26123) (xy 332.972544 -6.341189)
			(xy 332.934322 -6.417949) (xy 332.889181 -6.490855) (xy 332.837505 -6.559284) (xy 332.779736 -6.622654)
			(xy 332.716366 -6.680423) (xy 332.647937 -6.732099) (xy 332.575031 -6.77724) (xy 332.498271 -6.815462)
			(xy 332.418312 -6.846438) (xy 332.335836 -6.869905) (xy 332.251546 -6.885661) (xy 332.166163 -6.893573)
			(xy 332.080413 -6.893573) (xy 331.99503 -6.885661) (xy 331.91074 -6.869905) (xy 331.828264 -6.846438)
			(xy 331.748305 -6.815462) (xy 331.671545 -6.77724) (xy 331.598639 -6.732099) (xy 331.53021 -6.680423)
			(xy 331.46684 -6.622654) (xy 331.409071 -6.559284) (xy 331.357395 -6.490855) (xy 331.312254 -6.417949)
			(xy 331.274032 -6.341189) (xy 331.243056 -6.26123) (xy 331.219589 -6.178754) (xy 331.203833 -6.094464)
			(xy 331.195921 -6.009081) (xy 326.700655 -6.009081) (xy 326.692743 -6.094464) (xy 326.676987 -6.178754)
			(xy 326.65352 -6.26123) (xy 326.622544 -6.341189) (xy 326.584322 -6.417949) (xy 326.539181 -6.490855)
			(xy 326.487505 -6.559284) (xy 326.429736 -6.622654) (xy 326.366366 -6.680423) (xy 326.297937 -6.732099)
			(xy 326.225031 -6.77724) (xy 326.148271 -6.815462) (xy 326.068312 -6.846438) (xy 325.985836 -6.869905)
			(xy 325.901546 -6.885661) (xy 325.816163 -6.893573) (xy 325.730413 -6.893573) (xy 325.64503 -6.885661)
			(xy 325.56074 -6.869905) (xy 325.478264 -6.846438) (xy 325.398305 -6.815462) (xy 325.321545 -6.77724)
			(xy 325.248639 -6.732099) (xy 325.18021 -6.680423) (xy 325.11684 -6.622654) (xy 325.059071 -6.559284)
			(xy 325.007395 -6.490855) (xy 324.962254 -6.417949) (xy 324.924032 -6.341189) (xy 324.893056 -6.26123)
			(xy 324.869589 -6.178754) (xy 324.853833 -6.094464) (xy 324.845921 -6.009081) (xy 265.125975 -6.009081)
			(xy 265.118063 -6.094464) (xy 265.102307 -6.178754) (xy 265.07884 -6.26123) (xy 265.047864 -6.341189)
			(xy 265.009642 -6.417949) (xy 264.964501 -6.490855) (xy 264.912825 -6.559284) (xy 264.855056 -6.622654)
			(xy 264.791686 -6.680423) (xy 264.723257 -6.732099) (xy 264.650351 -6.77724) (xy 264.573591 -6.815462)
			(xy 264.493632 -6.846438) (xy 264.411156 -6.869905) (xy 264.326866 -6.885661) (xy 264.241483 -6.893573)
			(xy 264.155733 -6.893573) (xy 264.07035 -6.885661) (xy 263.98606 -6.869905) (xy 263.903584 -6.846438)
			(xy 263.823625 -6.815462) (xy 263.746865 -6.77724) (xy 263.673959 -6.732099) (xy 263.60553 -6.680423)
			(xy 263.54216 -6.622654) (xy 263.484391 -6.559284) (xy 263.432715 -6.490855) (xy 263.387574 -6.417949)
			(xy 263.349352 -6.341189) (xy 263.318376 -6.26123) (xy 263.294909 -6.178754) (xy 263.279153 -6.094464)
			(xy 263.271241 -6.009081) (xy 258.775975 -6.009081) (xy 258.768063 -6.094464) (xy 258.752307 -6.178754)
			(xy 258.72884 -6.26123) (xy 258.697864 -6.341189) (xy 258.659642 -6.417949) (xy 258.614501 -6.490855)
			(xy 258.562825 -6.559284) (xy 258.505056 -6.622654) (xy 258.441686 -6.680423) (xy 258.373257 -6.732099)
			(xy 258.300351 -6.77724) (xy 258.223591 -6.815462) (xy 258.143632 -6.846438) (xy 258.061156 -6.869905)
			(xy 257.976866 -6.885661) (xy 257.891483 -6.893573) (xy 257.805733 -6.893573) (xy 257.72035 -6.885661)
			(xy 257.63606 -6.869905) (xy 257.553584 -6.846438) (xy 257.473625 -6.815462) (xy 257.396865 -6.77724)
			(xy 257.323959 -6.732099) (xy 257.25553 -6.680423) (xy 257.19216 -6.622654) (xy 257.134391 -6.559284)
			(xy 257.082715 -6.490855) (xy 257.037574 -6.417949) (xy 256.999352 -6.341189) (xy 256.968376 -6.26123)
			(xy 256.944909 -6.178754) (xy 256.929153 -6.094464) (xy 256.921241 -6.009081) (xy 254.465119 -6.009081)
			(xy 254.465087 -6.011875) (xy 254.457175 -6.097258) (xy 254.441419 -6.181548) (xy 254.417952 -6.264024)
			(xy 254.386976 -6.343983) (xy 254.348754 -6.420743) (xy 254.303613 -6.493649) (xy 254.251937 -6.562078)
			(xy 254.194168 -6.625448) (xy 254.130798 -6.683217) (xy 254.062369 -6.734893) (xy 253.989463 -6.780034)
			(xy 253.912703 -6.818256) (xy 253.832744 -6.849232) (xy 253.750268 -6.872699) (xy 253.665978 -6.888455)
			(xy 253.580595 -6.896367) (xy 253.494845 -6.896367) (xy 253.409462 -6.888455) (xy 253.325172 -6.872699)
			(xy 253.242696 -6.849232) (xy 253.162737 -6.818256) (xy 253.085977 -6.780034) (xy 253.013071 -6.734893)
			(xy 252.944642 -6.683217) (xy 252.881272 -6.625448) (xy 252.823503 -6.562078) (xy 252.771827 -6.493649)
			(xy 252.726686 -6.420743) (xy 252.688464 -6.343983) (xy 252.657488 -6.264024) (xy 252.634021 -6.181548)
			(xy 252.618265 -6.097258) (xy 252.610353 -6.011875) (xy 248.115087 -6.011875) (xy 248.107175 -6.097258)
			(xy 248.091419 -6.181548) (xy 248.067952 -6.264024) (xy 248.036976 -6.343983) (xy 247.998754 -6.420743)
			(xy 247.953613 -6.493649) (xy 247.901937 -6.562078) (xy 247.844168 -6.625448) (xy 247.780798 -6.683217)
			(xy 247.712369 -6.734893) (xy 247.639463 -6.780034) (xy 247.562703 -6.818256) (xy 247.482744 -6.849232)
			(xy 247.400268 -6.872699) (xy 247.315978 -6.888455) (xy 247.230595 -6.896367) (xy 247.144845 -6.896367)
			(xy 247.059462 -6.888455) (xy 246.975172 -6.872699) (xy 246.892696 -6.849232) (xy 246.812737 -6.818256)
			(xy 246.735977 -6.780034) (xy 246.663071 -6.734893) (xy 246.594642 -6.683217) (xy 246.531272 -6.625448)
			(xy 246.473503 -6.562078) (xy 246.421827 -6.493649) (xy 246.376686 -6.420743) (xy 246.338464 -6.343983)
			(xy 246.307488 -6.264024) (xy 246.284021 -6.181548) (xy 246.268265 -6.097258) (xy 246.260353 -6.011875)
			(xy 216.248247 -6.011875) (xy 216.240335 -6.097258) (xy 216.224579 -6.181548) (xy 216.201112 -6.264024)
			(xy 216.170136 -6.343983) (xy 216.131914 -6.420743) (xy 216.086773 -6.493649) (xy 216.035097 -6.562078)
			(xy 215.977328 -6.625448) (xy 215.913958 -6.683217) (xy 215.845529 -6.734893) (xy 215.772623 -6.780034)
			(xy 215.695863 -6.818256) (xy 215.615904 -6.849232) (xy 215.533428 -6.872699) (xy 215.449138 -6.888455)
			(xy 215.363755 -6.896367) (xy 215.278005 -6.896367) (xy 215.192622 -6.888455) (xy 215.108332 -6.872699)
			(xy 215.025856 -6.849232) (xy 214.945897 -6.818256) (xy 214.869137 -6.780034) (xy 214.796231 -6.734893)
			(xy 214.727802 -6.683217) (xy 214.664432 -6.625448) (xy 214.606663 -6.562078) (xy 214.554987 -6.493649)
			(xy 214.509846 -6.420743) (xy 214.471624 -6.343983) (xy 214.440648 -6.264024) (xy 214.417181 -6.181548)
			(xy 214.401425 -6.097258) (xy 214.393513 -6.011875) (xy 209.898247 -6.011875) (xy 209.890335 -6.097258)
			(xy 209.874579 -6.181548) (xy 209.851112 -6.264024) (xy 209.820136 -6.343983) (xy 209.781914 -6.420743)
			(xy 209.736773 -6.493649) (xy 209.685097 -6.562078) (xy 209.627328 -6.625448) (xy 209.563958 -6.683217)
			(xy 209.495529 -6.734893) (xy 209.422623 -6.780034) (xy 209.345863 -6.818256) (xy 209.265904 -6.849232)
			(xy 209.183428 -6.872699) (xy 209.099138 -6.888455) (xy 209.013755 -6.896367) (xy 208.928005 -6.896367)
			(xy 208.842622 -6.888455) (xy 208.758332 -6.872699) (xy 208.675856 -6.849232) (xy 208.595897 -6.818256)
			(xy 208.519137 -6.780034) (xy 208.446231 -6.734893) (xy 208.377802 -6.683217) (xy 208.314432 -6.625448)
			(xy 208.256663 -6.562078) (xy 208.204987 -6.493649) (xy 208.159846 -6.420743) (xy 208.121624 -6.343983)
			(xy 208.090648 -6.264024) (xy 208.067181 -6.181548) (xy 208.051425 -6.097258) (xy 208.043513 -6.011875)
			(xy 197.209918 -6.011875) (xy 197.209918 -7.78002) (xy 197.21044 -7.835826) (xy 197.218783 -7.947127)
			(xy 197.235419 -8.057493) (xy 197.260257 -8.166307) (xy 197.293157 -8.27296) (xy 197.333935 -8.376857)
			(xy 197.382363 -8.477416) (xy 197.43817 -8.574075) (xy 197.501045 -8.666293) (xy 197.570635 -8.753555)
			(xy 197.646552 -8.835372) (xy 197.728371 -8.911287) (xy 197.815634 -8.980875) (xy 197.907854 -9.043748)
			(xy 198.004514 -9.099553) (xy 198.105074 -9.147979) (xy 198.208972 -9.188755) (xy 198.315626 -9.221652)
			(xy 198.424441 -9.246487) (xy 198.534807 -9.263121) (xy 198.646108 -9.271461) (xy 198.701914 -9.272016)
			(xy 223.300036 -9.272016) (xy 223.370389 -9.27251) (xy 223.510873 -9.280402) (xy 223.650694 -9.296158)
			(xy 223.789412 -9.319729) (xy 223.92659 -9.35104) (xy 224.061796 -9.389995) (xy 224.194606 -9.436468)
			(xy 224.3246 -9.490316) (xy 224.451371 -9.551367) (xy 224.57452 -9.619431) (xy 224.693658 -9.694292)
			(xy 224.808411 -9.775716) (xy 224.918419 -9.863446) (xy 225.023334 -9.957206) (xy 225.122827 -10.056701)
			(xy 225.216585 -10.161618) (xy 225.304313 -10.271627) (xy 225.385734 -10.386382) (xy 225.460594 -10.505522)
			(xy 225.528655 -10.628671) (xy 225.589704 -10.755444) (xy 225.643549 -10.885439) (xy 225.69002 -11.01825)
			(xy 225.728972 -11.153457) (xy 225.760281 -11.290635) (xy 225.783849 -11.429353) (xy 225.799602 -11.569174)
			(xy 225.807491 -11.709659) (xy 225.808032 -11.780012) (xy 225.808032 -31.197296) (xy 227.377752 -32.767016)
			(xy 254.645668 -32.767016)
		)
		(stroke
			(width 0)
			(type solid)
		)
		(fill yes)
		(layer "In8.Cu")
		(net "DELTA_L_GND_1")
	)
	(gr_poly
		(pts
			(xy 58.144156 -440.42203) (xy 58.148885 -440.390461) (xy 58.165188 -440.328742) (xy 58.189058 -440.269538)
			(xy 58.220124 -440.213771) (xy 58.257901 -440.162313) (xy 58.301798 -440.115967) (xy 58.351131 -440.075455)
			(xy 58.40513 -440.04141) (xy 58.462953 -440.014364) (xy 58.523697 -439.994738) (xy 58.586413 -439.982838)
			(xy 58.650124 -439.978851) (xy 58.713835 -439.982838) (xy 58.776551 -439.994738) (xy 58.837295 -440.014364)
			(xy 58.895118 -440.04141) (xy 58.949117 -440.075455) (xy 58.99845 -440.115967) (xy 59.042347 -440.162313)
			(xy 59.080124 -440.213771) (xy 59.11119 -440.269538) (xy 59.13506 -440.328742) (xy 59.151363 -440.390461)
			(xy 59.156092 -440.42203) (xy 59.161934 -440.465972) (xy 62.138306 -440.465972) (xy 62.144148 -440.42203)
			(xy 62.148877 -440.390461) (xy 62.16518 -440.328742) (xy 62.18905 -440.269538) (xy 62.220116 -440.213771)
			(xy 62.257893 -440.162313) (xy 62.30179 -440.115967) (xy 62.351123 -440.075455) (xy 62.405122 -440.04141)
			(xy 62.462945 -440.014364) (xy 62.523689 -439.994738) (xy 62.586405 -439.982838) (xy 62.650116 -439.978851)
			(xy 62.713827 -439.982838) (xy 62.776543 -439.994738) (xy 62.837287 -440.014364) (xy 62.89511 -440.04141)
			(xy 62.949109 -440.075455) (xy 62.998442 -440.115967) (xy 63.042339 -440.162313) (xy 63.080116 -440.213771)
			(xy 63.111182 -440.269538) (xy 63.135052 -440.328742) (xy 63.151355 -440.390461) (xy 63.156084 -440.42203)
			(xy 63.161926 -440.465972) (xy 66.138298 -440.465972) (xy 66.14414 -440.42203) (xy 66.148869 -440.390461)
			(xy 66.165172 -440.328742) (xy 66.189042 -440.269538) (xy 66.220108 -440.213771) (xy 66.257885 -440.162313)
			(xy 66.301782 -440.115967) (xy 66.351115 -440.075455) (xy 66.405114 -440.04141) (xy 66.462937 -440.014364)
			(xy 66.523681 -439.994738) (xy 66.586397 -439.982838) (xy 66.650108 -439.978851) (xy 66.713819 -439.982838)
			(xy 66.776535 -439.994738) (xy 66.837279 -440.014364) (xy 66.895102 -440.04141) (xy 66.949101 -440.075455)
			(xy 66.998434 -440.115967) (xy 67.042331 -440.162313) (xy 67.080108 -440.213771) (xy 67.111174 -440.269538)
			(xy 67.135044 -440.328742) (xy 67.151347 -440.390461) (xy 67.156076 -440.42203) (xy 67.161918 -440.465972)
			(xy 70.13829 -440.465972) (xy 70.144132 -440.42203) (xy 70.148861 -440.390461) (xy 70.165164 -440.328742)
			(xy 70.189034 -440.269538) (xy 70.2201 -440.213771) (xy 70.257877 -440.162313) (xy 70.301774 -440.115967)
			(xy 70.351107 -440.075455) (xy 70.405106 -440.04141) (xy 70.462929 -440.014364) (xy 70.523673 -439.994738)
			(xy 70.586389 -439.982838) (xy 70.6501 -439.978851) (xy 70.713811 -439.982838) (xy 70.776527 -439.994738)
			(xy 70.837271 -440.014364) (xy 70.895094 -440.04141) (xy 70.949093 -440.075455) (xy 70.998426 -440.115967)
			(xy 71.042323 -440.162313) (xy 71.0801 -440.213771) (xy 71.111166 -440.269538) (xy 71.135036 -440.328742)
			(xy 71.151339 -440.390461) (xy 71.156068 -440.42203) (xy 71.16191 -440.465972) (xy 75.13828 -440.465972)
			(xy 75.144122 -440.42203) (xy 75.148851 -440.390461) (xy 75.165154 -440.328742) (xy 75.189024 -440.269538)
			(xy 75.22009 -440.213771) (xy 75.257867 -440.162313) (xy 75.301764 -440.115967) (xy 75.351097 -440.075455)
			(xy 75.405096 -440.04141) (xy 75.462919 -440.014364) (xy 75.523663 -439.994738) (xy 75.586379 -439.982838)
			(xy 75.65009 -439.978851) (xy 75.713801 -439.982838) (xy 75.776517 -439.994738) (xy 75.837261 -440.014364)
			(xy 75.895084 -440.04141) (xy 75.949083 -440.075455) (xy 75.998416 -440.115967) (xy 76.042313 -440.162313)
			(xy 76.08009 -440.213771) (xy 76.111156 -440.269538) (xy 76.135026 -440.328742) (xy 76.151329 -440.390461)
			(xy 76.156058 -440.42203) (xy 76.1619 -440.465972) (xy 79.138272 -440.465972) (xy 79.144114 -440.42203)
			(xy 79.148843 -440.390461) (xy 79.165146 -440.328742) (xy 79.189016 -440.269538) (xy 79.220082 -440.213771)
			(xy 79.257859 -440.162313) (xy 79.301756 -440.115967) (xy 79.351089 -440.075455) (xy 79.405088 -440.04141)
			(xy 79.462911 -440.014364) (xy 79.523655 -439.994738) (xy 79.586371 -439.982838) (xy 79.650082 -439.978851)
			(xy 79.713793 -439.982838) (xy 79.776509 -439.994738) (xy 79.837253 -440.014364) (xy 79.895076 -440.04141)
			(xy 79.949075 -440.075455) (xy 79.998408 -440.115967) (xy 80.042305 -440.162313) (xy 80.080082 -440.213771)
			(xy 80.111148 -440.269538) (xy 80.135018 -440.328742) (xy 80.151321 -440.390461) (xy 80.15605 -440.42203)
			(xy 80.161892 -440.465972) (xy 83.138264 -440.465972) (xy 83.144106 -440.42203) (xy 83.148835 -440.390461)
			(xy 83.165138 -440.328742) (xy 83.189008 -440.269538) (xy 83.220074 -440.213771) (xy 83.257851 -440.162313)
			(xy 83.301748 -440.115967) (xy 83.351081 -440.075455) (xy 83.40508 -440.04141) (xy 83.462903 -440.014364)
			(xy 83.523647 -439.994738) (xy 83.586363 -439.982838) (xy 83.650074 -439.978851) (xy 83.713785 -439.982838)
			(xy 83.776501 -439.994738) (xy 83.837245 -440.014364) (xy 83.895068 -440.04141) (xy 83.949067 -440.075455)
			(xy 83.9984 -440.115967) (xy 84.042297 -440.162313) (xy 84.080074 -440.213771) (xy 84.11114 -440.269538)
			(xy 84.13501 -440.328742) (xy 84.151313 -440.390461) (xy 84.156042 -440.42203) (xy 84.161884 -440.465972)
			(xy 87.138256 -440.465972) (xy 87.144098 -440.42203) (xy 87.148827 -440.390461) (xy 87.16513 -440.328742)
			(xy 87.189 -440.269538) (xy 87.220066 -440.213771) (xy 87.257843 -440.162313) (xy 87.30174 -440.115967)
			(xy 87.351073 -440.075455) (xy 87.405072 -440.04141) (xy 87.462895 -440.014364) (xy 87.523639 -439.994738)
			(xy 87.586355 -439.982838) (xy 87.650066 -439.978851) (xy 87.713777 -439.982838) (xy 87.776493 -439.994738)
			(xy 87.837237 -440.014364) (xy 87.89506 -440.04141) (xy 87.949059 -440.075455) (xy 87.998392 -440.115967)
			(xy 88.042289 -440.162313) (xy 88.080066 -440.213771) (xy 88.111132 -440.269538) (xy 88.135002 -440.328742)
			(xy 88.151305 -440.390461) (xy 88.156034 -440.42203) (xy 88.161876 -440.465972) (xy 98.016822 -440.465972)
			(xy 98.031879 -440.465426) (xy 98.060684 -440.456638) (xy 98.085673 -440.439833) (xy 98.104677 -440.416471)
			(xy 98.116042 -440.388583) (xy 98.11878 -440.358593) (xy 98.112655 -440.329107) (xy 98.098197 -440.30269)
			(xy 98.076665 -440.281636) (xy 98.063558 -440.274202) (xy 97.97279 -440.226317) (xy 97.794627 -440.124416)
			(xy 97.620566 -440.015658) (xy 97.450869 -439.900206) (xy 97.285795 -439.778237) (xy 97.125594 -439.649934)
			(xy 96.970509 -439.515493) (xy 96.820774 -439.375117) (xy 96.676617 -439.22902) (xy 96.538256 -439.077421)
			(xy 96.4059 -438.920552) (xy 96.279751 -438.75865) (xy 96.16 -438.59196) (xy 96.046828 -438.420735)
			(xy 95.940407 -438.245235) (xy 95.840897 -438.065725) (xy 95.74845 -437.882478) (xy 95.663207 -437.695771)
			(xy 95.585295 -437.505888) (xy 95.514834 -437.313116) (xy 95.451929 -437.117747) (xy 95.396677 -436.920078)
			(xy 95.349162 -436.720408) (xy 95.309454 -436.519039) (xy 95.277615 -436.316278) (xy 95.253692 -436.112431)
			(xy 95.237722 -435.907807) (xy 95.229729 -435.702717) (xy 95.229172 -435.600094) (xy 95.229668 -435.497873)
			(xy 95.237595 -435.293583) (xy 95.253438 -435.089755) (xy 95.277172 -434.886695) (xy 95.308762 -434.684707)
			(xy 95.348161 -434.484096) (xy 95.395309 -434.285164) (xy 95.450135 -434.08821) (xy 95.512557 -433.893529)
			(xy 95.58248 -433.701416) (xy 95.659801 -433.512158) (xy 95.744401 -433.326041) (xy 95.836155 -433.143344)
			(xy 95.934924 -432.964342) (xy 96.04056 -432.789305) (xy 96.152903 -432.618495) (xy 96.271785 -432.45217)
			(xy 96.397027 -432.29058) (xy 96.52844 -432.133968) (xy 96.665827 -431.982569) (xy 96.808982 -431.836611)
			(xy 96.957688 -431.696314) (xy 97.111723 -431.561888) (xy 97.270854 -431.433536) (xy 97.434843 -431.311451)
			(xy 97.603441 -431.195817) (xy 97.776397 -431.086807) (xy 97.95345 -430.984586) (xy 98.134334 -430.889306)
			(xy 98.318775 -430.801113) (xy 98.506498 -430.720137) (xy 98.69722 -430.646501) (xy 98.890653 -430.580316)
			(xy 99.086507 -430.521681) (xy 99.284488 -430.470685) (xy 99.484297 -430.427403) (xy 99.685634 -430.391902)
			(xy 99.888196 -430.364235) (xy 100.091678 -430.344442) (xy 100.295775 -430.332555) (xy 100.50018 -430.328591)
			(xy 100.704585 -430.332555) (xy 100.908682 -430.344442) (xy 101.112164 -430.364235) (xy 101.314726 -430.391902)
			(xy 101.516063 -430.427403) (xy 101.715872 -430.470685) (xy 101.913853 -430.521681) (xy 102.109707 -430.580316)
			(xy 102.30314 -430.646501) (xy 102.493862 -430.720137) (xy 102.681585 -430.801113) (xy 102.866026 -430.889306)
			(xy 103.04691 -430.984586) (xy 103.223963 -431.086807) (xy 103.396919 -431.195817) (xy 103.565517 -431.311451)
			(xy 103.729506 -431.433536) (xy 103.888637 -431.561888) (xy 104.042672 -431.696314) (xy 104.191378 -431.836611)
			(xy 104.334533 -431.982569) (xy 104.47192 -432.133968) (xy 104.603333 -432.29058) (xy 104.728575 -432.45217)
			(xy 104.847457 -432.618495) (xy 104.9598 -432.789305) (xy 105.065436 -432.964342) (xy 105.164205 -433.143344)
			(xy 105.255959 -433.326041) (xy 105.340559 -433.512158) (xy 105.41788 -433.701416) (xy 105.487803 -433.893529)
			(xy 105.550225 -434.08821) (xy 105.605051 -434.285164) (xy 105.652199 -434.484096) (xy 105.691598 -434.684707)
			(xy 105.723188 -434.886695) (xy 105.746922 -435.089755) (xy 105.762765 -435.293583) (xy 105.770692 -435.497873)
			(xy 105.771188 -435.600094) (xy 105.770692 -435.702718) (xy 105.762704 -435.907811) (xy 105.746738 -436.112437)
			(xy 105.722819 -436.316287) (xy 105.690982 -436.519052) (xy 105.651277 -436.720423) (xy 105.603763 -436.920096)
			(xy 105.548512 -437.117768) (xy 105.485608 -437.313139) (xy 105.415146 -437.505914) (xy 105.337234 -437.695799)
			(xy 105.251989 -437.882508) (xy 105.15954 -438.065757) (xy 105.060028 -438.245268) (xy 104.953604 -438.420769)
			(xy 104.840428 -438.591995) (xy 104.720673 -438.758685) (xy 104.59452 -438.920587) (xy 104.462159 -439.077455)
			(xy 104.323793 -439.229052) (xy 104.17963 -439.375148) (xy 104.02989 -439.515521) (xy 103.874798 -439.649959)
			(xy 103.714591 -439.778258) (xy 103.549511 -439.900222) (xy 103.379808 -440.015669) (xy 103.20574 -440.124421)
			(xy 103.02757 -440.226316) (xy 102.936802 -440.274202) (xy 102.923684 -440.281619) (xy 102.902154 -440.302681)
			(xy 102.887699 -440.329106) (xy 102.881575 -440.358596) (xy 102.884315 -440.388591) (xy 102.89568 -440.416484)
			(xy 102.914683 -440.439853) (xy 102.939673 -440.456666) (xy 102.968478 -440.465465) (xy 102.983538 -440.465972)
			(xy 108.564172 -440.465972) (xy 108.564172 -433.182268) (xy 108.524442 -433.105807) (xy 108.450941 -432.949936)
			(xy 108.384375 -432.790979) (xy 108.324873 -432.629246) (xy 108.27255 -432.46505) (xy 108.227507 -432.298709)
			(xy 108.189832 -432.130546) (xy 108.159598 -431.960887) (xy 108.136864 -431.790062) (xy 108.121673 -431.618401)
			(xy 108.114056 -431.446238) (xy 108.113576 -431.360072) (xy 108.11405 -431.273905) (xy 108.121648 -431.10174)
			(xy 108.136823 -430.930076) (xy 108.159547 -430.759247) (xy 108.189775 -430.589586) (xy 108.227448 -430.421421)
			(xy 108.272493 -430.255079) (xy 108.324823 -430.090883) (xy 108.384337 -429.929152) (xy 108.450917 -429.770199)
			(xy 108.524436 -429.614335) (xy 108.564172 -429.537876) (xy 108.564172 -420.872412) (xy 115.623848 -420.872412)
			(xy 115.623848 -427.289976) (xy 125.238002 -427.289976) (xy 125.238092 -427.275402) (xy 125.239747 -427.246301)
			(xy 125.241304 -427.23181) (xy 125.241304 -426.147992) (xy 125.239761 -426.1335) (xy 125.238108 -426.1044)
			(xy 125.238002 -426.089826) (xy 125.238097 -426.075252) (xy 125.239748 -426.046151) (xy 125.241304 -426.03166)
			(xy 125.241304 -425.419012) (xy 125.241727 -425.406903) (xy 125.249223 -425.383876) (xy 125.263483 -425.364302)
			(xy 125.283104 -425.350107) (xy 125.306156 -425.342687) (xy 125.318266 -425.342304) (xy 126.258066 -425.342304)
			(xy 126.27015 -425.342836) (xy 126.293144 -425.350279) (xy 126.312721 -425.36445) (xy 126.326974 -425.383968)
			(xy 126.334513 -425.40693) (xy 126.335028 -425.419012) (xy 126.335028 -427.960536) (xy 126.334615 -427.972644)
			(xy 126.327109 -427.995668) (xy 126.312845 -428.015238) (xy 126.293225 -428.029432) (xy 126.270175 -428.036857)
			(xy 126.258066 -428.037244) (xy 125.318266 -428.037244) (xy 125.306173 -428.036821) (xy 125.283169 -428.029353)
			(xy 125.263588 -428.015156) (xy 125.249339 -427.995612) (xy 125.241811 -427.972628) (xy 125.241304 -427.960536)
			(xy 125.241304 -427.348142) (xy 125.239757 -427.33365) (xy 125.238107 -427.30455) (xy 125.238002 -427.289976)
			(xy 115.623848 -427.289976) (xy 115.623848 -428.28972) (xy 127.237998 -428.28972) (xy 127.238092 -428.275146)
			(xy 127.239744 -428.246045) (xy 127.2413 -428.231554) (xy 127.2413 -427.14799) (xy 127.239757 -427.133498)
			(xy 127.238104 -427.104398) (xy 127.237998 -427.089824) (xy 127.238092 -427.07525) (xy 127.239744 -427.046149)
			(xy 127.2413 -427.031658) (xy 127.2413 -426.41901) (xy 127.24182 -426.4069) (xy 127.2493 -426.383863)
			(xy 127.263531 -426.364265) (xy 127.28312 -426.350022) (xy 127.306152 -426.342527) (xy 127.318262 -426.342048)
			(xy 128.258062 -426.342048) (xy 128.270184 -426.342492) (xy 128.293243 -426.349975) (xy 128.31286 -426.36422)
			(xy 128.327112 -426.383832) (xy 128.334603 -426.406888) (xy 128.335024 -426.41901) (xy 128.335024 -427.289976)
			(xy 129.237994 -427.289976) (xy 129.238084 -427.275402) (xy 129.239739 -427.246301) (xy 129.241296 -427.23181)
			(xy 129.241296 -426.147992) (xy 129.239753 -426.1335) (xy 129.2381 -426.1044) (xy 129.237994 -426.089826)
			(xy 129.238089 -426.075252) (xy 129.23974 -426.046151) (xy 129.241296 -426.03166) (xy 129.241296 -425.419012)
			(xy 129.241727 -425.406904) (xy 129.249222 -425.383878) (xy 129.26348 -425.364305) (xy 129.283099 -425.35011)
			(xy 129.306149 -425.342688) (xy 129.318258 -425.342304) (xy 130.258058 -425.342304) (xy 130.270142 -425.342842)
			(xy 130.293135 -425.350283) (xy 130.312713 -425.364453) (xy 130.326966 -425.383969) (xy 130.334505 -425.40693)
			(xy 130.33502 -425.419012) (xy 130.33502 -427.960536) (xy 130.334615 -427.972645) (xy 130.327108 -427.99567)
			(xy 130.312843 -428.01524) (xy 130.29322 -428.029435) (xy 130.270168 -428.036858) (xy 130.258058 -428.037244)
			(xy 129.318258 -428.037244) (xy 129.306165 -428.036828) (xy 129.28316 -428.029358) (xy 129.263579 -428.015159)
			(xy 129.249331 -427.995614) (xy 129.241803 -427.972628) (xy 129.241296 -427.960536) (xy 129.241296 -427.348142)
			(xy 129.239749 -427.33365) (xy 129.238099 -427.30455) (xy 129.237994 -427.289976) (xy 128.335024 -427.289976)
			(xy 128.335024 -428.28972) (xy 131.23799 -428.28972) (xy 131.238084 -428.275146) (xy 131.239736 -428.246045)
			(xy 131.241292 -428.231554) (xy 131.241292 -427.14799) (xy 131.239749 -427.133498) (xy 131.238096 -427.104398)
			(xy 131.23799 -427.089824) (xy 131.238085 -427.07525) (xy 131.239736 -427.046149) (xy 131.241292 -427.031658)
			(xy 131.241292 -426.41901) (xy 131.24182 -426.406901) (xy 131.249299 -426.383865) (xy 131.263528 -426.364268)
			(xy 131.283115 -426.350024) (xy 131.306145 -426.342528) (xy 131.318254 -426.342048) (xy 132.258054 -426.342048)
			(xy 132.270175 -426.342499) (xy 132.293234 -426.34998) (xy 132.312851 -426.364223) (xy 132.327104 -426.383833)
			(xy 132.334595 -426.406889) (xy 132.335016 -426.41901) (xy 132.335016 -427.289976) (xy 133.237986 -427.289976)
			(xy 133.238076 -427.275402) (xy 133.239731 -427.246301) (xy 133.241288 -427.23181) (xy 133.241288 -426.147992)
			(xy 133.239745 -426.1335) (xy 133.238092 -426.1044) (xy 133.237986 -426.089826) (xy 133.238081 -426.075252)
			(xy 133.239732 -426.046151) (xy 133.241288 -426.03166) (xy 133.241288 -425.419012) (xy 133.241727 -425.406905)
			(xy 133.249221 -425.38388) (xy 133.263477 -425.364308) (xy 133.283094 -425.350113) (xy 133.306142 -425.342689)
			(xy 133.31825 -425.342304) (xy 134.25805 -425.342304) (xy 134.270133 -425.342849) (xy 134.293126 -425.350288)
			(xy 134.312704 -425.364455) (xy 134.326958 -425.383971) (xy 134.334497 -425.406931) (xy 134.335012 -425.419012)
			(xy 134.335012 -427.960536) (xy 134.334614 -427.972646) (xy 134.327107 -427.995672) (xy 134.31284 -428.015243)
			(xy 134.293215 -428.029437) (xy 134.270161 -428.036859) (xy 134.25805 -428.037244) (xy 133.31825 -428.037244)
			(xy 133.306161 -428.03675) (xy 133.28316 -428.029305) (xy 133.263578 -428.015126) (xy 133.249326 -427.995597)
			(xy 133.241795 -427.972623) (xy 133.241288 -427.960536) (xy 133.241288 -427.348142) (xy 133.239741 -427.33365)
			(xy 133.238091 -427.30455) (xy 133.237986 -427.289976) (xy 132.335016 -427.289976) (xy 132.335016 -428.28972)
			(xy 135.237982 -428.28972) (xy 135.238076 -428.275146) (xy 135.239728 -428.246045) (xy 135.241284 -428.231554)
			(xy 135.241284 -427.14799) (xy 135.239741 -427.133498) (xy 135.238088 -427.104398) (xy 135.237982 -427.089824)
			(xy 135.238077 -427.07525) (xy 135.239728 -427.046149) (xy 135.241284 -427.031658) (xy 135.241284 -426.41901)
			(xy 135.241669 -426.406883) (xy 135.249164 -426.383817) (xy 135.263423 -426.364198) (xy 135.283049 -426.349948)
			(xy 135.306119 -426.342464) (xy 135.318246 -426.342048) (xy 136.258046 -426.342048) (xy 136.270164 -426.342473)
			(xy 136.29321 -426.349974) (xy 136.312812 -426.364228) (xy 136.327052 -426.38384) (xy 136.334536 -426.406892)
			(xy 136.335008 -426.41901) (xy 136.335008 -427.289976) (xy 137.237978 -427.289976) (xy 137.238068 -427.275402)
			(xy 137.239723 -427.246301) (xy 137.24128 -427.23181) (xy 137.24128 -426.147992) (xy 137.239737 -426.1335)
			(xy 137.238084 -426.1044) (xy 137.237978 -426.089826) (xy 137.238073 -426.075252) (xy 137.239724 -426.046151)
			(xy 137.24128 -426.03166) (xy 137.24128 -425.419012) (xy 137.241727 -425.406906) (xy 137.24922 -425.383882)
			(xy 137.263475 -425.364311) (xy 137.283089 -425.350115) (xy 137.306135 -425.342691) (xy 137.318242 -425.342304)
			(xy 138.258042 -425.342304) (xy 138.27013 -425.342771) (xy 138.293126 -425.350235) (xy 138.312702 -425.364423)
			(xy 138.326953 -425.383953) (xy 138.33449 -425.406925) (xy 138.335004 -425.419012) (xy 138.335004 -427.960536)
			(xy 138.334614 -427.972646) (xy 138.327106 -427.995674) (xy 138.312837 -428.015246) (xy 138.29321 -428.02944)
			(xy 138.270154 -428.03686) (xy 138.258042 -428.037244) (xy 137.318242 -428.037244) (xy 137.306153 -428.036757)
			(xy 137.283151 -428.029309) (xy 137.263569 -428.015129) (xy 137.249318 -427.995598) (xy 137.241787 -427.972623)
			(xy 137.24128 -427.960536) (xy 137.24128 -427.348142) (xy 137.239733 -427.33365) (xy 137.238083 -427.30455)
			(xy 137.237978 -427.289976) (xy 136.335008 -427.289976) (xy 136.335008 -428.28972) (xy 139.237974 -428.28972)
			(xy 139.238068 -428.275146) (xy 139.23972 -428.246045) (xy 139.241276 -428.231554) (xy 139.241276 -427.14799)
			(xy 139.239733 -427.133498) (xy 139.23808 -427.104398) (xy 139.237974 -427.089824) (xy 139.238069 -427.07525)
			(xy 139.23972 -427.046149) (xy 139.241276 -427.031658) (xy 139.241276 -426.41901) (xy 139.241669 -426.406884)
			(xy 139.249163 -426.383819) (xy 139.26342 -426.364201) (xy 139.283044 -426.34995) (xy 139.306112 -426.342465)
			(xy 139.318238 -426.342048) (xy 140.258038 -426.342048) (xy 140.270156 -426.342479) (xy 140.293202 -426.349978)
			(xy 140.312804 -426.36423) (xy 140.327044 -426.383841) (xy 140.334528 -426.406892) (xy 140.335 -426.41901)
			(xy 140.335 -427.289976) (xy 142.237968 -427.289976) (xy 142.238082 -427.274891) (xy 142.23986 -427.244772)
			(xy 142.241524 -427.229778) (xy 142.241524 -426.150024) (xy 142.239855 -426.135031) (xy 142.238077 -426.104912)
			(xy 142.237968 -426.089826) (xy 142.238078 -426.07474) (xy 142.239859 -426.044622) (xy 142.241524 -426.029628)
			(xy 142.241524 -425.419012) (xy 142.241924 -425.406927) (xy 142.249392 -425.383939) (xy 142.2636 -425.364386)
			(xy 142.283157 -425.350183) (xy 142.306147 -425.34272) (xy 142.318232 -425.342304) (xy 143.258032 -425.342304)
			(xy 143.270109 -425.342737) (xy 143.29308 -425.35021) (xy 143.312617 -425.364414) (xy 143.32681 -425.38396)
			(xy 143.33427 -425.406934) (xy 143.33474 -425.419012) (xy 143.33474 -427.960536) (xy 143.334267 -427.972609)
			(xy 143.326799 -427.995572) (xy 143.312603 -428.015106) (xy 143.293069 -428.0293) (xy 143.270105 -428.036768)
			(xy 143.258032 -428.037244) (xy 142.318232 -428.037244) (xy 142.306163 -428.036709) (xy 142.283203 -428.02926)
			(xy 142.263668 -428.01508) (xy 142.249471 -427.995558) (xy 142.242001 -427.972605) (xy 142.241524 -427.960536)
			(xy 142.241524 -427.350174) (xy 142.23986 -427.33518) (xy 142.238078 -427.305062) (xy 142.237968 -427.289976)
			(xy 140.335 -427.289976) (xy 140.335 -428.28972) (xy 144.237964 -428.28972) (xy 144.238073 -428.274634)
			(xy 144.239855 -428.244516) (xy 144.24152 -428.229522) (xy 144.24152 -427.150022) (xy 144.239851 -427.135029)
			(xy 144.238073 -427.10491) (xy 144.237964 -427.089824) (xy 144.238074 -427.074738) (xy 144.239855 -427.04462)
			(xy 144.24152 -427.029626) (xy 144.24152 -426.41901) (xy 144.242016 -426.406923) (xy 144.249467 -426.383926)
			(xy 144.263647 -426.364348) (xy 144.283173 -426.350096) (xy 144.306143 -426.34256) (xy 144.318228 -426.342048)
			(xy 145.258028 -426.342048) (xy 145.270133 -426.342492) (xy 145.293152 -426.349993) (xy 145.312721 -426.364249)
			(xy 145.326916 -426.383861) (xy 145.334345 -426.406904) (xy 145.334736 -426.41901) (xy 145.334736 -427.289976)
			(xy 146.23796 -427.289976) (xy 146.238074 -427.274891) (xy 146.239852 -427.244772) (xy 146.241516 -427.229778)
			(xy 146.241516 -426.150024) (xy 146.239847 -426.135031) (xy 146.238069 -426.104912) (xy 146.23796 -426.089826)
			(xy 146.23807 -426.07474) (xy 146.239851 -426.044622) (xy 146.241516 -426.029628) (xy 146.241516 -425.419012)
			(xy 146.241923 -425.406928) (xy 146.249391 -425.383941) (xy 146.263597 -425.364389) (xy 146.283152 -425.350185)
			(xy 146.306139 -425.342722) (xy 146.318224 -425.342304) (xy 147.258024 -425.342304) (xy 147.270101 -425.342744)
			(xy 147.293071 -425.350215) (xy 147.312609 -425.364417) (xy 147.326802 -425.383961) (xy 147.334261 -425.406935)
			(xy 147.334732 -425.419012) (xy 147.334732 -427.960536) (xy 147.334267 -427.97261) (xy 147.326798 -427.995574)
			(xy 147.3126 -428.015109) (xy 147.293064 -428.029303) (xy 147.270098 -428.036769) (xy 147.258024 -428.037244)
			(xy 146.318224 -428.037244) (xy 146.306154 -428.036716) (xy 146.283194 -428.029264) (xy 146.26366 -428.015083)
			(xy 146.249463 -427.99556) (xy 146.241993 -427.972605) (xy 146.241516 -427.960536) (xy 146.241516 -427.350174)
			(xy 146.239852 -427.33518) (xy 146.23807 -427.305062) (xy 146.23796 -427.289976) (xy 145.334736 -427.289976)
			(xy 145.334736 -428.28972) (xy 148.237956 -428.28972) (xy 148.238066 -428.274634) (xy 148.239847 -428.244516)
			(xy 148.241512 -428.229522) (xy 148.241512 -427.150022) (xy 148.239843 -427.135029) (xy 148.238065 -427.10491)
			(xy 148.237956 -427.089824) (xy 148.238066 -427.074738) (xy 148.239847 -427.04462) (xy 148.241512 -427.029626)
			(xy 148.241512 -426.41901) (xy 148.242015 -426.406924) (xy 148.249466 -426.383928) (xy 148.263644 -426.364351)
			(xy 148.283168 -426.350099) (xy 148.306136 -426.342562) (xy 148.31822 -426.342048) (xy 149.25802 -426.342048)
			(xy 149.270125 -426.342499) (xy 149.293144 -426.349997) (xy 149.312712 -426.364252) (xy 149.326908 -426.383863)
			(xy 149.334337 -426.406904) (xy 149.334728 -426.41901) (xy 149.334728 -427.289976) (xy 150.237952 -427.289976)
			(xy 150.238066 -427.274891) (xy 150.239844 -427.244772) (xy 150.241508 -427.229778) (xy 150.241508 -426.150024)
			(xy 150.239839 -426.135031) (xy 150.238061 -426.104912) (xy 150.237952 -426.089826) (xy 150.238062 -426.07474)
			(xy 150.239843 -426.044622) (xy 150.241508 -426.029628) (xy 150.241508 -425.419012) (xy 150.241923 -425.406928)
			(xy 150.249389 -425.383943) (xy 150.263594 -425.364392) (xy 150.283147 -425.350188) (xy 150.306132 -425.342723)
			(xy 150.318216 -425.342304) (xy 151.258016 -425.342304) (xy 151.270093 -425.342751) (xy 151.293062 -425.350219)
			(xy 151.3126 -425.36442) (xy 151.326794 -425.383963) (xy 151.334253 -425.406935) (xy 151.334724 -425.419012)
			(xy 151.334724 -427.960536) (xy 151.334267 -427.972611) (xy 151.326796 -427.995577) (xy 151.312597 -428.015112)
			(xy 151.293059 -428.029306) (xy 151.270091 -428.03677) (xy 151.258016 -428.037244) (xy 150.318216 -428.037244)
			(xy 150.306146 -428.036723) (xy 150.283185 -428.029269) (xy 150.263651 -428.015086) (xy 150.249455 -427.995561)
			(xy 150.241985 -427.972606) (xy 150.241508 -427.960536) (xy 150.241508 -427.350174) (xy 150.239844 -427.33518)
			(xy 150.238062 -427.305062) (xy 150.237952 -427.289976) (xy 149.334728 -427.289976) (xy 149.334728 -428.28972)
			(xy 152.237948 -428.28972) (xy 152.238058 -428.274634) (xy 152.239839 -428.244516) (xy 152.241504 -428.229522)
			(xy 152.241504 -427.150022) (xy 152.239835 -427.135029) (xy 152.238057 -427.10491) (xy 152.237948 -427.089824)
			(xy 152.238058 -427.074738) (xy 152.239839 -427.04462) (xy 152.241504 -427.029626) (xy 152.241504 -426.41901)
			(xy 152.242015 -426.406925) (xy 152.249465 -426.38393) (xy 152.263641 -426.364353) (xy 152.283163 -426.350101)
			(xy 152.306128 -426.342563) (xy 152.318212 -426.342048) (xy 153.258012 -426.342048) (xy 153.270116 -426.342505)
			(xy 153.293135 -426.350002) (xy 153.312704 -426.364255) (xy 153.3269 -426.383864) (xy 153.334329 -426.406905)
			(xy 153.33472 -426.41901) (xy 153.33472 -427.289976) (xy 154.237944 -427.289976) (xy 154.238059 -427.274891)
			(xy 154.239836 -427.244772) (xy 154.2415 -427.229778) (xy 154.2415 -426.150024) (xy 154.239831 -426.135031)
			(xy 154.238053 -426.104912) (xy 154.237944 -426.089826) (xy 154.238054 -426.07474) (xy 154.239835 -426.044622)
			(xy 154.2415 -426.029628) (xy 154.2415 -425.419012) (xy 154.241923 -425.406929) (xy 154.249388 -425.383946)
			(xy 154.263592 -425.364394) (xy 154.283142 -425.35019) (xy 154.306125 -425.342724) (xy 154.318208 -425.342304)
			(xy 155.258008 -425.342304) (xy 155.270092 -425.342706) (xy 155.293077 -425.350177) (xy 155.312629 -425.364386)
			(xy 155.326832 -425.383941) (xy 155.334297 -425.406928) (xy 155.334716 -425.419012) (xy 155.334716 -427.960536)
			(xy 155.334267 -427.972612) (xy 155.326795 -427.995579) (xy 155.312595 -428.015115) (xy 155.293054 -428.029308)
			(xy 155.270084 -428.036771) (xy 155.258008 -428.037244) (xy 154.318208 -428.037244) (xy 154.306137 -428.03673)
			(xy 154.283177 -428.029274) (xy 154.263643 -428.015089) (xy 154.249447 -427.995563) (xy 154.241977 -427.972606)
			(xy 154.2415 -427.960536) (xy 154.2415 -427.350174) (xy 154.239836 -427.33518) (xy 154.238054 -427.305062)
			(xy 154.237944 -427.289976) (xy 153.33472 -427.289976) (xy 153.33472 -428.28972) (xy 156.23794 -428.28972)
			(xy 156.238052 -428.274634) (xy 156.239833 -428.244516) (xy 156.241496 -428.229522) (xy 156.241496 -427.150022)
			(xy 156.239827 -427.135029) (xy 156.238049 -427.10491) (xy 156.23794 -427.089824) (xy 156.23805 -427.074738)
			(xy 156.239831 -427.04462) (xy 156.241496 -427.029626) (xy 156.241496 -426.41901) (xy 156.242015 -426.406925)
			(xy 156.249464 -426.383932) (xy 156.263639 -426.364356) (xy 156.283158 -426.350104) (xy 156.306121 -426.342564)
			(xy 156.318204 -426.342048) (xy 157.258004 -426.342048) (xy 157.270108 -426.342512) (xy 157.293127 -426.350006)
			(xy 157.312695 -426.364257) (xy 157.326891 -426.383866) (xy 157.334321 -426.406905) (xy 157.334712 -426.41901)
			(xy 157.334712 -428.960534) (xy 157.334321 -428.97263) (xy 157.326849 -428.99564) (xy 157.312644 -429.015223)
			(xy 157.293092 -429.029471) (xy 157.270099 -429.036994) (xy 157.258004 -429.037496) (xy 156.318204 -429.037496)
			(xy 156.306095 -429.03708) (xy 156.283067 -429.029582) (xy 156.263493 -429.01532) (xy 156.249299 -428.995698)
			(xy 156.241879 -428.972644) (xy 156.241496 -428.960534) (xy 156.241496 -428.349918) (xy 156.239827 -428.334925)
			(xy 156.238049 -428.304806) (xy 156.23794 -428.28972) (xy 153.33472 -428.28972) (xy 153.33472 -428.960534)
			(xy 153.334321 -428.972629) (xy 153.32685 -428.995638) (xy 153.312647 -429.015221) (xy 153.293097 -429.029469)
			(xy 153.270106 -429.036993) (xy 153.258012 -429.037496) (xy 152.318212 -429.037496) (xy 152.306103 -429.037073)
			(xy 152.283076 -429.029577) (xy 152.263502 -429.015317) (xy 152.249307 -428.995696) (xy 152.241887 -428.972644)
			(xy 152.241504 -428.960534) (xy 152.241504 -428.349918) (xy 152.239835 -428.334925) (xy 152.238057 -428.304806)
			(xy 152.237948 -428.28972) (xy 149.334728 -428.28972) (xy 149.334728 -428.960534) (xy 149.334321 -428.972629)
			(xy 149.326851 -428.995636) (xy 149.31265 -429.015218) (xy 149.293102 -429.029466) (xy 149.270113 -429.036992)
			(xy 149.25802 -429.037496) (xy 148.31822 -429.037496) (xy 148.306112 -429.037066) (xy 148.283085 -429.029572)
			(xy 148.263511 -429.015314) (xy 148.249316 -428.995695) (xy 148.241895 -428.972643) (xy 148.241512 -428.960534)
			(xy 148.241512 -428.349918) (xy 148.239843 -428.334925) (xy 148.238065 -428.304806) (xy 148.237956 -428.28972)
			(xy 145.334736 -428.28972) (xy 145.334736 -428.960534) (xy 145.334321 -428.972628) (xy 145.326852 -428.995634)
			(xy 145.312653 -429.015215) (xy 145.293107 -429.029464) (xy 145.27012 -429.03699) (xy 145.258028 -429.037496)
			(xy 144.318228 -429.037496) (xy 144.30612 -429.03706) (xy 144.283093 -429.029567) (xy 144.263519 -429.015311)
			(xy 144.249324 -428.995693) (xy 144.241903 -428.972643) (xy 144.24152 -428.960534) (xy 144.24152 -428.349918)
			(xy 144.239851 -428.334925) (xy 144.238073 -428.304806) (xy 144.237964 -428.28972) (xy 140.335 -428.28972)
			(xy 140.335 -428.960534) (xy 140.334518 -428.972647) (xy 140.327026 -428.995684) (xy 140.312785 -429.015282)
			(xy 140.293188 -429.029524) (xy 140.270151 -429.037017) (xy 140.258038 -429.037496) (xy 139.318238 -429.037496)
			(xy 139.306121 -429.037008) (xy 139.283069 -429.029531) (xy 139.263456 -429.015295) (xy 139.249202 -428.995696)
			(xy 139.241703 -428.972651) (xy 139.241276 -428.960534) (xy 139.241276 -428.347886) (xy 139.239733 -428.333394)
			(xy 139.23808 -428.304294) (xy 139.237974 -428.28972) (xy 136.335008 -428.28972) (xy 136.335008 -428.960534)
			(xy 136.334518 -428.972646) (xy 136.327027 -428.995682) (xy 136.312788 -429.01528) (xy 136.293193 -429.029522)
			(xy 136.270158 -429.037016) (xy 136.258046 -429.037496) (xy 135.318246 -429.037496) (xy 135.306129 -429.037002)
			(xy 135.283077 -429.029526) (xy 135.263464 -429.015292) (xy 135.249211 -428.995694) (xy 135.241711 -428.972651)
			(xy 135.241284 -428.960534) (xy 135.241284 -428.347886) (xy 135.239741 -428.333394) (xy 135.238088 -428.304294)
			(xy 135.237982 -428.28972) (xy 132.335016 -428.28972) (xy 132.335016 -428.960534) (xy 132.334668 -428.972663)
			(xy 132.327161 -428.995731) (xy 132.312892 -429.015349) (xy 132.293259 -429.029598) (xy 132.270184 -429.037081)
			(xy 132.258054 -429.037496) (xy 131.318254 -429.037496) (xy 131.30614 -429.037028) (xy 131.283101 -429.029532)
			(xy 131.263503 -429.015288) (xy 131.249262 -428.995688) (xy 131.24177 -428.972648) (xy 131.241292 -428.960534)
			(xy 131.241292 -428.347886) (xy 131.239749 -428.333394) (xy 131.238096 -428.304294) (xy 131.23799 -428.28972)
			(xy 128.335024 -428.28972) (xy 128.335024 -428.960534) (xy 128.334669 -428.972662) (xy 128.327162 -428.995729)
			(xy 128.312895 -429.015347) (xy 128.293264 -429.029595) (xy 128.270191 -429.03708) (xy 128.258062 -429.037496)
			(xy 127.318262 -429.037496) (xy 127.306149 -429.037021) (xy 127.28311 -429.029528) (xy 127.263512 -429.015285)
			(xy 127.24927 -428.995686) (xy 127.241778 -428.972647) (xy 127.2413 -428.960534) (xy 127.2413 -428.347886)
			(xy 127.239757 -428.333394) (xy 127.238104 -428.304294) (xy 127.237998 -428.28972) (xy 115.623848 -428.28972)
			(xy 115.623848 -429.82896) (xy 115.657639 -429.909572) (xy 115.718855 -430.073317) (xy 115.772692 -430.239633)
			(xy 115.819041 -430.40819) (xy 115.85781 -430.57865) (xy 115.888922 -430.750673) (xy 115.907724 -430.889918)
			(xy 125.238002 -430.889918) (xy 125.238096 -430.875344) (xy 125.239748 -430.846243) (xy 125.241304 -430.831752)
			(xy 125.241304 -429.747934) (xy 125.239756 -429.733442) (xy 125.238106 -429.704342) (xy 125.238002 -429.689768)
			(xy 125.2381 -429.675194) (xy 125.23975 -429.646093) (xy 125.241304 -429.631602) (xy 125.241304 -429.018954)
			(xy 125.241772 -429.00684) (xy 125.249268 -428.983801) (xy 125.263512 -428.964203) (xy 125.283112 -428.949962)
			(xy 125.306152 -428.94247) (xy 125.318266 -428.941992) (xy 126.258066 -428.941992) (xy 126.270174 -428.94254)
			(xy 126.293209 -428.950012) (xy 126.312807 -428.964236) (xy 126.327051 -428.98382) (xy 126.334547 -429.006846)
			(xy 126.335028 -429.018954) (xy 126.335028 -431.560478) (xy 126.334621 -431.572603) (xy 126.32713 -431.595667)
			(xy 126.312877 -431.615285) (xy 126.293256 -431.629536) (xy 126.270191 -431.637023) (xy 126.258066 -431.63744)
			(xy 125.318266 -431.63744) (xy 125.306147 -431.637017) (xy 125.283099 -431.629518) (xy 125.263496 -431.615264)
			(xy 125.249257 -431.59565) (xy 125.241774 -431.572597) (xy 125.241304 -431.560478) (xy 125.241304 -430.948084)
			(xy 125.23976 -430.933592) (xy 125.238108 -430.904492) (xy 125.238002 -430.889918) (xy 115.907724 -430.889918)
			(xy 115.912314 -430.923914) (xy 115.92794 -431.098027) (xy 115.935768 -431.272665) (xy 115.936268 -431.360072)
			(xy 115.935765 -431.447478) (xy 115.927918 -431.622114) (xy 115.912279 -431.796225) (xy 115.899624 -431.889916)
			(xy 127.237998 -431.889916) (xy 127.238092 -431.875342) (xy 127.239744 -431.846241) (xy 127.2413 -431.83175)
			(xy 127.2413 -430.747932) (xy 127.239752 -430.73344) (xy 127.238102 -430.70434) (xy 127.237998 -430.689766)
			(xy 127.238096 -430.675192) (xy 127.239746 -430.646091) (xy 127.2413 -430.6316) (xy 127.2413 -430.018952)
			(xy 127.241676 -430.006841) (xy 127.249188 -429.983812) (xy 127.26346 -429.96424) (xy 127.28309 -429.950047)
			(xy 127.306149 -429.942627) (xy 127.318262 -429.942244) (xy 128.258062 -429.942244) (xy 128.27015 -429.94274)
			(xy 128.29315 -429.950187) (xy 128.312731 -429.964366) (xy 128.326983 -429.983894) (xy 128.334515 -430.006866)
			(xy 128.335024 -430.018952) (xy 128.335024 -430.889918) (xy 129.237994 -430.889918) (xy 129.238088 -430.875344)
			(xy 129.23974 -430.846243) (xy 129.241296 -430.831752) (xy 129.241296 -429.747934) (xy 129.239749 -429.733442)
			(xy 129.238098 -429.704342) (xy 129.237994 -429.689768) (xy 129.238092 -429.675194) (xy 129.239742 -429.646093)
			(xy 129.241296 -429.631602) (xy 129.241296 -429.018954) (xy 129.241772 -429.006841) (xy 129.249267 -428.983804)
			(xy 129.263509 -428.964206) (xy 129.283107 -428.949965) (xy 129.306145 -428.942471) (xy 129.318258 -428.941992)
			(xy 130.258058 -428.941992) (xy 130.270166 -428.942547) (xy 130.2932 -428.950017) (xy 130.312798 -428.964239)
			(xy 130.327043 -428.983821) (xy 130.334539 -429.006847) (xy 130.33502 -429.018954) (xy 130.33502 -431.560478)
			(xy 130.334621 -431.572604) (xy 130.327129 -431.595669) (xy 130.312874 -431.615288) (xy 130.293251 -431.629538)
			(xy 130.270184 -431.637024) (xy 130.258058 -431.63744) (xy 129.318258 -431.63744) (xy 129.306139 -431.637024)
			(xy 129.283091 -431.629522) (xy 129.263488 -431.615267) (xy 129.249248 -431.595652) (xy 129.241766 -431.572597)
			(xy 129.241296 -431.560478) (xy 129.241296 -430.948084) (xy 129.239753 -430.933592) (xy 129.2381 -430.904492)
			(xy 129.237994 -430.889918) (xy 128.335024 -430.889918) (xy 128.335024 -431.889916) (xy 131.23799 -431.889916)
			(xy 131.238084 -431.875342) (xy 131.239736 -431.846241) (xy 131.241292 -431.83175) (xy 131.241292 -430.747932)
			(xy 131.239744 -430.73344) (xy 131.238094 -430.70434) (xy 131.23799 -430.689766) (xy 131.238088 -430.675192)
			(xy 131.239738 -430.646091) (xy 131.241292 -430.6316) (xy 131.241292 -430.018952) (xy 131.241675 -430.006841)
			(xy 131.249187 -429.983814) (xy 131.263458 -429.964242) (xy 131.283085 -429.950049) (xy 131.306142 -429.942628)
			(xy 131.318254 -429.942244) (xy 132.258054 -429.942244) (xy 132.270142 -429.942747) (xy 132.293141 -429.950191)
			(xy 132.312722 -429.964368) (xy 132.326974 -429.983895) (xy 132.334507 -430.006866) (xy 132.335016 -430.018952)
			(xy 132.335016 -430.889918) (xy 133.237986 -430.889918) (xy 133.23808 -430.875344) (xy 133.239732 -430.846243)
			(xy 133.241288 -430.831752) (xy 133.241288 -429.747934) (xy 133.239741 -429.733442) (xy 133.23809 -429.704342)
			(xy 133.237986 -429.689768) (xy 133.238084 -429.675194) (xy 133.239734 -429.646093) (xy 133.241288 -429.631602)
			(xy 133.241288 -429.018954) (xy 133.241772 -429.006842) (xy 133.249266 -428.983806) (xy 133.263506 -428.964209)
			(xy 133.283102 -428.949967) (xy 133.306138 -428.942472) (xy 133.31825 -428.941992) (xy 134.25805 -428.941992)
			(xy 134.270163 -428.942468) (xy 134.2932 -428.949964) (xy 134.312797 -428.964206) (xy 134.327038 -428.983804)
			(xy 134.334532 -429.006841) (xy 134.335012 -429.018954) (xy 134.335012 -431.560478) (xy 134.33447 -431.572586)
			(xy 134.326995 -431.59562) (xy 134.312769 -431.615218) (xy 134.293185 -431.629462) (xy 134.270158 -431.636959)
			(xy 134.25805 -431.63744) (xy 133.31825 -431.63744) (xy 133.306131 -431.63703) (xy 133.283082 -431.629527)
			(xy 133.263479 -431.615269) (xy 133.24924 -431.595653) (xy 133.241758 -431.572598) (xy 133.241288 -431.560478)
			(xy 133.241288 -430.948084) (xy 133.239745 -430.933592) (xy 133.238092 -430.904492) (xy 133.237986 -430.889918)
			(xy 132.335016 -430.889918) (xy 132.335016 -431.889916) (xy 135.237982 -431.889916) (xy 135.238076 -431.875342)
			(xy 135.239728 -431.846241) (xy 135.241284 -431.83175) (xy 135.241284 -430.747932) (xy 135.239736 -430.73344)
			(xy 135.238086 -430.70434) (xy 135.237982 -430.689766) (xy 135.23808 -430.675192) (xy 135.23973 -430.646091)
			(xy 135.241284 -430.6316) (xy 135.241284 -430.018952) (xy 135.241675 -430.006842) (xy 135.249186 -429.983816)
			(xy 135.263455 -429.964245) (xy 135.28308 -429.950052) (xy 135.306135 -429.942629) (xy 135.318246 -429.942244)
			(xy 136.258046 -429.942244) (xy 136.270138 -429.942668) (xy 136.293141 -429.950138) (xy 136.312721 -429.964336)
			(xy 136.32697 -429.983878) (xy 136.3345 -430.006861) (xy 136.335008 -430.018952) (xy 136.335008 -430.889918)
			(xy 137.237978 -430.889918) (xy 137.238072 -430.875344) (xy 137.239724 -430.846243) (xy 137.24128 -430.831752)
			(xy 137.24128 -429.747934) (xy 137.239733 -429.733442) (xy 137.238082 -429.704342) (xy 137.237978 -429.689768)
			(xy 137.238076 -429.675194) (xy 137.239726 -429.646093) (xy 137.24128 -429.631602) (xy 137.24128 -429.018954)
			(xy 137.241673 -429.006833) (xy 137.249178 -428.983781) (xy 137.263439 -428.964176) (xy 137.28306 -428.949938)
			(xy 137.30612 -428.942459) (xy 137.318242 -428.941992) (xy 138.258042 -428.941992) (xy 138.270154 -428.942475)
			(xy 138.293191 -428.949968) (xy 138.312788 -428.964209) (xy 138.32703 -428.983805) (xy 138.334524 -429.006842)
			(xy 138.335004 -429.018954) (xy 138.335004 -431.560478) (xy 138.33447 -431.572587) (xy 138.326994 -431.595623)
			(xy 138.312767 -431.615221) (xy 138.29318 -431.629465) (xy 138.270151 -431.63696) (xy 138.258042 -431.63744)
			(xy 137.318242 -431.63744) (xy 137.306119 -431.637004) (xy 137.283058 -431.629521) (xy 137.26344 -431.615274)
			(xy 137.249188 -431.59566) (xy 137.241699 -431.572601) (xy 137.24128 -431.560478) (xy 137.24128 -430.948084)
			(xy 137.239737 -430.933592) (xy 137.238084 -430.904492) (xy 137.237978 -430.889918) (xy 136.335008 -430.889918)
			(xy 136.335008 -431.889916) (xy 139.237974 -431.889916) (xy 139.238068 -431.875342) (xy 139.23972 -431.846241)
			(xy 139.241276 -431.83175) (xy 139.241276 -430.747932) (xy 139.239728 -430.73344) (xy 139.238078 -430.70434)
			(xy 139.237974 -430.689766) (xy 139.238072 -430.675192) (xy 139.239722 -430.646091) (xy 139.241276 -430.6316)
			(xy 139.241276 -430.018952) (xy 139.241675 -430.006843) (xy 139.249185 -429.983818) (xy 139.263452 -429.964248)
			(xy 139.283075 -429.950054) (xy 139.306128 -429.94263) (xy 139.318238 -429.942244) (xy 140.258038 -429.942244)
			(xy 140.27013 -429.942675) (xy 140.293133 -429.950143) (xy 140.312712 -429.964338) (xy 140.326961 -429.983879)
			(xy 140.334492 -430.006861) (xy 140.335 -430.018952) (xy 140.335 -430.889918) (xy 142.237968 -430.889918)
			(xy 142.238077 -430.874832) (xy 142.239859 -430.844714) (xy 142.241524 -430.82972) (xy 142.241524 -429.749966)
			(xy 142.239859 -429.734972) (xy 142.238078 -429.704854) (xy 142.237968 -429.689768) (xy 142.238082 -429.674682)
			(xy 142.23986 -429.644564) (xy 142.241524 -429.62957) (xy 142.241524 -429.018954) (xy 142.241968 -429.006864)
			(xy 142.249435 -428.983864) (xy 142.263628 -428.964286) (xy 142.283165 -428.950037) (xy 142.306143 -428.942503)
			(xy 142.318232 -428.941992) (xy 143.258032 -428.941992) (xy 143.270142 -428.942389) (xy 143.293169 -428.949896)
			(xy 143.312741 -428.964163) (xy 143.326934 -428.983788) (xy 143.334356 -429.006843) (xy 143.33474 -429.018954)
			(xy 143.33474 -431.560478) (xy 143.334273 -431.572568) (xy 143.32682 -431.595572) (xy 143.312634 -431.615154)
			(xy 143.293099 -431.629404) (xy 143.270121 -431.636933) (xy 143.258032 -431.63744) (xy 142.318232 -431.63744)
			(xy 142.306129 -431.636957) (xy 142.283109 -431.629471) (xy 142.263539 -431.615225) (xy 142.249342 -431.59562)
			(xy 142.241913 -431.572582) (xy 142.241524 -431.560478) (xy 142.241524 -430.950116) (xy 142.239855 -430.935123)
			(xy 142.238077 -430.905004) (xy 142.237968 -430.889918) (xy 140.335 -430.889918) (xy 140.335 -431.889916)
			(xy 144.237964 -431.889916) (xy 144.238073 -431.87483) (xy 144.239855 -431.844712) (xy 144.24152 -431.829718)
			(xy 144.24152 -430.749964) (xy 144.239855 -430.73497) (xy 144.238074 -430.704852) (xy 144.237964 -430.689766)
			(xy 144.238078 -430.67468) (xy 144.239856 -430.644562) (xy 144.24152 -430.629568) (xy 144.24152 -430.018952)
			(xy 144.241924 -430.006872) (xy 144.249403 -429.983899) (xy 144.263614 -429.96436) (xy 144.283167 -429.950168)
			(xy 144.306148 -429.942712) (xy 144.318228 -429.942244) (xy 145.258028 -429.942244) (xy 145.270099 -429.942739)
			(xy 145.293059 -429.950204) (xy 145.312592 -429.964394) (xy 145.326787 -429.983923) (xy 145.334258 -430.006881)
			(xy 145.334736 -430.018952) (xy 145.334736 -430.889918) (xy 146.23796 -430.889918) (xy 146.238069 -430.874832)
			(xy 146.239851 -430.844714) (xy 146.241516 -430.82972) (xy 146.241516 -429.749966) (xy 146.239851 -429.734972)
			(xy 146.23807 -429.704854) (xy 146.23796 -429.689768) (xy 146.238074 -429.674682) (xy 146.239852 -429.644564)
			(xy 146.241516 -429.62957) (xy 146.241516 -429.018954) (xy 146.241968 -429.006864) (xy 146.249434 -428.983866)
			(xy 146.263626 -428.964289) (xy 146.28316 -428.950039) (xy 146.306136 -428.942504) (xy 146.318224 -428.941992)
			(xy 147.258024 -428.941992) (xy 147.270133 -428.942396) (xy 147.29316 -428.949901) (xy 147.312732 -428.964166)
			(xy 147.326926 -428.983789) (xy 147.334348 -429.006843) (xy 147.334732 -429.018954) (xy 147.334732 -431.560478)
			(xy 147.334273 -431.572569) (xy 147.326819 -431.595574) (xy 147.312632 -431.615156) (xy 147.293094 -431.629407)
			(xy 147.270114 -431.636934) (xy 147.258024 -431.63744) (xy 146.318224 -431.63744) (xy 146.30612 -431.636964)
			(xy 146.283101 -431.629476) (xy 146.263531 -431.615228) (xy 146.249334 -431.595622) (xy 146.241905 -431.572583)
			(xy 146.241516 -431.560478) (xy 146.241516 -430.950116) (xy 146.239847 -430.935123) (xy 146.238069 -430.905004)
			(xy 146.23796 -430.889918) (xy 145.334736 -430.889918) (xy 145.334736 -431.889916) (xy 148.237956 -431.889916)
			(xy 148.238065 -431.87483) (xy 148.239847 -431.844712) (xy 148.241512 -431.829718) (xy 148.241512 -430.749964)
			(xy 148.239847 -430.73497) (xy 148.238066 -430.704852) (xy 148.237956 -430.689766) (xy 148.23807 -430.67468)
			(xy 148.239848 -430.644562) (xy 148.241512 -430.629568) (xy 148.241512 -430.018952) (xy 148.241924 -430.006873)
			(xy 148.249402 -429.983901) (xy 148.263611 -429.964363) (xy 148.283162 -429.950171) (xy 148.306141 -429.942713)
			(xy 148.31822 -429.942244) (xy 149.25802 -429.942244) (xy 149.270091 -429.942747) (xy 149.29305 -429.950209)
			(xy 149.312583 -429.964397) (xy 149.326778 -429.983924) (xy 149.334249 -430.006881) (xy 149.334728 -430.018952)
			(xy 149.334728 -430.889918) (xy 150.237952 -430.889918) (xy 150.238061 -430.874832) (xy 150.239843 -430.844714)
			(xy 150.241508 -430.82972) (xy 150.241508 -429.749966) (xy 150.239843 -429.734972) (xy 150.238062 -429.704854)
			(xy 150.237952 -429.689768) (xy 150.238066 -429.674682) (xy 150.239844 -429.644564) (xy 150.241508 -429.62957)
			(xy 150.241508 -429.018954) (xy 150.241968 -429.006865) (xy 150.249433 -428.983868) (xy 150.263623 -428.964292)
			(xy 150.283155 -428.950042) (xy 150.306129 -428.942505) (xy 150.318216 -428.941992) (xy 151.258016 -428.941992)
			(xy 151.270125 -428.942402) (xy 151.293151 -428.949905) (xy 151.312724 -428.964169) (xy 151.326918 -428.983791)
			(xy 151.33434 -429.006844) (xy 151.334724 -429.018954) (xy 151.334724 -431.560478) (xy 151.334273 -431.57257)
			(xy 151.326818 -431.595576) (xy 151.312629 -431.615159) (xy 151.293089 -431.629409) (xy 151.270106 -431.636935)
			(xy 151.258016 -431.63744) (xy 150.318216 -431.63744) (xy 150.306112 -431.63697) (xy 150.283092 -431.62948)
			(xy 150.263522 -431.615231) (xy 150.249326 -431.595623) (xy 150.241897 -431.572583) (xy 150.241508 -431.560478)
			(xy 150.241508 -430.950116) (xy 150.239839 -430.935123) (xy 150.238061 -430.905004) (xy 150.237952 -430.889918)
			(xy 149.334728 -430.889918) (xy 149.334728 -431.889916) (xy 152.237948 -431.889916) (xy 152.238057 -431.87483)
			(xy 152.239839 -431.844712) (xy 152.241504 -431.829718) (xy 152.241504 -430.749964) (xy 152.239839 -430.73497)
			(xy 152.238058 -430.704852) (xy 152.237948 -430.689766) (xy 152.238062 -430.67468) (xy 152.23984 -430.644562)
			(xy 152.241504 -430.629568) (xy 152.241504 -430.018952) (xy 152.241923 -430.006874) (xy 152.249401 -429.983903)
			(xy 152.263608 -429.964366) (xy 152.283157 -429.950173) (xy 152.306133 -429.942714) (xy 152.318212 -429.942244)
			(xy 153.258012 -429.942244) (xy 153.270082 -429.942753) (xy 153.293042 -429.950213) (xy 153.312574 -429.9644)
			(xy 153.32677 -429.983926) (xy 153.334241 -430.006882) (xy 153.33472 -430.018952) (xy 153.33472 -430.889918)
			(xy 154.237944 -430.889918) (xy 154.238053 -430.874832) (xy 154.239835 -430.844714) (xy 154.2415 -430.82972)
			(xy 154.2415 -429.749966) (xy 154.239835 -429.734972) (xy 154.238054 -429.704854) (xy 154.237944 -429.689768)
			(xy 154.238058 -429.674682) (xy 154.239836 -429.644564) (xy 154.2415 -429.62957) (xy 154.2415 -429.018954)
			(xy 154.241967 -429.006866) (xy 154.249432 -428.983871) (xy 154.26362 -428.964295) (xy 154.28315 -428.950044)
			(xy 154.306122 -428.942507) (xy 154.318208 -428.941992) (xy 155.258008 -428.941992) (xy 155.270117 -428.942409)
			(xy 155.293143 -428.94991) (xy 155.312715 -428.964172) (xy 155.32691 -428.983792) (xy 155.334332 -429.006844)
			(xy 155.334716 -429.018954) (xy 155.334716 -431.560478) (xy 155.334273 -431.572571) (xy 155.326817 -431.595578)
			(xy 155.312626 -431.615162) (xy 155.293084 -431.629412) (xy 155.270099 -431.636937) (xy 155.258008 -431.63744)
			(xy 154.318208 -431.63744) (xy 154.306104 -431.636978) (xy 154.283083 -431.629485) (xy 154.263513 -431.615234)
			(xy 154.249317 -431.595625) (xy 154.241889 -431.572584) (xy 154.2415 -431.560478) (xy 154.2415 -430.950116)
			(xy 154.239831 -430.935123) (xy 154.238053 -430.905004) (xy 154.237944 -430.889918) (xy 153.33472 -430.889918)
			(xy 153.33472 -431.889916) (xy 156.23794 -431.889916) (xy 156.238051 -431.87483) (xy 156.239833 -431.844712)
			(xy 156.241496 -431.829718) (xy 156.241496 -430.749964) (xy 156.239831 -430.73497) (xy 156.23805 -430.704852)
			(xy 156.23794 -430.689766) (xy 156.238054 -430.67468) (xy 156.239832 -430.644562) (xy 156.241496 -430.629568)
			(xy 156.241496 -430.018952) (xy 156.241923 -430.006875) (xy 156.249399 -429.983905) (xy 156.263605 -429.964368)
			(xy 156.283152 -429.950176) (xy 156.306126 -429.942715) (xy 156.318204 -429.942244) (xy 157.258004 -429.942244)
			(xy 157.270074 -429.94276) (xy 157.293033 -429.950218) (xy 157.312566 -429.964403) (xy 157.326762 -429.983927)
			(xy 157.334233 -430.006882) (xy 157.334712 -430.018952) (xy 157.334712 -432.560476) (xy 157.334267 -432.572557)
			(xy 157.326806 -432.595538) (xy 157.312609 -432.615089) (xy 157.293063 -432.629294) (xy 157.270085 -432.636762)
			(xy 157.258004 -432.637184) (xy 156.318204 -432.637184) (xy 156.306119 -432.636784) (xy 156.283132 -432.629314)
			(xy 156.26358 -432.615106) (xy 156.249376 -432.59555) (xy 156.241913 -432.572561) (xy 156.241496 -432.560476)
			(xy 156.241496 -431.950114) (xy 156.239826 -431.935121) (xy 156.238049 -431.905002) (xy 156.23794 -431.889916)
			(xy 153.33472 -431.889916) (xy 153.33472 -432.560476) (xy 153.334267 -432.572556) (xy 153.326807 -432.595536)
			(xy 153.312611 -432.615086) (xy 153.293068 -432.629291) (xy 153.270092 -432.636761) (xy 153.258012 -432.637184)
			(xy 152.318212 -432.637184) (xy 152.306128 -432.636777) (xy 152.283141 -432.629309) (xy 152.263589 -432.615103)
			(xy 152.249385 -432.595548) (xy 152.241922 -432.572561) (xy 152.241504 -432.560476) (xy 152.241504 -431.950114)
			(xy 152.239834 -431.935121) (xy 152.238057 -431.905002) (xy 152.237948 -431.889916) (xy 149.334728 -431.889916)
			(xy 149.334728 -432.560476) (xy 149.334267 -432.572555) (xy 149.326809 -432.595534) (xy 149.312614 -432.615083)
			(xy 149.293073 -432.629288) (xy 149.270099 -432.63676) (xy 149.25802 -432.637184) (xy 148.31822 -432.637184)
			(xy 148.306136 -432.63677) (xy 148.28315 -432.629305) (xy 148.263597 -432.6151) (xy 148.249393 -432.595547)
			(xy 148.24193 -432.57256) (xy 148.241512 -432.560476) (xy 148.241512 -431.950114) (xy 148.239842 -431.935121)
			(xy 148.238065 -431.905002) (xy 148.237956 -431.889916) (xy 145.334736 -431.889916) (xy 145.334736 -432.560476)
			(xy 145.334216 -432.572547) (xy 145.326763 -432.595508) (xy 145.31258 -432.615043) (xy 145.293055 -432.62924)
			(xy 145.270098 -432.636708) (xy 145.258028 -432.637184) (xy 144.318228 -432.637184) (xy 144.306144 -432.636763)
			(xy 144.283159 -432.6293) (xy 144.263606 -432.615097) (xy 144.249402 -432.595545) (xy 144.241938 -432.57256)
			(xy 144.24152 -432.560476) (xy 144.24152 -431.950114) (xy 144.23985 -431.935121) (xy 144.238073 -431.905002)
			(xy 144.237964 -431.889916) (xy 140.335 -431.889916) (xy 140.335 -432.560476) (xy 140.334563 -432.572584)
			(xy 140.32707 -432.59561) (xy 140.312814 -432.615184) (xy 140.293196 -432.629379) (xy 140.270147 -432.6368)
			(xy 140.258038 -432.637184) (xy 139.318238 -432.637184) (xy 139.306153 -432.636661) (xy 139.283157 -432.629217)
			(xy 139.263579 -432.615044) (xy 139.249326 -432.595524) (xy 139.241789 -432.572559) (xy 139.241276 -432.560476)
			(xy 139.241276 -431.948082) (xy 139.239733 -431.93359) (xy 139.23808 -431.90449) (xy 139.237974 -431.889916)
			(xy 136.335008 -431.889916) (xy 136.335008 -432.560476) (xy 136.334563 -432.572583) (xy 136.327071 -432.595608)
			(xy 136.312817 -432.615181) (xy 136.293201 -432.629376) (xy 136.270154 -432.636799) (xy 136.258046 -432.637184)
			(xy 135.318246 -432.637184) (xy 135.306161 -432.636654) (xy 135.283166 -432.629213) (xy 135.263587 -432.615042)
			(xy 135.249334 -432.595522) (xy 135.241797 -432.572559) (xy 135.241284 -432.560476) (xy 135.241284 -431.948082)
			(xy 135.239741 -431.93359) (xy 135.238088 -431.90449) (xy 135.237982 -431.889916) (xy 132.335016 -431.889916)
			(xy 132.335016 -432.560476) (xy 132.334563 -432.572582) (xy 132.327072 -432.595606) (xy 132.31282 -432.615178)
			(xy 132.293206 -432.629374) (xy 132.270161 -432.636798) (xy 132.258054 -432.637184) (xy 131.318254 -432.637184)
			(xy 131.306164 -432.636732) (xy 131.283166 -432.629266) (xy 131.263589 -432.615074) (xy 131.249339 -432.59554)
			(xy 131.241804 -432.572564) (xy 131.241292 -432.560476) (xy 131.241292 -431.948082) (xy 131.239749 -431.93359)
			(xy 131.238096 -431.90449) (xy 131.23799 -431.889916) (xy 128.335024 -431.889916) (xy 128.335024 -432.560476)
			(xy 128.334563 -432.572581) (xy 128.327074 -432.595604) (xy 128.312823 -432.615175) (xy 128.293212 -432.629371)
			(xy 128.270168 -432.636797) (xy 128.258062 -432.637184) (xy 127.318262 -432.637184) (xy 127.306173 -432.636726)
			(xy 127.283175 -432.629261) (xy 127.263598 -432.615072) (xy 127.249348 -432.595538) (xy 127.241812 -432.572564)
			(xy 127.2413 -432.560476) (xy 127.2413 -431.948082) (xy 127.239756 -431.93359) (xy 127.238104 -431.90449)
			(xy 127.237998 -431.889916) (xy 115.899624 -431.889916) (xy 115.888879 -431.969464) (xy 115.857765 -432.141485)
			(xy 115.819 -432.311944) (xy 115.772659 -432.480502) (xy 115.718836 -432.646822) (xy 115.657638 -432.810572)
			(xy 115.623848 -432.891184) (xy 115.623848 -434.48986) (xy 125.238002 -434.48986) (xy 125.2381 -434.475286)
			(xy 125.239749 -434.446185) (xy 125.241304 -434.431694) (xy 125.241304 -433.34813) (xy 125.239756 -433.333638)
			(xy 125.238106 -433.304538) (xy 125.238002 -433.289964) (xy 125.2381 -433.27539) (xy 125.239749 -433.246289)
			(xy 125.241304 -433.231798) (xy 125.241304 -432.618896) (xy 125.241713 -432.606787) (xy 125.249214 -432.583758)
			(xy 125.263477 -432.564185) (xy 125.283101 -432.549991) (xy 125.306155 -432.542571) (xy 125.318266 -432.542188)
			(xy 126.258066 -432.542188) (xy 126.270159 -432.542637) (xy 126.293166 -432.55009) (xy 126.312751 -432.56428)
			(xy 126.327001 -432.583821) (xy 126.334525 -432.606805) (xy 126.335028 -432.618896) (xy 126.335028 -435.16042)
			(xy 126.334601 -435.172527) (xy 126.3271 -435.19555) (xy 126.31284 -435.215121) (xy 126.293222 -435.229316)
			(xy 126.270174 -435.236741) (xy 126.258066 -435.237128) (xy 125.318266 -435.237128) (xy 125.306171 -435.236721)
			(xy 125.283164 -435.229251) (xy 125.263582 -435.21505) (xy 125.249334 -435.195502) (xy 125.241808 -435.172513)
			(xy 125.241304 -435.16042) (xy 125.241304 -434.548026) (xy 125.239756 -434.533534) (xy 125.238106 -434.504434)
			(xy 125.238002 -434.48986) (xy 115.623848 -434.48986) (xy 115.623848 -435.489858) (xy 127.237998 -435.489858)
			(xy 127.238095 -435.475284) (xy 127.239745 -435.446183) (xy 127.2413 -435.431692) (xy 127.2413 -434.348128)
			(xy 127.239752 -434.333636) (xy 127.238102 -434.304536) (xy 127.237998 -434.289962) (xy 127.238096 -434.275388)
			(xy 127.239745 -434.246287) (xy 127.2413 -434.231796) (xy 127.2413 -433.618894) (xy 127.241806 -433.606783)
			(xy 127.24929 -433.583746) (xy 127.263525 -433.564148) (xy 127.283117 -433.549905) (xy 127.306151 -433.542411)
			(xy 127.318262 -433.541932) (xy 128.258062 -433.541932) (xy 128.270182 -433.542392) (xy 128.293239 -433.549873)
			(xy 128.312854 -433.564115) (xy 128.327107 -433.583722) (xy 128.334601 -433.606774) (xy 128.335024 -433.618894)
			(xy 128.335024 -434.48986) (xy 129.237994 -434.48986) (xy 129.238092 -434.475286) (xy 129.239741 -434.446185)
			(xy 129.241296 -434.431694) (xy 129.241296 -433.34813) (xy 129.239748 -433.333638) (xy 129.238098 -433.304538)
			(xy 129.237994 -433.289964) (xy 129.238092 -433.27539) (xy 129.239741 -433.246289) (xy 129.241296 -433.231798)
			(xy 129.241296 -432.618896) (xy 129.241713 -432.606787) (xy 129.249213 -432.583761) (xy 129.263474 -432.564188)
			(xy 129.283096 -432.549993) (xy 129.306148 -432.542572) (xy 129.318258 -432.542188) (xy 130.258058 -432.542188)
			(xy 130.27015 -432.542644) (xy 130.293158 -432.550095) (xy 130.312742 -432.564283) (xy 130.326993 -432.583822)
			(xy 130.334517 -432.606805) (xy 130.33502 -432.618896) (xy 130.33502 -435.16042) (xy 130.334601 -435.172528)
			(xy 130.327099 -435.195552) (xy 130.312837 -435.215123) (xy 130.293217 -435.229318) (xy 130.270167 -435.236742)
			(xy 130.258058 -435.237128) (xy 129.318258 -435.237128) (xy 129.306163 -435.236728) (xy 129.283156 -435.229256)
			(xy 129.263574 -435.215053) (xy 129.249326 -435.195504) (xy 129.2418 -435.172514) (xy 129.241296 -435.16042)
			(xy 129.241296 -434.548026) (xy 129.239748 -434.533534) (xy 129.238098 -434.504434) (xy 129.237994 -434.48986)
			(xy 128.335024 -434.48986) (xy 128.335024 -435.489858) (xy 131.23799 -435.489858) (xy 131.238087 -435.475284)
			(xy 131.239737 -435.446183) (xy 131.241292 -435.431692) (xy 131.241292 -434.348128) (xy 131.239744 -434.333636)
			(xy 131.238094 -434.304536) (xy 131.23799 -434.289962) (xy 131.238088 -434.275388) (xy 131.239737 -434.246287)
			(xy 131.241292 -434.231796) (xy 131.241292 -433.618894) (xy 131.241806 -433.606784) (xy 131.249289 -433.583748)
			(xy 131.263522 -433.564151) (xy 131.283112 -433.549908) (xy 131.306144 -433.542412) (xy 131.318254 -433.541932)
			(xy 132.258054 -433.541932) (xy 132.270174 -433.542399) (xy 132.29323 -433.549878) (xy 132.312846 -433.564117)
			(xy 132.327098 -433.583723) (xy 132.334593 -433.606775) (xy 132.335016 -433.618894) (xy 132.335016 -434.48986)
			(xy 133.237986 -434.48986) (xy 133.238084 -434.475286) (xy 133.239733 -434.446185) (xy 133.241288 -434.431694)
			(xy 133.241288 -433.34813) (xy 133.23974 -433.333638) (xy 133.23809 -433.304538) (xy 133.237986 -433.289964)
			(xy 133.238084 -433.27539) (xy 133.239733 -433.246289) (xy 133.241288 -433.231798) (xy 133.241288 -432.618896)
			(xy 133.241713 -432.606788) (xy 133.249212 -432.583763) (xy 133.263472 -432.564191) (xy 133.283091 -432.549996)
			(xy 133.306141 -432.542573) (xy 133.31825 -432.542188) (xy 134.25805 -432.542188) (xy 134.270142 -432.542651)
			(xy 134.293149 -432.5501) (xy 134.312734 -432.564285) (xy 134.326984 -432.583823) (xy 134.334509 -432.606806)
			(xy 134.335012 -432.618896) (xy 134.335012 -435.16042) (xy 134.334601 -435.172529) (xy 134.327097 -435.195555)
			(xy 134.312834 -435.215126) (xy 134.293212 -435.229321) (xy 134.27016 -435.236743) (xy 134.25805 -435.237128)
			(xy 133.31825 -435.237128) (xy 133.30616 -435.23665) (xy 133.283155 -435.229203) (xy 133.263572 -435.21502)
			(xy 133.249321 -435.195487) (xy 133.241793 -435.172508) (xy 133.241288 -435.16042) (xy 133.241288 -434.548026)
			(xy 133.23974 -434.533534) (xy 133.23809 -434.504434) (xy 133.237986 -434.48986) (xy 132.335016 -434.48986)
			(xy 132.335016 -435.489858) (xy 135.237982 -435.489858) (xy 135.238079 -435.475284) (xy 135.239729 -435.446183)
			(xy 135.241284 -435.431692) (xy 135.241284 -434.348128) (xy 135.239736 -434.333636) (xy 135.238086 -434.304536)
			(xy 135.237982 -434.289962) (xy 135.23808 -434.275388) (xy 135.239729 -434.246287) (xy 135.241284 -434.231796)
			(xy 135.241284 -433.618894) (xy 135.241656 -433.606766) (xy 135.249155 -433.5837) (xy 135.263418 -433.564081)
			(xy 135.283046 -433.549831) (xy 135.306118 -433.542348) (xy 135.318246 -433.541932) (xy 136.258046 -433.541932)
			(xy 136.270162 -433.542372) (xy 136.293206 -433.549872) (xy 136.312807 -433.564122) (xy 136.327047 -433.58373)
			(xy 136.334534 -433.606777) (xy 136.335008 -433.618894) (xy 136.335008 -434.48986) (xy 137.237978 -434.48986)
			(xy 137.238076 -434.475286) (xy 137.239725 -434.446185) (xy 137.24128 -434.431694) (xy 137.24128 -433.34813)
			(xy 137.239732 -433.333638) (xy 137.238082 -433.304538) (xy 137.237978 -433.289964) (xy 137.238076 -433.27539)
			(xy 137.239726 -433.246289) (xy 137.24128 -433.231798) (xy 137.24128 -432.618896) (xy 137.241712 -432.606789)
			(xy 137.249211 -432.583765) (xy 137.263469 -432.564194) (xy 137.283086 -432.549998) (xy 137.306134 -432.542574)
			(xy 137.318242 -432.542188) (xy 138.258042 -432.542188) (xy 138.270139 -432.542572) (xy 138.293149 -432.550047)
			(xy 138.312732 -432.564253) (xy 138.326979 -432.583806) (xy 138.334502 -432.606801) (xy 138.335004 -432.618896)
			(xy 138.335004 -435.16042) (xy 138.334601 -435.17253) (xy 138.327096 -435.195557) (xy 138.312831 -435.215129)
			(xy 138.293207 -435.229323) (xy 138.270153 -435.236744) (xy 138.258042 -435.237128) (xy 137.318242 -435.237128)
			(xy 137.306151 -435.236656) (xy 137.283147 -435.229207) (xy 137.263563 -435.215023) (xy 137.249313 -435.195488)
			(xy 137.241785 -435.172509) (xy 137.24128 -435.16042) (xy 137.24128 -434.548026) (xy 137.239732 -434.533534)
			(xy 137.238082 -434.504434) (xy 137.237978 -434.48986) (xy 136.335008 -434.48986) (xy 136.335008 -435.489858)
			(xy 139.237974 -435.489858) (xy 139.238072 -435.475284) (xy 139.239721 -435.446183) (xy 139.241276 -435.431692)
			(xy 139.241276 -434.348128) (xy 139.239728 -434.333636) (xy 139.238078 -434.304536) (xy 139.237974 -434.289962)
			(xy 139.238072 -434.275388) (xy 139.239721 -434.246287) (xy 139.241276 -434.231796) (xy 139.241276 -433.618894)
			(xy 139.241656 -433.606767) (xy 139.249154 -433.583702) (xy 139.263415 -433.564084) (xy 139.283041 -433.549834)
			(xy 139.306111 -433.542349) (xy 139.318238 -433.541932) (xy 140.258038 -433.541932) (xy 140.270154 -433.542379)
			(xy 140.293197 -433.549876) (xy 140.312798 -433.564125) (xy 140.327038 -433.583731) (xy 140.334526 -433.606778)
			(xy 140.335 -433.618894) (xy 140.335 -434.48986) (xy 142.237968 -434.48986) (xy 142.238081 -434.474774)
			(xy 142.23986 -434.444656) (xy 142.241524 -434.429662) (xy 142.241524 -433.350162) (xy 142.239859 -433.335168)
			(xy 142.238078 -433.30505) (xy 142.237968 -433.289964) (xy 142.238081 -433.274878) (xy 142.23986 -433.24476)
			(xy 142.241524 -433.229766) (xy 142.241524 -432.618896) (xy 142.24191 -432.60681) (xy 142.249382 -432.583822)
			(xy 142.263594 -432.564268) (xy 142.283154 -432.550066) (xy 142.306146 -432.542604) (xy 142.318232 -432.542188)
			(xy 143.258032 -432.542188) (xy 143.270108 -432.542637) (xy 143.293075 -432.550108) (xy 143.312612 -432.564308)
			(xy 143.326805 -432.58385) (xy 143.334268 -432.60682) (xy 143.33474 -432.618896) (xy 143.33474 -435.16042)
			(xy 143.334253 -435.172492) (xy 143.326789 -435.195455) (xy 143.312597 -435.214989) (xy 143.293065 -435.229184)
			(xy 143.270104 -435.236651) (xy 143.258032 -435.237128) (xy 142.318232 -435.237128) (xy 142.306153 -435.23666)
			(xy 142.283175 -435.229204) (xy 142.263626 -435.215011) (xy 142.24942 -435.195472) (xy 142.241948 -435.172499)
			(xy 142.241524 -435.16042) (xy 142.241524 -434.550058) (xy 142.239858 -434.535064) (xy 142.238078 -434.504946)
			(xy 142.237968 -434.48986) (xy 140.335 -434.48986) (xy 140.335 -435.489858) (xy 144.237964 -435.489858)
			(xy 144.238077 -435.474772) (xy 144.239856 -435.444654) (xy 144.24152 -435.42966) (xy 144.24152 -434.35016)
			(xy 144.239855 -434.335166) (xy 144.238074 -434.305048) (xy 144.237964 -434.289962) (xy 144.238077 -434.274876)
			(xy 144.239856 -434.244758) (xy 144.24152 -434.229764) (xy 144.24152 -433.618894) (xy 144.242002 -433.606806)
			(xy 144.249458 -433.583809) (xy 144.263641 -433.564231) (xy 144.28317 -433.54998) (xy 144.306142 -433.542444)
			(xy 144.318228 -433.541932) (xy 145.258028 -433.541932) (xy 145.270142 -433.542293) (xy 145.293175 -433.549804)
			(xy 145.312751 -433.564079) (xy 145.326943 -433.583714) (xy 145.334357 -433.606779) (xy 145.334736 -433.618894)
			(xy 145.334736 -434.48986) (xy 146.23796 -434.48986) (xy 146.238073 -434.474774) (xy 146.239852 -434.444656)
			(xy 146.241516 -434.429662) (xy 146.241516 -433.350162) (xy 146.239851 -433.335168) (xy 146.23807 -433.30505)
			(xy 146.23796 -433.289964) (xy 146.238073 -433.274878) (xy 146.239852 -433.24476) (xy 146.241516 -433.229766)
			(xy 146.241516 -432.618896) (xy 146.241909 -432.606811) (xy 146.249381 -432.583824) (xy 146.263591 -432.564271)
			(xy 146.283149 -432.550068) (xy 146.306138 -432.542605) (xy 146.318224 -432.542188) (xy 147.258024 -432.542188)
			(xy 147.270099 -432.542644) (xy 147.293067 -432.550113) (xy 147.312603 -432.564311) (xy 147.326797 -432.583851)
			(xy 147.334259 -432.606821) (xy 147.334732 -432.618896) (xy 147.334732 -435.16042) (xy 147.334253 -435.172493)
			(xy 147.326788 -435.195457) (xy 147.312594 -435.214991) (xy 147.29306 -435.229186) (xy 147.270097 -435.236652)
			(xy 147.258024 -435.237128) (xy 146.318224 -435.237128) (xy 146.306145 -435.236667) (xy 146.283166 -435.229209)
			(xy 146.263617 -435.215014) (xy 146.249412 -435.195473) (xy 146.24194 -435.172499) (xy 146.241516 -435.16042)
			(xy 146.241516 -434.550058) (xy 146.23985 -434.535064) (xy 146.23807 -434.504946) (xy 146.23796 -434.48986)
			(xy 145.334736 -434.48986) (xy 145.334736 -435.489858) (xy 148.237956 -435.489858) (xy 148.238069 -435.474772)
			(xy 148.239848 -435.444654) (xy 148.241512 -435.42966) (xy 148.241512 -434.35016) (xy 148.239847 -434.335166)
			(xy 148.238066 -434.305048) (xy 148.237956 -434.289962) (xy 148.238069 -434.274876) (xy 148.239848 -434.244758)
			(xy 148.241512 -434.229764) (xy 148.241512 -433.618894) (xy 148.242002 -433.606807) (xy 148.249457 -433.583811)
			(xy 148.263639 -433.564234) (xy 148.283165 -433.549982) (xy 148.306135 -433.542445) (xy 148.31822 -433.541932)
			(xy 149.25802 -433.541932) (xy 149.270133 -433.5423) (xy 149.293167 -433.549808) (xy 149.312742 -433.564081)
			(xy 149.326935 -433.583715) (xy 149.334349 -433.606779) (xy 149.334728 -433.618894) (xy 149.334728 -434.48986)
			(xy 150.237952 -434.48986) (xy 150.238065 -434.474774) (xy 150.239844 -434.444656) (xy 150.241508 -434.429662)
			(xy 150.241508 -433.350162) (xy 150.239843 -433.335168) (xy 150.238062 -433.30505) (xy 150.237952 -433.289964)
			(xy 150.238065 -433.274878) (xy 150.239844 -433.24476) (xy 150.241508 -433.229766) (xy 150.241508 -432.618896)
			(xy 150.241909 -432.606811) (xy 150.24938 -432.583826) (xy 150.263588 -432.564274) (xy 150.283144 -432.550071)
			(xy 150.306131 -432.542606) (xy 150.318216 -432.542188) (xy 151.258016 -432.542188) (xy 151.270091 -432.542651)
			(xy 151.293058 -432.550117) (xy 151.312594 -432.564314) (xy 151.326788 -432.583853) (xy 151.334251 -432.606821)
			(xy 151.334724 -432.618896) (xy 151.334724 -435.16042) (xy 151.334253 -435.172494) (xy 151.326787 -435.195459)
			(xy 151.312591 -435.214994) (xy 151.293055 -435.229189) (xy 151.27009 -435.236654) (xy 151.258016 -435.237128)
			(xy 150.318216 -435.237128) (xy 150.306144 -435.236622) (xy 150.283181 -435.229167) (xy 150.263645 -435.21498)
			(xy 150.24945 -435.195451) (xy 150.241983 -435.172492) (xy 150.241508 -435.16042) (xy 150.241508 -434.550058)
			(xy 150.239842 -434.535064) (xy 150.238062 -434.504946) (xy 150.237952 -434.48986) (xy 149.334728 -434.48986)
			(xy 149.334728 -435.489858) (xy 152.237948 -435.489858) (xy 152.238061 -435.474772) (xy 152.23984 -435.444654)
			(xy 152.241504 -435.42966) (xy 152.241504 -434.35016) (xy 152.239838 -434.335166) (xy 152.238058 -434.305048)
			(xy 152.237948 -434.289962) (xy 152.238061 -434.274876) (xy 152.23984 -434.244758) (xy 152.241504 -434.229764)
			(xy 152.241504 -433.618894) (xy 152.242002 -433.606808) (xy 152.249456 -433.583813) (xy 152.263636 -433.564236)
			(xy 152.28316 -433.549985) (xy 152.306128 -433.542447) (xy 152.318212 -433.541932) (xy 153.258012 -433.541932)
			(xy 153.270125 -433.542306) (xy 153.293158 -433.549813) (xy 153.312734 -433.564084) (xy 153.326927 -433.583717)
			(xy 153.334341 -433.60678) (xy 153.33472 -433.618894) (xy 153.33472 -434.48986) (xy 154.237944 -434.48986)
			(xy 154.238057 -434.474774) (xy 154.239836 -434.444656) (xy 154.2415 -434.429662) (xy 154.2415 -433.350162)
			(xy 154.239835 -433.335168) (xy 154.238054 -433.30505) (xy 154.237944 -433.289964) (xy 154.238057 -433.274878)
			(xy 154.239836 -433.24476) (xy 154.2415 -433.229766) (xy 154.2415 -432.618896) (xy 154.241909 -432.606812)
			(xy 154.249379 -432.583828) (xy 154.263586 -432.564277) (xy 154.283139 -432.550073) (xy 154.306124 -432.542607)
			(xy 154.318208 -432.542188) (xy 155.258008 -432.542188) (xy 155.270083 -432.542657) (xy 155.293049 -432.550122)
			(xy 155.312586 -432.564317) (xy 155.32678 -432.583854) (xy 155.334243 -432.606821) (xy 155.334716 -432.618896)
			(xy 155.334716 -435.16042) (xy 155.334253 -435.172495) (xy 155.326786 -435.195461) (xy 155.312589 -435.214997)
			(xy 155.29305 -435.229191) (xy 155.270083 -435.236655) (xy 155.258008 -435.237128) (xy 154.318208 -435.237128)
			(xy 154.306136 -435.236629) (xy 154.283172 -435.229171) (xy 154.263637 -435.214983) (xy 154.249441 -435.195453)
			(xy 154.241975 -435.172492) (xy 154.2415 -435.16042) (xy 154.2415 -434.550058) (xy 154.239834 -434.535064)
			(xy 154.238054 -434.504946) (xy 154.237944 -434.48986) (xy 153.33472 -434.48986) (xy 153.33472 -435.489858)
			(xy 156.23794 -435.489858) (xy 156.238053 -435.474772) (xy 156.239832 -435.444654) (xy 156.241496 -435.42966)
			(xy 156.241496 -434.35016) (xy 156.23983 -434.335166) (xy 156.23805 -434.305048) (xy 156.23794 -434.289962)
			(xy 156.238053 -434.274876) (xy 156.239832 -434.244758) (xy 156.241496 -434.229764) (xy 156.241496 -433.618894)
			(xy 156.242002 -433.606809) (xy 156.249455 -433.583815) (xy 156.263633 -433.564239) (xy 156.283155 -433.549987)
			(xy 156.30612 -433.542448) (xy 156.318204 -433.541932) (xy 157.258004 -433.541932) (xy 157.270116 -433.542313)
			(xy 157.293149 -433.549818) (xy 157.312725 -433.564087) (xy 157.326918 -433.583718) (xy 157.334333 -433.60678)
			(xy 157.334712 -433.618894) (xy 157.334712 -436.160418) (xy 157.334307 -436.172513) (xy 157.32684 -436.195523)
			(xy 157.312639 -436.215106) (xy 157.293089 -436.229355) (xy 157.270098 -436.236878) (xy 157.258004 -436.23738)
			(xy 156.318204 -436.23738) (xy 156.306093 -436.23698) (xy 156.283063 -436.229479) (xy 156.263488 -436.215214)
			(xy 156.249294 -436.195588) (xy 156.241876 -436.17253) (xy 156.241496 -436.160418) (xy 156.241496 -435.550056)
			(xy 156.23983 -435.535062) (xy 156.23805 -435.504944) (xy 156.23794 -435.489858) (xy 153.33472 -435.489858)
			(xy 153.33472 -436.160418) (xy 153.334307 -436.172513) (xy 153.326841 -436.195521) (xy 153.312642 -436.215104)
			(xy 153.293094 -436.229352) (xy 153.270105 -436.236877) (xy 153.258012 -436.23738) (xy 152.318212 -436.23738)
			(xy 152.306102 -436.236973) (xy 152.283072 -436.229474) (xy 152.263497 -436.215211) (xy 152.249302 -436.195586)
			(xy 152.241885 -436.17253) (xy 152.241504 -436.160418) (xy 152.241504 -435.550056) (xy 152.239838 -435.535062)
			(xy 152.238058 -435.504944) (xy 152.237948 -435.489858) (xy 149.334728 -435.489858) (xy 149.334728 -436.160418)
			(xy 149.334308 -436.172512) (xy 149.326842 -436.195518) (xy 149.312645 -436.215101) (xy 149.293099 -436.22935)
			(xy 149.270112 -436.236876) (xy 149.25802 -436.23738) (xy 148.31822 -436.23738) (xy 148.30611 -436.236966)
			(xy 148.28308 -436.22947) (xy 148.263505 -436.215208) (xy 148.249311 -436.195585) (xy 148.241893 -436.172529)
			(xy 148.241512 -436.160418) (xy 148.241512 -435.550056) (xy 148.239846 -435.535062) (xy 148.238066 -435.504944)
			(xy 148.237956 -435.489858) (xy 145.334736 -435.489858) (xy 145.334736 -436.160418) (xy 145.334308 -436.172511)
			(xy 145.326843 -436.195516) (xy 145.312647 -436.215098) (xy 145.293104 -436.229347) (xy 145.27012 -436.236874)
			(xy 145.258028 -436.23738) (xy 144.318228 -436.23738) (xy 144.306119 -436.236959) (xy 144.283089 -436.229465)
			(xy 144.263514 -436.215206) (xy 144.249319 -436.195583) (xy 144.241901 -436.172529) (xy 144.24152 -436.160418)
			(xy 144.24152 -435.550056) (xy 144.239854 -435.535062) (xy 144.238074 -435.504944) (xy 144.237964 -435.489858)
			(xy 140.335 -435.489858) (xy 140.335 -436.160418) (xy 140.334504 -436.17253) (xy 140.327017 -436.195567)
			(xy 140.31278 -436.215165) (xy 140.293185 -436.229408) (xy 140.27015 -436.236901) (xy 140.258038 -436.23738)
			(xy 139.318238 -436.23738) (xy 139.306119 -436.236908) (xy 139.283064 -436.229428) (xy 139.26345 -436.21519)
			(xy 139.249197 -436.195586) (xy 139.241701 -436.172537) (xy 139.241276 -436.160418) (xy 139.241276 -435.548024)
			(xy 139.239728 -435.533532) (xy 139.238078 -435.504432) (xy 139.237974 -435.489858) (xy 136.335008 -435.489858)
			(xy 136.335008 -436.160418) (xy 136.334505 -436.172529) (xy 136.327018 -436.195565) (xy 136.312782 -436.215163)
			(xy 136.29319 -436.229405) (xy 136.270157 -436.2369) (xy 136.258046 -436.23738) (xy 135.318246 -436.23738)
			(xy 135.306127 -436.236901) (xy 135.283073 -436.229424) (xy 135.263459 -436.215187) (xy 135.249205 -436.195584)
			(xy 135.241709 -436.172536) (xy 135.241284 -436.160418) (xy 135.241284 -435.548024) (xy 135.239736 -435.533532)
			(xy 135.238086 -435.504432) (xy 135.237982 -435.489858) (xy 132.335016 -435.489858) (xy 132.335016 -436.160418)
			(xy 132.334654 -436.172546) (xy 132.327152 -436.195613) (xy 132.312886 -436.215232) (xy 132.293256 -436.229481)
			(xy 132.270183 -436.236965) (xy 132.258054 -436.23738) (xy 131.318254 -436.23738) (xy 131.306139 -436.236928)
			(xy 131.283097 -436.22943) (xy 131.263498 -436.215182) (xy 131.249257 -436.195578) (xy 131.241768 -436.172533)
			(xy 131.241292 -436.160418) (xy 131.241292 -435.548024) (xy 131.239744 -435.533532) (xy 131.238094 -435.504432)
			(xy 131.23799 -435.489858) (xy 128.335024 -435.489858) (xy 128.335024 -436.160418) (xy 128.334655 -436.172545)
			(xy 128.327153 -436.195611) (xy 128.312889 -436.215229) (xy 128.293261 -436.229478) (xy 128.27019 -436.236963)
			(xy 128.258062 -436.23738) (xy 127.318262 -436.23738) (xy 127.306147 -436.236921) (xy 127.283106 -436.229425)
			(xy 127.263506 -436.21518) (xy 127.249265 -436.195576) (xy 127.241776 -436.172533) (xy 127.2413 -436.160418)
			(xy 127.2413 -435.548024) (xy 127.239751 -435.533532) (xy 127.238102 -435.504432) (xy 127.237998 -435.489858)
			(xy 115.623848 -435.489858) (xy 115.623848 -438.089802) (xy 125.238002 -438.089802) (xy 125.238095 -438.075228)
			(xy 125.239748 -438.046127) (xy 125.241304 -438.031636) (xy 125.241304 -436.948072) (xy 125.239759 -436.93358)
			(xy 125.238107 -436.90448) (xy 125.238002 -436.889906) (xy 125.238095 -436.875332) (xy 125.239748 -436.846231)
			(xy 125.241304 -436.83174) (xy 125.241304 -436.219092) (xy 125.241709 -436.206982) (xy 125.249212 -436.183954)
			(xy 125.263476 -436.164381) (xy 125.2831 -436.150186) (xy 125.306155 -436.142767) (xy 125.318266 -436.142384)
			(xy 126.258066 -436.142384) (xy 126.270158 -436.142837) (xy 126.293165 -436.15029) (xy 126.312749 -436.164478)
			(xy 126.327 -436.184018) (xy 126.334525 -436.207001) (xy 126.335028 -436.219092) (xy 126.335028 -438.760616)
			(xy 126.334598 -438.772723) (xy 126.327097 -438.795746) (xy 126.312838 -438.815316) (xy 126.293222 -438.829511)
			(xy 126.270174 -438.836937) (xy 126.258066 -438.837324) (xy 125.318266 -438.837324) (xy 125.306171 -438.836921)
			(xy 125.283163 -438.829451) (xy 125.263581 -438.815249) (xy 125.249333 -438.7957) (xy 125.241808 -438.77271)
			(xy 125.241304 -438.760616) (xy 125.241304 -438.147968) (xy 125.239759 -438.133476) (xy 125.238107 -438.104376)
			(xy 125.238002 -438.089802) (xy 115.623848 -438.089802) (xy 115.623848 -439.0898) (xy 127.237998 -439.0898)
			(xy 127.23809 -439.075226) (xy 127.239744 -439.046125) (xy 127.2413 -439.031634) (xy 127.2413 -437.94807)
			(xy 127.239755 -437.933578) (xy 127.238103 -437.904478) (xy 127.237998 -437.889904) (xy 127.238091 -437.87533)
			(xy 127.239744 -437.846229) (xy 127.2413 -437.831738) (xy 127.2413 -437.21909) (xy 127.241803 -437.206979)
			(xy 127.249288 -437.183942) (xy 127.263524 -437.164343) (xy 127.283117 -437.150101) (xy 127.306151 -437.142607)
			(xy 127.318262 -437.142128) (xy 128.258062 -437.142128) (xy 128.270182 -437.142592) (xy 128.293238 -437.150073)
			(xy 128.312853 -437.164313) (xy 128.327105 -437.183919) (xy 128.3346 -437.20697) (xy 128.335024 -437.21909)
			(xy 128.335024 -438.089802) (xy 129.237994 -438.089802) (xy 129.238087 -438.075228) (xy 129.23974 -438.046127)
			(xy 129.241296 -438.031636) (xy 129.241296 -436.948072) (xy 129.239752 -436.93358) (xy 129.238099 -436.90448)
			(xy 129.237994 -436.889906) (xy 129.238087 -436.875332) (xy 129.23974 -436.846231) (xy 129.241296 -436.83174)
			(xy 129.241296 -436.219092) (xy 129.241709 -436.206983) (xy 129.24921 -436.183956) (xy 129.263473 -436.164384)
			(xy 129.283095 -436.150189) (xy 129.306148 -436.142768) (xy 129.318258 -436.142384) (xy 130.258058 -436.142384)
			(xy 130.27015 -436.142844) (xy 130.293156 -436.150294) (xy 130.312741 -436.164481) (xy 130.326991 -436.184019)
			(xy 130.334516 -436.207002) (xy 130.33502 -436.219092) (xy 130.33502 -438.760616) (xy 130.334598 -438.772724)
			(xy 130.327096 -438.795748) (xy 130.312836 -438.815319) (xy 130.293217 -438.829514) (xy 130.270167 -438.836938)
			(xy 130.258058 -438.837324) (xy 129.318258 -438.837324) (xy 129.306163 -438.836928) (xy 129.283155 -438.829455)
			(xy 129.263572 -438.815252) (xy 129.249324 -438.795701) (xy 129.2418 -438.77271) (xy 129.241296 -438.760616)
			(xy 129.241296 -438.147968) (xy 129.239751 -438.133476) (xy 129.238099 -438.104376) (xy 129.237994 -438.089802)
			(xy 128.335024 -438.089802) (xy 128.335024 -439.0898) (xy 131.23799 -439.0898) (xy 131.238082 -439.075226)
			(xy 131.239736 -439.046125) (xy 131.241292 -439.031634) (xy 131.241292 -437.94807) (xy 131.239748 -437.933578)
			(xy 131.238095 -437.904478) (xy 131.23799 -437.889904) (xy 131.238083 -437.87533) (xy 131.239736 -437.846229)
			(xy 131.241292 -437.831738) (xy 131.241292 -437.21909) (xy 131.241803 -437.20698) (xy 131.249287 -437.183944)
			(xy 131.263521 -437.164346) (xy 131.283112 -437.150104) (xy 131.306144 -437.142608) (xy 131.318254 -437.142128)
			(xy 132.258054 -437.142128) (xy 132.270173 -437.142599) (xy 132.293229 -437.150077) (xy 132.312844 -437.164316)
			(xy 132.327097 -437.183921) (xy 132.334592 -437.206971) (xy 132.335016 -437.21909) (xy 132.335016 -438.089802)
			(xy 133.237986 -438.089802) (xy 133.238079 -438.075228) (xy 133.239732 -438.046127) (xy 133.241288 -438.031636)
			(xy 133.241288 -436.948072) (xy 133.239744 -436.93358) (xy 133.238091 -436.90448) (xy 133.237986 -436.889906)
			(xy 133.238079 -436.875332) (xy 133.239732 -436.846231) (xy 133.241288 -436.83174) (xy 133.241288 -436.219092)
			(xy 133.241709 -436.206984) (xy 133.249209 -436.183958) (xy 133.26347 -436.164386) (xy 133.28309 -436.150192)
			(xy 133.306141 -436.142769) (xy 133.31825 -436.142384) (xy 134.25805 -436.142384) (xy 134.270141 -436.142851)
			(xy 134.293148 -436.150299) (xy 134.312732 -436.164484) (xy 134.326983 -436.184021) (xy 134.334508 -436.207002)
			(xy 134.335012 -436.219092) (xy 134.335012 -438.760616) (xy 134.334598 -438.772725) (xy 134.327095 -438.79575)
			(xy 134.312833 -438.815322) (xy 134.293212 -438.829517) (xy 134.27016 -438.836939) (xy 134.25805 -438.837324)
			(xy 133.31825 -438.837324) (xy 133.306159 -438.836849) (xy 133.283154 -438.829402) (xy 133.26357 -438.815219)
			(xy 133.249319 -438.795684) (xy 133.241793 -438.772705) (xy 133.241288 -438.760616) (xy 133.241288 -438.147968)
			(xy 133.239743 -438.133476) (xy 133.238091 -438.104376) (xy 133.237986 -438.089802) (xy 132.335016 -438.089802)
			(xy 132.335016 -439.0898) (xy 135.237982 -439.0898) (xy 135.238075 -439.075226) (xy 135.239728 -439.046125)
			(xy 135.241284 -439.031634) (xy 135.241284 -437.94807) (xy 135.23974 -437.933578) (xy 135.238087 -437.904478)
			(xy 135.237982 -437.889904) (xy 135.238075 -437.87533) (xy 135.239728 -437.846229) (xy 135.241284 -437.831738)
			(xy 135.241284 -437.21909) (xy 135.241652 -437.206962) (xy 135.249153 -437.183895) (xy 135.263416 -437.164276)
			(xy 135.283045 -437.150027) (xy 135.306118 -437.142544) (xy 135.318246 -437.142128) (xy 136.258046 -437.142128)
			(xy 136.270162 -437.142572) (xy 136.293205 -437.150071) (xy 136.312805 -437.164321) (xy 136.327045 -437.183927)
			(xy 136.334533 -437.206974) (xy 136.335008 -437.21909) (xy 136.335008 -438.089802) (xy 137.237978 -438.089802)
			(xy 137.238071 -438.075228) (xy 137.239724 -438.046127) (xy 137.24128 -438.031636) (xy 137.24128 -436.948072)
			(xy 137.239736 -436.93358) (xy 137.238083 -436.90448) (xy 137.237978 -436.889906) (xy 137.238071 -436.875332)
			(xy 137.239724 -436.846231) (xy 137.24128 -436.83174) (xy 137.24128 -436.219092) (xy 137.241709 -436.206985)
			(xy 137.249208 -436.183961) (xy 137.263467 -436.164389) (xy 137.283085 -436.150194) (xy 137.306133 -436.14277)
			(xy 137.318242 -436.142384) (xy 138.258042 -436.142384) (xy 138.270138 -436.142772) (xy 138.293148 -436.150246)
			(xy 138.312731 -436.164451) (xy 138.326978 -436.184004) (xy 138.334501 -436.206997) (xy 138.335004 -436.219092)
			(xy 138.335004 -438.760616) (xy 138.334597 -438.772725) (xy 138.327094 -438.795752) (xy 138.31283 -438.815325)
			(xy 138.293207 -438.829519) (xy 138.270153 -438.83694) (xy 138.258042 -438.837324) (xy 137.318242 -438.837324)
			(xy 137.306151 -438.836856) (xy 137.283146 -438.829407) (xy 137.263562 -438.815222) (xy 137.249311 -438.795686)
			(xy 137.241785 -438.772705) (xy 137.24128 -438.760616) (xy 137.24128 -438.147968) (xy 137.239735 -438.133476)
			(xy 137.238083 -438.104376) (xy 137.237978 -438.089802) (xy 136.335008 -438.089802) (xy 136.335008 -439.0898)
			(xy 139.237974 -439.0898) (xy 139.238067 -439.075226) (xy 139.23972 -439.046125) (xy 139.241276 -439.031634)
			(xy 139.241276 -437.94807) (xy 139.239732 -437.933578) (xy 139.238079 -437.904478) (xy 139.237974 -437.889904)
			(xy 139.238067 -437.87533) (xy 139.23972 -437.846229) (xy 139.241276 -437.831738) (xy 139.241276 -437.21909)
			(xy 139.241652 -437.206963) (xy 139.249152 -437.183897) (xy 139.263413 -437.164279) (xy 139.28304 -437.15003)
			(xy 139.306111 -437.142545) (xy 139.318238 -437.142128) (xy 140.258038 -437.142128) (xy 140.270154 -437.142579)
			(xy 140.293196 -437.150076) (xy 140.312797 -437.164323) (xy 140.327037 -437.183929) (xy 140.334525 -437.206974)
			(xy 140.335 -437.21909) (xy 140.335 -438.089802) (xy 142.237968 -438.089802) (xy 142.238085 -438.074717)
			(xy 142.239861 -438.044598) (xy 142.241524 -438.029604) (xy 142.241524 -436.950104) (xy 142.239854 -436.935111)
			(xy 142.238076 -436.904992) (xy 142.237968 -436.889906) (xy 142.238076 -436.87482) (xy 142.239858 -436.844702)
			(xy 142.241524 -436.829708) (xy 142.241524 -436.219092) (xy 142.241906 -436.207006) (xy 142.24938 -436.184017)
			(xy 142.263593 -436.164464) (xy 142.283153 -436.150262) (xy 142.306145 -436.1428) (xy 142.318232 -436.142384)
			(xy 143.258032 -436.142384) (xy 143.270107 -436.142837) (xy 143.293074 -436.150307) (xy 143.31261 -436.164507)
			(xy 143.326804 -436.184047) (xy 143.334267 -436.207016) (xy 143.33474 -436.219092) (xy 143.33474 -438.760616)
			(xy 143.33425 -438.772688) (xy 143.326787 -438.79565) (xy 143.312596 -438.815184) (xy 143.293065 -438.829379)
			(xy 143.270104 -438.836847) (xy 143.258032 -438.837324) (xy 142.318232 -438.837324) (xy 142.306153 -438.83686)
			(xy 142.283174 -438.829403) (xy 142.263624 -438.81521) (xy 142.249418 -438.795669) (xy 142.241947 -438.772695)
			(xy 142.241524 -438.760616) (xy 142.241524 -438.15) (xy 142.239853 -438.135007) (xy 142.238076 -438.104888)
			(xy 142.237968 -438.089802) (xy 140.335 -438.089802) (xy 140.335 -439.0898) (xy 144.237964 -439.0898)
			(xy 144.23808 -439.074715) (xy 144.239857 -439.044596) (xy 144.24152 -439.029602) (xy 144.24152 -437.950102)
			(xy 144.239849 -437.935109) (xy 144.238072 -437.90499) (xy 144.237964 -437.889904) (xy 144.238081 -437.874819)
			(xy 144.239857 -437.8447) (xy 144.24152 -437.829706) (xy 144.24152 -437.21909) (xy 144.241999 -437.207002)
			(xy 144.249456 -437.184004) (xy 144.26364 -437.164426) (xy 144.28317 -437.150176) (xy 144.306142 -437.14264)
			(xy 144.318228 -437.142128) (xy 145.258028 -437.142128) (xy 145.270141 -437.142493) (xy 145.293174 -437.150003)
			(xy 145.312749 -437.164277) (xy 145.326942 -437.183911) (xy 145.334357 -437.206975) (xy 145.334736 -437.21909)
			(xy 145.334736 -438.089802) (xy 146.23796 -438.089802) (xy 146.238077 -438.074717) (xy 146.239853 -438.044598)
			(xy 146.241516 -438.029604) (xy 146.241516 -436.950104) (xy 146.239846 -436.935111) (xy 146.238068 -436.904992)
			(xy 146.23796 -436.889906) (xy 146.238068 -436.87482) (xy 146.23985 -436.844702) (xy 146.241516 -436.829708)
			(xy 146.241516 -436.219092) (xy 146.241906 -436.207006) (xy 146.249379 -436.184019) (xy 146.26359 -436.164467)
			(xy 146.283148 -436.150264) (xy 146.306138 -436.142801) (xy 146.318224 -436.142384) (xy 147.258024 -436.142384)
			(xy 147.270099 -436.142844) (xy 147.293066 -436.150312) (xy 147.312601 -436.16451) (xy 147.326795 -436.184049)
			(xy 147.334259 -436.207017) (xy 147.334732 -436.219092) (xy 147.334732 -438.760616) (xy 147.33425 -438.772689)
			(xy 147.326786 -438.795653) (xy 147.312593 -438.815187) (xy 147.29306 -438.829382) (xy 147.270097 -438.836848)
			(xy 147.258024 -438.837324) (xy 146.318224 -438.837324) (xy 146.306144 -438.836867) (xy 146.283165 -438.829408)
			(xy 146.263616 -438.815213) (xy 146.24941 -438.795671) (xy 146.241939 -438.772696) (xy 146.241516 -438.760616)
			(xy 146.241516 -438.15) (xy 146.239845 -438.135007) (xy 146.238068 -438.104888) (xy 146.23796 -438.089802)
			(xy 145.334736 -438.089802) (xy 145.334736 -439.0898) (xy 148.237956 -439.0898) (xy 148.238073 -439.074715)
			(xy 148.239849 -439.044596) (xy 148.241512 -439.029602) (xy 148.241512 -437.950102) (xy 148.239841 -437.935109)
			(xy 148.238064 -437.90499) (xy 148.237956 -437.889904) (xy 148.238073 -437.874819) (xy 148.239849 -437.8447)
			(xy 148.241512 -437.829706) (xy 148.241512 -437.21909) (xy 148.241999 -437.207003) (xy 148.249455 -437.184007)
			(xy 148.263637 -437.164429) (xy 148.283165 -437.150178) (xy 148.306134 -437.142641) (xy 148.31822 -437.142128)
			(xy 149.25802 -437.142128) (xy 149.270133 -437.1425) (xy 149.293165 -437.150008) (xy 149.312741 -437.16428)
			(xy 149.326934 -437.183913) (xy 149.334349 -437.206976) (xy 149.334728 -437.21909) (xy 149.334728 -438.089802)
			(xy 150.237952 -438.089802) (xy 150.238069 -438.074717) (xy 150.239845 -438.044598) (xy 150.241508 -438.029604)
			(xy 150.241508 -436.950104) (xy 150.239838 -436.935111) (xy 150.23806 -436.904992) (xy 150.237952 -436.889906)
			(xy 150.23806 -436.87482) (xy 150.239842 -436.844702) (xy 150.241508 -436.829708) (xy 150.241508 -436.219092)
			(xy 150.241906 -436.207007) (xy 150.249378 -436.184021) (xy 150.263587 -436.16447) (xy 150.283143 -436.150267)
			(xy 150.306131 -436.142802) (xy 150.318216 -436.142384) (xy 151.258016 -436.142384) (xy 151.270091 -436.142851)
			(xy 151.293057 -436.150317) (xy 151.312593 -436.164513) (xy 151.326787 -436.18405) (xy 151.334251 -436.207017)
			(xy 151.334724 -436.219092) (xy 151.334724 -438.760616) (xy 151.33425 -438.77269) (xy 151.326785 -438.795655)
			(xy 151.31259 -438.81519) (xy 151.293055 -438.829385) (xy 151.27009 -438.83685) (xy 151.258016 -438.837324)
			(xy 150.318216 -438.837324) (xy 150.306144 -438.836822) (xy 150.28318 -438.829366) (xy 150.263644 -438.815179)
			(xy 150.249448 -438.795649) (xy 150.241983 -438.772688) (xy 150.241508 -438.760616) (xy 150.241508 -438.15)
			(xy 150.239837 -438.135007) (xy 150.23806 -438.104888) (xy 150.237952 -438.089802) (xy 149.334728 -438.089802)
			(xy 149.334728 -439.0898) (xy 152.237948 -439.0898) (xy 152.238065 -439.074715) (xy 152.239841 -439.044596)
			(xy 152.241504 -439.029602) (xy 152.241504 -437.950102) (xy 152.239833 -437.935109) (xy 152.238056 -437.90499)
			(xy 152.237948 -437.889904) (xy 152.238065 -437.874819) (xy 152.239841 -437.8447) (xy 152.241504 -437.829706)
			(xy 152.241504 -437.21909) (xy 152.241998 -437.207004) (xy 152.249453 -437.184009) (xy 152.263634 -437.164432)
			(xy 152.28316 -437.150181) (xy 152.306127 -437.142643) (xy 152.318212 -437.142128) (xy 153.258012 -437.142128)
			(xy 153.270124 -437.142506) (xy 153.293157 -437.150012) (xy 153.312732 -437.164283) (xy 153.326925 -437.183914)
			(xy 153.334341 -437.206976) (xy 153.33472 -437.21909) (xy 153.33472 -438.089802) (xy 154.237944 -438.089802)
			(xy 154.238061 -438.074717) (xy 154.239837 -438.044598) (xy 154.2415 -438.029604) (xy 154.2415 -436.950104)
			(xy 154.23983 -436.935111) (xy 154.238052 -436.904992) (xy 154.237944 -436.889906) (xy 154.238052 -436.87482)
			(xy 154.239834 -436.844702) (xy 154.2415 -436.829708) (xy 154.2415 -436.219092) (xy 154.241958 -436.207016)
			(xy 154.249423 -436.184047) (xy 154.263621 -436.16451) (xy 154.283162 -436.150316) (xy 154.306132 -436.142855)
			(xy 154.318208 -436.142384) (xy 155.258008 -436.142384) (xy 155.270082 -436.142857) (xy 155.293048 -436.150321)
			(xy 155.312584 -436.164516) (xy 155.326779 -436.184052) (xy 155.334243 -436.207018) (xy 155.334716 -436.219092)
			(xy 155.334716 -438.760616) (xy 155.334249 -438.772691) (xy 155.326783 -438.795657) (xy 155.312587 -438.815193)
			(xy 155.29305 -438.829387) (xy 155.270083 -438.836851) (xy 155.258008 -438.837324) (xy 154.318208 -438.837324)
			(xy 154.306135 -438.836829) (xy 154.283171 -438.829371) (xy 154.263635 -438.815182) (xy 154.24944 -438.79565)
			(xy 154.241975 -438.772688) (xy 154.2415 -438.760616) (xy 154.2415 -438.15) (xy 154.239829 -438.135007)
			(xy 154.238052 -438.104888) (xy 154.237944 -438.089802) (xy 153.33472 -438.089802) (xy 153.33472 -439.0898)
			(xy 156.23794 -439.0898) (xy 156.238057 -439.074715) (xy 156.239833 -439.044596) (xy 156.241496 -439.029602)
			(xy 156.241496 -437.950102) (xy 156.239825 -437.935109) (xy 156.238048 -437.90499) (xy 156.23794 -437.889904)
			(xy 156.238057 -437.874819) (xy 156.239833 -437.8447) (xy 156.241496 -437.829706) (xy 156.241496 -437.21909)
			(xy 156.241998 -437.207004) (xy 156.249452 -437.184011) (xy 156.263631 -437.164435) (xy 156.283155 -437.150183)
			(xy 156.30612 -437.142644) (xy 156.318204 -437.142128) (xy 157.258004 -437.142128) (xy 157.270116 -437.142513)
			(xy 157.293148 -437.150017) (xy 157.312724 -437.164286) (xy 157.326917 -437.183916) (xy 157.334333 -437.206977)
			(xy 157.334712 -437.21909) (xy 157.334712 -439.760614) (xy 157.334304 -439.772709) (xy 157.326838 -439.795718)
			(xy 157.312637 -439.815302) (xy 157.293089 -439.829551) (xy 157.270098 -439.837074) (xy 157.258004 -439.837576)
			(xy 156.318204 -439.837576) (xy 156.306093 -439.83718) (xy 156.283062 -439.829679) (xy 156.263486 -439.815413)
			(xy 156.249292 -439.795785) (xy 156.241876 -439.772727) (xy 156.241496 -439.760614) (xy 156.241496 -439.149998)
			(xy 156.239825 -439.135005) (xy 156.238048 -439.104886) (xy 156.23794 -439.0898) (xy 153.33472 -439.0898)
			(xy 153.33472 -439.760614) (xy 153.334304 -439.772708) (xy 153.326839 -439.795716) (xy 153.31264 -439.815299)
			(xy 153.293094 -439.829548) (xy 153.270105 -439.837073) (xy 153.258012 -439.837576) (xy 152.318212 -439.837576)
			(xy 152.306101 -439.837173) (xy 152.28307 -439.829674) (xy 152.263495 -439.81541) (xy 152.249301 -439.795784)
			(xy 152.241884 -439.772726) (xy 152.241504 -439.760614) (xy 152.241504 -439.149998) (xy 152.239833 -439.135005)
			(xy 152.238056 -439.104886) (xy 152.237948 -439.0898) (xy 149.334728 -439.0898) (xy 149.334728 -439.760614)
			(xy 149.334304 -439.772708) (xy 149.32684 -439.795714) (xy 149.312643 -439.815297) (xy 149.293099 -439.829546)
			(xy 149.270112 -439.837072) (xy 149.25802 -439.837576) (xy 148.31822 -439.837576) (xy 148.30611 -439.837166)
			(xy 148.283079 -439.829669) (xy 148.263504 -439.815407) (xy 148.249309 -439.795782) (xy 148.241892 -439.772726)
			(xy 148.241512 -439.760614) (xy 148.241512 -439.149998) (xy 148.239841 -439.135005) (xy 148.238064 -439.104886)
			(xy 148.237956 -439.0898) (xy 145.334736 -439.0898) (xy 145.334736 -439.760614) (xy 145.334304 -439.772707)
			(xy 145.326841 -439.795712) (xy 145.312646 -439.815294) (xy 145.293104 -439.829543) (xy 145.270119 -439.83707)
			(xy 145.258028 -439.837576) (xy 144.318228 -439.837576) (xy 144.306118 -439.837159) (xy 144.283088 -439.829665)
			(xy 144.263512 -439.815404) (xy 144.249317 -439.795781) (xy 144.2419 -439.772725) (xy 144.24152 -439.760614)
			(xy 144.24152 -439.149998) (xy 144.239849 -439.135005) (xy 144.238072 -439.104886) (xy 144.237964 -439.0898)
			(xy 140.335 -439.0898) (xy 140.335 -439.760614) (xy 140.334501 -439.772726) (xy 140.327015 -439.795763)
			(xy 140.312778 -439.815361) (xy 140.293184 -439.829604) (xy 140.270149 -439.837097) (xy 140.258038 -439.837576)
			(xy 139.318238 -439.837576) (xy 139.306119 -439.837108) (xy 139.283063 -439.829628) (xy 139.263449 -439.815388)
			(xy 139.249196 -439.795783) (xy 139.2417 -439.772733) (xy 139.241276 -439.760614) (xy 139.241276 -439.147966)
			(xy 139.239731 -439.133474) (xy 139.238079 -439.104374) (xy 139.237974 -439.0898) (xy 136.335008 -439.0898)
			(xy 136.335008 -439.760614) (xy 136.334501 -439.772725) (xy 136.327016 -439.795761) (xy 136.312781 -439.815358)
			(xy 136.293189 -439.829601) (xy 136.270157 -439.837096) (xy 136.258046 -439.837576) (xy 135.318246 -439.837576)
			(xy 135.306127 -439.837101) (xy 135.283072 -439.829623) (xy 135.263457 -439.815385) (xy 135.249204 -439.795782)
			(xy 135.241708 -439.772733) (xy 135.241284 -439.760614) (xy 135.241284 -439.147966) (xy 135.239739 -439.133474)
			(xy 135.238087 -439.104374) (xy 135.237982 -439.0898) (xy 132.335016 -439.0898) (xy 132.335016 -439.760614)
			(xy 132.334651 -439.772742) (xy 132.327149 -439.795809) (xy 132.312885 -439.815428) (xy 132.293255 -439.829677)
			(xy 132.270182 -439.83716) (xy 132.258054 -439.837576) (xy 131.318254 -439.837576) (xy 131.306138 -439.837128)
			(xy 131.283096 -439.82963) (xy 131.263496 -439.815381) (xy 131.249256 -439.795775) (xy 131.241767 -439.77273)
			(xy 131.241292 -439.760614) (xy 131.241292 -439.147966) (xy 131.239747 -439.133474) (xy 131.238095 -439.104374)
			(xy 131.23799 -439.0898) (xy 128.335024 -439.0898) (xy 128.335024 -439.760614) (xy 128.334651 -439.772741)
			(xy 128.32715 -439.795807) (xy 128.312888 -439.815425) (xy 128.29326 -439.829674) (xy 128.27019 -439.837159)
			(xy 128.258062 -439.837576) (xy 127.318262 -439.837576) (xy 127.306147 -439.837121) (xy 127.283105 -439.829625)
			(xy 127.263505 -439.815378) (xy 127.249264 -439.795774) (xy 127.241775 -439.772729) (xy 127.2413 -439.760614)
			(xy 127.2413 -439.147966) (xy 127.239755 -439.133474) (xy 127.238103 -439.104374) (xy 127.237998 -439.0898)
			(xy 115.623848 -439.0898) (xy 115.623848 -440.465972) (xy 125.238256 -440.465972) (xy 125.244098 -440.42203)
			(xy 125.248827 -440.390461) (xy 125.26513 -440.328742) (xy 125.289 -440.269538) (xy 125.320066 -440.213771)
			(xy 125.357843 -440.162313) (xy 125.40174 -440.115967) (xy 125.451073 -440.075455) (xy 125.505072 -440.04141)
			(xy 125.562895 -440.014364) (xy 125.623639 -439.994738) (xy 125.686355 -439.982838) (xy 125.750066 -439.978851)
			(xy 125.813777 -439.982838) (xy 125.876493 -439.994738) (xy 125.937237 -440.014364) (xy 125.99506 -440.04141)
			(xy 126.049059 -440.075455) (xy 126.098392 -440.115967) (xy 126.142289 -440.162313) (xy 126.180066 -440.213771)
			(xy 126.211132 -440.269538) (xy 126.235002 -440.328742) (xy 126.251305 -440.390461) (xy 126.256034 -440.42203)
			(xy 126.261876 -440.465972) (xy 129.238248 -440.465972) (xy 129.24409 -440.42203) (xy 129.248819 -440.390461)
			(xy 129.265122 -440.328742) (xy 129.288992 -440.269538) (xy 129.320058 -440.213771) (xy 129.357835 -440.162313)
			(xy 129.401732 -440.115967) (xy 129.451065 -440.075455) (xy 129.505064 -440.04141) (xy 129.562887 -440.014364)
			(xy 129.623631 -439.994738) (xy 129.686347 -439.982838) (xy 129.750058 -439.978851) (xy 129.813769 -439.982838)
			(xy 129.876485 -439.994738) (xy 129.937229 -440.014364) (xy 129.995052 -440.04141) (xy 130.049051 -440.075455)
			(xy 130.098384 -440.115967) (xy 130.142281 -440.162313) (xy 130.180058 -440.213771) (xy 130.211124 -440.269538)
			(xy 130.234994 -440.328742) (xy 130.251297 -440.390461) (xy 130.256026 -440.42203) (xy 130.261868 -440.465972)
			(xy 133.23824 -440.465972) (xy 133.244082 -440.42203) (xy 133.248811 -440.390461) (xy 133.265114 -440.328742)
			(xy 133.288984 -440.269538) (xy 133.32005 -440.213771) (xy 133.357827 -440.162313) (xy 133.401724 -440.115967)
			(xy 133.451057 -440.075455) (xy 133.505056 -440.04141) (xy 133.562879 -440.014364) (xy 133.623623 -439.994738)
			(xy 133.686339 -439.982838) (xy 133.75005 -439.978851) (xy 133.813761 -439.982838) (xy 133.876477 -439.994738)
			(xy 133.937221 -440.014364) (xy 133.995044 -440.04141) (xy 134.049043 -440.075455) (xy 134.098376 -440.115967)
			(xy 134.142273 -440.162313) (xy 134.18005 -440.213771) (xy 134.211116 -440.269538) (xy 134.234986 -440.328742)
			(xy 134.251289 -440.390461) (xy 134.256018 -440.42203) (xy 134.26186 -440.465972) (xy 137.238232 -440.465972)
			(xy 137.244074 -440.42203) (xy 137.248803 -440.390461) (xy 137.265106 -440.328742) (xy 137.288976 -440.269538)
			(xy 137.320042 -440.213771) (xy 137.357819 -440.162313) (xy 137.401716 -440.115967) (xy 137.451049 -440.075455)
			(xy 137.505048 -440.04141) (xy 137.562871 -440.014364) (xy 137.623615 -439.994738) (xy 137.686331 -439.982838)
			(xy 137.750042 -439.978851) (xy 137.813753 -439.982838) (xy 137.876469 -439.994738) (xy 137.937213 -440.014364)
			(xy 137.995036 -440.04141) (xy 138.049035 -440.075455) (xy 138.098368 -440.115967) (xy 138.142265 -440.162313)
			(xy 138.180042 -440.213771) (xy 138.211108 -440.269538) (xy 138.234978 -440.328742) (xy 138.251281 -440.390461)
			(xy 138.25601 -440.42203) (xy 138.261852 -440.465972) (xy 142.238222 -440.465972) (xy 142.244064 -440.42203)
			(xy 142.248793 -440.390461) (xy 142.265096 -440.328742) (xy 142.288966 -440.269538) (xy 142.320032 -440.213771)
			(xy 142.357809 -440.162313) (xy 142.401706 -440.115967) (xy 142.451039 -440.075455) (xy 142.505038 -440.04141)
			(xy 142.562861 -440.014364) (xy 142.623605 -439.994738) (xy 142.686321 -439.982838) (xy 142.750032 -439.978851)
			(xy 142.813743 -439.982838) (xy 142.876459 -439.994738) (xy 142.937203 -440.014364) (xy 142.995026 -440.04141)
			(xy 143.049025 -440.075455) (xy 143.098358 -440.115967) (xy 143.142255 -440.162313) (xy 143.180032 -440.213771)
			(xy 143.211098 -440.269538) (xy 143.234968 -440.328742) (xy 143.251271 -440.390461) (xy 143.256 -440.42203)
			(xy 143.261842 -440.465972) (xy 146.238214 -440.465972) (xy 146.244056 -440.42203) (xy 146.248785 -440.390461)
			(xy 146.265088 -440.328742) (xy 146.288958 -440.269538) (xy 146.320024 -440.213771) (xy 146.357801 -440.162313)
			(xy 146.401698 -440.115967) (xy 146.451031 -440.075455) (xy 146.50503 -440.04141) (xy 146.562853 -440.014364)
			(xy 146.623597 -439.994738) (xy 146.686313 -439.982838) (xy 146.750024 -439.978851) (xy 146.813735 -439.982838)
			(xy 146.876451 -439.994738) (xy 146.937195 -440.014364) (xy 146.995018 -440.04141) (xy 147.049017 -440.075455)
			(xy 147.09835 -440.115967) (xy 147.142247 -440.162313) (xy 147.180024 -440.213771) (xy 147.21109 -440.269538)
			(xy 147.23496 -440.328742) (xy 147.251263 -440.390461) (xy 147.255992 -440.42203) (xy 147.261834 -440.465972)
			(xy 150.238206 -440.465972) (xy 150.244048 -440.42203) (xy 150.248777 -440.390461) (xy 150.26508 -440.328742)
			(xy 150.28895 -440.269538) (xy 150.320016 -440.213771) (xy 150.357793 -440.162313) (xy 150.40169 -440.115967)
			(xy 150.451023 -440.075455) (xy 150.505022 -440.04141) (xy 150.562845 -440.014364) (xy 150.623589 -439.994738)
			(xy 150.686305 -439.982838) (xy 150.750016 -439.978851) (xy 150.813727 -439.982838) (xy 150.876443 -439.994738)
			(xy 150.937187 -440.014364) (xy 150.99501 -440.04141) (xy 151.049009 -440.075455) (xy 151.098342 -440.115967)
			(xy 151.142239 -440.162313) (xy 151.180016 -440.213771) (xy 151.211082 -440.269538) (xy 151.234952 -440.328742)
			(xy 151.251255 -440.390461) (xy 151.255984 -440.42203) (xy 151.261826 -440.465972) (xy 154.238198 -440.465972)
			(xy 154.24404 -440.42203) (xy 154.248769 -440.390461) (xy 154.265072 -440.328742) (xy 154.288942 -440.269538)
			(xy 154.320008 -440.213771) (xy 154.357785 -440.162313) (xy 154.401682 -440.115967) (xy 154.451015 -440.075455)
			(xy 154.505014 -440.04141) (xy 154.562837 -440.014364) (xy 154.623581 -439.994738) (xy 154.686297 -439.982838)
			(xy 154.750008 -439.978851) (xy 154.813719 -439.982838) (xy 154.876435 -439.994738) (xy 154.937179 -440.014364)
			(xy 154.995002 -440.04141) (xy 155.049001 -440.075455) (xy 155.098334 -440.115967) (xy 155.142231 -440.162313)
			(xy 155.180008 -440.213771) (xy 155.211074 -440.269538) (xy 155.234944 -440.328742) (xy 155.251247 -440.390461)
			(xy 155.255976 -440.42203) (xy 155.261818 -440.465972) (xy 166.734236 -440.465972) (xy 167.27424 -439.925968)
			(xy 167.27424 -416.88258) (xy 167.274723 -416.857628) (xy 167.282517 -416.808336) (xy 167.297925 -416.76087)
			(xy 167.320568 -416.716398) (xy 167.349889 -416.676016) (xy 167.367204 -416.658044) (xy 170.240452 -413.784796)
			(xy 170.258451 -413.767514) (xy 170.298835 -413.738208) (xy 170.343302 -413.71557) (xy 170.390758 -413.700156)
			(xy 170.44004 -413.692344) (xy 170.464988 -413.691832) (xy 180.29809 -413.691832) (xy 180.322247 -413.677438)
			(xy 180.37409 -413.655663) (xy 180.428728 -413.642375) (xy 180.48478 -413.637907) (xy 180.540832 -413.642375)
			(xy 180.59547 -413.655663) (xy 180.647313 -413.677438) (xy 180.67147 -413.691832) (xy 181.045358 -413.691832)
			(xy 181.066573 -413.673113) (xy 181.113492 -413.641501) (xy 181.164565 -413.617164) (xy 181.218672 -413.600637)
			(xy 181.274626 -413.592282) (xy 181.331202 -413.592282) (xy 181.387156 -413.600637) (xy 181.441263 -413.617164)
			(xy 181.492336 -413.641501) (xy 181.539255 -413.673113) (xy 181.56047 -413.691832) (xy 184.688988 -413.691832)
			(xy 184.688988 -408.491182) (xy 184.689446 -408.466228) (xy 184.697241 -408.416933) (xy 184.712652 -408.369464)
			(xy 184.735299 -408.324991) (xy 184.764625 -408.284609) (xy 184.781952 -408.266646) (xy 184.892188 -408.15641)
			(xy 184.892188 -407.290778) (xy 184.874469 -407.269822) (xy 184.844603 -407.223784) (xy 184.821645 -407.17394)
			(xy 184.806067 -407.12132) (xy 184.798191 -407.067011) (xy 184.7977 -407.039572) (xy 184.798716 -407.013918)
			(xy 184.80024 -406.99055) (xy 184.654952 -406.845262) (xy 184.637666 -406.827264) (xy 184.608353 -406.786882)
			(xy 184.585709 -406.742416) (xy 184.57029 -406.694959) (xy 184.562475 -406.645675) (xy 184.561988 -406.620726)
			(xy 184.561988 -400.685254) (xy 184.562481 -400.660307) (xy 184.570292 -400.611027) (xy 184.585716 -400.563576)
			(xy 184.608371 -400.519122) (xy 184.637702 -400.478758) (xy 184.672984 -400.443479) (xy 184.713351 -400.414154)
			(xy 184.757808 -400.391503) (xy 184.80526 -400.376084) (xy 184.854541 -400.368278) (xy 184.879488 -400.367754)
			(xy 188.73343 -400.367754) (xy 188.758607 -400.36826) (xy 188.808324 -400.376252) (xy 188.856159 -400.391982)
			(xy 188.900915 -400.415058) (xy 188.941474 -400.444902) (xy 188.95949 -400.462496) (xy 189.16142 -400.667474)
			(xy 189.178441 -400.685395) (xy 189.207278 -400.725532) (xy 189.229543 -400.769656) (xy 189.244696 -400.816698)
			(xy 189.252371 -400.865521) (xy 189.25286 -400.890232) (xy 189.25286 -403.517354) (xy 189.46876 -403.517354)
			(xy 189.493711 -403.51784) (xy 189.542999 -403.52564) (xy 189.590461 -403.541053) (xy 189.634927 -403.5637)
			(xy 189.675304 -403.593025) (xy 189.693296 -403.610318) (xy 189.904624 -403.821646) (xy 189.921911 -403.839643)
			(xy 189.951225 -403.880025) (xy 189.973869 -403.924491) (xy 189.989288 -403.971948) (xy 189.997103 -404.021232)
			(xy 189.997588 -404.046182) (xy 189.997588 -404.34641) (xy 190.325756 -404.674578) (xy 190.350394 -404.671276)
			(xy 190.363099 -404.669705) (xy 190.388647 -404.668052) (xy 190.401448 -404.667974) (xy 190.428697 -404.668463)
			(xy 190.482641 -404.676225) (xy 190.534931 -404.691584) (xy 190.584503 -404.714228) (xy 190.630349 -404.743695)
			(xy 190.671535 -404.779386) (xy 190.707223 -404.820575) (xy 190.736687 -404.866423) (xy 190.759326 -404.915997)
			(xy 190.774681 -404.968288) (xy 190.782439 -405.022232) (xy 190.782956 -405.049482) (xy 190.782886 -405.062283)
			(xy 190.781237 -405.087833) (xy 190.779654 -405.100536) (xy 190.776352 -405.125428) (xy 191.001904 -405.35098)
			(xy 196.838316 -405.35098) (xy 197.83298 -404.356316) (xy 197.83298 -400.893788) (xy 197.833437 -400.868834)
			(xy 197.841231 -400.819538) (xy 197.856641 -400.772069) (xy 197.879288 -400.727595) (xy 197.908613 -400.687211)
			(xy 197.925944 -400.669252) (xy 198.116952 -400.478244) (xy 198.13495 -400.460959) (xy 198.175333 -400.431649)
			(xy 198.219799 -400.409008) (xy 198.267256 -400.393591) (xy 198.316539 -400.385778) (xy 198.341488 -400.38528)
			(xy 201.995532 -400.38528) (xy 202.020486 -400.385739) (xy 202.06978 -400.393535) (xy 202.117247 -400.408948)
			(xy 202.161719 -400.431596) (xy 202.2021 -400.460922) (xy 202.220068 -400.478244) (xy 202.418696 -400.676872)
			(xy 202.435978 -400.694872) (xy 202.465282 -400.735256) (xy 202.487917 -400.779722) (xy 202.503329 -400.827179)
			(xy 202.511138 -400.87646) (xy 202.51166 -400.901408) (xy 202.51166 -404.330916) (xy 202.604624 -404.42388)
			(xy 202.621909 -404.441878) (xy 202.651218 -404.482261) (xy 202.673858 -404.526727) (xy 202.689272 -404.574184)
			(xy 202.697082 -404.623467) (xy 202.697588 -404.648416) (xy 202.697588 -407.475436) (xy 204.291692 -409.06954)
			(xy 206.414116 -409.06954) (xy 208.310988 -407.172668) (xy 208.310988 -404.642828) (xy 208.311475 -404.617878)
			(xy 208.319277 -404.568591) (xy 208.334693 -404.521132) (xy 208.357343 -404.476668) (xy 208.38667 -404.436295)
			(xy 208.403952 -404.418292) (xy 208.50098 -404.321264) (xy 208.50098 -400.893788) (xy 208.501437 -400.868834)
			(xy 208.509231 -400.819538) (xy 208.524641 -400.772069) (xy 208.547288 -400.727595) (xy 208.576613 -400.687211)
			(xy 208.593944 -400.669252) (xy 208.784952 -400.478244) (xy 208.80295 -400.460959) (xy 208.843333 -400.431649)
			(xy 208.887799 -400.409008) (xy 208.935256 -400.393591) (xy 208.984539 -400.385778) (xy 209.009488 -400.38528)
			(xy 212.668612 -400.38528) (xy 212.693566 -400.385737) (xy 212.742862 -400.393531) (xy 212.790331 -400.408941)
			(xy 212.834805 -400.431588) (xy 212.875189 -400.460913) (xy 212.893148 -400.478244) (xy 213.084156 -400.669252)
			(xy 213.101441 -400.68725) (xy 213.130751 -400.727633) (xy 213.153392 -400.772099) (xy 213.168809 -400.819556)
			(xy 213.176622 -400.868839) (xy 213.17712 -400.893788) (xy 213.17712 -404.353776) (xy 213.261956 -404.438612)
			(xy 213.279243 -404.456609) (xy 213.308558 -404.496991) (xy 213.331205 -404.541456) (xy 213.346628 -404.588914)
			(xy 213.354447 -404.638198) (xy 213.35492 -404.663148) (xy 213.35492 -407.394156) (xy 214.926164 -408.9654)
			(xy 217.141044 -408.9654) (xy 218.978988 -407.127456) (xy 218.978988 -404.673308) (xy 218.979477 -404.648358)
			(xy 218.987281 -404.599073) (xy 219.002699 -404.551616) (xy 219.025351 -404.507154) (xy 219.05468 -404.466784)
			(xy 219.071952 -404.448772) (xy 219.16136 -404.359364) (xy 219.16136 -400.906488) (xy 219.161842 -400.881536)
			(xy 219.169635 -400.832244) (xy 219.185043 -400.784777) (xy 219.207687 -400.740306) (xy 219.237009 -400.699924)
			(xy 219.254324 -400.681952) (xy 219.458032 -400.478244) (xy 219.47603 -400.460958) (xy 219.516412 -400.431645)
			(xy 219.560878 -400.409001) (xy 219.608335 -400.393582) (xy 219.657618 -400.385766) (xy 219.682568 -400.38528)
			(xy 223.323912 -400.38528) (xy 223.348866 -400.385737) (xy 223.398162 -400.393531) (xy 223.445631 -400.408941)
			(xy 223.490105 -400.431588) (xy 223.530489 -400.460913) (xy 223.548448 -400.478244) (xy 223.759776 -400.689572)
			(xy 223.777059 -400.707571) (xy 223.806365 -400.747955) (xy 223.829002 -400.792421) (xy 223.844414 -400.839878)
			(xy 223.852224 -400.88916) (xy 223.85274 -400.914108) (xy 223.85274 -404.348188) (xy 223.940624 -404.436072)
			(xy 223.957909 -404.45407) (xy 223.98722 -404.494452) (xy 224.009861 -404.538918) (xy 224.025276 -404.586376)
			(xy 224.033087 -404.635659) (xy 224.033588 -404.660608) (xy 224.033588 -407.272236) (xy 225.838512 -409.07716)
			(xy 227.803456 -409.07716) (xy 229.621588 -407.259028) (xy 229.621588 -404.678388) (xy 229.622045 -404.653434)
			(xy 229.629839 -404.604138) (xy 229.64525 -404.556669) (xy 229.667896 -404.512195) (xy 229.697222 -404.471812)
			(xy 229.714552 -404.453852) (xy 229.82682 -404.341584) (xy 229.82682 -400.901408) (xy 229.827308 -400.876458)
			(xy 229.835112 -400.827171) (xy 229.850527 -400.779712) (xy 229.873176 -400.735248) (xy 229.9025 -400.694873)
			(xy 229.919784 -400.676872) (xy 230.120952 -400.475704) (xy 230.138951 -400.458421) (xy 230.179335 -400.429115)
			(xy 230.223801 -400.406476) (xy 230.271258 -400.391062) (xy 230.32054 -400.38325) (xy 230.345488 -400.38274)
			(xy 233.996992 -400.38274) (xy 234.021942 -400.383229) (xy 234.071228 -400.391032) (xy 234.118687 -400.406448)
			(xy 234.16315 -400.429098) (xy 234.203524 -400.458423) (xy 234.221528 -400.475704) (xy 234.422696 -400.676872)
			(xy 234.439978 -400.694872) (xy 234.469282 -400.735256) (xy 234.491917 -400.779722) (xy 234.507329 -400.827179)
			(xy 234.515138 -400.87646) (xy 234.51566 -400.901408) (xy 234.51566 -404.346156) (xy 235.652564 -405.48306)
			(xy 237.746032 -405.48306) (xy 237.770984 -405.483544) (xy 237.820274 -405.49134) (xy 237.867738 -405.50675)
			(xy 237.912208 -405.529395) (xy 237.952587 -405.558718) (xy 237.970568 -405.576024) (xy 238.814356 -406.419812)
			(xy 238.968788 -406.419812) (xy 239.014 -406.3746) (xy 239.014 -397.839946) (xy 239.014737 -397.809321)
			(xy 239.026508 -397.749211) (xy 239.037368 -397.720566) (xy 239.093502 -397.582136) (xy 239.102129 -397.561823)
			(xy 239.124186 -397.523598) (xy 239.151321 -397.488794) (xy 239.166908 -397.47317) (xy 239.218978 -397.423132)
			(xy 239.692688 -396.949422) (xy 239.720266 -396.92256) (xy 239.780416 -396.874505) (xy 239.845566 -396.833485)
			(xy 239.914899 -396.800015) (xy 239.987543 -396.774516) (xy 240.062584 -396.75731) (xy 240.13908 -396.748611)
			(xy 240.177574 -396.748) (xy 274.117054 -396.748) (xy 274.147679 -396.748737) (xy 274.207789 -396.760508)
			(xy 274.236434 -396.771368) (xy 274.374864 -396.827502) (xy 274.395177 -396.836129) (xy 274.433402 -396.858186)
			(xy 274.468206 -396.885321) (xy 274.48383 -396.900908) (xy 274.533868 -396.952978) (xy 274.753578 -397.172688)
			(xy 274.777454 -397.19758) (xy 274.78702 -397.207439) (xy 274.810234 -397.222108) (xy 274.836516 -397.230063)
			(xy 274.863968 -397.23073) (xy 274.890605 -397.22406) (xy 274.914503 -397.210536) (xy 274.92452 -397.201136)
			(xy 275.284692 -396.840964) (xy 275.302691 -396.823681) (xy 275.343074 -396.794374) (xy 275.38754 -396.771736)
			(xy 275.434997 -396.756325) (xy 275.48428 -396.748517) (xy 275.509228 -396.748) (xy 280.83764 -396.748)
			(xy 280.862593 -396.748459) (xy 280.911886 -396.756258) (xy 280.959352 -396.771671) (xy 281.003822 -396.794321)
			(xy 281.044202 -396.82365) (xy 281.062176 -396.840964) (xy 281.593544 -397.372332) (xy 281.61083 -397.39033)
			(xy 281.640144 -397.430711) (xy 281.662789 -397.475177) (xy 281.678209 -397.522634) (xy 281.686026 -397.571918)
			(xy 281.686508 -397.596868) (xy 281.686508 -398.65534) (xy 457.185003 -398.65534) (xy 457.185003 -398.5262)
			(xy 457.192953 -398.397305) (xy 457.208823 -398.269145) (xy 457.232552 -398.142204) (xy 457.264051 -398.016965)
			(xy 457.3032 -397.893902) (xy 457.349851 -397.773483) (xy 457.403826 -397.656164) (xy 457.464921 -397.54239)
			(xy 457.532904 -397.432593) (xy 457.607518 -397.32719) (xy 457.688479 -397.22658) (xy 457.775479 -397.131145)
			(xy 457.86819 -397.041246) (xy 457.96626 -396.957225) (xy 458.069315 -396.879401) (xy 458.176966 -396.808069)
			(xy 458.288805 -396.743499) (xy 458.404406 -396.685937) (xy 458.523331 -396.6356) (xy 458.64513 -396.59268)
			(xy 458.76934 -396.557339) (xy 458.895489 -396.529712) (xy 459.023101 -396.509903) (xy 459.15169 -396.497987)
			(xy 459.280768 -396.494011) (xy 459.409846 -396.497987) (xy 459.538435 -396.509903) (xy 459.666047 -396.529712)
			(xy 459.792196 -396.557339) (xy 459.916406 -396.59268) (xy 460.038205 -396.6356) (xy 460.15713 -396.685937)
			(xy 460.272731 -396.743499) (xy 460.38457 -396.808069) (xy 460.492221 -396.879401) (xy 460.595276 -396.957225)
			(xy 460.693346 -397.041246) (xy 460.786057 -397.131145) (xy 460.873057 -397.22658) (xy 460.954018 -397.32719)
			(xy 461.028632 -397.432593) (xy 461.096615 -397.54239) (xy 461.15771 -397.656164) (xy 461.211685 -397.773483)
			(xy 461.258336 -397.893902) (xy 461.297485 -398.016965) (xy 461.328984 -398.142204) (xy 461.352713 -398.269145)
			(xy 461.368583 -398.397305) (xy 461.376533 -398.5262) (xy 461.37703 -398.59077) (xy 461.376533 -398.65534)
			(xy 461.368583 -398.784235) (xy 461.352713 -398.912395) (xy 461.328984 -399.039336) (xy 461.297485 -399.164575)
			(xy 461.258336 -399.287638) (xy 461.211685 -399.408057) (xy 461.15771 -399.525376) (xy 461.096615 -399.63915)
			(xy 461.028632 -399.748947) (xy 460.954018 -399.85435) (xy 460.873057 -399.95496) (xy 460.786057 -400.050395)
			(xy 460.693346 -400.140294) (xy 460.595276 -400.224315) (xy 460.492221 -400.302139) (xy 460.38457 -400.373471)
			(xy 460.272731 -400.438041) (xy 460.15713 -400.495603) (xy 460.038205 -400.54594) (xy 459.916406 -400.58886)
			(xy 459.792196 -400.624201) (xy 459.666047 -400.651828) (xy 459.538435 -400.671637) (xy 459.409846 -400.683553)
			(xy 459.280768 -400.68753) (xy 459.15169 -400.683553) (xy 459.023101 -400.671637) (xy 458.895489 -400.651828)
			(xy 458.76934 -400.624201) (xy 458.64513 -400.58886) (xy 458.523331 -400.54594) (xy 458.404406 -400.495603)
			(xy 458.288805 -400.438041) (xy 458.176966 -400.373471) (xy 458.069315 -400.302139) (xy 457.96626 -400.224315)
			(xy 457.86819 -400.140294) (xy 457.775479 -400.050395) (xy 457.688479 -399.95496) (xy 457.607518 -399.85435)
			(xy 457.532904 -399.748947) (xy 457.464921 -399.63915) (xy 457.403826 -399.525376) (xy 457.349851 -399.408057)
			(xy 457.3032 -399.287638) (xy 457.264051 -399.164575) (xy 457.232552 -399.039336) (xy 457.208823 -398.912395)
			(xy 457.192953 -398.784235) (xy 457.185003 -398.65534) (xy 281.686508 -398.65534) (xy 281.686508 -399.9835)
			(xy 289.606441 -399.9835) (xy 289.610455 -399.919698) (xy 289.622434 -399.856902) (xy 289.642189 -399.796103)
			(xy 289.669408 -399.73826) (xy 289.703662 -399.684283) (xy 289.744411 -399.635026) (xy 289.791013 -399.591264)
			(xy 289.842731 -399.553688) (xy 289.898752 -399.52289) (xy 289.958191 -399.499357) (xy 290.02011 -399.483458)
			(xy 290.083534 -399.475446) (xy 290.115498 -399.474944) (xy 290.115752 -399.474944) (xy 290.147498 -399.475464)
			(xy 290.210494 -399.483393) (xy 290.272014 -399.499096) (xy 290.331102 -399.52233) (xy 290.386842 -399.552733)
			(xy 290.438367 -399.589834) (xy 290.461954 -399.611088) (xy 290.469217 -399.617272) (xy 290.486967 -399.624223)
			(xy 290.506029 -399.624223) (xy 290.523779 -399.617272) (xy 290.531042 -399.611088) (xy 290.554631 -399.589832)
			(xy 290.60614 -399.5527) (xy 290.661874 -399.522276) (xy 290.720965 -399.499035) (xy 290.782492 -399.483338)
			(xy 290.845495 -399.475431) (xy 290.877244 -399.474944) (xy 290.877498 -399.474944) (xy 290.909457 -399.475521)
			(xy 290.972872 -399.483532) (xy 291.034783 -399.499427) (xy 291.094213 -399.522957) (xy 291.150226 -399.55375)
			(xy 291.201937 -399.591321) (xy 291.248532 -399.635076) (xy 291.289276 -399.684326) (xy 291.323525 -399.738295)
			(xy 291.350741 -399.79613) (xy 291.370493 -399.856921) (xy 291.38247 -399.919707) (xy 291.386484 -399.9835)
			(xy 292.146441 -399.9835) (xy 292.150455 -399.919698) (xy 292.162434 -399.856902) (xy 292.182189 -399.796103)
			(xy 292.209408 -399.73826) (xy 292.243662 -399.684283) (xy 292.284411 -399.635026) (xy 292.331013 -399.591264)
			(xy 292.382731 -399.553688) (xy 292.438752 -399.52289) (xy 292.498191 -399.499357) (xy 292.56011 -399.483458)
			(xy 292.623534 -399.475446) (xy 292.655498 -399.474944) (xy 292.655752 -399.474944) (xy 292.687498 -399.475464)
			(xy 292.750494 -399.483393) (xy 292.812014 -399.499096) (xy 292.871102 -399.52233) (xy 292.926842 -399.552733)
			(xy 292.978367 -399.589834) (xy 293.001954 -399.611088) (xy 293.009217 -399.617272) (xy 293.026967 -399.624223)
			(xy 293.046029 -399.624223) (xy 293.063779 -399.617272) (xy 293.071042 -399.611088) (xy 293.094631 -399.589832)
			(xy 293.14614 -399.5527) (xy 293.201874 -399.522276) (xy 293.260965 -399.499035) (xy 293.322492 -399.483338)
			(xy 293.385495 -399.475431) (xy 293.417244 -399.474944) (xy 293.417498 -399.474944) (xy 293.449457 -399.475521)
			(xy 293.512872 -399.483532) (xy 293.574783 -399.499427) (xy 293.634213 -399.522957) (xy 293.690226 -399.55375)
			(xy 293.741937 -399.591321) (xy 293.788532 -399.635076) (xy 293.829276 -399.684326) (xy 293.863525 -399.738295)
			(xy 293.890741 -399.79613) (xy 293.910493 -399.856921) (xy 293.92247 -399.919707) (xy 293.926484 -399.9835)
			(xy 294.53602 -399.9835) (xy 294.540035 -399.919693) (xy 294.552015 -399.856892) (xy 294.571773 -399.796089)
			(xy 294.598995 -399.738241) (xy 294.633253 -399.684261) (xy 294.674007 -399.635001) (xy 294.720613 -399.591237)
			(xy 294.772338 -399.55366) (xy 294.828364 -399.522862) (xy 294.887809 -399.499329) (xy 294.949734 -399.483433)
			(xy 295.013163 -399.475423) (xy 295.04513 -399.474944) (xy 295.045384 -399.474944) (xy 295.077131 -399.475444)
			(xy 295.140127 -399.483377) (xy 295.201647 -399.499084) (xy 295.260736 -399.522322) (xy 295.316476 -399.552728)
			(xy 295.368 -399.589832) (xy 295.391586 -399.611088) (xy 295.398849 -399.617272) (xy 295.416599 -399.624223)
			(xy 295.435661 -399.624223) (xy 295.453411 -399.617272) (xy 295.460674 -399.611088) (xy 295.48425 -399.589817)
			(xy 295.535761 -399.552686) (xy 295.591498 -399.522265) (xy 295.650592 -399.499026) (xy 295.712121 -399.483332)
			(xy 295.775126 -399.475429) (xy 295.806876 -399.474944) (xy 295.80713 -399.474944) (xy 295.839087 -399.475544)
			(xy 295.902496 -399.483558) (xy 295.964401 -399.499455) (xy 296.023825 -399.522986) (xy 296.079832 -399.553779)
			(xy 296.131538 -399.591348) (xy 296.178128 -399.635102) (xy 296.218866 -399.684349) (xy 296.253112 -399.738314)
			(xy 296.280324 -399.796145) (xy 296.300074 -399.856931) (xy 296.312049 -399.919712) (xy 296.316063 -399.9835)
			(xy 297.07602 -399.9835) (xy 297.080035 -399.919693) (xy 297.092015 -399.856892) (xy 297.111773 -399.796089)
			(xy 297.138995 -399.738241) (xy 297.173253 -399.684261) (xy 297.214007 -399.635001) (xy 297.260613 -399.591237)
			(xy 297.312338 -399.55366) (xy 297.368364 -399.522862) (xy 297.427809 -399.499329) (xy 297.489734 -399.483433)
			(xy 297.553163 -399.475423) (xy 297.58513 -399.474944) (xy 297.585384 -399.474944) (xy 297.617131 -399.475444)
			(xy 297.680127 -399.483377) (xy 297.741647 -399.499084) (xy 297.800736 -399.522322) (xy 297.856476 -399.552728)
			(xy 297.908 -399.589832) (xy 297.931586 -399.611088) (xy 297.938849 -399.617272) (xy 297.956599 -399.624223)
			(xy 297.975661 -399.624223) (xy 297.993411 -399.617272) (xy 298.000674 -399.611088) (xy 298.02425 -399.589817)
			(xy 298.075761 -399.552686) (xy 298.131498 -399.522265) (xy 298.190592 -399.499026) (xy 298.252121 -399.483332)
			(xy 298.315126 -399.475429) (xy 298.346876 -399.474944) (xy 298.34713 -399.474944) (xy 298.379087 -399.475544)
			(xy 298.442496 -399.483558) (xy 298.504401 -399.499455) (xy 298.563825 -399.522986) (xy 298.619832 -399.553779)
			(xy 298.671538 -399.591348) (xy 298.718128 -399.635102) (xy 298.758866 -399.684349) (xy 298.793112 -399.738314)
			(xy 298.820324 -399.796145) (xy 298.840074 -399.856931) (xy 298.852049 -399.919712) (xy 298.856063 -399.9835)
			(xy 298.852049 -400.047288) (xy 298.840074 -400.110069) (xy 298.820324 -400.170855) (xy 298.793112 -400.228686)
			(xy 298.758866 -400.282651) (xy 298.718128 -400.331898) (xy 298.671538 -400.375652) (xy 298.619832 -400.413221)
			(xy 298.563825 -400.444014) (xy 298.504401 -400.467545) (xy 298.442496 -400.483442) (xy 298.379087 -400.491456)
			(xy 298.34713 -400.49196) (xy 298.346876 -400.49196) (xy 298.315131 -400.491422) (xy 298.252136 -400.483497)
			(xy 298.190616 -400.467797) (xy 298.131527 -400.444566) (xy 298.075787 -400.414166) (xy 298.024261 -400.377069)
			(xy 298.000674 -400.355816) (xy 297.993411 -400.349632) (xy 297.975661 -400.342681) (xy 297.956599 -400.342681)
			(xy 297.938849 -400.349632) (xy 297.931586 -400.355816) (xy 297.908028 -400.377107) (xy 297.856512 -400.414235)
			(xy 297.800771 -400.444654) (xy 297.741674 -400.467889) (xy 297.680142 -400.483579) (xy 297.617135 -400.491478)
			(xy 297.585384 -400.49196) (xy 297.58513 -400.49196) (xy 297.553163 -400.491577) (xy 297.489734 -400.483567)
			(xy 297.427809 -400.467671) (xy 297.368364 -400.444138) (xy 297.312338 -400.41334) (xy 297.260613 -400.375763)
			(xy 297.214007 -400.331999) (xy 297.173253 -400.282739) (xy 297.138995 -400.228759) (xy 297.111773 -400.170911)
			(xy 297.092015 -400.110108) (xy 297.080035 -400.047307) (xy 297.07602 -399.9835) (xy 296.316063 -399.9835)
			(xy 296.312049 -400.047288) (xy 296.300074 -400.110069) (xy 296.280324 -400.170855) (xy 296.253112 -400.228686)
			(xy 296.218866 -400.282651) (xy 296.178128 -400.331898) (xy 296.131538 -400.375652) (xy 296.079832 -400.413221)
			(xy 296.023825 -400.444014) (xy 295.964401 -400.467545) (xy 295.902496 -400.483442) (xy 295.839087 -400.491456)
			(xy 295.80713 -400.49196) (xy 295.806876 -400.49196) (xy 295.775131 -400.491422) (xy 295.712136 -400.483497)
			(xy 295.650616 -400.467797) (xy 295.591527 -400.444566) (xy 295.535787 -400.414166) (xy 295.484261 -400.377069)
			(xy 295.460674 -400.355816) (xy 295.453411 -400.349632) (xy 295.435661 -400.342681) (xy 295.416599 -400.342681)
			(xy 295.398849 -400.349632) (xy 295.391586 -400.355816) (xy 295.368028 -400.377107) (xy 295.316512 -400.414235)
			(xy 295.260771 -400.444654) (xy 295.201674 -400.467889) (xy 295.140142 -400.483579) (xy 295.077135 -400.491478)
			(xy 295.045384 -400.49196) (xy 295.04513 -400.49196) (xy 295.013163 -400.491577) (xy 294.949734 -400.483567)
			(xy 294.887809 -400.467671) (xy 294.828364 -400.444138) (xy 294.772338 -400.41334) (xy 294.720613 -400.375763)
			(xy 294.674007 -400.331999) (xy 294.633253 -400.282739) (xy 294.598995 -400.228759) (xy 294.571773 -400.170911)
			(xy 294.552015 -400.110108) (xy 294.540035 -400.047307) (xy 294.53602 -399.9835) (xy 293.926484 -399.9835)
			(xy 293.92247 -400.047293) (xy 293.910493 -400.110079) (xy 293.890741 -400.17087) (xy 293.863525 -400.228705)
			(xy 293.829276 -400.282674) (xy 293.788532 -400.331924) (xy 293.741937 -400.375679) (xy 293.690226 -400.41325)
			(xy 293.634213 -400.444043) (xy 293.574783 -400.467573) (xy 293.512872 -400.483468) (xy 293.449457 -400.491479)
			(xy 293.417498 -400.49196) (xy 293.417244 -400.49196) (xy 293.385498 -400.491442) (xy 293.322502 -400.483512)
			(xy 293.260982 -400.467809) (xy 293.201894 -400.444575) (xy 293.146154 -400.414171) (xy 293.094629 -400.37707)
			(xy 293.071042 -400.355816) (xy 293.063779 -400.349632) (xy 293.046029 -400.342681) (xy 293.026967 -400.342681)
			(xy 293.009217 -400.349632) (xy 293.001954 -400.355816) (xy 292.978367 -400.377074) (xy 292.926858 -400.414206)
			(xy 292.871123 -400.44463) (xy 292.812032 -400.467871) (xy 292.750504 -400.483567) (xy 292.687501 -400.491474)
			(xy 292.655752 -400.49196) (xy 292.655498 -400.49196) (xy 292.623534 -400.491554) (xy 292.56011 -400.483542)
			(xy 292.498191 -400.467643) (xy 292.438752 -400.44411) (xy 292.382731 -400.413312) (xy 292.331013 -400.375736)
			(xy 292.284411 -400.331974) (xy 292.243662 -400.282717) (xy 292.209408 -400.22874) (xy 292.182189 -400.170897)
			(xy 292.162434 -400.110098) (xy 292.150455 -400.047302) (xy 292.146441 -399.9835) (xy 291.386484 -399.9835)
			(xy 291.38247 -400.047293) (xy 291.370493 -400.110079) (xy 291.350741 -400.17087) (xy 291.323525 -400.228705)
			(xy 291.289276 -400.282674) (xy 291.248532 -400.331924) (xy 291.201937 -400.375679) (xy 291.150226 -400.41325)
			(xy 291.094213 -400.444043) (xy 291.034783 -400.467573) (xy 290.972872 -400.483468) (xy 290.909457 -400.491479)
			(xy 290.877498 -400.49196) (xy 290.877244 -400.49196) (xy 290.845498 -400.491442) (xy 290.782502 -400.483512)
			(xy 290.720982 -400.467809) (xy 290.661894 -400.444575) (xy 290.606154 -400.414171) (xy 290.554629 -400.37707)
			(xy 290.531042 -400.355816) (xy 290.523779 -400.349632) (xy 290.506029 -400.342681) (xy 290.486967 -400.342681)
			(xy 290.469217 -400.349632) (xy 290.461954 -400.355816) (xy 290.438367 -400.377074) (xy 290.386858 -400.414206)
			(xy 290.331123 -400.44463) (xy 290.272032 -400.467871) (xy 290.210504 -400.483567) (xy 290.147501 -400.491474)
			(xy 290.115752 -400.49196) (xy 290.115498 -400.49196) (xy 290.083534 -400.491554) (xy 290.02011 -400.483542)
			(xy 289.958191 -400.467643) (xy 289.898752 -400.44411) (xy 289.842731 -400.413312) (xy 289.791013 -400.375736)
			(xy 289.744411 -400.331974) (xy 289.703662 -400.282717) (xy 289.669408 -400.22874) (xy 289.642189 -400.170897)
			(xy 289.622434 -400.110098) (xy 289.610455 -400.047302) (xy 289.606441 -399.9835) (xy 281.686508 -399.9835)
			(xy 281.686508 -400.885449) (xy 303.599106 -400.885449) (xy 303.599106 -400.830951) (xy 303.606862 -400.777009)
			(xy 303.622215 -400.724719) (xy 303.644854 -400.675146) (xy 303.674317 -400.6293) (xy 303.710004 -400.588113)
			(xy 303.75119 -400.552424) (xy 303.797036 -400.52296) (xy 303.846608 -400.500319) (xy 303.898897 -400.484964)
			(xy 303.952839 -400.477207) (xy 303.980088 -400.47672) (xy 304.843688 -400.47672) (xy 304.870943 -400.477126)
			(xy 304.9249 -400.484882) (xy 304.977203 -400.500238) (xy 305.026788 -400.522882) (xy 305.072646 -400.552352)
			(xy 305.113843 -400.588048) (xy 305.149541 -400.629244) (xy 305.179012 -400.675101) (xy 305.201657 -400.724686)
			(xy 305.217015 -400.776989) (xy 305.224773 -400.830945) (xy 305.224773 -400.885452) (xy 306.662283 -400.885452)
			(xy 306.662283 -400.830948) (xy 306.67004 -400.776998) (xy 306.685397 -400.724702) (xy 306.70804 -400.675124)
			(xy 306.737508 -400.629273) (xy 306.773202 -400.588082) (xy 306.814395 -400.552391) (xy 306.860248 -400.522926)
			(xy 306.909828 -400.500287) (xy 306.962126 -400.484935) (xy 307.016076 -400.477181) (xy 307.043328 -400.47672)
			(xy 307.906928 -400.47672) (xy 307.93418 -400.477152) (xy 307.988129 -400.484912) (xy 308.040424 -400.500271)
			(xy 308.090001 -400.522915) (xy 308.135851 -400.552384) (xy 308.177041 -400.588079) (xy 308.212732 -400.629271)
			(xy 308.242198 -400.675123) (xy 308.264839 -400.724702) (xy 308.280194 -400.776999) (xy 308.28795 -400.830948)
			(xy 308.28795 -400.885448) (xy 309.725606 -400.885448) (xy 309.725606 -400.830952) (xy 309.733361 -400.777011)
			(xy 309.748714 -400.724723) (xy 309.771351 -400.675152) (xy 309.800812 -400.629306) (xy 309.836497 -400.58812)
			(xy 309.877681 -400.552431) (xy 309.923524 -400.522966) (xy 309.973093 -400.500325) (xy 310.02538 -400.484968)
			(xy 310.07932 -400.477208) (xy 310.106568 -400.47672) (xy 310.970168 -400.47672) (xy 310.997424 -400.477125)
			(xy 311.051383 -400.484879) (xy 311.103688 -400.500233) (xy 311.153276 -400.522875) (xy 311.199137 -400.552345)
			(xy 311.240336 -400.588041) (xy 311.276036 -400.629238) (xy 311.305509 -400.675096) (xy 311.328156 -400.724682)
			(xy 311.343515 -400.776986) (xy 311.351273 -400.830944) (xy 311.351273 -400.885451) (xy 312.788783 -400.885451)
			(xy 312.788783 -400.830949) (xy 312.79654 -400.777001) (xy 312.811895 -400.724706) (xy 312.834537 -400.675129)
			(xy 312.864003 -400.629279) (xy 312.899695 -400.588089) (xy 312.940886 -400.552398) (xy 312.986736 -400.522933)
			(xy 313.036314 -400.500292) (xy 313.088609 -400.484938) (xy 313.142557 -400.477183) (xy 313.169808 -400.47672)
			(xy 314.033408 -400.47672) (xy 314.060661 -400.47715) (xy 314.114612 -400.484908) (xy 314.166909 -400.500265)
			(xy 314.216489 -400.522909) (xy 314.262342 -400.552377) (xy 314.303534 -400.588071) (xy 314.339228 -400.629264)
			(xy 314.368695 -400.675118) (xy 314.391337 -400.724698) (xy 314.406693 -400.776996) (xy 314.41445 -400.830947)
			(xy 314.41445 -400.885453) (xy 315.851983 -400.885453) (xy 315.851983 -400.830947) (xy 315.859741 -400.776996)
			(xy 315.875098 -400.724698) (xy 315.897743 -400.675118) (xy 315.927213 -400.629266) (xy 315.962909 -400.588075)
			(xy 316.004105 -400.552384) (xy 316.04996 -400.52292) (xy 316.099543 -400.500282) (xy 316.151843 -400.484931)
			(xy 316.205795 -400.47718) (xy 316.233048 -400.47672) (xy 317.096648 -400.47672) (xy 317.123899 -400.477153)
			(xy 317.177846 -400.484916) (xy 317.230138 -400.500276) (xy 317.279713 -400.522922) (xy 317.325561 -400.552391)
			(xy 317.366748 -400.588086) (xy 317.402437 -400.629278) (xy 317.431901 -400.675129) (xy 317.454541 -400.724707)
			(xy 317.469894 -400.777001) (xy 317.47765 -400.830949) (xy 317.47765 -400.885449) (xy 318.915306 -400.885449)
			(xy 318.915306 -400.830951) (xy 318.923062 -400.777009) (xy 318.938415 -400.724719) (xy 318.961054 -400.675146)
			(xy 318.990517 -400.6293) (xy 319.026204 -400.588113) (xy 319.06739 -400.552424) (xy 319.113236 -400.52296)
			(xy 319.162808 -400.500319) (xy 319.215097 -400.484964) (xy 319.269039 -400.477207) (xy 319.296288 -400.47672)
			(xy 320.159888 -400.47672) (xy 320.187143 -400.477126) (xy 320.2411 -400.484882) (xy 320.293403 -400.500238)
			(xy 320.342988 -400.522882) (xy 320.388846 -400.552352) (xy 320.430043 -400.588048) (xy 320.465741 -400.629244)
			(xy 320.495212 -400.675101) (xy 320.517857 -400.724686) (xy 320.533215 -400.776989) (xy 320.540973 -400.830945)
			(xy 320.540973 -400.885452) (xy 321.978483 -400.885452) (xy 321.978483 -400.830948) (xy 321.98624 -400.776998)
			(xy 322.001597 -400.724702) (xy 322.02424 -400.675124) (xy 322.053708 -400.629273) (xy 322.089402 -400.588082)
			(xy 322.130595 -400.552391) (xy 322.176448 -400.522926) (xy 322.226028 -400.500287) (xy 322.278326 -400.484935)
			(xy 322.332276 -400.477181) (xy 322.359528 -400.47672) (xy 323.223128 -400.47672) (xy 323.25038 -400.477152)
			(xy 323.304329 -400.484912) (xy 323.356624 -400.500271) (xy 323.406201 -400.522915) (xy 323.452051 -400.552384)
			(xy 323.493241 -400.588079) (xy 323.528932 -400.629271) (xy 323.558398 -400.675123) (xy 323.581039 -400.724702)
			(xy 323.596394 -400.776999) (xy 323.60415 -400.830948) (xy 323.60415 -400.885448) (xy 325.041806 -400.885448)
			(xy 325.041806 -400.830952) (xy 325.049561 -400.777011) (xy 325.064914 -400.724723) (xy 325.087551 -400.675152)
			(xy 325.117012 -400.629306) (xy 325.152697 -400.58812) (xy 325.193881 -400.552431) (xy 325.239724 -400.522966)
			(xy 325.289293 -400.500325) (xy 325.34158 -400.484968) (xy 325.39552 -400.477208) (xy 325.422768 -400.47672)
			(xy 326.286368 -400.47672) (xy 326.313624 -400.477125) (xy 326.367583 -400.484879) (xy 326.419888 -400.500233)
			(xy 326.469476 -400.522875) (xy 326.515337 -400.552345) (xy 326.556536 -400.588041) (xy 326.592236 -400.629238)
			(xy 326.621709 -400.675096) (xy 326.644356 -400.724682) (xy 326.659715 -400.776986) (xy 326.667473 -400.830944)
			(xy 326.667473 -400.885451) (xy 328.104983 -400.885451) (xy 328.104983 -400.830949) (xy 328.11274 -400.777001)
			(xy 328.128095 -400.724706) (xy 328.150737 -400.675129) (xy 328.180203 -400.629279) (xy 328.215895 -400.588089)
			(xy 328.257086 -400.552398) (xy 328.302936 -400.522933) (xy 328.352514 -400.500292) (xy 328.404809 -400.484938)
			(xy 328.458757 -400.477183) (xy 328.486008 -400.47672) (xy 329.349608 -400.47672) (xy 329.376861 -400.47715)
			(xy 329.430812 -400.484908) (xy 329.483109 -400.500265) (xy 329.532689 -400.522909) (xy 329.578542 -400.552377)
			(xy 329.619734 -400.588071) (xy 329.655428 -400.629264) (xy 329.684895 -400.675118) (xy 329.707537 -400.724698)
			(xy 329.722893 -400.776996) (xy 329.73065 -400.830947) (xy 329.73065 -400.885453) (xy 331.168183 -400.885453)
			(xy 331.168183 -400.830947) (xy 331.175941 -400.776996) (xy 331.191298 -400.724698) (xy 331.213943 -400.675118)
			(xy 331.243413 -400.629266) (xy 331.279109 -400.588075) (xy 331.320305 -400.552384) (xy 331.36616 -400.52292)
			(xy 331.415743 -400.500282) (xy 331.468043 -400.484931) (xy 331.521995 -400.47718) (xy 331.549248 -400.47672)
			(xy 332.412848 -400.47672) (xy 332.440099 -400.477153) (xy 332.494046 -400.484916) (xy 332.546338 -400.500276)
			(xy 332.595913 -400.522922) (xy 332.641761 -400.552391) (xy 332.682948 -400.588086) (xy 332.718637 -400.629278)
			(xy 332.748101 -400.675129) (xy 332.770741 -400.724707) (xy 332.786094 -400.777001) (xy 332.79385 -400.830949)
			(xy 332.79385 -400.885449) (xy 334.231506 -400.885449) (xy 334.231506 -400.830951) (xy 334.239262 -400.777009)
			(xy 334.254615 -400.724719) (xy 334.277254 -400.675146) (xy 334.306717 -400.6293) (xy 334.342404 -400.588113)
			(xy 334.38359 -400.552424) (xy 334.429436 -400.52296) (xy 334.479008 -400.500319) (xy 334.531297 -400.484964)
			(xy 334.585239 -400.477207) (xy 334.612488 -400.47672) (xy 335.476088 -400.47672) (xy 335.503343 -400.477126)
			(xy 335.5573 -400.484882) (xy 335.609603 -400.500238) (xy 335.659188 -400.522882) (xy 335.705046 -400.552352)
			(xy 335.746243 -400.588048) (xy 335.781941 -400.629244) (xy 335.811412 -400.675101) (xy 335.834057 -400.724686)
			(xy 335.849415 -400.776989) (xy 335.857173 -400.830945) (xy 335.857173 -400.885452) (xy 337.294683 -400.885452)
			(xy 337.294683 -400.830948) (xy 337.30244 -400.776998) (xy 337.317797 -400.724702) (xy 337.34044 -400.675124)
			(xy 337.369908 -400.629273) (xy 337.405602 -400.588082) (xy 337.446795 -400.552391) (xy 337.492648 -400.522926)
			(xy 337.542228 -400.500287) (xy 337.594526 -400.484935) (xy 337.648476 -400.477181) (xy 337.675728 -400.47672)
			(xy 338.539328 -400.47672) (xy 338.56658 -400.477152) (xy 338.620529 -400.484912) (xy 338.672824 -400.500271)
			(xy 338.722401 -400.522915) (xy 338.768251 -400.552384) (xy 338.809441 -400.588079) (xy 338.845132 -400.629271)
			(xy 338.874598 -400.675123) (xy 338.897239 -400.724702) (xy 338.912594 -400.776999) (xy 338.92035 -400.830948)
			(xy 338.92035 -400.885448) (xy 340.358006 -400.885448) (xy 340.358006 -400.830952) (xy 340.365761 -400.777011)
			(xy 340.381114 -400.724723) (xy 340.403751 -400.675152) (xy 340.433212 -400.629306) (xy 340.468897 -400.58812)
			(xy 340.510081 -400.552431) (xy 340.555924 -400.522966) (xy 340.605493 -400.500325) (xy 340.65778 -400.484968)
			(xy 340.71172 -400.477208) (xy 340.738968 -400.47672) (xy 341.602568 -400.47672) (xy 341.629824 -400.477125)
			(xy 341.683783 -400.484879) (xy 341.736088 -400.500233) (xy 341.785676 -400.522875) (xy 341.831537 -400.552345)
			(xy 341.872736 -400.588041) (xy 341.908436 -400.629238) (xy 341.937909 -400.675096) (xy 341.960556 -400.724682)
			(xy 341.975915 -400.776986) (xy 341.983673 -400.830944) (xy 341.983673 -400.885451) (xy 343.421183 -400.885451)
			(xy 343.421183 -400.830949) (xy 343.42894 -400.777001) (xy 343.444295 -400.724706) (xy 343.466937 -400.675129)
			(xy 343.496403 -400.629279) (xy 343.532095 -400.588089) (xy 343.573286 -400.552398) (xy 343.619136 -400.522933)
			(xy 343.668714 -400.500292) (xy 343.721009 -400.484938) (xy 343.774957 -400.477183) (xy 343.802208 -400.47672)
			(xy 344.665808 -400.47672) (xy 344.693061 -400.47715) (xy 344.747012 -400.484908) (xy 344.799309 -400.500265)
			(xy 344.848889 -400.522909) (xy 344.894742 -400.552377) (xy 344.935934 -400.588071) (xy 344.971628 -400.629264)
			(xy 345.001095 -400.675118) (xy 345.023737 -400.724698) (xy 345.039093 -400.776996) (xy 345.04685 -400.830947)
			(xy 345.04685 -400.885453) (xy 346.484383 -400.885453) (xy 346.484383 -400.830947) (xy 346.492141 -400.776996)
			(xy 346.507498 -400.724698) (xy 346.530143 -400.675118) (xy 346.559613 -400.629266) (xy 346.595309 -400.588075)
			(xy 346.636505 -400.552384) (xy 346.68236 -400.52292) (xy 346.731943 -400.500282) (xy 346.784243 -400.484931)
			(xy 346.838195 -400.47718) (xy 346.865448 -400.47672) (xy 347.729048 -400.47672) (xy 347.756299 -400.477153)
			(xy 347.810246 -400.484916) (xy 347.862538 -400.500276) (xy 347.912113 -400.522922) (xy 347.957961 -400.552391)
			(xy 347.999148 -400.588086) (xy 348.034837 -400.629278) (xy 348.064301 -400.675129) (xy 348.086941 -400.724707)
			(xy 348.102294 -400.777001) (xy 348.11005 -400.830949) (xy 348.11005 -400.885449) (xy 349.547706 -400.885449)
			(xy 349.547706 -400.830951) (xy 349.555462 -400.777009) (xy 349.570815 -400.724719) (xy 349.593454 -400.675146)
			(xy 349.622917 -400.6293) (xy 349.658604 -400.588113) (xy 349.69979 -400.552424) (xy 349.745636 -400.52296)
			(xy 349.795208 -400.500319) (xy 349.847497 -400.484964) (xy 349.901439 -400.477207) (xy 349.928688 -400.47672)
			(xy 350.792288 -400.47672) (xy 350.819543 -400.477126) (xy 350.8735 -400.484882) (xy 350.925803 -400.500238)
			(xy 350.975388 -400.522882) (xy 351.021246 -400.552352) (xy 351.062443 -400.588048) (xy 351.098141 -400.629244)
			(xy 351.127612 -400.675101) (xy 351.150257 -400.724686) (xy 351.165615 -400.776989) (xy 351.173373 -400.830945)
			(xy 351.173373 -400.885452) (xy 371.041883 -400.885452) (xy 371.041883 -400.830948) (xy 371.049641 -400.776998)
			(xy 371.064997 -400.724702) (xy 371.08764 -400.675123) (xy 371.117109 -400.629272) (xy 371.152803 -400.588082)
			(xy 371.193996 -400.552391) (xy 371.23985 -400.522926) (xy 371.28943 -400.500286) (xy 371.341728 -400.484934)
			(xy 371.395678 -400.477181) (xy 371.42293 -400.47672) (xy 372.28653 -400.47672) (xy 372.313782 -400.477152)
			(xy 372.36773 -400.484912) (xy 372.420025 -400.500271) (xy 372.469602 -400.522916) (xy 372.515452 -400.552385)
			(xy 372.556642 -400.588079) (xy 372.592333 -400.629272) (xy 372.621799 -400.675124) (xy 372.644439 -400.724703)
			(xy 372.659794 -400.776999) (xy 372.66755 -400.830948) (xy 372.66755 -400.885448) (xy 374.105206 -400.885448)
			(xy 374.105206 -400.830952) (xy 374.112961 -400.777011) (xy 374.128314 -400.724723) (xy 374.150951 -400.675151)
			(xy 374.180412 -400.629306) (xy 374.216098 -400.588119) (xy 374.257281 -400.55243) (xy 374.303125 -400.522965)
			(xy 374.352694 -400.500324) (xy 374.404982 -400.484968) (xy 374.458922 -400.477208) (xy 374.48617 -400.47672)
			(xy 375.34977 -400.47672) (xy 375.377026 -400.477125) (xy 375.430984 -400.484879) (xy 375.48329 -400.500234)
			(xy 375.532877 -400.522876) (xy 375.578738 -400.552345) (xy 375.619937 -400.588042) (xy 375.655637 -400.629238)
			(xy 375.68511 -400.675096) (xy 375.707756 -400.724682) (xy 375.723115 -400.776986) (xy 375.730873 -400.830944)
			(xy 375.730873 -400.885451) (xy 377.168383 -400.885451) (xy 377.168383 -400.830949) (xy 377.17614 -400.777001)
			(xy 377.191495 -400.724706) (xy 377.214137 -400.675129) (xy 377.243604 -400.629279) (xy 377.279296 -400.588089)
			(xy 377.320487 -400.552398) (xy 377.366338 -400.522932) (xy 377.415915 -400.500292) (xy 377.468211 -400.484938)
			(xy 377.522159 -400.477183) (xy 377.54941 -400.47672) (xy 378.41301 -400.47672) (xy 378.440263 -400.477151)
			(xy 378.494213 -400.484909) (xy 378.546511 -400.500266) (xy 378.59609 -400.522909) (xy 378.641943 -400.552378)
			(xy 378.683135 -400.588072) (xy 378.718828 -400.629265) (xy 378.748296 -400.675118) (xy 378.770938 -400.724699)
			(xy 378.786293 -400.776996) (xy 378.79405 -400.830947) (xy 378.79405 -400.885447) (xy 380.231706 -400.885447)
			(xy 380.231706 -400.830953) (xy 380.239461 -400.777014) (xy 380.254812 -400.724727) (xy 380.277448 -400.675157)
			(xy 380.306907 -400.629312) (xy 380.342591 -400.588126) (xy 380.383772 -400.552437) (xy 380.429613 -400.522972)
			(xy 380.47918 -400.50033) (xy 380.531465 -400.484971) (xy 380.585403 -400.47721) (xy 380.61265 -400.47672)
			(xy 381.47625 -400.47672) (xy 381.503507 -400.477124) (xy 381.557468 -400.484875) (xy 381.609775 -400.500228)
			(xy 381.659365 -400.522869) (xy 381.705228 -400.552338) (xy 381.74643 -400.588035) (xy 381.782132 -400.629232)
			(xy 381.811607 -400.675091) (xy 381.834254 -400.724678) (xy 381.849614 -400.776983) (xy 381.857373 -400.830943)
			(xy 381.857373 -400.885449) (xy 383.294906 -400.885449) (xy 383.294906 -400.830951) (xy 383.302662 -400.777008)
			(xy 383.318015 -400.724718) (xy 383.340654 -400.675145) (xy 383.370117 -400.629299) (xy 383.405805 -400.588112)
			(xy 383.446991 -400.552423) (xy 383.492837 -400.522959) (xy 383.542409 -400.500319) (xy 383.594699 -400.484964)
			(xy 383.648641 -400.477207) (xy 383.67589 -400.47672) (xy 384.53949 -400.47672) (xy 384.566745 -400.477126)
			(xy 384.620701 -400.484883) (xy 384.673004 -400.500239) (xy 384.722589 -400.522883) (xy 384.768447 -400.552352)
			(xy 384.809644 -400.588049) (xy 384.845342 -400.629245) (xy 384.874813 -400.675102) (xy 384.897458 -400.724686)
			(xy 384.912815 -400.776989) (xy 384.920573 -400.830945) (xy 384.920573 -400.885452) (xy 386.358083 -400.885452)
			(xy 386.358083 -400.830948) (xy 386.365841 -400.776998) (xy 386.381197 -400.724702) (xy 386.40384 -400.675123)
			(xy 386.433309 -400.629272) (xy 386.469003 -400.588082) (xy 386.510196 -400.552391) (xy 386.55605 -400.522926)
			(xy 386.60563 -400.500286) (xy 386.657928 -400.484934) (xy 386.711878 -400.477181) (xy 386.73913 -400.47672)
			(xy 387.60273 -400.47672) (xy 387.629982 -400.477152) (xy 387.68393 -400.484912) (xy 387.736225 -400.500271)
			(xy 387.785802 -400.522916) (xy 387.831652 -400.552385) (xy 387.872842 -400.588079) (xy 387.908533 -400.629272)
			(xy 387.937999 -400.675124) (xy 387.960639 -400.724703) (xy 387.975994 -400.776999) (xy 387.98375 -400.830948)
			(xy 387.98375 -400.885448) (xy 389.421406 -400.885448) (xy 389.421406 -400.830952) (xy 389.429161 -400.777011)
			(xy 389.444514 -400.724723) (xy 389.467151 -400.675151) (xy 389.496612 -400.629306) (xy 389.532298 -400.588119)
			(xy 389.573481 -400.55243) (xy 389.619325 -400.522965) (xy 389.668894 -400.500324) (xy 389.721182 -400.484968)
			(xy 389.775122 -400.477208) (xy 389.80237 -400.47672) (xy 390.66597 -400.47672) (xy 390.693226 -400.477125)
			(xy 390.747184 -400.484879) (xy 390.79949 -400.500234) (xy 390.849077 -400.522876) (xy 390.894938 -400.552345)
			(xy 390.936137 -400.588042) (xy 390.971837 -400.629238) (xy 391.00131 -400.675096) (xy 391.023956 -400.724682)
			(xy 391.039315 -400.776986) (xy 391.047073 -400.830944) (xy 391.047073 -400.885451) (xy 392.484583 -400.885451)
			(xy 392.484583 -400.830949) (xy 392.49234 -400.777001) (xy 392.507695 -400.724706) (xy 392.530337 -400.675129)
			(xy 392.559804 -400.629279) (xy 392.595496 -400.588089) (xy 392.636687 -400.552398) (xy 392.682538 -400.522932)
			(xy 392.732115 -400.500292) (xy 392.784411 -400.484938) (xy 392.838359 -400.477183) (xy 392.86561 -400.47672)
			(xy 393.72921 -400.47672) (xy 393.756463 -400.477151) (xy 393.810413 -400.484909) (xy 393.862711 -400.500266)
			(xy 393.91229 -400.522909) (xy 393.958143 -400.552378) (xy 393.999335 -400.588072) (xy 394.035028 -400.629265)
			(xy 394.064496 -400.675118) (xy 394.087138 -400.724699) (xy 394.102493 -400.776996) (xy 394.11025 -400.830947)
			(xy 394.11025 -400.885447) (xy 395.547906 -400.885447) (xy 395.547906 -400.830953) (xy 395.555661 -400.777014)
			(xy 395.571012 -400.724727) (xy 395.593648 -400.675157) (xy 395.623107 -400.629312) (xy 395.658791 -400.588126)
			(xy 395.699972 -400.552437) (xy 395.745813 -400.522972) (xy 395.79538 -400.50033) (xy 395.847665 -400.484971)
			(xy 395.901603 -400.47721) (xy 395.92885 -400.47672) (xy 396.79245 -400.47672) (xy 396.819707 -400.477124)
			(xy 396.873668 -400.484875) (xy 396.925975 -400.500228) (xy 396.975565 -400.522869) (xy 397.021428 -400.552338)
			(xy 397.06263 -400.588035) (xy 397.098332 -400.629232) (xy 397.127807 -400.675091) (xy 397.150454 -400.724678)
			(xy 397.165814 -400.776983) (xy 397.173573 -400.830943) (xy 397.173573 -400.885449) (xy 398.611106 -400.885449)
			(xy 398.611106 -400.830951) (xy 398.618862 -400.777008) (xy 398.634215 -400.724718) (xy 398.656854 -400.675145)
			(xy 398.686317 -400.629299) (xy 398.722005 -400.588112) (xy 398.763191 -400.552423) (xy 398.809037 -400.522959)
			(xy 398.858609 -400.500319) (xy 398.910899 -400.484964) (xy 398.964841 -400.477207) (xy 398.99209 -400.47672)
			(xy 399.85569 -400.47672) (xy 399.882945 -400.477126) (xy 399.936901 -400.484883) (xy 399.989204 -400.500239)
			(xy 400.038789 -400.522883) (xy 400.084647 -400.552352) (xy 400.125844 -400.588049) (xy 400.161542 -400.629245)
			(xy 400.191013 -400.675102) (xy 400.213658 -400.724686) (xy 400.229015 -400.776989) (xy 400.236773 -400.830945)
			(xy 400.236773 -400.885452) (xy 401.674283 -400.885452) (xy 401.674283 -400.830948) (xy 401.682041 -400.776998)
			(xy 401.697397 -400.724702) (xy 401.72004 -400.675123) (xy 401.749509 -400.629272) (xy 401.785203 -400.588082)
			(xy 401.826396 -400.552391) (xy 401.87225 -400.522926) (xy 401.92183 -400.500286) (xy 401.974128 -400.484934)
			(xy 402.028078 -400.477181) (xy 402.05533 -400.47672) (xy 402.91893 -400.47672) (xy 402.946182 -400.477152)
			(xy 403.00013 -400.484912) (xy 403.052425 -400.500271) (xy 403.102002 -400.522916) (xy 403.147852 -400.552385)
			(xy 403.189042 -400.588079) (xy 403.224733 -400.629272) (xy 403.254199 -400.675124) (xy 403.276839 -400.724703)
			(xy 403.292194 -400.776999) (xy 403.29995 -400.830948) (xy 403.29995 -400.885448) (xy 404.737606 -400.885448)
			(xy 404.737606 -400.830952) (xy 404.745361 -400.777011) (xy 404.760714 -400.724723) (xy 404.783351 -400.675151)
			(xy 404.812812 -400.629306) (xy 404.848498 -400.588119) (xy 404.889681 -400.55243) (xy 404.935525 -400.522965)
			(xy 404.985094 -400.500324) (xy 405.037382 -400.484968) (xy 405.091322 -400.477208) (xy 405.11857 -400.47672)
			(xy 405.98217 -400.47672) (xy 406.009426 -400.477125) (xy 406.063384 -400.484879) (xy 406.11569 -400.500234)
			(xy 406.165277 -400.522876) (xy 406.211138 -400.552345) (xy 406.252337 -400.588042) (xy 406.288037 -400.629238)
			(xy 406.31751 -400.675096) (xy 406.340156 -400.724682) (xy 406.355515 -400.776986) (xy 406.363273 -400.830944)
			(xy 406.363273 -400.885451) (xy 407.800783 -400.885451) (xy 407.800783 -400.830949) (xy 407.80854 -400.777001)
			(xy 407.823895 -400.724706) (xy 407.846537 -400.675129) (xy 407.876004 -400.629279) (xy 407.911696 -400.588089)
			(xy 407.952887 -400.552398) (xy 407.998738 -400.522932) (xy 408.048315 -400.500292) (xy 408.100611 -400.484938)
			(xy 408.154559 -400.477183) (xy 408.18181 -400.47672) (xy 409.04541 -400.47672) (xy 409.072663 -400.477151)
			(xy 409.126613 -400.484909) (xy 409.178911 -400.500266) (xy 409.22849 -400.522909) (xy 409.274343 -400.552378)
			(xy 409.315535 -400.588072) (xy 409.351228 -400.629265) (xy 409.380696 -400.675118) (xy 409.403338 -400.724699)
			(xy 409.418693 -400.776996) (xy 409.42645 -400.830947) (xy 409.42645 -400.885447) (xy 410.864106 -400.885447)
			(xy 410.864106 -400.830953) (xy 410.871861 -400.777014) (xy 410.887212 -400.724727) (xy 410.909848 -400.675157)
			(xy 410.939307 -400.629312) (xy 410.974991 -400.588126) (xy 411.016172 -400.552437) (xy 411.062013 -400.522972)
			(xy 411.11158 -400.50033) (xy 411.163865 -400.484971) (xy 411.217803 -400.47721) (xy 411.24505 -400.47672)
			(xy 412.10865 -400.47672) (xy 412.135907 -400.477124) (xy 412.189868 -400.484875) (xy 412.242175 -400.500228)
			(xy 412.291765 -400.522869) (xy 412.337628 -400.552338) (xy 412.37883 -400.588035) (xy 412.414532 -400.629232)
			(xy 412.444007 -400.675091) (xy 412.466654 -400.724678) (xy 412.482014 -400.776983) (xy 412.489773 -400.830943)
			(xy 412.489773 -400.885449) (xy 413.927306 -400.885449) (xy 413.927306 -400.830951) (xy 413.935062 -400.777008)
			(xy 413.950415 -400.724718) (xy 413.973054 -400.675145) (xy 414.002517 -400.629299) (xy 414.038205 -400.588112)
			(xy 414.079391 -400.552423) (xy 414.125237 -400.522959) (xy 414.174809 -400.500319) (xy 414.227099 -400.484964)
			(xy 414.281041 -400.477207) (xy 414.30829 -400.47672) (xy 415.17189 -400.47672) (xy 415.199145 -400.477126)
			(xy 415.253101 -400.484883) (xy 415.305404 -400.500239) (xy 415.354989 -400.522883) (xy 415.400847 -400.552352)
			(xy 415.442044 -400.588049) (xy 415.477742 -400.629245) (xy 415.507213 -400.675102) (xy 415.529858 -400.724686)
			(xy 415.545215 -400.776989) (xy 415.552973 -400.830945) (xy 415.552973 -400.885452) (xy 416.990483 -400.885452)
			(xy 416.990483 -400.830948) (xy 416.998241 -400.776998) (xy 417.013597 -400.724702) (xy 417.03624 -400.675123)
			(xy 417.065709 -400.629272) (xy 417.101403 -400.588082) (xy 417.142596 -400.552391) (xy 417.18845 -400.522926)
			(xy 417.23803 -400.500286) (xy 417.290328 -400.484934) (xy 417.344278 -400.477181) (xy 417.37153 -400.47672)
			(xy 418.23513 -400.47672) (xy 418.262382 -400.477152) (xy 418.31633 -400.484912) (xy 418.368625 -400.500271)
			(xy 418.418202 -400.522916) (xy 418.464052 -400.552385) (xy 418.505242 -400.588079) (xy 418.540933 -400.629272)
			(xy 418.570399 -400.675124) (xy 418.593039 -400.724703) (xy 418.608394 -400.776999) (xy 418.61615 -400.830948)
			(xy 418.61615 -400.885452) (xy 418.608394 -400.939401) (xy 418.593039 -400.991697) (xy 418.570399 -401.041276)
			(xy 418.540933 -401.087128) (xy 418.505242 -401.128321) (xy 418.464052 -401.164015) (xy 418.418202 -401.193484)
			(xy 418.368625 -401.216129) (xy 418.31633 -401.231488) (xy 418.262382 -401.239248) (xy 418.23513 -401.239736)
			(xy 417.37153 -401.239736) (xy 417.344278 -401.239219) (xy 417.290328 -401.231466) (xy 417.23803 -401.216114)
			(xy 417.18845 -401.193474) (xy 417.142596 -401.164009) (xy 417.101403 -401.128318) (xy 417.065709 -401.087128)
			(xy 417.03624 -401.041277) (xy 417.013597 -400.991698) (xy 416.998241 -400.939402) (xy 416.990483 -400.885452)
			(xy 415.552973 -400.885452) (xy 415.552973 -400.885455) (xy 415.545215 -400.939411) (xy 415.529858 -400.991714)
			(xy 415.507213 -401.041298) (xy 415.477742 -401.087155) (xy 415.442044 -401.128351) (xy 415.400847 -401.164048)
			(xy 415.354989 -401.193517) (xy 415.305404 -401.216161) (xy 415.253101 -401.231517) (xy 415.199145 -401.239274)
			(xy 415.17189 -401.239736) (xy 414.30829 -401.239736) (xy 414.281041 -401.239193) (xy 414.227099 -401.231436)
			(xy 414.174809 -401.216081) (xy 414.125237 -401.193441) (xy 414.079391 -401.163977) (xy 414.038205 -401.128288)
			(xy 414.002517 -401.087101) (xy 413.973054 -401.041255) (xy 413.950415 -400.991682) (xy 413.935062 -400.939392)
			(xy 413.927306 -400.885449) (xy 412.489773 -400.885449) (xy 412.489773 -400.885457) (xy 412.482014 -400.939416)
			(xy 412.466654 -400.991722) (xy 412.444007 -401.041309) (xy 412.414532 -401.087168) (xy 412.37883 -401.128365)
			(xy 412.337628 -401.164062) (xy 412.291765 -401.193531) (xy 412.242175 -401.216172) (xy 412.189868 -401.231525)
			(xy 412.135907 -401.239276) (xy 412.10865 -401.239736) (xy 411.24505 -401.239736) (xy 411.217803 -401.23919)
			(xy 411.163865 -401.231429) (xy 411.11158 -401.21607) (xy 411.062013 -401.193428) (xy 411.016172 -401.163963)
			(xy 410.974991 -401.128274) (xy 410.939307 -401.087088) (xy 410.909848 -401.041243) (xy 410.887212 -400.991673)
			(xy 410.871861 -400.939386) (xy 410.864106 -400.885447) (xy 409.42645 -400.885447) (xy 409.42645 -400.885453)
			(xy 409.418693 -400.939404) (xy 409.403338 -400.991701) (xy 409.380696 -401.041282) (xy 409.351228 -401.087135)
			(xy 409.315535 -401.128328) (xy 409.274343 -401.164022) (xy 409.22849 -401.193491) (xy 409.178911 -401.216134)
			(xy 409.126613 -401.231491) (xy 409.072663 -401.239249) (xy 409.04541 -401.239736) (xy 408.18181 -401.239736)
			(xy 408.154559 -401.239217) (xy 408.100611 -401.231462) (xy 408.048315 -401.216108) (xy 407.998738 -401.193468)
			(xy 407.952887 -401.164002) (xy 407.911696 -401.128311) (xy 407.876004 -401.087121) (xy 407.846537 -401.041271)
			(xy 407.823895 -400.991694) (xy 407.80854 -400.939399) (xy 407.800783 -400.885451) (xy 406.363273 -400.885451)
			(xy 406.363273 -400.885456) (xy 406.355515 -400.939414) (xy 406.340156 -400.991718) (xy 406.31751 -401.041304)
			(xy 406.288037 -401.087162) (xy 406.252337 -401.128358) (xy 406.211138 -401.164055) (xy 406.165277 -401.193524)
			(xy 406.11569 -401.216166) (xy 406.063384 -401.231521) (xy 406.009426 -401.239275) (xy 405.98217 -401.239736)
			(xy 405.11857 -401.239736) (xy 405.091322 -401.239192) (xy 405.037382 -401.231432) (xy 404.985094 -401.216076)
			(xy 404.935525 -401.193435) (xy 404.889682 -401.16397) (xy 404.848498 -401.128281) (xy 404.812812 -401.087094)
			(xy 404.783351 -401.041249) (xy 404.760714 -400.991677) (xy 404.745361 -400.939389) (xy 404.737606 -400.885448)
			(xy 403.29995 -400.885448) (xy 403.29995 -400.885452) (xy 403.292194 -400.939401) (xy 403.276839 -400.991697)
			(xy 403.254199 -401.041276) (xy 403.224733 -401.087128) (xy 403.189042 -401.128321) (xy 403.147852 -401.164015)
			(xy 403.102002 -401.193484) (xy 403.052425 -401.216129) (xy 403.00013 -401.231488) (xy 402.946182 -401.239248)
			(xy 402.91893 -401.239736) (xy 402.05533 -401.239736) (xy 402.028078 -401.239219) (xy 401.974128 -401.231466)
			(xy 401.92183 -401.216114) (xy 401.87225 -401.193474) (xy 401.826396 -401.164009) (xy 401.785203 -401.128318)
			(xy 401.749509 -401.087128) (xy 401.72004 -401.041277) (xy 401.697397 -400.991698) (xy 401.682041 -400.939402)
			(xy 401.674283 -400.885452) (xy 400.236773 -400.885452) (xy 400.236773 -400.885455) (xy 400.229015 -400.939411)
			(xy 400.213658 -400.991714) (xy 400.191013 -401.041298) (xy 400.161542 -401.087155) (xy 400.125844 -401.128351)
			(xy 400.084647 -401.164048) (xy 400.038789 -401.193517) (xy 399.989204 -401.216161) (xy 399.936901 -401.231517)
			(xy 399.882945 -401.239274) (xy 399.85569 -401.239736) (xy 398.99209 -401.239736) (xy 398.964841 -401.239193)
			(xy 398.910899 -401.231436) (xy 398.858609 -401.216081) (xy 398.809037 -401.193441) (xy 398.763191 -401.163977)
			(xy 398.722005 -401.128288) (xy 398.686317 -401.087101) (xy 398.656854 -401.041255) (xy 398.634215 -400.991682)
			(xy 398.618862 -400.939392) (xy 398.611106 -400.885449) (xy 397.173573 -400.885449) (xy 397.173573 -400.885457)
			(xy 397.165814 -400.939416) (xy 397.150454 -400.991722) (xy 397.127807 -401.041309) (xy 397.098332 -401.087168)
			(xy 397.06263 -401.128365) (xy 397.021428 -401.164062) (xy 396.975565 -401.193531) (xy 396.925975 -401.216172)
			(xy 396.873668 -401.231525) (xy 396.819707 -401.239276) (xy 396.79245 -401.239736) (xy 395.92885 -401.239736)
			(xy 395.901603 -401.23919) (xy 395.847665 -401.231429) (xy 395.79538 -401.21607) (xy 395.745813 -401.193428)
			(xy 395.699972 -401.163963) (xy 395.658791 -401.128274) (xy 395.623107 -401.087088) (xy 395.593648 -401.041243)
			(xy 395.571012 -400.991673) (xy 395.555661 -400.939386) (xy 395.547906 -400.885447) (xy 394.11025 -400.885447)
			(xy 394.11025 -400.885453) (xy 394.102493 -400.939404) (xy 394.087138 -400.991701) (xy 394.064496 -401.041282)
			(xy 394.035028 -401.087135) (xy 393.999335 -401.128328) (xy 393.958143 -401.164022) (xy 393.91229 -401.193491)
			(xy 393.862711 -401.216134) (xy 393.810413 -401.231491) (xy 393.756463 -401.239249) (xy 393.72921 -401.239736)
			(xy 392.86561 -401.239736) (xy 392.838359 -401.239217) (xy 392.784411 -401.231462) (xy 392.732115 -401.216108)
			(xy 392.682538 -401.193468) (xy 392.636687 -401.164002) (xy 392.595496 -401.128311) (xy 392.559804 -401.087121)
			(xy 392.530337 -401.041271) (xy 392.507695 -400.991694) (xy 392.49234 -400.939399) (xy 392.484583 -400.885451)
			(xy 391.047073 -400.885451) (xy 391.047073 -400.885456) (xy 391.039315 -400.939414) (xy 391.023956 -400.991718)
			(xy 391.00131 -401.041304) (xy 390.971837 -401.087162) (xy 390.936137 -401.128358) (xy 390.894938 -401.164055)
			(xy 390.849077 -401.193524) (xy 390.79949 -401.216166) (xy 390.747184 -401.231521) (xy 390.693226 -401.239275)
			(xy 390.66597 -401.239736) (xy 389.80237 -401.239736) (xy 389.775122 -401.239192) (xy 389.721182 -401.231432)
			(xy 389.668894 -401.216076) (xy 389.619325 -401.193435) (xy 389.573482 -401.16397) (xy 389.532298 -401.128281)
			(xy 389.496612 -401.087094) (xy 389.467151 -401.041249) (xy 389.444514 -400.991677) (xy 389.429161 -400.939389)
			(xy 389.421406 -400.885448) (xy 387.98375 -400.885448) (xy 387.98375 -400.885452) (xy 387.975994 -400.939401)
			(xy 387.960639 -400.991697) (xy 387.937999 -401.041276) (xy 387.908533 -401.087128) (xy 387.872842 -401.128321)
			(xy 387.831652 -401.164015) (xy 387.785802 -401.193484) (xy 387.736225 -401.216129) (xy 387.68393 -401.231488)
			(xy 387.629982 -401.239248) (xy 387.60273 -401.239736) (xy 386.73913 -401.239736) (xy 386.711878 -401.239219)
			(xy 386.657928 -401.231466) (xy 386.60563 -401.216114) (xy 386.55605 -401.193474) (xy 386.510196 -401.164009)
			(xy 386.469003 -401.128318) (xy 386.433309 -401.087128) (xy 386.40384 -401.041277) (xy 386.381197 -400.991698)
			(xy 386.365841 -400.939402) (xy 386.358083 -400.885452) (xy 384.920573 -400.885452) (xy 384.920573 -400.885455)
			(xy 384.912815 -400.939411) (xy 384.897458 -400.991714) (xy 384.874813 -401.041298) (xy 384.845342 -401.087155)
			(xy 384.809644 -401.128351) (xy 384.768447 -401.164048) (xy 384.722589 -401.193517) (xy 384.673004 -401.216161)
			(xy 384.620701 -401.231517) (xy 384.566745 -401.239274) (xy 384.53949 -401.239736) (xy 383.67589 -401.239736)
			(xy 383.648641 -401.239193) (xy 383.594699 -401.231436) (xy 383.542409 -401.216081) (xy 383.492837 -401.193441)
			(xy 383.446991 -401.163977) (xy 383.405805 -401.128288) (xy 383.370117 -401.087101) (xy 383.340654 -401.041255)
			(xy 383.318015 -400.991682) (xy 383.302662 -400.939392) (xy 383.294906 -400.885449) (xy 381.857373 -400.885449)
			(xy 381.857373 -400.885457) (xy 381.849614 -400.939416) (xy 381.834254 -400.991722) (xy 381.811607 -401.041309)
			(xy 381.782132 -401.087168) (xy 381.74643 -401.128365) (xy 381.705228 -401.164062) (xy 381.659365 -401.193531)
			(xy 381.609775 -401.216172) (xy 381.557468 -401.231525) (xy 381.503507 -401.239276) (xy 381.47625 -401.239736)
			(xy 380.61265 -401.239736) (xy 380.585403 -401.23919) (xy 380.531465 -401.231429) (xy 380.47918 -401.21607)
			(xy 380.429613 -401.193428) (xy 380.383772 -401.163963) (xy 380.342591 -401.128274) (xy 380.306907 -401.087088)
			(xy 380.277448 -401.041243) (xy 380.254812 -400.991673) (xy 380.239461 -400.939386) (xy 380.231706 -400.885447)
			(xy 378.79405 -400.885447) (xy 378.79405 -400.885453) (xy 378.786293 -400.939404) (xy 378.770938 -400.991701)
			(xy 378.748296 -401.041282) (xy 378.718828 -401.087135) (xy 378.683135 -401.128328) (xy 378.641943 -401.164022)
			(xy 378.59609 -401.193491) (xy 378.546511 -401.216134) (xy 378.494213 -401.231491) (xy 378.440263 -401.239249)
			(xy 378.41301 -401.239736) (xy 377.54941 -401.239736) (xy 377.522159 -401.239217) (xy 377.468211 -401.231462)
			(xy 377.415915 -401.216108) (xy 377.366338 -401.193468) (xy 377.320487 -401.164002) (xy 377.279296 -401.128311)
			(xy 377.243604 -401.087121) (xy 377.214137 -401.041271) (xy 377.191495 -400.991694) (xy 377.17614 -400.939399)
			(xy 377.168383 -400.885451) (xy 375.730873 -400.885451) (xy 375.730873 -400.885456) (xy 375.723115 -400.939414)
			(xy 375.707756 -400.991718) (xy 375.68511 -401.041304) (xy 375.655637 -401.087162) (xy 375.619937 -401.128358)
			(xy 375.578738 -401.164055) (xy 375.532877 -401.193524) (xy 375.48329 -401.216166) (xy 375.430984 -401.231521)
			(xy 375.377026 -401.239275) (xy 375.34977 -401.239736) (xy 374.48617 -401.239736) (xy 374.458922 -401.239192)
			(xy 374.404982 -401.231432) (xy 374.352694 -401.216076) (xy 374.303125 -401.193435) (xy 374.257282 -401.16397)
			(xy 374.216098 -401.128281) (xy 374.180412 -401.087094) (xy 374.150951 -401.041249) (xy 374.128314 -400.991677)
			(xy 374.112961 -400.939389) (xy 374.105206 -400.885448) (xy 372.66755 -400.885448) (xy 372.66755 -400.885452)
			(xy 372.659794 -400.939401) (xy 372.644439 -400.991697) (xy 372.621799 -401.041276) (xy 372.592333 -401.087128)
			(xy 372.556642 -401.128321) (xy 372.515452 -401.164015) (xy 372.469602 -401.193484) (xy 372.420025 -401.216129)
			(xy 372.36773 -401.231488) (xy 372.313782 -401.239248) (xy 372.28653 -401.239736) (xy 371.42293 -401.239736)
			(xy 371.395678 -401.239219) (xy 371.341728 -401.231466) (xy 371.28943 -401.216114) (xy 371.23985 -401.193474)
			(xy 371.193996 -401.164009) (xy 371.152803 -401.128318) (xy 371.117109 -401.087128) (xy 371.08764 -401.041277)
			(xy 371.064997 -400.991698) (xy 371.049641 -400.939402) (xy 371.041883 -400.885452) (xy 351.173373 -400.885452)
			(xy 351.173373 -400.885455) (xy 351.165615 -400.939411) (xy 351.150257 -400.991714) (xy 351.127612 -401.041299)
			(xy 351.098141 -401.087156) (xy 351.062443 -401.128352) (xy 351.021246 -401.164048) (xy 350.975388 -401.193518)
			(xy 350.925803 -401.216162) (xy 350.8735 -401.231518) (xy 350.819543 -401.239274) (xy 350.792288 -401.239736)
			(xy 349.928688 -401.239736) (xy 349.901439 -401.239193) (xy 349.847497 -401.231436) (xy 349.795208 -401.216081)
			(xy 349.745636 -401.19344) (xy 349.69979 -401.163976) (xy 349.658604 -401.128287) (xy 349.622917 -401.0871)
			(xy 349.593454 -401.041254) (xy 349.570815 -400.991681) (xy 349.555462 -400.939391) (xy 349.547706 -400.885449)
			(xy 348.11005 -400.885449) (xy 348.11005 -400.885451) (xy 348.102294 -400.939399) (xy 348.086941 -400.991693)
			(xy 348.064301 -401.041271) (xy 348.034837 -401.087122) (xy 347.999148 -401.128314) (xy 347.957961 -401.164009)
			(xy 347.912113 -401.193478) (xy 347.862538 -401.216124) (xy 347.810245 -401.231484) (xy 347.756299 -401.239247)
			(xy 347.729048 -401.239736) (xy 346.865448 -401.239736) (xy 346.838195 -401.23922) (xy 346.784243 -401.231469)
			(xy 346.731943 -401.216118) (xy 346.68236 -401.19348) (xy 346.636505 -401.164016) (xy 346.595309 -401.128325)
			(xy 346.559613 -401.087134) (xy 346.530143 -401.041282) (xy 346.507498 -400.991702) (xy 346.492141 -400.939404)
			(xy 346.484383 -400.885453) (xy 345.04685 -400.885453) (xy 345.039093 -400.939404) (xy 345.023737 -400.991702)
			(xy 345.001095 -401.041282) (xy 344.971628 -401.087136) (xy 344.935934 -401.128329) (xy 344.894742 -401.164023)
			(xy 344.848889 -401.193491) (xy 344.799309 -401.216135) (xy 344.747012 -401.231492) (xy 344.693061 -401.23925)
			(xy 344.665808 -401.239736) (xy 343.802208 -401.239736) (xy 343.774957 -401.239217) (xy 343.721009 -401.231462)
			(xy 343.668714 -401.216108) (xy 343.619136 -401.193467) (xy 343.573286 -401.164002) (xy 343.532095 -401.128311)
			(xy 343.496403 -401.087121) (xy 343.466937 -401.041271) (xy 343.444295 -400.991694) (xy 343.42894 -400.939399)
			(xy 343.421183 -400.885451) (xy 341.983673 -400.885451) (xy 341.983673 -400.885456) (xy 341.975915 -400.939414)
			(xy 341.960556 -400.991718) (xy 341.937909 -401.041304) (xy 341.908436 -401.087162) (xy 341.872736 -401.128359)
			(xy 341.831537 -401.164055) (xy 341.785676 -401.193525) (xy 341.736088 -401.216167) (xy 341.683783 -401.231521)
			(xy 341.629824 -401.239275) (xy 341.602568 -401.239736) (xy 340.738968 -401.239736) (xy 340.71172 -401.239192)
			(xy 340.65778 -401.231432) (xy 340.605493 -401.216075) (xy 340.555924 -401.193434) (xy 340.510081 -401.163969)
			(xy 340.468897 -401.12828) (xy 340.433212 -401.087094) (xy 340.403751 -401.041248) (xy 340.381114 -400.991677)
			(xy 340.365761 -400.939389) (xy 340.358006 -400.885448) (xy 338.92035 -400.885448) (xy 338.92035 -400.885452)
			(xy 338.912594 -400.939401) (xy 338.897239 -400.991698) (xy 338.874598 -401.041277) (xy 338.845132 -401.087129)
			(xy 338.809441 -401.128321) (xy 338.768251 -401.164016) (xy 338.722401 -401.193485) (xy 338.672824 -401.216129)
			(xy 338.620529 -401.231488) (xy 338.56658 -401.239248) (xy 338.539328 -401.239736) (xy 337.675728 -401.239736)
			(xy 337.648476 -401.239219) (xy 337.594526 -401.231465) (xy 337.542228 -401.216113) (xy 337.492648 -401.193474)
			(xy 337.446795 -401.164009) (xy 337.405602 -401.128318) (xy 337.369908 -401.087127) (xy 337.34044 -401.041276)
			(xy 337.317797 -400.991698) (xy 337.30244 -400.939402) (xy 337.294683 -400.885452) (xy 335.857173 -400.885452)
			(xy 335.857173 -400.885455) (xy 335.849415 -400.939411) (xy 335.834057 -400.991714) (xy 335.811412 -401.041299)
			(xy 335.781941 -401.087156) (xy 335.746243 -401.128352) (xy 335.705046 -401.164048) (xy 335.659188 -401.193518)
			(xy 335.609603 -401.216162) (xy 335.5573 -401.231518) (xy 335.503343 -401.239274) (xy 335.476088 -401.239736)
			(xy 334.612488 -401.239736) (xy 334.585239 -401.239193) (xy 334.531297 -401.231436) (xy 334.479008 -401.216081)
			(xy 334.429436 -401.19344) (xy 334.38359 -401.163976) (xy 334.342404 -401.128287) (xy 334.306717 -401.0871)
			(xy 334.277254 -401.041254) (xy 334.254615 -400.991681) (xy 334.239262 -400.939391) (xy 334.231506 -400.885449)
			(xy 332.79385 -400.885449) (xy 332.79385 -400.885451) (xy 332.786094 -400.939399) (xy 332.770741 -400.991693)
			(xy 332.748101 -401.041271) (xy 332.718637 -401.087122) (xy 332.682948 -401.128314) (xy 332.641761 -401.164009)
			(xy 332.595913 -401.193478) (xy 332.546338 -401.216124) (xy 332.494045 -401.231484) (xy 332.440099 -401.239247)
			(xy 332.412848 -401.239736) (xy 331.549248 -401.239736) (xy 331.521995 -401.23922) (xy 331.468043 -401.231469)
			(xy 331.415743 -401.216118) (xy 331.36616 -401.19348) (xy 331.320305 -401.164016) (xy 331.279109 -401.128325)
			(xy 331.243413 -401.087134) (xy 331.213943 -401.041282) (xy 331.191298 -400.991702) (xy 331.175941 -400.939404)
			(xy 331.168183 -400.885453) (xy 329.73065 -400.885453) (xy 329.722893 -400.939404) (xy 329.707537 -400.991702)
			(xy 329.684895 -401.041282) (xy 329.655428 -401.087136) (xy 329.619734 -401.128329) (xy 329.578542 -401.164023)
			(xy 329.532689 -401.193491) (xy 329.483109 -401.216135) (xy 329.430812 -401.231492) (xy 329.376861 -401.23925)
			(xy 329.349608 -401.239736) (xy 328.486008 -401.239736) (xy 328.458757 -401.239217) (xy 328.404809 -401.231462)
			(xy 328.352514 -401.216108) (xy 328.302936 -401.193467) (xy 328.257086 -401.164002) (xy 328.215895 -401.128311)
			(xy 328.180203 -401.087121) (xy 328.150737 -401.041271) (xy 328.128095 -400.991694) (xy 328.11274 -400.939399)
			(xy 328.104983 -400.885451) (xy 326.667473 -400.885451) (xy 326.667473 -400.885456) (xy 326.659715 -400.939414)
			(xy 326.644356 -400.991718) (xy 326.621709 -401.041304) (xy 326.592236 -401.087162) (xy 326.556536 -401.128359)
			(xy 326.515337 -401.164055) (xy 326.469476 -401.193525) (xy 326.419888 -401.216167) (xy 326.367583 -401.231521)
			(xy 326.313624 -401.239275) (xy 326.286368 -401.239736) (xy 325.422768 -401.239736) (xy 325.39552 -401.239192)
			(xy 325.34158 -401.231432) (xy 325.289293 -401.216075) (xy 325.239724 -401.193434) (xy 325.193881 -401.163969)
			(xy 325.152697 -401.12828) (xy 325.117012 -401.087094) (xy 325.087551 -401.041248) (xy 325.064914 -400.991677)
			(xy 325.049561 -400.939389) (xy 325.041806 -400.885448) (xy 323.60415 -400.885448) (xy 323.60415 -400.885452)
			(xy 323.596394 -400.939401) (xy 323.581039 -400.991698) (xy 323.558398 -401.041277) (xy 323.528932 -401.087129)
			(xy 323.493241 -401.128321) (xy 323.452051 -401.164016) (xy 323.406201 -401.193485) (xy 323.356624 -401.216129)
			(xy 323.304329 -401.231488) (xy 323.25038 -401.239248) (xy 323.223128 -401.239736) (xy 322.359528 -401.239736)
			(xy 322.332276 -401.239219) (xy 322.278326 -401.231465) (xy 322.226028 -401.216113) (xy 322.176448 -401.193474)
			(xy 322.130595 -401.164009) (xy 322.089402 -401.128318) (xy 322.053708 -401.087127) (xy 322.02424 -401.041276)
			(xy 322.001597 -400.991698) (xy 321.98624 -400.939402) (xy 321.978483 -400.885452) (xy 320.540973 -400.885452)
			(xy 320.540973 -400.885455) (xy 320.533215 -400.939411) (xy 320.517857 -400.991714) (xy 320.495212 -401.041299)
			(xy 320.465741 -401.087156) (xy 320.430043 -401.128352) (xy 320.388846 -401.164048) (xy 320.342988 -401.193518)
			(xy 320.293403 -401.216162) (xy 320.2411 -401.231518) (xy 320.187143 -401.239274) (xy 320.159888 -401.239736)
			(xy 319.296288 -401.239736) (xy 319.269039 -401.239193) (xy 319.215097 -401.231436) (xy 319.162808 -401.216081)
			(xy 319.113236 -401.19344) (xy 319.06739 -401.163976) (xy 319.026204 -401.128287) (xy 318.990517 -401.0871)
			(xy 318.961054 -401.041254) (xy 318.938415 -400.991681) (xy 318.923062 -400.939391) (xy 318.915306 -400.885449)
			(xy 317.47765 -400.885449) (xy 317.47765 -400.885451) (xy 317.469894 -400.939399) (xy 317.454541 -400.991693)
			(xy 317.431901 -401.041271) (xy 317.402437 -401.087122) (xy 317.366748 -401.128314) (xy 317.325561 -401.164009)
			(xy 317.279713 -401.193478) (xy 317.230138 -401.216124) (xy 317.177845 -401.231484) (xy 317.123899 -401.239247)
			(xy 317.096648 -401.239736) (xy 316.233048 -401.239736) (xy 316.205795 -401.23922) (xy 316.151843 -401.231469)
			(xy 316.099543 -401.216118) (xy 316.04996 -401.19348) (xy 316.004105 -401.164016) (xy 315.962909 -401.128325)
			(xy 315.927213 -401.087134) (xy 315.897743 -401.041282) (xy 315.875098 -400.991702) (xy 315.859741 -400.939404)
			(xy 315.851983 -400.885453) (xy 314.41445 -400.885453) (xy 314.406693 -400.939404) (xy 314.391337 -400.991702)
			(xy 314.368695 -401.041282) (xy 314.339228 -401.087136) (xy 314.303534 -401.128329) (xy 314.262342 -401.164023)
			(xy 314.216489 -401.193491) (xy 314.166909 -401.216135) (xy 314.114612 -401.231492) (xy 314.060661 -401.23925)
			(xy 314.033408 -401.239736) (xy 313.169808 -401.239736) (xy 313.142557 -401.239217) (xy 313.088609 -401.231462)
			(xy 313.036314 -401.216108) (xy 312.986736 -401.193467) (xy 312.940886 -401.164002) (xy 312.899695 -401.128311)
			(xy 312.864003 -401.087121) (xy 312.834537 -401.041271) (xy 312.811895 -400.991694) (xy 312.79654 -400.939399)
			(xy 312.788783 -400.885451) (xy 311.351273 -400.885451) (xy 311.351273 -400.885456) (xy 311.343515 -400.939414)
			(xy 311.328156 -400.991718) (xy 311.305509 -401.041304) (xy 311.276036 -401.087162) (xy 311.240336 -401.128359)
			(xy 311.199137 -401.164055) (xy 311.153276 -401.193525) (xy 311.103688 -401.216167) (xy 311.051383 -401.231521)
			(xy 310.997424 -401.239275) (xy 310.970168 -401.239736) (xy 310.106568 -401.239736) (xy 310.07932 -401.239192)
			(xy 310.02538 -401.231432) (xy 309.973093 -401.216075) (xy 309.923524 -401.193434) (xy 309.877681 -401.163969)
			(xy 309.836497 -401.12828) (xy 309.800812 -401.087094) (xy 309.771351 -401.041248) (xy 309.748714 -400.991677)
			(xy 309.733361 -400.939389) (xy 309.725606 -400.885448) (xy 308.28795 -400.885448) (xy 308.28795 -400.885452)
			(xy 308.280194 -400.939401) (xy 308.264839 -400.991698) (xy 308.242198 -401.041277) (xy 308.212732 -401.087129)
			(xy 308.177041 -401.128321) (xy 308.135851 -401.164016) (xy 308.090001 -401.193485) (xy 308.040424 -401.216129)
			(xy 307.988129 -401.231488) (xy 307.93418 -401.239248) (xy 307.906928 -401.239736) (xy 307.043328 -401.239736)
			(xy 307.016076 -401.239219) (xy 306.962126 -401.231465) (xy 306.909828 -401.216113) (xy 306.860248 -401.193474)
			(xy 306.814395 -401.164009) (xy 306.773202 -401.128318) (xy 306.737508 -401.087127) (xy 306.70804 -401.041276)
			(xy 306.685397 -400.991698) (xy 306.67004 -400.939402) (xy 306.662283 -400.885452) (xy 305.224773 -400.885452)
			(xy 305.224773 -400.885455) (xy 305.217015 -400.939411) (xy 305.201657 -400.991714) (xy 305.179012 -401.041299)
			(xy 305.149541 -401.087156) (xy 305.113843 -401.128352) (xy 305.072646 -401.164048) (xy 305.026788 -401.193518)
			(xy 304.977203 -401.216162) (xy 304.9249 -401.231518) (xy 304.870943 -401.239274) (xy 304.843688 -401.239736)
			(xy 303.980088 -401.239736) (xy 303.952839 -401.239193) (xy 303.898897 -401.231436) (xy 303.846608 -401.216081)
			(xy 303.797036 -401.19344) (xy 303.75119 -401.163976) (xy 303.710004 -401.128287) (xy 303.674317 -401.0871)
			(xy 303.644854 -401.041254) (xy 303.622215 -400.991681) (xy 303.606862 -400.939391) (xy 303.599106 -400.885449)
			(xy 281.686508 -400.885449) (xy 281.686508 -402.0155) (xy 287.066441 -402.0155) (xy 287.070455 -401.951698)
			(xy 287.082434 -401.888902) (xy 287.102189 -401.828103) (xy 287.129408 -401.77026) (xy 287.163662 -401.716283)
			(xy 287.204411 -401.667026) (xy 287.251013 -401.623264) (xy 287.302731 -401.585688) (xy 287.358752 -401.55489)
			(xy 287.418191 -401.531357) (xy 287.48011 -401.515458) (xy 287.543534 -401.507446) (xy 287.575498 -401.506944)
			(xy 287.575752 -401.506944) (xy 287.607498 -401.507464) (xy 287.670494 -401.515393) (xy 287.732014 -401.531096)
			(xy 287.791102 -401.55433) (xy 287.846842 -401.584733) (xy 287.898367 -401.621834) (xy 287.921954 -401.643088)
			(xy 287.929217 -401.649272) (xy 287.946967 -401.656223) (xy 287.966029 -401.656223) (xy 287.983779 -401.649272)
			(xy 287.991042 -401.643088) (xy 288.014631 -401.621832) (xy 288.06614 -401.5847) (xy 288.121874 -401.554276)
			(xy 288.180965 -401.531035) (xy 288.242492 -401.515338) (xy 288.305495 -401.507431) (xy 288.337244 -401.506944)
			(xy 288.337498 -401.506944) (xy 288.369457 -401.507521) (xy 288.432872 -401.515532) (xy 288.494783 -401.531427)
			(xy 288.554213 -401.554957) (xy 288.610226 -401.58575) (xy 288.661937 -401.623321) (xy 288.708532 -401.667076)
			(xy 288.749276 -401.716326) (xy 288.783525 -401.770295) (xy 288.810741 -401.82813) (xy 288.830493 -401.888921)
			(xy 288.84247 -401.951707) (xy 288.846484 -402.0155) (xy 289.606441 -402.0155) (xy 289.610455 -401.951698)
			(xy 289.622434 -401.888902) (xy 289.642189 -401.828103) (xy 289.669408 -401.77026) (xy 289.703662 -401.716283)
			(xy 289.744411 -401.667026) (xy 289.791013 -401.623264) (xy 289.842731 -401.585688) (xy 289.898752 -401.55489)
			(xy 289.958191 -401.531357) (xy 290.02011 -401.515458) (xy 290.083534 -401.507446) (xy 290.115498 -401.506944)
			(xy 290.115752 -401.506944) (xy 290.147498 -401.507464) (xy 290.210494 -401.515393) (xy 290.272014 -401.531096)
			(xy 290.331102 -401.55433) (xy 290.386842 -401.584733) (xy 290.438367 -401.621834) (xy 290.461954 -401.643088)
			(xy 290.469217 -401.649272) (xy 290.486967 -401.656223) (xy 290.506029 -401.656223) (xy 290.523779 -401.649272)
			(xy 290.531042 -401.643088) (xy 290.554631 -401.621832) (xy 290.60614 -401.5847) (xy 290.661874 -401.554276)
			(xy 290.720965 -401.531035) (xy 290.782492 -401.515338) (xy 290.845495 -401.507431) (xy 290.877244 -401.506944)
			(xy 290.877498 -401.506944) (xy 290.909457 -401.507521) (xy 290.972872 -401.515532) (xy 291.034783 -401.531427)
			(xy 291.094213 -401.554957) (xy 291.150226 -401.58575) (xy 291.201937 -401.623321) (xy 291.248532 -401.667076)
			(xy 291.289276 -401.716326) (xy 291.323525 -401.770295) (xy 291.350741 -401.82813) (xy 291.370493 -401.888921)
			(xy 291.38247 -401.951707) (xy 291.386484 -402.0155) (xy 292.146441 -402.0155) (xy 292.150455 -401.951698)
			(xy 292.162434 -401.888902) (xy 292.182189 -401.828103) (xy 292.209408 -401.77026) (xy 292.243662 -401.716283)
			(xy 292.284411 -401.667026) (xy 292.331013 -401.623264) (xy 292.382731 -401.585688) (xy 292.438752 -401.55489)
			(xy 292.498191 -401.531357) (xy 292.56011 -401.515458) (xy 292.623534 -401.507446) (xy 292.655498 -401.506944)
			(xy 292.655752 -401.506944) (xy 292.687498 -401.507464) (xy 292.750494 -401.515393) (xy 292.812014 -401.531096)
			(xy 292.871102 -401.55433) (xy 292.926842 -401.584733) (xy 292.978367 -401.621834) (xy 293.001954 -401.643088)
			(xy 293.009217 -401.649272) (xy 293.026967 -401.656223) (xy 293.046029 -401.656223) (xy 293.063779 -401.649272)
			(xy 293.071042 -401.643088) (xy 293.094631 -401.621832) (xy 293.14614 -401.5847) (xy 293.201874 -401.554276)
			(xy 293.260965 -401.531035) (xy 293.322492 -401.515338) (xy 293.385495 -401.507431) (xy 293.417244 -401.506944)
			(xy 293.417498 -401.506944) (xy 293.449457 -401.507521) (xy 293.512872 -401.515532) (xy 293.574783 -401.531427)
			(xy 293.634213 -401.554957) (xy 293.690226 -401.58575) (xy 293.741937 -401.623321) (xy 293.788532 -401.667076)
			(xy 293.829276 -401.716326) (xy 293.863525 -401.770295) (xy 293.890741 -401.82813) (xy 293.910493 -401.888921)
			(xy 293.92247 -401.951707) (xy 293.926484 -402.0155) (xy 294.53602 -402.0155) (xy 294.540035 -401.951693)
			(xy 294.552015 -401.888892) (xy 294.571773 -401.828089) (xy 294.598995 -401.770241) (xy 294.633253 -401.716261)
			(xy 294.674007 -401.667001) (xy 294.720613 -401.623237) (xy 294.772338 -401.58566) (xy 294.828364 -401.554862)
			(xy 294.887809 -401.531329) (xy 294.949734 -401.515433) (xy 295.013163 -401.507423) (xy 295.04513 -401.506944)
			(xy 295.045384 -401.506944) (xy 295.077131 -401.507444) (xy 295.140127 -401.515377) (xy 295.201647 -401.531084)
			(xy 295.260736 -401.554322) (xy 295.316476 -401.584728) (xy 295.368 -401.621832) (xy 295.391586 -401.643088)
			(xy 295.398849 -401.649272) (xy 295.416599 -401.656223) (xy 295.435661 -401.656223) (xy 295.453411 -401.649272)
			(xy 295.460674 -401.643088) (xy 295.48425 -401.621817) (xy 295.535761 -401.584686) (xy 295.591498 -401.554265)
			(xy 295.650592 -401.531026) (xy 295.712121 -401.515332) (xy 295.775126 -401.507429) (xy 295.806876 -401.506944)
			(xy 295.80713 -401.506944) (xy 295.839087 -401.507544) (xy 295.902496 -401.515558) (xy 295.964401 -401.531455)
			(xy 296.023825 -401.554986) (xy 296.079832 -401.585779) (xy 296.131538 -401.623348) (xy 296.178128 -401.667102)
			(xy 296.218866 -401.716349) (xy 296.253112 -401.770314) (xy 296.280324 -401.828145) (xy 296.300074 -401.888931)
			(xy 296.312049 -401.951712) (xy 296.316063 -402.0155) (xy 297.07602 -402.0155) (xy 297.080035 -401.951693)
			(xy 297.092015 -401.888892) (xy 297.111773 -401.828089) (xy 297.138995 -401.770241) (xy 297.173253 -401.716261)
			(xy 297.214007 -401.667001) (xy 297.260613 -401.623237) (xy 297.312338 -401.58566) (xy 297.368364 -401.554862)
			(xy 297.427809 -401.531329) (xy 297.489734 -401.515433) (xy 297.553163 -401.507423) (xy 297.58513 -401.506944)
			(xy 297.585384 -401.506944) (xy 297.617131 -401.507444) (xy 297.680127 -401.515377) (xy 297.741647 -401.531084)
			(xy 297.800736 -401.554322) (xy 297.856476 -401.584728) (xy 297.908 -401.621832) (xy 297.931586 -401.643088)
			(xy 297.938849 -401.649272) (xy 297.956599 -401.656223) (xy 297.975661 -401.656223) (xy 297.993411 -401.649272)
			(xy 298.000674 -401.643088) (xy 298.02425 -401.621817) (xy 298.075761 -401.584686) (xy 298.131498 -401.554265)
			(xy 298.190592 -401.531026) (xy 298.252121 -401.515332) (xy 298.315126 -401.507429) (xy 298.346876 -401.506944)
			(xy 298.34713 -401.506944) (xy 298.379087 -401.507544) (xy 298.442496 -401.515558) (xy 298.504401 -401.531455)
			(xy 298.563825 -401.554986) (xy 298.619832 -401.585779) (xy 298.671538 -401.623348) (xy 298.718128 -401.667102)
			(xy 298.758866 -401.716349) (xy 298.793112 -401.770314) (xy 298.820324 -401.828145) (xy 298.840074 -401.888931)
			(xy 298.852049 -401.951712) (xy 298.856063 -402.0155) (xy 298.852049 -402.079288) (xy 298.840074 -402.142069)
			(xy 298.820324 -402.202855) (xy 298.793112 -402.260686) (xy 298.758866 -402.314651) (xy 298.718128 -402.363898)
			(xy 298.671538 -402.407652) (xy 298.619832 -402.445221) (xy 298.563825 -402.476014) (xy 298.504401 -402.499545)
			(xy 298.442496 -402.515442) (xy 298.379087 -402.523456) (xy 298.34713 -402.52396) (xy 298.346876 -402.52396)
			(xy 298.315131 -402.523422) (xy 298.252136 -402.515497) (xy 298.190616 -402.499797) (xy 298.131527 -402.476566)
			(xy 298.075787 -402.446166) (xy 298.024261 -402.409069) (xy 298.000674 -402.387816) (xy 297.993411 -402.381632)
			(xy 297.975661 -402.374681) (xy 297.956599 -402.374681) (xy 297.938849 -402.381632) (xy 297.931586 -402.387816)
			(xy 297.908028 -402.409107) (xy 297.856512 -402.446235) (xy 297.800771 -402.476654) (xy 297.741674 -402.499889)
			(xy 297.680142 -402.515579) (xy 297.617135 -402.523478) (xy 297.585384 -402.52396) (xy 297.58513 -402.52396)
			(xy 297.553163 -402.523577) (xy 297.489734 -402.515567) (xy 297.427809 -402.499671) (xy 297.368364 -402.476138)
			(xy 297.312338 -402.44534) (xy 297.260613 -402.407763) (xy 297.214007 -402.363999) (xy 297.173253 -402.314739)
			(xy 297.138995 -402.260759) (xy 297.111773 -402.202911) (xy 297.092015 -402.142108) (xy 297.080035 -402.079307)
			(xy 297.07602 -402.0155) (xy 296.316063 -402.0155) (xy 296.312049 -402.079288) (xy 296.300074 -402.142069)
			(xy 296.280324 -402.202855) (xy 296.253112 -402.260686) (xy 296.218866 -402.314651) (xy 296.178128 -402.363898)
			(xy 296.131538 -402.407652) (xy 296.079832 -402.445221) (xy 296.023825 -402.476014) (xy 295.964401 -402.499545)
			(xy 295.902496 -402.515442) (xy 295.839087 -402.523456) (xy 295.80713 -402.52396) (xy 295.806876 -402.52396)
			(xy 295.775131 -402.523422) (xy 295.712136 -402.515497) (xy 295.650616 -402.499797) (xy 295.591527 -402.476566)
			(xy 295.535787 -402.446166) (xy 295.484261 -402.409069) (xy 295.460674 -402.387816) (xy 295.453411 -402.381632)
			(xy 295.435661 -402.374681) (xy 295.416599 -402.374681) (xy 295.398849 -402.381632) (xy 295.391586 -402.387816)
			(xy 295.368028 -402.409107) (xy 295.316512 -402.446235) (xy 295.260771 -402.476654) (xy 295.201674 -402.499889)
			(xy 295.140142 -402.515579) (xy 295.077135 -402.523478) (xy 295.045384 -402.52396) (xy 295.04513 -402.52396)
			(xy 295.013163 -402.523577) (xy 294.949734 -402.515567) (xy 294.887809 -402.499671) (xy 294.828364 -402.476138)
			(xy 294.772338 -402.44534) (xy 294.720613 -402.407763) (xy 294.674007 -402.363999) (xy 294.633253 -402.314739)
			(xy 294.598995 -402.260759) (xy 294.571773 -402.202911) (xy 294.552015 -402.142108) (xy 294.540035 -402.079307)
			(xy 294.53602 -402.0155) (xy 293.926484 -402.0155) (xy 293.92247 -402.079293) (xy 293.910493 -402.142079)
			(xy 293.890741 -402.20287) (xy 293.863525 -402.260705) (xy 293.829276 -402.314674) (xy 293.788532 -402.363924)
			(xy 293.741937 -402.407679) (xy 293.690226 -402.44525) (xy 293.634213 -402.476043) (xy 293.574783 -402.499573)
			(xy 293.512872 -402.515468) (xy 293.449457 -402.523479) (xy 293.417498 -402.52396) (xy 293.417244 -402.52396)
			(xy 293.385498 -402.523442) (xy 293.322502 -402.515512) (xy 293.260982 -402.499809) (xy 293.201894 -402.476575)
			(xy 293.146154 -402.446171) (xy 293.094629 -402.40907) (xy 293.071042 -402.387816) (xy 293.063779 -402.381632)
			(xy 293.046029 -402.374681) (xy 293.026967 -402.374681) (xy 293.009217 -402.381632) (xy 293.001954 -402.387816)
			(xy 292.978367 -402.409074) (xy 292.926858 -402.446206) (xy 292.871123 -402.47663) (xy 292.812032 -402.499871)
			(xy 292.750504 -402.515567) (xy 292.687501 -402.523474) (xy 292.655752 -402.52396) (xy 292.655498 -402.52396)
			(xy 292.623534 -402.523554) (xy 292.56011 -402.515542) (xy 292.498191 -402.499643) (xy 292.438752 -402.47611)
			(xy 292.382731 -402.445312) (xy 292.331013 -402.407736) (xy 292.284411 -402.363974) (xy 292.243662 -402.314717)
			(xy 292.209408 -402.26074) (xy 292.182189 -402.202897) (xy 292.162434 -402.142098) (xy 292.150455 -402.079302)
			(xy 292.146441 -402.0155) (xy 291.386484 -402.0155) (xy 291.38247 -402.079293) (xy 291.370493 -402.142079)
			(xy 291.350741 -402.20287) (xy 291.323525 -402.260705) (xy 291.289276 -402.314674) (xy 291.248532 -402.363924)
			(xy 291.201937 -402.407679) (xy 291.150226 -402.44525) (xy 291.094213 -402.476043) (xy 291.034783 -402.499573)
			(xy 290.972872 -402.515468) (xy 290.909457 -402.523479) (xy 290.877498 -402.52396) (xy 290.877244 -402.52396)
			(xy 290.845498 -402.523442) (xy 290.782502 -402.515512) (xy 290.720982 -402.499809) (xy 290.661894 -402.476575)
			(xy 290.606154 -402.446171) (xy 290.554629 -402.40907) (xy 290.531042 -402.387816) (xy 290.523779 -402.381632)
			(xy 290.506029 -402.374681) (xy 290.486967 -402.374681) (xy 290.469217 -402.381632) (xy 290.461954 -402.387816)
			(xy 290.438367 -402.409074) (xy 290.386858 -402.446206) (xy 290.331123 -402.47663) (xy 290.272032 -402.499871)
			(xy 290.210504 -402.515567) (xy 290.147501 -402.523474) (xy 290.115752 -402.52396) (xy 290.115498 -402.52396)
			(xy 290.083534 -402.523554) (xy 290.02011 -402.515542) (xy 289.958191 -402.499643) (xy 289.898752 -402.47611)
			(xy 289.842731 -402.445312) (xy 289.791013 -402.407736) (xy 289.744411 -402.363974) (xy 289.703662 -402.314717)
			(xy 289.669408 -402.26074) (xy 289.642189 -402.202897) (xy 289.622434 -402.142098) (xy 289.610455 -402.079302)
			(xy 289.606441 -402.0155) (xy 288.846484 -402.0155) (xy 288.84247 -402.079293) (xy 288.830493 -402.142079)
			(xy 288.810741 -402.20287) (xy 288.783525 -402.260705) (xy 288.749276 -402.314674) (xy 288.708532 -402.363924)
			(xy 288.661937 -402.407679) (xy 288.610226 -402.44525) (xy 288.554213 -402.476043) (xy 288.494783 -402.499573)
			(xy 288.432872 -402.515468) (xy 288.369457 -402.523479) (xy 288.337498 -402.52396) (xy 288.337244 -402.52396)
			(xy 288.305498 -402.523442) (xy 288.242502 -402.515512) (xy 288.180982 -402.499809) (xy 288.121894 -402.476575)
			(xy 288.066154 -402.446171) (xy 288.014629 -402.40907) (xy 287.991042 -402.387816) (xy 287.983779 -402.381632)
			(xy 287.966029 -402.374681) (xy 287.946967 -402.374681) (xy 287.929217 -402.381632) (xy 287.921954 -402.387816)
			(xy 287.898367 -402.409074) (xy 287.846858 -402.446206) (xy 287.791123 -402.47663) (xy 287.732032 -402.499871)
			(xy 287.670504 -402.515567) (xy 287.607501 -402.523474) (xy 287.575752 -402.52396) (xy 287.575498 -402.52396)
			(xy 287.543534 -402.523554) (xy 287.48011 -402.515542) (xy 287.418191 -402.499643) (xy 287.358752 -402.47611)
			(xy 287.302731 -402.445312) (xy 287.251013 -402.407736) (xy 287.204411 -402.363974) (xy 287.163662 -402.314717)
			(xy 287.129408 -402.26074) (xy 287.102189 -402.202897) (xy 287.082434 -402.142098) (xy 287.070455 -402.079302)
			(xy 287.066441 -402.0155) (xy 281.686508 -402.0155) (xy 281.686508 -404.0475) (xy 287.066441 -404.0475)
			(xy 287.070455 -403.983698) (xy 287.082434 -403.920902) (xy 287.102189 -403.860103) (xy 287.129408 -403.80226)
			(xy 287.163662 -403.748283) (xy 287.204411 -403.699026) (xy 287.251013 -403.655264) (xy 287.302731 -403.617688)
			(xy 287.358752 -403.58689) (xy 287.418191 -403.563357) (xy 287.48011 -403.547458) (xy 287.543534 -403.539446)
			(xy 287.575498 -403.538944) (xy 287.575752 -403.538944) (xy 287.607498 -403.539464) (xy 287.670494 -403.547393)
			(xy 287.732014 -403.563096) (xy 287.791102 -403.58633) (xy 287.846842 -403.616733) (xy 287.898367 -403.653834)
			(xy 287.921954 -403.675088) (xy 287.929217 -403.681272) (xy 287.946967 -403.688223) (xy 287.966029 -403.688223)
			(xy 287.983779 -403.681272) (xy 287.991042 -403.675088) (xy 288.014631 -403.653832) (xy 288.06614 -403.6167)
			(xy 288.121874 -403.586276) (xy 288.180965 -403.563035) (xy 288.242492 -403.547338) (xy 288.305495 -403.539431)
			(xy 288.337244 -403.538944) (xy 288.337498 -403.538944) (xy 288.369457 -403.539521) (xy 288.432872 -403.547532)
			(xy 288.494783 -403.563427) (xy 288.554213 -403.586957) (xy 288.610226 -403.61775) (xy 288.661937 -403.655321)
			(xy 288.708532 -403.699076) (xy 288.749276 -403.748326) (xy 288.783525 -403.802295) (xy 288.810741 -403.86013)
			(xy 288.830493 -403.920921) (xy 288.84247 -403.983707) (xy 288.846484 -404.0475) (xy 289.606441 -404.0475)
			(xy 289.610455 -403.983698) (xy 289.622434 -403.920902) (xy 289.642189 -403.860103) (xy 289.669408 -403.80226)
			(xy 289.703662 -403.748283) (xy 289.744411 -403.699026) (xy 289.791013 -403.655264) (xy 289.842731 -403.617688)
			(xy 289.898752 -403.58689) (xy 289.958191 -403.563357) (xy 290.02011 -403.547458) (xy 290.083534 -403.539446)
			(xy 290.115498 -403.538944) (xy 290.115752 -403.538944) (xy 290.147498 -403.539464) (xy 290.210494 -403.547393)
			(xy 290.272014 -403.563096) (xy 290.331102 -403.58633) (xy 290.386842 -403.616733) (xy 290.438367 -403.653834)
			(xy 290.461954 -403.675088) (xy 290.469217 -403.681272) (xy 290.486967 -403.688223) (xy 290.506029 -403.688223)
			(xy 290.523779 -403.681272) (xy 290.531042 -403.675088) (xy 290.554631 -403.653832) (xy 290.60614 -403.6167)
			(xy 290.661874 -403.586276) (xy 290.720965 -403.563035) (xy 290.782492 -403.547338) (xy 290.845495 -403.539431)
			(xy 290.877244 -403.538944) (xy 290.877498 -403.538944) (xy 290.909457 -403.539521) (xy 290.972872 -403.547532)
			(xy 291.034783 -403.563427) (xy 291.094213 -403.586957) (xy 291.150226 -403.61775) (xy 291.201937 -403.655321)
			(xy 291.248532 -403.699076) (xy 291.289276 -403.748326) (xy 291.323525 -403.802295) (xy 291.350741 -403.86013)
			(xy 291.370493 -403.920921) (xy 291.38247 -403.983707) (xy 291.386484 -404.0475) (xy 292.146441 -404.0475)
			(xy 292.150455 -403.983698) (xy 292.162434 -403.920902) (xy 292.182189 -403.860103) (xy 292.209408 -403.80226)
			(xy 292.243662 -403.748283) (xy 292.284411 -403.699026) (xy 292.331013 -403.655264) (xy 292.382731 -403.617688)
			(xy 292.438752 -403.58689) (xy 292.498191 -403.563357) (xy 292.56011 -403.547458) (xy 292.623534 -403.539446)
			(xy 292.655498 -403.538944) (xy 292.655752 -403.538944) (xy 292.687498 -403.539464) (xy 292.750494 -403.547393)
			(xy 292.812014 -403.563096) (xy 292.871102 -403.58633) (xy 292.926842 -403.616733) (xy 292.978367 -403.653834)
			(xy 293.001954 -403.675088) (xy 293.009217 -403.681272) (xy 293.026967 -403.688223) (xy 293.046029 -403.688223)
			(xy 293.063779 -403.681272) (xy 293.071042 -403.675088) (xy 293.094631 -403.653832) (xy 293.14614 -403.6167)
			(xy 293.201874 -403.586276) (xy 293.260965 -403.563035) (xy 293.322492 -403.547338) (xy 293.385495 -403.539431)
			(xy 293.417244 -403.538944) (xy 293.417498 -403.538944) (xy 293.449457 -403.539521) (xy 293.512872 -403.547532)
			(xy 293.574783 -403.563427) (xy 293.634213 -403.586957) (xy 293.690226 -403.61775) (xy 293.741937 -403.655321)
			(xy 293.788532 -403.699076) (xy 293.829276 -403.748326) (xy 293.863525 -403.802295) (xy 293.890741 -403.86013)
			(xy 293.910493 -403.920921) (xy 293.92247 -403.983707) (xy 293.926484 -404.0475) (xy 294.53602 -404.0475)
			(xy 294.540035 -403.983693) (xy 294.552015 -403.920892) (xy 294.571773 -403.860089) (xy 294.598995 -403.802241)
			(xy 294.633253 -403.748261) (xy 294.674007 -403.699001) (xy 294.720613 -403.655237) (xy 294.772338 -403.61766)
			(xy 294.828364 -403.586862) (xy 294.887809 -403.563329) (xy 294.949734 -403.547433) (xy 295.013163 -403.539423)
			(xy 295.04513 -403.538944) (xy 295.045384 -403.538944) (xy 295.077131 -403.539444) (xy 295.140127 -403.547377)
			(xy 295.201647 -403.563084) (xy 295.260736 -403.586322) (xy 295.316476 -403.616728) (xy 295.368 -403.653832)
			(xy 295.391586 -403.675088) (xy 295.398849 -403.681272) (xy 295.416599 -403.688223) (xy 295.435661 -403.688223)
			(xy 295.453411 -403.681272) (xy 295.460674 -403.675088) (xy 295.48425 -403.653817) (xy 295.535761 -403.616686)
			(xy 295.591498 -403.586265) (xy 295.650592 -403.563026) (xy 295.712121 -403.547332) (xy 295.775126 -403.539429)
			(xy 295.806876 -403.538944) (xy 295.80713 -403.538944) (xy 295.839087 -403.539544) (xy 295.902496 -403.547558)
			(xy 295.964401 -403.563455) (xy 296.023825 -403.586986) (xy 296.079832 -403.617779) (xy 296.131538 -403.655348)
			(xy 296.178128 -403.699102) (xy 296.218866 -403.748349) (xy 296.253112 -403.802314) (xy 296.280324 -403.860145)
			(xy 296.300074 -403.920931) (xy 296.312049 -403.983712) (xy 296.316063 -404.0475) (xy 297.07602 -404.0475)
			(xy 297.080035 -403.983693) (xy 297.092015 -403.920892) (xy 297.111773 -403.860089) (xy 297.138995 -403.802241)
			(xy 297.173253 -403.748261) (xy 297.214007 -403.699001) (xy 297.260613 -403.655237) (xy 297.312338 -403.61766)
			(xy 297.368364 -403.586862) (xy 297.427809 -403.563329) (xy 297.489734 -403.547433) (xy 297.553163 -403.539423)
			(xy 297.58513 -403.538944) (xy 297.585384 -403.538944) (xy 297.617131 -403.539444) (xy 297.680127 -403.547377)
			(xy 297.741647 -403.563084) (xy 297.800736 -403.586322) (xy 297.856476 -403.616728) (xy 297.908 -403.653832)
			(xy 297.931586 -403.675088) (xy 297.938849 -403.681272) (xy 297.956599 -403.688223) (xy 297.975661 -403.688223)
			(xy 297.993411 -403.681272) (xy 298.000674 -403.675088) (xy 298.02425 -403.653817) (xy 298.075761 -403.616686)
			(xy 298.131498 -403.586265) (xy 298.190592 -403.563026) (xy 298.252121 -403.547332) (xy 298.315126 -403.539429)
			(xy 298.346876 -403.538944) (xy 298.34713 -403.538944) (xy 298.379087 -403.539544) (xy 298.442496 -403.547558)
			(xy 298.504401 -403.563455) (xy 298.563825 -403.586986) (xy 298.619832 -403.617779) (xy 298.671538 -403.655348)
			(xy 298.718128 -403.699102) (xy 298.758866 -403.748349) (xy 298.793112 -403.802314) (xy 298.820324 -403.860145)
			(xy 298.836897 -403.911152) (xy 303.599054 -403.911152) (xy 303.599054 -403.856648) (xy 303.60681 -403.802698)
			(xy 303.622166 -403.7504) (xy 303.644808 -403.700821) (xy 303.674275 -403.654968) (xy 303.709967 -403.613776)
			(xy 303.751159 -403.578082) (xy 303.79701 -403.548613) (xy 303.846589 -403.52597) (xy 303.898886 -403.510613)
			(xy 303.952836 -403.502855) (xy 303.980088 -403.502368) (xy 304.843688 -403.502368) (xy 304.87094 -403.502878)
			(xy 304.924889 -403.510634) (xy 304.977185 -403.525988) (xy 305.026763 -403.548628) (xy 305.072615 -403.578094)
			(xy 305.113806 -403.613785) (xy 305.149499 -403.654976) (xy 305.178966 -403.700826) (xy 305.201608 -403.750404)
			(xy 305.216964 -403.8027) (xy 305.224721 -403.856648) (xy 305.224721 -403.911152) (xy 305.22472 -403.911156)
			(xy 306.662231 -403.911156) (xy 306.662231 -403.856644) (xy 306.669989 -403.802687) (xy 306.685348 -403.750384)
			(xy 306.707994 -403.700799) (xy 306.737466 -403.654941) (xy 306.773165 -403.613745) (xy 306.814364 -403.578049)
			(xy 306.860223 -403.54858) (xy 306.90981 -403.525938) (xy 306.962115 -403.510583) (xy 307.016072 -403.502829)
			(xy 307.043328 -403.502368) (xy 307.906928 -403.502368) (xy 307.934176 -403.502904) (xy 307.988117 -403.510663)
			(xy 308.040405 -403.52602) (xy 308.089976 -403.548661) (xy 308.13582 -403.578126) (xy 308.177004 -403.613816)
			(xy 308.21269 -403.655002) (xy 308.242152 -403.700849) (xy 308.26479 -403.750421) (xy 308.280143 -403.80271)
			(xy 308.287898 -403.856652) (xy 308.287898 -403.911148) (xy 308.287897 -403.911152) (xy 309.725554 -403.911152)
			(xy 309.725554 -403.856648) (xy 309.73331 -403.8027) (xy 309.748664 -403.750405) (xy 309.771305 -403.700826)
			(xy 309.80077 -403.654975) (xy 309.83646 -403.613783) (xy 309.877649 -403.578089) (xy 309.923498 -403.54862)
			(xy 309.973075 -403.525976) (xy 310.025369 -403.510617) (xy 310.079317 -403.502856) (xy 310.106568 -403.502368)
			(xy 310.970168 -403.502368) (xy 310.997421 -403.502877) (xy 311.051372 -403.51063) (xy 311.10367 -403.525982)
			(xy 311.153251 -403.548621) (xy 311.199105 -403.578087) (xy 311.240299 -403.613778) (xy 311.275994 -403.654969)
			(xy 311.305463 -403.700821) (xy 311.328107 -403.7504) (xy 311.343463 -403.802697) (xy 311.351221 -403.856647)
			(xy 311.351221 -403.911153) (xy 311.351221 -403.911155) (xy 312.788731 -403.911155) (xy 312.788731 -403.856645)
			(xy 312.796489 -403.80269) (xy 312.811846 -403.750388) (xy 312.834491 -403.700804) (xy 312.863961 -403.654948)
			(xy 312.899658 -403.613752) (xy 312.940854 -403.578056) (xy 312.986711 -403.548587) (xy 313.036296 -403.525943)
			(xy 313.088598 -403.510587) (xy 313.142553 -403.50283) (xy 313.169808 -403.502368) (xy 314.033408 -403.502368)
			(xy 314.060657 -403.502903) (xy 314.114601 -403.51066) (xy 314.166891 -403.526015) (xy 314.216464 -403.548655)
			(xy 314.26231 -403.578119) (xy 314.303497 -403.613809) (xy 314.339186 -403.654996) (xy 314.368649 -403.700843)
			(xy 314.391288 -403.750417) (xy 314.406642 -403.802707) (xy 314.414398 -403.856651) (xy 314.414398 -403.911149)
			(xy 314.414397 -403.911157) (xy 315.851931 -403.911157) (xy 315.851931 -403.856643) (xy 315.85969 -403.802685)
			(xy 315.875049 -403.75038) (xy 315.897697 -403.700793) (xy 315.927171 -403.654935) (xy 315.962872 -403.613738)
			(xy 316.004073 -403.578042) (xy 316.049935 -403.548574) (xy 316.099525 -403.525932) (xy 316.151832 -403.51058)
			(xy 316.205791 -403.502828) (xy 316.233048 -403.502368) (xy 317.096648 -403.502368) (xy 317.123895 -403.502905)
			(xy 317.177834 -403.510667) (xy 317.23012 -403.526025) (xy 317.279688 -403.548668) (xy 317.325529 -403.578133)
			(xy 317.366711 -403.613823) (xy 317.402395 -403.655009) (xy 317.431855 -403.700854) (xy 317.454491 -403.750425)
			(xy 317.469843 -403.802713) (xy 317.477598 -403.856653) (xy 317.477598 -403.911147) (xy 317.477597 -403.911152)
			(xy 318.915254 -403.911152) (xy 318.915254 -403.856648) (xy 318.92301 -403.802698) (xy 318.938366 -403.7504)
			(xy 318.961008 -403.700821) (xy 318.990475 -403.654968) (xy 319.026167 -403.613776) (xy 319.067359 -403.578082)
			(xy 319.11321 -403.548613) (xy 319.162789 -403.52597) (xy 319.215086 -403.510613) (xy 319.269036 -403.502855)
			(xy 319.296288 -403.502368) (xy 320.159888 -403.502368) (xy 320.18714 -403.502878) (xy 320.241089 -403.510634)
			(xy 320.293385 -403.525988) (xy 320.342963 -403.548628) (xy 320.388815 -403.578094) (xy 320.430006 -403.613785)
			(xy 320.465699 -403.654976) (xy 320.495166 -403.700826) (xy 320.517808 -403.750404) (xy 320.533164 -403.8027)
			(xy 320.540921 -403.856648) (xy 320.540921 -403.911152) (xy 320.54092 -403.911156) (xy 321.978431 -403.911156)
			(xy 321.978431 -403.856644) (xy 321.986189 -403.802687) (xy 322.001548 -403.750384) (xy 322.024194 -403.700799)
			(xy 322.053666 -403.654941) (xy 322.089365 -403.613745) (xy 322.130564 -403.578049) (xy 322.176423 -403.54858)
			(xy 322.22601 -403.525938) (xy 322.278315 -403.510583) (xy 322.332272 -403.502829) (xy 322.359528 -403.502368)
			(xy 323.223128 -403.502368) (xy 323.250376 -403.502904) (xy 323.304317 -403.510663) (xy 323.356605 -403.52602)
			(xy 323.406176 -403.548661) (xy 323.45202 -403.578126) (xy 323.493204 -403.613816) (xy 323.52889 -403.655002)
			(xy 323.558352 -403.700849) (xy 323.58099 -403.750421) (xy 323.596343 -403.80271) (xy 323.604098 -403.856652)
			(xy 323.604098 -403.911148) (xy 323.604097 -403.911152) (xy 325.041754 -403.911152) (xy 325.041754 -403.856648)
			(xy 325.04951 -403.8027) (xy 325.064864 -403.750405) (xy 325.087505 -403.700826) (xy 325.11697 -403.654975)
			(xy 325.15266 -403.613783) (xy 325.193849 -403.578089) (xy 325.239698 -403.54862) (xy 325.289275 -403.525976)
			(xy 325.341569 -403.510617) (xy 325.395517 -403.502856) (xy 325.422768 -403.502368) (xy 326.286368 -403.502368)
			(xy 326.313621 -403.502877) (xy 326.367572 -403.51063) (xy 326.41987 -403.525982) (xy 326.469451 -403.548621)
			(xy 326.515305 -403.578087) (xy 326.556499 -403.613778) (xy 326.592194 -403.654969) (xy 326.621663 -403.700821)
			(xy 326.644307 -403.7504) (xy 326.659663 -403.802697) (xy 326.667421 -403.856647) (xy 326.667421 -403.911153)
			(xy 326.667421 -403.911155) (xy 328.104931 -403.911155) (xy 328.104931 -403.856645) (xy 328.112689 -403.80269)
			(xy 328.128046 -403.750388) (xy 328.150691 -403.700804) (xy 328.180161 -403.654948) (xy 328.215858 -403.613752)
			(xy 328.257054 -403.578056) (xy 328.302911 -403.548587) (xy 328.352496 -403.525943) (xy 328.404798 -403.510587)
			(xy 328.458753 -403.50283) (xy 328.486008 -403.502368) (xy 329.349608 -403.502368) (xy 329.376857 -403.502903)
			(xy 329.430801 -403.51066) (xy 329.483091 -403.526015) (xy 329.532664 -403.548655) (xy 329.57851 -403.578119)
			(xy 329.619697 -403.613809) (xy 329.655386 -403.654996) (xy 329.684849 -403.700843) (xy 329.707488 -403.750417)
			(xy 329.722842 -403.802707) (xy 329.730598 -403.856651) (xy 329.730598 -403.911149) (xy 329.730597 -403.911157)
			(xy 331.168131 -403.911157) (xy 331.168131 -403.856643) (xy 331.17589 -403.802685) (xy 331.191249 -403.75038)
			(xy 331.213897 -403.700793) (xy 331.243371 -403.654935) (xy 331.279072 -403.613738) (xy 331.320273 -403.578042)
			(xy 331.366135 -403.548574) (xy 331.415725 -403.525932) (xy 331.468032 -403.51058) (xy 331.521991 -403.502828)
			(xy 331.549248 -403.502368) (xy 332.412848 -403.502368) (xy 332.440095 -403.502905) (xy 332.494034 -403.510667)
			(xy 332.54632 -403.526025) (xy 332.595888 -403.548668) (xy 332.641729 -403.578133) (xy 332.682911 -403.613823)
			(xy 332.718595 -403.655009) (xy 332.748055 -403.700854) (xy 332.770691 -403.750425) (xy 332.786043 -403.802713)
			(xy 332.793798 -403.856653) (xy 332.793798 -403.911147) (xy 332.793797 -403.911152) (xy 334.231454 -403.911152)
			(xy 334.231454 -403.856648) (xy 334.23921 -403.802698) (xy 334.254566 -403.7504) (xy 334.277208 -403.700821)
			(xy 334.306675 -403.654968) (xy 334.342367 -403.613776) (xy 334.383559 -403.578082) (xy 334.42941 -403.548613)
			(xy 334.478989 -403.52597) (xy 334.531286 -403.510613) (xy 334.585236 -403.502855) (xy 334.612488 -403.502368)
			(xy 335.476088 -403.502368) (xy 335.50334 -403.502878) (xy 335.557289 -403.510634) (xy 335.609585 -403.525988)
			(xy 335.659163 -403.548628) (xy 335.705015 -403.578094) (xy 335.746206 -403.613785) (xy 335.781899 -403.654976)
			(xy 335.811366 -403.700826) (xy 335.834008 -403.750404) (xy 335.849364 -403.8027) (xy 335.857121 -403.856648)
			(xy 335.857121 -403.911152) (xy 335.85712 -403.911156) (xy 337.294631 -403.911156) (xy 337.294631 -403.856644)
			(xy 337.302389 -403.802687) (xy 337.317748 -403.750384) (xy 337.340394 -403.700799) (xy 337.369866 -403.654941)
			(xy 337.405565 -403.613745) (xy 337.446764 -403.578049) (xy 337.492623 -403.54858) (xy 337.54221 -403.525938)
			(xy 337.594515 -403.510583) (xy 337.648472 -403.502829) (xy 337.675728 -403.502368) (xy 338.539328 -403.502368)
			(xy 338.566576 -403.502904) (xy 338.620517 -403.510663) (xy 338.672805 -403.52602) (xy 338.722376 -403.548661)
			(xy 338.76822 -403.578126) (xy 338.809404 -403.613816) (xy 338.84509 -403.655002) (xy 338.874552 -403.700849)
			(xy 338.89719 -403.750421) (xy 338.912543 -403.80271) (xy 338.920298 -403.856652) (xy 338.920298 -403.911148)
			(xy 338.920297 -403.911152) (xy 340.357954 -403.911152) (xy 340.357954 -403.856648) (xy 340.36571 -403.8027)
			(xy 340.381064 -403.750405) (xy 340.403705 -403.700826) (xy 340.43317 -403.654975) (xy 340.46886 -403.613783)
			(xy 340.510049 -403.578089) (xy 340.555898 -403.54862) (xy 340.605475 -403.525976) (xy 340.657769 -403.510617)
			(xy 340.711717 -403.502856) (xy 340.738968 -403.502368) (xy 341.602568 -403.502368) (xy 341.629821 -403.502877)
			(xy 341.683772 -403.51063) (xy 341.73607 -403.525982) (xy 341.785651 -403.548621) (xy 341.831505 -403.578087)
			(xy 341.872699 -403.613778) (xy 341.908394 -403.654969) (xy 341.937863 -403.700821) (xy 341.960507 -403.7504)
			(xy 341.975863 -403.802697) (xy 341.983621 -403.856647) (xy 341.983621 -403.911153) (xy 341.983621 -403.911155)
			(xy 343.421131 -403.911155) (xy 343.421131 -403.856645) (xy 343.428889 -403.80269) (xy 343.444246 -403.750388)
			(xy 343.466891 -403.700804) (xy 343.496361 -403.654948) (xy 343.532058 -403.613752) (xy 343.573254 -403.578056)
			(xy 343.619111 -403.548587) (xy 343.668696 -403.525943) (xy 343.720998 -403.510587) (xy 343.774953 -403.50283)
			(xy 343.802208 -403.502368) (xy 344.665808 -403.502368) (xy 344.693057 -403.502903) (xy 344.747001 -403.51066)
			(xy 344.799291 -403.526015) (xy 344.848864 -403.548655) (xy 344.89471 -403.578119) (xy 344.935897 -403.613809)
			(xy 344.971586 -403.654996) (xy 345.001049 -403.700843) (xy 345.023688 -403.750417) (xy 345.039042 -403.802707)
			(xy 345.046798 -403.856651) (xy 345.046798 -403.911149) (xy 345.046797 -403.911157) (xy 346.484331 -403.911157)
			(xy 346.484331 -403.856643) (xy 346.49209 -403.802685) (xy 346.507449 -403.75038) (xy 346.530097 -403.700793)
			(xy 346.559571 -403.654935) (xy 346.595272 -403.613738) (xy 346.636473 -403.578042) (xy 346.682335 -403.548574)
			(xy 346.731925 -403.525932) (xy 346.784232 -403.51058) (xy 346.838191 -403.502828) (xy 346.865448 -403.502368)
			(xy 347.729048 -403.502368) (xy 347.756295 -403.502905) (xy 347.810234 -403.510667) (xy 347.86252 -403.526025)
			(xy 347.912088 -403.548668) (xy 347.957929 -403.578133) (xy 347.999111 -403.613823) (xy 348.034795 -403.655009)
			(xy 348.064255 -403.700854) (xy 348.086891 -403.750425) (xy 348.102243 -403.802713) (xy 348.109998 -403.856653)
			(xy 348.109998 -403.911147) (xy 348.109997 -403.911152) (xy 349.547654 -403.911152) (xy 349.547654 -403.856648)
			(xy 349.55541 -403.802698) (xy 349.570766 -403.7504) (xy 349.593408 -403.700821) (xy 349.622875 -403.654968)
			(xy 349.658567 -403.613776) (xy 349.699759 -403.578082) (xy 349.74561 -403.548613) (xy 349.795189 -403.52597)
			(xy 349.847486 -403.510613) (xy 349.901436 -403.502855) (xy 349.928688 -403.502368) (xy 350.792288 -403.502368)
			(xy 350.81954 -403.502878) (xy 350.873489 -403.510634) (xy 350.925785 -403.525988) (xy 350.975363 -403.548628)
			(xy 351.021215 -403.578094) (xy 351.062406 -403.613785) (xy 351.098099 -403.654976) (xy 351.127566 -403.700826)
			(xy 351.150208 -403.750404) (xy 351.165564 -403.8027) (xy 351.173321 -403.856648) (xy 351.173321 -403.911152)
			(xy 351.17332 -403.911156) (xy 371.041831 -403.911156) (xy 371.041831 -403.856644) (xy 371.049589 -403.802687)
			(xy 371.064948 -403.750383) (xy 371.087594 -403.700798) (xy 371.117067 -403.654941) (xy 371.152766 -403.613745)
			(xy 371.193965 -403.578049) (xy 371.239824 -403.54858) (xy 371.289412 -403.525937) (xy 371.341716 -403.510583)
			(xy 371.395674 -403.502829) (xy 371.42293 -403.502368) (xy 372.28653 -403.502368) (xy 372.313778 -403.502904)
			(xy 372.367719 -403.510664) (xy 372.420007 -403.52602) (xy 372.469577 -403.548662) (xy 372.515421 -403.578127)
			(xy 372.556605 -403.613816) (xy 372.592291 -403.655003) (xy 372.621753 -403.700849) (xy 372.64439 -403.750421)
			(xy 372.659743 -403.80271) (xy 372.667498 -403.856652) (xy 372.667498 -403.911148) (xy 372.667497 -403.911152)
			(xy 374.105154 -403.911152) (xy 374.105154 -403.856648) (xy 374.11291 -403.8027) (xy 374.128265 -403.750404)
			(xy 374.150905 -403.700826) (xy 374.18037 -403.654974) (xy 374.216061 -403.613782) (xy 374.25725 -403.578088)
			(xy 374.3031 -403.548619) (xy 374.352676 -403.525975) (xy 374.404971 -403.510616) (xy 374.458918 -403.502856)
			(xy 374.48617 -403.502368) (xy 375.34977 -403.502368) (xy 375.377023 -403.502877) (xy 375.430973 -403.51063)
			(xy 375.483271 -403.525983) (xy 375.532852 -403.548622) (xy 375.578706 -403.578087) (xy 375.6199 -403.613779)
			(xy 375.655595 -403.65497) (xy 375.685064 -403.700821) (xy 375.707707 -403.7504) (xy 375.723063 -403.802697)
			(xy 375.730821 -403.856647) (xy 375.730821 -403.911153) (xy 375.730821 -403.911155) (xy 377.168331 -403.911155)
			(xy 377.168331 -403.856645) (xy 377.176089 -403.80269) (xy 377.191446 -403.750388) (xy 377.214091 -403.700804)
			(xy 377.243562 -403.654947) (xy 377.279259 -403.613752) (xy 377.320455 -403.578056) (xy 377.366313 -403.548586)
			(xy 377.415897 -403.525943) (xy 377.468199 -403.510587) (xy 377.522155 -403.50283) (xy 377.54941 -403.502368)
			(xy 378.41301 -403.502368) (xy 378.440259 -403.502903) (xy 378.494202 -403.51066) (xy 378.546492 -403.526015)
			(xy 378.596065 -403.548655) (xy 378.641911 -403.57812) (xy 378.683098 -403.613809) (xy 378.718786 -403.654997)
			(xy 378.748249 -403.700844) (xy 378.770888 -403.750417) (xy 378.786242 -403.802708) (xy 378.793998 -403.856651)
			(xy 378.793998 -403.911149) (xy 378.793998 -403.911151) (xy 380.231654 -403.911151) (xy 380.231654 -403.856649)
			(xy 380.239409 -403.802703) (xy 380.254763 -403.750409) (xy 380.277402 -403.700832) (xy 380.306865 -403.654981)
			(xy 380.342554 -403.613789) (xy 380.383741 -403.578095) (xy 380.429588 -403.548626) (xy 380.479162 -403.52598)
			(xy 380.531454 -403.51062) (xy 380.585399 -403.502857) (xy 380.61265 -403.502368) (xy 381.47625 -403.502368)
			(xy 381.503503 -403.502876) (xy 381.557456 -403.510627) (xy 381.609757 -403.525977) (xy 381.65934 -403.548616)
			(xy 381.705197 -403.57808) (xy 381.746393 -403.613772) (xy 381.78209 -403.654963) (xy 381.81156 -403.700816)
			(xy 381.834205 -403.750396) (xy 381.849563 -403.802695) (xy 381.857321 -403.856647) (xy 381.857321 -403.911153)
			(xy 383.294854 -403.911153) (xy 383.294854 -403.856647) (xy 383.302611 -403.802697) (xy 383.317966 -403.7504)
			(xy 383.340608 -403.70082) (xy 383.370075 -403.654968) (xy 383.405768 -403.613775) (xy 383.44696 -403.578081)
			(xy 383.492812 -403.548613) (xy 383.542391 -403.52597) (xy 383.594687 -403.510613) (xy 383.648638 -403.502855)
			(xy 383.67589 -403.502368) (xy 384.53949 -403.502368) (xy 384.566742 -403.502879) (xy 384.62069 -403.510634)
			(xy 384.672986 -403.525988) (xy 384.722564 -403.548629) (xy 384.768416 -403.578095) (xy 384.809607 -403.613786)
			(xy 384.845299 -403.654976) (xy 384.874767 -403.700827) (xy 384.897408 -403.750405) (xy 384.912764 -403.8027)
			(xy 384.920521 -403.856648) (xy 384.920521 -403.911152) (xy 384.92052 -403.911156) (xy 386.358031 -403.911156)
			(xy 386.358031 -403.856644) (xy 386.365789 -403.802687) (xy 386.381148 -403.750383) (xy 386.403794 -403.700798)
			(xy 386.433267 -403.654941) (xy 386.468966 -403.613745) (xy 386.510165 -403.578049) (xy 386.556024 -403.54858)
			(xy 386.605612 -403.525937) (xy 386.657916 -403.510583) (xy 386.711874 -403.502829) (xy 386.73913 -403.502368)
			(xy 387.60273 -403.502368) (xy 387.629978 -403.502904) (xy 387.683919 -403.510664) (xy 387.736207 -403.52602)
			(xy 387.785777 -403.548662) (xy 387.831621 -403.578127) (xy 387.872805 -403.613816) (xy 387.908491 -403.655003)
			(xy 387.937953 -403.700849) (xy 387.96059 -403.750421) (xy 387.975943 -403.80271) (xy 387.983698 -403.856652)
			(xy 387.983698 -403.911148) (xy 387.983697 -403.911152) (xy 389.421354 -403.911152) (xy 389.421354 -403.856648)
			(xy 389.42911 -403.8027) (xy 389.444465 -403.750404) (xy 389.467105 -403.700826) (xy 389.49657 -403.654974)
			(xy 389.532261 -403.613782) (xy 389.57345 -403.578088) (xy 389.6193 -403.548619) (xy 389.668876 -403.525975)
			(xy 389.721171 -403.510616) (xy 389.775118 -403.502856) (xy 389.80237 -403.502368) (xy 390.66597 -403.502368)
			(xy 390.693223 -403.502877) (xy 390.747173 -403.51063) (xy 390.799471 -403.525983) (xy 390.849052 -403.548622)
			(xy 390.894906 -403.578087) (xy 390.9361 -403.613779) (xy 390.971795 -403.65497) (xy 391.001264 -403.700821)
			(xy 391.023907 -403.7504) (xy 391.039263 -403.802697) (xy 391.047021 -403.856647) (xy 391.047021 -403.911153)
			(xy 391.047021 -403.911155) (xy 392.484531 -403.911155) (xy 392.484531 -403.856645) (xy 392.492289 -403.80269)
			(xy 392.507646 -403.750388) (xy 392.530291 -403.700804) (xy 392.559762 -403.654947) (xy 392.595459 -403.613752)
			(xy 392.636655 -403.578056) (xy 392.682513 -403.548586) (xy 392.732097 -403.525943) (xy 392.784399 -403.510587)
			(xy 392.838355 -403.50283) (xy 392.86561 -403.502368) (xy 393.72921 -403.502368) (xy 393.756459 -403.502903)
			(xy 393.810402 -403.51066) (xy 393.862692 -403.526015) (xy 393.912265 -403.548655) (xy 393.958111 -403.57812)
			(xy 393.999298 -403.613809) (xy 394.034986 -403.654997) (xy 394.064449 -403.700844) (xy 394.087088 -403.750417)
			(xy 394.102442 -403.802708) (xy 394.110198 -403.856651) (xy 394.110198 -403.911149) (xy 394.110198 -403.911151)
			(xy 395.547854 -403.911151) (xy 395.547854 -403.856649) (xy 395.555609 -403.802703) (xy 395.570963 -403.750409)
			(xy 395.593602 -403.700832) (xy 395.623065 -403.654981) (xy 395.658754 -403.613789) (xy 395.699941 -403.578095)
			(xy 395.745788 -403.548626) (xy 395.795362 -403.52598) (xy 395.847654 -403.51062) (xy 395.901599 -403.502857)
			(xy 395.92885 -403.502368) (xy 396.79245 -403.502368) (xy 396.819703 -403.502876) (xy 396.873656 -403.510627)
			(xy 396.925957 -403.525977) (xy 396.97554 -403.548616) (xy 397.021397 -403.57808) (xy 397.062593 -403.613772)
			(xy 397.09829 -403.654963) (xy 397.12776 -403.700816) (xy 397.150405 -403.750396) (xy 397.165763 -403.802695)
			(xy 397.173521 -403.856647) (xy 397.173521 -403.911153) (xy 398.611054 -403.911153) (xy 398.611054 -403.856647)
			(xy 398.618811 -403.802697) (xy 398.634166 -403.7504) (xy 398.656808 -403.70082) (xy 398.686275 -403.654968)
			(xy 398.721968 -403.613775) (xy 398.76316 -403.578081) (xy 398.809012 -403.548613) (xy 398.858591 -403.52597)
			(xy 398.910887 -403.510613) (xy 398.964838 -403.502855) (xy 398.99209 -403.502368) (xy 399.85569 -403.502368)
			(xy 399.882942 -403.502879) (xy 399.93689 -403.510634) (xy 399.989186 -403.525988) (xy 400.038764 -403.548629)
			(xy 400.084616 -403.578095) (xy 400.125807 -403.613786) (xy 400.161499 -403.654976) (xy 400.190967 -403.700827)
			(xy 400.213608 -403.750405) (xy 400.228964 -403.8027) (xy 400.236721 -403.856648) (xy 400.236721 -403.911152)
			(xy 400.23672 -403.911156) (xy 401.674231 -403.911156) (xy 401.674231 -403.856644) (xy 401.681989 -403.802687)
			(xy 401.697348 -403.750383) (xy 401.719994 -403.700798) (xy 401.749467 -403.654941) (xy 401.785166 -403.613745)
			(xy 401.826365 -403.578049) (xy 401.872224 -403.54858) (xy 401.921812 -403.525937) (xy 401.974116 -403.510583)
			(xy 402.028074 -403.502829) (xy 402.05533 -403.502368) (xy 402.91893 -403.502368) (xy 402.946178 -403.502904)
			(xy 403.000119 -403.510664) (xy 403.052407 -403.52602) (xy 403.101977 -403.548662) (xy 403.147821 -403.578127)
			(xy 403.189005 -403.613816) (xy 403.224691 -403.655003) (xy 403.254153 -403.700849) (xy 403.27679 -403.750421)
			(xy 403.292143 -403.80271) (xy 403.299898 -403.856652) (xy 403.299898 -403.911148) (xy 403.299897 -403.911152)
			(xy 404.737554 -403.911152) (xy 404.737554 -403.856648) (xy 404.74531 -403.8027) (xy 404.760665 -403.750404)
			(xy 404.783305 -403.700826) (xy 404.81277 -403.654974) (xy 404.848461 -403.613782) (xy 404.88965 -403.578088)
			(xy 404.9355 -403.548619) (xy 404.985076 -403.525975) (xy 405.037371 -403.510616) (xy 405.091318 -403.502856)
			(xy 405.11857 -403.502368) (xy 405.98217 -403.502368) (xy 406.009423 -403.502877) (xy 406.063373 -403.51063)
			(xy 406.115671 -403.525983) (xy 406.165252 -403.548622) (xy 406.211106 -403.578087) (xy 406.2523 -403.613779)
			(xy 406.287995 -403.65497) (xy 406.317464 -403.700821) (xy 406.340107 -403.7504) (xy 406.355463 -403.802697)
			(xy 406.363221 -403.856647) (xy 406.363221 -403.911153) (xy 406.363221 -403.911155) (xy 407.800731 -403.911155)
			(xy 407.800731 -403.856645) (xy 407.808489 -403.80269) (xy 407.823846 -403.750388) (xy 407.846491 -403.700804)
			(xy 407.875962 -403.654947) (xy 407.911659 -403.613752) (xy 407.952855 -403.578056) (xy 407.998713 -403.548586)
			(xy 408.048297 -403.525943) (xy 408.100599 -403.510587) (xy 408.154555 -403.50283) (xy 408.18181 -403.502368)
			(xy 409.04541 -403.502368) (xy 409.072659 -403.502903) (xy 409.126602 -403.51066) (xy 409.178892 -403.526015)
			(xy 409.228465 -403.548655) (xy 409.274311 -403.57812) (xy 409.315498 -403.613809) (xy 409.351186 -403.654997)
			(xy 409.380649 -403.700844) (xy 409.403288 -403.750417) (xy 409.418642 -403.802708) (xy 409.426398 -403.856651)
			(xy 409.426398 -403.911149) (xy 409.426398 -403.911151) (xy 410.864054 -403.911151) (xy 410.864054 -403.856649)
			(xy 410.871809 -403.802703) (xy 410.887163 -403.750409) (xy 410.909802 -403.700832) (xy 410.939265 -403.654981)
			(xy 410.974954 -403.613789) (xy 411.016141 -403.578095) (xy 411.061988 -403.548626) (xy 411.111562 -403.52598)
			(xy 411.163854 -403.51062) (xy 411.217799 -403.502857) (xy 411.24505 -403.502368) (xy 412.10865 -403.502368)
			(xy 412.135903 -403.502876) (xy 412.189856 -403.510627) (xy 412.242157 -403.525977) (xy 412.29174 -403.548616)
			(xy 412.337597 -403.57808) (xy 412.378793 -403.613772) (xy 412.41449 -403.654963) (xy 412.44396 -403.700816)
			(xy 412.466605 -403.750396) (xy 412.481963 -403.802695) (xy 412.489721 -403.856647) (xy 412.489721 -403.911153)
			(xy 413.927254 -403.911153) (xy 413.927254 -403.856647) (xy 413.935011 -403.802697) (xy 413.950366 -403.7504)
			(xy 413.973008 -403.70082) (xy 414.002475 -403.654968) (xy 414.038168 -403.613775) (xy 414.07936 -403.578081)
			(xy 414.125212 -403.548613) (xy 414.174791 -403.52597) (xy 414.227087 -403.510613) (xy 414.281038 -403.502855)
			(xy 414.30829 -403.502368) (xy 415.17189 -403.502368) (xy 415.199142 -403.502879) (xy 415.25309 -403.510634)
			(xy 415.305386 -403.525988) (xy 415.354964 -403.548629) (xy 415.400816 -403.578095) (xy 415.442007 -403.613786)
			(xy 415.477699 -403.654976) (xy 415.507167 -403.700827) (xy 415.529808 -403.750405) (xy 415.545164 -403.8027)
			(xy 415.552921 -403.856648) (xy 415.552921 -403.911152) (xy 415.55292 -403.911156) (xy 416.990431 -403.911156)
			(xy 416.990431 -403.856644) (xy 416.998189 -403.802687) (xy 417.013548 -403.750383) (xy 417.036194 -403.700798)
			(xy 417.065667 -403.654941) (xy 417.101366 -403.613745) (xy 417.142565 -403.578049) (xy 417.188424 -403.54858)
			(xy 417.238012 -403.525937) (xy 417.290316 -403.510583) (xy 417.344274 -403.502829) (xy 417.37153 -403.502368)
			(xy 418.23513 -403.502368) (xy 418.262378 -403.502904) (xy 418.316319 -403.510664) (xy 418.368607 -403.52602)
			(xy 418.418177 -403.548662) (xy 418.464021 -403.578127) (xy 418.505205 -403.613816) (xy 418.540891 -403.655003)
			(xy 418.570353 -403.700849) (xy 418.59299 -403.750421) (xy 418.608343 -403.80271) (xy 418.616098 -403.856652)
			(xy 418.616098 -403.911148) (xy 418.608343 -403.96509) (xy 418.59299 -404.017379) (xy 418.570353 -404.066951)
			(xy 418.540891 -404.112797) (xy 418.505205 -404.153984) (xy 418.464021 -404.189673) (xy 418.418177 -404.219138)
			(xy 418.368607 -404.24178) (xy 418.316319 -404.257136) (xy 418.262378 -404.264896) (xy 418.23513 -404.265384)
			(xy 417.37153 -404.265384) (xy 417.344274 -404.264971) (xy 417.290316 -404.257217) (xy 417.238012 -404.241863)
			(xy 417.188424 -404.21922) (xy 417.142565 -404.189751) (xy 417.101366 -404.154055) (xy 417.065667 -404.112859)
			(xy 417.036194 -404.067002) (xy 417.013548 -404.017417) (xy 416.998189 -403.965113) (xy 416.990431 -403.911156)
			(xy 415.55292 -403.911156) (xy 415.545164 -403.9651) (xy 415.529808 -404.017395) (xy 415.507167 -404.066973)
			(xy 415.477699 -404.112824) (xy 415.442007 -404.154014) (xy 415.400816 -404.189705) (xy 415.354964 -404.219171)
			(xy 415.305386 -404.241812) (xy 415.25309 -404.257166) (xy 415.199142 -404.264921) (xy 415.17189 -404.265384)
			(xy 414.30829 -404.265384) (xy 414.281038 -404.264945) (xy 414.227087 -404.257187) (xy 414.174791 -404.24183)
			(xy 414.125212 -404.219187) (xy 414.07936 -404.189719) (xy 414.038168 -404.154025) (xy 414.002475 -404.112832)
			(xy 413.973008 -404.06698) (xy 413.950366 -404.0174) (xy 413.935011 -403.965103) (xy 413.927254 -403.911153)
			(xy 412.489721 -403.911153) (xy 412.481963 -403.965105) (xy 412.466605 -404.017404) (xy 412.44396 -404.066984)
			(xy 412.41449 -404.112837) (xy 412.378793 -404.154028) (xy 412.337597 -404.18972) (xy 412.29174 -404.219184)
			(xy 412.242157 -404.241823) (xy 412.189856 -404.257173) (xy 412.135903 -404.264924) (xy 412.10865 -404.265384)
			(xy 411.24505 -404.265384) (xy 411.217799 -404.264943) (xy 411.163854 -404.25718) (xy 411.111562 -404.24182)
			(xy 411.061988 -404.219174) (xy 411.016141 -404.189705) (xy 410.974954 -404.154011) (xy 410.939265 -404.112819)
			(xy 410.909802 -404.066968) (xy 410.887163 -404.017391) (xy 410.871809 -403.965097) (xy 410.864054 -403.911151)
			(xy 409.426398 -403.911151) (xy 409.418642 -403.965092) (xy 409.403288 -404.017383) (xy 409.380649 -404.066956)
			(xy 409.351186 -404.112803) (xy 409.315498 -404.153991) (xy 409.274311 -404.18968) (xy 409.228465 -404.219145)
			(xy 409.178892 -404.241785) (xy 409.126602 -404.25714) (xy 409.072659 -404.264897) (xy 409.04541 -404.265384)
			(xy 408.18181 -404.265384) (xy 408.154555 -404.26497) (xy 408.100599 -404.257213) (xy 408.048297 -404.241857)
			(xy 407.998713 -404.219214) (xy 407.952855 -404.189744) (xy 407.911659 -404.154048) (xy 407.875962 -404.112853)
			(xy 407.846491 -404.066996) (xy 407.823846 -404.017412) (xy 407.808489 -403.96511) (xy 407.800731 -403.911155)
			(xy 406.363221 -403.911155) (xy 406.355463 -403.965103) (xy 406.340107 -404.0174) (xy 406.317464 -404.066979)
			(xy 406.287995 -404.11283) (xy 406.2523 -404.154021) (xy 406.211106 -404.189713) (xy 406.165252 -404.219178)
			(xy 406.115671 -404.241817) (xy 406.063373 -404.25717) (xy 406.009423 -404.264923) (xy 405.98217 -404.265384)
			(xy 405.11857 -404.265384) (xy 405.091318 -404.264944) (xy 405.037371 -404.257184) (xy 404.985076 -404.241825)
			(xy 404.9355 -404.219181) (xy 404.88965 -404.189712) (xy 404.848461 -404.154018) (xy 404.81277 -404.112826)
			(xy 404.783305 -404.066974) (xy 404.760665 -404.017396) (xy 404.74531 -403.9651) (xy 404.737554 -403.911152)
			(xy 403.299897 -403.911152) (xy 403.292143 -403.96509) (xy 403.27679 -404.017379) (xy 403.254153 -404.066951)
			(xy 403.224691 -404.112797) (xy 403.189005 -404.153984) (xy 403.147821 -404.189673) (xy 403.101977 -404.219138)
			(xy 403.052407 -404.24178) (xy 403.000119 -404.257136) (xy 402.946178 -404.264896) (xy 402.91893 -404.265384)
			(xy 402.05533 -404.265384) (xy 402.028074 -404.264971) (xy 401.974116 -404.257217) (xy 401.921812 -404.241863)
			(xy 401.872224 -404.21922) (xy 401.826365 -404.189751) (xy 401.785166 -404.154055) (xy 401.749467 -404.112859)
			(xy 401.719994 -404.067002) (xy 401.697348 -404.017417) (xy 401.681989 -403.965113) (xy 401.674231 -403.911156)
			(xy 400.23672 -403.911156) (xy 400.228964 -403.9651) (xy 400.213608 -404.017395) (xy 400.190967 -404.066973)
			(xy 400.161499 -404.112824) (xy 400.125807 -404.154014) (xy 400.084616 -404.189705) (xy 400.038764 -404.219171)
			(xy 399.989186 -404.241812) (xy 399.93689 -404.257166) (xy 399.882942 -404.264921) (xy 399.85569 -404.265384)
			(xy 398.99209 -404.265384) (xy 398.964838 -404.264945) (xy 398.910887 -404.257187) (xy 398.858591 -404.24183)
			(xy 398.809012 -404.219187) (xy 398.76316 -404.189719) (xy 398.721968 -404.154025) (xy 398.686275 -404.112832)
			(xy 398.656808 -404.06698) (xy 398.634166 -404.0174) (xy 398.618811 -403.965103) (xy 398.611054 -403.911153)
			(xy 397.173521 -403.911153) (xy 397.165763 -403.965105) (xy 397.150405 -404.017404) (xy 397.12776 -404.066984)
			(xy 397.09829 -404.112837) (xy 397.062593 -404.154028) (xy 397.021397 -404.18972) (xy 396.97554 -404.219184)
			(xy 396.925957 -404.241823) (xy 396.873656 -404.257173) (xy 396.819703 -404.264924) (xy 396.79245 -404.265384)
			(xy 395.92885 -404.265384) (xy 395.901599 -404.264943) (xy 395.847654 -404.25718) (xy 395.795362 -404.24182)
			(xy 395.745788 -404.219174) (xy 395.699941 -404.189705) (xy 395.658754 -404.154011) (xy 395.623065 -404.112819)
			(xy 395.593602 -404.066968) (xy 395.570963 -404.017391) (xy 395.555609 -403.965097) (xy 395.547854 -403.911151)
			(xy 394.110198 -403.911151) (xy 394.102442 -403.965092) (xy 394.087088 -404.017383) (xy 394.064449 -404.066956)
			(xy 394.034986 -404.112803) (xy 393.999298 -404.153991) (xy 393.958111 -404.18968) (xy 393.912265 -404.219145)
			(xy 393.862692 -404.241785) (xy 393.810402 -404.25714) (xy 393.756459 -404.264897) (xy 393.72921 -404.265384)
			(xy 392.86561 -404.265384) (xy 392.838355 -404.26497) (xy 392.784399 -404.257213) (xy 392.732097 -404.241857)
			(xy 392.682513 -404.219214) (xy 392.636655 -404.189744) (xy 392.595459 -404.154048) (xy 392.559762 -404.112853)
			(xy 392.530291 -404.066996) (xy 392.507646 -404.017412) (xy 392.492289 -403.96511) (xy 392.484531 -403.911155)
			(xy 391.047021 -403.911155) (xy 391.039263 -403.965103) (xy 391.023907 -404.0174) (xy 391.001264 -404.066979)
			(xy 390.971795 -404.11283) (xy 390.9361 -404.154021) (xy 390.894906 -404.189713) (xy 390.849052 -404.219178)
			(xy 390.799471 -404.241817) (xy 390.747173 -404.25717) (xy 390.693223 -404.264923) (xy 390.66597 -404.265384)
			(xy 389.80237 -404.265384) (xy 389.775118 -404.264944) (xy 389.721171 -404.257184) (xy 389.668876 -404.241825)
			(xy 389.6193 -404.219181) (xy 389.57345 -404.189712) (xy 389.532261 -404.154018) (xy 389.49657 -404.112826)
			(xy 389.467105 -404.066974) (xy 389.444465 -404.017396) (xy 389.42911 -403.9651) (xy 389.421354 -403.911152)
			(xy 387.983697 -403.911152) (xy 387.975943 -403.96509) (xy 387.96059 -404.017379) (xy 387.937953 -404.066951)
			(xy 387.908491 -404.112797) (xy 387.872805 -404.153984) (xy 387.831621 -404.189673) (xy 387.785777 -404.219138)
			(xy 387.736207 -404.24178) (xy 387.683919 -404.257136) (xy 387.629978 -404.264896) (xy 387.60273 -404.265384)
			(xy 386.73913 -404.265384) (xy 386.711874 -404.264971) (xy 386.657916 -404.257217) (xy 386.605612 -404.241863)
			(xy 386.556024 -404.21922) (xy 386.510165 -404.189751) (xy 386.468966 -404.154055) (xy 386.433267 -404.112859)
			(xy 386.403794 -404.067002) (xy 386.381148 -404.017417) (xy 386.365789 -403.965113) (xy 386.358031 -403.911156)
			(xy 384.92052 -403.911156) (xy 384.912764 -403.9651) (xy 384.897408 -404.017395) (xy 384.874767 -404.066973)
			(xy 384.845299 -404.112824) (xy 384.809607 -404.154014) (xy 384.768416 -404.189705) (xy 384.722564 -404.219171)
			(xy 384.672986 -404.241812) (xy 384.62069 -404.257166) (xy 384.566742 -404.264921) (xy 384.53949 -404.265384)
			(xy 383.67589 -404.265384) (xy 383.648638 -404.264945) (xy 383.594687 -404.257187) (xy 383.542391 -404.24183)
			(xy 383.492812 -404.219187) (xy 383.44696 -404.189719) (xy 383.405768 -404.154025) (xy 383.370075 -404.112832)
			(xy 383.340608 -404.06698) (xy 383.317966 -404.0174) (xy 383.302611 -403.965103) (xy 383.294854 -403.911153)
			(xy 381.857321 -403.911153) (xy 381.849563 -403.965105) (xy 381.834205 -404.017404) (xy 381.81156 -404.066984)
			(xy 381.78209 -404.112837) (xy 381.746393 -404.154028) (xy 381.705197 -404.18972) (xy 381.65934 -404.219184)
			(xy 381.609757 -404.241823) (xy 381.557456 -404.257173) (xy 381.503503 -404.264924) (xy 381.47625 -404.265384)
			(xy 380.61265 -404.265384) (xy 380.585399 -404.264943) (xy 380.531454 -404.25718) (xy 380.479162 -404.24182)
			(xy 380.429588 -404.219174) (xy 380.383741 -404.189705) (xy 380.342554 -404.154011) (xy 380.306865 -404.112819)
			(xy 380.277402 -404.066968) (xy 380.254763 -404.017391) (xy 380.239409 -403.965097) (xy 380.231654 -403.911151)
			(xy 378.793998 -403.911151) (xy 378.786242 -403.965092) (xy 378.770888 -404.017383) (xy 378.748249 -404.066956)
			(xy 378.718786 -404.112803) (xy 378.683098 -404.153991) (xy 378.641911 -404.18968) (xy 378.596065 -404.219145)
			(xy 378.546492 -404.241785) (xy 378.494202 -404.25714) (xy 378.440259 -404.264897) (xy 378.41301 -404.265384)
			(xy 377.54941 -404.265384) (xy 377.522155 -404.26497) (xy 377.468199 -404.257213) (xy 377.415897 -404.241857)
			(xy 377.366313 -404.219214) (xy 377.320455 -404.189744) (xy 377.279259 -404.154048) (xy 377.243562 -404.112853)
			(xy 377.214091 -404.066996) (xy 377.191446 -404.017412) (xy 377.176089 -403.96511) (xy 377.168331 -403.911155)
			(xy 375.730821 -403.911155) (xy 375.723063 -403.965103) (xy 375.707707 -404.0174) (xy 375.685064 -404.066979)
			(xy 375.655595 -404.11283) (xy 375.6199 -404.154021) (xy 375.578706 -404.189713) (xy 375.532852 -404.219178)
			(xy 375.483271 -404.241817) (xy 375.430973 -404.25717) (xy 375.377023 -404.264923) (xy 375.34977 -404.265384)
			(xy 374.48617 -404.265384) (xy 374.458918 -404.264944) (xy 374.404971 -404.257184) (xy 374.352676 -404.241825)
			(xy 374.3031 -404.219181) (xy 374.25725 -404.189712) (xy 374.216061 -404.154018) (xy 374.18037 -404.112826)
			(xy 374.150905 -404.066974) (xy 374.128265 -404.017396) (xy 374.11291 -403.9651) (xy 374.105154 -403.911152)
			(xy 372.667497 -403.911152) (xy 372.659743 -403.96509) (xy 372.64439 -404.017379) (xy 372.621753 -404.066951)
			(xy 372.592291 -404.112797) (xy 372.556605 -404.153984) (xy 372.515421 -404.189673) (xy 372.469577 -404.219138)
			(xy 372.420007 -404.24178) (xy 372.367719 -404.257136) (xy 372.313778 -404.264896) (xy 372.28653 -404.265384)
			(xy 371.42293 -404.265384) (xy 371.395674 -404.264971) (xy 371.341716 -404.257217) (xy 371.289412 -404.241863)
			(xy 371.239824 -404.21922) (xy 371.193965 -404.189751) (xy 371.152766 -404.154055) (xy 371.117067 -404.112859)
			(xy 371.087594 -404.067002) (xy 371.064948 -404.017417) (xy 371.049589 -403.965113) (xy 371.041831 -403.911156)
			(xy 351.17332 -403.911156) (xy 351.165564 -403.9651) (xy 351.150208 -404.017396) (xy 351.127566 -404.066974)
			(xy 351.098099 -404.112824) (xy 351.062406 -404.154015) (xy 351.021215 -404.189706) (xy 350.975363 -404.219172)
			(xy 350.925785 -404.241812) (xy 350.873489 -404.257166) (xy 350.81954 -404.264922) (xy 350.792288 -404.265384)
			(xy 349.928688 -404.265384) (xy 349.901436 -404.264945) (xy 349.847486 -404.257187) (xy 349.795189 -404.24183)
			(xy 349.74561 -404.219187) (xy 349.699759 -404.189718) (xy 349.658567 -404.154024) (xy 349.622875 -404.112832)
			(xy 349.593408 -404.066979) (xy 349.570766 -404.0174) (xy 349.55541 -403.965102) (xy 349.547654 -403.911152)
			(xy 348.109997 -403.911152) (xy 348.102243 -403.965087) (xy 348.086891 -404.017375) (xy 348.064255 -404.066946)
			(xy 348.034795 -404.112791) (xy 347.999111 -404.153977) (xy 347.957929 -404.189667) (xy 347.912088 -404.219132)
			(xy 347.86252 -404.241775) (xy 347.810234 -404.257133) (xy 347.756295 -404.264895) (xy 347.729048 -404.265384)
			(xy 346.865448 -404.265384) (xy 346.838191 -404.264972) (xy 346.784232 -404.25722) (xy 346.731925 -404.241868)
			(xy 346.682335 -404.219226) (xy 346.636473 -404.189758) (xy 346.595272 -404.154062) (xy 346.559571 -404.112865)
			(xy 346.530097 -404.067007) (xy 346.507449 -404.01742) (xy 346.49209 -403.965115) (xy 346.484331 -403.911157)
			(xy 345.046797 -403.911157) (xy 345.039042 -403.965093) (xy 345.023688 -404.017383) (xy 345.001049 -404.066957)
			(xy 344.971586 -404.112804) (xy 344.935897 -404.153991) (xy 344.89471 -404.189681) (xy 344.848864 -404.219145)
			(xy 344.799291 -404.241785) (xy 344.747001 -404.25714) (xy 344.693057 -404.264897) (xy 344.665808 -404.265384)
			(xy 343.802208 -404.265384) (xy 343.774953 -404.26497) (xy 343.720998 -404.257213) (xy 343.668696 -404.241857)
			(xy 343.619111 -404.219213) (xy 343.573254 -404.189744) (xy 343.532058 -404.154048) (xy 343.496361 -404.112852)
			(xy 343.466891 -404.066996) (xy 343.444246 -404.017412) (xy 343.428889 -403.96511) (xy 343.421131 -403.911155)
			(xy 341.983621 -403.911155) (xy 341.975863 -403.965103) (xy 341.960507 -404.0174) (xy 341.937863 -404.066979)
			(xy 341.908394 -404.112831) (xy 341.872699 -404.154022) (xy 341.831505 -404.189713) (xy 341.785651 -404.219179)
			(xy 341.73607 -404.241818) (xy 341.683772 -404.25717) (xy 341.629821 -404.264923) (xy 341.602568 -404.265384)
			(xy 340.738968 -404.265384) (xy 340.711717 -404.264944) (xy 340.657769 -404.257183) (xy 340.605475 -404.241824)
			(xy 340.555898 -404.21918) (xy 340.510049 -404.189711) (xy 340.46886 -404.154017) (xy 340.43317 -404.112825)
			(xy 340.403705 -404.066974) (xy 340.381064 -404.017395) (xy 340.36571 -403.9651) (xy 340.357954 -403.911152)
			(xy 338.920297 -403.911152) (xy 338.912543 -403.96509) (xy 338.89719 -404.017379) (xy 338.874552 -404.066951)
			(xy 338.84509 -404.112798) (xy 338.809404 -404.153984) (xy 338.76822 -404.189674) (xy 338.722376 -404.219139)
			(xy 338.672805 -404.24178) (xy 338.620517 -404.257137) (xy 338.566576 -404.264896) (xy 338.539328 -404.265384)
			(xy 337.675728 -404.265384) (xy 337.648472 -404.264971) (xy 337.594515 -404.257217) (xy 337.54221 -404.241862)
			(xy 337.492623 -404.21922) (xy 337.446764 -404.189751) (xy 337.405565 -404.154055) (xy 337.369866 -404.112859)
			(xy 337.340394 -404.067001) (xy 337.317748 -404.017416) (xy 337.302389 -403.965113) (xy 337.294631 -403.911156)
			(xy 335.85712 -403.911156) (xy 335.849364 -403.9651) (xy 335.834008 -404.017396) (xy 335.811366 -404.066974)
			(xy 335.781899 -404.112824) (xy 335.746206 -404.154015) (xy 335.705015 -404.189706) (xy 335.659163 -404.219172)
			(xy 335.609585 -404.241812) (xy 335.557289 -404.257166) (xy 335.50334 -404.264922) (xy 335.476088 -404.265384)
			(xy 334.612488 -404.265384) (xy 334.585236 -404.264945) (xy 334.531286 -404.257187) (xy 334.478989 -404.24183)
			(xy 334.42941 -404.219187) (xy 334.383559 -404.189718) (xy 334.342367 -404.154024) (xy 334.306675 -404.112832)
			(xy 334.277208 -404.066979) (xy 334.254566 -404.0174) (xy 334.23921 -403.965102) (xy 334.231454 -403.911152)
			(xy 332.793797 -403.911152) (xy 332.786043 -403.965087) (xy 332.770691 -404.017375) (xy 332.748055 -404.066946)
			(xy 332.718595 -404.112791) (xy 332.682911 -404.153977) (xy 332.641729 -404.189667) (xy 332.595888 -404.219132)
			(xy 332.54632 -404.241775) (xy 332.494034 -404.257133) (xy 332.440095 -404.264895) (xy 332.412848 -404.265384)
			(xy 331.549248 -404.265384) (xy 331.521991 -404.264972) (xy 331.468032 -404.25722) (xy 331.415725 -404.241868)
			(xy 331.366135 -404.219226) (xy 331.320273 -404.189758) (xy 331.279072 -404.154062) (xy 331.243371 -404.112865)
			(xy 331.213897 -404.067007) (xy 331.191249 -404.01742) (xy 331.17589 -403.965115) (xy 331.168131 -403.911157)
			(xy 329.730597 -403.911157) (xy 329.722842 -403.965093) (xy 329.707488 -404.017383) (xy 329.684849 -404.066957)
			(xy 329.655386 -404.112804) (xy 329.619697 -404.153991) (xy 329.57851 -404.189681) (xy 329.532664 -404.219145)
			(xy 329.483091 -404.241785) (xy 329.430801 -404.25714) (xy 329.376857 -404.264897) (xy 329.349608 -404.265384)
			(xy 328.486008 -404.265384) (xy 328.458753 -404.26497) (xy 328.404798 -404.257213) (xy 328.352496 -404.241857)
			(xy 328.302911 -404.219213) (xy 328.257054 -404.189744) (xy 328.215858 -404.154048) (xy 328.180161 -404.112852)
			(xy 328.150691 -404.066996) (xy 328.128046 -404.017412) (xy 328.112689 -403.96511) (xy 328.104931 -403.911155)
			(xy 326.667421 -403.911155) (xy 326.659663 -403.965103) (xy 326.644307 -404.0174) (xy 326.621663 -404.066979)
			(xy 326.592194 -404.112831) (xy 326.556499 -404.154022) (xy 326.515305 -404.189713) (xy 326.469451 -404.219179)
			(xy 326.41987 -404.241818) (xy 326.367572 -404.25717) (xy 326.313621 -404.264923) (xy 326.286368 -404.265384)
			(xy 325.422768 -404.265384) (xy 325.395517 -404.264944) (xy 325.341569 -404.257183) (xy 325.289275 -404.241824)
			(xy 325.239698 -404.21918) (xy 325.193849 -404.189711) (xy 325.15266 -404.154017) (xy 325.11697 -404.112825)
			(xy 325.087505 -404.066974) (xy 325.064864 -404.017395) (xy 325.04951 -403.9651) (xy 325.041754 -403.911152)
			(xy 323.604097 -403.911152) (xy 323.596343 -403.96509) (xy 323.58099 -404.017379) (xy 323.558352 -404.066951)
			(xy 323.52889 -404.112798) (xy 323.493204 -404.153984) (xy 323.45202 -404.189674) (xy 323.406176 -404.219139)
			(xy 323.356605 -404.24178) (xy 323.304317 -404.257137) (xy 323.250376 -404.264896) (xy 323.223128 -404.265384)
			(xy 322.359528 -404.265384) (xy 322.332272 -404.264971) (xy 322.278315 -404.257217) (xy 322.22601 -404.241862)
			(xy 322.176423 -404.21922) (xy 322.130564 -404.189751) (xy 322.089365 -404.154055) (xy 322.053666 -404.112859)
			(xy 322.024194 -404.067001) (xy 322.001548 -404.017416) (xy 321.986189 -403.965113) (xy 321.978431 -403.911156)
			(xy 320.54092 -403.911156) (xy 320.533164 -403.9651) (xy 320.517808 -404.017396) (xy 320.495166 -404.066974)
			(xy 320.465699 -404.112824) (xy 320.430006 -404.154015) (xy 320.388815 -404.189706) (xy 320.342963 -404.219172)
			(xy 320.293385 -404.241812) (xy 320.241089 -404.257166) (xy 320.18714 -404.264922) (xy 320.159888 -404.265384)
			(xy 319.296288 -404.265384) (xy 319.269036 -404.264945) (xy 319.215086 -404.257187) (xy 319.162789 -404.24183)
			(xy 319.11321 -404.219187) (xy 319.067359 -404.189718) (xy 319.026167 -404.154024) (xy 318.990475 -404.112832)
			(xy 318.961008 -404.066979) (xy 318.938366 -404.0174) (xy 318.92301 -403.965102) (xy 318.915254 -403.911152)
			(xy 317.477597 -403.911152) (xy 317.469843 -403.965087) (xy 317.454491 -404.017375) (xy 317.431855 -404.066946)
			(xy 317.402395 -404.112791) (xy 317.366711 -404.153977) (xy 317.325529 -404.189667) (xy 317.279688 -404.219132)
			(xy 317.23012 -404.241775) (xy 317.177834 -404.257133) (xy 317.123895 -404.264895) (xy 317.096648 -404.265384)
			(xy 316.233048 -404.265384) (xy 316.205791 -404.264972) (xy 316.151832 -404.25722) (xy 316.099525 -404.241868)
			(xy 316.049935 -404.219226) (xy 316.004073 -404.189758) (xy 315.962872 -404.154062) (xy 315.927171 -404.112865)
			(xy 315.897697 -404.067007) (xy 315.875049 -404.01742) (xy 315.85969 -403.965115) (xy 315.851931 -403.911157)
			(xy 314.414397 -403.911157) (xy 314.406642 -403.965093) (xy 314.391288 -404.017383) (xy 314.368649 -404.066957)
			(xy 314.339186 -404.112804) (xy 314.303497 -404.153991) (xy 314.26231 -404.189681) (xy 314.216464 -404.219145)
			(xy 314.166891 -404.241785) (xy 314.114601 -404.25714) (xy 314.060657 -404.264897) (xy 314.033408 -404.265384)
			(xy 313.169808 -404.265384) (xy 313.142553 -404.26497) (xy 313.088598 -404.257213) (xy 313.036296 -404.241857)
			(xy 312.986711 -404.219213) (xy 312.940854 -404.189744) (xy 312.899658 -404.154048) (xy 312.863961 -404.112852)
			(xy 312.834491 -404.066996) (xy 312.811846 -404.017412) (xy 312.796489 -403.96511) (xy 312.788731 -403.911155)
			(xy 311.351221 -403.911155) (xy 311.343463 -403.965103) (xy 311.328107 -404.0174) (xy 311.305463 -404.066979)
			(xy 311.275994 -404.112831) (xy 311.240299 -404.154022) (xy 311.199105 -404.189713) (xy 311.153251 -404.219179)
			(xy 311.10367 -404.241818) (xy 311.051372 -404.25717) (xy 310.997421 -404.264923) (xy 310.970168 -404.265384)
			(xy 310.106568 -404.265384) (xy 310.079317 -404.264944) (xy 310.025369 -404.257183) (xy 309.973075 -404.241824)
			(xy 309.923498 -404.21918) (xy 309.877649 -404.189711) (xy 309.83646 -404.154017) (xy 309.80077 -404.112825)
			(xy 309.771305 -404.066974) (xy 309.748664 -404.017395) (xy 309.73331 -403.9651) (xy 309.725554 -403.911152)
			(xy 308.287897 -403.911152) (xy 308.280143 -403.96509) (xy 308.26479 -404.017379) (xy 308.242152 -404.066951)
			(xy 308.21269 -404.112798) (xy 308.177004 -404.153984) (xy 308.13582 -404.189674) (xy 308.089976 -404.219139)
			(xy 308.040405 -404.24178) (xy 307.988117 -404.257137) (xy 307.934176 -404.264896) (xy 307.906928 -404.265384)
			(xy 307.043328 -404.265384) (xy 307.016072 -404.264971) (xy 306.962115 -404.257217) (xy 306.90981 -404.241862)
			(xy 306.860223 -404.21922) (xy 306.814364 -404.189751) (xy 306.773165 -404.154055) (xy 306.737466 -404.112859)
			(xy 306.707994 -404.067001) (xy 306.685348 -404.017416) (xy 306.669989 -403.965113) (xy 306.662231 -403.911156)
			(xy 305.22472 -403.911156) (xy 305.216964 -403.9651) (xy 305.201608 -404.017396) (xy 305.178966 -404.066974)
			(xy 305.149499 -404.112824) (xy 305.113806 -404.154015) (xy 305.072615 -404.189706) (xy 305.026763 -404.219172)
			(xy 304.977185 -404.241812) (xy 304.924889 -404.257166) (xy 304.87094 -404.264922) (xy 304.843688 -404.265384)
			(xy 303.980088 -404.265384) (xy 303.952836 -404.264945) (xy 303.898886 -404.257187) (xy 303.846589 -404.24183)
			(xy 303.79701 -404.219187) (xy 303.751159 -404.189718) (xy 303.709967 -404.154024) (xy 303.674275 -404.112832)
			(xy 303.644808 -404.066979) (xy 303.622166 -404.0174) (xy 303.60681 -403.965102) (xy 303.599054 -403.911152)
			(xy 298.836897 -403.911152) (xy 298.840074 -403.920931) (xy 298.852049 -403.983712) (xy 298.856063 -404.0475)
			(xy 298.852049 -404.111288) (xy 298.840074 -404.174069) (xy 298.820324 -404.234855) (xy 298.793112 -404.292686)
			(xy 298.758866 -404.346651) (xy 298.718128 -404.395898) (xy 298.671538 -404.439652) (xy 298.619832 -404.477221)
			(xy 298.563825 -404.508014) (xy 298.504401 -404.531545) (xy 298.442496 -404.547442) (xy 298.379087 -404.555456)
			(xy 298.34713 -404.55596) (xy 298.346876 -404.55596) (xy 298.315131 -404.555422) (xy 298.252136 -404.547497)
			(xy 298.190616 -404.531797) (xy 298.131527 -404.508566) (xy 298.075787 -404.478166) (xy 298.024261 -404.441069)
			(xy 298.000674 -404.419816) (xy 297.993411 -404.413632) (xy 297.975661 -404.406681) (xy 297.956599 -404.406681)
			(xy 297.938849 -404.413632) (xy 297.931586 -404.419816) (xy 297.908028 -404.441107) (xy 297.856512 -404.478235)
			(xy 297.800771 -404.508654) (xy 297.741674 -404.531889) (xy 297.680142 -404.547579) (xy 297.617135 -404.555478)
			(xy 297.585384 -404.55596) (xy 297.58513 -404.55596) (xy 297.553163 -404.555577) (xy 297.489734 -404.547567)
			(xy 297.427809 -404.531671) (xy 297.368364 -404.508138) (xy 297.312338 -404.47734) (xy 297.260613 -404.439763)
			(xy 297.214007 -404.395999) (xy 297.173253 -404.346739) (xy 297.138995 -404.292759) (xy 297.111773 -404.234911)
			(xy 297.092015 -404.174108) (xy 297.080035 -404.111307) (xy 297.07602 -404.0475) (xy 296.316063 -404.0475)
			(xy 296.312049 -404.111288) (xy 296.300074 -404.174069) (xy 296.280324 -404.234855) (xy 296.253112 -404.292686)
			(xy 296.218866 -404.346651) (xy 296.178128 -404.395898) (xy 296.131538 -404.439652) (xy 296.079832 -404.477221)
			(xy 296.023825 -404.508014) (xy 295.964401 -404.531545) (xy 295.902496 -404.547442) (xy 295.839087 -404.555456)
			(xy 295.80713 -404.55596) (xy 295.806876 -404.55596) (xy 295.775131 -404.555422) (xy 295.712136 -404.547497)
			(xy 295.650616 -404.531797) (xy 295.591527 -404.508566) (xy 295.535787 -404.478166) (xy 295.484261 -404.441069)
			(xy 295.460674 -404.419816) (xy 295.453411 -404.413632) (xy 295.435661 -404.406681) (xy 295.416599 -404.406681)
			(xy 295.398849 -404.413632) (xy 295.391586 -404.419816) (xy 295.368028 -404.441107) (xy 295.316512 -404.478235)
			(xy 295.260771 -404.508654) (xy 295.201674 -404.531889) (xy 295.140142 -404.547579) (xy 295.077135 -404.555478)
			(xy 295.045384 -404.55596) (xy 295.04513 -404.55596) (xy 295.013163 -404.555577) (xy 294.949734 -404.547567)
			(xy 294.887809 -404.531671) (xy 294.828364 -404.508138) (xy 294.772338 -404.47734) (xy 294.720613 -404.439763)
			(xy 294.674007 -404.395999) (xy 294.633253 -404.346739) (xy 294.598995 -404.292759) (xy 294.571773 -404.234911)
			(xy 294.552015 -404.174108) (xy 294.540035 -404.111307) (xy 294.53602 -404.0475) (xy 293.926484 -404.0475)
			(xy 293.92247 -404.111293) (xy 293.910493 -404.174079) (xy 293.890741 -404.23487) (xy 293.863525 -404.292705)
			(xy 293.829276 -404.346674) (xy 293.788532 -404.395924) (xy 293.741937 -404.439679) (xy 293.690226 -404.47725)
			(xy 293.634213 -404.508043) (xy 293.574783 -404.531573) (xy 293.512872 -404.547468) (xy 293.449457 -404.555479)
			(xy 293.417498 -404.55596) (xy 293.417244 -404.55596) (xy 293.385498 -404.555442) (xy 293.322502 -404.547512)
			(xy 293.260982 -404.531809) (xy 293.201894 -404.508575) (xy 293.146154 -404.478171) (xy 293.094629 -404.44107)
			(xy 293.071042 -404.419816) (xy 293.063779 -404.413632) (xy 293.046029 -404.406681) (xy 293.026967 -404.406681)
			(xy 293.009217 -404.413632) (xy 293.001954 -404.419816) (xy 292.978367 -404.441074) (xy 292.926858 -404.478206)
			(xy 292.871123 -404.50863) (xy 292.812032 -404.531871) (xy 292.750504 -404.547567) (xy 292.687501 -404.555474)
			(xy 292.655752 -404.55596) (xy 292.655498 -404.55596) (xy 292.623534 -404.555554) (xy 292.56011 -404.547542)
			(xy 292.498191 -404.531643) (xy 292.438752 -404.50811) (xy 292.382731 -404.477312) (xy 292.331013 -404.439736)
			(xy 292.284411 -404.395974) (xy 292.243662 -404.346717) (xy 292.209408 -404.29274) (xy 292.182189 -404.234897)
			(xy 292.162434 -404.174098) (xy 292.150455 -404.111302) (xy 292.146441 -404.0475) (xy 291.386484 -404.0475)
			(xy 291.38247 -404.111293) (xy 291.370493 -404.174079) (xy 291.350741 -404.23487) (xy 291.323525 -404.292705)
			(xy 291.289276 -404.346674) (xy 291.248532 -404.395924) (xy 291.201937 -404.439679) (xy 291.150226 -404.47725)
			(xy 291.094213 -404.508043) (xy 291.034783 -404.531573) (xy 290.972872 -404.547468) (xy 290.909457 -404.555479)
			(xy 290.877498 -404.55596) (xy 290.877244 -404.55596) (xy 290.845498 -404.555442) (xy 290.782502 -404.547512)
			(xy 290.720982 -404.531809) (xy 290.661894 -404.508575) (xy 290.606154 -404.478171) (xy 290.554629 -404.44107)
			(xy 290.531042 -404.419816) (xy 290.523779 -404.413632) (xy 290.506029 -404.406681) (xy 290.486967 -404.406681)
			(xy 290.469217 -404.413632) (xy 290.461954 -404.419816) (xy 290.438367 -404.441074) (xy 290.386858 -404.478206)
			(xy 290.331123 -404.50863) (xy 290.272032 -404.531871) (xy 290.210504 -404.547567) (xy 290.147501 -404.555474)
			(xy 290.115752 -404.55596) (xy 290.115498 -404.55596) (xy 290.083534 -404.555554) (xy 290.02011 -404.547542)
			(xy 289.958191 -404.531643) (xy 289.898752 -404.50811) (xy 289.842731 -404.477312) (xy 289.791013 -404.439736)
			(xy 289.744411 -404.395974) (xy 289.703662 -404.346717) (xy 289.669408 -404.29274) (xy 289.642189 -404.234897)
			(xy 289.622434 -404.174098) (xy 289.610455 -404.111302) (xy 289.606441 -404.0475) (xy 288.846484 -404.0475)
			(xy 288.84247 -404.111293) (xy 288.830493 -404.174079) (xy 288.810741 -404.23487) (xy 288.783525 -404.292705)
			(xy 288.749276 -404.346674) (xy 288.708532 -404.395924) (xy 288.661937 -404.439679) (xy 288.610226 -404.47725)
			(xy 288.554213 -404.508043) (xy 288.494783 -404.531573) (xy 288.432872 -404.547468) (xy 288.369457 -404.555479)
			(xy 288.337498 -404.55596) (xy 288.337244 -404.55596) (xy 288.305498 -404.555442) (xy 288.242502 -404.547512)
			(xy 288.180982 -404.531809) (xy 288.121894 -404.508575) (xy 288.066154 -404.478171) (xy 288.014629 -404.44107)
			(xy 287.991042 -404.419816) (xy 287.983779 -404.413632) (xy 287.966029 -404.406681) (xy 287.946967 -404.406681)
			(xy 287.929217 -404.413632) (xy 287.921954 -404.419816) (xy 287.898367 -404.441074) (xy 287.846858 -404.478206)
			(xy 287.791123 -404.50863) (xy 287.732032 -404.531871) (xy 287.670504 -404.547567) (xy 287.607501 -404.555474)
			(xy 287.575752 -404.55596) (xy 287.575498 -404.55596) (xy 287.543534 -404.555554) (xy 287.48011 -404.547542)
			(xy 287.418191 -404.531643) (xy 287.358752 -404.50811) (xy 287.302731 -404.477312) (xy 287.251013 -404.439736)
			(xy 287.204411 -404.395974) (xy 287.163662 -404.346717) (xy 287.129408 -404.29274) (xy 287.102189 -404.234897)
			(xy 287.082434 -404.174098) (xy 287.070455 -404.111302) (xy 287.066441 -404.0475) (xy 281.686508 -404.0475)
			(xy 281.686508 -405.908764) (xy 281.686047 -405.933716) (xy 281.678246 -405.983008) (xy 281.662829 -406.030472)
			(xy 281.640178 -406.07494) (xy 281.610848 -406.115316) (xy 281.593544 -406.1333) (xy 281.262328 -406.464516)
			(xy 281.244328 -406.481797) (xy 281.203943 -406.511099) (xy 281.159477 -406.533733) (xy 281.11202 -406.549144)
			(xy 281.06274 -406.556952) (xy 281.037792 -406.55748) (xy 278.18334 -406.55748) (xy 278.17335 -406.558673)
			(xy 278.153269 -406.559941) (xy 278.143208 -406.56002) (xy 275.351748 -406.56002) (xy 275.326797 -406.559534)
			(xy 275.277509 -406.551736) (xy 275.230047 -406.536322) (xy 275.185581 -406.513674) (xy 275.145205 -406.484349)
			(xy 275.127212 -406.467056) (xy 275.088096 -406.42794) (xy 275.077426 -406.418067) (xy 275.05188 -406.404223)
			(xy 275.023469 -406.398135) (xy 274.994494 -406.400297) (xy 274.9673 -406.410533) (xy 274.944091 -406.428014)
			(xy 274.926746 -406.451325) (xy 274.921218 -406.46477) (xy 274.908109 -406.502967) (xy 274.874163 -406.576246)
			(xy 274.831847 -406.645033) (xy 274.781748 -406.708375) (xy 274.753578 -406.737312) (xy 274.459335 -407.031749)
			(xy 304.945298 -407.031749) (xy 304.945298 -406.977251) (xy 304.953054 -406.923307) (xy 304.968408 -406.871016)
			(xy 304.991047 -406.821442) (xy 305.02051 -406.775595) (xy 305.056199 -406.734407) (xy 305.097385 -406.698718)
			(xy 305.143232 -406.669252) (xy 305.192805 -406.646612) (xy 305.245095 -406.631257) (xy 305.299039 -406.623499)
			(xy 305.326288 -406.623012) (xy 306.189888 -406.623012) (xy 306.217143 -406.623434) (xy 306.271098 -406.63119)
			(xy 306.3234 -406.646546) (xy 306.372984 -406.669189) (xy 306.418841 -406.698658) (xy 306.460038 -406.734354)
			(xy 306.495735 -406.775549) (xy 306.525205 -406.821405) (xy 306.54785 -406.870989) (xy 306.563207 -406.92329)
			(xy 306.570965 -406.977245) (xy 306.570965 -407.031753) (xy 308.008475 -407.031753) (xy 308.008475 -406.977247)
			(xy 308.016233 -406.923297) (xy 308.031589 -406.870999) (xy 308.054233 -406.82142) (xy 308.083702 -406.775568)
			(xy 308.119397 -406.734377) (xy 308.16059 -406.698685) (xy 308.206445 -406.669219) (xy 308.256026 -406.64658)
			(xy 308.308324 -406.631227) (xy 308.362275 -406.623473) (xy 308.389528 -406.623012) (xy 309.253128 -406.623012)
			(xy 309.280379 -406.62346) (xy 309.334327 -406.63122) (xy 309.386621 -406.646578) (xy 309.436197 -406.669222)
			(xy 309.482047 -406.698691) (xy 309.523236 -406.734384) (xy 309.558926 -406.775576) (xy 309.588391 -406.821427)
			(xy 309.611032 -406.871005) (xy 309.626386 -406.923301) (xy 309.634142 -406.977249) (xy 309.634142 -407.031748)
			(xy 311.071798 -407.031748) (xy 311.071798 -406.977252) (xy 311.079553 -406.92331) (xy 311.094906 -406.87102)
			(xy 311.117544 -406.821448) (xy 311.147005 -406.775601) (xy 311.182692 -406.734414) (xy 311.223876 -406.698725)
			(xy 311.26972 -406.669259) (xy 311.31929 -406.646617) (xy 311.371578 -406.63126) (xy 311.42552 -406.6235)
			(xy 311.452768 -406.623012) (xy 312.316368 -406.623012) (xy 312.343624 -406.623433) (xy 312.397581 -406.631186)
			(xy 312.449886 -406.64654) (xy 312.499472 -406.669182) (xy 312.545332 -406.698651) (xy 312.586531 -406.734347)
			(xy 312.62223 -406.775542) (xy 312.651702 -406.821399) (xy 312.674348 -406.870984) (xy 312.689707 -406.923288)
			(xy 312.697465 -406.977244) (xy 312.697465 -407.031752) (xy 314.134975 -407.031752) (xy 314.134975 -406.977248)
			(xy 314.142732 -406.923299) (xy 314.158088 -406.871004) (xy 314.18073 -406.821426) (xy 314.210197 -406.775575)
			(xy 314.245889 -406.734384) (xy 314.287081 -406.698692) (xy 314.332933 -406.669226) (xy 314.382511 -406.646585)
			(xy 314.434807 -406.63123) (xy 314.488756 -406.623475) (xy 314.516008 -406.623012) (xy 315.379608 -406.623012)
			(xy 315.40686 -406.623458) (xy 315.46081 -406.631216) (xy 315.513107 -406.646573) (xy 315.562685 -406.669216)
			(xy 315.608537 -406.698684) (xy 315.649729 -406.734377) (xy 315.685421 -406.775569) (xy 315.714888 -406.821422)
			(xy 315.73753 -406.871001) (xy 315.752885 -406.923298) (xy 315.760642 -406.977248) (xy 315.760642 -407.031752)
			(xy 315.760642 -407.031754) (xy 317.198175 -407.031754) (xy 317.198175 -406.977246) (xy 317.205933 -406.923294)
			(xy 317.221291 -406.870995) (xy 317.243936 -406.821414) (xy 317.273407 -406.775561) (xy 317.309104 -406.73437)
			(xy 317.3503 -406.698678) (xy 317.396157 -406.669213) (xy 317.44574 -406.646574) (xy 317.498041 -406.631223)
			(xy 317.551994 -406.623472) (xy 317.579248 -406.623012) (xy 318.442848 -406.623012) (xy 318.470098 -406.623461)
			(xy 318.524044 -406.631224) (xy 318.576336 -406.646584) (xy 318.625909 -406.669229) (xy 318.671756 -406.698698)
			(xy 318.712943 -406.734391) (xy 318.748631 -406.775582) (xy 318.778094 -406.821433) (xy 318.800733 -406.87101)
			(xy 318.816087 -406.923303) (xy 318.823842 -406.97725) (xy 318.823842 -407.031749) (xy 320.261498 -407.031749)
			(xy 320.261498 -406.977251) (xy 320.269254 -406.923307) (xy 320.284608 -406.871016) (xy 320.307247 -406.821442)
			(xy 320.33671 -406.775595) (xy 320.372399 -406.734407) (xy 320.413585 -406.698718) (xy 320.459432 -406.669252)
			(xy 320.509005 -406.646612) (xy 320.561295 -406.631257) (xy 320.615239 -406.623499) (xy 320.642488 -406.623012)
			(xy 321.506088 -406.623012) (xy 321.533343 -406.623434) (xy 321.587298 -406.63119) (xy 321.6396 -406.646546)
			(xy 321.689184 -406.669189) (xy 321.735041 -406.698658) (xy 321.776238 -406.734354) (xy 321.811935 -406.775549)
			(xy 321.841405 -406.821405) (xy 321.86405 -406.870989) (xy 321.879407 -406.92329) (xy 321.887165 -406.977245)
			(xy 321.887165 -407.031753) (xy 323.324675 -407.031753) (xy 323.324675 -406.977247) (xy 323.332433 -406.923297)
			(xy 323.347789 -406.870999) (xy 323.370433 -406.82142) (xy 323.399902 -406.775568) (xy 323.435597 -406.734377)
			(xy 323.47679 -406.698685) (xy 323.522645 -406.669219) (xy 323.572226 -406.64658) (xy 323.624524 -406.631227)
			(xy 323.678475 -406.623473) (xy 323.705728 -406.623012) (xy 324.569328 -406.623012) (xy 324.596579 -406.62346)
			(xy 324.650527 -406.63122) (xy 324.702821 -406.646578) (xy 324.752397 -406.669222) (xy 324.798247 -406.698691)
			(xy 324.839436 -406.734384) (xy 324.875126 -406.775576) (xy 324.904591 -406.821427) (xy 324.927232 -406.871005)
			(xy 324.942586 -406.923301) (xy 324.950342 -406.977249) (xy 324.950342 -407.031748) (xy 326.387998 -407.031748)
			(xy 326.387998 -406.977252) (xy 326.395753 -406.92331) (xy 326.411106 -406.87102) (xy 326.433744 -406.821448)
			(xy 326.463205 -406.775601) (xy 326.498892 -406.734414) (xy 326.540076 -406.698725) (xy 326.58592 -406.669259)
			(xy 326.63549 -406.646617) (xy 326.687778 -406.63126) (xy 326.74172 -406.6235) (xy 326.768968 -406.623012)
			(xy 327.632568 -406.623012) (xy 327.659824 -406.623433) (xy 327.713781 -406.631186) (xy 327.766086 -406.64654)
			(xy 327.815672 -406.669182) (xy 327.861532 -406.698651) (xy 327.902731 -406.734347) (xy 327.93843 -406.775542)
			(xy 327.967902 -406.821399) (xy 327.990548 -406.870984) (xy 328.005907 -406.923288) (xy 328.013665 -406.977244)
			(xy 328.013665 -407.031752) (xy 329.451175 -407.031752) (xy 329.451175 -406.977248) (xy 329.458932 -406.923299)
			(xy 329.474288 -406.871004) (xy 329.49693 -406.821426) (xy 329.526397 -406.775575) (xy 329.562089 -406.734384)
			(xy 329.603281 -406.698692) (xy 329.649133 -406.669226) (xy 329.698711 -406.646585) (xy 329.751007 -406.63123)
			(xy 329.804956 -406.623475) (xy 329.832208 -406.623012) (xy 330.695808 -406.623012) (xy 330.72306 -406.623458)
			(xy 330.77701 -406.631216) (xy 330.829307 -406.646573) (xy 330.878885 -406.669216) (xy 330.924737 -406.698684)
			(xy 330.965929 -406.734377) (xy 331.001621 -406.775569) (xy 331.031088 -406.821422) (xy 331.05373 -406.871001)
			(xy 331.069085 -406.923298) (xy 331.076842 -406.977248) (xy 331.076842 -407.031752) (xy 331.076842 -407.031754)
			(xy 332.514375 -407.031754) (xy 332.514375 -406.977246) (xy 332.522133 -406.923294) (xy 332.537491 -406.870995)
			(xy 332.560136 -406.821414) (xy 332.589607 -406.775561) (xy 332.625304 -406.73437) (xy 332.6665 -406.698678)
			(xy 332.712357 -406.669213) (xy 332.76194 -406.646574) (xy 332.814241 -406.631223) (xy 332.868194 -406.623472)
			(xy 332.895448 -406.623012) (xy 333.759048 -406.623012) (xy 333.786298 -406.623461) (xy 333.840244 -406.631224)
			(xy 333.892536 -406.646584) (xy 333.942109 -406.669229) (xy 333.987956 -406.698698) (xy 334.029143 -406.734391)
			(xy 334.064831 -406.775582) (xy 334.094294 -406.821433) (xy 334.116933 -406.87101) (xy 334.132287 -406.923303)
			(xy 334.140042 -406.97725) (xy 334.140042 -407.031749) (xy 335.577698 -407.031749) (xy 335.577698 -406.977251)
			(xy 335.585454 -406.923307) (xy 335.600808 -406.871016) (xy 335.623447 -406.821442) (xy 335.65291 -406.775595)
			(xy 335.688599 -406.734407) (xy 335.729785 -406.698718) (xy 335.775632 -406.669252) (xy 335.825205 -406.646612)
			(xy 335.877495 -406.631257) (xy 335.931439 -406.623499) (xy 335.958688 -406.623012) (xy 336.822288 -406.623012)
			(xy 336.849543 -406.623434) (xy 336.903498 -406.63119) (xy 336.9558 -406.646546) (xy 337.005384 -406.669189)
			(xy 337.051241 -406.698658) (xy 337.092438 -406.734354) (xy 337.128135 -406.775549) (xy 337.157605 -406.821405)
			(xy 337.18025 -406.870989) (xy 337.195607 -406.92329) (xy 337.203365 -406.977245) (xy 337.203365 -407.031753)
			(xy 338.640875 -407.031753) (xy 338.640875 -406.977247) (xy 338.648633 -406.923297) (xy 338.663989 -406.870999)
			(xy 338.686633 -406.82142) (xy 338.716102 -406.775568) (xy 338.751797 -406.734377) (xy 338.79299 -406.698685)
			(xy 338.838845 -406.669219) (xy 338.888426 -406.64658) (xy 338.940724 -406.631227) (xy 338.994675 -406.623473)
			(xy 339.021928 -406.623012) (xy 339.885528 -406.623012) (xy 339.912779 -406.62346) (xy 339.966727 -406.63122)
			(xy 340.019021 -406.646578) (xy 340.068597 -406.669222) (xy 340.114447 -406.698691) (xy 340.155636 -406.734384)
			(xy 340.191326 -406.775576) (xy 340.220791 -406.821427) (xy 340.243432 -406.871005) (xy 340.258786 -406.923301)
			(xy 340.266542 -406.977249) (xy 340.266542 -407.031748) (xy 341.704198 -407.031748) (xy 341.704198 -406.977252)
			(xy 341.711953 -406.92331) (xy 341.727306 -406.87102) (xy 341.749944 -406.821448) (xy 341.779405 -406.775601)
			(xy 341.815092 -406.734414) (xy 341.856276 -406.698725) (xy 341.90212 -406.669259) (xy 341.95169 -406.646617)
			(xy 342.003978 -406.63126) (xy 342.05792 -406.6235) (xy 342.085168 -406.623012) (xy 342.948768 -406.623012)
			(xy 342.976024 -406.623433) (xy 343.029981 -406.631186) (xy 343.082286 -406.64654) (xy 343.131872 -406.669182)
			(xy 343.177732 -406.698651) (xy 343.218931 -406.734347) (xy 343.25463 -406.775542) (xy 343.284102 -406.821399)
			(xy 343.306748 -406.870984) (xy 343.322107 -406.923288) (xy 343.329865 -406.977244) (xy 343.329865 -407.031752)
			(xy 344.767375 -407.031752) (xy 344.767375 -406.977248) (xy 344.775132 -406.923299) (xy 344.790488 -406.871004)
			(xy 344.81313 -406.821426) (xy 344.842597 -406.775575) (xy 344.878289 -406.734384) (xy 344.919481 -406.698692)
			(xy 344.965333 -406.669226) (xy 345.014911 -406.646585) (xy 345.067207 -406.63123) (xy 345.121156 -406.623475)
			(xy 345.148408 -406.623012) (xy 346.012008 -406.623012) (xy 346.03926 -406.623458) (xy 346.09321 -406.631216)
			(xy 346.145507 -406.646573) (xy 346.195085 -406.669216) (xy 346.240937 -406.698684) (xy 346.282129 -406.734377)
			(xy 346.317821 -406.775569) (xy 346.347288 -406.821422) (xy 346.36993 -406.871001) (xy 346.385285 -406.923298)
			(xy 346.393042 -406.977248) (xy 346.393042 -407.031752) (xy 346.393042 -407.031754) (xy 347.830575 -407.031754)
			(xy 347.830575 -406.977246) (xy 347.838333 -406.923294) (xy 347.853691 -406.870995) (xy 347.876336 -406.821414)
			(xy 347.905807 -406.775561) (xy 347.941504 -406.73437) (xy 347.9827 -406.698678) (xy 348.028557 -406.669213)
			(xy 348.07814 -406.646574) (xy 348.130441 -406.631223) (xy 348.184394 -406.623472) (xy 348.211648 -406.623012)
			(xy 349.075248 -406.623012) (xy 349.102498 -406.623461) (xy 349.156444 -406.631224) (xy 349.208736 -406.646584)
			(xy 349.258309 -406.669229) (xy 349.304156 -406.698698) (xy 349.345343 -406.734391) (xy 349.381031 -406.775582)
			(xy 349.410494 -406.821433) (xy 349.433133 -406.87101) (xy 349.448487 -406.923303) (xy 349.456242 -406.97725)
			(xy 349.456242 -407.031749) (xy 350.893898 -407.031749) (xy 350.893898 -406.977251) (xy 350.901654 -406.923307)
			(xy 350.917008 -406.871016) (xy 350.939647 -406.821442) (xy 350.96911 -406.775595) (xy 351.004799 -406.734407)
			(xy 351.045985 -406.698718) (xy 351.091832 -406.669252) (xy 351.141405 -406.646612) (xy 351.193695 -406.631257)
			(xy 351.247639 -406.623499) (xy 351.274888 -406.623012) (xy 352.138488 -406.623012) (xy 352.165743 -406.623434)
			(xy 352.219698 -406.63119) (xy 352.272 -406.646546) (xy 352.321584 -406.669189) (xy 352.367441 -406.698658)
			(xy 352.408638 -406.734354) (xy 352.444335 -406.775549) (xy 352.473805 -406.821405) (xy 352.49645 -406.870989)
			(xy 352.511807 -406.92329) (xy 352.519565 -406.977245) (xy 352.519565 -407.031753) (xy 372.388075 -407.031753)
			(xy 372.388075 -406.977247) (xy 372.395833 -406.923296) (xy 372.411189 -406.870999) (xy 372.433833 -406.821419)
			(xy 372.463302 -406.775567) (xy 372.498997 -406.734376) (xy 372.540191 -406.698684) (xy 372.586046 -406.669219)
			(xy 372.635627 -406.646579) (xy 372.687926 -406.631226) (xy 372.741877 -406.623473) (xy 372.76913 -406.623012)
			(xy 373.63273 -406.623012) (xy 373.659981 -406.62346) (xy 373.713929 -406.63122) (xy 373.766222 -406.646579)
			(xy 373.815799 -406.669223) (xy 373.861648 -406.698691) (xy 373.902836 -406.734385) (xy 373.938527 -406.775576)
			(xy 373.967992 -406.821428) (xy 373.990632 -406.871006) (xy 374.005986 -406.923301) (xy 374.013742 -406.977249)
			(xy 374.013742 -407.031748) (xy 375.451398 -407.031748) (xy 375.451398 -406.977252) (xy 375.459153 -406.923309)
			(xy 375.474506 -406.87102) (xy 375.497144 -406.821447) (xy 375.526606 -406.775601) (xy 375.562292 -406.734414)
			(xy 375.603477 -406.698724) (xy 375.649321 -406.669258) (xy 375.698892 -406.646617) (xy 375.75118 -406.63126)
			(xy 375.805122 -406.6235) (xy 375.83237 -406.623012) (xy 376.69597 -406.623012) (xy 376.723226 -406.623433)
			(xy 376.777183 -406.631187) (xy 376.829487 -406.646541) (xy 376.879074 -406.669183) (xy 376.924933 -406.698652)
			(xy 376.966131 -406.734347) (xy 377.00183 -406.775543) (xy 377.031303 -406.8214) (xy 377.053948 -406.870985)
			(xy 377.069307 -406.923288) (xy 377.077065 -406.977244) (xy 377.077065 -407.031752) (xy 378.514575 -407.031752)
			(xy 378.514575 -406.977248) (xy 378.522332 -406.923299) (xy 378.537688 -406.871003) (xy 378.56033 -406.821425)
			(xy 378.589797 -406.775574) (xy 378.62549 -406.734383) (xy 378.666682 -406.698691) (xy 378.712534 -406.669225)
			(xy 378.762113 -406.646584) (xy 378.814409 -406.63123) (xy 378.868358 -406.623475) (xy 378.89561 -406.623012)
			(xy 379.75921 -406.623012) (xy 379.786462 -406.623459) (xy 379.840412 -406.631217) (xy 379.892708 -406.646573)
			(xy 379.942287 -406.669216) (xy 379.988138 -406.698684) (xy 380.029329 -406.734378) (xy 380.065022 -406.77557)
			(xy 380.094489 -406.821422) (xy 380.11713 -406.871001) (xy 380.132486 -406.923298) (xy 380.140242 -406.977248)
			(xy 380.140242 -407.031748) (xy 381.577898 -407.031748) (xy 381.577898 -406.977252) (xy 381.585653 -406.923312)
			(xy 381.601005 -406.871024) (xy 381.623641 -406.821453) (xy 381.653101 -406.775607) (xy 381.688785 -406.734421)
			(xy 381.729967 -406.698731) (xy 381.775809 -406.669265) (xy 381.825377 -406.646622) (xy 381.877663 -406.631264)
			(xy 381.931603 -406.623502) (xy 381.95885 -406.623012) (xy 382.82245 -406.623012) (xy 382.849707 -406.623431)
			(xy 382.903666 -406.631183) (xy 382.955973 -406.646536) (xy 383.005562 -406.669176) (xy 383.051423 -406.698645)
			(xy 383.092624 -406.73434) (xy 383.128325 -406.775536) (xy 383.1578 -406.821394) (xy 383.180447 -406.870981)
			(xy 383.195806 -406.923285) (xy 383.203565 -406.977243) (xy 383.203565 -407.031749) (xy 384.641098 -407.031749)
			(xy 384.641098 -406.977251) (xy 384.648854 -406.923307) (xy 384.664208 -406.871016) (xy 384.686847 -406.821442)
			(xy 384.716311 -406.775594) (xy 384.751999 -406.734406) (xy 384.793186 -406.698717) (xy 384.839033 -406.669252)
			(xy 384.888606 -406.646611) (xy 384.940897 -406.631256) (xy 384.994841 -406.623499) (xy 385.02209 -406.623012)
			(xy 385.88569 -406.623012) (xy 385.912945 -406.623434) (xy 385.9669 -406.63119) (xy 386.019202 -406.646546)
			(xy 386.068786 -406.66919) (xy 386.114642 -406.698659) (xy 386.155838 -406.734354) (xy 386.191535 -406.77555)
			(xy 386.221006 -406.821406) (xy 386.24365 -406.870989) (xy 386.259007 -406.923291) (xy 386.266765 -406.977245)
			(xy 386.266765 -407.031753) (xy 387.704275 -407.031753) (xy 387.704275 -406.977247) (xy 387.712033 -406.923296)
			(xy 387.727389 -406.870999) (xy 387.750033 -406.821419) (xy 387.779502 -406.775567) (xy 387.815197 -406.734376)
			(xy 387.856391 -406.698684) (xy 387.902246 -406.669219) (xy 387.951827 -406.646579) (xy 388.004126 -406.631226)
			(xy 388.058077 -406.623473) (xy 388.08533 -406.623012) (xy 388.94893 -406.623012) (xy 388.976181 -406.62346)
			(xy 389.030129 -406.63122) (xy 389.082422 -406.646579) (xy 389.131999 -406.669223) (xy 389.177848 -406.698691)
			(xy 389.219036 -406.734385) (xy 389.254727 -406.775576) (xy 389.284192 -406.821428) (xy 389.306832 -406.871006)
			(xy 389.322186 -406.923301) (xy 389.329942 -406.977249) (xy 389.329942 -407.031748) (xy 390.767598 -407.031748)
			(xy 390.767598 -406.977252) (xy 390.775353 -406.923309) (xy 390.790706 -406.87102) (xy 390.813344 -406.821447)
			(xy 390.842806 -406.775601) (xy 390.878492 -406.734414) (xy 390.919677 -406.698724) (xy 390.965521 -406.669258)
			(xy 391.015092 -406.646617) (xy 391.06738 -406.63126) (xy 391.121322 -406.6235) (xy 391.14857 -406.623012)
			(xy 392.01217 -406.623012) (xy 392.039426 -406.623433) (xy 392.093383 -406.631187) (xy 392.145687 -406.646541)
			(xy 392.195274 -406.669183) (xy 392.241133 -406.698652) (xy 392.282331 -406.734347) (xy 392.31803 -406.775543)
			(xy 392.347503 -406.8214) (xy 392.370148 -406.870985) (xy 392.385507 -406.923288) (xy 392.393265 -406.977244)
			(xy 392.393265 -407.031752) (xy 393.830775 -407.031752) (xy 393.830775 -406.977248) (xy 393.838532 -406.923299)
			(xy 393.853888 -406.871003) (xy 393.87653 -406.821425) (xy 393.905997 -406.775574) (xy 393.94169 -406.734383)
			(xy 393.982882 -406.698691) (xy 394.028734 -406.669225) (xy 394.078313 -406.646584) (xy 394.130609 -406.63123)
			(xy 394.184558 -406.623475) (xy 394.21181 -406.623012) (xy 395.07541 -406.623012) (xy 395.102662 -406.623459)
			(xy 395.156612 -406.631217) (xy 395.208908 -406.646573) (xy 395.258487 -406.669216) (xy 395.304338 -406.698684)
			(xy 395.345529 -406.734378) (xy 395.381222 -406.77557) (xy 395.410689 -406.821422) (xy 395.43333 -406.871001)
			(xy 395.448686 -406.923298) (xy 395.456442 -406.977248) (xy 395.456442 -407.031748) (xy 396.894098 -407.031748)
			(xy 396.894098 -406.977252) (xy 396.901853 -406.923312) (xy 396.917205 -406.871024) (xy 396.939841 -406.821453)
			(xy 396.969301 -406.775607) (xy 397.004985 -406.734421) (xy 397.046167 -406.698731) (xy 397.092009 -406.669265)
			(xy 397.141577 -406.646622) (xy 397.193863 -406.631264) (xy 397.247803 -406.623502) (xy 397.27505 -406.623012)
			(xy 398.13865 -406.623012) (xy 398.165907 -406.623431) (xy 398.219866 -406.631183) (xy 398.272173 -406.646536)
			(xy 398.321762 -406.669176) (xy 398.367623 -406.698645) (xy 398.408824 -406.73434) (xy 398.444525 -406.775536)
			(xy 398.474 -406.821394) (xy 398.496647 -406.870981) (xy 398.512006 -406.923285) (xy 398.519765 -406.977243)
			(xy 398.519765 -407.031749) (xy 399.957298 -407.031749) (xy 399.957298 -406.977251) (xy 399.965054 -406.923307)
			(xy 399.980408 -406.871016) (xy 400.003047 -406.821442) (xy 400.032511 -406.775594) (xy 400.068199 -406.734406)
			(xy 400.109386 -406.698717) (xy 400.155233 -406.669252) (xy 400.204806 -406.646611) (xy 400.257097 -406.631256)
			(xy 400.311041 -406.623499) (xy 400.33829 -406.623012) (xy 401.20189 -406.623012) (xy 401.229145 -406.623434)
			(xy 401.2831 -406.63119) (xy 401.335402 -406.646546) (xy 401.384986 -406.66919) (xy 401.430842 -406.698659)
			(xy 401.472038 -406.734354) (xy 401.507735 -406.77555) (xy 401.537206 -406.821406) (xy 401.55985 -406.870989)
			(xy 401.575207 -406.923291) (xy 401.582965 -406.977245) (xy 401.582965 -407.031753) (xy 403.020475 -407.031753)
			(xy 403.020475 -406.977247) (xy 403.028233 -406.923296) (xy 403.043589 -406.870999) (xy 403.066233 -406.821419)
			(xy 403.095702 -406.775567) (xy 403.131397 -406.734376) (xy 403.172591 -406.698684) (xy 403.218446 -406.669219)
			(xy 403.268027 -406.646579) (xy 403.320326 -406.631226) (xy 403.374277 -406.623473) (xy 403.40153 -406.623012)
			(xy 404.26513 -406.623012) (xy 404.292381 -406.62346) (xy 404.346329 -406.63122) (xy 404.398622 -406.646579)
			(xy 404.448199 -406.669223) (xy 404.494048 -406.698691) (xy 404.535236 -406.734385) (xy 404.570927 -406.775576)
			(xy 404.600392 -406.821428) (xy 404.623032 -406.871006) (xy 404.638386 -406.923301) (xy 404.646142 -406.977249)
			(xy 404.646142 -407.031748) (xy 406.083798 -407.031748) (xy 406.083798 -406.977252) (xy 406.091553 -406.923309)
			(xy 406.106906 -406.87102) (xy 406.129544 -406.821447) (xy 406.159006 -406.775601) (xy 406.194692 -406.734414)
			(xy 406.235877 -406.698724) (xy 406.281721 -406.669258) (xy 406.331292 -406.646617) (xy 406.38358 -406.63126)
			(xy 406.437522 -406.6235) (xy 406.46477 -406.623012) (xy 407.32837 -406.623012) (xy 407.355626 -406.623433)
			(xy 407.409583 -406.631187) (xy 407.461887 -406.646541) (xy 407.511474 -406.669183) (xy 407.557333 -406.698652)
			(xy 407.598531 -406.734347) (xy 407.63423 -406.775543) (xy 407.663703 -406.8214) (xy 407.686348 -406.870985)
			(xy 407.701707 -406.923288) (xy 407.709465 -406.977244) (xy 407.709465 -407.031752) (xy 409.146975 -407.031752)
			(xy 409.146975 -406.977248) (xy 409.154732 -406.923299) (xy 409.170088 -406.871003) (xy 409.19273 -406.821425)
			(xy 409.222197 -406.775574) (xy 409.25789 -406.734383) (xy 409.299082 -406.698691) (xy 409.344934 -406.669225)
			(xy 409.394513 -406.646584) (xy 409.446809 -406.63123) (xy 409.500758 -406.623475) (xy 409.52801 -406.623012)
			(xy 410.39161 -406.623012) (xy 410.418862 -406.623459) (xy 410.472812 -406.631217) (xy 410.525108 -406.646573)
			(xy 410.574687 -406.669216) (xy 410.620538 -406.698684) (xy 410.661729 -406.734378) (xy 410.697422 -406.77557)
			(xy 410.726889 -406.821422) (xy 410.74953 -406.871001) (xy 410.764886 -406.923298) (xy 410.772642 -406.977248)
			(xy 410.772642 -407.031748) (xy 412.210298 -407.031748) (xy 412.210298 -406.977252) (xy 412.218053 -406.923312)
			(xy 412.233405 -406.871024) (xy 412.256041 -406.821453) (xy 412.285501 -406.775607) (xy 412.321185 -406.734421)
			(xy 412.362367 -406.698731) (xy 412.408209 -406.669265) (xy 412.457777 -406.646622) (xy 412.510063 -406.631264)
			(xy 412.564003 -406.623502) (xy 412.59125 -406.623012) (xy 413.45485 -406.623012) (xy 413.482107 -406.623431)
			(xy 413.536066 -406.631183) (xy 413.588373 -406.646536) (xy 413.637962 -406.669176) (xy 413.683823 -406.698645)
			(xy 413.725024 -406.73434) (xy 413.760725 -406.775536) (xy 413.7902 -406.821394) (xy 413.812847 -406.870981)
			(xy 413.828206 -406.923285) (xy 413.835965 -406.977243) (xy 413.835965 -407.031749) (xy 415.273498 -407.031749)
			(xy 415.273498 -406.977251) (xy 415.281254 -406.923307) (xy 415.296608 -406.871016) (xy 415.319247 -406.821442)
			(xy 415.348711 -406.775594) (xy 415.384399 -406.734406) (xy 415.425586 -406.698717) (xy 415.471433 -406.669252)
			(xy 415.521006 -406.646611) (xy 415.573297 -406.631256) (xy 415.627241 -406.623499) (xy 415.65449 -406.623012)
			(xy 416.51809 -406.623012) (xy 416.545345 -406.623434) (xy 416.5993 -406.63119) (xy 416.651602 -406.646546)
			(xy 416.701186 -406.66919) (xy 416.747042 -406.698659) (xy 416.788238 -406.734354) (xy 416.823935 -406.77555)
			(xy 416.853406 -406.821406) (xy 416.87605 -406.870989) (xy 416.891407 -406.923291) (xy 416.899165 -406.977245)
			(xy 416.899165 -407.031753) (xy 418.336675 -407.031753) (xy 418.336675 -406.977247) (xy 418.344433 -406.923296)
			(xy 418.359789 -406.870999) (xy 418.382433 -406.821419) (xy 418.411902 -406.775567) (xy 418.447597 -406.734376)
			(xy 418.488791 -406.698684) (xy 418.534646 -406.669219) (xy 418.584227 -406.646579) (xy 418.636526 -406.631226)
			(xy 418.690477 -406.623473) (xy 418.71773 -406.623012) (xy 419.58133 -406.623012) (xy 419.608581 -406.62346)
			(xy 419.662529 -406.63122) (xy 419.714822 -406.646579) (xy 419.764399 -406.669223) (xy 419.810248 -406.698691)
			(xy 419.851436 -406.734385) (xy 419.887127 -406.775576) (xy 419.916592 -406.821428) (xy 419.939232 -406.871006)
			(xy 419.954586 -406.923301) (xy 419.962342 -406.977249) (xy 419.962342 -407.031751) (xy 419.954586 -407.085699)
			(xy 419.939232 -407.137994) (xy 419.916592 -407.187572) (xy 419.887127 -407.233424) (xy 419.851436 -407.274615)
			(xy 419.810248 -407.310309) (xy 419.764399 -407.339777) (xy 419.714822 -407.362421) (xy 419.662529 -407.37778)
			(xy 419.608581 -407.38554) (xy 419.58133 -407.386028) (xy 418.71773 -407.386028) (xy 418.690477 -407.385527)
			(xy 418.636526 -407.377774) (xy 418.584227 -407.362421) (xy 418.534646 -407.339781) (xy 418.488791 -407.310316)
			(xy 418.447597 -407.274624) (xy 418.411902 -407.233433) (xy 418.382433 -407.187581) (xy 418.359789 -407.138001)
			(xy 418.344433 -407.085704) (xy 418.336675 -407.031753) (xy 416.899165 -407.031753) (xy 416.899165 -407.031755)
			(xy 416.891407 -407.085709) (xy 416.87605 -407.138011) (xy 416.853406 -407.187594) (xy 416.823935 -407.23345)
			(xy 416.788238 -407.274646) (xy 416.747042 -407.310341) (xy 416.701186 -407.33981) (xy 416.651602 -407.362454)
			(xy 416.5993 -407.37781) (xy 416.545345 -407.385566) (xy 416.51809 -407.386028) (xy 415.65449 -407.386028)
			(xy 415.627241 -407.385501) (xy 415.573297 -407.377744) (xy 415.521006 -407.362389) (xy 415.471433 -407.339748)
			(xy 415.425586 -407.310283) (xy 415.384399 -407.274594) (xy 415.348711 -407.233406) (xy 415.319247 -407.187558)
			(xy 415.296608 -407.137984) (xy 415.281254 -407.085693) (xy 415.273498 -407.031749) (xy 413.835965 -407.031749)
			(xy 413.835965 -407.031757) (xy 413.828206 -407.085715) (xy 413.812847 -407.138019) (xy 413.7902 -407.187606)
			(xy 413.760725 -407.233464) (xy 413.725024 -407.27466) (xy 413.683823 -407.310355) (xy 413.637962 -407.339824)
			(xy 413.588373 -407.362464) (xy 413.536066 -407.377817) (xy 413.482107 -407.385569) (xy 413.45485 -407.386028)
			(xy 412.59125 -407.386028) (xy 412.564003 -407.385498) (xy 412.510063 -407.377736) (xy 412.457777 -407.362378)
			(xy 412.408209 -407.339735) (xy 412.362367 -407.310269) (xy 412.321185 -407.274579) (xy 412.285501 -407.233393)
			(xy 412.256041 -407.187547) (xy 412.233405 -407.137976) (xy 412.218053 -407.085688) (xy 412.210298 -407.031748)
			(xy 410.772642 -407.031748) (xy 410.772642 -407.031752) (xy 410.764886 -407.085702) (xy 410.74953 -407.137999)
			(xy 410.726889 -407.187578) (xy 410.697422 -407.23343) (xy 410.661729 -407.274622) (xy 410.620538 -407.310316)
			(xy 410.574687 -407.339784) (xy 410.525108 -407.362427) (xy 410.472812 -407.377783) (xy 410.418862 -407.385541)
			(xy 410.39161 -407.386028) (xy 409.52801 -407.386028) (xy 409.500758 -407.385525) (xy 409.446809 -407.37777)
			(xy 409.394513 -407.362416) (xy 409.344934 -407.339775) (xy 409.299082 -407.310309) (xy 409.25789 -407.274617)
			(xy 409.222197 -407.233426) (xy 409.19273 -407.187575) (xy 409.170088 -407.137997) (xy 409.154732 -407.085701)
			(xy 409.146975 -407.031752) (xy 407.709465 -407.031752) (xy 407.709465 -407.031756) (xy 407.701707 -407.085712)
			(xy 407.686348 -407.138015) (xy 407.663703 -407.1876) (xy 407.63423 -407.233457) (xy 407.598531 -407.274653)
			(xy 407.557333 -407.310348) (xy 407.511474 -407.339817) (xy 407.461887 -407.362459) (xy 407.409583 -407.377813)
			(xy 407.355626 -407.385567) (xy 407.32837 -407.386028) (xy 406.46477 -407.386028) (xy 406.437522 -407.3855)
			(xy 406.38358 -407.37774) (xy 406.331292 -407.362383) (xy 406.281721 -407.339742) (xy 406.235877 -407.310276)
			(xy 406.194692 -407.274586) (xy 406.159006 -407.233399) (xy 406.129544 -407.187553) (xy 406.106906 -407.13798)
			(xy 406.091553 -407.085691) (xy 406.083798 -407.031748) (xy 404.646142 -407.031748) (xy 404.646142 -407.031751)
			(xy 404.638386 -407.085699) (xy 404.623032 -407.137994) (xy 404.600392 -407.187572) (xy 404.570927 -407.233424)
			(xy 404.535236 -407.274615) (xy 404.494048 -407.310309) (xy 404.448199 -407.339777) (xy 404.398622 -407.362421)
			(xy 404.346329 -407.37778) (xy 404.292381 -407.38554) (xy 404.26513 -407.386028) (xy 403.40153 -407.386028)
			(xy 403.374277 -407.385527) (xy 403.320326 -407.377774) (xy 403.268027 -407.362421) (xy 403.218446 -407.339781)
			(xy 403.172591 -407.310316) (xy 403.131397 -407.274624) (xy 403.095702 -407.233433) (xy 403.066233 -407.187581)
			(xy 403.043589 -407.138001) (xy 403.028233 -407.085704) (xy 403.020475 -407.031753) (xy 401.582965 -407.031753)
			(xy 401.582965 -407.031755) (xy 401.575207 -407.085709) (xy 401.55985 -407.138011) (xy 401.537206 -407.187594)
			(xy 401.507735 -407.23345) (xy 401.472038 -407.274646) (xy 401.430842 -407.310341) (xy 401.384986 -407.33981)
			(xy 401.335402 -407.362454) (xy 401.2831 -407.37781) (xy 401.229145 -407.385566) (xy 401.20189 -407.386028)
			(xy 400.33829 -407.386028) (xy 400.311041 -407.385501) (xy 400.257097 -407.377744) (xy 400.204806 -407.362389)
			(xy 400.155233 -407.339748) (xy 400.109386 -407.310283) (xy 400.068199 -407.274594) (xy 400.032511 -407.233406)
			(xy 400.003047 -407.187558) (xy 399.980408 -407.137984) (xy 399.965054 -407.085693) (xy 399.957298 -407.031749)
			(xy 398.519765 -407.031749) (xy 398.519765 -407.031757) (xy 398.512006 -407.085715) (xy 398.496647 -407.138019)
			(xy 398.474 -407.187606) (xy 398.444525 -407.233464) (xy 398.408824 -407.27466) (xy 398.367623 -407.310355)
			(xy 398.321762 -407.339824) (xy 398.272173 -407.362464) (xy 398.219866 -407.377817) (xy 398.165907 -407.385569)
			(xy 398.13865 -407.386028) (xy 397.27505 -407.386028) (xy 397.247803 -407.385498) (xy 397.193863 -407.377736)
			(xy 397.141577 -407.362378) (xy 397.092009 -407.339735) (xy 397.046167 -407.310269) (xy 397.004985 -407.274579)
			(xy 396.969301 -407.233393) (xy 396.939841 -407.187547) (xy 396.917205 -407.137976) (xy 396.901853 -407.085688)
			(xy 396.894098 -407.031748) (xy 395.456442 -407.031748) (xy 395.456442 -407.031752) (xy 395.448686 -407.085702)
			(xy 395.43333 -407.137999) (xy 395.410689 -407.187578) (xy 395.381222 -407.23343) (xy 395.345529 -407.274622)
			(xy 395.304338 -407.310316) (xy 395.258487 -407.339784) (xy 395.208908 -407.362427) (xy 395.156612 -407.377783)
			(xy 395.102662 -407.385541) (xy 395.07541 -407.386028) (xy 394.21181 -407.386028) (xy 394.184558 -407.385525)
			(xy 394.130609 -407.37777) (xy 394.078313 -407.362416) (xy 394.028734 -407.339775) (xy 393.982882 -407.310309)
			(xy 393.94169 -407.274617) (xy 393.905997 -407.233426) (xy 393.87653 -407.187575) (xy 393.853888 -407.137997)
			(xy 393.838532 -407.085701) (xy 393.830775 -407.031752) (xy 392.393265 -407.031752) (xy 392.393265 -407.031756)
			(xy 392.385507 -407.085712) (xy 392.370148 -407.138015) (xy 392.347503 -407.1876) (xy 392.31803 -407.233457)
			(xy 392.282331 -407.274653) (xy 392.241133 -407.310348) (xy 392.195274 -407.339817) (xy 392.145687 -407.362459)
			(xy 392.093383 -407.377813) (xy 392.039426 -407.385567) (xy 392.01217 -407.386028) (xy 391.14857 -407.386028)
			(xy 391.121322 -407.3855) (xy 391.06738 -407.37774) (xy 391.015092 -407.362383) (xy 390.965521 -407.339742)
			(xy 390.919677 -407.310276) (xy 390.878492 -407.274586) (xy 390.842806 -407.233399) (xy 390.813344 -407.187553)
			(xy 390.790706 -407.13798) (xy 390.775353 -407.085691) (xy 390.767598 -407.031748) (xy 389.329942 -407.031748)
			(xy 389.329942 -407.031751) (xy 389.322186 -407.085699) (xy 389.306832 -407.137994) (xy 389.284192 -407.187572)
			(xy 389.254727 -407.233424) (xy 389.219036 -407.274615) (xy 389.177848 -407.310309) (xy 389.131999 -407.339777)
			(xy 389.082422 -407.362421) (xy 389.030129 -407.37778) (xy 388.976181 -407.38554) (xy 388.94893 -407.386028)
			(xy 388.08533 -407.386028) (xy 388.058077 -407.385527) (xy 388.004126 -407.377774) (xy 387.951827 -407.362421)
			(xy 387.902246 -407.339781) (xy 387.856391 -407.310316) (xy 387.815197 -407.274624) (xy 387.779502 -407.233433)
			(xy 387.750033 -407.187581) (xy 387.727389 -407.138001) (xy 387.712033 -407.085704) (xy 387.704275 -407.031753)
			(xy 386.266765 -407.031753) (xy 386.266765 -407.031755) (xy 386.259007 -407.085709) (xy 386.24365 -407.138011)
			(xy 386.221006 -407.187594) (xy 386.191535 -407.23345) (xy 386.155838 -407.274646) (xy 386.114642 -407.310341)
			(xy 386.068786 -407.33981) (xy 386.019202 -407.362454) (xy 385.9669 -407.37781) (xy 385.912945 -407.385566)
			(xy 385.88569 -407.386028) (xy 385.02209 -407.386028) (xy 384.994841 -407.385501) (xy 384.940897 -407.377744)
			(xy 384.888606 -407.362389) (xy 384.839033 -407.339748) (xy 384.793186 -407.310283) (xy 384.751999 -407.274594)
			(xy 384.716311 -407.233406) (xy 384.686847 -407.187558) (xy 384.664208 -407.137984) (xy 384.648854 -407.085693)
			(xy 384.641098 -407.031749) (xy 383.203565 -407.031749) (xy 383.203565 -407.031757) (xy 383.195806 -407.085715)
			(xy 383.180447 -407.138019) (xy 383.1578 -407.187606) (xy 383.128325 -407.233464) (xy 383.092624 -407.27466)
			(xy 383.051423 -407.310355) (xy 383.005562 -407.339824) (xy 382.955973 -407.362464) (xy 382.903666 -407.377817)
			(xy 382.849707 -407.385569) (xy 382.82245 -407.386028) (xy 381.95885 -407.386028) (xy 381.931603 -407.385498)
			(xy 381.877663 -407.377736) (xy 381.825377 -407.362378) (xy 381.775809 -407.339735) (xy 381.729967 -407.310269)
			(xy 381.688785 -407.274579) (xy 381.653101 -407.233393) (xy 381.623641 -407.187547) (xy 381.601005 -407.137976)
			(xy 381.585653 -407.085688) (xy 381.577898 -407.031748) (xy 380.140242 -407.031748) (xy 380.140242 -407.031752)
			(xy 380.132486 -407.085702) (xy 380.11713 -407.137999) (xy 380.094489 -407.187578) (xy 380.065022 -407.23343)
			(xy 380.029329 -407.274622) (xy 379.988138 -407.310316) (xy 379.942287 -407.339784) (xy 379.892708 -407.362427)
			(xy 379.840412 -407.377783) (xy 379.786462 -407.385541) (xy 379.75921 -407.386028) (xy 378.89561 -407.386028)
			(xy 378.868358 -407.385525) (xy 378.814409 -407.37777) (xy 378.762113 -407.362416) (xy 378.712534 -407.339775)
			(xy 378.666682 -407.310309) (xy 378.62549 -407.274617) (xy 378.589797 -407.233426) (xy 378.56033 -407.187575)
			(xy 378.537688 -407.137997) (xy 378.522332 -407.085701) (xy 378.514575 -407.031752) (xy 377.077065 -407.031752)
			(xy 377.077065 -407.031756) (xy 377.069307 -407.085712) (xy 377.053948 -407.138015) (xy 377.031303 -407.1876)
			(xy 377.00183 -407.233457) (xy 376.966131 -407.274653) (xy 376.924933 -407.310348) (xy 376.879074 -407.339817)
			(xy 376.829487 -407.362459) (xy 376.777183 -407.377813) (xy 376.723226 -407.385567) (xy 376.69597 -407.386028)
			(xy 375.83237 -407.386028) (xy 375.805122 -407.3855) (xy 375.75118 -407.37774) (xy 375.698892 -407.362383)
			(xy 375.649321 -407.339742) (xy 375.603477 -407.310276) (xy 375.562292 -407.274586) (xy 375.526606 -407.233399)
			(xy 375.497144 -407.187553) (xy 375.474506 -407.13798) (xy 375.459153 -407.085691) (xy 375.451398 -407.031748)
			(xy 374.013742 -407.031748) (xy 374.013742 -407.031751) (xy 374.005986 -407.085699) (xy 373.990632 -407.137994)
			(xy 373.967992 -407.187572) (xy 373.938527 -407.233424) (xy 373.902836 -407.274615) (xy 373.861648 -407.310309)
			(xy 373.815799 -407.339777) (xy 373.766222 -407.362421) (xy 373.713929 -407.37778) (xy 373.659981 -407.38554)
			(xy 373.63273 -407.386028) (xy 372.76913 -407.386028) (xy 372.741877 -407.385527) (xy 372.687926 -407.377774)
			(xy 372.635627 -407.362421) (xy 372.586046 -407.339781) (xy 372.540191 -407.310316) (xy 372.498997 -407.274624)
			(xy 372.463302 -407.233433) (xy 372.433833 -407.187581) (xy 372.411189 -407.138001) (xy 372.395833 -407.085704)
			(xy 372.388075 -407.031753) (xy 352.519565 -407.031753) (xy 352.519565 -407.031755) (xy 352.511807 -407.08571)
			(xy 352.49645 -407.138011) (xy 352.473805 -407.187595) (xy 352.444335 -407.233451) (xy 352.408638 -407.274646)
			(xy 352.367441 -407.310342) (xy 352.321584 -407.339811) (xy 352.272 -407.362454) (xy 352.219698 -407.37781)
			(xy 352.165743 -407.385566) (xy 352.138488 -407.386028) (xy 351.274888 -407.386028) (xy 351.247639 -407.385501)
			(xy 351.193695 -407.377743) (xy 351.141405 -407.362388) (xy 351.091832 -407.339748) (xy 351.045985 -407.310282)
			(xy 351.004799 -407.274593) (xy 350.96911 -407.233405) (xy 350.939647 -407.187558) (xy 350.917008 -407.137984)
			(xy 350.901654 -407.085693) (xy 350.893898 -407.031749) (xy 349.456242 -407.031749) (xy 349.456242 -407.03175)
			(xy 349.448487 -407.085697) (xy 349.433133 -407.137991) (xy 349.410494 -407.187567) (xy 349.381031 -407.233418)
			(xy 349.345343 -407.274609) (xy 349.304156 -407.310302) (xy 349.258309 -407.339771) (xy 349.208736 -407.362416)
			(xy 349.156444 -407.377776) (xy 349.102498 -407.385539) (xy 349.075248 -407.386028) (xy 348.211648 -407.386028)
			(xy 348.184394 -407.385528) (xy 348.130441 -407.377777) (xy 348.07814 -407.362426) (xy 348.028557 -407.339787)
			(xy 347.9827 -407.310322) (xy 347.941504 -407.27463) (xy 347.905807 -407.233439) (xy 347.876336 -407.187586)
			(xy 347.853691 -407.138005) (xy 347.838333 -407.085706) (xy 347.830575 -407.031754) (xy 346.393042 -407.031754)
			(xy 346.385285 -407.085702) (xy 346.36993 -407.137999) (xy 346.347288 -407.187578) (xy 346.317821 -407.233431)
			(xy 346.282129 -407.274623) (xy 346.240937 -407.310316) (xy 346.195085 -407.339784) (xy 346.145507 -407.362427)
			(xy 346.09321 -407.377784) (xy 346.03926 -407.385542) (xy 346.012008 -407.386028) (xy 345.148408 -407.386028)
			(xy 345.121156 -407.385525) (xy 345.067207 -407.37777) (xy 345.014911 -407.362415) (xy 344.965333 -407.339774)
			(xy 344.919481 -407.310308) (xy 344.878289 -407.274616) (xy 344.842597 -407.233425) (xy 344.81313 -407.187574)
			(xy 344.790488 -407.137996) (xy 344.775132 -407.085701) (xy 344.767375 -407.031752) (xy 343.329865 -407.031752)
			(xy 343.329865 -407.031756) (xy 343.322107 -407.085712) (xy 343.306748 -407.138016) (xy 343.284102 -407.187601)
			(xy 343.25463 -407.233458) (xy 343.218931 -407.274653) (xy 343.177732 -407.310349) (xy 343.131872 -407.339818)
			(xy 343.082286 -407.36246) (xy 343.029981 -407.377814) (xy 342.976024 -407.385567) (xy 342.948768 -407.386028)
			(xy 342.085168 -407.386028) (xy 342.05792 -407.3855) (xy 342.003978 -407.37774) (xy 341.95169 -407.362383)
			(xy 341.90212 -407.339741) (xy 341.856276 -407.310275) (xy 341.815092 -407.274586) (xy 341.779405 -407.233399)
			(xy 341.749944 -407.187552) (xy 341.727306 -407.13798) (xy 341.711953 -407.08569) (xy 341.704198 -407.031748)
			(xy 340.266542 -407.031748) (xy 340.266542 -407.031751) (xy 340.258786 -407.0857) (xy 340.243432 -407.137995)
			(xy 340.220791 -407.187573) (xy 340.191326 -407.233424) (xy 340.155636 -407.274616) (xy 340.114447 -407.310309)
			(xy 340.068597 -407.339778) (xy 340.019021 -407.362422) (xy 339.966727 -407.37778) (xy 339.912779 -407.38554)
			(xy 339.885528 -407.386028) (xy 339.021928 -407.386028) (xy 338.994675 -407.385527) (xy 338.940724 -407.377773)
			(xy 338.888426 -407.36242) (xy 338.838845 -407.339781) (xy 338.79299 -407.310315) (xy 338.751797 -407.274623)
			(xy 338.716102 -407.233432) (xy 338.686633 -407.18758) (xy 338.663989 -407.138001) (xy 338.648633 -407.085703)
			(xy 338.640875 -407.031753) (xy 337.203365 -407.031753) (xy 337.203365 -407.031755) (xy 337.195607 -407.08571)
			(xy 337.18025 -407.138011) (xy 337.157605 -407.187595) (xy 337.128135 -407.233451) (xy 337.092438 -407.274646)
			(xy 337.051241 -407.310342) (xy 337.005384 -407.339811) (xy 336.9558 -407.362454) (xy 336.903498 -407.37781)
			(xy 336.849543 -407.385566) (xy 336.822288 -407.386028) (xy 335.958688 -407.386028) (xy 335.931439 -407.385501)
			(xy 335.877495 -407.377743) (xy 335.825205 -407.362388) (xy 335.775632 -407.339748) (xy 335.729785 -407.310282)
			(xy 335.688599 -407.274593) (xy 335.65291 -407.233405) (xy 335.623447 -407.187558) (xy 335.600808 -407.137984)
			(xy 335.585454 -407.085693) (xy 335.577698 -407.031749) (xy 334.140042 -407.031749) (xy 334.140042 -407.03175)
			(xy 334.132287 -407.085697) (xy 334.116933 -407.137991) (xy 334.094294 -407.187567) (xy 334.064831 -407.233418)
			(xy 334.029143 -407.274609) (xy 333.987956 -407.310302) (xy 333.942109 -407.339771) (xy 333.892536 -407.362416)
			(xy 333.840244 -407.377776) (xy 333.786298 -407.385539) (xy 333.759048 -407.386028) (xy 332.895448 -407.386028)
			(xy 332.868194 -407.385528) (xy 332.814241 -407.377777) (xy 332.76194 -407.362426) (xy 332.712357 -407.339787)
			(xy 332.6665 -407.310322) (xy 332.625304 -407.27463) (xy 332.589607 -407.233439) (xy 332.560136 -407.187586)
			(xy 332.537491 -407.138005) (xy 332.522133 -407.085706) (xy 332.514375 -407.031754) (xy 331.076842 -407.031754)
			(xy 331.069085 -407.085702) (xy 331.05373 -407.137999) (xy 331.031088 -407.187578) (xy 331.001621 -407.233431)
			(xy 330.965929 -407.274623) (xy 330.924737 -407.310316) (xy 330.878885 -407.339784) (xy 330.829307 -407.362427)
			(xy 330.77701 -407.377784) (xy 330.72306 -407.385542) (xy 330.695808 -407.386028) (xy 329.832208 -407.386028)
			(xy 329.804956 -407.385525) (xy 329.751007 -407.37777) (xy 329.698711 -407.362415) (xy 329.649133 -407.339774)
			(xy 329.603281 -407.310308) (xy 329.562089 -407.274616) (xy 329.526397 -407.233425) (xy 329.49693 -407.187574)
			(xy 329.474288 -407.137996) (xy 329.458932 -407.085701) (xy 329.451175 -407.031752) (xy 328.013665 -407.031752)
			(xy 328.013665 -407.031756) (xy 328.005907 -407.085712) (xy 327.990548 -407.138016) (xy 327.967902 -407.187601)
			(xy 327.93843 -407.233458) (xy 327.902731 -407.274653) (xy 327.861532 -407.310349) (xy 327.815672 -407.339818)
			(xy 327.766086 -407.36246) (xy 327.713781 -407.377814) (xy 327.659824 -407.385567) (xy 327.632568 -407.386028)
			(xy 326.768968 -407.386028) (xy 326.74172 -407.3855) (xy 326.687778 -407.37774) (xy 326.63549 -407.362383)
			(xy 326.58592 -407.339741) (xy 326.540076 -407.310275) (xy 326.498892 -407.274586) (xy 326.463205 -407.233399)
			(xy 326.433744 -407.187552) (xy 326.411106 -407.13798) (xy 326.395753 -407.08569) (xy 326.387998 -407.031748)
			(xy 324.950342 -407.031748) (xy 324.950342 -407.031751) (xy 324.942586 -407.0857) (xy 324.927232 -407.137995)
			(xy 324.904591 -407.187573) (xy 324.875126 -407.233424) (xy 324.839436 -407.274616) (xy 324.798247 -407.310309)
			(xy 324.752397 -407.339778) (xy 324.702821 -407.362422) (xy 324.650527 -407.37778) (xy 324.596579 -407.38554)
			(xy 324.569328 -407.386028) (xy 323.705728 -407.386028) (xy 323.678475 -407.385527) (xy 323.624524 -407.377773)
			(xy 323.572226 -407.36242) (xy 323.522645 -407.339781) (xy 323.47679 -407.310315) (xy 323.435597 -407.274623)
			(xy 323.399902 -407.233432) (xy 323.370433 -407.18758) (xy 323.347789 -407.138001) (xy 323.332433 -407.085703)
			(xy 323.324675 -407.031753) (xy 321.887165 -407.031753) (xy 321.887165 -407.031755) (xy 321.879407 -407.08571)
			(xy 321.86405 -407.138011) (xy 321.841405 -407.187595) (xy 321.811935 -407.233451) (xy 321.776238 -407.274646)
			(xy 321.735041 -407.310342) (xy 321.689184 -407.339811) (xy 321.6396 -407.362454) (xy 321.587298 -407.37781)
			(xy 321.533343 -407.385566) (xy 321.506088 -407.386028) (xy 320.642488 -407.386028) (xy 320.615239 -407.385501)
			(xy 320.561295 -407.377743) (xy 320.509005 -407.362388) (xy 320.459432 -407.339748) (xy 320.413585 -407.310282)
			(xy 320.372399 -407.274593) (xy 320.33671 -407.233405) (xy 320.307247 -407.187558) (xy 320.284608 -407.137984)
			(xy 320.269254 -407.085693) (xy 320.261498 -407.031749) (xy 318.823842 -407.031749) (xy 318.823842 -407.03175)
			(xy 318.816087 -407.085697) (xy 318.800733 -407.137991) (xy 318.778094 -407.187567) (xy 318.748631 -407.233418)
			(xy 318.712943 -407.274609) (xy 318.671756 -407.310302) (xy 318.625909 -407.339771) (xy 318.576336 -407.362416)
			(xy 318.524044 -407.377776) (xy 318.470098 -407.385539) (xy 318.442848 -407.386028) (xy 317.579248 -407.386028)
			(xy 317.551994 -407.385528) (xy 317.498041 -407.377777) (xy 317.44574 -407.362426) (xy 317.396157 -407.339787)
			(xy 317.3503 -407.310322) (xy 317.309104 -407.27463) (xy 317.273407 -407.233439) (xy 317.243936 -407.187586)
			(xy 317.221291 -407.138005) (xy 317.205933 -407.085706) (xy 317.198175 -407.031754) (xy 315.760642 -407.031754)
			(xy 315.752885 -407.085702) (xy 315.73753 -407.137999) (xy 315.714888 -407.187578) (xy 315.685421 -407.233431)
			(xy 315.649729 -407.274623) (xy 315.608537 -407.310316) (xy 315.562685 -407.339784) (xy 315.513107 -407.362427)
			(xy 315.46081 -407.377784) (xy 315.40686 -407.385542) (xy 315.379608 -407.386028) (xy 314.516008 -407.386028)
			(xy 314.488756 -407.385525) (xy 314.434807 -407.37777) (xy 314.382511 -407.362415) (xy 314.332933 -407.339774)
			(xy 314.287081 -407.310308) (xy 314.245889 -407.274616) (xy 314.210197 -407.233425) (xy 314.18073 -407.187574)
			(xy 314.158088 -407.137996) (xy 314.142732 -407.085701) (xy 314.134975 -407.031752) (xy 312.697465 -407.031752)
			(xy 312.697465 -407.031756) (xy 312.689707 -407.085712) (xy 312.674348 -407.138016) (xy 312.651702 -407.187601)
			(xy 312.62223 -407.233458) (xy 312.586531 -407.274653) (xy 312.545332 -407.310349) (xy 312.499472 -407.339818)
			(xy 312.449886 -407.36246) (xy 312.397581 -407.377814) (xy 312.343624 -407.385567) (xy 312.316368 -407.386028)
			(xy 311.452768 -407.386028) (xy 311.42552 -407.3855) (xy 311.371578 -407.37774) (xy 311.31929 -407.362383)
			(xy 311.26972 -407.339741) (xy 311.223876 -407.310275) (xy 311.182692 -407.274586) (xy 311.147005 -407.233399)
			(xy 311.117544 -407.187552) (xy 311.094906 -407.13798) (xy 311.079553 -407.08569) (xy 311.071798 -407.031748)
			(xy 309.634142 -407.031748) (xy 309.634142 -407.031751) (xy 309.626386 -407.0857) (xy 309.611032 -407.137995)
			(xy 309.588391 -407.187573) (xy 309.558926 -407.233424) (xy 309.523236 -407.274616) (xy 309.482047 -407.310309)
			(xy 309.436197 -407.339778) (xy 309.386621 -407.362422) (xy 309.334327 -407.37778) (xy 309.280379 -407.38554)
			(xy 309.253128 -407.386028) (xy 308.389528 -407.386028) (xy 308.362275 -407.385527) (xy 308.308324 -407.377773)
			(xy 308.256026 -407.36242) (xy 308.206445 -407.339781) (xy 308.16059 -407.310315) (xy 308.119397 -407.274623)
			(xy 308.083702 -407.233432) (xy 308.054233 -407.18758) (xy 308.031589 -407.138001) (xy 308.016233 -407.085703)
			(xy 308.008475 -407.031753) (xy 306.570965 -407.031753) (xy 306.570965 -407.031755) (xy 306.563207 -407.08571)
			(xy 306.54785 -407.138011) (xy 306.525205 -407.187595) (xy 306.495735 -407.233451) (xy 306.460038 -407.274646)
			(xy 306.418841 -407.310342) (xy 306.372984 -407.339811) (xy 306.3234 -407.362454) (xy 306.271098 -407.37781)
			(xy 306.217143 -407.385566) (xy 306.189888 -407.386028) (xy 305.326288 -407.386028) (xy 305.299039 -407.385501)
			(xy 305.245095 -407.377743) (xy 305.192805 -407.362388) (xy 305.143232 -407.339748) (xy 305.097385 -407.310282)
			(xy 305.056199 -407.274593) (xy 305.02051 -407.233405) (xy 304.991047 -407.187558) (xy 304.968408 -407.137984)
			(xy 304.953054 -407.085693) (xy 304.945298 -407.031749) (xy 274.459335 -407.031749) (xy 274.369276 -407.121868)
			(xy 274.369276 -407.203148) (xy 274.602448 -407.43632) (xy 280.100532 -407.43632) (xy 280.125484 -407.436804)
			(xy 280.174775 -407.444599) (xy 280.222241 -407.460008) (xy 280.266712 -407.482651) (xy 280.307094 -407.511971)
			(xy 280.325068 -407.529284) (xy 280.739596 -407.943812) (xy 280.756881 -407.96181) (xy 280.786193 -408.002193)
			(xy 280.808837 -408.046659) (xy 280.824257 -408.094116) (xy 280.832075 -408.143399) (xy 280.83256 -408.168348)
			(xy 280.83256 -410.057453) (xy 304.945246 -410.057453) (xy 304.945246 -410.002947) (xy 304.953003 -409.948996)
			(xy 304.968358 -409.896698) (xy 304.991001 -409.847117) (xy 305.020468 -409.801263) (xy 305.056162 -409.76007)
			(xy 305.097354 -409.724375) (xy 305.143207 -409.694906) (xy 305.192786 -409.672263) (xy 305.245084 -409.656905)
			(xy 305.299035 -409.649147) (xy 305.326288 -409.64866) (xy 306.189888 -409.64866) (xy 306.217139 -409.649186)
			(xy 306.271087 -409.656941) (xy 306.323382 -409.672295) (xy 306.372959 -409.694935) (xy 306.41881 -409.7244)
			(xy 306.460001 -409.760091) (xy 306.495693 -409.80128) (xy 306.525159 -409.84713) (xy 306.547801 -409.896707)
			(xy 306.563156 -409.949001) (xy 306.570913 -410.002949) (xy 306.570913 -410.057451) (xy 306.570912 -410.057456)
			(xy 308.008423 -410.057456) (xy 308.008423 -410.002944) (xy 308.016181 -409.948986) (xy 308.03154 -409.896681)
			(xy 308.054187 -409.847095) (xy 308.08366 -409.801236) (xy 308.119359 -409.76004) (xy 308.160559 -409.724343)
			(xy 308.206419 -409.694873) (xy 308.256007 -409.67223) (xy 308.308313 -409.656875) (xy 308.362272 -409.649121)
			(xy 308.389528 -409.64866) (xy 309.253128 -409.64866) (xy 309.280376 -409.649212) (xy 309.334316 -409.656971)
			(xy 309.386603 -409.672327) (xy 309.436172 -409.694968) (xy 309.482015 -409.724433) (xy 309.523199 -409.760121)
			(xy 309.558884 -409.801307) (xy 309.588345 -409.847152) (xy 309.610982 -409.896724) (xy 309.626335 -409.949012)
			(xy 309.63409 -410.002952) (xy 309.63409 -410.057448) (xy 309.634089 -410.057452) (xy 311.071746 -410.057452)
			(xy 311.071746 -410.002948) (xy 311.079502 -409.948998) (xy 311.094857 -409.896702) (xy 311.117498 -409.847123)
			(xy 311.146963 -409.80127) (xy 311.182654 -409.760077) (xy 311.223844 -409.724383) (xy 311.269695 -409.694913)
			(xy 311.319272 -409.672268) (xy 311.371567 -409.656909) (xy 311.425516 -409.649148) (xy 311.452768 -409.64866)
			(xy 312.316368 -409.64866) (xy 312.34362 -409.649185) (xy 312.39757 -409.656938) (xy 312.449867 -409.67229)
			(xy 312.499447 -409.694928) (xy 312.545301 -409.724393) (xy 312.586494 -409.760084) (xy 312.622188 -409.801274)
			(xy 312.651656 -409.847125) (xy 312.674299 -409.896703) (xy 312.689655 -409.948999) (xy 312.697413 -410.002948)
			(xy 312.697413 -410.057452) (xy 312.697412 -410.057456) (xy 314.134923 -410.057456) (xy 314.134923 -410.002944)
			(xy 314.142681 -409.948988) (xy 314.158039 -409.896685) (xy 314.180684 -409.8471) (xy 314.210155 -409.801243)
			(xy 314.245852 -409.760047) (xy 314.287049 -409.72435) (xy 314.332907 -409.69488) (xy 314.382493 -409.672236)
			(xy 314.434796 -409.656879) (xy 314.488752 -409.649122) (xy 314.516008 -409.64866) (xy 315.379608 -409.64866)
			(xy 315.406857 -409.649211) (xy 315.460799 -409.656968) (xy 315.513088 -409.672322) (xy 315.56266 -409.694962)
			(xy 315.608506 -409.724426) (xy 315.649691 -409.760114) (xy 315.685379 -409.801301) (xy 315.714842 -409.847147)
			(xy 315.737481 -409.896719) (xy 315.752834 -409.949009) (xy 315.76059 -410.002951) (xy 315.76059 -410.057449)
			(xy 315.760589 -410.057457) (xy 317.198123 -410.057457) (xy 317.198123 -410.002943) (xy 317.205882 -409.948983)
			(xy 317.221242 -409.896677) (xy 317.24389 -409.847089) (xy 317.273365 -409.80123) (xy 317.309066 -409.760033)
			(xy 317.350268 -409.724336) (xy 317.396131 -409.694867) (xy 317.445722 -409.672225) (xy 317.49803 -409.656872)
			(xy 317.551991 -409.64912) (xy 317.579248 -409.64866) (xy 318.442848 -409.64866) (xy 318.470095 -409.649213)
			(xy 318.524033 -409.656975) (xy 318.576317 -409.672333) (xy 318.625884 -409.694975) (xy 318.671725 -409.72444)
			(xy 318.712906 -409.760128) (xy 318.748589 -409.801314) (xy 318.778048 -409.847158) (xy 318.800684 -409.896728)
			(xy 318.816035 -409.949014) (xy 318.82379 -410.002953) (xy 318.82379 -410.057447) (xy 318.823789 -410.057453)
			(xy 320.261446 -410.057453) (xy 320.261446 -410.002947) (xy 320.269203 -409.948996) (xy 320.284558 -409.896698)
			(xy 320.307201 -409.847117) (xy 320.336668 -409.801263) (xy 320.372362 -409.76007) (xy 320.413554 -409.724375)
			(xy 320.459407 -409.694906) (xy 320.508986 -409.672263) (xy 320.561284 -409.656905) (xy 320.615235 -409.649147)
			(xy 320.642488 -409.64866) (xy 321.506088 -409.64866) (xy 321.533339 -409.649186) (xy 321.587287 -409.656941)
			(xy 321.639582 -409.672295) (xy 321.689159 -409.694935) (xy 321.73501 -409.7244) (xy 321.776201 -409.760091)
			(xy 321.811893 -409.80128) (xy 321.841359 -409.84713) (xy 321.864001 -409.896707) (xy 321.879356 -409.949001)
			(xy 321.887113 -410.002949) (xy 321.887113 -410.057451) (xy 321.887112 -410.057456) (xy 323.324623 -410.057456)
			(xy 323.324623 -410.002944) (xy 323.332381 -409.948986) (xy 323.34774 -409.896681) (xy 323.370387 -409.847095)
			(xy 323.39986 -409.801236) (xy 323.435559 -409.76004) (xy 323.476759 -409.724343) (xy 323.522619 -409.694873)
			(xy 323.572207 -409.67223) (xy 323.624513 -409.656875) (xy 323.678472 -409.649121) (xy 323.705728 -409.64866)
			(xy 324.569328 -409.64866) (xy 324.596576 -409.649212) (xy 324.650516 -409.656971) (xy 324.702803 -409.672327)
			(xy 324.752372 -409.694968) (xy 324.798215 -409.724433) (xy 324.839399 -409.760121) (xy 324.875084 -409.801307)
			(xy 324.904545 -409.847152) (xy 324.927182 -409.896724) (xy 324.942535 -409.949012) (xy 324.95029 -410.002952)
			(xy 324.95029 -410.057448) (xy 324.950289 -410.057452) (xy 326.387946 -410.057452) (xy 326.387946 -410.002948)
			(xy 326.395702 -409.948998) (xy 326.411057 -409.896702) (xy 326.433698 -409.847123) (xy 326.463163 -409.80127)
			(xy 326.498854 -409.760077) (xy 326.540044 -409.724383) (xy 326.585895 -409.694913) (xy 326.635472 -409.672268)
			(xy 326.687767 -409.656909) (xy 326.741716 -409.649148) (xy 326.768968 -409.64866) (xy 327.632568 -409.64866)
			(xy 327.65982 -409.649185) (xy 327.71377 -409.656938) (xy 327.766067 -409.67229) (xy 327.815647 -409.694928)
			(xy 327.861501 -409.724393) (xy 327.902694 -409.760084) (xy 327.938388 -409.801274) (xy 327.967856 -409.847125)
			(xy 327.990499 -409.896703) (xy 328.005855 -409.948999) (xy 328.013613 -410.002948) (xy 328.013613 -410.057452)
			(xy 328.013612 -410.057456) (xy 329.451123 -410.057456) (xy 329.451123 -410.002944) (xy 329.458881 -409.948988)
			(xy 329.474239 -409.896685) (xy 329.496884 -409.8471) (xy 329.526355 -409.801243) (xy 329.562052 -409.760047)
			(xy 329.603249 -409.72435) (xy 329.649107 -409.69488) (xy 329.698693 -409.672236) (xy 329.750996 -409.656879)
			(xy 329.804952 -409.649122) (xy 329.832208 -409.64866) (xy 330.695808 -409.64866) (xy 330.723057 -409.649211)
			(xy 330.776999 -409.656968) (xy 330.829288 -409.672322) (xy 330.87886 -409.694962) (xy 330.924706 -409.724426)
			(xy 330.965891 -409.760114) (xy 331.001579 -409.801301) (xy 331.031042 -409.847147) (xy 331.053681 -409.896719)
			(xy 331.069034 -409.949009) (xy 331.07679 -410.002951) (xy 331.07679 -410.057449) (xy 331.076789 -410.057457)
			(xy 332.514323 -410.057457) (xy 332.514323 -410.002943) (xy 332.522082 -409.948983) (xy 332.537442 -409.896677)
			(xy 332.56009 -409.847089) (xy 332.589565 -409.80123) (xy 332.625266 -409.760033) (xy 332.666468 -409.724336)
			(xy 332.712331 -409.694867) (xy 332.761922 -409.672225) (xy 332.81423 -409.656872) (xy 332.868191 -409.64912)
			(xy 332.895448 -409.64866) (xy 333.759048 -409.64866) (xy 333.786295 -409.649213) (xy 333.840233 -409.656975)
			(xy 333.892517 -409.672333) (xy 333.942084 -409.694975) (xy 333.987925 -409.72444) (xy 334.029106 -409.760128)
			(xy 334.064789 -409.801314) (xy 334.094248 -409.847158) (xy 334.116884 -409.896728) (xy 334.132235 -409.949014)
			(xy 334.13999 -410.002953) (xy 334.13999 -410.057447) (xy 334.139989 -410.057453) (xy 335.577646 -410.057453)
			(xy 335.577646 -410.002947) (xy 335.585403 -409.948996) (xy 335.600758 -409.896698) (xy 335.623401 -409.847117)
			(xy 335.652868 -409.801263) (xy 335.688562 -409.76007) (xy 335.729754 -409.724375) (xy 335.775607 -409.694906)
			(xy 335.825186 -409.672263) (xy 335.877484 -409.656905) (xy 335.931435 -409.649147) (xy 335.958688 -409.64866)
			(xy 336.822288 -409.64866) (xy 336.849539 -409.649186) (xy 336.903487 -409.656941) (xy 336.955782 -409.672295)
			(xy 337.005359 -409.694935) (xy 337.05121 -409.7244) (xy 337.092401 -409.760091) (xy 337.128093 -409.80128)
			(xy 337.157559 -409.84713) (xy 337.180201 -409.896707) (xy 337.195556 -409.949001) (xy 337.203313 -410.002949)
			(xy 337.203313 -410.057451) (xy 337.203312 -410.057456) (xy 338.640823 -410.057456) (xy 338.640823 -410.002944)
			(xy 338.648581 -409.948986) (xy 338.66394 -409.896681) (xy 338.686587 -409.847095) (xy 338.71606 -409.801236)
			(xy 338.751759 -409.76004) (xy 338.792959 -409.724343) (xy 338.838819 -409.694873) (xy 338.888407 -409.67223)
			(xy 338.940713 -409.656875) (xy 338.994672 -409.649121) (xy 339.021928 -409.64866) (xy 339.885528 -409.64866)
			(xy 339.912776 -409.649212) (xy 339.966716 -409.656971) (xy 340.019003 -409.672327) (xy 340.068572 -409.694968)
			(xy 340.114415 -409.724433) (xy 340.155599 -409.760121) (xy 340.191284 -409.801307) (xy 340.220745 -409.847152)
			(xy 340.243382 -409.896724) (xy 340.258735 -409.949012) (xy 340.26649 -410.002952) (xy 340.26649 -410.057448)
			(xy 340.266489 -410.057452) (xy 341.704146 -410.057452) (xy 341.704146 -410.002948) (xy 341.711902 -409.948998)
			(xy 341.727257 -409.896702) (xy 341.749898 -409.847123) (xy 341.779363 -409.80127) (xy 341.815054 -409.760077)
			(xy 341.856244 -409.724383) (xy 341.902095 -409.694913) (xy 341.951672 -409.672268) (xy 342.003967 -409.656909)
			(xy 342.057916 -409.649148) (xy 342.085168 -409.64866) (xy 342.948768 -409.64866) (xy 342.97602 -409.649185)
			(xy 343.02997 -409.656938) (xy 343.082267 -409.67229) (xy 343.131847 -409.694928) (xy 343.177701 -409.724393)
			(xy 343.218894 -409.760084) (xy 343.254588 -409.801274) (xy 343.284056 -409.847125) (xy 343.306699 -409.896703)
			(xy 343.322055 -409.948999) (xy 343.329813 -410.002948) (xy 343.329813 -410.057452) (xy 343.329812 -410.057456)
			(xy 344.767323 -410.057456) (xy 344.767323 -410.002944) (xy 344.775081 -409.948988) (xy 344.790439 -409.896685)
			(xy 344.813084 -409.8471) (xy 344.842555 -409.801243) (xy 344.878252 -409.760047) (xy 344.919449 -409.72435)
			(xy 344.965307 -409.69488) (xy 345.014893 -409.672236) (xy 345.067196 -409.656879) (xy 345.121152 -409.649122)
			(xy 345.148408 -409.64866) (xy 346.012008 -409.64866) (xy 346.039257 -409.649211) (xy 346.093199 -409.656968)
			(xy 346.145488 -409.672322) (xy 346.19506 -409.694962) (xy 346.240906 -409.724426) (xy 346.282091 -409.760114)
			(xy 346.317779 -409.801301) (xy 346.347242 -409.847147) (xy 346.369881 -409.896719) (xy 346.385234 -409.949009)
			(xy 346.39299 -410.002951) (xy 346.39299 -410.057449) (xy 346.392989 -410.057457) (xy 347.830523 -410.057457)
			(xy 347.830523 -410.002943) (xy 347.838282 -409.948983) (xy 347.853642 -409.896677) (xy 347.87629 -409.847089)
			(xy 347.905765 -409.80123) (xy 347.941466 -409.760033) (xy 347.982668 -409.724336) (xy 348.028531 -409.694867)
			(xy 348.078122 -409.672225) (xy 348.13043 -409.656872) (xy 348.184391 -409.64912) (xy 348.211648 -409.64866)
			(xy 349.075248 -409.64866) (xy 349.102495 -409.649213) (xy 349.156433 -409.656975) (xy 349.208717 -409.672333)
			(xy 349.258284 -409.694975) (xy 349.304125 -409.72444) (xy 349.345306 -409.760128) (xy 349.380989 -409.801314)
			(xy 349.410448 -409.847158) (xy 349.433084 -409.896728) (xy 349.448435 -409.949014) (xy 349.45619 -410.002953)
			(xy 349.45619 -410.057447) (xy 349.456189 -410.057453) (xy 350.893846 -410.057453) (xy 350.893846 -410.002947)
			(xy 350.901603 -409.948996) (xy 350.916958 -409.896698) (xy 350.939601 -409.847117) (xy 350.969068 -409.801263)
			(xy 351.004762 -409.76007) (xy 351.045954 -409.724375) (xy 351.091807 -409.694906) (xy 351.141386 -409.672263)
			(xy 351.193684 -409.656905) (xy 351.247635 -409.649147) (xy 351.274888 -409.64866) (xy 352.138488 -409.64866)
			(xy 352.165739 -409.649186) (xy 352.219687 -409.656941) (xy 352.271982 -409.672295) (xy 352.321559 -409.694935)
			(xy 352.36741 -409.7244) (xy 352.408601 -409.760091) (xy 352.444293 -409.80128) (xy 352.473759 -409.84713)
			(xy 352.496401 -409.896707) (xy 352.511756 -409.949001) (xy 352.519513 -410.002949) (xy 352.519513 -410.057451)
			(xy 352.519512 -410.057457) (xy 372.388023 -410.057457) (xy 372.388023 -410.002943) (xy 372.395781 -409.948985)
			(xy 372.41114 -409.896681) (xy 372.433787 -409.847094) (xy 372.46326 -409.801236) (xy 372.49896 -409.760039)
			(xy 372.54016 -409.724342) (xy 372.586021 -409.694872) (xy 372.635609 -409.67223) (xy 372.687915 -409.656875)
			(xy 372.741873 -409.649121) (xy 372.76913 -409.64866) (xy 373.63273 -409.64866) (xy 373.659978 -409.649212)
			(xy 373.713917 -409.656972) (xy 373.766204 -409.672328) (xy 373.815773 -409.694969) (xy 373.861616 -409.724434)
			(xy 373.902799 -409.760122) (xy 373.938484 -409.801308) (xy 373.967945 -409.847153) (xy 373.990583 -409.896724)
			(xy 374.005935 -409.949012) (xy 374.01369 -410.002952) (xy 374.01369 -410.057448) (xy 374.013689 -410.057452)
			(xy 375.451346 -410.057452) (xy 375.451346 -410.002948) (xy 375.459102 -409.948998) (xy 375.474457 -409.896701)
			(xy 375.497098 -409.847122) (xy 375.526564 -409.801269) (xy 375.562255 -409.760076) (xy 375.603445 -409.724382)
			(xy 375.649296 -409.694912) (xy 375.698873 -409.672268) (xy 375.751169 -409.656909) (xy 375.805118 -409.649148)
			(xy 375.83237 -409.64866) (xy 376.69597 -409.64866) (xy 376.723222 -409.649185) (xy 376.777172 -409.656938)
			(xy 376.829469 -409.67229) (xy 376.879048 -409.694929) (xy 376.924901 -409.724394) (xy 376.966094 -409.760084)
			(xy 377.001788 -409.801274) (xy 377.031257 -409.847125) (xy 377.053899 -409.896703) (xy 377.069256 -409.948999)
			(xy 377.077013 -410.002948) (xy 377.077013 -410.057452) (xy 377.077012 -410.057456) (xy 378.514523 -410.057456)
			(xy 378.514523 -410.002944) (xy 378.522281 -409.948988) (xy 378.537639 -409.896685) (xy 378.560284 -409.8471)
			(xy 378.589755 -409.801242) (xy 378.625453 -409.760046) (xy 378.66665 -409.724349) (xy 378.712509 -409.694879)
			(xy 378.762094 -409.672235) (xy 378.814398 -409.656879) (xy 378.868354 -409.649122) (xy 378.89561 -409.64866)
			(xy 379.75921 -409.64866) (xy 379.786458 -409.649211) (xy 379.840401 -409.656968) (xy 379.89269 -409.672323)
			(xy 379.942261 -409.694962) (xy 379.988107 -409.724426) (xy 380.029292 -409.760115) (xy 380.06498 -409.801301)
			(xy 380.094442 -409.847147) (xy 380.117081 -409.89672) (xy 380.132434 -409.949009) (xy 380.14019 -410.002952)
			(xy 380.14019 -410.057448) (xy 380.14019 -410.057451) (xy 381.577846 -410.057451) (xy 381.577846 -410.002949)
			(xy 381.585602 -409.949001) (xy 381.600955 -409.896706) (xy 381.623595 -409.847128) (xy 381.653059 -409.801276)
			(xy 381.688748 -409.760083) (xy 381.729936 -409.724389) (xy 381.775784 -409.694919) (xy 381.825359 -409.672273)
			(xy 381.877652 -409.656912) (xy 381.931599 -409.649149) (xy 381.95885 -409.64866) (xy 382.82245 -409.64866)
			(xy 382.849703 -409.649184) (xy 382.903655 -409.656934) (xy 382.955954 -409.672285) (xy 383.005536 -409.694923)
			(xy 383.051392 -409.724387) (xy 383.092587 -409.760077) (xy 383.128283 -409.801268) (xy 383.157753 -409.84712)
			(xy 383.180398 -409.896699) (xy 383.195755 -409.948996) (xy 383.203513 -410.002947) (xy 383.203513 -410.057453)
			(xy 384.641046 -410.057453) (xy 384.641046 -410.002947) (xy 384.648803 -409.948996) (xy 384.664159 -409.896697)
			(xy 384.686801 -409.847117) (xy 384.716269 -409.801263) (xy 384.751962 -409.760069) (xy 384.793155 -409.724375)
			(xy 384.839008 -409.694906) (xy 384.888588 -409.672262) (xy 384.940886 -409.656905) (xy 384.994837 -409.649147)
			(xy 385.02209 -409.64866) (xy 385.88569 -409.64866) (xy 385.912941 -409.649187) (xy 385.966889 -409.656942)
			(xy 386.019183 -409.672296) (xy 386.06876 -409.694936) (xy 386.114611 -409.724401) (xy 386.155801 -409.760092)
			(xy 386.191493 -409.801281) (xy 386.22096 -409.847131) (xy 386.243601 -409.896707) (xy 386.258956 -409.949002)
			(xy 386.266713 -410.002949) (xy 386.266713 -410.057451) (xy 386.266712 -410.057457) (xy 387.704223 -410.057457)
			(xy 387.704223 -410.002943) (xy 387.711981 -409.948985) (xy 387.72734 -409.896681) (xy 387.749987 -409.847094)
			(xy 387.77946 -409.801236) (xy 387.81516 -409.760039) (xy 387.85636 -409.724342) (xy 387.902221 -409.694872)
			(xy 387.951809 -409.67223) (xy 388.004115 -409.656875) (xy 388.058073 -409.649121) (xy 388.08533 -409.64866)
			(xy 388.94893 -409.64866) (xy 388.976178 -409.649212) (xy 389.030117 -409.656972) (xy 389.082404 -409.672328)
			(xy 389.131973 -409.694969) (xy 389.177816 -409.724434) (xy 389.218999 -409.760122) (xy 389.254684 -409.801308)
			(xy 389.284145 -409.847153) (xy 389.306783 -409.896724) (xy 389.322135 -409.949012) (xy 389.32989 -410.002952)
			(xy 389.32989 -410.057448) (xy 389.329889 -410.057452) (xy 390.767546 -410.057452) (xy 390.767546 -410.002948)
			(xy 390.775302 -409.948998) (xy 390.790657 -409.896701) (xy 390.813298 -409.847122) (xy 390.842764 -409.801269)
			(xy 390.878455 -409.760076) (xy 390.919645 -409.724382) (xy 390.965496 -409.694912) (xy 391.015073 -409.672268)
			(xy 391.067369 -409.656909) (xy 391.121318 -409.649148) (xy 391.14857 -409.64866) (xy 392.01217 -409.64866)
			(xy 392.039422 -409.649185) (xy 392.093372 -409.656938) (xy 392.145669 -409.67229) (xy 392.195248 -409.694929)
			(xy 392.241101 -409.724394) (xy 392.282294 -409.760084) (xy 392.317988 -409.801274) (xy 392.347457 -409.847125)
			(xy 392.370099 -409.896703) (xy 392.385456 -409.948999) (xy 392.393213 -410.002948) (xy 392.393213 -410.057452)
			(xy 392.393212 -410.057456) (xy 393.830723 -410.057456) (xy 393.830723 -410.002944) (xy 393.838481 -409.948988)
			(xy 393.853839 -409.896685) (xy 393.876484 -409.8471) (xy 393.905955 -409.801242) (xy 393.941653 -409.760046)
			(xy 393.98285 -409.724349) (xy 394.028709 -409.694879) (xy 394.078294 -409.672235) (xy 394.130598 -409.656879)
			(xy 394.184554 -409.649122) (xy 394.21181 -409.64866) (xy 395.07541 -409.64866) (xy 395.102658 -409.649211)
			(xy 395.156601 -409.656968) (xy 395.20889 -409.672323) (xy 395.258461 -409.694962) (xy 395.304307 -409.724426)
			(xy 395.345492 -409.760115) (xy 395.38118 -409.801301) (xy 395.410642 -409.847147) (xy 395.433281 -409.89672)
			(xy 395.448634 -409.949009) (xy 395.45639 -410.002952) (xy 395.45639 -410.057448) (xy 395.45639 -410.057451)
			(xy 396.894046 -410.057451) (xy 396.894046 -410.002949) (xy 396.901802 -409.949001) (xy 396.917155 -409.896706)
			(xy 396.939795 -409.847128) (xy 396.969259 -409.801276) (xy 397.004948 -409.760083) (xy 397.046136 -409.724389)
			(xy 397.091984 -409.694919) (xy 397.141559 -409.672273) (xy 397.193852 -409.656912) (xy 397.247799 -409.649149)
			(xy 397.27505 -409.64866) (xy 398.13865 -409.64866) (xy 398.165903 -409.649184) (xy 398.219855 -409.656934)
			(xy 398.272154 -409.672285) (xy 398.321736 -409.694923) (xy 398.367592 -409.724387) (xy 398.408787 -409.760077)
			(xy 398.444483 -409.801268) (xy 398.473953 -409.84712) (xy 398.496598 -409.896699) (xy 398.511955 -409.948996)
			(xy 398.519713 -410.002947) (xy 398.519713 -410.057453) (xy 399.957246 -410.057453) (xy 399.957246 -410.002947)
			(xy 399.965003 -409.948996) (xy 399.980359 -409.896697) (xy 400.003001 -409.847117) (xy 400.032469 -409.801263)
			(xy 400.068162 -409.760069) (xy 400.109355 -409.724375) (xy 400.155208 -409.694906) (xy 400.204788 -409.672262)
			(xy 400.257086 -409.656905) (xy 400.311037 -409.649147) (xy 400.33829 -409.64866) (xy 401.20189 -409.64866)
			(xy 401.229141 -409.649187) (xy 401.283089 -409.656942) (xy 401.335383 -409.672296) (xy 401.38496 -409.694936)
			(xy 401.430811 -409.724401) (xy 401.472001 -409.760092) (xy 401.507693 -409.801281) (xy 401.53716 -409.847131)
			(xy 401.559801 -409.896707) (xy 401.575156 -409.949002) (xy 401.582913 -410.002949) (xy 401.582913 -410.057451)
			(xy 401.582912 -410.057457) (xy 403.020423 -410.057457) (xy 403.020423 -410.002943) (xy 403.028181 -409.948985)
			(xy 403.04354 -409.896681) (xy 403.066187 -409.847094) (xy 403.09566 -409.801236) (xy 403.13136 -409.760039)
			(xy 403.17256 -409.724342) (xy 403.218421 -409.694872) (xy 403.268009 -409.67223) (xy 403.320315 -409.656875)
			(xy 403.374273 -409.649121) (xy 403.40153 -409.64866) (xy 404.26513 -409.64866) (xy 404.292378 -409.649212)
			(xy 404.346317 -409.656972) (xy 404.398604 -409.672328) (xy 404.448173 -409.694969) (xy 404.494016 -409.724434)
			(xy 404.535199 -409.760122) (xy 404.570884 -409.801308) (xy 404.600345 -409.847153) (xy 404.622983 -409.896724)
			(xy 404.638335 -409.949012) (xy 404.64609 -410.002952) (xy 404.64609 -410.057448) (xy 404.646089 -410.057452)
			(xy 406.083746 -410.057452) (xy 406.083746 -410.002948) (xy 406.091502 -409.948998) (xy 406.106857 -409.896701)
			(xy 406.129498 -409.847122) (xy 406.158964 -409.801269) (xy 406.194655 -409.760076) (xy 406.235845 -409.724382)
			(xy 406.281696 -409.694912) (xy 406.331273 -409.672268) (xy 406.383569 -409.656909) (xy 406.437518 -409.649148)
			(xy 406.46477 -409.64866) (xy 407.32837 -409.64866) (xy 407.355622 -409.649185) (xy 407.409572 -409.656938)
			(xy 407.461869 -409.67229) (xy 407.511448 -409.694929) (xy 407.557301 -409.724394) (xy 407.598494 -409.760084)
			(xy 407.634188 -409.801274) (xy 407.663657 -409.847125) (xy 407.686299 -409.896703) (xy 407.701656 -409.948999)
			(xy 407.709413 -410.002948) (xy 407.709413 -410.057452) (xy 407.709412 -410.057456) (xy 409.146923 -410.057456)
			(xy 409.146923 -410.002944) (xy 409.154681 -409.948988) (xy 409.170039 -409.896685) (xy 409.192684 -409.8471)
			(xy 409.222155 -409.801242) (xy 409.257853 -409.760046) (xy 409.29905 -409.724349) (xy 409.344909 -409.694879)
			(xy 409.394494 -409.672235) (xy 409.446798 -409.656879) (xy 409.500754 -409.649122) (xy 409.52801 -409.64866)
			(xy 410.39161 -409.64866) (xy 410.418858 -409.649211) (xy 410.472801 -409.656968) (xy 410.52509 -409.672323)
			(xy 410.574661 -409.694962) (xy 410.620507 -409.724426) (xy 410.661692 -409.760115) (xy 410.69738 -409.801301)
			(xy 410.726842 -409.847147) (xy 410.749481 -409.89672) (xy 410.764834 -409.949009) (xy 410.77259 -410.002952)
			(xy 410.77259 -410.057448) (xy 410.77259 -410.057451) (xy 412.210246 -410.057451) (xy 412.210246 -410.002949)
			(xy 412.218002 -409.949001) (xy 412.233355 -409.896706) (xy 412.255995 -409.847128) (xy 412.285459 -409.801276)
			(xy 412.321148 -409.760083) (xy 412.362336 -409.724389) (xy 412.408184 -409.694919) (xy 412.457759 -409.672273)
			(xy 412.510052 -409.656912) (xy 412.563999 -409.649149) (xy 412.59125 -409.64866) (xy 413.45485 -409.64866)
			(xy 413.482103 -409.649184) (xy 413.536055 -409.656934) (xy 413.588354 -409.672285) (xy 413.637936 -409.694923)
			(xy 413.683792 -409.724387) (xy 413.724987 -409.760077) (xy 413.760683 -409.801268) (xy 413.790153 -409.84712)
			(xy 413.812798 -409.896699) (xy 413.828155 -409.948996) (xy 413.835913 -410.002947) (xy 413.835913 -410.057453)
			(xy 415.273446 -410.057453) (xy 415.273446 -410.002947) (xy 415.281203 -409.948996) (xy 415.296559 -409.896697)
			(xy 415.319201 -409.847117) (xy 415.348669 -409.801263) (xy 415.384362 -409.760069) (xy 415.425555 -409.724375)
			(xy 415.471408 -409.694906) (xy 415.520988 -409.672262) (xy 415.573286 -409.656905) (xy 415.627237 -409.649147)
			(xy 415.65449 -409.64866) (xy 416.51809 -409.64866) (xy 416.545341 -409.649187) (xy 416.599289 -409.656942)
			(xy 416.651583 -409.672296) (xy 416.70116 -409.694936) (xy 416.747011 -409.724401) (xy 416.788201 -409.760092)
			(xy 416.823893 -409.801281) (xy 416.85336 -409.847131) (xy 416.876001 -409.896707) (xy 416.891356 -409.949002)
			(xy 416.899113 -410.002949) (xy 416.899113 -410.057451) (xy 416.899112 -410.057457) (xy 418.336623 -410.057457)
			(xy 418.336623 -410.002943) (xy 418.344381 -409.948985) (xy 418.35974 -409.896681) (xy 418.382387 -409.847094)
			(xy 418.41186 -409.801236) (xy 418.44756 -409.760039) (xy 418.48876 -409.724342) (xy 418.534621 -409.694872)
			(xy 418.584209 -409.67223) (xy 418.636515 -409.656875) (xy 418.690473 -409.649121) (xy 418.71773 -409.64866)
			(xy 419.58133 -409.64866) (xy 419.608578 -409.649212) (xy 419.662517 -409.656972) (xy 419.714804 -409.672328)
			(xy 419.764373 -409.694969) (xy 419.810216 -409.724434) (xy 419.851399 -409.760122) (xy 419.887084 -409.801308)
			(xy 419.916545 -409.847153) (xy 419.939183 -409.896724) (xy 419.954535 -409.949012) (xy 419.96229 -410.002952)
			(xy 419.96229 -410.057448) (xy 419.954535 -410.111388) (xy 419.939183 -410.163676) (xy 419.916545 -410.213247)
			(xy 419.887084 -410.259092) (xy 419.851399 -410.300278) (xy 419.810216 -410.335966) (xy 419.764373 -410.365431)
			(xy 419.714804 -410.388072) (xy 419.662517 -410.403428) (xy 419.608578 -410.411188) (xy 419.58133 -410.411676)
			(xy 418.71773 -410.411676) (xy 418.690473 -410.411279) (xy 418.636515 -410.403525) (xy 418.584209 -410.38817)
			(xy 418.534621 -410.365528) (xy 418.48876 -410.336058) (xy 418.44756 -410.300361) (xy 418.41186 -410.259164)
			(xy 418.382387 -410.213306) (xy 418.35974 -410.163719) (xy 418.344381 -410.111415) (xy 418.336623 -410.057457)
			(xy 416.899112 -410.057457) (xy 416.891356 -410.111398) (xy 416.876001 -410.163693) (xy 416.85336 -410.213269)
			(xy 416.823893 -410.259119) (xy 416.788201 -410.300308) (xy 416.747011 -410.335999) (xy 416.70116 -410.365464)
			(xy 416.651583 -410.388104) (xy 416.599289 -410.403458) (xy 416.545341 -410.411213) (xy 416.51809 -410.411676)
			(xy 415.65449 -410.411676) (xy 415.627237 -410.411253) (xy 415.573286 -410.403495) (xy 415.520988 -410.388138)
			(xy 415.471408 -410.365494) (xy 415.425555 -410.336025) (xy 415.384362 -410.300331) (xy 415.348669 -410.259137)
			(xy 415.319201 -410.213283) (xy 415.296559 -410.163703) (xy 415.281203 -410.111404) (xy 415.273446 -410.057453)
			(xy 413.835913 -410.057453) (xy 413.828155 -410.111404) (xy 413.812798 -410.163701) (xy 413.790153 -410.21328)
			(xy 413.760683 -410.259132) (xy 413.724987 -410.300323) (xy 413.683792 -410.336013) (xy 413.637936 -410.365477)
			(xy 413.588354 -410.388115) (xy 413.536055 -410.403466) (xy 413.482103 -410.411216) (xy 413.45485 -410.411676)
			(xy 412.59125 -410.411676) (xy 412.563999 -410.411251) (xy 412.510052 -410.403488) (xy 412.457759 -410.388127)
			(xy 412.408184 -410.365481) (xy 412.362336 -410.336011) (xy 412.321148 -410.300317) (xy 412.285459 -410.259124)
			(xy 412.255995 -410.213272) (xy 412.233355 -410.163694) (xy 412.218002 -410.111399) (xy 412.210246 -410.057451)
			(xy 410.77259 -410.057451) (xy 410.764834 -410.111391) (xy 410.749481 -410.16368) (xy 410.726842 -410.213253)
			(xy 410.69738 -410.259099) (xy 410.661692 -410.300285) (xy 410.620507 -410.335974) (xy 410.574661 -410.365438)
			(xy 410.52509 -410.388077) (xy 410.472801 -410.403432) (xy 410.418858 -410.411189) (xy 410.39161 -410.411676)
			(xy 409.52801 -410.411676) (xy 409.500754 -410.411278) (xy 409.446798 -410.403521) (xy 409.394494 -410.388165)
			(xy 409.344909 -410.365521) (xy 409.29905 -410.336051) (xy 409.257853 -410.300354) (xy 409.222155 -410.259158)
			(xy 409.192684 -410.2133) (xy 409.170039 -410.163715) (xy 409.154681 -410.111412) (xy 409.146923 -410.057456)
			(xy 407.709412 -410.057456) (xy 407.701656 -410.111401) (xy 407.686299 -410.163697) (xy 407.663657 -410.213275)
			(xy 407.634188 -410.259126) (xy 407.598494 -410.300316) (xy 407.557301 -410.336006) (xy 407.511448 -410.365471)
			(xy 407.461869 -410.38811) (xy 407.409572 -410.403462) (xy 407.355622 -410.411215) (xy 407.32837 -410.411676)
			(xy 406.46477 -410.411676) (xy 406.437518 -410.411252) (xy 406.383569 -410.403491) (xy 406.331273 -410.388132)
			(xy 406.281696 -410.365488) (xy 406.235845 -410.336018) (xy 406.194655 -410.300324) (xy 406.158964 -410.259131)
			(xy 406.129498 -410.213278) (xy 406.106857 -410.163699) (xy 406.091502 -410.111402) (xy 406.083746 -410.057452)
			(xy 404.646089 -410.057452) (xy 404.638335 -410.111388) (xy 404.622983 -410.163676) (xy 404.600345 -410.213247)
			(xy 404.570884 -410.259092) (xy 404.535199 -410.300278) (xy 404.494016 -410.335966) (xy 404.448173 -410.365431)
			(xy 404.398604 -410.388072) (xy 404.346317 -410.403428) (xy 404.292378 -410.411188) (xy 404.26513 -410.411676)
			(xy 403.40153 -410.411676) (xy 403.374273 -410.411279) (xy 403.320315 -410.403525) (xy 403.268009 -410.38817)
			(xy 403.218421 -410.365528) (xy 403.17256 -410.336058) (xy 403.13136 -410.300361) (xy 403.09566 -410.259164)
			(xy 403.066187 -410.213306) (xy 403.04354 -410.163719) (xy 403.028181 -410.111415) (xy 403.020423 -410.057457)
			(xy 401.582912 -410.057457) (xy 401.575156 -410.111398) (xy 401.559801 -410.163693) (xy 401.53716 -410.213269)
			(xy 401.507693 -410.259119) (xy 401.472001 -410.300308) (xy 401.430811 -410.335999) (xy 401.38496 -410.365464)
			(xy 401.335383 -410.388104) (xy 401.283089 -410.403458) (xy 401.229141 -410.411213) (xy 401.20189 -410.411676)
			(xy 400.33829 -410.411676) (xy 400.311037 -410.411253) (xy 400.257086 -410.403495) (xy 400.204788 -410.388138)
			(xy 400.155208 -410.365494) (xy 400.109355 -410.336025) (xy 400.068162 -410.300331) (xy 400.032469 -410.259137)
			(xy 400.003001 -410.213283) (xy 399.980359 -410.163703) (xy 399.965003 -410.111404) (xy 399.957246 -410.057453)
			(xy 398.519713 -410.057453) (xy 398.511955 -410.111404) (xy 398.496598 -410.163701) (xy 398.473953 -410.21328)
			(xy 398.444483 -410.259132) (xy 398.408787 -410.300323) (xy 398.367592 -410.336013) (xy 398.321736 -410.365477)
			(xy 398.272154 -410.388115) (xy 398.219855 -410.403466) (xy 398.165903 -410.411216) (xy 398.13865 -410.411676)
			(xy 397.27505 -410.411676) (xy 397.247799 -410.411251) (xy 397.193852 -410.403488) (xy 397.141559 -410.388127)
			(xy 397.091984 -410.365481) (xy 397.046136 -410.336011) (xy 397.004948 -410.300317) (xy 396.969259 -410.259124)
			(xy 396.939795 -410.213272) (xy 396.917155 -410.163694) (xy 396.901802 -410.111399) (xy 396.894046 -410.057451)
			(xy 395.45639 -410.057451) (xy 395.448634 -410.111391) (xy 395.433281 -410.16368) (xy 395.410642 -410.213253)
			(xy 395.38118 -410.259099) (xy 395.345492 -410.300285) (xy 395.304307 -410.335974) (xy 395.258461 -410.365438)
			(xy 395.20889 -410.388077) (xy 395.156601 -410.403432) (xy 395.102658 -410.411189) (xy 395.07541 -410.411676)
			(xy 394.21181 -410.411676) (xy 394.184554 -410.411278) (xy 394.130598 -410.403521) (xy 394.078294 -410.388165)
			(xy 394.028709 -410.365521) (xy 393.98285 -410.336051) (xy 393.941653 -410.300354) (xy 393.905955 -410.259158)
			(xy 393.876484 -410.2133) (xy 393.853839 -410.163715) (xy 393.838481 -410.111412) (xy 393.830723 -410.057456)
			(xy 392.393212 -410.057456) (xy 392.385456 -410.111401) (xy 392.370099 -410.163697) (xy 392.347457 -410.213275)
			(xy 392.317988 -410.259126) (xy 392.282294 -410.300316) (xy 392.241101 -410.336006) (xy 392.195248 -410.365471)
			(xy 392.145669 -410.38811) (xy 392.093372 -410.403462) (xy 392.039422 -410.411215) (xy 392.01217 -410.411676)
			(xy 391.14857 -410.411676) (xy 391.121318 -410.411252) (xy 391.067369 -410.403491) (xy 391.015073 -410.388132)
			(xy 390.965496 -410.365488) (xy 390.919645 -410.336018) (xy 390.878455 -410.300324) (xy 390.842764 -410.259131)
			(xy 390.813298 -410.213278) (xy 390.790657 -410.163699) (xy 390.775302 -410.111402) (xy 390.767546 -410.057452)
			(xy 389.329889 -410.057452) (xy 389.322135 -410.111388) (xy 389.306783 -410.163676) (xy 389.284145 -410.213247)
			(xy 389.254684 -410.259092) (xy 389.218999 -410.300278) (xy 389.177816 -410.335966) (xy 389.131973 -410.365431)
			(xy 389.082404 -410.388072) (xy 389.030117 -410.403428) (xy 388.976178 -410.411188) (xy 388.94893 -410.411676)
			(xy 388.08533 -410.411676) (xy 388.058073 -410.411279) (xy 388.004115 -410.403525) (xy 387.951809 -410.38817)
			(xy 387.902221 -410.365528) (xy 387.85636 -410.336058) (xy 387.81516 -410.300361) (xy 387.77946 -410.259164)
			(xy 387.749987 -410.213306) (xy 387.72734 -410.163719) (xy 387.711981 -410.111415) (xy 387.704223 -410.057457)
			(xy 386.266712 -410.057457) (xy 386.258956 -410.111398) (xy 386.243601 -410.163693) (xy 386.22096 -410.213269)
			(xy 386.191493 -410.259119) (xy 386.155801 -410.300308) (xy 386.114611 -410.335999) (xy 386.06876 -410.365464)
			(xy 386.019183 -410.388104) (xy 385.966889 -410.403458) (xy 385.912941 -410.411213) (xy 385.88569 -410.411676)
			(xy 385.02209 -410.411676) (xy 384.994837 -410.411253) (xy 384.940886 -410.403495) (xy 384.888588 -410.388138)
			(xy 384.839008 -410.365494) (xy 384.793155 -410.336025) (xy 384.751962 -410.300331) (xy 384.716269 -410.259137)
			(xy 384.686801 -410.213283) (xy 384.664159 -410.163703) (xy 384.648803 -410.111404) (xy 384.641046 -410.057453)
			(xy 383.203513 -410.057453) (xy 383.195755 -410.111404) (xy 383.180398 -410.163701) (xy 383.157753 -410.21328)
			(xy 383.128283 -410.259132) (xy 383.092587 -410.300323) (xy 383.051392 -410.336013) (xy 383.005536 -410.365477)
			(xy 382.955954 -410.388115) (xy 382.903655 -410.403466) (xy 382.849703 -410.411216) (xy 382.82245 -410.411676)
			(xy 381.95885 -410.411676) (xy 381.931599 -410.411251) (xy 381.877652 -410.403488) (xy 381.825359 -410.388127)
			(xy 381.775784 -410.365481) (xy 381.729936 -410.336011) (xy 381.688748 -410.300317) (xy 381.653059 -410.259124)
			(xy 381.623595 -410.213272) (xy 381.600955 -410.163694) (xy 381.585602 -410.111399) (xy 381.577846 -410.057451)
			(xy 380.14019 -410.057451) (xy 380.132434 -410.111391) (xy 380.117081 -410.16368) (xy 380.094442 -410.213253)
			(xy 380.06498 -410.259099) (xy 380.029292 -410.300285) (xy 379.988107 -410.335974) (xy 379.942261 -410.365438)
			(xy 379.89269 -410.388077) (xy 379.840401 -410.403432) (xy 379.786458 -410.411189) (xy 379.75921 -410.411676)
			(xy 378.89561 -410.411676) (xy 378.868354 -410.411278) (xy 378.814398 -410.403521) (xy 378.762094 -410.388165)
			(xy 378.712509 -410.365521) (xy 378.66665 -410.336051) (xy 378.625453 -410.300354) (xy 378.589755 -410.259158)
			(xy 378.560284 -410.2133) (xy 378.537639 -410.163715) (xy 378.522281 -410.111412) (xy 378.514523 -410.057456)
			(xy 377.077012 -410.057456) (xy 377.069256 -410.111401) (xy 377.053899 -410.163697) (xy 377.031257 -410.213275)
			(xy 377.001788 -410.259126) (xy 376.966094 -410.300316) (xy 376.924901 -410.336006) (xy 376.879048 -410.365471)
			(xy 376.829469 -410.38811) (xy 376.777172 -410.403462) (xy 376.723222 -410.411215) (xy 376.69597 -410.411676)
			(xy 375.83237 -410.411676) (xy 375.805118 -410.411252) (xy 375.751169 -410.403491) (xy 375.698873 -410.388132)
			(xy 375.649296 -410.365488) (xy 375.603445 -410.336018) (xy 375.562255 -410.300324) (xy 375.526564 -410.259131)
			(xy 375.497098 -410.213278) (xy 375.474457 -410.163699) (xy 375.459102 -410.111402) (xy 375.451346 -410.057452)
			(xy 374.013689 -410.057452) (xy 374.005935 -410.111388) (xy 373.990583 -410.163676) (xy 373.967945 -410.213247)
			(xy 373.938484 -410.259092) (xy 373.902799 -410.300278) (xy 373.861616 -410.335966) (xy 373.815773 -410.365431)
			(xy 373.766204 -410.388072) (xy 373.713917 -410.403428) (xy 373.659978 -410.411188) (xy 373.63273 -410.411676)
			(xy 372.76913 -410.411676) (xy 372.741873 -410.411279) (xy 372.687915 -410.403525) (xy 372.635609 -410.38817)
			(xy 372.586021 -410.365528) (xy 372.54016 -410.336058) (xy 372.49896 -410.300361) (xy 372.46326 -410.259164)
			(xy 372.433787 -410.213306) (xy 372.41114 -410.163719) (xy 372.395781 -410.111415) (xy 372.388023 -410.057457)
			(xy 352.519512 -410.057457) (xy 352.511756 -410.111399) (xy 352.496401 -410.163693) (xy 352.473759 -410.21327)
			(xy 352.444293 -410.25912) (xy 352.408601 -410.300309) (xy 352.36741 -410.336) (xy 352.321559 -410.365465)
			(xy 352.271982 -410.388105) (xy 352.219687 -410.403459) (xy 352.165739 -410.411214) (xy 352.138488 -410.411676)
			(xy 351.274888 -410.411676) (xy 351.247635 -410.411253) (xy 351.193684 -410.403495) (xy 351.141386 -410.388137)
			(xy 351.091807 -410.365494) (xy 351.045954 -410.336025) (xy 351.004762 -410.30033) (xy 350.969068 -410.259137)
			(xy 350.939601 -410.213283) (xy 350.916958 -410.163702) (xy 350.901603 -410.111404) (xy 350.893846 -410.057453)
			(xy 349.456189 -410.057453) (xy 349.448435 -410.111386) (xy 349.433084 -410.163672) (xy 349.410448 -410.213242)
			(xy 349.380989 -410.259086) (xy 349.345306 -410.300272) (xy 349.304125 -410.33596) (xy 349.258284 -410.365425)
			(xy 349.208717 -410.388067) (xy 349.156433 -410.403425) (xy 349.102495 -410.411187) (xy 349.075248 -410.411676)
			(xy 348.211648 -410.411676) (xy 348.184391 -410.41128) (xy 348.13043 -410.403528) (xy 348.078122 -410.388175)
			(xy 348.028531 -410.365533) (xy 347.982668 -410.336064) (xy 347.941466 -410.300367) (xy 347.905765 -410.25917)
			(xy 347.87629 -410.213311) (xy 347.853642 -410.163723) (xy 347.838282 -410.111417) (xy 347.830523 -410.057457)
			(xy 346.392989 -410.057457) (xy 346.385234 -410.111391) (xy 346.369881 -410.163681) (xy 346.347242 -410.213253)
			(xy 346.317779 -410.259099) (xy 346.282091 -410.300286) (xy 346.240906 -410.335974) (xy 346.19506 -410.365438)
			(xy 346.145488 -410.388078) (xy 346.093199 -410.403432) (xy 346.039257 -410.411189) (xy 346.012008 -410.411676)
			(xy 345.148408 -410.411676) (xy 345.121152 -410.411278) (xy 345.067196 -410.403521) (xy 345.014893 -410.388164)
			(xy 344.965307 -410.36552) (xy 344.919449 -410.33605) (xy 344.878252 -410.300353) (xy 344.842555 -410.259157)
			(xy 344.813084 -410.2133) (xy 344.790439 -410.163715) (xy 344.775081 -410.111412) (xy 344.767323 -410.057456)
			(xy 343.329812 -410.057456) (xy 343.322055 -410.111401) (xy 343.306699 -410.163697) (xy 343.284056 -410.213275)
			(xy 343.254588 -410.259126) (xy 343.218894 -410.300316) (xy 343.177701 -410.336007) (xy 343.131847 -410.365472)
			(xy 343.082267 -410.38811) (xy 343.02997 -410.403462) (xy 342.97602 -410.411215) (xy 342.948768 -410.411676)
			(xy 342.085168 -410.411676) (xy 342.057916 -410.411252) (xy 342.003967 -410.403491) (xy 341.951672 -410.388132)
			(xy 341.902095 -410.365487) (xy 341.856244 -410.336017) (xy 341.815054 -410.300323) (xy 341.779363 -410.25913)
			(xy 341.749898 -410.213277) (xy 341.727257 -410.163698) (xy 341.711902 -410.111402) (xy 341.704146 -410.057452)
			(xy 340.266489 -410.057452) (xy 340.258735 -410.111388) (xy 340.243382 -410.163676) (xy 340.220745 -410.213248)
			(xy 340.191284 -410.259093) (xy 340.155599 -410.300279) (xy 340.114415 -410.335967) (xy 340.068572 -410.365432)
			(xy 340.019003 -410.388073) (xy 339.966716 -410.403429) (xy 339.912776 -410.411188) (xy 339.885528 -410.411676)
			(xy 339.021928 -410.411676) (xy 338.994672 -410.411279) (xy 338.940713 -410.403525) (xy 338.888407 -410.38817)
			(xy 338.838819 -410.365527) (xy 338.792959 -410.336057) (xy 338.751759 -410.30036) (xy 338.71606 -410.259164)
			(xy 338.686587 -410.213305) (xy 338.66394 -410.163719) (xy 338.648581 -410.111414) (xy 338.640823 -410.057456)
			(xy 337.203312 -410.057456) (xy 337.195556 -410.111399) (xy 337.180201 -410.163693) (xy 337.157559 -410.21327)
			(xy 337.128093 -410.25912) (xy 337.092401 -410.300309) (xy 337.05121 -410.336) (xy 337.005359 -410.365465)
			(xy 336.955782 -410.388105) (xy 336.903487 -410.403459) (xy 336.849539 -410.411214) (xy 336.822288 -410.411676)
			(xy 335.958688 -410.411676) (xy 335.931435 -410.411253) (xy 335.877484 -410.403495) (xy 335.825186 -410.388137)
			(xy 335.775607 -410.365494) (xy 335.729754 -410.336025) (xy 335.688562 -410.30033) (xy 335.652868 -410.259137)
			(xy 335.623401 -410.213283) (xy 335.600758 -410.163702) (xy 335.585403 -410.111404) (xy 335.577646 -410.057453)
			(xy 334.139989 -410.057453) (xy 334.132235 -410.111386) (xy 334.116884 -410.163672) (xy 334.094248 -410.213242)
			(xy 334.064789 -410.259086) (xy 334.029106 -410.300272) (xy 333.987925 -410.33596) (xy 333.942084 -410.365425)
			(xy 333.892517 -410.388067) (xy 333.840233 -410.403425) (xy 333.786295 -410.411187) (xy 333.759048 -410.411676)
			(xy 332.895448 -410.411676) (xy 332.868191 -410.41128) (xy 332.81423 -410.403528) (xy 332.761922 -410.388175)
			(xy 332.712331 -410.365533) (xy 332.666468 -410.336064) (xy 332.625266 -410.300367) (xy 332.589565 -410.25917)
			(xy 332.56009 -410.213311) (xy 332.537442 -410.163723) (xy 332.522082 -410.111417) (xy 332.514323 -410.057457)
			(xy 331.076789 -410.057457) (xy 331.069034 -410.111391) (xy 331.053681 -410.163681) (xy 331.031042 -410.213253)
			(xy 331.001579 -410.259099) (xy 330.965891 -410.300286) (xy 330.924706 -410.335974) (xy 330.87886 -410.365438)
			(xy 330.829288 -410.388078) (xy 330.776999 -410.403432) (xy 330.723057 -410.411189) (xy 330.695808 -410.411676)
			(xy 329.832208 -410.411676) (xy 329.804952 -410.411278) (xy 329.750996 -410.403521) (xy 329.698693 -410.388164)
			(xy 329.649107 -410.36552) (xy 329.603249 -410.33605) (xy 329.562052 -410.300353) (xy 329.526355 -410.259157)
			(xy 329.496884 -410.2133) (xy 329.474239 -410.163715) (xy 329.458881 -410.111412) (xy 329.451123 -410.057456)
			(xy 328.013612 -410.057456) (xy 328.005855 -410.111401) (xy 327.990499 -410.163697) (xy 327.967856 -410.213275)
			(xy 327.938388 -410.259126) (xy 327.902694 -410.300316) (xy 327.861501 -410.336007) (xy 327.815647 -410.365472)
			(xy 327.766067 -410.38811) (xy 327.71377 -410.403462) (xy 327.65982 -410.411215) (xy 327.632568 -410.411676)
			(xy 326.768968 -410.411676) (xy 326.741716 -410.411252) (xy 326.687767 -410.403491) (xy 326.635472 -410.388132)
			(xy 326.585895 -410.365487) (xy 326.540044 -410.336017) (xy 326.498854 -410.300323) (xy 326.463163 -410.25913)
			(xy 326.433698 -410.213277) (xy 326.411057 -410.163698) (xy 326.395702 -410.111402) (xy 326.387946 -410.057452)
			(xy 324.950289 -410.057452) (xy 324.942535 -410.111388) (xy 324.927182 -410.163676) (xy 324.904545 -410.213248)
			(xy 324.875084 -410.259093) (xy 324.839399 -410.300279) (xy 324.798215 -410.335967) (xy 324.752372 -410.365432)
			(xy 324.702803 -410.388073) (xy 324.650516 -410.403429) (xy 324.596576 -410.411188) (xy 324.569328 -410.411676)
			(xy 323.705728 -410.411676) (xy 323.678472 -410.411279) (xy 323.624513 -410.403525) (xy 323.572207 -410.38817)
			(xy 323.522619 -410.365527) (xy 323.476759 -410.336057) (xy 323.435559 -410.30036) (xy 323.39986 -410.259164)
			(xy 323.370387 -410.213305) (xy 323.34774 -410.163719) (xy 323.332381 -410.111414) (xy 323.324623 -410.057456)
			(xy 321.887112 -410.057456) (xy 321.879356 -410.111399) (xy 321.864001 -410.163693) (xy 321.841359 -410.21327)
			(xy 321.811893 -410.25912) (xy 321.776201 -410.300309) (xy 321.73501 -410.336) (xy 321.689159 -410.365465)
			(xy 321.639582 -410.388105) (xy 321.587287 -410.403459) (xy 321.533339 -410.411214) (xy 321.506088 -410.411676)
			(xy 320.642488 -410.411676) (xy 320.615235 -410.411253) (xy 320.561284 -410.403495) (xy 320.508986 -410.388137)
			(xy 320.459407 -410.365494) (xy 320.413554 -410.336025) (xy 320.372362 -410.30033) (xy 320.336668 -410.259137)
			(xy 320.307201 -410.213283) (xy 320.284558 -410.163702) (xy 320.269203 -410.111404) (xy 320.261446 -410.057453)
			(xy 318.823789 -410.057453) (xy 318.816035 -410.111386) (xy 318.800684 -410.163672) (xy 318.778048 -410.213242)
			(xy 318.748589 -410.259086) (xy 318.712906 -410.300272) (xy 318.671725 -410.33596) (xy 318.625884 -410.365425)
			(xy 318.576317 -410.388067) (xy 318.524033 -410.403425) (xy 318.470095 -410.411187) (xy 318.442848 -410.411676)
			(xy 317.579248 -410.411676) (xy 317.551991 -410.41128) (xy 317.49803 -410.403528) (xy 317.445722 -410.388175)
			(xy 317.396131 -410.365533) (xy 317.350268 -410.336064) (xy 317.309066 -410.300367) (xy 317.273365 -410.25917)
			(xy 317.24389 -410.213311) (xy 317.221242 -410.163723) (xy 317.205882 -410.111417) (xy 317.198123 -410.057457)
			(xy 315.760589 -410.057457) (xy 315.752834 -410.111391) (xy 315.737481 -410.163681) (xy 315.714842 -410.213253)
			(xy 315.685379 -410.259099) (xy 315.649691 -410.300286) (xy 315.608506 -410.335974) (xy 315.56266 -410.365438)
			(xy 315.513088 -410.388078) (xy 315.460799 -410.403432) (xy 315.406857 -410.411189) (xy 315.379608 -410.411676)
			(xy 314.516008 -410.411676) (xy 314.488752 -410.411278) (xy 314.434796 -410.403521) (xy 314.382493 -410.388164)
			(xy 314.332907 -410.36552) (xy 314.287049 -410.33605) (xy 314.245852 -410.300353) (xy 314.210155 -410.259157)
			(xy 314.180684 -410.2133) (xy 314.158039 -410.163715) (xy 314.142681 -410.111412) (xy 314.134923 -410.057456)
			(xy 312.697412 -410.057456) (xy 312.689655 -410.111401) (xy 312.674299 -410.163697) (xy 312.651656 -410.213275)
			(xy 312.622188 -410.259126) (xy 312.586494 -410.300316) (xy 312.545301 -410.336007) (xy 312.499447 -410.365472)
			(xy 312.449867 -410.38811) (xy 312.39757 -410.403462) (xy 312.34362 -410.411215) (xy 312.316368 -410.411676)
			(xy 311.452768 -410.411676) (xy 311.425516 -410.411252) (xy 311.371567 -410.403491) (xy 311.319272 -410.388132)
			(xy 311.269695 -410.365487) (xy 311.223844 -410.336017) (xy 311.182654 -410.300323) (xy 311.146963 -410.25913)
			(xy 311.117498 -410.213277) (xy 311.094857 -410.163698) (xy 311.079502 -410.111402) (xy 311.071746 -410.057452)
			(xy 309.634089 -410.057452) (xy 309.626335 -410.111388) (xy 309.610982 -410.163676) (xy 309.588345 -410.213248)
			(xy 309.558884 -410.259093) (xy 309.523199 -410.300279) (xy 309.482015 -410.335967) (xy 309.436172 -410.365432)
			(xy 309.386603 -410.388073) (xy 309.334316 -410.403429) (xy 309.280376 -410.411188) (xy 309.253128 -410.411676)
			(xy 308.389528 -410.411676) (xy 308.362272 -410.411279) (xy 308.308313 -410.403525) (xy 308.256007 -410.38817)
			(xy 308.206419 -410.365527) (xy 308.160559 -410.336057) (xy 308.119359 -410.30036) (xy 308.08366 -410.259164)
			(xy 308.054187 -410.213305) (xy 308.03154 -410.163719) (xy 308.016181 -410.111414) (xy 308.008423 -410.057456)
			(xy 306.570912 -410.057456) (xy 306.563156 -410.111399) (xy 306.547801 -410.163693) (xy 306.525159 -410.21327)
			(xy 306.495693 -410.25912) (xy 306.460001 -410.300309) (xy 306.41881 -410.336) (xy 306.372959 -410.365465)
			(xy 306.323382 -410.388105) (xy 306.271087 -410.403459) (xy 306.217139 -410.411214) (xy 306.189888 -410.411676)
			(xy 305.326288 -410.411676) (xy 305.299035 -410.411253) (xy 305.245084 -410.403495) (xy 305.192786 -410.388137)
			(xy 305.143207 -410.365494) (xy 305.097354 -410.336025) (xy 305.056162 -410.30033) (xy 305.020468 -410.259137)
			(xy 304.991001 -410.213283) (xy 304.968358 -410.163702) (xy 304.953003 -410.111404) (xy 304.945246 -410.057453)
			(xy 280.83256 -410.057453) (xy 280.83256 -414.855152) (xy 292.492176 -414.855152) (xy 292.506654 -414.827974)
			(xy 292.519946 -414.803725) (xy 292.55246 -414.758997) (xy 292.591093 -414.719435) (xy 292.635037 -414.685868)
			(xy 292.683368 -414.659001) (xy 292.735073 -414.639397) (xy 292.789068 -414.627468) (xy 292.84422 -414.623464)
			(xy 292.899372 -414.627468) (xy 292.953367 -414.639397) (xy 293.005072 -414.659001) (xy 293.053403 -414.685868)
			(xy 293.097347 -414.719435) (xy 293.13598 -414.758997) (xy 293.168494 -414.803725) (xy 293.181786 -414.827974)
			(xy 293.196264 -414.855152) (xy 304.845466 -414.855152) (xy 304.858928 -414.82518) (xy 304.870632 -414.800489)
			(xy 304.900057 -414.754449) (xy 304.93575 -414.713077) (xy 304.97698 -414.677221) (xy 305.022904 -414.647615)
			(xy 305.072582 -414.624863) (xy 305.124998 -414.609431) (xy 305.17908 -414.601635) (xy 305.23372 -414.601635)
			(xy 305.287802 -414.609431) (xy 305.340218 -414.624863) (xy 305.389896 -414.647615) (xy 305.43582 -414.677221)
			(xy 305.47705 -414.713077) (xy 305.512743 -414.754449) (xy 305.542168 -414.800489) (xy 305.553872 -414.82518)
			(xy 305.567334 -414.855152) (xy 309.099712 -414.855152) (xy 309.124664 -414.855634) (xy 309.173957 -414.863427)
			(xy 309.221423 -414.878835) (xy 309.265895 -414.901478) (xy 309.306277 -414.930799) (xy 309.324248 -414.948116)
			(xy 310.508396 -416.132264) (xy 310.525678 -416.150264) (xy 310.554983 -416.190648) (xy 310.57762 -416.235114)
			(xy 310.593033 -416.28257) (xy 310.600843 -416.331852) (xy 310.60136 -416.3568) (xy 310.60136 -427.289976)
			(xy 314.138056 -427.289976) (xy 314.13817 -427.274891) (xy 314.139948 -427.244772) (xy 314.141612 -427.229778)
			(xy 314.141612 -426.150024) (xy 314.139943 -426.135031) (xy 314.138165 -426.104912) (xy 314.138056 -426.089826)
			(xy 314.138166 -426.07474) (xy 314.139947 -426.044622) (xy 314.141612 -426.029628) (xy 314.141612 -425.419012)
			(xy 314.142023 -425.406928) (xy 314.14949 -425.383942) (xy 314.163696 -425.36439) (xy 314.183249 -425.350186)
			(xy 314.206236 -425.342722) (xy 314.21832 -425.342304) (xy 315.15812 -425.342304) (xy 315.170197 -425.342748)
			(xy 315.193167 -425.350217) (xy 315.212704 -425.364419) (xy 315.226898 -425.383962) (xy 315.234357 -425.406935)
			(xy 315.234828 -425.419012) (xy 315.234828 -427.960536) (xy 315.234367 -427.97261) (xy 315.226897 -427.995576)
			(xy 315.212699 -428.01511) (xy 315.193161 -428.029304) (xy 315.170195 -428.036769) (xy 315.15812 -428.037244)
			(xy 314.21832 -428.037244) (xy 314.20625 -428.036719) (xy 314.18329 -428.029267) (xy 314.163755 -428.015085)
			(xy 314.149559 -427.995561) (xy 314.142089 -427.972606) (xy 314.141612 -427.960536) (xy 314.141612 -427.350174)
			(xy 314.139948 -427.33518) (xy 314.138166 -427.305062) (xy 314.138056 -427.289976) (xy 310.60136 -427.289976)
			(xy 310.60136 -428.28972) (xy 316.138052 -428.28972) (xy 316.138162 -428.274634) (xy 316.139943 -428.244516)
			(xy 316.141608 -428.229522) (xy 316.141608 -427.150022) (xy 316.139939 -427.135029) (xy 316.138161 -427.10491)
			(xy 316.138052 -427.089824) (xy 316.138162 -427.074738) (xy 316.139943 -427.04462) (xy 316.141608 -427.029626)
			(xy 316.141608 -426.41901) (xy 316.142115 -426.406924) (xy 316.149565 -426.383929) (xy 316.163743 -426.364352)
			(xy 316.183266 -426.3501) (xy 316.206232 -426.342562) (xy 316.218316 -426.342048) (xy 317.158116 -426.342048)
			(xy 317.170221 -426.342502) (xy 317.193239 -426.349999) (xy 317.212808 -426.364253) (xy 317.227004 -426.383863)
			(xy 317.234433 -426.406904) (xy 317.234824 -426.41901) (xy 317.234824 -427.289976) (xy 318.138048 -427.289976)
			(xy 318.138162 -427.274891) (xy 318.13994 -427.244772) (xy 318.141604 -427.229778) (xy 318.141604 -426.150024)
			(xy 318.139935 -426.135031) (xy 318.138157 -426.104912) (xy 318.138048 -426.089826) (xy 318.138158 -426.07474)
			(xy 318.139939 -426.044622) (xy 318.141604 -426.029628) (xy 318.141604 -425.419012) (xy 318.142023 -425.406929)
			(xy 318.149489 -425.383944) (xy 318.163693 -425.364393) (xy 318.183244 -425.350189) (xy 318.206229 -425.342723)
			(xy 318.218312 -425.342304) (xy 319.158112 -425.342304) (xy 319.170188 -425.342754) (xy 319.193158 -425.350222)
			(xy 319.212696 -425.364421) (xy 319.226889 -425.383964) (xy 319.234349 -425.406935) (xy 319.23482 -425.419012)
			(xy 319.23482 -427.960536) (xy 319.234367 -427.972611) (xy 319.226896 -427.995578) (xy 319.212696 -428.015113)
			(xy 319.193156 -428.029307) (xy 319.170187 -428.036771) (xy 319.158112 -428.037244) (xy 318.218312 -428.037244)
			(xy 318.206242 -428.036726) (xy 318.183281 -428.029271) (xy 318.163747 -428.015087) (xy 318.149551 -427.995562)
			(xy 318.142081 -427.972606) (xy 318.141604 -427.960536) (xy 318.141604 -427.350174) (xy 318.13994 -427.33518)
			(xy 318.138158 -427.305062) (xy 318.138048 -427.289976) (xy 317.234824 -427.289976) (xy 317.234824 -428.28972)
			(xy 320.138044 -428.28972) (xy 320.138154 -428.274634) (xy 320.139935 -428.244516) (xy 320.1416 -428.229522)
			(xy 320.1416 -427.150022) (xy 320.139931 -427.135029) (xy 320.138153 -427.10491) (xy 320.138044 -427.089824)
			(xy 320.138154 -427.074738) (xy 320.139935 -427.04462) (xy 320.1416 -427.029626) (xy 320.1416 -426.41901)
			(xy 320.142115 -426.406925) (xy 320.149564 -426.383931) (xy 320.16374 -426.364355) (xy 320.183261 -426.350103)
			(xy 320.206225 -426.342563) (xy 320.218308 -426.342048) (xy 321.158108 -426.342048) (xy 321.170212 -426.342509)
			(xy 321.193231 -426.350004) (xy 321.212799 -426.364256) (xy 321.226996 -426.383865) (xy 321.234425 -426.406905)
			(xy 321.234816 -426.41901) (xy 321.234816 -427.289976) (xy 322.13804 -427.289976) (xy 322.138155 -427.274891)
			(xy 322.139932 -427.244772) (xy 322.141596 -427.229778) (xy 322.141596 -426.150024) (xy 322.139927 -426.135031)
			(xy 322.138149 -426.104912) (xy 322.13804 -426.089826) (xy 322.13815 -426.07474) (xy 322.139931 -426.044622)
			(xy 322.141596 -426.029628) (xy 322.141596 -425.419012) (xy 322.142023 -425.40693) (xy 322.149488 -425.383947)
			(xy 322.16369 -425.364396) (xy 322.183239 -425.350191) (xy 322.206222 -425.342724) (xy 322.218304 -425.342304)
			(xy 323.158104 -425.342304) (xy 323.170188 -425.342709) (xy 323.193173 -425.350179) (xy 323.212724 -425.364387)
			(xy 323.226928 -425.383941) (xy 323.234393 -425.406928) (xy 323.234812 -425.419012) (xy 323.234812 -427.960536)
			(xy 323.234367 -427.972612) (xy 323.226895 -427.99558) (xy 323.212693 -428.015116) (xy 323.193151 -428.029309)
			(xy 323.17018 -428.036772) (xy 323.158104 -428.037244) (xy 322.218304 -428.037244) (xy 322.206233 -428.036733)
			(xy 322.183272 -428.029276) (xy 322.163738 -428.01509) (xy 322.149542 -427.995564) (xy 322.142073 -427.972607)
			(xy 322.141596 -427.960536) (xy 322.141596 -427.350174) (xy 322.139932 -427.33518) (xy 322.13815 -427.305062)
			(xy 322.13804 -427.289976) (xy 321.234816 -427.289976) (xy 321.234816 -428.28972) (xy 324.138036 -428.28972)
			(xy 324.138148 -428.274634) (xy 324.139929 -428.244516) (xy 324.141592 -428.229522) (xy 324.141592 -427.150022)
			(xy 324.139923 -427.135029) (xy 324.138145 -427.10491) (xy 324.138036 -427.089824) (xy 324.138148 -427.074738)
			(xy 324.139929 -427.04462) (xy 324.141592 -427.029626) (xy 324.141592 -426.41901) (xy 324.142115 -426.406926)
			(xy 324.149563 -426.383934) (xy 324.163737 -426.364358) (xy 324.183256 -426.350105) (xy 324.206218 -426.342564)
			(xy 324.2183 -426.342048) (xy 325.1581 -426.342048) (xy 325.170204 -426.342515) (xy 325.193222 -426.350009)
			(xy 325.212791 -426.364259) (xy 325.226987 -426.383866) (xy 325.234417 -426.406905) (xy 325.234808 -426.41901)
			(xy 325.234808 -427.289976) (xy 326.138032 -427.289976) (xy 326.138149 -427.274891) (xy 326.139927 -427.244772)
			(xy 326.141588 -427.229778) (xy 326.141588 -426.150024) (xy 326.139919 -426.135031) (xy 326.138141 -426.104912)
			(xy 326.138032 -426.089826) (xy 326.138144 -426.07474) (xy 326.139925 -426.044622) (xy 326.141588 -426.029628)
			(xy 326.141588 -425.419012) (xy 326.142023 -425.40693) (xy 326.149487 -425.383949) (xy 326.163687 -425.364399)
			(xy 326.183234 -425.350194) (xy 326.206214 -425.342726) (xy 326.218296 -425.342304) (xy 327.158096 -425.342304)
			(xy 327.17018 -425.342716) (xy 327.193164 -425.350184) (xy 327.212716 -425.36439) (xy 327.22692 -425.383943)
			(xy 327.234385 -425.406928) (xy 327.234804 -425.419012) (xy 327.234804 -427.960536) (xy 327.234367 -427.972613)
			(xy 327.226894 -427.995582) (xy 327.21269 -428.015119) (xy 327.193146 -428.029312) (xy 327.170173 -428.036773)
			(xy 327.158096 -428.037244) (xy 326.218296 -428.037244) (xy 326.206225 -428.03674) (xy 326.183264 -428.02928)
			(xy 326.16373 -428.015093) (xy 326.149534 -427.995565) (xy 326.142065 -427.972607) (xy 326.141588 -427.960536)
			(xy 326.141588 -427.350174) (xy 326.139924 -427.33518) (xy 326.138142 -427.305062) (xy 326.138032 -427.289976)
			(xy 325.234808 -427.289976) (xy 325.234808 -428.28972) (xy 328.138028 -428.28972) (xy 328.13814 -428.274634)
			(xy 328.139921 -428.244516) (xy 328.141584 -428.229522) (xy 328.141584 -427.150022) (xy 328.139915 -427.135029)
			(xy 328.138137 -427.10491) (xy 328.138028 -427.089824) (xy 328.13814 -427.074738) (xy 328.139921 -427.04462)
			(xy 328.141584 -427.029626) (xy 328.141584 -426.41901) (xy 328.142017 -426.406917) (xy 328.149476 -426.383909)
			(xy 328.16367 -426.364325) (xy 328.183214 -426.350076) (xy 328.2062 -426.342551) (xy 328.218292 -426.342048)
			(xy 329.158092 -426.342048) (xy 329.170195 -426.342522) (xy 329.193214 -426.350013) (xy 329.212782 -426.364262)
			(xy 329.226979 -426.383868) (xy 329.234409 -426.406906) (xy 329.2348 -426.41901) (xy 329.2348 -427.289976)
			(xy 331.138022 -427.289976) (xy 331.138113 -427.275402) (xy 331.139767 -427.246301) (xy 331.141324 -427.23181)
			(xy 331.141324 -426.147992) (xy 331.139781 -426.1335) (xy 331.138128 -426.1044) (xy 331.138022 -426.089826)
			(xy 331.138117 -426.075252) (xy 331.139769 -426.046151) (xy 331.141324 -426.03166) (xy 331.141324 -425.419012)
			(xy 331.141727 -425.406901) (xy 331.149226 -425.38387) (xy 331.16349 -425.364295) (xy 331.183116 -425.350101)
			(xy 331.206174 -425.342684) (xy 331.218286 -425.342304) (xy 332.158086 -425.342304) (xy 332.170171 -425.342819)
			(xy 332.193165 -425.350267) (xy 332.212742 -425.364443) (xy 332.226995 -425.383964) (xy 332.234533 -425.406929)
			(xy 332.235048 -425.419012) (xy 332.235048 -427.960536) (xy 332.234615 -427.972642) (xy 332.227111 -427.995662)
			(xy 332.212852 -428.01523) (xy 332.193238 -428.029426) (xy 332.170193 -428.036854) (xy 332.158086 -428.037244)
			(xy 331.218286 -428.037244) (xy 331.206194 -428.036804) (xy 331.18319 -428.029342) (xy 331.163609 -428.015149)
			(xy 331.14936 -427.995609) (xy 331.141831 -427.972627) (xy 331.141324 -427.960536) (xy 331.141324 -427.348142)
			(xy 331.139777 -427.33365) (xy 331.138127 -427.30455) (xy 331.138022 -427.289976) (xy 329.2348 -427.289976)
			(xy 329.2348 -428.28972) (xy 333.138018 -428.28972) (xy 333.138113 -428.275146) (xy 333.139764 -428.246045)
			(xy 333.14132 -428.231554) (xy 333.14132 -427.14799) (xy 333.139777 -427.133498) (xy 333.138124 -427.104398)
			(xy 333.138018 -427.089824) (xy 333.138113 -427.07525) (xy 333.139765 -427.046149) (xy 333.14132 -427.031658)
			(xy 333.14132 -426.41901) (xy 333.14182 -426.406898) (xy 333.149302 -426.383858) (xy 333.163538 -426.364258)
			(xy 333.183133 -426.350015) (xy 333.20617 -426.342525) (xy 333.218282 -426.342048) (xy 334.158082 -426.342048)
			(xy 334.170205 -426.342475) (xy 334.193265 -426.349964) (xy 334.212881 -426.364213) (xy 334.227132 -426.383828)
			(xy 334.234623 -426.406887) (xy 334.235044 -426.41901) (xy 334.235044 -427.289976) (xy 335.138014 -427.289976)
			(xy 335.138104 -427.275402) (xy 335.139759 -427.246301) (xy 335.141316 -427.23181) (xy 335.141316 -426.147992)
			(xy 335.139773 -426.1335) (xy 335.13812 -426.1044) (xy 335.138014 -426.089826) (xy 335.138109 -426.075252)
			(xy 335.13976 -426.046151) (xy 335.141316 -426.03166) (xy 335.141316 -425.419012) (xy 335.141727 -425.406902)
			(xy 335.149225 -425.383873) (xy 335.163487 -425.364298) (xy 335.183111 -425.350104) (xy 335.206167 -425.342685)
			(xy 335.218278 -425.342304) (xy 336.158078 -425.342304) (xy 336.170163 -425.342825) (xy 336.193157 -425.350272)
			(xy 336.212734 -425.364446) (xy 336.226986 -425.383966) (xy 336.234525 -425.406929) (xy 336.23504 -425.419012)
			(xy 336.23504 -427.960536) (xy 336.234615 -427.972643) (xy 336.22711 -427.995664) (xy 336.21285 -428.015233)
			(xy 336.193233 -428.029428) (xy 336.170186 -428.036855) (xy 336.158078 -428.037244) (xy 335.218278 -428.037244)
			(xy 335.206186 -428.036811) (xy 335.183182 -428.029347) (xy 335.163601 -428.015152) (xy 335.149351 -427.99561)
			(xy 335.141823 -427.972627) (xy 335.141316 -427.960536) (xy 335.141316 -427.348142) (xy 335.139769 -427.33365)
			(xy 335.138119 -427.30455) (xy 335.138014 -427.289976) (xy 334.235044 -427.289976) (xy 334.235044 -428.28972)
			(xy 337.13801 -428.28972) (xy 337.138104 -428.275146) (xy 337.139756 -428.246045) (xy 337.141312 -428.231554)
			(xy 337.141312 -427.14799) (xy 337.139769 -427.133498) (xy 337.138116 -427.104398) (xy 337.13801 -427.089824)
			(xy 337.138104 -427.07525) (xy 337.139756 -427.046149) (xy 337.141312 -427.031658) (xy 337.141312 -426.41901)
			(xy 337.14182 -426.406899) (xy 337.149301 -426.38386) (xy 337.163535 -426.36426) (xy 337.183128 -426.350018)
			(xy 337.206163 -426.342526) (xy 337.218274 -426.342048) (xy 338.158074 -426.342048) (xy 338.170196 -426.342482)
			(xy 338.193256 -426.349969) (xy 338.212872 -426.364216) (xy 338.227124 -426.38383) (xy 338.234615 -426.406888)
			(xy 338.235036 -426.41901) (xy 338.235036 -427.289976) (xy 339.138006 -427.289976) (xy 339.138096 -427.275402)
			(xy 339.139751 -427.246301) (xy 339.141308 -427.23181) (xy 339.141308 -426.147992) (xy 339.139765 -426.1335)
			(xy 339.138112 -426.1044) (xy 339.138006 -426.089826) (xy 339.138101 -426.075252) (xy 339.139752 -426.046151)
			(xy 339.141308 -426.03166) (xy 339.141308 -425.419012) (xy 339.141727 -425.406903) (xy 339.149224 -425.383875)
			(xy 339.163485 -425.364301) (xy 339.183106 -425.350106) (xy 339.20616 -425.342687) (xy 339.21827 -425.342304)
			(xy 340.15807 -425.342304) (xy 340.170154 -425.342832) (xy 340.193148 -425.350276) (xy 340.212725 -425.364448)
			(xy 340.226978 -425.383967) (xy 340.234517 -425.40693) (xy 340.235032 -425.419012) (xy 340.235032 -427.960536)
			(xy 340.234615 -427.972644) (xy 340.227109 -427.995667) (xy 340.212847 -428.015236) (xy 340.193228 -428.029431)
			(xy 340.170179 -428.036856) (xy 340.15807 -428.037244) (xy 339.21827 -428.037244) (xy 339.206177 -428.036818)
			(xy 339.183173 -428.029351) (xy 339.163592 -428.015154) (xy 339.149343 -427.995612) (xy 339.141815 -427.972627)
			(xy 339.141308 -427.960536) (xy 339.141308 -427.348142) (xy 339.139761 -427.33365) (xy 339.138111 -427.30455)
			(xy 339.138006 -427.289976) (xy 338.235036 -427.289976) (xy 338.235036 -428.28972) (xy 341.138002 -428.28972)
			(xy 341.138096 -428.275146) (xy 341.139748 -428.246045) (xy 341.141304 -428.231554) (xy 341.141304 -427.14799)
			(xy 341.139761 -427.133498) (xy 341.138108 -427.104398) (xy 341.138002 -427.089824) (xy 341.138096 -427.07525)
			(xy 341.139748 -427.046149) (xy 341.141304 -427.031658) (xy 341.141304 -426.41901) (xy 341.14182 -426.406899)
			(xy 341.1493 -426.383862) (xy 341.163532 -426.364263) (xy 341.183123 -426.35002) (xy 341.206156 -426.342527)
			(xy 341.218266 -426.342048) (xy 342.158066 -426.342048) (xy 342.170188 -426.342489) (xy 342.193247 -426.349973)
			(xy 342.212864 -426.364219) (xy 342.227116 -426.383831) (xy 342.234607 -426.406888) (xy 342.235028 -426.41901)
			(xy 342.235028 -427.289976) (xy 343.137998 -427.289976) (xy 343.138088 -427.275402) (xy 343.139743 -427.246301)
			(xy 343.1413 -427.23181) (xy 343.1413 -426.147992) (xy 343.139757 -426.1335) (xy 343.138104 -426.1044)
			(xy 343.137998 -426.089826) (xy 343.138093 -426.075252) (xy 343.139744 -426.046151) (xy 343.1413 -426.03166)
			(xy 343.1413 -425.419012) (xy 343.141727 -425.406904) (xy 343.149223 -425.383877) (xy 343.163482 -425.364304)
			(xy 343.183101 -425.350109) (xy 343.206152 -425.342688) (xy 343.218262 -425.342304) (xy 344.158062 -425.342304)
			(xy 344.170146 -425.342839) (xy 344.193139 -425.350281) (xy 344.212717 -425.364451) (xy 344.22697 -425.383968)
			(xy 344.234509 -425.40693) (xy 344.235024 -425.419012) (xy 344.235024 -427.960536) (xy 344.234615 -427.972644)
			(xy 344.227108 -427.995669) (xy 344.212844 -428.015239) (xy 344.193223 -428.029433) (xy 344.170172 -428.036857)
			(xy 344.158062 -428.037244) (xy 343.218262 -428.037244) (xy 343.206169 -428.036825) (xy 343.183164 -428.029356)
			(xy 343.163584 -428.015157) (xy 343.149335 -427.995613) (xy 343.141807 -427.972628) (xy 343.1413 -427.960536)
			(xy 343.1413 -427.348142) (xy 343.139753 -427.33365) (xy 343.138103 -427.30455) (xy 343.137998 -427.289976)
			(xy 342.235028 -427.289976) (xy 342.235028 -428.28972) (xy 345.137994 -428.28972) (xy 345.138088 -428.275146)
			(xy 345.13974 -428.246045) (xy 345.141296 -428.231554) (xy 345.141296 -427.14799) (xy 345.139753 -427.133498)
			(xy 345.1381 -427.104398) (xy 345.137994 -427.089824) (xy 345.138088 -427.07525) (xy 345.13974 -427.046149)
			(xy 345.141296 -427.031658) (xy 345.141296 -426.41901) (xy 345.14182 -426.4069) (xy 345.149299 -426.383864)
			(xy 345.163529 -426.364266) (xy 345.183118 -426.350023) (xy 345.206148 -426.342528) (xy 345.218258 -426.342048)
			(xy 346.158058 -426.342048) (xy 346.17018 -426.342496) (xy 346.193239 -426.349978) (xy 346.212855 -426.364222)
			(xy 346.227108 -426.383833) (xy 346.234599 -426.406889) (xy 346.23502 -426.41901) (xy 346.23502 -428.960534)
			(xy 346.234669 -428.972663) (xy 346.227162 -428.99573) (xy 346.212894 -429.015348) (xy 346.193262 -429.029597)
			(xy 346.170187 -429.03708) (xy 346.158058 -429.037496) (xy 345.218258 -429.037496) (xy 345.206145 -429.037025)
			(xy 345.183106 -429.02953) (xy 345.163508 -429.015287) (xy 345.149266 -428.995687) (xy 345.141774 -428.972647)
			(xy 345.141296 -428.960534) (xy 345.141296 -428.347886) (xy 345.139753 -428.333394) (xy 345.1381 -428.304294)
			(xy 345.137994 -428.28972) (xy 342.235028 -428.28972) (xy 342.235028 -428.960534) (xy 342.234617 -428.972654)
			(xy 342.227116 -428.995704) (xy 342.21286 -429.015308) (xy 342.193243 -429.029547) (xy 342.170186 -429.037027)
			(xy 342.158066 -429.037496) (xy 341.218266 -429.037496) (xy 341.206153 -429.037018) (xy 341.183114 -429.029525)
			(xy 341.163516 -429.015284) (xy 341.149275 -428.995686) (xy 341.141782 -428.972647) (xy 341.141304 -428.960534)
			(xy 341.141304 -428.347886) (xy 341.139761 -428.333394) (xy 341.138108 -428.304294) (xy 341.138002 -428.28972)
			(xy 338.235036 -428.28972) (xy 338.235036 -428.960534) (xy 338.234617 -428.972653) (xy 338.227117 -428.995702)
			(xy 338.212862 -429.015305) (xy 338.193248 -429.029545) (xy 338.170193 -429.037026) (xy 338.158074 -429.037496)
			(xy 337.218274 -429.037496) (xy 337.206161 -429.037011) (xy 337.183123 -429.029521) (xy 337.163525 -429.015281)
			(xy 337.149283 -428.995684) (xy 337.14179 -428.972646) (xy 337.141312 -428.960534) (xy 337.141312 -428.347886)
			(xy 337.139769 -428.333394) (xy 337.138116 -428.304294) (xy 337.13801 -428.28972) (xy 334.235044 -428.28972)
			(xy 334.235044 -428.960534) (xy 334.234617 -428.972652) (xy 334.227118 -428.9957) (xy 334.212865 -429.015302)
			(xy 334.193253 -429.029542) (xy 334.1702 -429.037025) (xy 334.158082 -429.037496) (xy 333.218282 -429.037496)
			(xy 333.20617 -429.037004) (xy 333.183132 -429.029516) (xy 333.163533 -429.015278) (xy 333.149291 -428.995683)
			(xy 333.141798 -428.972646) (xy 333.14132 -428.960534) (xy 333.14132 -428.347886) (xy 333.139777 -428.333394)
			(xy 333.138124 -428.304294) (xy 333.138018 -428.28972) (xy 329.2348 -428.28972) (xy 329.2348 -428.960534)
			(xy 329.234322 -428.972621) (xy 329.226861 -428.995616) (xy 329.212676 -429.015192) (xy 329.193148 -429.029443)
			(xy 329.170178 -429.036981) (xy 329.158092 -429.037496) (xy 328.218292 -429.037496) (xy 328.206182 -429.037091)
			(xy 328.183154 -429.029588) (xy 328.163581 -429.015324) (xy 328.149386 -428.9957) (xy 328.141967 -428.972645)
			(xy 328.141584 -428.960534) (xy 328.141584 -428.349918) (xy 328.139915 -428.334925) (xy 328.138137 -428.304806)
			(xy 328.138028 -428.28972) (xy 325.234808 -428.28972) (xy 325.234808 -428.960534) (xy 325.234323 -428.972621)
			(xy 325.226862 -428.995614) (xy 325.212679 -429.01519) (xy 325.193153 -429.029441) (xy 325.170185 -429.03698)
			(xy 325.1581 -429.037496) (xy 324.2183 -429.037496) (xy 324.206191 -429.037084) (xy 324.183163 -429.029584)
			(xy 324.163589 -429.015321) (xy 324.149395 -428.995699) (xy 324.141975 -428.972645) (xy 324.141592 -428.960534)
			(xy 324.141592 -428.349918) (xy 324.139923 -428.334925) (xy 324.138145 -428.304806) (xy 324.138036 -428.28972)
			(xy 321.234816 -428.28972) (xy 321.234816 -428.960534) (xy 321.234421 -428.97263) (xy 321.226949 -428.995639)
			(xy 321.212746 -429.015222) (xy 321.193195 -429.02947) (xy 321.170203 -429.036993) (xy 321.158108 -429.037496)
			(xy 320.218308 -429.037496) (xy 320.206199 -429.037077) (xy 320.183171 -429.029579) (xy 320.163598 -429.015319)
			(xy 320.149403 -428.995697) (xy 320.141983 -428.972644) (xy 320.1416 -428.960534) (xy 320.1416 -428.349918)
			(xy 320.139931 -428.334925) (xy 320.138153 -428.304806) (xy 320.138044 -428.28972) (xy 317.234824 -428.28972)
			(xy 317.234824 -428.960534) (xy 317.234421 -428.972629) (xy 317.226951 -428.995637) (xy 317.212749 -429.015219)
			(xy 317.1932 -429.029467) (xy 317.17021 -429.036992) (xy 317.158116 -429.037496) (xy 316.218316 -429.037496)
			(xy 316.206208 -429.03707) (xy 316.18318 -429.029574) (xy 316.163607 -429.015315) (xy 316.149412 -428.995695)
			(xy 316.141991 -428.972644) (xy 316.141608 -428.960534) (xy 316.141608 -428.349918) (xy 316.139939 -428.334925)
			(xy 316.138161 -428.304806) (xy 316.138052 -428.28972) (xy 310.60136 -428.28972) (xy 310.60136 -430.889918)
			(xy 314.138056 -430.889918) (xy 314.138165 -430.874832) (xy 314.139947 -430.844714) (xy 314.141612 -430.82972)
			(xy 314.141612 -429.749966) (xy 314.139947 -429.734972) (xy 314.138166 -429.704854) (xy 314.138056 -429.689768)
			(xy 314.13817 -429.674682) (xy 314.139948 -429.644564) (xy 314.141612 -429.62957) (xy 314.141612 -429.018954)
			(xy 314.142068 -429.006865) (xy 314.149534 -428.983867) (xy 314.163724 -428.964291) (xy 314.183258 -428.950041)
			(xy 314.206232 -428.942505) (xy 314.21832 -428.941992) (xy 315.15812 -428.941992) (xy 315.170229 -428.942399)
			(xy 315.193256 -428.949903) (xy 315.212828 -428.964167) (xy 315.227022 -428.98379) (xy 315.234444 -429.006843)
			(xy 315.234828 -429.018954) (xy 315.234828 -431.560478) (xy 315.234373 -431.57257) (xy 315.226919 -431.595575)
			(xy 315.21273 -431.615158) (xy 315.193192 -431.629408) (xy 315.17021 -431.636935) (xy 315.15812 -431.63744)
			(xy 314.21832 -431.63744) (xy 314.206216 -431.636967) (xy 314.183196 -431.629478) (xy 314.163627 -431.61523)
			(xy 314.14943 -431.595622) (xy 314.142001 -431.572583) (xy 314.141612 -431.560478) (xy 314.141612 -430.950116)
			(xy 314.139943 -430.935123) (xy 314.138165 -430.905004) (xy 314.138056 -430.889918) (xy 310.60136 -430.889918)
			(xy 310.60136 -431.889916) (xy 316.138052 -431.889916) (xy 316.138161 -431.87483) (xy 316.139943 -431.844712)
			(xy 316.141608 -431.829718) (xy 316.141608 -430.749964) (xy 316.139943 -430.73497) (xy 316.138162 -430.704852)
			(xy 316.138052 -430.689766) (xy 316.138166 -430.67468) (xy 316.139944 -430.644562) (xy 316.141608 -430.629568)
			(xy 316.141608 -430.018952) (xy 316.142023 -430.006873) (xy 316.149501 -429.983902) (xy 316.16371 -429.964364)
			(xy 316.183259 -429.950172) (xy 316.206237 -429.942713) (xy 316.218316 -429.942244) (xy 317.158116 -429.942244)
			(xy 317.170187 -429.94275) (xy 317.193146 -429.950211) (xy 317.212679 -429.964399) (xy 317.226874 -429.983925)
			(xy 317.234345 -430.006882) (xy 317.234824 -430.018952) (xy 317.234824 -430.889918) (xy 318.138048 -430.889918)
			(xy 318.138157 -430.874832) (xy 318.139939 -430.844714) (xy 318.141604 -430.82972) (xy 318.141604 -429.749966)
			(xy 318.139939 -429.734972) (xy 318.138158 -429.704854) (xy 318.138048 -429.689768) (xy 318.138162 -429.674682)
			(xy 318.13994 -429.644564) (xy 318.141604 -429.62957) (xy 318.141604 -429.018954) (xy 318.142067 -429.006866)
			(xy 318.149532 -428.98387) (xy 318.163721 -428.964293) (xy 318.183253 -428.950043) (xy 318.206225 -428.942506)
			(xy 318.218312 -428.941992) (xy 319.158112 -428.941992) (xy 319.170221 -428.942406) (xy 319.193247 -428.949908)
			(xy 319.212819 -428.96417) (xy 319.227014 -428.983792) (xy 319.234436 -429.006844) (xy 319.23482 -429.018954)
			(xy 319.23482 -431.560478) (xy 319.234373 -431.57257) (xy 319.226918 -431.595577) (xy 319.212727 -431.615161)
			(xy 319.193187 -431.629411) (xy 319.170203 -431.636936) (xy 319.158112 -431.63744) (xy 318.218312 -431.63744)
			(xy 318.206208 -431.636974) (xy 318.183188 -431.629483) (xy 318.163618 -431.615232) (xy 318.149422 -431.595624)
			(xy 318.141993 -431.572583) (xy 318.141604 -431.560478) (xy 318.141604 -430.950116) (xy 318.139935 -430.935123)
			(xy 318.138157 -430.905004) (xy 318.138048 -430.889918) (xy 317.234824 -430.889918) (xy 317.234824 -431.889916)
			(xy 320.138044 -431.889916) (xy 320.138153 -431.87483) (xy 320.139935 -431.844712) (xy 320.1416 -431.829718)
			(xy 320.1416 -430.749964) (xy 320.139935 -430.73497) (xy 320.138154 -430.704852) (xy 320.138044 -430.689766)
			(xy 320.138158 -430.67468) (xy 320.139936 -430.644562) (xy 320.1416 -430.629568) (xy 320.1416 -430.018952)
			(xy 320.142023 -430.006874) (xy 320.1495 -429.983904) (xy 320.163707 -429.964367) (xy 320.183254 -429.950174)
			(xy 320.20623 -429.942714) (xy 320.218308 -429.942244) (xy 321.158108 -429.942244) (xy 321.170178 -429.942757)
			(xy 321.193137 -429.950216) (xy 321.21267 -429.964401) (xy 321.226866 -429.983927) (xy 321.234337 -430.006882)
			(xy 321.234816 -430.018952) (xy 321.234816 -430.889918) (xy 322.13804 -430.889918) (xy 322.138151 -430.874832)
			(xy 322.139933 -430.844714) (xy 322.141596 -430.82972) (xy 322.141596 -429.749966) (xy 322.139931 -429.734972)
			(xy 322.13815 -429.704854) (xy 322.13804 -429.689768) (xy 322.138154 -429.674682) (xy 322.139932 -429.644564)
			(xy 322.141596 -429.62957) (xy 322.141596 -429.018954) (xy 322.142067 -429.006866) (xy 322.149531 -428.983872)
			(xy 322.163718 -428.964296) (xy 322.183248 -428.950046) (xy 322.206218 -428.942507) (xy 322.218304 -428.941992)
			(xy 323.158104 -428.941992) (xy 323.170212 -428.942413) (xy 323.193238 -428.949912) (xy 323.212811 -428.964173)
			(xy 323.227006 -428.983793) (xy 323.234428 -429.006844) (xy 323.234812 -429.018954) (xy 323.234812 -431.560478)
			(xy 323.234373 -431.572571) (xy 323.226916 -431.595579) (xy 323.212724 -431.615164) (xy 323.193182 -431.629413)
			(xy 323.170196 -431.636937) (xy 323.158104 -431.63744) (xy 322.218304 -431.63744) (xy 322.206199 -431.636981)
			(xy 322.183179 -431.629488) (xy 322.163609 -431.615236) (xy 322.149413 -431.595625) (xy 322.141985 -431.572584)
			(xy 322.141596 -431.560478) (xy 322.141596 -430.950116) (xy 322.139927 -430.935123) (xy 322.138149 -430.905004)
			(xy 322.13804 -430.889918) (xy 321.234816 -430.889918) (xy 321.234816 -431.889916) (xy 324.138036 -431.889916)
			(xy 324.138147 -431.87483) (xy 324.139929 -431.844712) (xy 324.141592 -431.829718) (xy 324.141592 -430.749964)
			(xy 324.139927 -430.73497) (xy 324.138146 -430.704852) (xy 324.138036 -430.689766) (xy 324.138152 -430.674681)
			(xy 324.13993 -430.644562) (xy 324.141592 -430.629568) (xy 324.141592 -430.018952) (xy 324.142023 -430.006875)
			(xy 324.149499 -429.983906) (xy 324.163704 -429.96437) (xy 324.183249 -429.950177) (xy 324.206223 -429.942716)
			(xy 324.2183 -429.942244) (xy 325.1581 -429.942244) (xy 325.17017 -429.942764) (xy 325.193129 -429.95022)
			(xy 325.212662 -429.964404) (xy 325.226858 -429.983928) (xy 325.234329 -430.006883) (xy 325.234808 -430.018952)
			(xy 325.234808 -430.889918) (xy 326.138032 -430.889918) (xy 326.138143 -430.874832) (xy 326.139925 -430.844714)
			(xy 326.141588 -430.82972) (xy 326.141588 -429.749966) (xy 326.139923 -429.734972) (xy 326.138142 -429.704854)
			(xy 326.138032 -429.689768) (xy 326.138148 -429.674683) (xy 326.139926 -429.644564) (xy 326.141588 -429.62957)
			(xy 326.141588 -429.018954) (xy 326.141969 -429.006857) (xy 326.149444 -428.983847) (xy 326.163651 -428.964264)
			(xy 326.183205 -428.950016) (xy 326.2062 -428.942494) (xy 326.218296 -428.941992) (xy 327.158096 -428.941992)
			(xy 327.170204 -428.942419) (xy 327.19323 -428.949917) (xy 327.212802 -428.964176) (xy 327.226997 -428.983795)
			(xy 327.23442 -429.006845) (xy 327.234804 -429.018954) (xy 327.234804 -431.560478) (xy 327.234275 -431.572562)
			(xy 327.226829 -431.595555) (xy 327.212657 -431.615131) (xy 327.19314 -431.629384) (xy 327.170178 -431.636924)
			(xy 327.158096 -431.63744) (xy 326.218296 -431.63744) (xy 326.206191 -431.636988) (xy 326.18317 -431.629492)
			(xy 326.163601 -431.615238) (xy 326.149405 -431.595627) (xy 326.141977 -431.572584) (xy 326.141588 -431.560478)
			(xy 326.141588 -430.950116) (xy 326.139919 -430.935123) (xy 326.138141 -430.905004) (xy 326.138032 -430.889918)
			(xy 325.234808 -430.889918) (xy 325.234808 -431.889916) (xy 328.138028 -431.889916) (xy 328.138139 -431.87483)
			(xy 328.139921 -431.844712) (xy 328.141584 -431.829718) (xy 328.141584 -430.749964) (xy 328.139919 -430.73497)
			(xy 328.138138 -430.704852) (xy 328.138028 -430.689766) (xy 328.138144 -430.674681) (xy 328.139922 -430.644562)
			(xy 328.141584 -430.629568) (xy 328.141584 -430.018952) (xy 328.142023 -430.006876) (xy 328.149498 -429.983908)
			(xy 328.163701 -429.964373) (xy 328.183244 -429.95018) (xy 328.206215 -429.942717) (xy 328.218292 -429.942244)
			(xy 329.158092 -429.942244) (xy 329.170161 -429.94277) (xy 329.19312 -429.950225) (xy 329.212653 -429.964407)
			(xy 329.22685 -429.98393) (xy 329.234321 -430.006883) (xy 329.2348 -430.018952) (xy 329.2348 -430.889918)
			(xy 331.138022 -430.889918) (xy 331.138116 -430.875344) (xy 331.139768 -430.846243) (xy 331.141324 -430.831752)
			(xy 331.141324 -429.747934) (xy 331.139776 -429.733442) (xy 331.138126 -429.704342) (xy 331.138022 -429.689768)
			(xy 331.138121 -429.675194) (xy 331.13977 -429.646093) (xy 331.141324 -429.631602) (xy 331.141324 -429.018954)
			(xy 331.141772 -429.006838) (xy 331.14927 -428.983796) (xy 331.163519 -428.964196) (xy 331.183125 -428.949956)
			(xy 331.20617 -428.942467) (xy 331.218286 -428.941992) (xy 332.158086 -428.941992) (xy 332.170195 -428.942523)
			(xy 332.19323 -428.950001) (xy 332.212828 -428.964229) (xy 332.227072 -428.983816) (xy 332.234568 -429.006845)
			(xy 332.235048 -429.018954) (xy 332.235048 -431.560478) (xy 332.234621 -431.572601) (xy 332.227133 -431.595662)
			(xy 332.212884 -431.615278) (xy 332.193269 -431.62953) (xy 332.170209 -431.63702) (xy 332.158086 -431.63744)
			(xy 331.218286 -431.63744) (xy 331.20616 -431.637051) (xy 331.183097 -431.629553) (xy 331.163481 -431.615294)
			(xy 331.149231 -431.59567) (xy 331.141743 -431.572604) (xy 331.141324 -431.560478) (xy 331.141324 -430.948084)
			(xy 331.139781 -430.933592) (xy 331.138128 -430.904492) (xy 331.138022 -430.889918) (xy 329.2348 -430.889918)
			(xy 329.2348 -431.889916) (xy 333.138018 -431.889916) (xy 333.138112 -431.875342) (xy 333.139764 -431.846241)
			(xy 333.14132 -431.83175) (xy 333.14132 -430.747932) (xy 333.139772 -430.73344) (xy 333.138122 -430.70434)
			(xy 333.138018 -430.689766) (xy 333.138117 -430.675192) (xy 333.139766 -430.646091) (xy 333.14132 -430.6316)
			(xy 333.14132 -430.018952) (xy 333.141676 -430.006839) (xy 333.149191 -429.983806) (xy 333.163467 -429.964232)
			(xy 333.183103 -429.95004) (xy 333.206167 -429.942624) (xy 333.218282 -429.942244) (xy 334.158082 -429.942244)
			(xy 334.170171 -429.942723) (xy 334.193172 -429.950175) (xy 334.212752 -429.964358) (xy 334.227003 -429.98389)
			(xy 334.234535 -430.006865) (xy 334.235044 -430.018952) (xy 334.235044 -430.889918) (xy 335.138014 -430.889918)
			(xy 335.138108 -430.875344) (xy 335.13976 -430.846243) (xy 335.141316 -430.831752) (xy 335.141316 -429.747934)
			(xy 335.139768 -429.733442) (xy 335.138118 -429.704342) (xy 335.138014 -429.689768) (xy 335.138112 -429.675194)
			(xy 335.139762 -429.646093) (xy 335.141316 -429.631602) (xy 335.141316 -429.018954) (xy 335.141772 -429.006839)
			(xy 335.149269 -428.983798) (xy 335.163516 -428.964199) (xy 335.18312 -428.949958) (xy 335.206163 -428.942468)
			(xy 335.218278 -428.941992) (xy 336.158078 -428.941992) (xy 336.170187 -428.94253) (xy 336.193222 -428.950005)
			(xy 336.21282 -428.964232) (xy 336.227064 -428.983817) (xy 336.234559 -429.006846) (xy 336.23504 -429.018954)
			(xy 336.23504 -431.560478) (xy 336.234621 -431.572602) (xy 336.227132 -431.595664) (xy 336.212881 -431.615281)
			(xy 336.193264 -431.629532) (xy 336.170202 -431.637021) (xy 336.158078 -431.63744) (xy 335.218278 -431.63744)
			(xy 335.20616 -431.637007) (xy 335.183112 -431.629511) (xy 335.163509 -431.61526) (xy 335.149269 -431.595648)
			(xy 335.141786 -431.572596) (xy 335.141316 -431.560478) (xy 335.141316 -430.948084) (xy 335.139773 -430.933592)
			(xy 335.13812 -430.904492) (xy 335.138014 -430.889918) (xy 334.235044 -430.889918) (xy 334.235044 -431.889916)
			(xy 337.13801 -431.889916) (xy 337.138104 -431.875342) (xy 337.139756 -431.846241) (xy 337.141312 -431.83175)
			(xy 337.141312 -430.747932) (xy 337.139764 -430.73344) (xy 337.138114 -430.70434) (xy 337.13801 -430.689766)
			(xy 337.138108 -430.675192) (xy 337.139757 -430.646091) (xy 337.141312 -430.6316) (xy 337.141312 -430.018952)
			(xy 337.141676 -430.006839) (xy 337.14919 -429.983809) (xy 337.163465 -429.964235) (xy 337.183098 -429.950043)
			(xy 337.20616 -429.942625) (xy 337.218274 -429.942244) (xy 338.158074 -429.942244) (xy 338.170163 -429.94273)
			(xy 338.193163 -429.95018) (xy 338.212744 -429.964361) (xy 338.226995 -429.983891) (xy 338.234527 -430.006865)
			(xy 338.235036 -430.018952) (xy 338.235036 -430.889918) (xy 339.138006 -430.889918) (xy 339.1381 -430.875344)
			(xy 339.139752 -430.846243) (xy 339.141308 -430.831752) (xy 339.141308 -429.747934) (xy 339.13976 -429.733442)
			(xy 339.13811 -429.704342) (xy 339.138006 -429.689768) (xy 339.138104 -429.675194) (xy 339.139754 -429.646093)
			(xy 339.141308 -429.631602) (xy 339.141308 -429.018954) (xy 339.141772 -429.00684) (xy 339.149268 -428.9838)
			(xy 339.163513 -428.964202) (xy 339.183115 -428.949961) (xy 339.206156 -428.94247) (xy 339.21827 -428.941992)
			(xy 340.15807 -428.941992) (xy 340.170178 -428.942537) (xy 340.193213 -428.95001) (xy 340.212811 -428.964235)
			(xy 340.227055 -428.983819) (xy 340.234551 -429.006846) (xy 340.235032 -429.018954) (xy 340.235032 -431.560478)
			(xy 340.234621 -431.572603) (xy 340.227131 -431.595666) (xy 340.212878 -431.615284) (xy 340.193259 -431.629535)
			(xy 340.170195 -431.637022) (xy 340.15807 -431.63744) (xy 339.21827 -431.63744) (xy 339.206152 -431.637014)
			(xy 339.183104 -431.629515) (xy 339.163501 -431.615262) (xy 339.149261 -431.59565) (xy 339.141778 -431.572597)
			(xy 339.141308 -431.560478) (xy 339.141308 -430.948084) (xy 339.139764 -430.933592) (xy 339.138112 -430.904492)
			(xy 339.138006 -430.889918) (xy 338.235036 -430.889918) (xy 338.235036 -431.889916) (xy 341.138002 -431.889916)
			(xy 341.138096 -431.875342) (xy 341.139748 -431.846241) (xy 341.141304 -431.83175) (xy 341.141304 -430.747932)
			(xy 341.139756 -430.73344) (xy 341.138106 -430.70434) (xy 341.138002 -430.689766) (xy 341.1381 -430.675192)
			(xy 341.13975 -430.646091) (xy 341.141304 -430.6316) (xy 341.141304 -430.018952) (xy 341.141676 -430.00684)
			(xy 341.149189 -429.983811) (xy 341.163462 -429.964238) (xy 341.183093 -429.950045) (xy 341.206153 -429.942626)
			(xy 341.218266 -429.942244) (xy 342.158066 -429.942244) (xy 342.170154 -429.942736) (xy 342.193154 -429.950184)
			(xy 342.212735 -429.964364) (xy 342.226987 -429.983893) (xy 342.234519 -430.006866) (xy 342.235028 -430.018952)
			(xy 342.235028 -430.889918) (xy 343.137998 -430.889918) (xy 343.138092 -430.875344) (xy 343.139744 -430.846243)
			(xy 343.1413 -430.831752) (xy 343.1413 -429.747934) (xy 343.139752 -429.733442) (xy 343.138102 -429.704342)
			(xy 343.137998 -429.689768) (xy 343.138096 -429.675194) (xy 343.139746 -429.646093) (xy 343.1413 -429.631602)
			(xy 343.1413 -429.018954) (xy 343.141772 -429.006841) (xy 343.149267 -428.983803) (xy 343.163511 -428.964205)
			(xy 343.18311 -428.949964) (xy 343.206149 -428.942471) (xy 343.218262 -428.941992) (xy 344.158062 -428.941992)
			(xy 344.17017 -428.942543) (xy 344.193204 -428.950015) (xy 344.212803 -428.964238) (xy 344.227047 -428.98382)
			(xy 344.234543 -429.006847) (xy 344.235024 -429.018954) (xy 344.235024 -431.560478) (xy 344.234621 -431.572603)
			(xy 344.22713 -431.595668) (xy 344.212875 -431.615287) (xy 344.193254 -431.629537) (xy 344.170187 -431.637023)
			(xy 344.158062 -431.63744) (xy 343.218262 -431.63744) (xy 343.206143 -431.63702) (xy 343.183095 -431.62952)
			(xy 343.163492 -431.615265) (xy 343.149253 -431.595651) (xy 343.14177 -431.572597) (xy 343.1413 -431.560478)
			(xy 343.1413 -430.948084) (xy 343.139756 -430.933592) (xy 343.138104 -430.904492) (xy 343.137998 -430.889918)
			(xy 342.235028 -430.889918) (xy 342.235028 -431.889916) (xy 345.137994 -431.889916) (xy 345.138088 -431.875342)
			(xy 345.13974 -431.846241) (xy 345.141296 -431.83175) (xy 345.141296 -430.747932) (xy 345.139748 -430.73344)
			(xy 345.138098 -430.70434) (xy 345.137994 -430.689766) (xy 345.138092 -430.675192) (xy 345.139742 -430.646091)
			(xy 345.141296 -430.6316) (xy 345.141296 -430.018952) (xy 345.141676 -430.006841) (xy 345.149188 -429.983813)
			(xy 345.163459 -429.964241) (xy 345.183088 -429.950048) (xy 345.206145 -429.942628) (xy 345.218258 -429.942244)
			(xy 346.158058 -429.942244) (xy 346.170146 -429.942743) (xy 346.193146 -429.950189) (xy 346.212727 -429.964367)
			(xy 346.226979 -429.983894) (xy 346.234511 -430.006866) (xy 346.23502 -430.018952) (xy 346.23502 -432.560476)
			(xy 346.234563 -432.572582) (xy 346.227073 -432.595605) (xy 346.212821 -432.615176) (xy 346.193209 -432.629373)
			(xy 346.170165 -432.636797) (xy 346.158058 -432.637184) (xy 345.218258 -432.637184) (xy 345.206169 -432.636729)
			(xy 345.183171 -432.629264) (xy 345.163593 -432.615073) (xy 345.149343 -432.595539) (xy 345.141808 -432.572564)
			(xy 345.141296 -432.560476) (xy 345.141296 -431.948082) (xy 345.139753 -431.93359) (xy 345.1381 -431.90449)
			(xy 345.137994 -431.889916) (xy 342.235028 -431.889916) (xy 342.235028 -432.560476) (xy 342.234563 -432.572581)
			(xy 342.227074 -432.595602) (xy 342.212824 -432.615174) (xy 342.193214 -432.62937) (xy 342.170172 -432.636796)
			(xy 342.158066 -432.637184) (xy 341.218266 -432.637184) (xy 341.206177 -432.636722) (xy 341.183179 -432.629259)
			(xy 341.163602 -432.61507) (xy 341.149352 -432.595538) (xy 341.141816 -432.572563) (xy 341.141304 -432.560476)
			(xy 341.141304 -431.948082) (xy 341.13976 -431.93359) (xy 341.138108 -431.90449) (xy 341.138002 -431.889916)
			(xy 338.235036 -431.889916) (xy 338.235036 -432.560476) (xy 338.234564 -432.57258) (xy 338.227075 -432.5956)
			(xy 338.212827 -432.615171) (xy 338.193219 -432.629367) (xy 338.170179 -432.636795) (xy 338.158074 -432.637184)
			(xy 337.218274 -432.637184) (xy 337.206185 -432.636715) (xy 337.183188 -432.629254) (xy 337.163611 -432.615067)
			(xy 337.14936 -432.595536) (xy 337.141824 -432.572563) (xy 337.141312 -432.560476) (xy 337.141312 -431.948082)
			(xy 337.139768 -431.93359) (xy 337.138116 -431.90449) (xy 337.13801 -431.889916) (xy 334.235044 -431.889916)
			(xy 334.235044 -432.560476) (xy 334.234564 -432.572579) (xy 334.227076 -432.595598) (xy 334.21283 -432.615168)
			(xy 334.193224 -432.629365) (xy 334.170186 -432.636794) (xy 334.158082 -432.637184) (xy 333.218282 -432.637184)
			(xy 333.206194 -432.636709) (xy 333.183197 -432.62925) (xy 333.163619 -432.615065) (xy 333.149368 -432.595535)
			(xy 333.141832 -432.572563) (xy 333.14132 -432.560476) (xy 333.14132 -431.948082) (xy 333.139776 -431.93359)
			(xy 333.138124 -431.90449) (xy 333.138018 -431.889916) (xy 329.2348 -431.889916) (xy 329.2348 -432.560476)
			(xy 329.234367 -432.572558) (xy 329.226905 -432.595542) (xy 329.212704 -432.615093) (xy 329.193156 -432.629297)
			(xy 329.170174 -432.636764) (xy 329.158092 -432.637184) (xy 328.218292 -432.637184) (xy 328.206206 -432.636794)
			(xy 328.183219 -432.629321) (xy 328.163667 -432.61511) (xy 328.149464 -432.595552) (xy 328.142001 -432.572562)
			(xy 328.141584 -432.560476) (xy 328.141584 -431.950114) (xy 328.139914 -431.935121) (xy 328.138137 -431.905002)
			(xy 328.138028 -431.889916) (xy 325.234808 -431.889916) (xy 325.234808 -432.560476) (xy 325.234367 -432.572557)
			(xy 325.226906 -432.595539) (xy 325.212707 -432.61509) (xy 325.193161 -432.629295) (xy 325.170181 -432.636763)
			(xy 325.1581 -432.637184) (xy 324.2183 -432.637184) (xy 324.206215 -432.636787) (xy 324.183228 -432.629317)
			(xy 324.163676 -432.615107) (xy 324.149472 -432.59555) (xy 324.142009 -432.572561) (xy 324.141592 -432.560476)
			(xy 324.141592 -431.950114) (xy 324.139922 -431.935121) (xy 324.138145 -431.905002) (xy 324.138036 -431.889916)
			(xy 321.234816 -431.889916) (xy 321.234816 -432.560476) (xy 321.234367 -432.572557) (xy 321.226907 -432.595537)
			(xy 321.21271 -432.615087) (xy 321.193166 -432.629292) (xy 321.170188 -432.636762) (xy 321.158108 -432.637184)
			(xy 320.218308 -432.637184) (xy 320.206223 -432.63678) (xy 320.183237 -432.629312) (xy 320.163684 -432.615105)
			(xy 320.149481 -432.595549) (xy 320.142017 -432.572561) (xy 320.1416 -432.560476) (xy 320.1416 -431.950114)
			(xy 320.13993 -431.935121) (xy 320.138153 -431.905002) (xy 320.138044 -431.889916) (xy 317.234824 -431.889916)
			(xy 317.234824 -432.560476) (xy 317.234367 -432.572556) (xy 317.226908 -432.595535) (xy 317.212713 -432.615084)
			(xy 317.193171 -432.62929) (xy 317.170196 -432.636761) (xy 317.158116 -432.637184) (xy 316.218316 -432.637184)
			(xy 316.206232 -432.636773) (xy 316.183246 -432.629307) (xy 316.163693 -432.615101) (xy 316.149489 -432.595547)
			(xy 316.142026 -432.57256) (xy 316.141608 -432.560476) (xy 316.141608 -431.950114) (xy 316.139938 -431.935121)
			(xy 316.138161 -431.905002) (xy 316.138052 -431.889916) (xy 310.60136 -431.889916) (xy 310.60136 -434.48986)
			(xy 314.138056 -434.48986) (xy 314.138169 -434.474774) (xy 314.139948 -434.444656) (xy 314.141612 -434.429662)
			(xy 314.141612 -433.350162) (xy 314.139947 -433.335168) (xy 314.138166 -433.30505) (xy 314.138056 -433.289964)
			(xy 314.138169 -433.274878) (xy 314.139948 -433.24476) (xy 314.141612 -433.229766) (xy 314.141612 -432.618896)
			(xy 314.142009 -432.606811) (xy 314.14948 -432.583825) (xy 314.16369 -432.564273) (xy 314.183246 -432.550069)
			(xy 314.206235 -432.542606) (xy 314.21832 -432.542188) (xy 315.15812 -432.542188) (xy 315.170195 -432.542647)
			(xy 315.193162 -432.550115) (xy 315.212699 -432.564313) (xy 315.226893 -432.583852) (xy 315.234355 -432.606821)
			(xy 315.234828 -432.618896) (xy 315.234828 -435.16042) (xy 315.234353 -435.172494) (xy 315.226887 -435.195458)
			(xy 315.212693 -435.214993) (xy 315.193158 -435.229187) (xy 315.170194 -435.236653) (xy 315.15812 -435.237128)
			(xy 314.21832 -435.237128) (xy 314.206248 -435.236619) (xy 314.183285 -435.229165) (xy 314.16375 -435.214979)
			(xy 314.149554 -435.195451) (xy 314.142087 -435.172491) (xy 314.141612 -435.16042) (xy 314.141612 -434.550058)
			(xy 314.139946 -434.535064) (xy 314.138166 -434.504946) (xy 314.138056 -434.48986) (xy 310.60136 -434.48986)
			(xy 310.60136 -435.489858) (xy 316.138052 -435.489858) (xy 316.138165 -435.474772) (xy 316.139944 -435.444654)
			(xy 316.141608 -435.42966) (xy 316.141608 -434.35016) (xy 316.139943 -434.335166) (xy 316.138162 -434.305048)
			(xy 316.138052 -434.289962) (xy 316.138165 -434.274876) (xy 316.139944 -434.244758) (xy 316.141608 -434.229764)
			(xy 316.141608 -433.618894) (xy 316.142102 -433.606807) (xy 316.149556 -433.583812) (xy 316.163737 -433.564235)
			(xy 316.183263 -433.549984) (xy 316.206231 -433.542446) (xy 316.218316 -433.541932) (xy 317.158116 -433.541932)
			(xy 317.170229 -433.542303) (xy 317.193262 -433.549811) (xy 317.212838 -433.564083) (xy 317.227031 -433.583716)
			(xy 317.234445 -433.606779) (xy 317.234824 -433.618894) (xy 317.234824 -434.48986) (xy 318.138048 -434.48986)
			(xy 318.138161 -434.474774) (xy 318.13994 -434.444656) (xy 318.141604 -434.429662) (xy 318.141604 -433.350162)
			(xy 318.139939 -433.335168) (xy 318.138158 -433.30505) (xy 318.138048 -433.289964) (xy 318.138161 -433.274878)
			(xy 318.13994 -433.24476) (xy 318.141604 -433.229766) (xy 318.141604 -432.618896) (xy 318.142009 -432.606812)
			(xy 318.149479 -432.583827) (xy 318.163687 -432.564276) (xy 318.183241 -432.550072) (xy 318.206228 -432.542607)
			(xy 318.218312 -432.542188) (xy 319.158112 -432.542188) (xy 319.170187 -432.542654) (xy 319.193154 -432.550119)
			(xy 319.21269 -432.564316) (xy 319.226884 -432.583854) (xy 319.234347 -432.606821) (xy 319.23482 -432.618896)
			(xy 319.23482 -435.16042) (xy 319.234353 -435.172494) (xy 319.226886 -435.19546) (xy 319.21269 -435.214996)
			(xy 319.193153 -435.22919) (xy 319.170186 -435.236654) (xy 319.158112 -435.237128) (xy 318.218312 -435.237128)
			(xy 318.20624 -435.236626) (xy 318.183277 -435.229169) (xy 318.163741 -435.214982) (xy 318.149546 -435.195452)
			(xy 318.142079 -435.172492) (xy 318.141604 -435.16042) (xy 318.141604 -434.550058) (xy 318.139938 -434.535064)
			(xy 318.138158 -434.504946) (xy 318.138048 -434.48986) (xy 317.234824 -434.48986) (xy 317.234824 -435.489858)
			(xy 320.138044 -435.489858) (xy 320.138157 -435.474772) (xy 320.139936 -435.444654) (xy 320.1416 -435.42966)
			(xy 320.1416 -434.35016) (xy 320.139934 -434.335166) (xy 320.138154 -434.305048) (xy 320.138044 -434.289962)
			(xy 320.138157 -434.274876) (xy 320.139936 -434.244758) (xy 320.1416 -434.229764) (xy 320.1416 -433.618894)
			(xy 320.142102 -433.606808) (xy 320.149555 -433.583814) (xy 320.163734 -433.564238) (xy 320.183258 -433.549986)
			(xy 320.206224 -433.542447) (xy 320.218308 -433.541932) (xy 321.158108 -433.541932) (xy 321.170221 -433.54231)
			(xy 321.193254 -433.549815) (xy 321.212829 -433.564086) (xy 321.227023 -433.583717) (xy 321.234437 -433.60678)
			(xy 321.234816 -433.618894) (xy 321.234816 -434.48986) (xy 322.13804 -434.48986) (xy 322.138153 -434.474774)
			(xy 322.139932 -434.444656) (xy 322.141596 -434.429662) (xy 322.141596 -433.350162) (xy 322.139931 -433.335168)
			(xy 322.13815 -433.30505) (xy 322.13804 -433.289964) (xy 322.138153 -433.274878) (xy 322.139932 -433.24476)
			(xy 322.141596 -433.229766) (xy 322.141596 -432.618896) (xy 322.142061 -432.606821) (xy 322.149525 -432.583853)
			(xy 322.163721 -432.564316) (xy 322.18326 -432.550121) (xy 322.206229 -432.54266) (xy 322.218304 -432.542188)
			(xy 323.158104 -432.542188) (xy 323.170178 -432.542661) (xy 323.193145 -432.550124) (xy 323.212682 -432.564318)
			(xy 323.226876 -432.583855) (xy 323.234339 -432.606822) (xy 323.234812 -432.618896) (xy 323.234812 -435.16042)
			(xy 323.234353 -435.172495) (xy 323.226885 -435.195462) (xy 323.212687 -435.214999) (xy 323.193148 -435.229193)
			(xy 323.170179 -435.236655) (xy 323.158104 -435.237128) (xy 322.218304 -435.237128) (xy 322.206232 -435.236633)
			(xy 322.183268 -435.229174) (xy 322.163733 -435.214984) (xy 322.149537 -435.195454) (xy 322.142071 -435.172492)
			(xy 322.141596 -435.16042) (xy 322.141596 -434.550058) (xy 322.13993 -434.535064) (xy 322.13815 -434.504946)
			(xy 322.13804 -434.48986) (xy 321.234816 -434.48986) (xy 321.234816 -435.489858) (xy 324.138036 -435.489858)
			(xy 324.138151 -435.474773) (xy 324.13993 -435.444654) (xy 324.141592 -435.42966) (xy 324.141592 -434.35016)
			(xy 324.139926 -434.335166) (xy 324.138146 -434.305048) (xy 324.138036 -434.289962) (xy 324.138151 -434.274877)
			(xy 324.13993 -434.244758) (xy 324.141592 -434.229764) (xy 324.141592 -433.618894) (xy 324.142102 -433.606809)
			(xy 324.149554 -433.583816) (xy 324.163731 -433.564241) (xy 324.183253 -433.549989) (xy 324.206217 -433.542448)
			(xy 324.2183 -433.541932) (xy 325.1581 -433.541932) (xy 325.170212 -433.542317) (xy 325.193245 -433.54982)
			(xy 325.212821 -433.564088) (xy 325.227014 -433.583719) (xy 325.234429 -433.60678) (xy 325.234808 -433.618894)
			(xy 325.234808 -434.48986) (xy 326.138032 -434.48986) (xy 326.138147 -434.474775) (xy 326.139926 -434.444656)
			(xy 326.141588 -434.429662) (xy 326.141588 -433.350162) (xy 326.139923 -433.335168) (xy 326.138142 -433.30505)
			(xy 326.138032 -433.289964) (xy 326.138148 -433.274879) (xy 326.139926 -433.24476) (xy 326.141588 -433.229766)
			(xy 326.141588 -432.618896) (xy 326.142061 -432.606822) (xy 326.149524 -432.583855) (xy 326.163718 -432.564318)
			(xy 326.183255 -432.550124) (xy 326.206222 -432.542661) (xy 326.218296 -432.542188) (xy 327.158096 -432.542188)
			(xy 327.17017 -432.542668) (xy 327.193136 -432.550129) (xy 327.212673 -432.564321) (xy 327.226868 -432.583857)
			(xy 327.234331 -432.606822) (xy 327.234804 -432.618896) (xy 327.234804 -435.16042) (xy 327.234353 -435.172496)
			(xy 327.226884 -435.195464) (xy 327.212684 -435.215001) (xy 327.193143 -435.229195) (xy 327.170172 -435.236656)
			(xy 327.158096 -435.237128) (xy 326.218296 -435.237128) (xy 326.206223 -435.236639) (xy 326.183259 -435.229178)
			(xy 326.163724 -435.214987) (xy 326.149529 -435.195455) (xy 326.142063 -435.172493) (xy 326.141588 -435.16042)
			(xy 326.141588 -434.550058) (xy 326.139922 -434.535064) (xy 326.138142 -434.504946) (xy 326.138032 -434.48986)
			(xy 325.234808 -434.48986) (xy 325.234808 -435.489858) (xy 328.138028 -435.489858) (xy 328.138143 -435.474773)
			(xy 328.139922 -435.444654) (xy 328.141584 -435.42966) (xy 328.141584 -434.35016) (xy 328.139918 -434.335166)
			(xy 328.138138 -434.305048) (xy 328.138028 -434.289962) (xy 328.138143 -434.274877) (xy 328.139922 -434.244758)
			(xy 328.141584 -434.229764) (xy 328.141584 -433.618894) (xy 328.142003 -433.6068) (xy 328.149467 -433.583792)
			(xy 328.163664 -433.564208) (xy 328.183211 -433.549959) (xy 328.206199 -433.542435) (xy 328.218292 -433.541932)
			(xy 329.158092 -433.541932) (xy 329.170204 -433.542323) (xy 329.193236 -433.549824) (xy 329.212812 -433.564091)
			(xy 329.227006 -433.58372) (xy 329.234421 -433.606781) (xy 329.2348 -433.618894) (xy 329.2348 -434.48986)
			(xy 331.138022 -434.48986) (xy 331.13812 -434.475286) (xy 331.13977 -434.446185) (xy 331.141324 -434.431694)
			(xy 331.141324 -433.34813) (xy 331.139776 -433.333638) (xy 331.138126 -433.304538) (xy 331.138022 -433.289964)
			(xy 331.13812 -433.27539) (xy 331.13977 -433.246289) (xy 331.141324 -433.231798) (xy 331.141324 -432.618896)
			(xy 331.141713 -432.606785) (xy 331.149217 -432.583753) (xy 331.163484 -432.564178) (xy 331.183113 -432.549984)
			(xy 331.206173 -432.542568) (xy 331.218286 -432.542188) (xy 332.158086 -432.542188) (xy 332.17018 -432.54262)
			(xy 332.193188 -432.550079) (xy 332.212772 -432.564273) (xy 332.227021 -432.583817) (xy 332.234545 -432.606804)
			(xy 332.235048 -432.618896) (xy 332.235048 -435.16042) (xy 332.234601 -435.172525) (xy 332.227102 -435.195545)
			(xy 332.212847 -435.215113) (xy 332.193235 -435.229309) (xy 332.170192 -435.236738) (xy 332.158086 -435.237128)
			(xy 331.218286 -435.237128) (xy 331.206192 -435.236704) (xy 331.183186 -435.22924) (xy 331.163603 -435.215043)
			(xy 331.149354 -435.195499) (xy 331.141828 -435.172512) (xy 331.141324 -435.16042) (xy 331.141324 -434.548026)
			(xy 331.139776 -434.533534) (xy 331.138126 -434.504434) (xy 331.138022 -434.48986) (xy 329.2348 -434.48986)
			(xy 329.2348 -435.489858) (xy 333.138018 -435.489858) (xy 333.138116 -435.475284) (xy 333.139766 -435.446183)
			(xy 333.14132 -435.431692) (xy 333.14132 -434.348128) (xy 333.139772 -434.333636) (xy 333.138122 -434.304536)
			(xy 333.138018 -434.289962) (xy 333.138116 -434.275388) (xy 333.139766 -434.246287) (xy 333.14132 -434.231796)
			(xy 333.14132 -433.618894) (xy 333.141807 -433.606781) (xy 333.149293 -433.583741) (xy 333.163532 -433.564141)
			(xy 333.18313 -433.549899) (xy 333.206169 -433.542408) (xy 333.218282 -433.541932) (xy 334.158082 -433.541932)
			(xy 334.170203 -433.542375) (xy 334.19326 -433.549862) (xy 334.212875 -433.564108) (xy 334.227127 -433.583718)
			(xy 334.234621 -433.606773) (xy 334.235044 -433.618894) (xy 334.235044 -434.48986) (xy 335.138014 -434.48986)
			(xy 335.138111 -434.475286) (xy 335.139761 -434.446185) (xy 335.141316 -434.431694) (xy 335.141316 -433.34813)
			(xy 335.139768 -433.333638) (xy 335.138118 -433.304538) (xy 335.138014 -433.289964) (xy 335.138112 -433.27539)
			(xy 335.139761 -433.246289) (xy 335.141316 -433.231798) (xy 335.141316 -432.618896) (xy 335.141713 -432.606785)
			(xy 335.149215 -432.583755) (xy 335.163481 -432.564181) (xy 335.183108 -432.549987) (xy 335.206166 -432.542569)
			(xy 335.218278 -432.542188) (xy 336.158078 -432.542188) (xy 336.170171 -432.542627) (xy 336.193179 -432.550084)
			(xy 336.212764 -432.564276) (xy 336.227013 -432.583818) (xy 336.234537 -432.606804) (xy 336.23504 -432.618896)
			(xy 336.23504 -435.16042) (xy 336.234601 -435.172526) (xy 336.227101 -435.195547) (xy 336.212844 -435.215116)
			(xy 336.19323 -435.229312) (xy 336.170185 -435.236739) (xy 336.158078 -435.237128) (xy 335.218278 -435.237128)
			(xy 335.206184 -435.236711) (xy 335.183177 -435.229244) (xy 335.163595 -435.215046) (xy 335.149346 -435.1955)
			(xy 335.14182 -435.172513) (xy 335.141316 -435.16042) (xy 335.141316 -434.548026) (xy 335.139768 -434.533534)
			(xy 335.138118 -434.504434) (xy 335.138014 -434.48986) (xy 334.235044 -434.48986) (xy 334.235044 -435.489858)
			(xy 337.13801 -435.489858) (xy 337.138107 -435.475284) (xy 337.139757 -435.446183) (xy 337.141312 -435.431692)
			(xy 337.141312 -434.348128) (xy 337.139764 -434.333636) (xy 337.138114 -434.304536) (xy 337.13801 -434.289962)
			(xy 337.138108 -434.275388) (xy 337.139757 -434.246287) (xy 337.141312 -434.231796) (xy 337.141312 -433.618894)
			(xy 337.141806 -433.606782) (xy 337.149292 -433.583743) (xy 337.163529 -433.564143) (xy 337.183125 -433.549901)
			(xy 337.206162 -433.54241) (xy 337.218274 -433.541932) (xy 338.158074 -433.541932) (xy 338.170195 -433.542382)
			(xy 338.193252 -433.549866) (xy 338.212867 -433.56411) (xy 338.227119 -433.58372) (xy 338.234613 -433.606773)
			(xy 338.235036 -433.618894) (xy 338.235036 -434.48986) (xy 339.138006 -434.48986) (xy 339.138104 -434.475286)
			(xy 339.139753 -434.446185) (xy 339.141308 -434.431694) (xy 339.141308 -433.34813) (xy 339.13976 -433.333638)
			(xy 339.13811 -433.304538) (xy 339.138006 -433.289964) (xy 339.138104 -433.27539) (xy 339.139753 -433.246289)
			(xy 339.141308 -433.231798) (xy 339.141308 -432.618896) (xy 339.141713 -432.606786) (xy 339.149214 -432.583757)
			(xy 339.163479 -432.564184) (xy 339.183103 -432.549989) (xy 339.206159 -432.54257) (xy 339.21827 -432.542188)
			(xy 340.15807 -432.542188) (xy 340.170163 -432.542634) (xy 340.19317 -432.550088) (xy 340.212755 -432.564278)
			(xy 340.227005 -432.58382) (xy 340.234529 -432.606805) (xy 340.235032 -432.618896) (xy 340.235032 -435.16042)
			(xy 340.234601 -435.172527) (xy 340.2271 -435.195549) (xy 340.212841 -435.215119) (xy 340.193225 -435.229314)
			(xy 340.170178 -435.23674) (xy 340.15807 -435.237128) (xy 339.21827 -435.237128) (xy 339.206176 -435.236718)
			(xy 339.183169 -435.229249) (xy 339.163586 -435.215049) (xy 339.149338 -435.195502) (xy 339.141812 -435.172513)
			(xy 339.141308 -435.16042) (xy 339.141308 -434.548026) (xy 339.13976 -434.533534) (xy 339.13811 -434.504434)
			(xy 339.138006 -434.48986) (xy 338.235036 -434.48986) (xy 338.235036 -435.489858) (xy 341.138002 -435.489858)
			(xy 341.138099 -435.475284) (xy 341.139749 -435.446183) (xy 341.141304 -435.431692) (xy 341.141304 -434.348128)
			(xy 341.139756 -434.333636) (xy 341.138106 -434.304536) (xy 341.138002 -434.289962) (xy 341.1381 -434.275388)
			(xy 341.139749 -434.246287) (xy 341.141304 -434.231796) (xy 341.141304 -433.618894) (xy 341.141806 -433.606783)
			(xy 341.149291 -433.583745) (xy 341.163526 -433.564146) (xy 341.18312 -433.549904) (xy 341.206155 -433.542411)
			(xy 341.218266 -433.541932) (xy 342.158066 -433.541932) (xy 342.170186 -433.542389) (xy 342.193243 -433.549871)
			(xy 342.212858 -433.564113) (xy 342.227111 -433.583721) (xy 342.234605 -433.606774) (xy 342.235028 -433.618894)
			(xy 342.235028 -434.48986) (xy 343.137998 -434.48986) (xy 343.138096 -434.475286) (xy 343.139745 -434.446185)
			(xy 343.1413 -434.431694) (xy 343.1413 -433.34813) (xy 343.139752 -433.333638) (xy 343.138102 -433.304538)
			(xy 343.137998 -433.289964) (xy 343.138096 -433.27539) (xy 343.139745 -433.246289) (xy 343.1413 -433.231798)
			(xy 343.1413 -432.618896) (xy 343.141713 -432.606787) (xy 343.149213 -432.583759) (xy 343.163476 -432.564186)
			(xy 343.183098 -432.549992) (xy 343.206152 -432.542571) (xy 343.218262 -432.542188) (xy 344.158062 -432.542188)
			(xy 344.170154 -432.542641) (xy 344.193162 -432.550093) (xy 344.212747 -432.564281) (xy 344.226997 -432.583821)
			(xy 344.234521 -432.606805) (xy 344.235024 -432.618896) (xy 344.235024 -435.16042) (xy 344.234601 -435.172528)
			(xy 344.227099 -435.195551) (xy 344.212838 -435.215122) (xy 344.19322 -435.229317) (xy 344.170171 -435.236741)
			(xy 344.158062 -435.237128) (xy 343.218262 -435.237128) (xy 343.206167 -435.236724) (xy 343.18316 -435.229253)
			(xy 343.163578 -435.215052) (xy 343.14933 -435.195503) (xy 343.141804 -435.172514) (xy 343.1413 -435.16042)
			(xy 343.1413 -434.548026) (xy 343.139752 -434.533534) (xy 343.138102 -434.504434) (xy 343.137998 -434.48986)
			(xy 342.235028 -434.48986) (xy 342.235028 -435.489858) (xy 345.137994 -435.489858) (xy 345.138091 -435.475284)
			(xy 345.139741 -435.446183) (xy 345.141296 -435.431692) (xy 345.141296 -434.348128) (xy 345.139748 -434.333636)
			(xy 345.138098 -434.304536) (xy 345.137994 -434.289962) (xy 345.138092 -434.275388) (xy 345.139741 -434.246287)
			(xy 345.141296 -434.231796) (xy 345.141296 -433.618894) (xy 345.141806 -433.606783) (xy 345.14929 -433.583747)
			(xy 345.163524 -433.564149) (xy 345.183115 -433.549906) (xy 345.206148 -433.542412) (xy 345.218258 -433.541932)
			(xy 346.158058 -433.541932) (xy 346.170178 -433.542396) (xy 346.193234 -433.549876) (xy 346.21285 -433.564116)
			(xy 346.227103 -433.583722) (xy 346.234597 -433.606774) (xy 346.23502 -433.618894) (xy 346.23502 -436.160418)
			(xy 346.234654 -436.172546) (xy 346.227152 -436.195612) (xy 346.212888 -436.215231) (xy 346.193258 -436.22948)
			(xy 346.170186 -436.236964) (xy 346.158058 -436.23738) (xy 345.218258 -436.23738) (xy 345.206143 -436.236924)
			(xy 345.183101 -436.229428) (xy 345.163502 -436.215181) (xy 345.149261 -436.195577) (xy 345.141772 -436.172533)
			(xy 345.141296 -436.160418) (xy 345.141296 -435.548024) (xy 345.139748 -435.533532) (xy 345.138098 -435.504432)
			(xy 345.137994 -435.489858) (xy 342.235028 -435.489858) (xy 342.235028 -436.160418) (xy 342.234655 -436.172545)
			(xy 342.227153 -436.19561) (xy 342.212891 -436.215228) (xy 342.193264 -436.229477) (xy 342.170193 -436.236963)
			(xy 342.158066 -436.23738) (xy 341.218266 -436.23738) (xy 341.206151 -436.236918) (xy 341.18311 -436.229423)
			(xy 341.16351 -436.215178) (xy 341.149269 -436.195576) (xy 341.14178 -436.172533) (xy 341.141304 -436.160418)
			(xy 341.141304 -435.548024) (xy 341.139755 -435.533532) (xy 341.138106 -435.504432) (xy 341.138002 -435.489858)
			(xy 338.235036 -435.489858) (xy 338.235036 -436.160418) (xy 338.234655 -436.172544) (xy 338.227154 -436.195608)
			(xy 338.212894 -436.215225) (xy 338.193269 -436.229474) (xy 338.1702 -436.236962) (xy 338.158074 -436.23738)
			(xy 337.218274 -436.23738) (xy 337.20616 -436.236911) (xy 337.183119 -436.229419) (xy 337.163519 -436.215175)
			(xy 337.149278 -436.195574) (xy 337.141788 -436.172532) (xy 337.141312 -436.160418) (xy 337.141312 -435.548024)
			(xy 337.139763 -435.533532) (xy 337.138114 -435.504432) (xy 337.13801 -435.489858) (xy 334.235044 -435.489858)
			(xy 334.235044 -436.160418) (xy 334.234604 -436.172535) (xy 334.227109 -436.195582) (xy 334.21286 -436.215185)
			(xy 334.19325 -436.229426) (xy 334.1702 -436.236909) (xy 334.158082 -436.23738) (xy 333.218282 -436.23738)
			(xy 333.206168 -436.236904) (xy 333.183127 -436.229414) (xy 333.163528 -436.215172) (xy 333.149286 -436.195573)
			(xy 333.141796 -436.172532) (xy 333.14132 -436.160418) (xy 333.14132 -435.548024) (xy 333.139771 -435.533532)
			(xy 333.138122 -435.504432) (xy 333.138018 -435.489858) (xy 329.2348 -435.489858) (xy 329.2348 -436.160418)
			(xy 329.234309 -436.172505) (xy 329.226852 -436.195499) (xy 329.21267 -436.215075) (xy 329.193145 -436.229327)
			(xy 329.170177 -436.236865) (xy 329.158092 -436.23738) (xy 328.218292 -436.23738) (xy 328.206181 -436.23699)
			(xy 328.18315 -436.229486) (xy 328.163575 -436.215219) (xy 328.149381 -436.19559) (xy 328.141964 -436.172531)
			(xy 328.141584 -436.160418) (xy 328.141584 -435.550056) (xy 328.139918 -435.535062) (xy 328.138138 -435.504944)
			(xy 328.138028 -435.489858) (xy 325.234808 -435.489858) (xy 325.234808 -436.160418) (xy 325.234309 -436.172504)
			(xy 325.226853 -436.195497) (xy 325.212673 -436.215072) (xy 325.19315 -436.229324) (xy 325.170184 -436.236864)
			(xy 325.1581 -436.23738) (xy 324.2183 -436.23738) (xy 324.206189 -436.236984) (xy 324.183158 -436.229482)
			(xy 324.163583 -436.215216) (xy 324.14939 -436.195589) (xy 324.141972 -436.17253) (xy 324.141592 -436.160418)
			(xy 324.141592 -435.550056) (xy 324.139926 -435.535062) (xy 324.138146 -435.504944) (xy 324.138036 -435.489858)
			(xy 321.234816 -435.489858) (xy 321.234816 -436.160418) (xy 321.234407 -436.172513) (xy 321.22694 -436.195522)
			(xy 321.21274 -436.215105) (xy 321.193192 -436.229353) (xy 321.170202 -436.236877) (xy 321.158108 -436.23738)
			(xy 320.218308 -436.23738) (xy 320.206198 -436.236977) (xy 320.183167 -436.229477) (xy 320.163592 -436.215213)
			(xy 320.149398 -436.195587) (xy 320.14198 -436.17253) (xy 320.1416 -436.160418) (xy 320.1416 -435.550056)
			(xy 320.139934 -435.535062) (xy 320.138154 -435.504944) (xy 320.138044 -435.489858) (xy 317.234824 -435.489858)
			(xy 317.234824 -436.160418) (xy 317.234407 -436.172512) (xy 317.226941 -436.195519) (xy 317.212743 -436.215102)
			(xy 317.193197 -436.229351) (xy 317.170209 -436.236876) (xy 317.158116 -436.23738) (xy 316.218316 -436.23738)
			(xy 316.206206 -436.23697) (xy 316.183176 -436.229472) (xy 316.163601 -436.21521) (xy 316.149406 -436.195585)
			(xy 316.141989 -436.172529) (xy 316.141608 -436.160418) (xy 316.141608 -435.550056) (xy 316.139942 -435.535062)
			(xy 316.138162 -435.504944) (xy 316.138052 -435.489858) (xy 310.60136 -435.489858) (xy 310.60136 -438.089802)
			(xy 314.138056 -438.089802) (xy 314.138173 -438.074717) (xy 314.139949 -438.044598) (xy 314.141612 -438.029604)
			(xy 314.141612 -436.950104) (xy 314.139942 -436.935111) (xy 314.138164 -436.904992) (xy 314.138056 -436.889906)
			(xy 314.138164 -436.87482) (xy 314.139946 -436.844702) (xy 314.141612 -436.829708) (xy 314.141612 -436.219092)
			(xy 314.142006 -436.207007) (xy 314.149478 -436.18402) (xy 314.163688 -436.164469) (xy 314.183246 -436.150265)
			(xy 314.206235 -436.142802) (xy 314.21832 -436.142384) (xy 315.15812 -436.142384) (xy 315.170195 -436.142847)
			(xy 315.193161 -436.150314) (xy 315.212697 -436.164511) (xy 315.226891 -436.18405) (xy 315.234355 -436.207017)
			(xy 315.234828 -436.219092) (xy 315.234828 -438.760616) (xy 315.23435 -438.772689) (xy 315.226885 -438.795654)
			(xy 315.212691 -438.815189) (xy 315.193157 -438.829383) (xy 315.170193 -438.836849) (xy 315.15812 -438.837324)
			(xy 314.21832 -438.837324) (xy 314.20624 -438.83687) (xy 314.183261 -438.82941) (xy 314.163711 -438.815214)
			(xy 314.149506 -438.795672) (xy 314.142035 -438.772696) (xy 314.141612 -438.760616) (xy 314.141612 -438.15)
			(xy 314.139941 -438.135007) (xy 314.138164 -438.104888) (xy 314.138056 -438.089802) (xy 310.60136 -438.089802)
			(xy 310.60136 -439.0898) (xy 316.138052 -439.0898) (xy 316.138169 -439.074715) (xy 316.139945 -439.044596)
			(xy 316.141608 -439.029602) (xy 316.141608 -437.950102) (xy 316.139937 -437.935109) (xy 316.13816 -437.90499)
			(xy 316.138052 -437.889904) (xy 316.138169 -437.874819) (xy 316.139945 -437.8447) (xy 316.141608 -437.829706)
			(xy 316.141608 -437.21909) (xy 316.142098 -437.207003) (xy 316.149554 -437.184008) (xy 316.163736 -437.164431)
			(xy 316.183262 -437.150179) (xy 316.206231 -437.142642) (xy 316.218316 -437.142128) (xy 317.158116 -437.142128)
			(xy 317.170229 -437.142503) (xy 317.193261 -437.15001) (xy 317.212836 -437.164281) (xy 317.227029 -437.183914)
			(xy 317.234445 -437.206976) (xy 317.234824 -437.21909) (xy 317.234824 -438.089802) (xy 318.138048 -438.089802)
			(xy 318.138165 -438.074717) (xy 318.139941 -438.044598) (xy 318.141604 -438.029604) (xy 318.141604 -436.950104)
			(xy 318.139934 -436.935111) (xy 318.138156 -436.904992) (xy 318.138048 -436.889906) (xy 318.138156 -436.87482)
			(xy 318.139938 -436.844702) (xy 318.141604 -436.829708) (xy 318.141604 -436.219092) (xy 318.142006 -436.207008)
			(xy 318.149477 -436.184023) (xy 318.163686 -436.164471) (xy 318.183241 -436.150268) (xy 318.206228 -436.142803)
			(xy 318.218312 -436.142384) (xy 319.158112 -436.142384) (xy 319.170186 -436.142854) (xy 319.193153 -436.150319)
			(xy 319.212689 -436.164514) (xy 319.226883 -436.184051) (xy 319.234347 -436.207018) (xy 319.23482 -436.219092)
			(xy 319.23482 -438.760616) (xy 319.234349 -438.77269) (xy 319.226884 -438.795656) (xy 319.212689 -438.815191)
			(xy 319.193152 -438.829386) (xy 319.170186 -438.83685) (xy 319.158112 -438.837324) (xy 318.218312 -438.837324)
			(xy 318.20624 -438.836826) (xy 318.183276 -438.829369) (xy 318.16374 -438.81518) (xy 318.149544 -438.79565)
			(xy 318.142079 -438.772688) (xy 318.141604 -438.760616) (xy 318.141604 -438.15) (xy 318.139933 -438.135007)
			(xy 318.138156 -438.104888) (xy 318.138048 -438.089802) (xy 317.234824 -438.089802) (xy 317.234824 -439.0898)
			(xy 320.138044 -439.0898) (xy 320.138161 -439.074715) (xy 320.139937 -439.044596) (xy 320.1416 -439.029602)
			(xy 320.1416 -437.950102) (xy 320.139929 -437.935109) (xy 320.138152 -437.90499) (xy 320.138044 -437.889904)
			(xy 320.138161 -437.874819) (xy 320.139937 -437.8447) (xy 320.1416 -437.829706) (xy 320.1416 -437.21909)
			(xy 320.142098 -437.207004) (xy 320.149553 -437.18401) (xy 320.163733 -437.164434) (xy 320.183257 -437.150182)
			(xy 320.206224 -437.142643) (xy 320.218308 -437.142128) (xy 321.158108 -437.142128) (xy 321.17022 -437.14251)
			(xy 321.193252 -437.150015) (xy 321.212828 -437.164284) (xy 321.227021 -437.183915) (xy 321.234437 -437.206976)
			(xy 321.234816 -437.21909) (xy 321.234816 -438.089802) (xy 322.13804 -438.089802) (xy 322.138157 -438.074717)
			(xy 322.139933 -438.044598) (xy 322.141596 -438.029604) (xy 322.141596 -436.950104) (xy 322.139926 -436.935111)
			(xy 322.138148 -436.904992) (xy 322.13804 -436.889906) (xy 322.13815 -436.87482) (xy 322.139932 -436.844702)
			(xy 322.141596 -436.829708) (xy 322.141596 -436.219092) (xy 322.142058 -436.207017) (xy 322.149523 -436.184049)
			(xy 322.16372 -436.164511) (xy 322.183259 -436.150317) (xy 322.206229 -436.142856) (xy 322.218304 -436.142384)
			(xy 323.158104 -436.142384) (xy 323.170178 -436.142861) (xy 323.193144 -436.150323) (xy 323.21268 -436.164517)
			(xy 323.226875 -436.184053) (xy 323.234339 -436.207018) (xy 323.234812 -436.219092) (xy 323.234812 -438.760616)
			(xy 323.234349 -438.772691) (xy 323.226883 -438.795658) (xy 323.212686 -438.815194) (xy 323.193147 -438.829388)
			(xy 323.170179 -438.836851) (xy 323.158104 -438.837324) (xy 322.218304 -438.837324) (xy 322.206231 -438.836833)
			(xy 322.183267 -438.829373) (xy 322.163731 -438.815183) (xy 322.149536 -438.795651) (xy 322.142071 -438.772689)
			(xy 322.141596 -438.760616) (xy 322.141596 -438.15) (xy 322.139925 -438.135007) (xy 322.138148 -438.104888)
			(xy 322.13804 -438.089802) (xy 321.234816 -438.089802) (xy 321.234816 -439.0898) (xy 324.138036 -439.0898)
			(xy 324.138153 -439.074715) (xy 324.139929 -439.044596) (xy 324.141592 -439.029602) (xy 324.141592 -437.950102)
			(xy 324.139921 -437.935109) (xy 324.138144 -437.90499) (xy 324.138036 -437.889904) (xy 324.138153 -437.874819)
			(xy 324.139929 -437.8447) (xy 324.141592 -437.829706) (xy 324.141592 -437.21909) (xy 324.142098 -437.207005)
			(xy 324.149552 -437.184012) (xy 324.16373 -437.164436) (xy 324.183252 -437.150184) (xy 324.206217 -437.142644)
			(xy 324.2183 -437.142128) (xy 325.1581 -437.142128) (xy 325.170212 -437.142516) (xy 325.193244 -437.150019)
			(xy 325.212819 -437.164287) (xy 325.227013 -437.183916) (xy 325.234429 -437.206977) (xy 325.234808 -437.21909)
			(xy 325.234808 -438.089802) (xy 326.138032 -438.089802) (xy 326.138151 -438.074717) (xy 326.139927 -438.044598)
			(xy 326.141588 -438.029604) (xy 326.141588 -436.950104) (xy 326.139917 -436.935111) (xy 326.13814 -436.904992)
			(xy 326.138032 -436.889906) (xy 326.138142 -436.87482) (xy 326.139924 -436.844702) (xy 326.141588 -436.829708)
			(xy 326.141588 -436.219092) (xy 326.142057 -436.207017) (xy 326.149522 -436.184051) (xy 326.163717 -436.164514)
			(xy 326.183254 -436.15032) (xy 326.206221 -436.142857) (xy 326.218296 -436.142384) (xy 327.158096 -436.142384)
			(xy 327.17017 -436.142868) (xy 327.193135 -436.150328) (xy 327.212672 -436.16452) (xy 327.226867 -436.184054)
			(xy 327.234331 -436.207019) (xy 327.234804 -436.219092) (xy 327.234804 -438.760616) (xy 327.234349 -438.772692)
			(xy 327.226882 -438.79566) (xy 327.212683 -438.815197) (xy 327.193142 -438.829391) (xy 327.170172 -438.836852)
			(xy 327.158096 -438.837324) (xy 326.218296 -438.837324) (xy 326.206223 -438.836839) (xy 326.183258 -438.829378)
			(xy 326.163723 -438.815186) (xy 326.149528 -438.795652) (xy 326.142063 -438.772689) (xy 326.141588 -438.760616)
			(xy 326.141588 -438.15) (xy 326.139917 -438.135007) (xy 326.13814 -438.104888) (xy 326.138032 -438.089802)
			(xy 325.234808 -438.089802) (xy 325.234808 -439.0898) (xy 328.138028 -439.0898) (xy 328.138147 -439.074715)
			(xy 328.139923 -439.044596) (xy 328.141584 -439.029602) (xy 328.141584 -437.950102) (xy 328.139913 -437.935109)
			(xy 328.138136 -437.90499) (xy 328.138028 -437.889904) (xy 328.138147 -437.874819) (xy 328.139923 -437.8447)
			(xy 328.141584 -437.829706) (xy 328.141584 -437.21909) (xy 328.142 -437.206996) (xy 328.149465 -437.183987)
			(xy 328.163663 -437.164404) (xy 328.18321 -437.150155) (xy 328.206199 -437.142631) (xy 328.218292 -437.142128)
			(xy 329.158092 -437.142128) (xy 329.170203 -437.142523) (xy 329.193235 -437.150024) (xy 329.212811 -437.16429)
			(xy 329.227005 -437.183918) (xy 329.234421 -437.206977) (xy 329.2348 -437.21909) (xy 329.2348 -438.089802)
			(xy 331.138022 -438.089802) (xy 331.138115 -438.075228) (xy 331.139768 -438.046127) (xy 331.141324 -438.031636)
			(xy 331.141324 -436.948072) (xy 331.13978 -436.93358) (xy 331.138127 -436.90448) (xy 331.138022 -436.889906)
			(xy 331.138115 -436.875332) (xy 331.139768 -436.846231) (xy 331.141324 -436.83174) (xy 331.141324 -436.219092)
			(xy 331.14171 -436.20698) (xy 331.149214 -436.183949) (xy 331.163483 -436.164374) (xy 331.183112 -436.15018)
			(xy 331.206173 -436.142764) (xy 331.218286 -436.142384) (xy 332.158086 -436.142384) (xy 332.170179 -436.14282)
			(xy 332.193187 -436.150278) (xy 332.212771 -436.164471) (xy 332.22702 -436.184014) (xy 332.234545 -436.207)
			(xy 332.235048 -436.219092) (xy 332.235048 -438.760616) (xy 332.234598 -438.772721) (xy 332.2271 -438.795741)
			(xy 332.212845 -438.815309) (xy 332.193234 -438.829505) (xy 332.170192 -438.836934) (xy 332.158086 -438.837324)
			(xy 331.218286 -438.837324) (xy 331.206192 -438.836904) (xy 331.183185 -438.829439) (xy 331.163602 -438.815242)
			(xy 331.149353 -438.795696) (xy 331.141828 -438.772709) (xy 331.141324 -438.760616) (xy 331.141324 -438.147968)
			(xy 331.139779 -438.133476) (xy 331.138127 -438.104376) (xy 331.138022 -438.089802) (xy 329.2348 -438.089802)
			(xy 329.2348 -439.0898) (xy 333.138018 -439.0898) (xy 333.138111 -439.075226) (xy 333.139764 -439.046125)
			(xy 333.14132 -439.031634) (xy 333.14132 -437.94807) (xy 333.139775 -437.933578) (xy 333.138123 -437.904478)
			(xy 333.138018 -437.889904) (xy 333.138111 -437.87533) (xy 333.139764 -437.846229) (xy 333.14132 -437.831738)
			(xy 333.14132 -437.21909) (xy 333.141803 -437.206977) (xy 333.149291 -437.183936) (xy 333.163531 -437.164336)
			(xy 333.183129 -437.150095) (xy 333.206169 -437.142604) (xy 333.218282 -437.142128) (xy 334.158082 -437.142128)
			(xy 334.170203 -437.142575) (xy 334.193259 -437.150061) (xy 334.212874 -437.164306) (xy 334.227126 -437.183916)
			(xy 334.23462 -437.206969) (xy 334.235044 -437.21909) (xy 334.235044 -438.089802) (xy 335.138014 -438.089802)
			(xy 335.138106 -438.075228) (xy 335.13976 -438.046127) (xy 335.141316 -438.031636) (xy 335.141316 -436.948072)
			(xy 335.139772 -436.93358) (xy 335.138119 -436.90448) (xy 335.138014 -436.889906) (xy 335.138107 -436.875332)
			(xy 335.13976 -436.846231) (xy 335.141316 -436.83174) (xy 335.141316 -436.219092) (xy 335.14171 -436.206981)
			(xy 335.149213 -436.183951) (xy 335.16348 -436.164376) (xy 335.183107 -436.150183) (xy 335.206166 -436.142765)
			(xy 335.218278 -436.142384) (xy 336.158078 -436.142384) (xy 336.170171 -436.142827) (xy 336.193178 -436.150283)
			(xy 336.212762 -436.164474) (xy 336.227012 -436.184016) (xy 336.234537 -436.207001) (xy 336.23504 -436.219092)
			(xy 336.23504 -438.760616) (xy 336.234598 -438.772722) (xy 336.227099 -438.795743) (xy 336.212843 -438.815312)
			(xy 336.193229 -438.829508) (xy 336.170185 -438.836935) (xy 336.158078 -438.837324) (xy 335.218278 -438.837324)
			(xy 335.206184 -438.836911) (xy 335.183176 -438.829444) (xy 335.163594 -438.815245) (xy 335.149345 -438.795698)
			(xy 335.14182 -438.772709) (xy 335.141316 -438.760616) (xy 335.141316 -438.147968) (xy 335.139771 -438.133476)
			(xy 335.138119 -438.104376) (xy 335.138014 -438.089802) (xy 334.235044 -438.089802) (xy 334.235044 -439.0898)
			(xy 337.13801 -439.0898) (xy 337.138102 -439.075226) (xy 337.139756 -439.046125) (xy 337.141312 -439.031634)
			(xy 337.141312 -437.94807) (xy 337.139767 -437.933578) (xy 337.138115 -437.904478) (xy 337.13801 -437.889904)
			(xy 337.138103 -437.87533) (xy 337.139756 -437.846229) (xy 337.141312 -437.831738) (xy 337.141312 -437.21909)
			(xy 337.141803 -437.206978) (xy 337.14929 -437.183938) (xy 337.163528 -437.164339) (xy 337.183124 -437.150097)
			(xy 337.206162 -437.142606) (xy 337.218274 -437.142128) (xy 338.158074 -437.142128) (xy 338.170194 -437.142582)
			(xy 338.193251 -437.150066) (xy 338.212865 -437.164309) (xy 338.227118 -437.183917) (xy 338.234612 -437.20697)
			(xy 338.235036 -437.21909) (xy 338.235036 -438.089802) (xy 339.138006 -438.089802) (xy 339.138099 -438.075228)
			(xy 339.139752 -438.046127) (xy 339.141308 -438.031636) (xy 339.141308 -436.948072) (xy 339.139763 -436.93358)
			(xy 339.138111 -436.90448) (xy 339.138006 -436.889906) (xy 339.138099 -436.875332) (xy 339.139752 -436.846231)
			(xy 339.141308 -436.83174) (xy 339.141308 -436.219092) (xy 339.141709 -436.206982) (xy 339.149212 -436.183953)
			(xy 339.163477 -436.164379) (xy 339.183102 -436.150185) (xy 339.206158 -436.142766) (xy 339.21827 -436.142384)
			(xy 340.15807 -436.142384) (xy 340.170162 -436.142834) (xy 340.193169 -436.150288) (xy 340.212754 -436.164477)
			(xy 340.227004 -436.184017) (xy 340.234529 -436.207001) (xy 340.235032 -436.219092) (xy 340.235032 -438.760616)
			(xy 340.234598 -438.772723) (xy 340.227098 -438.795745) (xy 340.21284 -438.815315) (xy 340.193224 -438.82951)
			(xy 340.170178 -438.836936) (xy 340.15807 -438.837324) (xy 339.21827 -438.837324) (xy 339.206175 -438.836918)
			(xy 339.183168 -438.829448) (xy 339.163585 -438.815247) (xy 339.149337 -438.795699) (xy 339.141812 -438.77271)
			(xy 339.141308 -438.760616) (xy 339.141308 -438.147968) (xy 339.139763 -438.133476) (xy 339.138111 -438.104376)
			(xy 339.138006 -438.089802) (xy 338.235036 -438.089802) (xy 338.235036 -439.0898) (xy 341.138002 -439.0898)
			(xy 341.138094 -439.075226) (xy 341.139748 -439.046125) (xy 341.141304 -439.031634) (xy 341.141304 -437.94807)
			(xy 341.139759 -437.933578) (xy 341.138107 -437.904478) (xy 341.138002 -437.889904) (xy 341.138095 -437.87533)
			(xy 341.139748 -437.846229) (xy 341.141304 -437.831738) (xy 341.141304 -437.21909) (xy 341.141803 -437.206978)
			(xy 341.149289 -437.183941) (xy 341.163525 -437.164342) (xy 341.183119 -437.1501) (xy 341.206154 -437.142607)
			(xy 341.218266 -437.142128) (xy 342.158066 -437.142128) (xy 342.170186 -437.142589) (xy 342.193242 -437.15007)
			(xy 342.212857 -437.164312) (xy 342.22711 -437.183918) (xy 342.234604 -437.20697) (xy 342.235028 -437.21909)
			(xy 342.235028 -438.089802) (xy 343.137998 -438.089802) (xy 343.138091 -438.075228) (xy 343.139744 -438.046127)
			(xy 343.1413 -438.031636) (xy 343.1413 -436.948072) (xy 343.139755 -436.93358) (xy 343.138103 -436.90448)
			(xy 343.137998 -436.889906) (xy 343.138091 -436.875332) (xy 343.139744 -436.846231) (xy 343.1413 -436.83174)
			(xy 343.1413 -436.219092) (xy 343.141709 -436.206983) (xy 343.149211 -436.183955) (xy 343.163474 -436.164382)
			(xy 343.183097 -436.150188) (xy 343.206151 -436.142767) (xy 343.218262 -436.142384) (xy 344.158062 -436.142384)
			(xy 344.170154 -436.142841) (xy 344.193161 -436.150292) (xy 344.212745 -436.16448) (xy 344.226995 -436.184019)
			(xy 344.234521 -436.207002) (xy 344.235024 -436.219092) (xy 344.235024 -438.760616) (xy 344.234598 -438.772723)
			(xy 344.227097 -438.795747) (xy 344.212837 -438.815318) (xy 344.193219 -438.829513) (xy 344.170171 -438.836937)
			(xy 344.158062 -438.837324) (xy 343.218262 -438.837324) (xy 343.206167 -438.836924) (xy 343.183159 -438.829453)
			(xy 343.163577 -438.81525) (xy 343.149329 -438.795701) (xy 343.141804 -438.77271) (xy 343.1413 -438.760616)
			(xy 343.1413 -438.147968) (xy 343.139755 -438.133476) (xy 343.138103 -438.104376) (xy 343.137998 -438.089802)
			(xy 342.235028 -438.089802) (xy 342.235028 -439.0898) (xy 345.137994 -439.0898) (xy 345.138086 -439.075226)
			(xy 345.13974 -439.046125) (xy 345.141296 -439.031634) (xy 345.141296 -437.94807) (xy 345.139752 -437.933578)
			(xy 345.138099 -437.904478) (xy 345.137994 -437.889904) (xy 345.138087 -437.87533) (xy 345.13974 -437.846229)
			(xy 345.141296 -437.831738) (xy 345.141296 -437.21909) (xy 345.141803 -437.206979) (xy 345.149288 -437.183943)
			(xy 345.163522 -437.164345) (xy 345.183114 -437.150102) (xy 345.206147 -437.142608) (xy 345.218258 -437.142128)
			(xy 346.158058 -437.142128) (xy 346.170178 -437.142595) (xy 346.193233 -437.150075) (xy 346.212848 -437.164315)
			(xy 346.227101 -437.18392) (xy 346.234596 -437.206971) (xy 346.23502 -437.21909) (xy 346.23502 -439.760614)
			(xy 346.234651 -439.772742) (xy 346.22715 -439.795808) (xy 346.212886 -439.815426) (xy 346.193258 -439.829675)
			(xy 346.170186 -439.83716) (xy 346.158058 -439.837576) (xy 345.218258 -439.837576) (xy 345.206143 -439.837124)
			(xy 345.1831 -439.829627) (xy 345.163501 -439.815379) (xy 345.14926 -439.795774) (xy 345.141771 -439.77273)
			(xy 345.141296 -439.760614) (xy 345.141296 -439.147966) (xy 345.139751 -439.133474) (xy 345.138099 -439.104374)
			(xy 345.137994 -439.0898) (xy 342.235028 -439.0898) (xy 342.235028 -439.760614) (xy 342.234651 -439.772741)
			(xy 342.227151 -439.795806) (xy 342.212889 -439.815424) (xy 342.193263 -439.829673) (xy 342.170193 -439.837159)
			(xy 342.158066 -439.837576) (xy 341.218266 -439.837576) (xy 341.206151 -439.837118) (xy 341.183109 -439.829623)
			(xy 341.163509 -439.815377) (xy 341.149268 -439.795773) (xy 341.141779 -439.772729) (xy 341.141304 -439.760614)
			(xy 341.141304 -439.147966) (xy 341.139759 -439.133474) (xy 341.138107 -439.104374) (xy 341.138002 -439.0898)
			(xy 338.235036 -439.0898) (xy 338.235036 -439.760614) (xy 338.234651 -439.77274) (xy 338.227152 -439.795804)
			(xy 338.212892 -439.815421) (xy 338.193268 -439.82967) (xy 338.1702 -439.837158) (xy 338.158074 -439.837576)
			(xy 337.218274 -439.837576) (xy 337.206159 -439.837111) (xy 337.183118 -439.829618) (xy 337.163518 -439.815374)
			(xy 337.149276 -439.795772) (xy 337.141787 -439.772729) (xy 337.141312 -439.760614) (xy 337.141312 -439.147966)
			(xy 337.139767 -439.133474) (xy 337.138115 -439.104374) (xy 337.13801 -439.0898) (xy 334.235044 -439.0898)
			(xy 334.235044 -439.760614) (xy 334.234651 -439.772739) (xy 334.227153 -439.795802) (xy 334.212895 -439.815418)
			(xy 334.193273 -439.829668) (xy 334.170207 -439.837157) (xy 334.158082 -439.837576) (xy 333.218282 -439.837576)
			(xy 333.206168 -439.837104) (xy 333.183126 -439.829614) (xy 333.163526 -439.815371) (xy 333.149285 -439.79577)
			(xy 333.141795 -439.772728) (xy 333.14132 -439.760614) (xy 333.14132 -439.147966) (xy 333.139775 -439.133474)
			(xy 333.138123 -439.104374) (xy 333.138018 -439.0898) (xy 329.2348 -439.0898) (xy 329.2348 -439.760614)
			(xy 329.234306 -439.7727) (xy 329.22685 -439.795695) (xy 329.212669 -439.815271) (xy 329.193144 -439.829523)
			(xy 329.170177 -439.837061) (xy 329.158092 -439.837576) (xy 328.218292 -439.837576) (xy 328.20618 -439.83719)
			(xy 328.183149 -439.829686) (xy 328.163574 -439.815417) (xy 328.14938 -439.795788) (xy 328.141964 -439.772727)
			(xy 328.141584 -439.760614) (xy 328.141584 -439.149998) (xy 328.139913 -439.135005) (xy 328.138136 -439.104886)
			(xy 328.138028 -439.0898) (xy 325.234808 -439.0898) (xy 325.234808 -439.760614) (xy 325.234306 -439.7727)
			(xy 325.226851 -439.795693) (xy 325.212672 -439.815268) (xy 325.193149 -439.82952) (xy 325.170184 -439.83706)
			(xy 325.1581 -439.837576) (xy 324.2183 -439.837576) (xy 324.206189 -439.837184) (xy 324.183157 -439.829681)
			(xy 324.163582 -439.815414) (xy 324.149388 -439.795786) (xy 324.141972 -439.772727) (xy 324.141592 -439.760614)
			(xy 324.141592 -439.149998) (xy 324.139921 -439.135005) (xy 324.138144 -439.104886) (xy 324.138036 -439.0898)
			(xy 321.234816 -439.0898) (xy 321.234816 -439.760614) (xy 321.234404 -439.772709) (xy 321.226938 -439.795717)
			(xy 321.212739 -439.815301) (xy 321.193191 -439.829549) (xy 321.170201 -439.837073) (xy 321.158108 -439.837576)
			(xy 320.218308 -439.837576) (xy 320.206197 -439.837177) (xy 320.183166 -439.829677) (xy 320.163591 -439.815412)
			(xy 320.149396 -439.795785) (xy 320.14198 -439.772726) (xy 320.1416 -439.760614) (xy 320.1416 -439.149998)
			(xy 320.139929 -439.135005) (xy 320.138152 -439.104886) (xy 320.138044 -439.0898) (xy 317.234824 -439.0898)
			(xy 317.234824 -439.760614) (xy 317.234404 -439.772708) (xy 317.226939 -439.795715) (xy 317.212742 -439.815298)
			(xy 317.193196 -439.829547) (xy 317.170209 -439.837072) (xy 317.158116 -439.837576) (xy 316.218316 -439.837576)
			(xy 316.206206 -439.83717) (xy 316.183175 -439.829672) (xy 316.163599 -439.815408) (xy 316.149405 -439.795783)
			(xy 316.141988 -439.772726) (xy 316.141608 -439.760614) (xy 316.141608 -439.149998) (xy 316.139937 -439.135005)
			(xy 316.13816 -439.104886) (xy 316.138052 -439.0898) (xy 310.60136 -439.0898) (xy 310.60136 -440.045348)
			(xy 311.021984 -440.465972) (xy 314.13831 -440.465972) (xy 314.144152 -440.42203) (xy 314.148881 -440.390461)
			(xy 314.165184 -440.328742) (xy 314.189054 -440.269538) (xy 314.22012 -440.213771) (xy 314.257897 -440.162313)
			(xy 314.301794 -440.115967) (xy 314.351127 -440.075455) (xy 314.405126 -440.04141) (xy 314.462949 -440.014364)
			(xy 314.523693 -439.994738) (xy 314.586409 -439.982838) (xy 314.65012 -439.978851) (xy 314.713831 -439.982838)
			(xy 314.776547 -439.994738) (xy 314.837291 -440.014364) (xy 314.895114 -440.04141) (xy 314.949113 -440.075455)
			(xy 314.998446 -440.115967) (xy 315.042343 -440.162313) (xy 315.08012 -440.213771) (xy 315.111186 -440.269538)
			(xy 315.135056 -440.328742) (xy 315.151359 -440.390461) (xy 315.156088 -440.42203) (xy 315.16193 -440.465972)
			(xy 318.138302 -440.465972) (xy 318.144144 -440.42203) (xy 318.148873 -440.390461) (xy 318.165176 -440.328742)
			(xy 318.189046 -440.269538) (xy 318.220112 -440.213771) (xy 318.257889 -440.162313) (xy 318.301786 -440.115967)
			(xy 318.351119 -440.075455) (xy 318.405118 -440.04141) (xy 318.462941 -440.014364) (xy 318.523685 -439.994738)
			(xy 318.586401 -439.982838) (xy 318.650112 -439.978851) (xy 318.713823 -439.982838) (xy 318.776539 -439.994738)
			(xy 318.837283 -440.014364) (xy 318.895106 -440.04141) (xy 318.949105 -440.075455) (xy 318.998438 -440.115967)
			(xy 319.042335 -440.162313) (xy 319.080112 -440.213771) (xy 319.111178 -440.269538) (xy 319.135048 -440.328742)
			(xy 319.151351 -440.390461) (xy 319.15608 -440.42203) (xy 319.161922 -440.465972) (xy 322.138294 -440.465972)
			(xy 322.144136 -440.42203) (xy 322.148865 -440.390461) (xy 322.165168 -440.328742) (xy 322.189038 -440.269538)
			(xy 322.220104 -440.213771) (xy 322.257881 -440.162313) (xy 322.301778 -440.115967) (xy 322.351111 -440.075455)
			(xy 322.40511 -440.04141) (xy 322.462933 -440.014364) (xy 322.523677 -439.994738) (xy 322.586393 -439.982838)
			(xy 322.650104 -439.978851) (xy 322.713815 -439.982838) (xy 322.776531 -439.994738) (xy 322.837275 -440.014364)
			(xy 322.895098 -440.04141) (xy 322.949097 -440.075455) (xy 322.99843 -440.115967) (xy 323.042327 -440.162313)
			(xy 323.080104 -440.213771) (xy 323.11117 -440.269538) (xy 323.13504 -440.328742) (xy 323.151343 -440.390461)
			(xy 323.156072 -440.42203) (xy 323.161914 -440.465972) (xy 326.138286 -440.465972) (xy 326.144128 -440.42203)
			(xy 326.148857 -440.390461) (xy 326.16516 -440.328742) (xy 326.18903 -440.269538) (xy 326.220096 -440.213771)
			(xy 326.257873 -440.162313) (xy 326.30177 -440.115967) (xy 326.351103 -440.075455) (xy 326.405102 -440.04141)
			(xy 326.462925 -440.014364) (xy 326.523669 -439.994738) (xy 326.586385 -439.982838) (xy 326.650096 -439.978851)
			(xy 326.713807 -439.982838) (xy 326.776523 -439.994738) (xy 326.837267 -440.014364) (xy 326.89509 -440.04141)
			(xy 326.949089 -440.075455) (xy 326.998422 -440.115967) (xy 327.042319 -440.162313) (xy 327.080096 -440.213771)
			(xy 327.111162 -440.269538) (xy 327.135032 -440.328742) (xy 327.151335 -440.390461) (xy 327.156064 -440.42203)
			(xy 327.161906 -440.465972) (xy 331.138276 -440.465972) (xy 331.144118 -440.42203) (xy 331.148847 -440.390461)
			(xy 331.16515 -440.328742) (xy 331.18902 -440.269538) (xy 331.220086 -440.213771) (xy 331.257863 -440.162313)
			(xy 331.30176 -440.115967) (xy 331.351093 -440.075455) (xy 331.405092 -440.04141) (xy 331.462915 -440.014364)
			(xy 331.523659 -439.994738) (xy 331.586375 -439.982838) (xy 331.650086 -439.978851) (xy 331.713797 -439.982838)
			(xy 331.776513 -439.994738) (xy 331.837257 -440.014364) (xy 331.89508 -440.04141) (xy 331.949079 -440.075455)
			(xy 331.998412 -440.115967) (xy 332.042309 -440.162313) (xy 332.080086 -440.213771) (xy 332.111152 -440.269538)
			(xy 332.135022 -440.328742) (xy 332.151325 -440.390461) (xy 332.156054 -440.42203) (xy 332.161896 -440.465972)
			(xy 335.138268 -440.465972) (xy 335.14411 -440.42203) (xy 335.148839 -440.390461) (xy 335.165142 -440.328742)
			(xy 335.189012 -440.269538) (xy 335.220078 -440.213771) (xy 335.257855 -440.162313) (xy 335.301752 -440.115967)
			(xy 335.351085 -440.075455) (xy 335.405084 -440.04141) (xy 335.462907 -440.014364) (xy 335.523651 -439.994738)
			(xy 335.586367 -439.982838) (xy 335.650078 -439.978851) (xy 335.713789 -439.982838) (xy 335.776505 -439.994738)
			(xy 335.837249 -440.014364) (xy 335.895072 -440.04141) (xy 335.949071 -440.075455) (xy 335.998404 -440.115967)
			(xy 336.042301 -440.162313) (xy 336.080078 -440.213771) (xy 336.111144 -440.269538) (xy 336.135014 -440.328742)
			(xy 336.151317 -440.390461) (xy 336.156046 -440.42203) (xy 336.161888 -440.465972) (xy 339.13826 -440.465972)
			(xy 339.144102 -440.42203) (xy 339.148831 -440.390461) (xy 339.165134 -440.328742) (xy 339.189004 -440.269538)
			(xy 339.22007 -440.213771) (xy 339.257847 -440.162313) (xy 339.301744 -440.115967) (xy 339.351077 -440.075455)
			(xy 339.405076 -440.04141) (xy 339.462899 -440.014364) (xy 339.523643 -439.994738) (xy 339.586359 -439.982838)
			(xy 339.65007 -439.978851) (xy 339.713781 -439.982838) (xy 339.776497 -439.994738) (xy 339.837241 -440.014364)
			(xy 339.895064 -440.04141) (xy 339.949063 -440.075455) (xy 339.998396 -440.115967) (xy 340.042293 -440.162313)
			(xy 340.08007 -440.213771) (xy 340.111136 -440.269538) (xy 340.135006 -440.328742) (xy 340.151309 -440.390461)
			(xy 340.156038 -440.42203) (xy 340.16188 -440.465972) (xy 343.138252 -440.465972) (xy 343.144094 -440.42203)
			(xy 343.148823 -440.390461) (xy 343.165126 -440.328742) (xy 343.188996 -440.269538) (xy 343.220062 -440.213771)
			(xy 343.257839 -440.162313) (xy 343.301736 -440.115967) (xy 343.351069 -440.075455) (xy 343.405068 -440.04141)
			(xy 343.462891 -440.014364) (xy 343.523635 -439.994738) (xy 343.586351 -439.982838) (xy 343.650062 -439.978851)
			(xy 343.713773 -439.982838) (xy 343.776489 -439.994738) (xy 343.837233 -440.014364) (xy 343.895056 -440.04141)
			(xy 343.949055 -440.075455) (xy 343.998388 -440.115967) (xy 344.042285 -440.162313) (xy 344.080062 -440.213771)
			(xy 344.111128 -440.269538) (xy 344.134998 -440.328742) (xy 344.151301 -440.390461) (xy 344.15603 -440.42203)
			(xy 344.161872 -440.465972) (xy 356.237032 -440.465972) (xy 356.237032 -433.027582) (xy 356.198836 -432.945331)
			(xy 356.129188 -432.777865) (xy 356.067377 -432.607352) (xy 356.013535 -432.434156) (xy 355.96778 -432.258651)
			(xy 355.930209 -432.081214) (xy 355.900903 -431.902226) (xy 355.879924 -431.722072) (xy 355.867319 -431.541139)
			(xy 355.863113 -431.359816) (xy 355.867317 -431.178494) (xy 355.879921 -430.997561) (xy 355.900898 -430.817407)
			(xy 355.930203 -430.638418) (xy 355.967773 -430.460981) (xy 356.013526 -430.285475) (xy 356.067366 -430.112279)
			(xy 356.129176 -429.941765) (xy 356.198823 -429.774299) (xy 356.237032 -429.692054) (xy 356.237032 -420.841932)
			(xy 363.296708 -420.841932) (xy 363.296708 -424.470068) (xy 421.270176 -424.470068) (xy 421.270176 -417.770056)
			(xy 421.270681 -417.664527) (xy 421.278765 -417.453623) (xy 421.294922 -417.243184) (xy 421.319127 -417.033518)
			(xy 421.351345 -416.824934) (xy 421.391528 -416.617736) (xy 421.439619 -416.412229) (xy 421.495545 -416.208716)
			(xy 421.559226 -416.007493) (xy 421.630567 -415.808858) (xy 421.709464 -415.613101) (xy 421.795802 -415.420509)
			(xy 421.889452 -415.231366) (xy 421.990279 -415.045949) (xy 422.098134 -414.864529) (xy 422.212858 -414.687374)
			(xy 422.334284 -414.514743) (xy 422.462233 -414.34689) (xy 422.596517 -414.184061) (xy 422.73694 -414.026495)
			(xy 422.883295 -413.874423) (xy 423.035367 -413.728068) (xy 423.192933 -413.587645) (xy 423.355762 -413.453361)
			(xy 423.523615 -413.325412) (xy 423.696246 -413.203986) (xy 423.873401 -413.089262) (xy 424.054821 -412.981407)
			(xy 424.240238 -412.88058) (xy 424.429381 -412.78693) (xy 424.621973 -412.700592) (xy 424.81773 -412.621695)
			(xy 425.016365 -412.550354) (xy 425.217588 -412.486673) (xy 425.421101 -412.430747) (xy 425.626608 -412.382656)
			(xy 425.833806 -412.342473) (xy 426.04239 -412.310255) (xy 426.252056 -412.28605) (xy 426.462495 -412.269893)
			(xy 426.673399 -412.261809) (xy 426.884457 -412.261809) (xy 427.095361 -412.269893) (xy 427.3058 -412.28605)
			(xy 427.515466 -412.310255) (xy 427.72405 -412.342473) (xy 427.931248 -412.382656) (xy 428.136755 -412.430747)
			(xy 428.340268 -412.486673) (xy 428.541491 -412.550354) (xy 428.740126 -412.621695) (xy 428.935883 -412.700592)
			(xy 429.128475 -412.78693) (xy 429.317618 -412.88058) (xy 429.503035 -412.981407) (xy 429.684455 -413.089262)
			(xy 429.86161 -413.203986) (xy 430.034241 -413.325412) (xy 430.202094 -413.453361) (xy 430.364923 -413.587645)
			(xy 430.522489 -413.728068) (xy 430.674561 -413.874423) (xy 430.820916 -414.026495) (xy 430.961339 -414.184061)
			(xy 431.095623 -414.34689) (xy 431.223572 -414.514743) (xy 431.344998 -414.687374) (xy 431.459722 -414.864529)
			(xy 431.567577 -415.045949) (xy 431.668404 -415.231366) (xy 431.762054 -415.420509) (xy 431.848392 -415.613101)
			(xy 431.927289 -415.808858) (xy 431.99863 -416.007493) (xy 432.062311 -416.208716) (xy 432.118237 -416.412229)
			(xy 432.166328 -416.617736) (xy 432.206511 -416.824934) (xy 432.238729 -417.033518) (xy 432.262934 -417.243184)
			(xy 432.279091 -417.453623) (xy 432.287175 -417.664527) (xy 432.28768 -417.770056) (xy 432.28768 -424.470068)
			(xy 432.287175 -424.575597) (xy 432.279091 -424.786501) (xy 432.262934 -424.99694) (xy 432.238729 -425.206606)
			(xy 432.206511 -425.41519) (xy 432.166328 -425.622388) (xy 432.118237 -425.827895) (xy 432.062311 -426.031408)
			(xy 431.99863 -426.232631) (xy 431.927289 -426.431266) (xy 431.848392 -426.627023) (xy 431.762054 -426.819615)
			(xy 431.668404 -427.008758) (xy 431.567577 -427.194175) (xy 431.459722 -427.375595) (xy 431.344998 -427.55275)
			(xy 431.223572 -427.725381) (xy 431.095623 -427.893234) (xy 430.961339 -428.056063) (xy 430.820916 -428.213629)
			(xy 430.674561 -428.365701) (xy 430.522489 -428.512056) (xy 430.364923 -428.652479) (xy 430.202094 -428.786763)
			(xy 430.034241 -428.914712) (xy 429.86161 -429.036138) (xy 429.684455 -429.150862) (xy 429.503035 -429.258717)
			(xy 429.317618 -429.359544) (xy 429.128475 -429.453194) (xy 428.935883 -429.539532) (xy 428.740126 -429.618429)
			(xy 428.541491 -429.68977) (xy 428.340268 -429.753451) (xy 428.136755 -429.809377) (xy 427.931248 -429.857468)
			(xy 427.72405 -429.897651) (xy 427.515466 -429.929869) (xy 427.3058 -429.954074) (xy 427.095361 -429.970231)
			(xy 426.884457 -429.978315) (xy 426.673399 -429.978315) (xy 426.462495 -429.970231) (xy 426.252056 -429.954074)
			(xy 426.04239 -429.929869) (xy 425.833806 -429.897651) (xy 425.626608 -429.857468) (xy 425.421101 -429.809377)
			(xy 425.217588 -429.753451) (xy 425.016365 -429.68977) (xy 424.81773 -429.618429) (xy 424.621973 -429.539532)
			(xy 424.429381 -429.453194) (xy 424.240238 -429.359544) (xy 424.054821 -429.258717) (xy 423.873401 -429.150862)
			(xy 423.696246 -429.036138) (xy 423.523615 -428.914712) (xy 423.355762 -428.786763) (xy 423.192933 -428.652479)
			(xy 423.035367 -428.512056) (xy 422.883295 -428.365701) (xy 422.73694 -428.213629) (xy 422.596517 -428.056063)
			(xy 422.462233 -427.893234) (xy 422.334284 -427.725381) (xy 422.212858 -427.55275) (xy 422.098134 -427.375595)
			(xy 421.990279 -427.194175) (xy 421.889452 -427.008758) (xy 421.795802 -426.819615) (xy 421.709464 -426.627023)
			(xy 421.630567 -426.431266) (xy 421.559226 -426.232631) (xy 421.495545 -426.031408) (xy 421.439619 -425.827895)
			(xy 421.391528 -425.622388) (xy 421.351345 -425.41519) (xy 421.319127 -425.206606) (xy 421.294922 -424.99694)
			(xy 421.278765 -424.786501) (xy 421.270681 -424.575597) (xy 421.270176 -424.470068) (xy 363.296708 -424.470068)
			(xy 363.296708 -427.289976) (xy 381.237998 -427.289976) (xy 381.238088 -427.275402) (xy 381.239743 -427.246301)
			(xy 381.2413 -427.23181) (xy 381.2413 -426.147992) (xy 381.239757 -426.1335) (xy 381.238104 -426.1044)
			(xy 381.237998 -426.089826) (xy 381.238093 -426.075252) (xy 381.239744 -426.046151) (xy 381.2413 -426.03166)
			(xy 381.2413 -425.419012) (xy 381.241727 -425.406904) (xy 381.249223 -425.383877) (xy 381.263482 -425.364304)
			(xy 381.283101 -425.350109) (xy 381.306152 -425.342688) (xy 381.318262 -425.342304) (xy 382.258062 -425.342304)
			(xy 382.270146 -425.342839) (xy 382.293139 -425.350281) (xy 382.312717 -425.364451) (xy 382.32697 -425.383968)
			(xy 382.334509 -425.40693) (xy 382.335024 -425.419012) (xy 382.335024 -427.960536) (xy 382.334615 -427.972644)
			(xy 382.327108 -427.995669) (xy 382.312844 -428.015239) (xy 382.293223 -428.029433) (xy 382.270172 -428.036857)
			(xy 382.258062 -428.037244) (xy 381.318262 -428.037244) (xy 381.306169 -428.036825) (xy 381.283164 -428.029356)
			(xy 381.263584 -428.015157) (xy 381.249335 -427.995613) (xy 381.241807 -427.972628) (xy 381.2413 -427.960536)
			(xy 381.2413 -427.348142) (xy 381.239753 -427.33365) (xy 381.238103 -427.30455) (xy 381.237998 -427.289976)
			(xy 363.296708 -427.289976) (xy 363.296708 -428.28972) (xy 383.237994 -428.28972) (xy 383.238088 -428.275146)
			(xy 383.23974 -428.246045) (xy 383.241296 -428.231554) (xy 383.241296 -427.14799) (xy 383.239753 -427.133498)
			(xy 383.2381 -427.104398) (xy 383.237994 -427.089824) (xy 383.238088 -427.07525) (xy 383.23974 -427.046149)
			(xy 383.241296 -427.031658) (xy 383.241296 -426.41901) (xy 383.24182 -426.4069) (xy 383.249299 -426.383864)
			(xy 383.263529 -426.364266) (xy 383.283118 -426.350023) (xy 383.306148 -426.342528) (xy 383.318258 -426.342048)
			(xy 384.258058 -426.342048) (xy 384.27018 -426.342496) (xy 384.293239 -426.349978) (xy 384.312855 -426.364222)
			(xy 384.327108 -426.383833) (xy 384.334599 -426.406889) (xy 384.33502 -426.41901) (xy 384.33502 -427.289976)
			(xy 385.23799 -427.289976) (xy 385.23808 -427.275402) (xy 385.239735 -427.246301) (xy 385.241292 -427.23181)
			(xy 385.241292 -426.147992) (xy 385.239749 -426.1335) (xy 385.238096 -426.1044) (xy 385.23799 -426.089826)
			(xy 385.238085 -426.075252) (xy 385.239736 -426.046151) (xy 385.241292 -426.03166) (xy 385.241292 -425.419012)
			(xy 385.241727 -425.406905) (xy 385.249222 -425.383879) (xy 385.263479 -425.364307) (xy 385.283096 -425.350111)
			(xy 385.306145 -425.342689) (xy 385.318254 -425.342304) (xy 386.258054 -425.342304) (xy 386.270138 -425.342846)
			(xy 386.293131 -425.350286) (xy 386.312708 -425.364454) (xy 386.326962 -425.38397) (xy 386.334501 -425.40693)
			(xy 386.335016 -425.419012) (xy 386.335016 -427.960536) (xy 386.334615 -427.972645) (xy 386.327107 -427.995671)
			(xy 386.312841 -428.015242) (xy 386.293218 -428.029436) (xy 386.270165 -428.036859) (xy 386.258054 -428.037244)
			(xy 385.318254 -428.037244) (xy 385.30616 -428.036832) (xy 385.283156 -428.02936) (xy 385.263575 -428.01516)
			(xy 385.249327 -427.995615) (xy 385.241799 -427.972628) (xy 385.241292 -427.960536) (xy 385.241292 -427.348142)
			(xy 385.239745 -427.33365) (xy 385.238095 -427.30455) (xy 385.23799 -427.289976) (xy 384.33502 -427.289976)
			(xy 384.33502 -428.28972) (xy 387.237986 -428.28972) (xy 387.23808 -428.275146) (xy 387.239732 -428.246045)
			(xy 387.241288 -428.231554) (xy 387.241288 -427.14799) (xy 387.239745 -427.133498) (xy 387.238092 -427.104398)
			(xy 387.237986 -427.089824) (xy 387.238081 -427.07525) (xy 387.239732 -427.046149) (xy 387.241288 -427.031658)
			(xy 387.241288 -426.41901) (xy 387.24182 -426.406901) (xy 387.249298 -426.383867) (xy 387.263526 -426.364269)
			(xy 387.283113 -426.350025) (xy 387.306141 -426.342529) (xy 387.31825 -426.342048) (xy 388.25805 -426.342048)
			(xy 388.270168 -426.342469) (xy 388.293215 -426.349972) (xy 388.312816 -426.364226) (xy 388.327056 -426.383839)
			(xy 388.33454 -426.406891) (xy 388.335012 -426.41901) (xy 388.335012 -427.289976) (xy 389.237982 -427.289976)
			(xy 389.238072 -427.275402) (xy 389.239727 -427.246301) (xy 389.241284 -427.23181) (xy 389.241284 -426.147992)
			(xy 389.239741 -426.1335) (xy 389.238088 -426.1044) (xy 389.237982 -426.089826) (xy 389.238077 -426.075252)
			(xy 389.239728 -426.046151) (xy 389.241284 -426.03166) (xy 389.241284 -425.419012) (xy 389.241727 -425.406905)
			(xy 389.249221 -425.383881) (xy 389.263476 -425.364309) (xy 389.283091 -425.350114) (xy 389.306138 -425.34269)
			(xy 389.318246 -425.342304) (xy 390.258046 -425.342304) (xy 390.270134 -425.342767) (xy 390.29313 -425.350232)
			(xy 390.312707 -425.364421) (xy 390.326957 -425.383953) (xy 390.334494 -425.406925) (xy 390.335008 -425.419012)
			(xy 390.335008 -427.960536) (xy 390.334614 -427.972646) (xy 390.327106 -427.995673) (xy 390.312838 -428.015245)
			(xy 390.293213 -428.029438) (xy 390.270157 -428.03686) (xy 390.258046 -428.037244) (xy 389.318246 -428.037244)
			(xy 389.306157 -428.036753) (xy 389.283155 -428.029307) (xy 389.263573 -428.015127) (xy 389.249322 -427.995597)
			(xy 389.241791 -427.972623) (xy 389.241284 -427.960536) (xy 389.241284 -427.348142) (xy 389.239737 -427.33365)
			(xy 389.238087 -427.30455) (xy 389.237982 -427.289976) (xy 388.335012 -427.289976) (xy 388.335012 -428.28972)
			(xy 391.237978 -428.28972) (xy 391.238072 -428.275146) (xy 391.239724 -428.246045) (xy 391.24128 -428.231554)
			(xy 391.24128 -427.14799) (xy 391.239737 -427.133498) (xy 391.238084 -427.104398) (xy 391.237978 -427.089824)
			(xy 391.238073 -427.07525) (xy 391.239724 -427.046149) (xy 391.24128 -427.031658) (xy 391.24128 -426.41901)
			(xy 391.241669 -426.406884) (xy 391.249164 -426.383818) (xy 391.263422 -426.364199) (xy 391.283047 -426.349949)
			(xy 391.306115 -426.342464) (xy 391.318242 -426.342048) (xy 392.258042 -426.342048) (xy 392.27016 -426.342476)
			(xy 392.293206 -426.349976) (xy 392.312808 -426.364229) (xy 392.327048 -426.383841) (xy 392.334532 -426.406892)
			(xy 392.335004 -426.41901) (xy 392.335004 -427.289976) (xy 393.237974 -427.289976) (xy 393.238064 -427.275402)
			(xy 393.239719 -427.246301) (xy 393.241276 -427.23181) (xy 393.241276 -426.147992) (xy 393.239733 -426.1335)
			(xy 393.23808 -426.1044) (xy 393.237974 -426.089826) (xy 393.238069 -426.075252) (xy 393.23972 -426.046151)
			(xy 393.241276 -426.03166) (xy 393.241276 -425.419012) (xy 393.241726 -425.406906) (xy 393.24922 -425.383883)
			(xy 393.263473 -425.364312) (xy 393.283086 -425.350116) (xy 393.306131 -425.342691) (xy 393.318238 -425.342304)
			(xy 394.258038 -425.342304) (xy 394.270126 -425.342774) (xy 394.293122 -425.350237) (xy 394.312698 -425.364424)
			(xy 394.326949 -425.383954) (xy 394.334486 -425.406926) (xy 394.335 -425.419012) (xy 394.335 -427.960536)
			(xy 394.334614 -427.972647) (xy 394.327105 -427.995675) (xy 394.312835 -428.015248) (xy 394.293208 -428.029441)
			(xy 394.27015 -428.036861) (xy 394.258038 -428.037244) (xy 393.318238 -428.037244) (xy 393.306149 -428.03676)
			(xy 393.283147 -428.029312) (xy 393.263565 -428.01513) (xy 393.249314 -427.995599) (xy 393.241783 -427.972623)
			(xy 393.241276 -427.960536) (xy 393.241276 -427.348142) (xy 393.239729 -427.33365) (xy 393.238079 -427.30455)
			(xy 393.237974 -427.289976) (xy 392.335004 -427.289976) (xy 392.335004 -428.28972) (xy 395.23797 -428.28972)
			(xy 395.238064 -428.275146) (xy 395.239716 -428.246045) (xy 395.241272 -428.231554) (xy 395.241272 -427.14799)
			(xy 395.239729 -427.133498) (xy 395.238076 -427.104398) (xy 395.23797 -427.089824) (xy 395.238065 -427.07525)
			(xy 395.239716 -427.046149) (xy 395.241272 -427.031658) (xy 395.241272 -426.41901) (xy 395.241669 -426.406884)
			(xy 395.249163 -426.38382) (xy 395.263419 -426.364202) (xy 395.283042 -426.349952) (xy 395.306108 -426.342465)
			(xy 395.318234 -426.342048) (xy 396.258034 -426.342048) (xy 396.270151 -426.342483) (xy 396.293197 -426.349981)
			(xy 396.312799 -426.364232) (xy 396.327039 -426.383842) (xy 396.334524 -426.406892) (xy 396.334996 -426.41901)
			(xy 396.334996 -427.289976) (xy 398.237964 -427.289976) (xy 398.238078 -427.274891) (xy 398.239856 -427.244772)
			(xy 398.24152 -427.229778) (xy 398.24152 -426.150024) (xy 398.239851 -426.135031) (xy 398.238073 -426.104912)
			(xy 398.237964 -426.089826) (xy 398.238074 -426.07474) (xy 398.239855 -426.044622) (xy 398.24152 -426.029628)
			(xy 398.24152 -425.419012) (xy 398.241924 -425.406927) (xy 398.249391 -425.38394) (xy 398.263599 -425.364387)
			(xy 398.283154 -425.350184) (xy 398.306143 -425.342721) (xy 398.318228 -425.342304) (xy 399.258028 -425.342304)
			(xy 399.270105 -425.34274) (xy 399.293075 -425.350212) (xy 399.312613 -425.364415) (xy 399.326806 -425.38396)
			(xy 399.334266 -425.406935) (xy 399.334736 -425.419012) (xy 399.334736 -427.960536) (xy 399.334267 -427.97261)
			(xy 399.326798 -427.995573) (xy 399.312602 -428.015107) (xy 399.293066 -428.029302) (xy 399.270102 -428.036768)
			(xy 399.258028 -428.037244) (xy 398.318228 -428.037244) (xy 398.306158 -428.036713) (xy 398.283198 -428.029262)
			(xy 398.263664 -428.015082) (xy 398.249467 -427.995559) (xy 398.241997 -427.972605) (xy 398.24152 -427.960536)
			(xy 398.24152 -427.350174) (xy 398.239856 -427.33518) (xy 398.238074 -427.305062) (xy 398.237964 -427.289976)
			(xy 396.334996 -427.289976) (xy 396.334996 -428.28972) (xy 400.23796 -428.28972) (xy 400.238069 -428.274634)
			(xy 400.239851 -428.244516) (xy 400.241516 -428.229522) (xy 400.241516 -427.150022) (xy 400.239847 -427.135029)
			(xy 400.238069 -427.10491) (xy 400.23796 -427.089824) (xy 400.23807 -427.074738) (xy 400.239851 -427.04462)
			(xy 400.241516 -427.029626) (xy 400.241516 -426.41901) (xy 400.242016 -426.406923) (xy 400.249467 -426.383927)
			(xy 400.263646 -426.364349) (xy 400.283171 -426.350097) (xy 400.306139 -426.342561) (xy 400.318224 -426.342048)
			(xy 401.258024 -426.342048) (xy 401.270129 -426.342495) (xy 401.293148 -426.349995) (xy 401.312716 -426.36425)
			(xy 401.326912 -426.383862) (xy 401.334341 -426.406904) (xy 401.334732 -426.41901) (xy 401.334732 -427.289976)
			(xy 402.237956 -427.289976) (xy 402.23807 -427.274891) (xy 402.239848 -427.244772) (xy 402.241512 -427.229778)
			(xy 402.241512 -426.150024) (xy 402.239843 -426.135031) (xy 402.238065 -426.104912) (xy 402.237956 -426.089826)
			(xy 402.238066 -426.07474) (xy 402.239847 -426.044622) (xy 402.241512 -426.029628) (xy 402.241512 -425.419012)
			(xy 402.241923 -425.406928) (xy 402.24939 -425.383942) (xy 402.263596 -425.36439) (xy 402.283149 -425.350186)
			(xy 402.306136 -425.342722) (xy 402.31822 -425.342304) (xy 403.25802 -425.342304) (xy 403.270097 -425.342748)
			(xy 403.293067 -425.350217) (xy 403.312604 -425.364419) (xy 403.326798 -425.383962) (xy 403.334257 -425.406935)
			(xy 403.334728 -425.419012) (xy 403.334728 -427.960536) (xy 403.334267 -427.97261) (xy 403.326797 -427.995576)
			(xy 403.312599 -428.01511) (xy 403.293061 -428.029304) (xy 403.270095 -428.036769) (xy 403.25802 -428.037244)
			(xy 402.31822 -428.037244) (xy 402.30615 -428.036719) (xy 402.28319 -428.029267) (xy 402.263655 -428.015085)
			(xy 402.249459 -427.995561) (xy 402.241989 -427.972606) (xy 402.241512 -427.960536) (xy 402.241512 -427.350174)
			(xy 402.239848 -427.33518) (xy 402.238066 -427.305062) (xy 402.237956 -427.289976) (xy 401.334732 -427.289976)
			(xy 401.334732 -428.28972) (xy 404.237952 -428.28972) (xy 404.238062 -428.274634) (xy 404.239843 -428.244516)
			(xy 404.241508 -428.229522) (xy 404.241508 -427.150022) (xy 404.239839 -427.135029) (xy 404.238061 -427.10491)
			(xy 404.237952 -427.089824) (xy 404.238062 -427.074738) (xy 404.239843 -427.04462) (xy 404.241508 -427.029626)
			(xy 404.241508 -426.41901) (xy 404.242015 -426.406924) (xy 404.249465 -426.383929) (xy 404.263643 -426.364352)
			(xy 404.283166 -426.3501) (xy 404.306132 -426.342562) (xy 404.318216 -426.342048) (xy 405.258016 -426.342048)
			(xy 405.270121 -426.342502) (xy 405.293139 -426.349999) (xy 405.312708 -426.364253) (xy 405.326904 -426.383863)
			(xy 405.334333 -426.406904) (xy 405.334724 -426.41901) (xy 405.334724 -427.289976) (xy 406.237948 -427.289976)
			(xy 406.238062 -427.274891) (xy 406.23984 -427.244772) (xy 406.241504 -427.229778) (xy 406.241504 -426.150024)
			(xy 406.239835 -426.135031) (xy 406.238057 -426.104912) (xy 406.237948 -426.089826) (xy 406.238058 -426.07474)
			(xy 406.239839 -426.044622) (xy 406.241504 -426.029628) (xy 406.241504 -425.419012) (xy 406.241923 -425.406929)
			(xy 406.249389 -425.383944) (xy 406.263593 -425.364393) (xy 406.283144 -425.350189) (xy 406.306129 -425.342723)
			(xy 406.318212 -425.342304) (xy 407.258012 -425.342304) (xy 407.270088 -425.342754) (xy 407.293058 -425.350222)
			(xy 407.312596 -425.364421) (xy 407.326789 -425.383964) (xy 407.334249 -425.406935) (xy 407.33472 -425.419012)
			(xy 407.33472 -427.960536) (xy 407.334267 -427.972611) (xy 407.326796 -427.995578) (xy 407.312596 -428.015113)
			(xy 407.293056 -428.029307) (xy 407.270087 -428.036771) (xy 407.258012 -428.037244) (xy 406.318212 -428.037244)
			(xy 406.306142 -428.036726) (xy 406.283181 -428.029271) (xy 406.263647 -428.015087) (xy 406.249451 -427.995562)
			(xy 406.241981 -427.972606) (xy 406.241504 -427.960536) (xy 406.241504 -427.350174) (xy 406.23984 -427.33518)
			(xy 406.238058 -427.305062) (xy 406.237948 -427.289976) (xy 405.334724 -427.289976) (xy 405.334724 -428.28972)
			(xy 408.237944 -428.28972) (xy 408.238054 -428.274634) (xy 408.239835 -428.244516) (xy 408.2415 -428.229522)
			(xy 408.2415 -427.150022) (xy 408.239831 -427.135029) (xy 408.238053 -427.10491) (xy 408.237944 -427.089824)
			(xy 408.238054 -427.074738) (xy 408.239835 -427.04462) (xy 408.2415 -427.029626) (xy 408.2415 -426.41901)
			(xy 408.242015 -426.406925) (xy 408.249464 -426.383931) (xy 408.26364 -426.364355) (xy 408.283161 -426.350103)
			(xy 408.306125 -426.342563) (xy 408.318208 -426.342048) (xy 409.258008 -426.342048) (xy 409.270112 -426.342509)
			(xy 409.293131 -426.350004) (xy 409.312699 -426.364256) (xy 409.326896 -426.383865) (xy 409.334325 -426.406905)
			(xy 409.334716 -426.41901) (xy 409.334716 -427.289976) (xy 410.23794 -427.289976) (xy 410.238055 -427.274891)
			(xy 410.239832 -427.244772) (xy 410.241496 -427.229778) (xy 410.241496 -426.150024) (xy 410.239827 -426.135031)
			(xy 410.238049 -426.104912) (xy 410.23794 -426.089826) (xy 410.23805 -426.07474) (xy 410.239831 -426.044622)
			(xy 410.241496 -426.029628) (xy 410.241496 -425.419012) (xy 410.241923 -425.40693) (xy 410.249388 -425.383947)
			(xy 410.26359 -425.364396) (xy 410.283139 -425.350191) (xy 410.306122 -425.342724) (xy 410.318204 -425.342304)
			(xy 411.258004 -425.342304) (xy 411.270088 -425.342709) (xy 411.293073 -425.350179) (xy 411.312624 -425.364387)
			(xy 411.326828 -425.383941) (xy 411.334293 -425.406928) (xy 411.334712 -425.419012) (xy 411.334712 -427.960536)
			(xy 411.334267 -427.972612) (xy 411.326795 -427.99558) (xy 411.312593 -428.015116) (xy 411.293051 -428.029309)
			(xy 411.27008 -428.036772) (xy 411.258004 -428.037244) (xy 410.318204 -428.037244) (xy 410.306133 -428.036733)
			(xy 410.283172 -428.029276) (xy 410.263638 -428.01509) (xy 410.249442 -427.995564) (xy 410.241973 -427.972607)
			(xy 410.241496 -427.960536) (xy 410.241496 -427.350174) (xy 410.239832 -427.33518) (xy 410.23805 -427.305062)
			(xy 410.23794 -427.289976) (xy 409.334716 -427.289976) (xy 409.334716 -428.28972) (xy 412.237936 -428.28972)
			(xy 412.238048 -428.274634) (xy 412.239829 -428.244516) (xy 412.241492 -428.229522) (xy 412.241492 -427.150022)
			(xy 412.239823 -427.135029) (xy 412.238045 -427.10491) (xy 412.237936 -427.089824) (xy 412.238048 -427.074738)
			(xy 412.239829 -427.04462) (xy 412.241492 -427.029626) (xy 412.241492 -426.41901) (xy 412.242015 -426.406926)
			(xy 412.249463 -426.383934) (xy 412.263637 -426.364358) (xy 412.283156 -426.350105) (xy 412.306118 -426.342564)
			(xy 412.3182 -426.342048) (xy 413.258 -426.342048) (xy 413.270104 -426.342515) (xy 413.293122 -426.350009)
			(xy 413.312691 -426.364259) (xy 413.326887 -426.383866) (xy 413.334317 -426.406905) (xy 413.334708 -426.41901)
			(xy 413.334708 -428.960534) (xy 413.334223 -428.972621) (xy 413.326762 -428.995614) (xy 413.312579 -429.01519)
			(xy 413.293053 -429.029441) (xy 413.270085 -429.03698) (xy 413.258 -429.037496) (xy 412.3182 -429.037496)
			(xy 412.306091 -429.037084) (xy 412.283063 -429.029584) (xy 412.263489 -429.015321) (xy 412.249295 -428.995699)
			(xy 412.241875 -428.972645) (xy 412.241492 -428.960534) (xy 412.241492 -428.349918) (xy 412.239823 -428.334925)
			(xy 412.238045 -428.304806) (xy 412.237936 -428.28972) (xy 409.334716 -428.28972) (xy 409.334716 -428.960534)
			(xy 409.334321 -428.97263) (xy 409.326849 -428.995639) (xy 409.312646 -429.015222) (xy 409.293095 -429.02947)
			(xy 409.270103 -429.036993) (xy 409.258008 -429.037496) (xy 408.318208 -429.037496) (xy 408.306099 -429.037077)
			(xy 408.283071 -429.029579) (xy 408.263498 -429.015319) (xy 408.249303 -428.995697) (xy 408.241883 -428.972644)
			(xy 408.2415 -428.960534) (xy 408.2415 -428.349918) (xy 408.239831 -428.334925) (xy 408.238053 -428.304806)
			(xy 408.237944 -428.28972) (xy 405.334724 -428.28972) (xy 405.334724 -428.960534) (xy 405.334321 -428.972629)
			(xy 405.326851 -428.995637) (xy 405.312649 -429.015219) (xy 405.2931 -429.029467) (xy 405.27011 -429.036992)
			(xy 405.258016 -429.037496) (xy 404.318216 -429.037496) (xy 404.306108 -429.03707) (xy 404.28308 -429.029574)
			(xy 404.263507 -429.015315) (xy 404.249312 -428.995695) (xy 404.241891 -428.972644) (xy 404.241508 -428.960534)
			(xy 404.241508 -428.349918) (xy 404.239839 -428.334925) (xy 404.238061 -428.304806) (xy 404.237952 -428.28972)
			(xy 401.334732 -428.28972) (xy 401.334732 -428.960534) (xy 401.334321 -428.972628) (xy 401.326852 -428.995635)
			(xy 401.312652 -429.015216) (xy 401.293105 -429.029465) (xy 401.270117 -429.036991) (xy 401.258024 -429.037496)
			(xy 400.318224 -429.037496) (xy 400.306116 -429.037063) (xy 400.283089 -429.02957) (xy 400.263515 -429.015313)
			(xy 400.24932 -428.995694) (xy 400.241899 -428.972643) (xy 400.241516 -428.960534) (xy 400.241516 -428.349918)
			(xy 400.239847 -428.334925) (xy 400.238069 -428.304806) (xy 400.23796 -428.28972) (xy 396.334996 -428.28972)
			(xy 396.334996 -428.960534) (xy 396.334518 -428.972647) (xy 396.327025 -428.995686) (xy 396.312784 -429.015284)
			(xy 396.293186 -429.029525) (xy 396.270147 -429.037018) (xy 396.258034 -429.037496) (xy 395.318234 -429.037496)
			(xy 395.306125 -429.03696) (xy 395.283088 -429.029486) (xy 395.263489 -429.01526) (xy 395.249245 -428.995673)
			(xy 395.241751 -428.972643) (xy 395.241272 -428.960534) (xy 395.241272 -428.347886) (xy 395.239729 -428.333394)
			(xy 395.238076 -428.304294) (xy 395.23797 -428.28972) (xy 392.335004 -428.28972) (xy 392.335004 -428.960534)
			(xy 392.334518 -428.972646) (xy 392.327027 -428.995683) (xy 392.312787 -429.015281) (xy 392.293191 -429.029523)
			(xy 392.270154 -429.037017) (xy 392.258042 -429.037496) (xy 391.318242 -429.037496) (xy 391.306125 -429.037005)
			(xy 391.283073 -429.029528) (xy 391.26346 -429.015294) (xy 391.249206 -428.995695) (xy 391.241707 -428.972651)
			(xy 391.24128 -428.960534) (xy 391.24128 -428.347886) (xy 391.239737 -428.333394) (xy 391.238084 -428.304294)
			(xy 391.237978 -428.28972) (xy 388.335012 -428.28972) (xy 388.335012 -428.960534) (xy 388.334518 -428.972645)
			(xy 388.327028 -428.995681) (xy 388.31279 -429.015278) (xy 388.293196 -429.02952) (xy 388.270161 -429.037016)
			(xy 388.25805 -429.037496) (xy 387.31825 -429.037496) (xy 387.306136 -429.037031) (xy 387.283097 -429.029535)
			(xy 387.263499 -429.015289) (xy 387.249258 -428.995689) (xy 387.241766 -428.972648) (xy 387.241288 -428.960534)
			(xy 387.241288 -428.347886) (xy 387.239745 -428.333394) (xy 387.238092 -428.304294) (xy 387.237986 -428.28972)
			(xy 384.33502 -428.28972) (xy 384.33502 -428.960534) (xy 384.334669 -428.972663) (xy 384.327162 -428.99573)
			(xy 384.312894 -429.015348) (xy 384.293262 -429.029597) (xy 384.270187 -429.03708) (xy 384.258058 -429.037496)
			(xy 383.318258 -429.037496) (xy 383.306145 -429.037025) (xy 383.283106 -429.02953) (xy 383.263508 -429.015287)
			(xy 383.249266 -428.995687) (xy 383.241774 -428.972647) (xy 383.241296 -428.960534) (xy 383.241296 -428.347886)
			(xy 383.239753 -428.333394) (xy 383.2381 -428.304294) (xy 383.237994 -428.28972) (xy 363.296708 -428.28972)
			(xy 363.296708 -429.659034) (xy 363.334523 -429.738474) (xy 363.403833 -429.90021) (xy 363.465799 -430.064898)
			(xy 363.520297 -430.232206) (xy 363.567215 -430.401796) (xy 363.60646 -430.573324) (xy 363.637951 -430.746444)
			(xy 363.661626 -430.920805) (xy 363.677435 -431.096053) (xy 363.685347 -431.271836) (xy 363.685346 -431.447796)
			(xy 363.677433 -431.623579) (xy 363.661622 -431.798828) (xy 363.637946 -431.973188) (xy 363.606454 -432.146307)
			(xy 363.567208 -432.317835) (xy 363.520288 -432.487425) (xy 363.465789 -432.654733) (xy 363.403821 -432.819421)
			(xy 363.33451 -432.981155) (xy 363.296708 -433.060602) (xy 363.296708 -440.465972) (xy 368.815112 -440.465972)
			(xy 368.83017 -440.465428) (xy 368.858977 -440.456641) (xy 368.88397 -440.439836) (xy 368.902975 -440.416473)
			(xy 368.914341 -440.388583) (xy 368.91708 -440.358591) (xy 368.910953 -440.329104) (xy 368.896494 -440.302685)
			(xy 368.874958 -440.281631) (xy 368.861848 -440.274202) (xy 368.771072 -440.226324) (xy 368.592892 -440.124436)
			(xy 368.418814 -440.01569) (xy 368.2491 -439.900249) (xy 368.08401 -439.778288) (xy 367.923792 -439.649994)
			(xy 367.76869 -439.51556) (xy 367.618939 -439.37519) (xy 367.474765 -439.229096) (xy 367.336389 -439.077501)
			(xy 367.204018 -438.920634) (xy 367.077855 -438.758733) (xy 366.958089 -438.592043) (xy 366.844903 -438.420818)
			(xy 366.738469 -438.245316) (xy 366.638947 -438.065804) (xy 366.546489 -437.882553) (xy 366.461235 -437.695843)
			(xy 366.383313 -437.505955) (xy 366.312843 -437.313177) (xy 366.249931 -437.117802) (xy 366.194672 -436.920127)
			(xy 366.14715 -436.72045) (xy 366.107437 -436.519074) (xy 366.075594 -436.316306) (xy 366.051668 -436.112451)
			(xy 366.035696 -435.907819) (xy 366.027702 -435.702721) (xy 366.027208 -435.600094) (xy 366.027704 -435.497868)
			(xy 366.035631 -435.293569) (xy 366.051475 -435.089731) (xy 366.075211 -434.88666) (xy 366.106802 -434.684663)
			(xy 366.146203 -434.484043) (xy 366.193353 -434.285101) (xy 366.248182 -434.088137) (xy 366.310606 -433.893447)
			(xy 366.380533 -433.701324) (xy 366.457857 -433.512058) (xy 366.542462 -433.325931) (xy 366.63422 -433.143226)
			(xy 366.732994 -432.964215) (xy 366.838635 -432.78917) (xy 366.950983 -432.618352) (xy 367.069871 -432.452019)
			(xy 367.195119 -432.290421) (xy 367.326539 -432.133801) (xy 367.463933 -431.982394) (xy 367.607094 -431.83643)
			(xy 367.755808 -431.696126) (xy 367.90985 -431.561693) (xy 368.068988 -431.433336) (xy 368.232985 -431.311245)
			(xy 368.401592 -431.195605) (xy 368.574556 -431.08659) (xy 368.751618 -430.984363) (xy 368.93251 -430.889079)
			(xy 369.11696 -430.800881) (xy 369.304692 -430.719902) (xy 369.495423 -430.646262) (xy 369.688865 -430.580074)
			(xy 369.884729 -430.521436) (xy 370.082719 -430.470437) (xy 370.282538 -430.427154) (xy 370.483884 -430.391651)
			(xy 370.686456 -430.363982) (xy 370.889949 -430.344189) (xy 371.094056 -430.332301) (xy 371.29847 -430.328337)
			(xy 371.502884 -430.332301) (xy 371.706991 -430.344189) (xy 371.910484 -430.363982) (xy 372.113056 -430.391651)
			(xy 372.314402 -430.427154) (xy 372.514221 -430.470437) (xy 372.712211 -430.521436) (xy 372.908075 -430.580074)
			(xy 373.101517 -430.646262) (xy 373.292248 -430.719902) (xy 373.47998 -430.800881) (xy 373.66443 -430.889079)
			(xy 373.666023 -430.889918) (xy 381.237998 -430.889918) (xy 381.238092 -430.875344) (xy 381.239744 -430.846243)
			(xy 381.2413 -430.831752) (xy 381.2413 -429.747934) (xy 381.239752 -429.733442) (xy 381.238102 -429.704342)
			(xy 381.237998 -429.689768) (xy 381.238096 -429.675194) (xy 381.239746 -429.646093) (xy 381.2413 -429.631602)
			(xy 381.2413 -429.018954) (xy 381.241772 -429.006841) (xy 381.249267 -428.983803) (xy 381.263511 -428.964205)
			(xy 381.28311 -428.949964) (xy 381.306149 -428.942471) (xy 381.318262 -428.941992) (xy 382.258062 -428.941992)
			(xy 382.27017 -428.942543) (xy 382.293204 -428.950015) (xy 382.312803 -428.964238) (xy 382.327047 -428.98382)
			(xy 382.334543 -429.006847) (xy 382.335024 -429.018954) (xy 382.335024 -431.560478) (xy 382.334621 -431.572603)
			(xy 382.32713 -431.595668) (xy 382.312875 -431.615287) (xy 382.293254 -431.629537) (xy 382.270187 -431.637023)
			(xy 382.258062 -431.63744) (xy 381.318262 -431.63744) (xy 381.306143 -431.63702) (xy 381.283095 -431.62952)
			(xy 381.263492 -431.615265) (xy 381.249253 -431.595651) (xy 381.24177 -431.572597) (xy 381.2413 -431.560478)
			(xy 381.2413 -430.948084) (xy 381.239756 -430.933592) (xy 381.238104 -430.904492) (xy 381.237998 -430.889918)
			(xy 373.666023 -430.889918) (xy 373.845322 -430.984363) (xy 374.022384 -431.08659) (xy 374.195348 -431.195605)
			(xy 374.363955 -431.311245) (xy 374.527952 -431.433336) (xy 374.68709 -431.561693) (xy 374.841132 -431.696126)
			(xy 374.989846 -431.83643) (xy 375.042305 -431.889916) (xy 383.237994 -431.889916) (xy 383.238088 -431.875342)
			(xy 383.23974 -431.846241) (xy 383.241296 -431.83175) (xy 383.241296 -430.747932) (xy 383.239748 -430.73344)
			(xy 383.238098 -430.70434) (xy 383.237994 -430.689766) (xy 383.238092 -430.675192) (xy 383.239742 -430.646091)
			(xy 383.241296 -430.6316) (xy 383.241296 -430.018952) (xy 383.241676 -430.006841) (xy 383.249188 -429.983813)
			(xy 383.263459 -429.964241) (xy 383.283088 -429.950048) (xy 383.306145 -429.942628) (xy 383.318258 -429.942244)
			(xy 384.258058 -429.942244) (xy 384.270146 -429.942743) (xy 384.293146 -429.950189) (xy 384.312727 -429.964367)
			(xy 384.326979 -429.983894) (xy 384.334511 -430.006866) (xy 384.33502 -430.018952) (xy 384.33502 -430.889918)
			(xy 385.23799 -430.889918) (xy 385.238084 -430.875344) (xy 385.239736 -430.846243) (xy 385.241292 -430.831752)
			(xy 385.241292 -429.747934) (xy 385.239745 -429.733442) (xy 385.238094 -429.704342) (xy 385.23799 -429.689768)
			(xy 385.238088 -429.675194) (xy 385.239738 -429.646093) (xy 385.241292 -429.631602) (xy 385.241292 -429.018954)
			(xy 385.241772 -429.006842) (xy 385.249266 -428.983805) (xy 385.263508 -428.964208) (xy 385.283105 -428.949966)
			(xy 385.306142 -428.942472) (xy 385.318254 -428.941992) (xy 386.258054 -428.941992) (xy 386.270162 -428.94255)
			(xy 386.293196 -428.950019) (xy 386.312794 -428.96424) (xy 386.327039 -428.983822) (xy 386.334535 -429.006847)
			(xy 386.335016 -429.018954) (xy 386.335016 -431.560478) (xy 386.334621 -431.572604) (xy 386.327129 -431.59567)
			(xy 386.312872 -431.61529) (xy 386.293249 -431.62954) (xy 386.27018 -431.637024) (xy 386.258054 -431.63744)
			(xy 385.318254 -431.63744) (xy 385.306135 -431.637027) (xy 385.283086 -431.629525) (xy 385.263484 -431.615268)
			(xy 385.249244 -431.595653) (xy 385.241762 -431.572598) (xy 385.241292 -431.560478) (xy 385.241292 -430.948084)
			(xy 385.239749 -430.933592) (xy 385.238096 -430.904492) (xy 385.23799 -430.889918) (xy 384.33502 -430.889918)
			(xy 384.33502 -431.889916) (xy 387.237986 -431.889916) (xy 387.23808 -431.875342) (xy 387.239732 -431.846241)
			(xy 387.241288 -431.83175) (xy 387.241288 -430.747932) (xy 387.23974 -430.73344) (xy 387.23809 -430.70434)
			(xy 387.237986 -430.689766) (xy 387.238084 -430.675192) (xy 387.239734 -430.646091) (xy 387.241288 -430.6316)
			(xy 387.241288 -430.018952) (xy 387.241675 -430.006842) (xy 387.249187 -429.983815) (xy 387.263456 -429.964244)
			(xy 387.283083 -429.95005) (xy 387.306138 -429.942629) (xy 387.31825 -429.942244) (xy 388.25805 -429.942244)
			(xy 388.270137 -429.94275) (xy 388.293137 -429.950193) (xy 388.312718 -429.96437) (xy 388.32697 -429.983896)
			(xy 388.334503 -430.006866) (xy 388.335012 -430.018952) (xy 388.335012 -430.889918) (xy 389.237982 -430.889918)
			(xy 389.238076 -430.875344) (xy 389.239728 -430.846243) (xy 389.241284 -430.831752) (xy 389.241284 -429.747934)
			(xy 389.239737 -429.733442) (xy 389.238086 -429.704342) (xy 389.237982 -429.689768) (xy 389.23808 -429.675194)
			(xy 389.23973 -429.646093) (xy 389.241284 -429.631602) (xy 389.241284 -429.018954) (xy 389.241673 -429.006832)
			(xy 389.249179 -428.98378) (xy 389.26344 -428.964175) (xy 389.283062 -428.949937) (xy 389.306124 -428.942459)
			(xy 389.318246 -428.941992) (xy 390.258046 -428.941992) (xy 390.270158 -428.942472) (xy 390.293195 -428.949966)
			(xy 390.312792 -428.964208) (xy 390.327034 -428.983805) (xy 390.334528 -429.006842) (xy 390.335008 -429.018954)
			(xy 390.335008 -431.560478) (xy 390.33447 -431.572587) (xy 390.326995 -431.595622) (xy 390.312768 -431.61522)
			(xy 390.293183 -431.629464) (xy 390.270154 -431.636959) (xy 390.258046 -431.63744) (xy 389.318246 -431.63744)
			(xy 389.306123 -431.637001) (xy 389.283062 -431.629518) (xy 389.263445 -431.615273) (xy 389.249193 -431.595659)
			(xy 389.241703 -431.5726) (xy 389.241284 -431.560478) (xy 389.241284 -430.948084) (xy 389.239741 -430.933592)
			(xy 389.238088 -430.904492) (xy 389.237982 -430.889918) (xy 388.335012 -430.889918) (xy 388.335012 -431.889916)
			(xy 391.237978 -431.889916) (xy 391.238072 -431.875342) (xy 391.239724 -431.846241) (xy 391.24128 -431.83175)
			(xy 391.24128 -430.747932) (xy 391.239732 -430.73344) (xy 391.238082 -430.70434) (xy 391.237978 -430.689766)
			(xy 391.238076 -430.675192) (xy 391.239726 -430.646091) (xy 391.24128 -430.6316) (xy 391.24128 -430.018952)
			(xy 391.241675 -430.006843) (xy 391.249186 -429.983817) (xy 391.263453 -429.964247) (xy 391.283077 -429.950053)
			(xy 391.306131 -429.94263) (xy 391.318242 -429.942244) (xy 392.258042 -429.942244) (xy 392.270134 -429.942672)
			(xy 392.293137 -429.95014) (xy 392.312716 -429.964337) (xy 392.326965 -429.983879) (xy 392.334496 -430.006861)
			(xy 392.335004 -430.018952) (xy 392.335004 -430.889918) (xy 393.237974 -430.889918) (xy 393.238068 -430.875344)
			(xy 393.23972 -430.846243) (xy 393.241276 -430.831752) (xy 393.241276 -429.747934) (xy 393.239729 -429.733442)
			(xy 393.238078 -429.704342) (xy 393.237974 -429.689768) (xy 393.238072 -429.675194) (xy 393.239722 -429.646093)
			(xy 393.241276 -429.631602) (xy 393.241276 -429.018954) (xy 393.241673 -429.006833) (xy 393.249178 -428.983782)
			(xy 393.263438 -428.964178) (xy 393.283057 -428.949939) (xy 393.306117 -428.94246) (xy 393.318238 -428.941992)
			(xy 394.258038 -428.941992) (xy 394.27015 -428.942479) (xy 394.293187 -428.949971) (xy 394.312784 -428.964211)
			(xy 394.327026 -428.983806) (xy 394.33452 -429.006842) (xy 394.335 -429.018954) (xy 394.335 -431.560478)
			(xy 394.33447 -431.572588) (xy 394.326994 -431.595624) (xy 394.312765 -431.615223) (xy 394.293177 -431.629466)
			(xy 394.270147 -431.636961) (xy 394.258038 -431.63744) (xy 393.318238 -431.63744) (xy 393.306115 -431.637007)
			(xy 393.283054 -431.629523) (xy 393.263436 -431.615275) (xy 393.249184 -431.595661) (xy 393.241695 -431.572601)
			(xy 393.241276 -431.560478) (xy 393.241276 -430.948084) (xy 393.239733 -430.933592) (xy 393.23808 -430.904492)
			(xy 393.237974 -430.889918) (xy 392.335004 -430.889918) (xy 392.335004 -431.889916) (xy 395.23797 -431.889916)
			(xy 395.238064 -431.875342) (xy 395.239716 -431.846241) (xy 395.241272 -431.83175) (xy 395.241272 -430.747932)
			(xy 395.239724 -430.73344) (xy 395.238074 -430.70434) (xy 395.23797 -430.689766) (xy 395.238068 -430.675192)
			(xy 395.239718 -430.646091) (xy 395.241272 -430.6316) (xy 395.241272 -430.018952) (xy 395.241675 -430.006843)
			(xy 395.249184 -429.983819) (xy 395.26345 -429.96425) (xy 395.283072 -429.950056) (xy 395.306124 -429.942631)
			(xy 395.318234 -429.942244) (xy 396.258034 -429.942244) (xy 396.270126 -429.942678) (xy 396.293128 -429.950145)
			(xy 396.312708 -429.96434) (xy 396.326957 -429.98388) (xy 396.334488 -430.006862) (xy 396.334996 -430.018952)
			(xy 396.334996 -430.889918) (xy 398.237964 -430.889918) (xy 398.238073 -430.874832) (xy 398.239855 -430.844714)
			(xy 398.24152 -430.82972) (xy 398.24152 -429.749966) (xy 398.239855 -429.734972) (xy 398.238074 -429.704854)
			(xy 398.237964 -429.689768) (xy 398.238078 -429.674682) (xy 398.239856 -429.644564) (xy 398.24152 -429.62957)
			(xy 398.24152 -429.018954) (xy 398.241968 -429.006864) (xy 398.249435 -428.983865) (xy 398.263627 -428.964288)
			(xy 398.283163 -428.950038) (xy 398.306139 -428.942504) (xy 398.318228 -428.941992) (xy 399.258028 -428.941992)
			(xy 399.270138 -428.942392) (xy 399.293164 -428.949899) (xy 399.312736 -428.964165) (xy 399.32693 -428.983789)
			(xy 399.334352 -429.006843) (xy 399.334736 -429.018954) (xy 399.334736 -431.560478) (xy 399.334273 -431.572569)
			(xy 399.32682 -431.595573) (xy 399.312633 -431.615155) (xy 399.293097 -431.629405) (xy 399.270117 -431.636934)
			(xy 399.258028 -431.63744) (xy 398.318228 -431.63744) (xy 398.306125 -431.63696) (xy 398.283105 -431.629473)
			(xy 398.263535 -431.615227) (xy 398.249338 -431.595621) (xy 398.241909 -431.572582) (xy 398.24152 -431.560478)
			(xy 398.24152 -430.950116) (xy 398.239851 -430.935123) (xy 398.238073 -430.905004) (xy 398.237964 -430.889918)
			(xy 396.334996 -430.889918) (xy 396.334996 -431.889916) (xy 400.23796 -431.889916) (xy 400.238069 -431.87483)
			(xy 400.239851 -431.844712) (xy 400.241516 -431.829718) (xy 400.241516 -430.749964) (xy 400.239851 -430.73497)
			(xy 400.23807 -430.704852) (xy 400.23796 -430.689766) (xy 400.238074 -430.67468) (xy 400.239852 -430.644562)
			(xy 400.241516 -430.629568) (xy 400.241516 -430.018952) (xy 400.241924 -430.006873) (xy 400.249402 -429.9839)
			(xy 400.263613 -429.964361) (xy 400.283164 -429.950169) (xy 400.306144 -429.942712) (xy 400.318224 -429.942244)
			(xy 401.258024 -429.942244) (xy 401.270095 -429.942743) (xy 401.293055 -429.950206) (xy 401.312587 -429.964396)
			(xy 401.326783 -429.983924) (xy 401.334253 -430.006881) (xy 401.334732 -430.018952) (xy 401.334732 -430.889918)
			(xy 402.237956 -430.889918) (xy 402.238065 -430.874832) (xy 402.239847 -430.844714) (xy 402.241512 -430.82972)
			(xy 402.241512 -429.749966) (xy 402.239847 -429.734972) (xy 402.238066 -429.704854) (xy 402.237956 -429.689768)
			(xy 402.23807 -429.674682) (xy 402.239848 -429.644564) (xy 402.241512 -429.62957) (xy 402.241512 -429.018954)
			(xy 402.241968 -429.006865) (xy 402.249434 -428.983867) (xy 402.263624 -428.964291) (xy 402.283158 -428.950041)
			(xy 402.306132 -428.942505) (xy 402.31822 -428.941992) (xy 403.25802 -428.941992) (xy 403.270129 -428.942399)
			(xy 403.293156 -428.949903) (xy 403.312728 -428.964167) (xy 403.326922 -428.98379) (xy 403.334344 -429.006843)
			(xy 403.334728 -429.018954) (xy 403.334728 -431.560478) (xy 403.334273 -431.57257) (xy 403.326819 -431.595575)
			(xy 403.31263 -431.615158) (xy 403.293092 -431.629408) (xy 403.27011 -431.636935) (xy 403.25802 -431.63744)
			(xy 402.31822 -431.63744) (xy 402.306116 -431.636967) (xy 402.283096 -431.629478) (xy 402.263527 -431.61523)
			(xy 402.24933 -431.595622) (xy 402.241901 -431.572583) (xy 402.241512 -431.560478) (xy 402.241512 -430.950116)
			(xy 402.239843 -430.935123) (xy 402.238065 -430.905004) (xy 402.237956 -430.889918) (xy 401.334732 -430.889918)
			(xy 401.334732 -431.889916) (xy 404.237952 -431.889916) (xy 404.238061 -431.87483) (xy 404.239843 -431.844712)
			(xy 404.241508 -431.829718) (xy 404.241508 -430.749964) (xy 404.239843 -430.73497) (xy 404.238062 -430.704852)
			(xy 404.237952 -430.689766) (xy 404.238066 -430.67468) (xy 404.239844 -430.644562) (xy 404.241508 -430.629568)
			(xy 404.241508 -430.018952) (xy 404.241923 -430.006873) (xy 404.249401 -429.983902) (xy 404.26361 -429.964364)
			(xy 404.283159 -429.950172) (xy 404.306137 -429.942713) (xy 404.318216 -429.942244) (xy 405.258016 -429.942244)
			(xy 405.270087 -429.94275) (xy 405.293046 -429.950211) (xy 405.312579 -429.964399) (xy 405.326774 -429.983925)
			(xy 405.334245 -430.006882) (xy 405.334724 -430.018952) (xy 405.334724 -430.889918) (xy 406.237948 -430.889918)
			(xy 406.238057 -430.874832) (xy 406.239839 -430.844714) (xy 406.241504 -430.82972) (xy 406.241504 -429.749966)
			(xy 406.239839 -429.734972) (xy 406.238058 -429.704854) (xy 406.237948 -429.689768) (xy 406.238062 -429.674682)
			(xy 406.23984 -429.644564) (xy 406.241504 -429.62957) (xy 406.241504 -429.018954) (xy 406.241967 -429.006866)
			(xy 406.249432 -428.98387) (xy 406.263621 -428.964293) (xy 406.283153 -428.950043) (xy 406.306125 -428.942506)
			(xy 406.318212 -428.941992) (xy 407.258012 -428.941992) (xy 407.270121 -428.942406) (xy 407.293147 -428.949908)
			(xy 407.312719 -428.96417) (xy 407.326914 -428.983792) (xy 407.334336 -429.006844) (xy 407.33472 -429.018954)
			(xy 407.33472 -431.560478) (xy 407.334273 -431.57257) (xy 407.326818 -431.595577) (xy 407.312627 -431.615161)
			(xy 407.293087 -431.629411) (xy 407.270103 -431.636936) (xy 407.258012 -431.63744) (xy 406.318212 -431.63744)
			(xy 406.306108 -431.636974) (xy 406.283088 -431.629483) (xy 406.263518 -431.615232) (xy 406.249322 -431.595624)
			(xy 406.241893 -431.572583) (xy 406.241504 -431.560478) (xy 406.241504 -430.950116) (xy 406.239835 -430.935123)
			(xy 406.238057 -430.905004) (xy 406.237948 -430.889918) (xy 405.334724 -430.889918) (xy 405.334724 -431.889916)
			(xy 408.237944 -431.889916) (xy 408.238053 -431.87483) (xy 408.239835 -431.844712) (xy 408.2415 -431.829718)
			(xy 408.2415 -430.749964) (xy 408.239835 -430.73497) (xy 408.238054 -430.704852) (xy 408.237944 -430.689766)
			(xy 408.238058 -430.67468) (xy 408.239836 -430.644562) (xy 408.2415 -430.629568) (xy 408.2415 -430.018952)
			(xy 408.241923 -430.006874) (xy 408.2494 -429.983904) (xy 408.263607 -429.964367) (xy 408.283154 -429.950174)
			(xy 408.30613 -429.942714) (xy 408.318208 -429.942244) (xy 409.258008 -429.942244) (xy 409.270078 -429.942757)
			(xy 409.293037 -429.950216) (xy 409.31257 -429.964401) (xy 409.326766 -429.983927) (xy 409.334237 -430.006882)
			(xy 409.334716 -430.018952) (xy 409.334716 -430.889918) (xy 410.23794 -430.889918) (xy 410.238051 -430.874832)
			(xy 410.239833 -430.844714) (xy 410.241496 -430.82972) (xy 410.241496 -429.749966) (xy 410.239831 -429.734972)
			(xy 410.23805 -429.704854) (xy 410.23794 -429.689768) (xy 410.238054 -429.674682) (xy 410.239832 -429.644564)
			(xy 410.241496 -429.62957) (xy 410.241496 -429.018954) (xy 410.241967 -429.006866) (xy 410.249431 -428.983872)
			(xy 410.263618 -428.964296) (xy 410.283148 -428.950046) (xy 410.306118 -428.942507) (xy 410.318204 -428.941992)
			(xy 411.258004 -428.941992) (xy 411.270112 -428.942413) (xy 411.293138 -428.949912) (xy 411.312711 -428.964173)
			(xy 411.326906 -428.983793) (xy 411.334328 -429.006844) (xy 411.334712 -429.018954) (xy 411.334712 -431.560478)
			(xy 411.334273 -431.572571) (xy 411.326816 -431.595579) (xy 411.312624 -431.615164) (xy 411.293082 -431.629413)
			(xy 411.270096 -431.636937) (xy 411.258004 -431.63744) (xy 410.318204 -431.63744) (xy 410.306099 -431.636981)
			(xy 410.283079 -431.629488) (xy 410.263509 -431.615236) (xy 410.249313 -431.595625) (xy 410.241885 -431.572584)
			(xy 410.241496 -431.560478) (xy 410.241496 -430.950116) (xy 410.239827 -430.935123) (xy 410.238049 -430.905004)
			(xy 410.23794 -430.889918) (xy 409.334716 -430.889918) (xy 409.334716 -431.889916) (xy 412.237936 -431.889916)
			(xy 412.238047 -431.87483) (xy 412.239829 -431.844712) (xy 412.241492 -431.829718) (xy 412.241492 -430.749964)
			(xy 412.239827 -430.73497) (xy 412.238046 -430.704852) (xy 412.237936 -430.689766) (xy 412.238052 -430.674681)
			(xy 412.23983 -430.644562) (xy 412.241492 -430.629568) (xy 412.241492 -430.018952) (xy 412.241923 -430.006875)
			(xy 412.249399 -429.983906) (xy 412.263604 -429.96437) (xy 412.283149 -429.950177) (xy 412.306123 -429.942716)
			(xy 412.3182 -429.942244) (xy 413.258 -429.942244) (xy 413.27007 -429.942764) (xy 413.293029 -429.95022)
			(xy 413.312562 -429.964404) (xy 413.326758 -429.983928) (xy 413.334229 -430.006883) (xy 413.334708 -430.018952)
			(xy 413.334708 -432.560476) (xy 413.334267 -432.572557) (xy 413.326806 -432.595539) (xy 413.312607 -432.61509)
			(xy 413.293061 -432.629295) (xy 413.270081 -432.636763) (xy 413.258 -432.637184) (xy 412.3182 -432.637184)
			(xy 412.306115 -432.636787) (xy 412.283128 -432.629317) (xy 412.263576 -432.615107) (xy 412.249372 -432.59555)
			(xy 412.241909 -432.572561) (xy 412.241492 -432.560476) (xy 412.241492 -431.950114) (xy 412.239822 -431.935121)
			(xy 412.238045 -431.905002) (xy 412.237936 -431.889916) (xy 409.334716 -431.889916) (xy 409.334716 -432.560476)
			(xy 409.334267 -432.572557) (xy 409.326807 -432.595537) (xy 409.31261 -432.615087) (xy 409.293066 -432.629292)
			(xy 409.270088 -432.636762) (xy 409.258008 -432.637184) (xy 408.318208 -432.637184) (xy 408.306123 -432.63678)
			(xy 408.283137 -432.629312) (xy 408.263584 -432.615105) (xy 408.249381 -432.595549) (xy 408.241917 -432.572561)
			(xy 408.2415 -432.560476) (xy 408.2415 -431.950114) (xy 408.23983 -431.935121) (xy 408.238053 -431.905002)
			(xy 408.237944 -431.889916) (xy 405.334724 -431.889916) (xy 405.334724 -432.560476) (xy 405.334267 -432.572556)
			(xy 405.326808 -432.595535) (xy 405.312613 -432.615084) (xy 405.293071 -432.62929) (xy 405.270096 -432.636761)
			(xy 405.258016 -432.637184) (xy 404.318216 -432.637184) (xy 404.306132 -432.636773) (xy 404.283146 -432.629307)
			(xy 404.263593 -432.615101) (xy 404.249389 -432.595547) (xy 404.241926 -432.57256) (xy 404.241508 -432.560476)
			(xy 404.241508 -431.950114) (xy 404.239838 -431.935121) (xy 404.238061 -431.905002) (xy 404.237952 -431.889916)
			(xy 401.334732 -431.889916) (xy 401.334732 -432.560476) (xy 401.334216 -432.572547) (xy 401.326763 -432.595509)
			(xy 401.312579 -432.615045) (xy 401.293052 -432.629241) (xy 401.270095 -432.636708) (xy 401.258024 -432.637184)
			(xy 400.318224 -432.637184) (xy 400.30614 -432.636766) (xy 400.283154 -432.629303) (xy 400.263601 -432.615099)
			(xy 400.249397 -432.595546) (xy 400.241934 -432.57256) (xy 400.241516 -432.560476) (xy 400.241516 -431.950114)
			(xy 400.239846 -431.935121) (xy 400.238069 -431.905002) (xy 400.23796 -431.889916) (xy 396.334996 -431.889916)
			(xy 396.334996 -432.560476) (xy 396.334563 -432.572584) (xy 396.32707 -432.595611) (xy 396.312813 -432.615185)
			(xy 396.293194 -432.62938) (xy 396.270143 -432.636801) (xy 396.258034 -432.637184) (xy 395.318234 -432.637184)
			(xy 395.306149 -432.636664) (xy 395.283153 -432.62922) (xy 395.263575 -432.615046) (xy 395.249322 -432.595525)
			(xy 395.241785 -432.572559) (xy 395.241272 -432.560476) (xy 395.241272 -431.948082) (xy 395.239729 -431.93359)
			(xy 395.238076 -431.90449) (xy 395.23797 -431.889916) (xy 392.335004 -431.889916) (xy 392.335004 -432.560476)
			(xy 392.334563 -432.572583) (xy 392.327071 -432.595609) (xy 392.312815 -432.615182) (xy 392.293199 -432.629378)
			(xy 392.27015 -432.6368) (xy 392.258042 -432.637184) (xy 391.318242 -432.637184) (xy 391.306157 -432.636657)
			(xy 391.283162 -432.629215) (xy 391.263583 -432.615043) (xy 391.24933 -432.595523) (xy 391.241793 -432.572559)
			(xy 391.24128 -432.560476) (xy 391.24128 -431.948082) (xy 391.239737 -431.93359) (xy 391.238084 -431.90449)
			(xy 391.237978 -431.889916) (xy 388.335012 -431.889916) (xy 388.335012 -432.560476) (xy 388.334563 -432.572582)
			(xy 388.327072 -432.595607) (xy 388.312818 -432.615179) (xy 388.293204 -432.629375) (xy 388.270158 -432.636799)
			(xy 388.25805 -432.637184) (xy 387.31825 -432.637184) (xy 387.306165 -432.636651) (xy 387.28317 -432.62921)
			(xy 387.263592 -432.61504) (xy 387.249339 -432.595522) (xy 387.241801 -432.572559) (xy 387.241288 -432.560476)
			(xy 387.241288 -431.948082) (xy 387.239745 -431.93359) (xy 387.238092 -431.90449) (xy 387.237986 -431.889916)
			(xy 384.33502 -431.889916) (xy 384.33502 -432.560476) (xy 384.334563 -432.572582) (xy 384.327073 -432.595605)
			(xy 384.312821 -432.615176) (xy 384.293209 -432.629373) (xy 384.270165 -432.636797) (xy 384.258058 -432.637184)
			(xy 383.318258 -432.637184) (xy 383.306169 -432.636729) (xy 383.283171 -432.629264) (xy 383.263593 -432.615073)
			(xy 383.249343 -432.595539) (xy 383.241808 -432.572564) (xy 383.241296 -432.560476) (xy 383.241296 -431.948082)
			(xy 383.239753 -431.93359) (xy 383.2381 -431.90449) (xy 383.237994 -431.889916) (xy 375.042305 -431.889916)
			(xy 375.133007 -431.982394) (xy 375.270401 -432.133801) (xy 375.401821 -432.290421) (xy 375.527069 -432.452019)
			(xy 375.645957 -432.618352) (xy 375.758305 -432.78917) (xy 375.863946 -432.964215) (xy 375.96272 -433.143226)
			(xy 376.054478 -433.325931) (xy 376.139083 -433.512058) (xy 376.216407 -433.701324) (xy 376.286334 -433.893447)
			(xy 376.348758 -434.088137) (xy 376.403587 -434.285101) (xy 376.450737 -434.484043) (xy 376.451879 -434.48986)
			(xy 381.237998 -434.48986) (xy 381.238096 -434.475286) (xy 381.239745 -434.446185) (xy 381.2413 -434.431694)
			(xy 381.2413 -433.34813) (xy 381.239752 -433.333638) (xy 381.238102 -433.304538) (xy 381.237998 -433.289964)
			(xy 381.238096 -433.27539) (xy 381.239745 -433.246289) (xy 381.2413 -433.231798) (xy 381.2413 -432.618896)
			(xy 381.241713 -432.606787) (xy 381.249213 -432.583759) (xy 381.263476 -432.564186) (xy 381.283098 -432.549992)
			(xy 381.306152 -432.542571) (xy 381.318262 -432.542188) (xy 382.258062 -432.542188) (xy 382.270154 -432.542641)
			(xy 382.293162 -432.550093) (xy 382.312747 -432.564281) (xy 382.326997 -432.583821) (xy 382.334521 -432.606805)
			(xy 382.335024 -432.618896) (xy 382.335024 -435.16042) (xy 382.334601 -435.172528) (xy 382.327099 -435.195551)
			(xy 382.312838 -435.215122) (xy 382.29322 -435.229317) (xy 382.270171 -435.236741) (xy 382.258062 -435.237128)
			(xy 381.318262 -435.237128) (xy 381.306167 -435.236724) (xy 381.28316 -435.229253) (xy 381.263578 -435.215052)
			(xy 381.24933 -435.195503) (xy 381.241804 -435.172514) (xy 381.2413 -435.16042) (xy 381.2413 -434.548026)
			(xy 381.239752 -434.533534) (xy 381.238102 -434.504434) (xy 381.237998 -434.48986) (xy 376.451879 -434.48986)
			(xy 376.490138 -434.684663) (xy 376.521729 -434.88666) (xy 376.545465 -435.089731) (xy 376.561309 -435.293569)
			(xy 376.568925 -435.489858) (xy 383.237994 -435.489858) (xy 383.238091 -435.475284) (xy 383.239741 -435.446183)
			(xy 383.241296 -435.431692) (xy 383.241296 -434.348128) (xy 383.239748 -434.333636) (xy 383.238098 -434.304536)
			(xy 383.237994 -434.289962) (xy 383.238092 -434.275388) (xy 383.239741 -434.246287) (xy 383.241296 -434.231796)
			(xy 383.241296 -433.618894) (xy 383.241806 -433.606783) (xy 383.24929 -433.583747) (xy 383.263524 -433.564149)
			(xy 383.283115 -433.549906) (xy 383.306148 -433.542412) (xy 383.318258 -433.541932) (xy 384.258058 -433.541932)
			(xy 384.270178 -433.542396) (xy 384.293234 -433.549876) (xy 384.31285 -433.564116) (xy 384.327103 -433.583722)
			(xy 384.334597 -433.606774) (xy 384.33502 -433.618894) (xy 384.33502 -434.48986) (xy 385.23799 -434.48986)
			(xy 385.238088 -434.475286) (xy 385.239737 -434.446185) (xy 385.241292 -434.431694) (xy 385.241292 -433.34813)
			(xy 385.239744 -433.333638) (xy 385.238094 -433.304538) (xy 385.23799 -433.289964) (xy 385.238088 -433.27539)
			(xy 385.239737 -433.246289) (xy 385.241292 -433.231798) (xy 385.241292 -432.618896) (xy 385.241713 -432.606788)
			(xy 385.249212 -432.583762) (xy 385.263473 -432.564189) (xy 385.283093 -432.549994) (xy 385.306144 -432.542572)
			(xy 385.318254 -432.542188) (xy 386.258054 -432.542188) (xy 386.270146 -432.542647) (xy 386.293153 -432.550097)
			(xy 386.312738 -432.564284) (xy 386.326988 -432.583823) (xy 386.334513 -432.606806) (xy 386.335016 -432.618896)
			(xy 386.335016 -435.16042) (xy 386.334601 -435.172528) (xy 386.327098 -435.195554) (xy 386.312836 -435.215125)
			(xy 386.293215 -435.229319) (xy 386.270164 -435.236743) (xy 386.258054 -435.237128) (xy 385.318254 -435.237128)
			(xy 385.306159 -435.236731) (xy 385.283151 -435.229258) (xy 385.263569 -435.215054) (xy 385.249322 -435.195505)
			(xy 385.241796 -435.172514) (xy 385.241292 -435.16042) (xy 385.241292 -434.548026) (xy 385.239744 -434.533534)
			(xy 385.238094 -434.504434) (xy 385.23799 -434.48986) (xy 384.33502 -434.48986) (xy 384.33502 -435.489858)
			(xy 387.237986 -435.489858) (xy 387.238083 -435.475284) (xy 387.239733 -435.446183) (xy 387.241288 -435.431692)
			(xy 387.241288 -434.348128) (xy 387.23974 -434.333636) (xy 387.23809 -434.304536) (xy 387.237986 -434.289962)
			(xy 387.238084 -434.275388) (xy 387.239733 -434.246287) (xy 387.241288 -434.231796) (xy 387.241288 -433.618894)
			(xy 387.241806 -433.606784) (xy 387.249289 -433.583749) (xy 387.263521 -433.564152) (xy 387.28311 -433.549909)
			(xy 387.30614 -433.542413) (xy 387.31825 -433.541932) (xy 388.25805 -433.541932) (xy 388.270167 -433.542369)
			(xy 388.29321 -433.549869) (xy 388.312811 -433.564121) (xy 388.327051 -433.583729) (xy 388.334538 -433.606777)
			(xy 388.335012 -433.618894) (xy 388.335012 -434.48986) (xy 389.237982 -434.48986) (xy 389.23808 -434.475286)
			(xy 389.239729 -434.446185) (xy 389.241284 -434.431694) (xy 389.241284 -433.34813) (xy 389.239736 -433.333638)
			(xy 389.238086 -433.304538) (xy 389.237982 -433.289964) (xy 389.23808 -433.27539) (xy 389.23973 -433.246289)
			(xy 389.241284 -433.231798) (xy 389.241284 -432.618896) (xy 389.241713 -432.606789) (xy 389.249211 -432.583764)
			(xy 389.26347 -432.564192) (xy 389.283088 -432.549997) (xy 389.306137 -432.542573) (xy 389.318246 -432.542188)
			(xy 390.258046 -432.542188) (xy 390.270143 -432.542569) (xy 390.293153 -432.550044) (xy 390.312736 -432.564251)
			(xy 390.326984 -432.583805) (xy 390.334506 -432.6068) (xy 390.335008 -432.618896) (xy 390.335008 -435.16042)
			(xy 390.334601 -435.172529) (xy 390.327097 -435.195556) (xy 390.312833 -435.215128) (xy 390.29321 -435.229322)
			(xy 390.270157 -435.236744) (xy 390.258046 -435.237128) (xy 389.318246 -435.237128) (xy 389.306156 -435.236653)
			(xy 389.283151 -435.229205) (xy 389.263568 -435.215022) (xy 389.249317 -435.195487) (xy 389.241789 -435.172509)
			(xy 389.241284 -435.16042) (xy 389.241284 -434.548026) (xy 389.239736 -434.533534) (xy 389.238086 -434.504434)
			(xy 389.237982 -434.48986) (xy 388.335012 -434.48986) (xy 388.335012 -435.489858) (xy 391.237978 -435.489858)
			(xy 391.238076 -435.475284) (xy 391.239725 -435.446183) (xy 391.24128 -435.431692) (xy 391.24128 -434.348128)
			(xy 391.239732 -434.333636) (xy 391.238082 -434.304536) (xy 391.237978 -434.289962) (xy 391.238076 -434.275388)
			(xy 391.239725 -434.246287) (xy 391.24128 -434.231796) (xy 391.24128 -433.618894) (xy 391.241656 -433.606767)
			(xy 391.249155 -433.583701) (xy 391.263416 -433.564082) (xy 391.283044 -433.549833) (xy 391.306115 -433.542348)
			(xy 391.318242 -433.541932) (xy 392.258042 -433.541932) (xy 392.270158 -433.542376) (xy 392.293202 -433.549874)
			(xy 392.312802 -433.564123) (xy 392.327043 -433.583731) (xy 392.33453 -433.606778) (xy 392.335004 -433.618894)
			(xy 392.335004 -434.48986) (xy 393.237974 -434.48986) (xy 393.238072 -434.475286) (xy 393.239721 -434.446185)
			(xy 393.241276 -434.431694) (xy 393.241276 -433.34813) (xy 393.239728 -433.333638) (xy 393.238078 -433.304538)
			(xy 393.237974 -433.289964) (xy 393.238072 -433.27539) (xy 393.239722 -433.246289) (xy 393.241276 -433.231798)
			(xy 393.241276 -432.618896) (xy 393.241712 -432.606789) (xy 393.24921 -432.583766) (xy 393.263467 -432.564195)
			(xy 393.283083 -432.55) (xy 393.30613 -432.542575) (xy 393.318238 -432.542188) (xy 394.258038 -432.542188)
			(xy 394.270134 -432.542576) (xy 394.293144 -432.550049) (xy 394.312728 -432.564254) (xy 394.326975 -432.583807)
			(xy 394.334498 -432.606801) (xy 394.335 -432.618896) (xy 394.335 -435.16042) (xy 394.334601 -435.17253)
			(xy 394.327096 -435.195558) (xy 394.31283 -435.215131) (xy 394.293205 -435.229325) (xy 394.270149 -435.236745)
			(xy 394.258038 -435.237128) (xy 393.318238 -435.237128) (xy 393.306147 -435.23666) (xy 393.283142 -435.22921)
			(xy 393.263559 -435.215024) (xy 393.249308 -435.195489) (xy 393.241781 -435.172509) (xy 393.241276 -435.16042)
			(xy 393.241276 -434.548026) (xy 393.239728 -434.533534) (xy 393.238078 -434.504434) (xy 393.237974 -434.48986)
			(xy 392.335004 -434.48986) (xy 392.335004 -435.489858) (xy 395.23797 -435.489858) (xy 395.238068 -435.475284)
			(xy 395.239717 -435.446183) (xy 395.241272 -435.431692) (xy 395.241272 -434.348128) (xy 395.239724 -434.333636)
			(xy 395.238074 -434.304536) (xy 395.23797 -434.289962) (xy 395.238068 -434.275388) (xy 395.239717 -434.246287)
			(xy 395.241272 -434.231796) (xy 395.241272 -433.618894) (xy 395.241656 -433.606768) (xy 395.249154 -433.583703)
			(xy 395.263413 -433.564085) (xy 395.283039 -433.549835) (xy 395.306107 -433.542349) (xy 395.318234 -433.541932)
			(xy 396.258034 -433.541932) (xy 396.27015 -433.542383) (xy 396.293193 -433.549878) (xy 396.312794 -433.564126)
			(xy 396.327034 -433.583732) (xy 396.334522 -433.606778) (xy 396.334996 -433.618894) (xy 396.334996 -434.48986)
			(xy 398.237964 -434.48986) (xy 398.238077 -434.474774) (xy 398.239856 -434.444656) (xy 398.24152 -434.429662)
			(xy 398.24152 -433.350162) (xy 398.239855 -433.335168) (xy 398.238074 -433.30505) (xy 398.237964 -433.289964)
			(xy 398.238077 -433.274878) (xy 398.239856 -433.24476) (xy 398.24152 -433.229766) (xy 398.24152 -432.618896)
			(xy 398.241909 -432.60681) (xy 398.249382 -432.583823) (xy 398.263593 -432.56427) (xy 398.283151 -432.550067)
			(xy 398.306142 -432.542604) (xy 398.318228 -432.542188) (xy 399.258028 -432.542188) (xy 399.270104 -432.54264)
			(xy 399.293071 -432.55011) (xy 399.312607 -432.56431) (xy 399.326801 -432.58385) (xy 399.334264 -432.60682)
			(xy 399.334736 -432.618896) (xy 399.334736 -435.16042) (xy 399.334253 -435.172493) (xy 399.326788 -435.195456)
			(xy 399.312596 -435.21499) (xy 399.293063 -435.229185) (xy 399.270101 -435.236652) (xy 399.258028 -435.237128)
			(xy 398.318228 -435.237128) (xy 398.306149 -435.236664) (xy 398.28317 -435.229206) (xy 398.263621 -435.215013)
			(xy 398.249416 -435.195473) (xy 398.241944 -435.172499) (xy 398.24152 -435.16042) (xy 398.24152 -434.550058)
			(xy 398.239854 -434.535064) (xy 398.238074 -434.504946) (xy 398.237964 -434.48986) (xy 396.334996 -434.48986)
			(xy 396.334996 -435.489858) (xy 400.23796 -435.489858) (xy 400.238073 -435.474772) (xy 400.239852 -435.444654)
			(xy 400.241516 -435.42966) (xy 400.241516 -434.35016) (xy 400.239851 -434.335166) (xy 400.23807 -434.305048)
			(xy 400.23796 -434.289962) (xy 400.238073 -434.274876) (xy 400.239852 -434.244758) (xy 400.241516 -434.229764)
			(xy 400.241516 -433.618894) (xy 400.242002 -433.606807) (xy 400.249457 -433.58381) (xy 400.26364 -433.564232)
			(xy 400.283168 -433.549981) (xy 400.306138 -433.542445) (xy 400.318224 -433.541932) (xy 401.258024 -433.541932)
			(xy 401.270137 -433.542296) (xy 401.293171 -433.549806) (xy 401.312746 -433.56408) (xy 401.326939 -433.583715)
			(xy 401.334353 -433.606779) (xy 401.334732 -433.618894) (xy 401.334732 -434.48986) (xy 402.237956 -434.48986)
			(xy 402.238069 -434.474774) (xy 402.239848 -434.444656) (xy 402.241512 -434.429662) (xy 402.241512 -433.350162)
			(xy 402.239847 -433.335168) (xy 402.238066 -433.30505) (xy 402.237956 -433.289964) (xy 402.238069 -433.274878)
			(xy 402.239848 -433.24476) (xy 402.241512 -433.229766) (xy 402.241512 -432.618896) (xy 402.241909 -432.606811)
			(xy 402.24938 -432.583825) (xy 402.26359 -432.564273) (xy 402.283146 -432.550069) (xy 402.306135 -432.542606)
			(xy 402.31822 -432.542188) (xy 403.25802 -432.542188) (xy 403.270095 -432.542647) (xy 403.293062 -432.550115)
			(xy 403.312599 -432.564313) (xy 403.326793 -432.583852) (xy 403.334255 -432.606821) (xy 403.334728 -432.618896)
			(xy 403.334728 -435.16042) (xy 403.334253 -435.172494) (xy 403.326787 -435.195458) (xy 403.312593 -435.214993)
			(xy 403.293058 -435.229187) (xy 403.270094 -435.236653) (xy 403.25802 -435.237128) (xy 402.31822 -435.237128)
			(xy 402.306148 -435.236619) (xy 402.283185 -435.229165) (xy 402.26365 -435.214979) (xy 402.249454 -435.195451)
			(xy 402.241987 -435.172491) (xy 402.241512 -435.16042) (xy 402.241512 -434.550058) (xy 402.239846 -434.535064)
			(xy 402.238066 -434.504946) (xy 402.237956 -434.48986) (xy 401.334732 -434.48986) (xy 401.334732 -435.489858)
			(xy 404.237952 -435.489858) (xy 404.238065 -435.474772) (xy 404.239844 -435.444654) (xy 404.241508 -435.42966)
			(xy 404.241508 -434.35016) (xy 404.239843 -434.335166) (xy 404.238062 -434.305048) (xy 404.237952 -434.289962)
			(xy 404.238065 -434.274876) (xy 404.239844 -434.244758) (xy 404.241508 -434.229764) (xy 404.241508 -433.618894)
			(xy 404.242002 -433.606807) (xy 404.249456 -433.583812) (xy 404.263637 -433.564235) (xy 404.283163 -433.549984)
			(xy 404.306131 -433.542446) (xy 404.318216 -433.541932) (xy 405.258016 -433.541932) (xy 405.270129 -433.542303)
			(xy 405.293162 -433.549811) (xy 405.312738 -433.564083) (xy 405.326931 -433.583716) (xy 405.334345 -433.606779)
			(xy 405.334724 -433.618894) (xy 405.334724 -434.48986) (xy 406.237948 -434.48986) (xy 406.238061 -434.474774)
			(xy 406.23984 -434.444656) (xy 406.241504 -434.429662) (xy 406.241504 -433.350162) (xy 406.239839 -433.335168)
			(xy 406.238058 -433.30505) (xy 406.237948 -433.289964) (xy 406.238061 -433.274878) (xy 406.23984 -433.24476)
			(xy 406.241504 -433.229766) (xy 406.241504 -432.618896) (xy 406.241909 -432.606812) (xy 406.249379 -432.583827)
			(xy 406.263587 -432.564276) (xy 406.283141 -432.550072) (xy 406.306128 -432.542607) (xy 406.318212 -432.542188)
			(xy 407.258012 -432.542188) (xy 407.270087 -432.542654) (xy 407.293054 -432.550119) (xy 407.31259 -432.564316)
			(xy 407.326784 -432.583854) (xy 407.334247 -432.606821) (xy 407.33472 -432.618896) (xy 407.33472 -435.16042)
			(xy 407.334253 -435.172494) (xy 407.326786 -435.19546) (xy 407.31259 -435.214996) (xy 407.293053 -435.22919)
			(xy 407.270086 -435.236654) (xy 407.258012 -435.237128) (xy 406.318212 -435.237128) (xy 406.30614 -435.236626)
			(xy 406.283177 -435.229169) (xy 406.263641 -435.214982) (xy 406.249446 -435.195452) (xy 406.241979 -435.172492)
			(xy 406.241504 -435.16042) (xy 406.241504 -434.550058) (xy 406.239838 -434.535064) (xy 406.238058 -434.504946)
			(xy 406.237948 -434.48986) (xy 405.334724 -434.48986) (xy 405.334724 -435.489858) (xy 408.237944 -435.489858)
			(xy 408.238057 -435.474772) (xy 408.239836 -435.444654) (xy 408.2415 -435.42966) (xy 408.2415 -434.35016)
			(xy 408.239834 -434.335166) (xy 408.238054 -434.305048) (xy 408.237944 -434.289962) (xy 408.238057 -434.274876)
			(xy 408.239836 -434.244758) (xy 408.2415 -434.229764) (xy 408.2415 -433.618894) (xy 408.242002 -433.606808)
			(xy 408.249455 -433.583814) (xy 408.263634 -433.564238) (xy 408.283158 -433.549986) (xy 408.306124 -433.542447)
			(xy 408.318208 -433.541932) (xy 409.258008 -433.541932) (xy 409.270121 -433.54231) (xy 409.293154 -433.549815)
			(xy 409.312729 -433.564086) (xy 409.326923 -433.583717) (xy 409.334337 -433.60678) (xy 409.334716 -433.618894)
			(xy 409.334716 -434.48986) (xy 410.23794 -434.48986) (xy 410.238053 -434.474774) (xy 410.239832 -434.444656)
			(xy 410.241496 -434.429662) (xy 410.241496 -433.350162) (xy 410.239831 -433.335168) (xy 410.23805 -433.30505)
			(xy 410.23794 -433.289964) (xy 410.238053 -433.274878) (xy 410.239832 -433.24476) (xy 410.241496 -433.229766)
			(xy 410.241496 -432.618896) (xy 410.241961 -432.606821) (xy 410.249425 -432.583853) (xy 410.263621 -432.564316)
			(xy 410.28316 -432.550121) (xy 410.306129 -432.54266) (xy 410.318204 -432.542188) (xy 411.258004 -432.542188)
			(xy 411.270078 -432.542661) (xy 411.293045 -432.550124) (xy 411.312582 -432.564318) (xy 411.326776 -432.583855)
			(xy 411.334239 -432.606822) (xy 411.334712 -432.618896) (xy 411.334712 -435.16042) (xy 411.334253 -435.172495)
			(xy 411.326785 -435.195462) (xy 411.312587 -435.214999) (xy 411.293048 -435.229193) (xy 411.270079 -435.236655)
			(xy 411.258004 -435.237128) (xy 410.318204 -435.237128) (xy 410.306132 -435.236633) (xy 410.283168 -435.229174)
			(xy 410.263633 -435.214984) (xy 410.249437 -435.195454) (xy 410.241971 -435.172492) (xy 410.241496 -435.16042)
			(xy 410.241496 -434.550058) (xy 410.23983 -434.535064) (xy 410.23805 -434.504946) (xy 410.23794 -434.48986)
			(xy 409.334716 -434.48986) (xy 409.334716 -435.489858) (xy 412.237936 -435.489858) (xy 412.238051 -435.474773)
			(xy 412.23983 -435.444654) (xy 412.241492 -435.42966) (xy 412.241492 -434.35016) (xy 412.239826 -434.335166)
			(xy 412.238046 -434.305048) (xy 412.237936 -434.289962) (xy 412.238051 -434.274877) (xy 412.23983 -434.244758)
			(xy 412.241492 -434.229764) (xy 412.241492 -433.618894) (xy 412.242002 -433.606809) (xy 412.249454 -433.583816)
			(xy 412.263631 -433.564241) (xy 412.283153 -433.549989) (xy 412.306117 -433.542448) (xy 412.3182 -433.541932)
			(xy 413.258 -433.541932) (xy 413.270112 -433.542317) (xy 413.293145 -433.54982) (xy 413.312721 -433.564088)
			(xy 413.326914 -433.583719) (xy 413.334329 -433.60678) (xy 413.334708 -433.618894) (xy 413.334708 -436.160418)
			(xy 413.334209 -436.172504) (xy 413.326753 -436.195497) (xy 413.312573 -436.215072) (xy 413.29305 -436.229324)
			(xy 413.270084 -436.236864) (xy 413.258 -436.23738) (xy 412.3182 -436.23738) (xy 412.306089 -436.236984)
			(xy 412.283058 -436.229482) (xy 412.263483 -436.215216) (xy 412.24929 -436.195589) (xy 412.241872 -436.17253)
			(xy 412.241492 -436.160418) (xy 412.241492 -435.550056) (xy 412.239826 -435.535062) (xy 412.238046 -435.504944)
			(xy 412.237936 -435.489858) (xy 409.334716 -435.489858) (xy 409.334716 -436.160418) (xy 409.334307 -436.172513)
			(xy 409.32684 -436.195522) (xy 409.31264 -436.215105) (xy 409.293092 -436.229353) (xy 409.270102 -436.236877)
			(xy 409.258008 -436.23738) (xy 408.318208 -436.23738) (xy 408.306098 -436.236977) (xy 408.283067 -436.229477)
			(xy 408.263492 -436.215213) (xy 408.249298 -436.195587) (xy 408.24188 -436.17253) (xy 408.2415 -436.160418)
			(xy 408.2415 -435.550056) (xy 408.239834 -435.535062) (xy 408.238054 -435.504944) (xy 408.237944 -435.489858)
			(xy 405.334724 -435.489858) (xy 405.334724 -436.160418) (xy 405.334307 -436.172512) (xy 405.326841 -436.195519)
			(xy 405.312643 -436.215102) (xy 405.293097 -436.229351) (xy 405.270109 -436.236876) (xy 405.258016 -436.23738)
			(xy 404.318216 -436.23738) (xy 404.306106 -436.23697) (xy 404.283076 -436.229472) (xy 404.263501 -436.21521)
			(xy 404.249306 -436.195585) (xy 404.241889 -436.172529) (xy 404.241508 -436.160418) (xy 404.241508 -435.550056)
			(xy 404.239842 -435.535062) (xy 404.238062 -435.504944) (xy 404.237952 -435.489858) (xy 401.334732 -435.489858)
			(xy 401.334732 -436.160418) (xy 401.334308 -436.172511) (xy 401.326843 -436.195517) (xy 401.312646 -436.215099)
			(xy 401.293102 -436.229348) (xy 401.270116 -436.236875) (xy 401.258024 -436.23738) (xy 400.318224 -436.23738)
			(xy 400.306114 -436.236963) (xy 400.283085 -436.229468) (xy 400.263509 -436.215207) (xy 400.249315 -436.195584)
			(xy 400.241897 -436.172529) (xy 400.241516 -436.160418) (xy 400.241516 -435.550056) (xy 400.23985 -435.535062)
			(xy 400.23807 -435.504944) (xy 400.23796 -435.489858) (xy 396.334996 -435.489858) (xy 396.334996 -436.160418)
			(xy 396.334504 -436.17253) (xy 396.327016 -436.195568) (xy 396.312778 -436.215167) (xy 396.293183 -436.229409)
			(xy 396.270146 -436.236902) (xy 396.258034 -436.23738) (xy 395.318234 -436.23738) (xy 395.306115 -436.236911)
			(xy 395.28306 -436.229431) (xy 395.263446 -436.215191) (xy 395.249193 -436.195587) (xy 395.241697 -436.172537)
			(xy 395.241272 -436.160418) (xy 395.241272 -435.548024) (xy 395.239724 -435.533532) (xy 395.238074 -435.504432)
			(xy 395.23797 -435.489858) (xy 392.335004 -435.489858) (xy 392.335004 -436.160418) (xy 392.334504 -436.172529)
			(xy 392.327017 -436.195566) (xy 392.312781 -436.215164) (xy 392.293188 -436.229406) (xy 392.270153 -436.236901)
			(xy 392.258042 -436.23738) (xy 391.318242 -436.23738) (xy 391.306123 -436.236905) (xy 391.283069 -436.229426)
			(xy 391.263455 -436.215188) (xy 391.249201 -436.195585) (xy 391.241705 -436.172536) (xy 391.24128 -436.160418)
			(xy 391.24128 -435.548024) (xy 391.239732 -435.533532) (xy 391.238082 -435.504432) (xy 391.237978 -435.489858)
			(xy 388.335012 -435.489858) (xy 388.335012 -436.160418) (xy 388.334505 -436.172529) (xy 388.327018 -436.195564)
			(xy 388.312784 -436.215161) (xy 388.293193 -436.229404) (xy 388.27016 -436.2369) (xy 388.25805 -436.23738)
			(xy 387.31825 -436.23738) (xy 387.306135 -436.236931) (xy 387.283093 -436.229432) (xy 387.263493 -436.215184)
			(xy 387.249253 -436.195578) (xy 387.241764 -436.172534) (xy 387.241288 -436.160418) (xy 387.241288 -435.548024)
			(xy 387.23974 -435.533532) (xy 387.23809 -435.504432) (xy 387.237986 -435.489858) (xy 384.33502 -435.489858)
			(xy 384.33502 -436.160418) (xy 384.334654 -436.172546) (xy 384.327152 -436.195612) (xy 384.312888 -436.215231)
			(xy 384.293258 -436.22948) (xy 384.270186 -436.236964) (xy 384.258058 -436.23738) (xy 383.318258 -436.23738)
			(xy 383.306143 -436.236924) (xy 383.283101 -436.229428) (xy 383.263502 -436.215181) (xy 383.249261 -436.195577)
			(xy 383.241772 -436.172533) (xy 383.241296 -436.160418) (xy 383.241296 -435.548024) (xy 383.239748 -435.533532)
			(xy 383.238098 -435.504432) (xy 383.237994 -435.489858) (xy 376.568925 -435.489858) (xy 376.569236 -435.497868)
			(xy 376.569732 -435.600094) (xy 376.569235 -435.702721) (xy 376.561245 -435.90782) (xy 376.545276 -436.112453)
			(xy 376.521353 -436.316308) (xy 376.489512 -436.519078) (xy 376.449802 -436.720455) (xy 376.402282 -436.920133)
			(xy 376.347025 -437.117809) (xy 376.284114 -437.313185) (xy 376.213645 -437.505964) (xy 376.135724 -437.695853)
			(xy 376.050471 -437.882564) (xy 375.958013 -438.065815) (xy 375.944715 -438.089802) (xy 381.237998 -438.089802)
			(xy 381.238091 -438.075228) (xy 381.239744 -438.046127) (xy 381.2413 -438.031636) (xy 381.2413 -436.948072)
			(xy 381.239755 -436.93358) (xy 381.238103 -436.90448) (xy 381.237998 -436.889906) (xy 381.238091 -436.875332)
			(xy 381.239744 -436.846231) (xy 381.2413 -436.83174) (xy 381.2413 -436.219092) (xy 381.241709 -436.206983)
			(xy 381.249211 -436.183955) (xy 381.263474 -436.164382) (xy 381.283097 -436.150188) (xy 381.306151 -436.142767)
			(xy 381.318262 -436.142384) (xy 382.258062 -436.142384) (xy 382.270154 -436.142841) (xy 382.293161 -436.150292)
			(xy 382.312745 -436.16448) (xy 382.326995 -436.184019) (xy 382.334521 -436.207002) (xy 382.335024 -436.219092)
			(xy 382.335024 -438.760616) (xy 382.334598 -438.772723) (xy 382.327097 -438.795747) (xy 382.312837 -438.815318)
			(xy 382.293219 -438.829513) (xy 382.270171 -438.836937) (xy 382.258062 -438.837324) (xy 381.318262 -438.837324)
			(xy 381.306167 -438.836924) (xy 381.283159 -438.829453) (xy 381.263577 -438.81525) (xy 381.249329 -438.795701)
			(xy 381.241804 -438.77271) (xy 381.2413 -438.760616) (xy 381.2413 -438.147968) (xy 381.239755 -438.133476)
			(xy 381.238103 -438.104376) (xy 381.237998 -438.089802) (xy 375.944715 -438.089802) (xy 375.858491 -438.245328)
			(xy 375.752057 -438.420831) (xy 375.63887 -438.592057) (xy 375.519104 -438.758747) (xy 375.39294 -438.920648)
			(xy 375.260568 -439.077514) (xy 375.249353 -439.0898) (xy 383.237994 -439.0898) (xy 383.238086 -439.075226)
			(xy 383.23974 -439.046125) (xy 383.241296 -439.031634) (xy 383.241296 -437.94807) (xy 383.239752 -437.933578)
			(xy 383.238099 -437.904478) (xy 383.237994 -437.889904) (xy 383.238087 -437.87533) (xy 383.23974 -437.846229)
			(xy 383.241296 -437.831738) (xy 383.241296 -437.21909) (xy 383.241803 -437.206979) (xy 383.249288 -437.183943)
			(xy 383.263522 -437.164345) (xy 383.283114 -437.150102) (xy 383.306147 -437.142608) (xy 383.318258 -437.142128)
			(xy 384.258058 -437.142128) (xy 384.270178 -437.142595) (xy 384.293233 -437.150075) (xy 384.312848 -437.164315)
			(xy 384.327101 -437.18392) (xy 384.334596 -437.206971) (xy 384.33502 -437.21909) (xy 384.33502 -438.089802)
			(xy 385.23799 -438.089802) (xy 385.238083 -438.075228) (xy 385.239736 -438.046127) (xy 385.241292 -438.031636)
			(xy 385.241292 -436.948072) (xy 385.239748 -436.93358) (xy 385.238095 -436.90448) (xy 385.23799 -436.889906)
			(xy 385.238083 -436.875332) (xy 385.239736 -436.846231) (xy 385.241292 -436.83174) (xy 385.241292 -436.219092)
			(xy 385.241709 -436.206983) (xy 385.24921 -436.183957) (xy 385.263472 -436.164385) (xy 385.283092 -436.15019)
			(xy 385.306144 -436.142768) (xy 385.318254 -436.142384) (xy 386.258054 -436.142384) (xy 386.270146 -436.142847)
			(xy 386.293152 -436.150297) (xy 386.312737 -436.164483) (xy 386.326987 -436.18402) (xy 386.334512 -436.207002)
			(xy 386.335016 -436.219092) (xy 386.335016 -438.760616) (xy 386.334598 -438.772724) (xy 386.327096 -438.795749)
			(xy 386.312834 -438.815321) (xy 386.293214 -438.829515) (xy 386.270163 -438.836939) (xy 386.258054 -438.837324)
			(xy 385.318254 -438.837324) (xy 385.306158 -438.836931) (xy 385.28315 -438.829457) (xy 385.263568 -438.815253)
			(xy 385.24932 -438.795702) (xy 385.241796 -438.77271) (xy 385.241292 -438.760616) (xy 385.241292 -438.147968)
			(xy 385.239747 -438.133476) (xy 385.238095 -438.104376) (xy 385.23799 -438.089802) (xy 384.33502 -438.089802)
			(xy 384.33502 -439.0898) (xy 387.237986 -439.0898) (xy 387.238078 -439.075226) (xy 387.239732 -439.046125)
			(xy 387.241288 -439.031634) (xy 387.241288 -437.94807) (xy 387.239744 -437.933578) (xy 387.238091 -437.904478)
			(xy 387.237986 -437.889904) (xy 387.238079 -437.87533) (xy 387.239732 -437.846229) (xy 387.241288 -437.831738)
			(xy 387.241288 -437.21909) (xy 387.241803 -437.20698) (xy 387.249287 -437.183945) (xy 387.263519 -437.164348)
			(xy 387.283109 -437.150105) (xy 387.30614 -437.142609) (xy 387.31825 -437.142128) (xy 388.25805 -437.142128)
			(xy 388.270166 -437.142569) (xy 388.293209 -437.150069) (xy 388.312809 -437.164319) (xy 388.32705 -437.183927)
			(xy 388.334537 -437.206974) (xy 388.335012 -437.21909) (xy 388.335012 -438.089802) (xy 389.237982 -438.089802)
			(xy 389.238075 -438.075228) (xy 389.239728 -438.046127) (xy 389.241284 -438.031636) (xy 389.241284 -436.948072)
			(xy 389.23974 -436.93358) (xy 389.238087 -436.90448) (xy 389.237982 -436.889906) (xy 389.238075 -436.875332)
			(xy 389.239728 -436.846231) (xy 389.241284 -436.83174) (xy 389.241284 -436.219092) (xy 389.241709 -436.206984)
			(xy 389.249209 -436.183959) (xy 389.263469 -436.164388) (xy 389.283087 -436.150193) (xy 389.306137 -436.142769)
			(xy 389.318246 -436.142384) (xy 390.258046 -436.142384) (xy 390.270142 -436.142769) (xy 390.293152 -436.150244)
			(xy 390.312735 -436.16445) (xy 390.326982 -436.184003) (xy 390.334505 -436.206997) (xy 390.335008 -436.219092)
			(xy 390.335008 -438.760616) (xy 390.334598 -438.772725) (xy 390.327095 -438.795751) (xy 390.312831 -438.815324)
			(xy 390.293209 -438.829518) (xy 390.270156 -438.83694) (xy 390.258046 -438.837324) (xy 389.318246 -438.837324)
			(xy 389.306155 -438.836853) (xy 389.28315 -438.829404) (xy 389.263566 -438.81522) (xy 389.249315 -438.795685)
			(xy 389.241789 -438.772705) (xy 389.241284 -438.760616) (xy 389.241284 -438.147968) (xy 389.239739 -438.133476)
			(xy 389.238087 -438.104376) (xy 389.237982 -438.089802) (xy 388.335012 -438.089802) (xy 388.335012 -439.0898)
			(xy 391.237978 -439.0898) (xy 391.238071 -439.075226) (xy 391.239724 -439.046125) (xy 391.24128 -439.031634)
			(xy 391.24128 -437.94807) (xy 391.239736 -437.933578) (xy 391.238083 -437.904478) (xy 391.237978 -437.889904)
			(xy 391.238071 -437.87533) (xy 391.239724 -437.846229) (xy 391.24128 -437.831738) (xy 391.24128 -437.21909)
			(xy 391.241652 -437.206963) (xy 391.249152 -437.183896) (xy 391.263415 -437.164278) (xy 391.283043 -437.150029)
			(xy 391.306114 -437.142544) (xy 391.318242 -437.142128) (xy 392.258042 -437.142128) (xy 392.270158 -437.142576)
			(xy 392.293201 -437.150073) (xy 392.312801 -437.164322) (xy 392.327041 -437.183928) (xy 392.334529 -437.206974)
			(xy 392.335004 -437.21909) (xy 392.335004 -438.089802) (xy 393.237974 -438.089802) (xy 393.238067 -438.075228)
			(xy 393.23972 -438.046127) (xy 393.241276 -438.031636) (xy 393.241276 -436.948072) (xy 393.239732 -436.93358)
			(xy 393.238079 -436.90448) (xy 393.237974 -436.889906) (xy 393.238067 -436.875332) (xy 393.23972 -436.846231)
			(xy 393.241276 -436.83174) (xy 393.241276 -436.219092) (xy 393.241709 -436.206985) (xy 393.249208 -436.183962)
			(xy 393.263466 -436.164391) (xy 393.283082 -436.150195) (xy 393.30613 -436.142771) (xy 393.318238 -436.142384)
			(xy 394.258038 -436.142384) (xy 394.270134 -436.142776) (xy 394.293143 -436.150248) (xy 394.312726 -436.164453)
			(xy 394.326974 -436.184004) (xy 394.334497 -436.206997) (xy 394.335 -436.219092) (xy 394.335 -438.760616)
			(xy 394.334597 -438.772726) (xy 394.327094 -438.795754) (xy 394.312828 -438.815326) (xy 394.293204 -438.82952)
			(xy 394.270149 -438.836941) (xy 394.258038 -438.837324) (xy 393.318238 -438.837324) (xy 393.306147 -438.83686)
			(xy 393.283141 -438.829409) (xy 393.263558 -438.815223) (xy 393.249307 -438.795686) (xy 393.241781 -438.772706)
			(xy 393.241276 -438.760616) (xy 393.241276 -438.147968) (xy 393.239731 -438.133476) (xy 393.238079 -438.104376)
			(xy 393.237974 -438.089802) (xy 392.335004 -438.089802) (xy 392.335004 -439.0898) (xy 395.23797 -439.0898)
			(xy 395.238063 -439.075226) (xy 395.239716 -439.046125) (xy 395.241272 -439.031634) (xy 395.241272 -437.94807)
			(xy 395.239728 -437.933578) (xy 395.238075 -437.904478) (xy 395.23797 -437.889904) (xy 395.238063 -437.87533)
			(xy 395.239716 -437.846229) (xy 395.241272 -437.831738) (xy 395.241272 -437.21909) (xy 395.241652 -437.206963)
			(xy 395.249151 -437.183898) (xy 395.263412 -437.164281) (xy 395.283038 -437.150031) (xy 395.306107 -437.142545)
			(xy 395.318234 -437.142128) (xy 396.258034 -437.142128) (xy 396.270149 -437.142583) (xy 396.293192 -437.150078)
			(xy 396.312792 -437.164325) (xy 396.327033 -437.18393) (xy 396.334521 -437.206975) (xy 396.334996 -437.21909)
			(xy 396.334996 -438.089802) (xy 398.237964 -438.089802) (xy 398.238081 -438.074717) (xy 398.239857 -438.044598)
			(xy 398.24152 -438.029604) (xy 398.24152 -436.950104) (xy 398.23985 -436.935111) (xy 398.238072 -436.904992)
			(xy 398.237964 -436.889906) (xy 398.238072 -436.87482) (xy 398.239854 -436.844702) (xy 398.24152 -436.829708)
			(xy 398.24152 -436.219092) (xy 398.241906 -436.207006) (xy 398.249379 -436.184018) (xy 398.263591 -436.164466)
			(xy 398.283151 -436.150263) (xy 398.306142 -436.1428) (xy 398.318228 -436.142384) (xy 399.258028 -436.142384)
			(xy 399.270103 -436.14284) (xy 399.29307 -436.150309) (xy 399.312606 -436.164508) (xy 399.3268 -436.184048)
			(xy 399.334263 -436.207017) (xy 399.334736 -436.219092) (xy 399.334736 -438.760616) (xy 399.33425 -438.772689)
			(xy 399.326786 -438.795651) (xy 399.312594 -438.815186) (xy 399.293062 -438.829381) (xy 399.270101 -438.836848)
			(xy 399.258028 -438.837324) (xy 398.318228 -438.837324) (xy 398.306148 -438.836864) (xy 398.283169 -438.829406)
			(xy 398.26362 -438.815211) (xy 398.249414 -438.79567) (xy 398.241943 -438.772695) (xy 398.24152 -438.760616)
			(xy 398.24152 -438.15) (xy 398.239849 -438.135007) (xy 398.238072 -438.104888) (xy 398.237964 -438.089802)
			(xy 396.334996 -438.089802) (xy 396.334996 -439.0898) (xy 400.23796 -439.0898) (xy 400.238077 -439.074715)
			(xy 400.239853 -439.044596) (xy 400.241516 -439.029602) (xy 400.241516 -437.950102) (xy 400.239845 -437.935109)
			(xy 400.238068 -437.90499) (xy 400.23796 -437.889904) (xy 400.238077 -437.874819) (xy 400.239853 -437.8447)
			(xy 400.241516 -437.829706) (xy 400.241516 -437.21909) (xy 400.241999 -437.207002) (xy 400.249455 -437.184006)
			(xy 400.263639 -437.164428) (xy 400.283167 -437.150177) (xy 400.306138 -437.142641) (xy 400.318224 -437.142128)
			(xy 401.258024 -437.142128) (xy 401.270137 -437.142496) (xy 401.29317 -437.150006) (xy 401.312745 -437.164279)
			(xy 401.326938 -437.183912) (xy 401.334353 -437.206975) (xy 401.334732 -437.21909) (xy 401.334732 -438.089802)
			(xy 402.237956 -438.089802) (xy 402.238073 -438.074717) (xy 402.239849 -438.044598) (xy 402.241512 -438.029604)
			(xy 402.241512 -436.950104) (xy 402.239842 -436.935111) (xy 402.238064 -436.904992) (xy 402.237956 -436.889906)
			(xy 402.238064 -436.87482) (xy 402.239846 -436.844702) (xy 402.241512 -436.829708) (xy 402.241512 -436.219092)
			(xy 402.241906 -436.207007) (xy 402.249378 -436.18402) (xy 402.263588 -436.164469) (xy 402.283146 -436.150265)
			(xy 402.306135 -436.142802) (xy 402.31822 -436.142384) (xy 403.25802 -436.142384) (xy 403.270095 -436.142847)
			(xy 403.293061 -436.150314) (xy 403.312597 -436.164511) (xy 403.326791 -436.18405) (xy 403.334255 -436.207017)
			(xy 403.334728 -436.219092) (xy 403.334728 -438.760616) (xy 403.33425 -438.772689) (xy 403.326785 -438.795654)
			(xy 403.312591 -438.815189) (xy 403.293057 -438.829383) (xy 403.270093 -438.836849) (xy 403.25802 -438.837324)
			(xy 402.31822 -438.837324) (xy 402.30614 -438.83687) (xy 402.283161 -438.82941) (xy 402.263611 -438.815214)
			(xy 402.249406 -438.795672) (xy 402.241935 -438.772696) (xy 402.241512 -438.760616) (xy 402.241512 -438.15)
			(xy 402.239841 -438.135007) (xy 402.238064 -438.104888) (xy 402.237956 -438.089802) (xy 401.334732 -438.089802)
			(xy 401.334732 -439.0898) (xy 404.237952 -439.0898) (xy 404.238069 -439.074715) (xy 404.239845 -439.044596)
			(xy 404.241508 -439.029602) (xy 404.241508 -437.950102) (xy 404.239837 -437.935109) (xy 404.23806 -437.90499)
			(xy 404.237952 -437.889904) (xy 404.238069 -437.874819) (xy 404.239845 -437.8447) (xy 404.241508 -437.829706)
			(xy 404.241508 -437.21909) (xy 404.241998 -437.207003) (xy 404.249454 -437.184008) (xy 404.263636 -437.164431)
			(xy 404.283162 -437.150179) (xy 404.306131 -437.142642) (xy 404.318216 -437.142128) (xy 405.258016 -437.142128)
			(xy 405.270129 -437.142503) (xy 405.293161 -437.15001) (xy 405.312736 -437.164281) (xy 405.326929 -437.183914)
			(xy 405.334345 -437.206976) (xy 405.334724 -437.21909) (xy 405.334724 -438.089802) (xy 406.237948 -438.089802)
			(xy 406.238065 -438.074717) (xy 406.239841 -438.044598) (xy 406.241504 -438.029604) (xy 406.241504 -436.950104)
			(xy 406.239834 -436.935111) (xy 406.238056 -436.904992) (xy 406.237948 -436.889906) (xy 406.238056 -436.87482)
			(xy 406.239838 -436.844702) (xy 406.241504 -436.829708) (xy 406.241504 -436.219092) (xy 406.241906 -436.207008)
			(xy 406.249377 -436.184023) (xy 406.263586 -436.164471) (xy 406.283141 -436.150268) (xy 406.306128 -436.142803)
			(xy 406.318212 -436.142384) (xy 407.258012 -436.142384) (xy 407.270086 -436.142854) (xy 407.293053 -436.150319)
			(xy 407.312589 -436.164514) (xy 407.326783 -436.184051) (xy 407.334247 -436.207018) (xy 407.33472 -436.219092)
			(xy 407.33472 -438.760616) (xy 407.334249 -438.77269) (xy 407.326784 -438.795656) (xy 407.312589 -438.815191)
			(xy 407.293052 -438.829386) (xy 407.270086 -438.83685) (xy 407.258012 -438.837324) (xy 406.318212 -438.837324)
			(xy 406.30614 -438.836826) (xy 406.283176 -438.829369) (xy 406.26364 -438.81518) (xy 406.249444 -438.79565)
			(xy 406.241979 -438.772688) (xy 406.241504 -438.760616) (xy 406.241504 -438.15) (xy 406.239833 -438.135007)
			(xy 406.238056 -438.104888) (xy 406.237948 -438.089802) (xy 405.334724 -438.089802) (xy 405.334724 -439.0898)
			(xy 408.237944 -439.0898) (xy 408.238061 -439.074715) (xy 408.239837 -439.044596) (xy 408.2415 -439.029602)
			(xy 408.2415 -437.950102) (xy 408.239829 -437.935109) (xy 408.238052 -437.90499) (xy 408.237944 -437.889904)
			(xy 408.238061 -437.874819) (xy 408.239837 -437.8447) (xy 408.2415 -437.829706) (xy 408.2415 -437.21909)
			(xy 408.241998 -437.207004) (xy 408.249453 -437.18401) (xy 408.263633 -437.164434) (xy 408.283157 -437.150182)
			(xy 408.306124 -437.142643) (xy 408.318208 -437.142128) (xy 409.258008 -437.142128) (xy 409.27012 -437.14251)
			(xy 409.293152 -437.150015) (xy 409.312728 -437.164284) (xy 409.326921 -437.183915) (xy 409.334337 -437.206976)
			(xy 409.334716 -437.21909) (xy 409.334716 -438.089802) (xy 410.23794 -438.089802) (xy 410.238057 -438.074717)
			(xy 410.239833 -438.044598) (xy 410.241496 -438.029604) (xy 410.241496 -436.950104) (xy 410.239826 -436.935111)
			(xy 410.238048 -436.904992) (xy 410.23794 -436.889906) (xy 410.23805 -436.87482) (xy 410.239832 -436.844702)
			(xy 410.241496 -436.829708) (xy 410.241496 -436.219092) (xy 410.241958 -436.207017) (xy 410.249423 -436.184049)
			(xy 410.26362 -436.164511) (xy 410.283159 -436.150317) (xy 410.306129 -436.142856) (xy 410.318204 -436.142384)
			(xy 411.258004 -436.142384) (xy 411.270078 -436.142861) (xy 411.293044 -436.150323) (xy 411.31258 -436.164517)
			(xy 411.326775 -436.184053) (xy 411.334239 -436.207018) (xy 411.334712 -436.219092) (xy 411.334712 -438.760616)
			(xy 411.334249 -438.772691) (xy 411.326783 -438.795658) (xy 411.312586 -438.815194) (xy 411.293047 -438.829388)
			(xy 411.270079 -438.836851) (xy 411.258004 -438.837324) (xy 410.318204 -438.837324) (xy 410.306131 -438.836833)
			(xy 410.283167 -438.829373) (xy 410.263631 -438.815183) (xy 410.249436 -438.795651) (xy 410.241971 -438.772689)
			(xy 410.241496 -438.760616) (xy 410.241496 -438.15) (xy 410.239825 -438.135007) (xy 410.238048 -438.104888)
			(xy 410.23794 -438.089802) (xy 409.334716 -438.089802) (xy 409.334716 -439.0898) (xy 412.237936 -439.0898)
			(xy 412.238053 -439.074715) (xy 412.239829 -439.044596) (xy 412.241492 -439.029602) (xy 412.241492 -437.950102)
			(xy 412.239821 -437.935109) (xy 412.238044 -437.90499) (xy 412.237936 -437.889904) (xy 412.238053 -437.874819)
			(xy 412.239829 -437.8447) (xy 412.241492 -437.829706) (xy 412.241492 -437.21909) (xy 412.241998 -437.207005)
			(xy 412.249452 -437.184012) (xy 412.26363 -437.164436) (xy 412.283152 -437.150184) (xy 412.306117 -437.142644)
			(xy 412.3182 -437.142128) (xy 413.258 -437.142128) (xy 413.270112 -437.142516) (xy 413.293144 -437.150019)
			(xy 413.312719 -437.164287) (xy 413.326913 -437.183916) (xy 413.334329 -437.206977) (xy 413.334708 -437.21909)
			(xy 413.334708 -439.760614) (xy 413.334206 -439.7727) (xy 413.326751 -439.795693) (xy 413.312572 -439.815268)
			(xy 413.293049 -439.82952) (xy 413.270084 -439.83706) (xy 413.258 -439.837576) (xy 412.3182 -439.837576)
			(xy 412.306089 -439.837184) (xy 412.283057 -439.829681) (xy 412.263482 -439.815414) (xy 412.249288 -439.795786)
			(xy 412.241872 -439.772727) (xy 412.241492 -439.760614) (xy 412.241492 -439.149998) (xy 412.239821 -439.135005)
			(xy 412.238044 -439.104886) (xy 412.237936 -439.0898) (xy 409.334716 -439.0898) (xy 409.334716 -439.760614)
			(xy 409.334304 -439.772709) (xy 409.326838 -439.795717) (xy 409.312639 -439.815301) (xy 409.293091 -439.829549)
			(xy 409.270101 -439.837073) (xy 409.258008 -439.837576) (xy 408.318208 -439.837576) (xy 408.306097 -439.837177)
			(xy 408.283066 -439.829677) (xy 408.263491 -439.815412) (xy 408.249296 -439.795785) (xy 408.24188 -439.772726)
			(xy 408.2415 -439.760614) (xy 408.2415 -439.149998) (xy 408.239829 -439.135005) (xy 408.238052 -439.104886)
			(xy 408.237944 -439.0898) (xy 405.334724 -439.0898) (xy 405.334724 -439.760614) (xy 405.334304 -439.772708)
			(xy 405.326839 -439.795715) (xy 405.312642 -439.815298) (xy 405.293096 -439.829547) (xy 405.270109 -439.837072)
			(xy 405.258016 -439.837576) (xy 404.318216 -439.837576) (xy 404.306106 -439.83717) (xy 404.283075 -439.829672)
			(xy 404.263499 -439.815408) (xy 404.249305 -439.795783) (xy 404.241888 -439.772726) (xy 404.241508 -439.760614)
			(xy 404.241508 -439.149998) (xy 404.239837 -439.135005) (xy 404.23806 -439.104886) (xy 404.237952 -439.0898)
			(xy 401.334732 -439.0898) (xy 401.334732 -439.760614) (xy 401.334304 -439.772707) (xy 401.32684 -439.795713)
			(xy 401.312645 -439.815295) (xy 401.293101 -439.829544) (xy 401.270116 -439.837071) (xy 401.258024 -439.837576)
			(xy 400.318224 -439.837576) (xy 400.306114 -439.837163) (xy 400.283083 -439.829667) (xy 400.263508 -439.815406)
			(xy 400.249313 -439.795781) (xy 400.241896 -439.772725) (xy 400.241516 -439.760614) (xy 400.241516 -439.149998)
			(xy 400.239845 -439.135005) (xy 400.238068 -439.104886) (xy 400.23796 -439.0898) (xy 396.334996 -439.0898)
			(xy 396.334996 -439.760614) (xy 396.334501 -439.772726) (xy 396.327014 -439.795764) (xy 396.312777 -439.815363)
			(xy 396.293182 -439.829605) (xy 396.270146 -439.837098) (xy 396.258034 -439.837576) (xy 395.318234 -439.837576)
			(xy 395.306114 -439.837111) (xy 395.283059 -439.82963) (xy 395.263445 -439.81539) (xy 395.249192 -439.795784)
			(xy 395.241696 -439.772733) (xy 395.241272 -439.760614) (xy 395.241272 -439.147966) (xy 395.239727 -439.133474)
			(xy 395.238075 -439.104374) (xy 395.23797 -439.0898) (xy 392.335004 -439.0898) (xy 392.335004 -439.760614)
			(xy 392.334501 -439.772725) (xy 392.327015 -439.795762) (xy 392.31278 -439.81536) (xy 392.293187 -439.829602)
			(xy 392.270153 -439.837097) (xy 392.258042 -439.837576) (xy 391.318242 -439.837576) (xy 391.306123 -439.837105)
			(xy 391.283068 -439.829626) (xy 391.263453 -439.815387) (xy 391.2492 -439.795783) (xy 391.241704 -439.772733)
			(xy 391.24128 -439.760614) (xy 391.24128 -439.147966) (xy 391.239735 -439.133474) (xy 391.238083 -439.104374)
			(xy 391.237978 -439.0898) (xy 388.335012 -439.0898) (xy 388.335012 -439.760614) (xy 388.334501 -439.772724)
			(xy 388.327016 -439.79576) (xy 388.312782 -439.815357) (xy 388.293192 -439.8296) (xy 388.27016 -439.837096)
			(xy 388.25805 -439.837576) (xy 387.31825 -439.837576) (xy 387.306134 -439.837131) (xy 387.283092 -439.829632)
			(xy 387.263492 -439.815382) (xy 387.249252 -439.795776) (xy 387.241763 -439.77273) (xy 387.241288 -439.760614)
			(xy 387.241288 -439.147966) (xy 387.239743 -439.133474) (xy 387.238091 -439.104374) (xy 387.237986 -439.0898)
			(xy 384.33502 -439.0898) (xy 384.33502 -439.760614) (xy 384.334651 -439.772742) (xy 384.32715 -439.795808)
			(xy 384.312886 -439.815426) (xy 384.293258 -439.829675) (xy 384.270186 -439.83716) (xy 384.258058 -439.837576)
			(xy 383.318258 -439.837576) (xy 383.306143 -439.837124) (xy 383.2831 -439.829627) (xy 383.263501 -439.815379)
			(xy 383.24926 -439.795774) (xy 383.241771 -439.77273) (xy 383.241296 -439.760614) (xy 383.241296 -439.147966)
			(xy 383.239751 -439.133474) (xy 383.238099 -439.104374) (xy 383.237994 -439.0898) (xy 375.249353 -439.0898)
			(xy 375.12219 -439.229109) (xy 374.978015 -439.375202) (xy 374.828262 -439.515571) (xy 374.673158 -439.650004)
			(xy 374.512939 -439.778297) (xy 374.347846 -439.900255) (xy 374.178131 -440.015694) (xy 374.00405 -440.124438)
			(xy 373.825868 -440.226324) (xy 373.735092 -440.274202) (xy 373.721975 -440.281619) (xy 373.700446 -440.302683)
			(xy 373.685993 -440.329108) (xy 373.679871 -440.358598) (xy 373.68261 -440.388592) (xy 373.693975 -440.416484)
			(xy 373.712976 -440.439853) (xy 373.737964 -440.456668) (xy 373.766769 -440.465468) (xy 373.781828 -440.465972)
			(xy 381.238252 -440.465972) (xy 381.244094 -440.42203) (xy 381.248823 -440.390461) (xy 381.265126 -440.328742)
			(xy 381.288996 -440.269538) (xy 381.320062 -440.213771) (xy 381.357839 -440.162313) (xy 381.401736 -440.115967)
			(xy 381.451069 -440.075455) (xy 381.505068 -440.04141) (xy 381.562891 -440.014364) (xy 381.623635 -439.994738)
			(xy 381.686351 -439.982838) (xy 381.750062 -439.978851) (xy 381.813773 -439.982838) (xy 381.876489 -439.994738)
			(xy 381.937233 -440.014364) (xy 381.995056 -440.04141) (xy 382.049055 -440.075455) (xy 382.098388 -440.115967)
			(xy 382.142285 -440.162313) (xy 382.180062 -440.213771) (xy 382.211128 -440.269538) (xy 382.234998 -440.328742)
			(xy 382.251301 -440.390461) (xy 382.25603 -440.42203) (xy 382.261872 -440.465972) (xy 385.238244 -440.465972)
			(xy 385.244086 -440.42203) (xy 385.248815 -440.390461) (xy 385.265118 -440.328742) (xy 385.288988 -440.269538)
			(xy 385.320054 -440.213771) (xy 385.357831 -440.162313) (xy 385.401728 -440.115967) (xy 385.451061 -440.075455)
			(xy 385.50506 -440.04141) (xy 385.562883 -440.014364) (xy 385.623627 -439.994738) (xy 385.686343 -439.982838)
			(xy 385.750054 -439.978851) (xy 385.813765 -439.982838) (xy 385.876481 -439.994738) (xy 385.937225 -440.014364)
			(xy 385.995048 -440.04141) (xy 386.049047 -440.075455) (xy 386.09838 -440.115967) (xy 386.142277 -440.162313)
			(xy 386.180054 -440.213771) (xy 386.21112 -440.269538) (xy 386.23499 -440.328742) (xy 386.251293 -440.390461)
			(xy 386.256022 -440.42203) (xy 386.261864 -440.465972) (xy 389.238236 -440.465972) (xy 389.244078 -440.42203)
			(xy 389.248807 -440.390461) (xy 389.26511 -440.328742) (xy 389.28898 -440.269538) (xy 389.320046 -440.213771)
			(xy 389.357823 -440.162313) (xy 389.40172 -440.115967) (xy 389.451053 -440.075455) (xy 389.505052 -440.04141)
			(xy 389.562875 -440.014364) (xy 389.623619 -439.994738) (xy 389.686335 -439.982838) (xy 389.750046 -439.978851)
			(xy 389.813757 -439.982838) (xy 389.876473 -439.994738) (xy 389.937217 -440.014364) (xy 389.99504 -440.04141)
			(xy 390.049039 -440.075455) (xy 390.098372 -440.115967) (xy 390.142269 -440.162313) (xy 390.180046 -440.213771)
			(xy 390.211112 -440.269538) (xy 390.234982 -440.328742) (xy 390.251285 -440.390461) (xy 390.256014 -440.42203)
			(xy 390.261856 -440.465972) (xy 393.238228 -440.465972) (xy 393.24407 -440.42203) (xy 393.248799 -440.390461)
			(xy 393.265102 -440.328742) (xy 393.288972 -440.269538) (xy 393.320038 -440.213771) (xy 393.357815 -440.162313)
			(xy 393.401712 -440.115967) (xy 393.451045 -440.075455) (xy 393.505044 -440.04141) (xy 393.562867 -440.014364)
			(xy 393.623611 -439.994738) (xy 393.686327 -439.982838) (xy 393.750038 -439.978851) (xy 393.813749 -439.982838)
			(xy 393.876465 -439.994738) (xy 393.937209 -440.014364) (xy 393.995032 -440.04141) (xy 394.049031 -440.075455)
			(xy 394.098364 -440.115967) (xy 394.142261 -440.162313) (xy 394.180038 -440.213771) (xy 394.211104 -440.269538)
			(xy 394.234974 -440.328742) (xy 394.251277 -440.390461) (xy 394.256006 -440.42203) (xy 394.261848 -440.465972)
			(xy 398.238218 -440.465972) (xy 398.24406 -440.42203) (xy 398.248789 -440.390461) (xy 398.265092 -440.328742)
			(xy 398.288962 -440.269538) (xy 398.320028 -440.213771) (xy 398.357805 -440.162313) (xy 398.401702 -440.115967)
			(xy 398.451035 -440.075455) (xy 398.505034 -440.04141) (xy 398.562857 -440.014364) (xy 398.623601 -439.994738)
			(xy 398.686317 -439.982838) (xy 398.750028 -439.978851) (xy 398.813739 -439.982838) (xy 398.876455 -439.994738)
			(xy 398.937199 -440.014364) (xy 398.995022 -440.04141) (xy 399.049021 -440.075455) (xy 399.098354 -440.115967)
			(xy 399.142251 -440.162313) (xy 399.180028 -440.213771) (xy 399.211094 -440.269538) (xy 399.234964 -440.328742)
			(xy 399.251267 -440.390461) (xy 399.255996 -440.42203) (xy 399.261838 -440.465972) (xy 402.23821 -440.465972)
			(xy 402.244052 -440.42203) (xy 402.248781 -440.390461) (xy 402.265084 -440.328742) (xy 402.288954 -440.269538)
			(xy 402.32002 -440.213771) (xy 402.357797 -440.162313) (xy 402.401694 -440.115967) (xy 402.451027 -440.075455)
			(xy 402.505026 -440.04141) (xy 402.562849 -440.014364) (xy 402.623593 -439.994738) (xy 402.686309 -439.982838)
			(xy 402.75002 -439.978851) (xy 402.813731 -439.982838) (xy 402.876447 -439.994738) (xy 402.937191 -440.014364)
			(xy 402.995014 -440.04141) (xy 403.049013 -440.075455) (xy 403.098346 -440.115967) (xy 403.142243 -440.162313)
			(xy 403.18002 -440.213771) (xy 403.211086 -440.269538) (xy 403.234956 -440.328742) (xy 403.251259 -440.390461)
			(xy 403.255988 -440.42203) (xy 403.26183 -440.465972) (xy 406.238202 -440.465972) (xy 406.244044 -440.42203)
			(xy 406.248773 -440.390461) (xy 406.265076 -440.328742) (xy 406.288946 -440.269538) (xy 406.320012 -440.213771)
			(xy 406.357789 -440.162313) (xy 406.401686 -440.115967) (xy 406.451019 -440.075455) (xy 406.505018 -440.04141)
			(xy 406.562841 -440.014364) (xy 406.623585 -439.994738) (xy 406.686301 -439.982838) (xy 406.750012 -439.978851)
			(xy 406.813723 -439.982838) (xy 406.876439 -439.994738) (xy 406.937183 -440.014364) (xy 406.995006 -440.04141)
			(xy 407.049005 -440.075455) (xy 407.098338 -440.115967) (xy 407.142235 -440.162313) (xy 407.180012 -440.213771)
			(xy 407.211078 -440.269538) (xy 407.234948 -440.328742) (xy 407.251251 -440.390461) (xy 407.25598 -440.42203)
			(xy 407.261822 -440.465972) (xy 410.238194 -440.465972) (xy 410.244036 -440.42203) (xy 410.248765 -440.390461)
			(xy 410.265068 -440.328742) (xy 410.288938 -440.269538) (xy 410.320004 -440.213771) (xy 410.357781 -440.162313)
			(xy 410.401678 -440.115967) (xy 410.451011 -440.075455) (xy 410.50501 -440.04141) (xy 410.562833 -440.014364)
			(xy 410.623577 -439.994738) (xy 410.686293 -439.982838) (xy 410.750004 -439.978851) (xy 410.813715 -439.982838)
			(xy 410.876431 -439.994738) (xy 410.937175 -440.014364) (xy 410.994998 -440.04141) (xy 411.048997 -440.075455)
			(xy 411.09833 -440.115967) (xy 411.142227 -440.162313) (xy 411.180004 -440.213771) (xy 411.21107 -440.269538)
			(xy 411.23494 -440.328742) (xy 411.251243 -440.390461) (xy 411.255972 -440.42203) (xy 411.261814 -440.465972)
			(xy 456.316588 -440.465972) (xy 456.331649 -440.465431) (xy 456.360462 -440.456649) (xy 456.385461 -440.439844)
			(xy 456.404472 -440.416479) (xy 456.415841 -440.388585) (xy 456.41858 -440.358587) (xy 456.41245 -440.329096)
			(xy 456.397986 -440.302674) (xy 456.376443 -440.28162) (xy 456.363324 -440.274202) (xy 456.272548 -440.226324)
			(xy 456.094369 -440.124435) (xy 455.920291 -440.015688) (xy 455.750579 -439.900247) (xy 455.585489 -439.778286)
			(xy 455.425272 -439.649992) (xy 455.27017 -439.515557) (xy 455.12042 -439.375187) (xy 454.976247 -439.229093)
			(xy 454.837871 -439.077498) (xy 454.705501 -438.920631) (xy 454.579338 -438.75873) (xy 454.459573 -438.59204)
			(xy 454.346388 -438.420815) (xy 454.239954 -438.245313) (xy 454.140433 -438.0658) (xy 454.047975 -437.88255)
			(xy 453.962722 -437.69584) (xy 453.884801 -437.505952) (xy 453.814331 -437.313175) (xy 453.751419 -437.1178)
			(xy 453.69616 -436.920125) (xy 453.648638 -436.720448) (xy 453.608926 -436.519073) (xy 453.577082 -436.316305)
			(xy 453.553157 -436.11245) (xy 453.537185 -435.907819) (xy 453.529191 -435.702721) (xy 453.528684 -435.600094)
			(xy 453.529186 -435.49659) (xy 453.537313 -435.289742) (xy 453.553555 -435.083372) (xy 453.577887 -434.877798)
			(xy 453.61027 -434.673339) (xy 453.650656 -434.470309) (xy 453.698982 -434.26902) (xy 453.755172 -434.069784)
			(xy 453.819142 -433.872908) (xy 453.890791 -433.678695) (xy 453.970011 -433.487445) (xy 454.056677 -433.299452)
			(xy 454.150657 -433.115007) (xy 454.251807 -432.934394) (xy 454.359969 -432.757891) (xy 454.474977 -432.58577)
			(xy 454.596654 -432.418298) (xy 454.724812 -432.255731) (xy 454.859254 -432.098322) (xy 454.999772 -431.946312)
			(xy 455.146149 -431.799936) (xy 455.298161 -431.659419) (xy 455.455572 -431.524979) (xy 455.618139 -431.396823)
			(xy 455.785613 -431.275147) (xy 455.957735 -431.160141) (xy 456.134239 -431.05198) (xy 456.314853 -430.950833)
			(xy 456.499299 -430.856854) (xy 456.687293 -430.77019) (xy 456.878544 -430.690973) (xy 457.072757 -430.619325)
			(xy 457.269634 -430.555357) (xy 457.468871 -430.499168) (xy 457.670159 -430.450845) (xy 457.87319 -430.410461)
			(xy 458.07765 -430.37808) (xy 458.283223 -430.35375) (xy 458.489593 -430.33751) (xy 458.696442 -430.329385)
			(xy 458.799946 -430.328832) (xy 458.903262 -430.329336) (xy 459.109734 -430.337432) (xy 459.315731 -430.353613)
			(xy 459.520936 -430.377856) (xy 459.725032 -430.410122) (xy 459.927707 -430.450362) (xy 460.12865 -430.498514)
			(xy 460.327551 -430.554505) (xy 460.524105 -430.618248) (xy 460.718009 -430.689644) (xy 460.908967 -430.768586)
			(xy 461.096684 -430.85495) (xy 461.280872 -430.948606) (xy 461.461248 -431.049407) (xy 461.637535 -431.157201)
			(xy 461.809462 -431.27182) (xy 461.976765 -431.39309) (xy 462.139187 -431.520823) (xy 462.296477 -431.654823)
			(xy 462.448396 -431.794885) (xy 462.594708 -431.940794) (xy 462.73519 -432.092324) (xy 462.869625 -432.249243)
			(xy 462.997807 -432.411311) (xy 463.119539 -432.578278) (xy 463.234633 -432.749887) (xy 463.342914 -432.925875)
			(xy 463.444214 -433.105972) (xy 463.538378 -433.2899) (xy 463.582258 -433.383436) (xy 463.588458 -433.395758)
			(xy 463.606302 -433.416779) (xy 463.629121 -433.432257) (xy 463.65525 -433.441065) (xy 463.682782 -433.44256)
			(xy 463.709711 -433.436633) (xy 463.734071 -433.423715) (xy 463.754087 -433.40475) (xy 463.768297 -433.381121)
			(xy 463.775666 -433.354551) (xy 463.77606 -433.340764) (xy 463.77606 -409.52801) (xy 463.77658 -409.441525)
			(xy 463.785062 -409.268764) (xy 463.802011 -409.096628) (xy 463.827387 -408.92553) (xy 463.861128 -408.755884)
			(xy 463.903153 -408.588097) (xy 463.953361 -408.422575) (xy 464.01163 -408.259716) (xy 464.07782 -408.099913)
			(xy 464.151773 -407.94355) (xy 464.233309 -407.791004) (xy 464.322232 -407.642643) (xy 464.418328 -407.498824)
			(xy 464.521366 -407.359894) (xy 464.631097 -407.226187) (xy 464.747256 -407.098026) (xy 464.808062 -407.036524)
			(xy 466.636608 -405.207978) (xy 466.658299 -405.185621) (xy 466.696247 -405.13622) (xy 466.72742 -405.082289)
			(xy 466.751285 -405.024748) (xy 466.767434 -404.964585) (xy 466.77559 -404.902828) (xy 466.776054 -404.871682)
			(xy 466.776054 -363.98835) (xy 466.775577 -363.974051) (xy 466.767657 -363.946572) (xy 466.752426 -363.922368)
			(xy 466.731078 -363.903339) (xy 466.705289 -363.890978) (xy 466.677084 -363.886257) (xy 466.648676 -363.889545)
			(xy 466.622295 -363.900584) (xy 466.600011 -363.918508) (xy 466.591396 -363.92993) (xy 466.530259 -364.016186)
			(xy 466.402259 -364.18449) (xy 466.267899 -364.347762) (xy 466.127377 -364.505761) (xy 465.980899 -364.658255)
			(xy 465.828681 -364.80502) (xy 465.670947 -364.94584) (xy 465.507928 -365.080507) (xy 465.339866 -365.208824)
			(xy 465.167006 -365.330602) (xy 464.989604 -365.445661) (xy 464.80792 -365.553833) (xy 464.622221 -365.654958)
			(xy 464.432781 -365.748887) (xy 464.239878 -365.835483) (xy 464.043796 -365.914617) (xy 463.844824 -365.986174)
			(xy 463.643255 -366.050049) (xy 463.439384 -366.106146) (xy 463.233512 -366.154384) (xy 463.025941 -366.194692)
			(xy 462.816977 -366.227011) (xy 462.606928 -366.251292) (xy 462.396102 -366.267501) (xy 462.18481 -366.275612)
			(xy 462.079086 -366.276128) (xy 462.078832 -366.276128) (xy 461.973234 -366.275629) (xy 461.762192 -366.267541)
			(xy 461.551616 -366.251375) (xy 461.341813 -366.227156) (xy 461.133091 -366.194918) (xy 460.925758 -366.154709)
			(xy 460.720117 -366.106588) (xy 460.516469 -366.050626) (xy 460.315115 -365.986905) (xy 460.11635 -365.915518)
			(xy 459.920464 -365.83657) (xy 459.727746 -365.750177) (xy 459.538479 -365.656465) (xy 459.35294 -365.555573)
			(xy 459.171402 -365.447649) (xy 458.99413 -365.33285) (xy 458.821386 -365.211345) (xy 458.653423 -365.083313)
			(xy 458.490487 -364.948942) (xy 458.332817 -364.808428) (xy 458.180645 -364.661978) (xy 458.034194 -364.509807)
			(xy 457.893679 -364.352138) (xy 457.759307 -364.189202) (xy 457.631274 -364.02124) (xy 457.509768 -363.848496)
			(xy 457.394968 -363.671226) (xy 457.287042 -363.489688) (xy 457.186149 -363.304149) (xy 457.092437 -363.114883)
			(xy 457.006043 -362.922165) (xy 456.927094 -362.72628) (xy 456.855706 -362.527515) (xy 456.791983 -362.326161)
			(xy 456.73602 -362.122514) (xy 456.687898 -361.916874) (xy 456.647688 -361.70954) (xy 456.615449 -361.500819)
			(xy 456.591228 -361.291016) (xy 456.575061 -361.08044) (xy 456.566971 -360.869398) (xy 456.566971 -360.658202)
			(xy 456.575061 -360.44716) (xy 456.591228 -360.236584) (xy 456.615449 -360.026781) (xy 456.647688 -359.81806)
			(xy 456.687898 -359.610726) (xy 456.73602 -359.405086) (xy 456.791983 -359.201439) (xy 456.855706 -359.000085)
			(xy 456.927094 -358.80132) (xy 457.006043 -358.605435) (xy 457.092437 -358.412717) (xy 457.186149 -358.223451)
			(xy 457.287042 -358.037912) (xy 457.394968 -357.856374) (xy 457.509768 -357.679104) (xy 457.631274 -357.50636)
			(xy 457.759307 -357.338398) (xy 457.893679 -357.175462) (xy 458.034194 -357.017793) (xy 458.180645 -356.865622)
			(xy 458.332817 -356.719172) (xy 458.490487 -356.578658) (xy 458.653423 -356.444287) (xy 458.821386 -356.316255)
			(xy 458.99413 -356.19475) (xy 459.171402 -356.079951) (xy 459.35294 -355.972027) (xy 459.538479 -355.871135)
			(xy 459.727746 -355.777423) (xy 459.920464 -355.69103) (xy 460.11635 -355.612082) (xy 460.315115 -355.540695)
			(xy 460.516469 -355.476974) (xy 460.720117 -355.421012) (xy 460.925758 -355.372891) (xy 461.133091 -355.332682)
			(xy 461.341813 -355.300444) (xy 461.551616 -355.276225) (xy 461.762192 -355.260059) (xy 461.973234 -355.251971)
			(xy 462.078832 -355.251512) (xy 462.079086 -355.251512) (xy 462.18481 -355.252014) (xy 462.396104 -355.260122)
			(xy 462.606931 -355.276328) (xy 462.816981 -355.300606) (xy 463.025946 -355.332922) (xy 463.233518 -355.373229)
			(xy 463.439391 -355.421465) (xy 463.643263 -355.477562) (xy 463.844834 -355.541436) (xy 464.043807 -355.612992)
			(xy 464.239889 -355.692127) (xy 464.432792 -355.778723) (xy 464.622233 -355.872653) (xy 464.807932 -355.97378)
			(xy 464.989616 -356.081953) (xy 465.167018 -356.197014) (xy 465.339878 -356.318794) (xy 465.507939 -356.447113)
			(xy 465.670956 -356.581783) (xy 465.828689 -356.722606) (xy 465.980905 -356.869374) (xy 466.127381 -357.021871)
			(xy 466.267901 -357.179874) (xy 466.402258 -357.343149) (xy 466.530254 -357.511457) (xy 466.591396 -357.59771)
			(xy 466.600021 -357.609122) (xy 466.622316 -357.627023) (xy 466.648698 -357.638046) (xy 466.677102 -357.641324)
			(xy 466.705302 -357.636603) (xy 466.731089 -357.624252) (xy 466.752443 -357.605238) (xy 466.767691 -357.581051)
			(xy 466.77564 -357.553586) (xy 466.776054 -357.53929) (xy 466.776054 -348.99346) (xy 466.775525 -348.978732)
			(xy 466.76705 -348.95052) (xy 466.750876 -348.9259) (xy 466.728347 -348.906921) (xy 466.701338 -348.895162)
			(xy 466.672096 -348.891601) (xy 466.643055 -348.896534) (xy 466.616629 -348.909551) (xy 466.595018 -348.929569)
			(xy 466.58002 -348.954923) (xy 466.575902 -348.969076) (xy 466.550644 -349.068848) (xy 466.493331 -349.266545)
			(xy 466.428343 -349.461854) (xy 466.35578 -349.654477) (xy 466.275752 -349.844119) (xy 466.188381 -350.030493)
			(xy 466.093801 -350.213314) (xy 465.992156 -350.392303) (xy 465.8836 -350.567188) (xy 465.768299 -350.737701)
			(xy 465.64643 -350.903583) (xy 465.518177 -351.06458) (xy 465.383737 -351.220448) (xy 465.243314 -351.370948)
			(xy 465.097123 -351.515851) (xy 464.945386 -351.654937) (xy 464.788334 -351.787992) (xy 464.626208 -351.914815)
			(xy 464.459255 -352.035212) (xy 464.287728 -352.148999) (xy 464.11189 -352.256003) (xy 463.932008 -352.35606)
			(xy 463.748357 -352.449018) (xy 463.561217 -352.534736) (xy 463.370874 -352.613083) (xy 463.177616 -352.683938)
			(xy 462.98174 -352.747195) (xy 462.783544 -352.802757) (xy 462.583329 -352.850538) (xy 462.381402 -352.890467)
			(xy 462.17807 -352.922482) (xy 461.973643 -352.946535) (xy 461.768433 -352.962588) (xy 461.562753 -352.970617)
			(xy 461.459834 -352.9711) (xy 461.357606 -352.970611) (xy 461.153305 -352.962685) (xy 460.949464 -352.946842)
			(xy 460.746391 -352.923108) (xy 460.544391 -352.891517) (xy 460.343768 -352.852117) (xy 460.144823 -352.804967)
			(xy 459.947857 -352.750139) (xy 459.753164 -352.687714) (xy 459.561039 -352.617788) (xy 459.371769 -352.540463)
			(xy 459.18564 -352.455859) (xy 459.002932 -352.3641) (xy 458.823919 -352.265326) (xy 458.64887 -352.159685)
			(xy 458.47805 -352.047335) (xy 458.311714 -351.928447) (xy 458.150114 -351.803198) (xy 457.993491 -351.671777)
			(xy 457.842083 -351.534382) (xy 457.696116 -351.391219) (xy 457.555809 -351.242504) (xy 457.421375 -351.088461)
			(xy 457.293015 -350.92932) (xy 457.170922 -350.765322) (xy 457.055281 -350.596713) (xy 456.946264 -350.423747)
			(xy 456.844036 -350.246684) (xy 456.74875 -350.065789) (xy 456.660551 -349.881337) (xy 456.57957 -349.693603)
			(xy 456.505929 -349.50287) (xy 456.43974 -349.309425) (xy 456.381101 -349.113559) (xy 456.330101 -348.915566)
			(xy 456.286817 -348.715745) (xy 456.251314 -348.514396) (xy 456.223644 -348.311821) (xy 456.203851 -348.108326)
			(xy 456.191963 -347.904217) (xy 456.187998 -347.6998) (xy 456.191963 -347.495383) (xy 456.203851 -347.291274)
			(xy 456.223644 -347.087779) (xy 456.251314 -346.885204) (xy 456.286817 -346.683855) (xy 456.330101 -346.484034)
			(xy 456.381101 -346.286041) (xy 456.43974 -346.090175) (xy 456.505929 -345.89673) (xy 456.57957 -345.705997)
			(xy 456.660551 -345.518263) (xy 456.74875 -345.333811) (xy 456.844036 -345.152916) (xy 456.946264 -344.975853)
			(xy 457.055281 -344.802887) (xy 457.170922 -344.634278) (xy 457.293015 -344.47028) (xy 457.421375 -344.311139)
			(xy 457.555809 -344.157096) (xy 457.696116 -344.008381) (xy 457.842083 -343.865218) (xy 457.993491 -343.727823)
			(xy 458.150114 -343.596402) (xy 458.311714 -343.471153) (xy 458.47805 -343.352265) (xy 458.64887 -343.239915)
			(xy 458.823919 -343.134274) (xy 459.002932 -343.0355) (xy 459.18564 -342.943741) (xy 459.371769 -342.859137)
			(xy 459.561039 -342.781812) (xy 459.753164 -342.711886) (xy 459.947857 -342.649461) (xy 460.144823 -342.594633)
			(xy 460.343768 -342.547483) (xy 460.544391 -342.508083) (xy 460.746391 -342.476492) (xy 460.949464 -342.452758)
			(xy 461.153305 -342.436915) (xy 461.357606 -342.428989) (xy 461.459834 -342.428576) (xy 461.562752 -342.429073)
			(xy 461.76843 -342.43711) (xy 461.973639 -342.45317) (xy 462.178063 -342.477228) (xy 462.381393 -342.509249)
			(xy 462.583318 -342.549182) (xy 462.78353 -342.596968) (xy 462.981724 -342.652533) (xy 463.177597 -342.715792)
			(xy 463.370852 -342.78665) (xy 463.561194 -342.864999) (xy 463.748331 -342.950718) (xy 463.93198 -343.043677)
			(xy 464.11186 -343.143734) (xy 464.287697 -343.250737) (xy 464.459223 -343.364523) (xy 464.626175 -343.484919)
			(xy 464.788301 -343.61174) (xy 464.945353 -343.744793) (xy 465.09709 -343.883876) (xy 465.243282 -344.028776)
			(xy 465.383707 -344.179273) (xy 465.518149 -344.335136) (xy 465.646404 -344.49613) (xy 465.768277 -344.662007)
			(xy 465.883581 -344.832516) (xy 465.992141 -345.007396) (xy 466.093792 -345.186381) (xy 466.188378 -345.369197)
			(xy 466.275755 -345.555566) (xy 466.35579 -345.745205) (xy 466.428361 -345.937823) (xy 466.493357 -346.133127)
			(xy 466.550679 -346.33082) (xy 466.575902 -346.4306) (xy 466.57995 -346.444783) (xy 466.594956 -346.47016)
			(xy 466.616582 -346.490197) (xy 466.643028 -346.503228) (xy 466.672093 -346.508166) (xy 466.701358 -346.504602)
			(xy 466.728388 -346.492832) (xy 466.750934 -346.473835) (xy 466.767118 -346.449193) (xy 466.775594 -346.420956)
			(xy 466.776054 -346.406216) (xy 466.776054 -161.793682) (xy 466.775528 -161.778952) (xy 466.767057 -161.750734)
			(xy 466.750883 -161.726108) (xy 466.728353 -161.707125) (xy 466.70134 -161.695362) (xy 466.672094 -161.691801)
			(xy 466.643049 -161.696736) (xy 466.61662 -161.709757) (xy 466.595009 -161.729781) (xy 466.580013 -161.755141)
			(xy 466.575902 -161.769298) (xy 466.550633 -161.869063) (xy 466.4933 -162.066744) (xy 466.428294 -162.262037)
			(xy 466.355714 -162.454644) (xy 466.275671 -162.644271) (xy 466.188287 -162.830628) (xy 466.093695 -163.013433)
			(xy 465.992039 -163.192405) (xy 465.883474 -163.367273) (xy 465.768167 -163.537771) (xy 465.646291 -163.703637)
			(xy 465.518034 -163.864619) (xy 465.383591 -164.020472) (xy 465.243167 -164.170958) (xy 465.096975 -164.315848)
			(xy 464.945239 -164.454921) (xy 464.78819 -164.587965) (xy 464.626067 -164.714777) (xy 464.459118 -164.835164)
			(xy 464.287596 -164.948943) (xy 464.111764 -165.055939) (xy 463.931889 -165.15599) (xy 463.748246 -165.248943)
			(xy 463.561115 -165.334657) (xy 463.37078 -165.413001) (xy 463.177532 -165.483856) (xy 462.981666 -165.547113)
			(xy 462.783479 -165.602676) (xy 462.583275 -165.650461) (xy 462.381358 -165.690394) (xy 462.178036 -165.722415)
			(xy 461.973619 -165.746475) (xy 461.768419 -165.762537) (xy 461.562748 -165.770577) (xy 461.459834 -165.771068)
			(xy 461.357613 -165.770579) (xy 461.153324 -165.762653) (xy 460.949496 -165.746812) (xy 460.746436 -165.723079)
			(xy 460.544449 -165.69149) (xy 460.343838 -165.652092) (xy 460.144906 -165.604946) (xy 459.947952 -165.550121)
			(xy 459.753272 -165.4877) (xy 459.561158 -165.417778) (xy 459.371901 -165.340459) (xy 459.185783 -165.255859)
			(xy 459.003086 -165.164106) (xy 458.824085 -165.065338) (xy 458.649047 -164.959704) (xy 458.478238 -164.847361)
			(xy 458.311913 -164.72848) (xy 458.150322 -164.603239) (xy 457.99371 -164.471827) (xy 457.842311 -164.33444)
			(xy 457.696353 -164.191287) (xy 457.556055 -164.042581) (xy 457.421629 -163.888547) (xy 457.293277 -163.729417)
			(xy 457.171192 -163.565429) (xy 457.055558 -163.396831) (xy 456.946548 -163.223875) (xy 456.844326 -163.046823)
			(xy 456.749047 -162.86594) (xy 456.660853 -162.681499) (xy 456.579877 -162.493777) (xy 456.506241 -162.303056)
			(xy 456.440056 -162.109623) (xy 456.381421 -161.91377) (xy 456.330424 -161.71579) (xy 456.287143 -161.515981)
			(xy 456.251642 -161.314644) (xy 456.223974 -161.112083) (xy 456.204182 -160.908601) (xy 456.192294 -160.704504)
			(xy 456.18833 -160.5001) (xy 456.192294 -160.295696) (xy 456.204182 -160.091599) (xy 456.223974 -159.888117)
			(xy 456.251642 -159.685556) (xy 456.287143 -159.484219) (xy 456.330424 -159.28441) (xy 456.381421 -159.08643)
			(xy 456.440056 -158.890577) (xy 456.506241 -158.697144) (xy 456.579877 -158.506423) (xy 456.660853 -158.318701)
			(xy 456.749047 -158.13426) (xy 456.844326 -157.953377) (xy 456.946548 -157.776325) (xy 457.055558 -157.603369)
			(xy 457.171192 -157.434771) (xy 457.293277 -157.270783) (xy 457.421629 -157.111653) (xy 457.556055 -156.957619)
			(xy 457.696353 -156.808913) (xy 457.842311 -156.66576) (xy 457.99371 -156.528373) (xy 458.150322 -156.396961)
			(xy 458.311913 -156.27172) (xy 458.478238 -156.152839) (xy 458.649047 -156.040496) (xy 458.824085 -155.934862)
			(xy 459.003086 -155.836094) (xy 459.185783 -155.744341) (xy 459.371901 -155.659741) (xy 459.561158 -155.582422)
			(xy 459.753272 -155.5125) (xy 459.947952 -155.450079) (xy 460.144906 -155.395254) (xy 460.343838 -155.348108)
			(xy 460.544449 -155.30871) (xy 460.746436 -155.277121) (xy 460.949496 -155.253388) (xy 461.153324 -155.237547)
			(xy 461.357613 -155.229621) (xy 461.459834 -155.229052) (xy 461.562749 -155.229547) (xy 461.768422 -155.23758)
			(xy 461.973625 -155.253635) (xy 462.178044 -155.277689) (xy 462.381369 -155.309704) (xy 462.583289 -155.349632)
			(xy 462.783496 -155.397411) (xy 462.981685 -155.45297) (xy 463.177555 -155.516224) (xy 463.370806 -155.587075)
			(xy 463.561144 -155.665417) (xy 463.748279 -155.751129) (xy 463.931925 -155.84408) (xy 464.111802 -155.94413)
			(xy 464.287637 -156.051126) (xy 464.459161 -156.164904) (xy 464.626112 -156.285291) (xy 464.788237 -156.412104)
			(xy 464.945288 -156.545149) (xy 465.097025 -156.684223) (xy 465.243218 -156.829115) (xy 465.383643 -156.979603)
			(xy 465.518086 -157.135459) (xy 465.646343 -157.296443) (xy 465.768217 -157.462312) (xy 465.883524 -157.632812)
			(xy 465.992086 -157.807684) (xy 466.09374 -157.98666) (xy 466.188329 -158.169468) (xy 466.27571 -158.355829)
			(xy 466.35575 -158.545459) (xy 466.428326 -158.738069) (xy 466.493327 -158.933366) (xy 466.550655 -159.131051)
			(xy 466.575902 -159.230822) (xy 466.579953 -159.245003) (xy 466.594961 -159.270375) (xy 466.616587 -159.290408)
			(xy 466.643032 -159.303435) (xy 466.672094 -159.308372) (xy 466.701357 -159.304808) (xy 466.728385 -159.29304)
			(xy 466.75093 -159.274047) (xy 466.767116 -159.249409) (xy 466.775597 -159.221176) (xy 466.776054 -159.206438)
			(xy 466.776054 -116.991384) (xy 466.740748 -116.979954) (xy 466.713936 -116.970846) (xy 466.663138 -116.945827)
			(xy 466.616598 -116.913571) (xy 466.57534 -116.874789) (xy 466.54027 -116.830331) (xy 466.51216 -116.781177)
			(xy 466.491627 -116.728406) (xy 466.479123 -116.673179) (xy 466.474924 -116.61671) (xy 466.47912 -116.560241)
			(xy 466.491621 -116.505014) (xy 466.512151 -116.452242) (xy 466.540259 -116.403086) (xy 466.575326 -116.358627)
			(xy 466.616582 -116.319842) (xy 466.66312 -116.287584) (xy 466.713917 -116.262562) (xy 466.740748 -116.253514)
			(xy 466.776054 -116.242084) (xy 466.776054 -115.636294) (xy 466.751251 -115.623187) (xy 466.705446 -115.590802)
			(xy 466.664877 -115.552057) (xy 466.63042 -115.50779) (xy 466.602816 -115.458953) (xy 466.582663 -115.406601)
			(xy 466.570393 -115.351861) (xy 466.566272 -115.295915) (xy 466.570389 -115.239969) (xy 466.582654 -115.185229)
			(xy 466.602803 -115.132875) (xy 466.630402 -115.084036) (xy 466.664856 -115.039765) (xy 466.705422 -115.001018)
			(xy 466.751225 -114.968629) (xy 466.776054 -114.955574) (xy 466.776054 -82.827876) (xy 466.776575 -82.741392)
			(xy 466.785059 -82.568632) (xy 466.80201 -82.396497) (xy 466.827388 -82.2254) (xy 466.861131 -82.055755)
			(xy 466.903158 -81.887971) (xy 466.953368 -81.722451) (xy 467.011639 -81.559594) (xy 467.077832 -81.399792)
			(xy 467.151787 -81.243432) (xy 467.233326 -81.090888) (xy 467.322251 -80.94253) (xy 467.41835 -80.798714)
			(xy 467.52139 -80.659787) (xy 467.631124 -80.526084) (xy 467.747286 -80.397927) (xy 467.808056 -80.33639)
			(xy 470.136474 -78.007972) (xy 470.158166 -77.985616) (xy 470.196116 -77.936216) (xy 470.22729 -77.882284)
			(xy 470.251157 -77.824744) (xy 470.267306 -77.76458) (xy 470.275462 -77.702823) (xy 470.27592 -77.671676)
			(xy 470.27592 -13.780008) (xy 470.275411 -13.748842) (xy 470.267276 -13.687043) (xy 470.251145 -13.626835)
			(xy 470.227293 -13.569247) (xy 470.196128 -13.515265) (xy 470.158185 -13.465813) (xy 470.114111 -13.421736)
			(xy 470.064661 -13.383789) (xy 470.010681 -13.352621) (xy 469.953095 -13.328766) (xy 469.892888 -13.31263)
			(xy 469.83109 -13.304491) (xy 469.799924 -13.304012) (xy 458.20203 -13.304012) (xy 458.118154 -13.303522)
			(xy 457.950593 -13.295541) (xy 457.783601 -13.279597) (xy 457.617557 -13.255724) (xy 457.452837 -13.223979)
			(xy 457.289814 -13.184431) (xy 457.128858 -13.137171) (xy 456.970332 -13.082306) (xy 456.814597 -13.019961)
			(xy 456.662004 -12.950276) (xy 456.5129 -12.873409) (xy 456.367623 -12.789534) (xy 456.226501 -12.698842)
			(xy 456.089854 -12.601537) (xy 455.957992 -12.497841) (xy 455.831213 -12.387988) (xy 455.709805 -12.272228)
			(xy 455.594043 -12.150821) (xy 455.484188 -12.024044) (xy 455.38049 -11.892183) (xy 455.283184 -11.755537)
			(xy 455.19249 -11.614417) (xy 455.108614 -11.46914) (xy 455.031745 -11.320037) (xy 454.962057 -11.167446)
			(xy 454.89971 -11.011711) (xy 454.844843 -10.853186) (xy 454.797581 -10.69223) (xy 454.758031 -10.529208)
			(xy 454.726283 -10.364488) (xy 454.702409 -10.198445) (xy 454.686462 -10.031453) (xy 454.67848 -9.863892)
			(xy 454.678034 -9.780016) (xy 454.678034 -7.056374) (xy 454.677578 -7.042621) (xy 454.670229 -7.016114)
			(xy 454.656071 -6.99253) (xy 454.636133 -6.973582) (xy 454.611859 -6.960642) (xy 454.585013 -6.954652)
			(xy 454.557541 -6.956045) (xy 454.531438 -6.964719) (xy 454.519792 -6.972046) (xy 454.482612 -6.996373)
			(xy 454.404581 -7.03888) (xy 454.322975 -7.074041) (xy 454.238485 -7.101556) (xy 454.151825 -7.121195)
			(xy 454.063727 -7.132791) (xy 453.974936 -7.136245) (xy 453.886204 -7.13153) (xy 453.79828 -7.118684)
			(xy 453.711907 -7.097816) (xy 453.627816 -7.069103) (xy 453.546718 -7.032787) (xy 453.469299 -6.989176)
			(xy 453.396213 -6.938638) (xy 453.328077 -6.8816) (xy 453.265469 -6.818545) (xy 453.208918 -6.750006)
			(xy 453.1589 -6.676563) (xy 453.115841 -6.598835) (xy 453.080103 -6.517481) (xy 453.051988 -6.433188)
			(xy 453.031735 -6.346669) (xy 453.019515 -6.258656) (xy 453.01543 -6.169892) (xy 453.019516 -6.081128)
			(xy 453.031738 -5.993115) (xy 453.051992 -5.906597) (xy 453.080108 -5.822304) (xy 453.115848 -5.740951)
			(xy 453.158909 -5.663224) (xy 453.208927 -5.589781) (xy 453.26548 -5.521243) (xy 453.328089 -5.458189)
			(xy 453.396225 -5.401153) (xy 453.469312 -5.350616) (xy 453.546732 -5.307006) (xy 453.627831 -5.270691)
			(xy 453.711922 -5.24198) (xy 453.798295 -5.221113) (xy 453.886219 -5.208269) (xy 453.974952 -5.203554)
			(xy 454.063742 -5.207011) (xy 454.15184 -5.218608) (xy 454.2385 -5.238248) (xy 454.32299 -5.265765)
			(xy 454.404595 -5.300926) (xy 454.482625 -5.343435) (xy 454.519792 -5.367782) (xy 454.53146 -5.375065)
			(xy 454.557553 -5.383734) (xy 454.585013 -5.385124) (xy 454.611848 -5.379137) (xy 454.636112 -5.366204)
			(xy 454.656044 -5.347266) (xy 454.6702 -5.323695) (xy 454.677551 -5.297201) (xy 454.678034 -5.283454)
			(xy 454.678034 -1.524) (xy 389.125968 -1.524) (xy 389.125968 -4.280154) (xy 389.126411 -4.293871)
			(xy 389.133709 -4.320316) (xy 389.147791 -4.343859) (xy 389.167638 -4.362798) (xy 389.191814 -4.375764)
			(xy 389.218571 -4.381818) (xy 389.245974 -4.380523) (xy 389.272041 -4.371972) (xy 389.283702 -4.364736)
			(xy 389.320918 -4.340694) (xy 389.398968 -4.298748) (xy 389.480532 -4.264128) (xy 389.564925 -4.237125)
			(xy 389.651436 -4.217966) (xy 389.739338 -4.206812) (xy 389.827893 -4.203757) (xy 389.916355 -4.208826)
			(xy 390.003981 -4.221977) (xy 390.090034 -4.243099) (xy 390.17379 -4.272015) (xy 390.254546 -4.308482)
			(xy 390.331621 -4.352193) (xy 390.404369 -4.40278) (xy 390.472177 -4.459818) (xy 390.534475 -4.522827)
			(xy 390.59074 -4.591278) (xy 390.640498 -4.664595) (xy 390.683331 -4.742162) (xy 390.718878 -4.823326)
			(xy 390.746842 -4.907405) (xy 390.763549 -4.978969) (xy 394.947631 -4.978969) (xy 394.947631 -4.924431)
			(xy 394.955393 -4.870448) (xy 394.970758 -4.81812) (xy 394.993414 -4.76851) (xy 395.0229 -4.72263)
			(xy 395.058614 -4.681413) (xy 395.099832 -4.645698) (xy 395.145712 -4.616213) (xy 395.195321 -4.593557)
			(xy 395.24765 -4.578193) (xy 395.301633 -4.570431) (xy 395.328902 -4.569968) (xy 396.192502 -4.569968)
			(xy 396.219773 -4.570395) (xy 396.273761 -4.578157) (xy 396.326094 -4.593524) (xy 396.375708 -4.616182)
			(xy 396.421593 -4.64567) (xy 396.462813 -4.681388) (xy 396.498531 -4.722609) (xy 396.528019 -4.768493)
			(xy 396.550677 -4.818107) (xy 396.566043 -4.870441) (xy 396.573806 -4.924429) (xy 396.573806 -4.978971)
			(xy 398.547532 -4.978971) (xy 398.547532 -4.924429) (xy 398.555294 -4.870443) (xy 398.570661 -4.818111)
			(xy 398.593321 -4.768498) (xy 398.62281 -4.722616) (xy 398.658529 -4.681398) (xy 398.699751 -4.645684)
			(xy 398.745637 -4.616199) (xy 398.795252 -4.593546) (xy 398.847586 -4.578185) (xy 398.901573 -4.570428)
			(xy 398.928844 -4.569968) (xy 399.792444 -4.569968) (xy 399.819713 -4.570398) (xy 399.873697 -4.578165)
			(xy 399.926025 -4.593535) (xy 399.975633 -4.616196) (xy 400.021512 -4.645685) (xy 400.062728 -4.681403)
			(xy 400.098441 -4.722623) (xy 400.127925 -4.768505) (xy 400.15058 -4.818116) (xy 400.165944 -4.870447)
			(xy 400.173706 -4.92443) (xy 400.173706 -4.978967) (xy 402.147554 -4.978967) (xy 402.147554 -4.924433)
			(xy 402.155315 -4.870455) (xy 402.170678 -4.818131) (xy 402.193332 -4.768526) (xy 402.222814 -4.722649)
			(xy 402.258525 -4.681435) (xy 402.299738 -4.645722) (xy 402.345613 -4.616239) (xy 402.395218 -4.593583)
			(xy 402.447542 -4.578218) (xy 402.501519 -4.570455) (xy 402.528786 -4.569968) (xy 403.392386 -4.569968)
			(xy 403.41966 -4.570371) (xy 403.473652 -4.578132) (xy 403.525991 -4.593498) (xy 403.57561 -4.616157)
			(xy 403.621499 -4.645646) (xy 403.662724 -4.681366) (xy 403.698445 -4.72259) (xy 403.727937 -4.768478)
			(xy 403.750597 -4.818096) (xy 403.765965 -4.870434) (xy 403.773728 -4.924426) (xy 403.773728 -4.978966)
			(xy 405.747754 -4.978966) (xy 405.747754 -4.924434) (xy 405.755515 -4.870456) (xy 405.770878 -4.818132)
			(xy 405.793531 -4.768527) (xy 405.823013 -4.72265) (xy 405.858724 -4.681436) (xy 405.899936 -4.645724)
			(xy 405.945811 -4.61624) (xy 405.995415 -4.593584) (xy 406.047738 -4.578219) (xy 406.101716 -4.570456)
			(xy 406.128982 -4.569968) (xy 406.992582 -4.569968) (xy 407.019856 -4.57037) (xy 407.073849 -4.578131)
			(xy 407.126188 -4.593497) (xy 407.175807 -4.616155) (xy 407.221697 -4.645645) (xy 407.262922 -4.681365)
			(xy 407.298644 -4.722589) (xy 407.328136 -4.768477) (xy 407.350797 -4.818095) (xy 407.366165 -4.870433)
			(xy 407.373928 -4.924426) (xy 407.373928 -4.978971) (xy 414.857632 -4.978971) (xy 414.857632 -4.924429)
			(xy 414.865394 -4.870442) (xy 414.880762 -4.81811) (xy 414.903421 -4.768498) (xy 414.93291 -4.722616)
			(xy 414.96863 -4.681397) (xy 415.009852 -4.645683) (xy 415.055738 -4.616199) (xy 415.105353 -4.593546)
			(xy 415.157687 -4.578184) (xy 415.211675 -4.570428) (xy 415.238946 -4.569968) (xy 416.102546 -4.569968)
			(xy 416.129815 -4.570398) (xy 416.183798 -4.578165) (xy 416.236126 -4.593536) (xy 416.285735 -4.616196)
			(xy 416.331613 -4.645686) (xy 416.372829 -4.681404) (xy 416.408542 -4.722624) (xy 416.438026 -4.768506)
			(xy 416.46068 -4.818117) (xy 416.476045 -4.870447) (xy 416.483806 -4.924431) (xy 416.483806 -4.978967)
			(xy 418.457654 -4.978967) (xy 418.457654 -4.924433) (xy 418.465415 -4.870455) (xy 418.480779 -4.818131)
			(xy 418.503432 -4.768525) (xy 418.532915 -4.722648) (xy 418.568626 -4.681434) (xy 418.609839 -4.645722)
			(xy 418.655715 -4.616238) (xy 418.705319 -4.593583) (xy 418.757643 -4.578218) (xy 418.811621 -4.570455)
			(xy 418.838888 -4.569968) (xy 419.702488 -4.569968) (xy 419.729762 -4.570371) (xy 419.783754 -4.578132)
			(xy 419.836092 -4.593499) (xy 419.885711 -4.616157) (xy 419.9316 -4.645647) (xy 419.972824 -4.681367)
			(xy 420.008546 -4.722591) (xy 420.038037 -4.768479) (xy 420.060697 -4.818096) (xy 420.076065 -4.870434)
			(xy 420.083828 -4.924426) (xy 420.083828 -4.978966) (xy 426.067754 -4.978966) (xy 426.067754 -4.924434)
			(xy 426.075515 -4.870456) (xy 426.090878 -4.818132) (xy 426.113531 -4.768527) (xy 426.143013 -4.72265)
			(xy 426.178724 -4.681436) (xy 426.219936 -4.645724) (xy 426.265811 -4.61624) (xy 426.315415 -4.593584)
			(xy 426.367738 -4.578219) (xy 426.421716 -4.570456) (xy 426.448982 -4.569968) (xy 427.312582 -4.569968)
			(xy 427.339856 -4.57037) (xy 427.393849 -4.578131) (xy 427.446188 -4.593497) (xy 427.495807 -4.616155)
			(xy 427.541697 -4.645645) (xy 427.582922 -4.681365) (xy 427.618644 -4.722589) (xy 427.648136 -4.768477)
			(xy 427.670797 -4.818095) (xy 427.686165 -4.870433) (xy 427.693928 -4.924426) (xy 427.693928 -4.97897)
			(xy 429.667631 -4.97897) (xy 429.667631 -4.92443) (xy 429.675394 -4.870445) (xy 429.69076 -4.818115)
			(xy 429.713417 -4.768504) (xy 429.742905 -4.722623) (xy 429.778622 -4.681405) (xy 429.819842 -4.645691)
			(xy 429.865725 -4.616206) (xy 429.915337 -4.593552) (xy 429.967669 -4.578189) (xy 430.021654 -4.57043)
			(xy 430.048924 -4.569968) (xy 430.912524 -4.569968) (xy 430.939794 -4.570396) (xy 430.99378 -4.578161)
			(xy 431.04611 -4.59353) (xy 431.095721 -4.616189) (xy 431.141603 -4.645678) (xy 431.182821 -4.681396)
			(xy 431.218536 -4.722616) (xy 431.248022 -4.7685) (xy 431.270679 -4.818112) (xy 431.286044 -4.870444)
			(xy 431.293806 -4.92443) (xy 431.293806 -4.97897) (xy 431.286044 -5.032956) (xy 431.270679 -5.085288)
			(xy 431.248022 -5.1349) (xy 431.218536 -5.180784) (xy 431.182821 -5.222004) (xy 431.141603 -5.257722)
			(xy 431.095721 -5.287211) (xy 431.04611 -5.30987) (xy 430.99378 -5.325239) (xy 430.939794 -5.333004)
			(xy 430.912524 -5.333492) (xy 430.048924 -5.333492) (xy 430.021654 -5.33297) (xy 429.967669 -5.325211)
			(xy 429.915337 -5.309848) (xy 429.865725 -5.287194) (xy 429.819842 -5.257709) (xy 429.778622 -5.221995)
			(xy 429.742905 -5.180777) (xy 429.713417 -5.134896) (xy 429.69076 -5.085285) (xy 429.675394 -5.032955)
			(xy 429.667631 -4.97897) (xy 427.693928 -4.97897) (xy 427.693928 -4.978974) (xy 427.686165 -5.032967)
			(xy 427.670797 -5.085305) (xy 427.648136 -5.134923) (xy 427.618644 -5.180811) (xy 427.582922 -5.222035)
			(xy 427.541697 -5.257755) (xy 427.495807 -5.287245) (xy 427.446188 -5.309903) (xy 427.393849 -5.325269)
			(xy 427.339856 -5.33303) (xy 427.312582 -5.333492) (xy 426.448982 -5.333492) (xy 426.421716 -5.332944)
			(xy 426.367738 -5.325181) (xy 426.315415 -5.309816) (xy 426.265811 -5.28716) (xy 426.219936 -5.257676)
			(xy 426.178724 -5.221964) (xy 426.143013 -5.18075) (xy 426.113531 -5.134873) (xy 426.090878 -5.085268)
			(xy 426.075515 -5.032944) (xy 426.067754 -4.978966) (xy 420.083828 -4.978966) (xy 420.083828 -4.978974)
			(xy 420.076065 -5.032966) (xy 420.060697 -5.085304) (xy 420.038037 -5.134921) (xy 420.008546 -5.180809)
			(xy 419.972824 -5.222033) (xy 419.9316 -5.257753) (xy 419.885711 -5.287243) (xy 419.836092 -5.309901)
			(xy 419.783754 -5.325268) (xy 419.729762 -5.333029) (xy 419.702488 -5.333492) (xy 418.838888 -5.333492)
			(xy 418.811621 -5.332945) (xy 418.757643 -5.325182) (xy 418.705319 -5.309817) (xy 418.655715 -5.287162)
			(xy 418.609839 -5.257678) (xy 418.568626 -5.221966) (xy 418.532915 -5.180752) (xy 418.503432 -5.134875)
			(xy 418.480779 -5.085269) (xy 418.465415 -5.032945) (xy 418.457654 -4.978967) (xy 416.483806 -4.978967)
			(xy 416.483806 -4.978969) (xy 416.476045 -5.032953) (xy 416.46068 -5.085283) (xy 416.438026 -5.134894)
			(xy 416.408542 -5.180776) (xy 416.372829 -5.221996) (xy 416.331613 -5.257714) (xy 416.285735 -5.287204)
			(xy 416.236126 -5.309864) (xy 416.183798 -5.325235) (xy 416.129815 -5.333002) (xy 416.102546 -5.333492)
			(xy 415.238946 -5.333492) (xy 415.211675 -5.332972) (xy 415.157687 -5.325216) (xy 415.105353 -5.309854)
			(xy 415.055738 -5.287201) (xy 415.009852 -5.257717) (xy 414.96863 -5.222003) (xy 414.93291 -5.180784)
			(xy 414.903421 -5.134902) (xy 414.880762 -5.08529) (xy 414.865394 -5.032958) (xy 414.857632 -4.978971)
			(xy 407.373928 -4.978971) (xy 407.373928 -4.978974) (xy 407.366165 -5.032967) (xy 407.350797 -5.085305)
			(xy 407.328136 -5.134923) (xy 407.298644 -5.180811) (xy 407.262922 -5.222035) (xy 407.221697 -5.257755)
			(xy 407.175807 -5.287245) (xy 407.126188 -5.309903) (xy 407.073849 -5.325269) (xy 407.019856 -5.33303)
			(xy 406.992582 -5.333492) (xy 406.128982 -5.333492) (xy 406.101716 -5.332944) (xy 406.047738 -5.325181)
			(xy 405.995415 -5.309816) (xy 405.945811 -5.28716) (xy 405.899936 -5.257676) (xy 405.858724 -5.221964)
			(xy 405.823013 -5.18075) (xy 405.793531 -5.134873) (xy 405.770878 -5.085268) (xy 405.755515 -5.032944)
			(xy 405.747754 -4.978966) (xy 403.773728 -4.978966) (xy 403.773728 -4.978974) (xy 403.765965 -5.032966)
			(xy 403.750597 -5.085304) (xy 403.727937 -5.134922) (xy 403.698445 -5.18081) (xy 403.662724 -5.222034)
			(xy 403.621499 -5.257754) (xy 403.57561 -5.287243) (xy 403.525991 -5.309902) (xy 403.473652 -5.325268)
			(xy 403.41966 -5.333029) (xy 403.392386 -5.333492) (xy 402.528786 -5.333492) (xy 402.501519 -5.332945)
			(xy 402.447542 -5.325182) (xy 402.395218 -5.309817) (xy 402.345613 -5.287161) (xy 402.299738 -5.257678)
			(xy 402.258525 -5.221965) (xy 402.222814 -5.180751) (xy 402.193332 -5.134874) (xy 402.170678 -5.085269)
			(xy 402.155315 -5.032945) (xy 402.147554 -4.978967) (xy 400.173706 -4.978967) (xy 400.173706 -4.97897)
			(xy 400.165944 -5.032953) (xy 400.15058 -5.085284) (xy 400.127925 -5.134895) (xy 400.098441 -5.180777)
			(xy 400.062728 -5.221997) (xy 400.021512 -5.257715) (xy 399.975633 -5.287204) (xy 399.926025 -5.309865)
			(xy 399.873697 -5.325235) (xy 399.819713 -5.333002) (xy 399.792444 -5.333492) (xy 398.928844 -5.333492)
			(xy 398.901573 -5.332972) (xy 398.847586 -5.325215) (xy 398.795252 -5.309854) (xy 398.745637 -5.287201)
			(xy 398.699751 -5.257716) (xy 398.658529 -5.222002) (xy 398.62281 -5.180784) (xy 398.593321 -5.134902)
			(xy 398.570661 -5.085289) (xy 398.555294 -5.032957) (xy 398.547532 -4.978971) (xy 396.573806 -4.978971)
			(xy 396.566043 -5.032959) (xy 396.550677 -5.085293) (xy 396.528019 -5.134907) (xy 396.498531 -5.180791)
			(xy 396.462813 -5.222012) (xy 396.421593 -5.25773) (xy 396.375708 -5.287218) (xy 396.326094 -5.309876)
			(xy 396.273761 -5.325243) (xy 396.219773 -5.333005) (xy 396.192502 -5.333492) (xy 395.328902 -5.333492)
			(xy 395.301633 -5.332969) (xy 395.24765 -5.325207) (xy 395.195321 -5.309843) (xy 395.145712 -5.287187)
			(xy 395.099832 -5.257702) (xy 395.058614 -5.221987) (xy 395.0229 -5.18077) (xy 394.993414 -5.13489)
			(xy 394.970758 -5.08528) (xy 394.955393 -5.032952) (xy 394.947631 -4.978969) (xy 390.763549 -4.978969)
			(xy 390.766986 -4.993693) (xy 390.779141 -5.081462) (xy 390.783206 -5.169976) (xy 390.779146 -5.25849)
			(xy 390.766994 -5.346261) (xy 390.746854 -5.432549) (xy 390.718895 -5.516629) (xy 390.683352 -5.597795)
			(xy 390.640523 -5.675364) (xy 390.590768 -5.748684) (xy 390.534507 -5.817138) (xy 390.472212 -5.88015)
			(xy 390.404407 -5.937192) (xy 390.331662 -5.987782) (xy 390.254588 -6.031496) (xy 390.173835 -6.067967)
			(xy 390.09008 -6.096887) (xy 390.004028 -6.118014) (xy 389.916403 -6.131169) (xy 389.827941 -6.136243)
			(xy 389.739386 -6.133192) (xy 389.651483 -6.122042) (xy 389.564971 -6.102887) (xy 389.480577 -6.075888)
			(xy 389.399011 -6.041273) (xy 389.320959 -5.999331) (xy 389.283702 -5.97535) (xy 389.272033 -5.968152)
			(xy 389.245982 -5.959639) (xy 389.218604 -5.958367) (xy 389.191876 -5.964428) (xy 389.167726 -5.977384)
			(xy 389.147895 -5.996302) (xy 389.133816 -6.019816) (xy 389.126503 -6.046229) (xy 389.125968 -6.059932)
			(xy 389.125968 -6.740774) (xy 393.142876 -6.740774) (xy 393.142876 -6.686226) (xy 393.150639 -6.632232)
			(xy 393.166008 -6.579894) (xy 393.18867 -6.530275) (xy 393.218162 -6.484387) (xy 393.253885 -6.443163)
			(xy 393.295112 -6.407443) (xy 393.341003 -6.377954) (xy 393.390624 -6.355297) (xy 393.442964 -6.339932)
			(xy 393.496958 -6.332173) (xy 393.524232 -6.331712) (xy 394.387832 -6.331712) (xy 394.415098 -6.332253)
			(xy 394.469074 -6.340017) (xy 394.521397 -6.355384) (xy 394.570999 -6.378041) (xy 394.616873 -6.407526)
			(xy 394.658084 -6.443238) (xy 394.693794 -6.484452) (xy 394.723274 -6.530329) (xy 394.745927 -6.579933)
			(xy 394.761289 -6.632257) (xy 394.76905 -6.686234) (xy 394.76905 -6.740766) (xy 394.769049 -6.74077)
			(xy 396.742898 -6.74077) (xy 396.742898 -6.68623) (xy 396.75066 -6.632245) (xy 396.766025 -6.579914)
			(xy 396.788681 -6.530302) (xy 396.818166 -6.484419) (xy 396.853881 -6.4432) (xy 396.895099 -6.407482)
			(xy 396.940979 -6.377993) (xy 396.99059 -6.355334) (xy 397.04292 -6.339965) (xy 397.096904 -6.3322)
			(xy 397.124174 -6.331712) (xy 397.987774 -6.331712) (xy 398.015044 -6.332226) (xy 398.06903 -6.339984)
			(xy 398.121363 -6.355347) (xy 398.170976 -6.378002) (xy 398.216859 -6.407487) (xy 398.25808 -6.443202)
			(xy 398.293798 -6.48442) (xy 398.323286 -6.530301) (xy 398.345944 -6.579913) (xy 398.36131 -6.632244)
			(xy 398.369072 -6.68623) (xy 398.369072 -6.74077) (xy 398.369071 -6.740774) (xy 400.342776 -6.740774)
			(xy 400.342776 -6.686226) (xy 400.350539 -6.632234) (xy 400.365907 -6.579897) (xy 400.388567 -6.530279)
			(xy 400.418058 -6.484392) (xy 400.45378 -6.443168) (xy 400.495005 -6.407449) (xy 400.540893 -6.377959)
			(xy 400.590512 -6.355301) (xy 400.64285 -6.339935) (xy 400.696842 -6.332174) (xy 400.724116 -6.331712)
			(xy 401.587716 -6.331712) (xy 401.614983 -6.332251) (xy 401.668961 -6.340014) (xy 401.721285 -6.35538)
			(xy 401.77089 -6.378036) (xy 401.816766 -6.40752) (xy 401.857978 -6.443233) (xy 401.89369 -6.484447)
			(xy 401.923172 -6.530324) (xy 401.945825 -6.57993) (xy 401.961189 -6.632255) (xy 401.96895 -6.686233)
			(xy 401.96895 -6.740767) (xy 401.968949 -6.740773) (xy 403.942976 -6.740773) (xy 403.942976 -6.686227)
			(xy 403.950739 -6.632235) (xy 403.966106 -6.579898) (xy 403.988766 -6.53028) (xy 404.018257 -6.484393)
			(xy 404.053978 -6.44317) (xy 404.095203 -6.40745) (xy 404.141091 -6.377961) (xy 404.190709 -6.355302)
			(xy 404.243047 -6.339936) (xy 404.297039 -6.332175) (xy 404.324312 -6.331712) (xy 405.187912 -6.331712)
			(xy 405.215179 -6.332251) (xy 405.269158 -6.340014) (xy 405.321482 -6.355379) (xy 405.371087 -6.378034)
			(xy 405.416964 -6.407519) (xy 405.458177 -6.443231) (xy 405.493889 -6.484446) (xy 405.523371 -6.530323)
			(xy 405.546025 -6.579929) (xy 405.561389 -6.632254) (xy 405.56915 -6.686233) (xy 405.56915 -6.740767)
			(xy 405.56915 -6.74077) (xy 413.052998 -6.74077) (xy 413.052998 -6.68623) (xy 413.06076 -6.632245)
			(xy 413.076125 -6.579914) (xy 413.098781 -6.530302) (xy 413.128267 -6.484419) (xy 413.163982 -6.443199)
			(xy 413.205199 -6.407481) (xy 413.25108 -6.377993) (xy 413.300691 -6.355334) (xy 413.353021 -6.339965)
			(xy 413.407006 -6.3322) (xy 413.434276 -6.331712) (xy 414.297876 -6.331712) (xy 414.325146 -6.332226)
			(xy 414.379132 -6.339985) (xy 414.431464 -6.355348) (xy 414.481077 -6.378002) (xy 414.52696 -6.407487)
			(xy 414.568181 -6.443202) (xy 414.603898 -6.48442) (xy 414.633386 -6.530302) (xy 414.656044 -6.579913)
			(xy 414.67141 -6.632244) (xy 414.679173 -6.68623) (xy 414.679173 -6.74077) (xy 414.679172 -6.740774)
			(xy 416.652876 -6.740774) (xy 416.652876 -6.686226) (xy 416.660639 -6.632234) (xy 416.676007 -6.579897)
			(xy 416.698667 -6.530279) (xy 416.728159 -6.484391) (xy 416.763881 -6.443168) (xy 416.805106 -6.407448)
			(xy 416.850995 -6.377959) (xy 416.900613 -6.355301) (xy 416.952952 -6.339935) (xy 417.006944 -6.332174)
			(xy 417.034218 -6.331712) (xy 417.897818 -6.331712) (xy 417.925085 -6.332252) (xy 417.979063 -6.340015)
			(xy 418.031386 -6.355381) (xy 418.080991 -6.378036) (xy 418.126867 -6.407521) (xy 418.168079 -6.443234)
			(xy 418.20379 -6.484448) (xy 418.233272 -6.530325) (xy 418.255926 -6.57993) (xy 418.271289 -6.632255)
			(xy 418.27905 -6.686233) (xy 418.27905 -6.740767) (xy 418.279049 -6.740773) (xy 424.262976 -6.740773)
			(xy 424.262976 -6.686227) (xy 424.270739 -6.632235) (xy 424.286106 -6.579898) (xy 424.308766 -6.53028)
			(xy 424.338257 -6.484393) (xy 424.373978 -6.44317) (xy 424.415203 -6.40745) (xy 424.461091 -6.377961)
			(xy 424.510709 -6.355302) (xy 424.563047 -6.339936) (xy 424.617039 -6.332175) (xy 424.644312 -6.331712)
			(xy 425.507912 -6.331712) (xy 425.535179 -6.332251) (xy 425.589158 -6.340014) (xy 425.641482 -6.355379)
			(xy 425.691087 -6.378034) (xy 425.736964 -6.407519) (xy 425.778177 -6.443231) (xy 425.813889 -6.484446)
			(xy 425.843371 -6.530323) (xy 425.866025 -6.579929) (xy 425.881389 -6.632254) (xy 425.88915 -6.686233)
			(xy 425.88915 -6.740767) (xy 425.88915 -6.740769) (xy 427.862998 -6.740769) (xy 427.862998 -6.686231)
			(xy 427.870759 -6.632248) (xy 427.886123 -6.579918) (xy 427.908778 -6.530308) (xy 427.938261 -6.484426)
			(xy 427.973974 -6.443207) (xy 428.015189 -6.407489) (xy 428.061067 -6.378) (xy 428.110675 -6.35534)
			(xy 428.163003 -6.339969) (xy 428.216985 -6.332202) (xy 428.244254 -6.331712) (xy 429.107854 -6.331712)
			(xy 429.135125 -6.332224) (xy 429.189113 -6.339981) (xy 429.241448 -6.355342) (xy 429.291064 -6.377995)
			(xy 429.33695 -6.40748) (xy 429.378173 -6.443195) (xy 429.413893 -6.484413) (xy 429.443383 -6.530296)
			(xy 429.466042 -6.579909) (xy 429.48141 -6.632242) (xy 429.489172 -6.686229) (xy 429.489172 -6.740771)
			(xy 429.488151 -6.747873) (xy 431.473788 -6.747873) (xy 431.473788 -6.693327) (xy 431.48155 -6.639337)
			(xy 431.496918 -6.587001) (xy 431.519578 -6.537385) (xy 431.549068 -6.491498) (xy 431.584789 -6.450276)
			(xy 431.626013 -6.414558) (xy 431.6719 -6.385069) (xy 431.721518 -6.362412) (xy 431.773854 -6.347047)
			(xy 431.827845 -6.339286) (xy 431.855118 -6.338824) (xy 432.718718 -6.338824) (xy 432.745986 -6.33934)
			(xy 432.799965 -6.347103) (xy 432.852291 -6.362469) (xy 432.901897 -6.385126) (xy 432.947774 -6.414611)
			(xy 432.988988 -6.450325) (xy 433.0247 -6.491541) (xy 433.054183 -6.537419) (xy 433.076837 -6.587026)
			(xy 433.092201 -6.639352) (xy 433.099962 -6.693332) (xy 433.099962 -6.740771) (xy 445.457798 -6.740771)
			(xy 445.457798 -6.686229) (xy 445.46556 -6.632243) (xy 445.480926 -6.579911) (xy 445.503583 -6.530298)
			(xy 445.53307 -6.484415) (xy 445.568786 -6.443195) (xy 445.610005 -6.407477) (xy 445.655888 -6.377989)
			(xy 445.7055 -6.35533) (xy 445.757831 -6.339963) (xy 445.811817 -6.332199) (xy 445.839088 -6.331712)
			(xy 446.702688 -6.331712) (xy 446.729958 -6.332227) (xy 446.783942 -6.339987) (xy 446.836273 -6.355351)
			(xy 446.885884 -6.378006) (xy 446.931766 -6.407492) (xy 446.972985 -6.443207) (xy 447.008701 -6.484424)
			(xy 447.038188 -6.530305) (xy 447.060845 -6.579916) (xy 447.076211 -6.632246) (xy 447.083973 -6.68623)
			(xy 447.083973 -6.74077) (xy 447.076211 -6.794754) (xy 447.060845 -6.847084) (xy 447.038188 -6.896695)
			(xy 447.008701 -6.942576) (xy 446.972985 -6.983793) (xy 446.931766 -7.019508) (xy 446.885884 -7.048994)
			(xy 446.836273 -7.071649) (xy 446.783942 -7.087013) (xy 446.729958 -7.094773) (xy 446.702688 -7.095236)
			(xy 445.839088 -7.095236) (xy 445.811817 -7.094801) (xy 445.757831 -7.087037) (xy 445.7055 -7.07167)
			(xy 445.655888 -7.049011) (xy 445.610005 -7.019523) (xy 445.568786 -6.983805) (xy 445.53307 -6.942585)
			(xy 445.503583 -6.896702) (xy 445.480926 -6.847089) (xy 445.46556 -6.794757) (xy 445.457798 -6.740771)
			(xy 433.099962 -6.740771) (xy 433.099962 -6.747868) (xy 433.092201 -6.801848) (xy 433.076837 -6.854174)
			(xy 433.054183 -6.903781) (xy 433.0247 -6.949659) (xy 432.988988 -6.990875) (xy 432.947774 -7.026589)
			(xy 432.901897 -7.056074) (xy 432.852291 -7.078731) (xy 432.799965 -7.094097) (xy 432.745986 -7.10186)
			(xy 432.718718 -7.102348) (xy 431.855118 -7.102348) (xy 431.827845 -7.101914) (xy 431.773854 -7.094153)
			(xy 431.721518 -7.078788) (xy 431.6719 -7.056131) (xy 431.626013 -7.026642) (xy 431.584789 -6.990924)
			(xy 431.549068 -6.949702) (xy 431.519578 -6.903815) (xy 431.496918 -6.854199) (xy 431.48155 -6.801863)
			(xy 431.473788 -6.747873) (xy 429.488151 -6.747873) (xy 429.48141 -6.794758) (xy 429.466042 -6.847091)
			(xy 429.443383 -6.896704) (xy 429.413893 -6.942587) (xy 429.378173 -6.983805) (xy 429.33695 -7.01952)
			(xy 429.291064 -7.049005) (xy 429.241448 -7.071658) (xy 429.189113 -7.087019) (xy 429.135125 -7.094776)
			(xy 429.107854 -7.095236) (xy 428.244254 -7.095236) (xy 428.216985 -7.094798) (xy 428.163003 -7.087031)
			(xy 428.110675 -7.07166) (xy 428.061067 -7.049) (xy 428.015189 -7.019511) (xy 427.973974 -6.983793)
			(xy 427.938261 -6.942574) (xy 427.908778 -6.896692) (xy 427.886123 -6.847082) (xy 427.870759 -6.794752)
			(xy 427.862998 -6.740769) (xy 425.88915 -6.740769) (xy 425.881389 -6.794746) (xy 425.866025 -6.847071)
			(xy 425.843371 -6.896677) (xy 425.813889 -6.942554) (xy 425.778177 -6.983769) (xy 425.736964 -7.019481)
			(xy 425.691087 -7.048966) (xy 425.641482 -7.071621) (xy 425.589158 -7.086986) (xy 425.535179 -7.094749)
			(xy 425.507912 -7.095236) (xy 424.644312 -7.095236) (xy 424.617039 -7.094825) (xy 424.563047 -7.087064)
			(xy 424.510709 -7.071698) (xy 424.461091 -7.049039) (xy 424.415203 -7.01955) (xy 424.373978 -6.98383)
			(xy 424.338257 -6.942607) (xy 424.308766 -6.89672) (xy 424.286106 -6.847102) (xy 424.270739 -6.794765)
			(xy 424.262976 -6.740773) (xy 418.279049 -6.740773) (xy 418.271289 -6.794745) (xy 418.255926 -6.84707)
			(xy 418.233272 -6.896675) (xy 418.20379 -6.942552) (xy 418.168079 -6.983766) (xy 418.126867 -7.019479)
			(xy 418.080991 -7.048964) (xy 418.031386 -7.071619) (xy 417.979063 -7.086985) (xy 417.925085 -7.094748)
			(xy 417.897818 -7.095236) (xy 417.034218 -7.095236) (xy 417.006944 -7.094826) (xy 416.952952 -7.087065)
			(xy 416.900613 -7.071699) (xy 416.850995 -7.049041) (xy 416.805106 -7.019552) (xy 416.763881 -6.983832)
			(xy 416.728159 -6.942609) (xy 416.698667 -6.896721) (xy 416.676007 -6.847103) (xy 416.660639 -6.794766)
			(xy 416.652876 -6.740774) (xy 414.679172 -6.740774) (xy 414.67141 -6.794756) (xy 414.656044 -6.847087)
			(xy 414.633386 -6.896698) (xy 414.603898 -6.94258) (xy 414.568181 -6.983798) (xy 414.52696 -7.019513)
			(xy 414.481077 -7.048998) (xy 414.431464 -7.071652) (xy 414.379132 -7.087015) (xy 414.325146 -7.094774)
			(xy 414.297876 -7.095236) (xy 413.434276 -7.095236) (xy 413.407006 -7.0948) (xy 413.353021 -7.087035)
			(xy 413.300691 -7.071666) (xy 413.25108 -7.049007) (xy 413.205199 -7.019519) (xy 413.163982 -6.983801)
			(xy 413.128267 -6.942581) (xy 413.098781 -6.896698) (xy 413.076125 -6.847086) (xy 413.06076 -6.794755)
			(xy 413.052998 -6.74077) (xy 405.56915 -6.74077) (xy 405.561389 -6.794746) (xy 405.546025 -6.847071)
			(xy 405.523371 -6.896677) (xy 405.493889 -6.942554) (xy 405.458177 -6.983769) (xy 405.416964 -7.019481)
			(xy 405.371087 -7.048966) (xy 405.321482 -7.071621) (xy 405.269158 -7.086986) (xy 405.215179 -7.094749)
			(xy 405.187912 -7.095236) (xy 404.324312 -7.095236) (xy 404.297039 -7.094825) (xy 404.243047 -7.087064)
			(xy 404.190709 -7.071698) (xy 404.141091 -7.049039) (xy 404.095203 -7.01955) (xy 404.053978 -6.98383)
			(xy 404.018257 -6.942607) (xy 403.988766 -6.89672) (xy 403.966106 -6.847102) (xy 403.950739 -6.794765)
			(xy 403.942976 -6.740773) (xy 401.968949 -6.740773) (xy 401.961189 -6.794745) (xy 401.945825 -6.84707)
			(xy 401.923172 -6.896676) (xy 401.89369 -6.942553) (xy 401.857978 -6.983767) (xy 401.816766 -7.01948)
			(xy 401.77089 -7.048964) (xy 401.721285 -7.07162) (xy 401.668961 -7.086986) (xy 401.614983 -7.094749)
			(xy 401.587716 -7.095236) (xy 400.724116 -7.095236) (xy 400.696842 -7.094826) (xy 400.64285 -7.087065)
			(xy 400.590512 -7.071699) (xy 400.540893 -7.049041) (xy 400.495005 -7.019551) (xy 400.45378 -6.983832)
			(xy 400.418058 -6.942608) (xy 400.388567 -6.896721) (xy 400.365907 -6.847103) (xy 400.350539 -6.794766)
			(xy 400.342776 -6.740774) (xy 398.369071 -6.740774) (xy 398.36131 -6.794756) (xy 398.345944 -6.847087)
			(xy 398.323286 -6.896699) (xy 398.293798 -6.94258) (xy 398.25808 -6.983798) (xy 398.216859 -7.019513)
			(xy 398.170976 -7.048998) (xy 398.121363 -7.071653) (xy 398.06903 -7.087016) (xy 398.015044 -7.094774)
			(xy 397.987774 -7.095236) (xy 397.124174 -7.095236) (xy 397.096904 -7.0948) (xy 397.04292 -7.087035)
			(xy 396.99059 -7.071666) (xy 396.940979 -7.049007) (xy 396.895099 -7.019518) (xy 396.853881 -6.9838)
			(xy 396.818166 -6.942581) (xy 396.788681 -6.896698) (xy 396.766025 -6.847086) (xy 396.75066 -6.794755)
			(xy 396.742898 -6.74077) (xy 394.769049 -6.74077) (xy 394.761289 -6.794743) (xy 394.745927 -6.847067)
			(xy 394.723274 -6.896671) (xy 394.693794 -6.942548) (xy 394.658084 -6.983762) (xy 394.616873 -7.019474)
			(xy 394.570999 -7.048959) (xy 394.521397 -7.071616) (xy 394.469074 -7.086983) (xy 394.415098 -7.094747)
			(xy 394.387832 -7.095236) (xy 393.524232 -7.095236) (xy 393.496958 -7.094827) (xy 393.442964 -7.087068)
			(xy 393.390624 -7.071703) (xy 393.341003 -7.049046) (xy 393.295112 -7.019557) (xy 393.253885 -6.983837)
			(xy 393.218162 -6.942613) (xy 393.18867 -6.896725) (xy 393.166008 -6.847106) (xy 393.150639 -6.794768)
			(xy 393.142876 -6.740774) (xy 389.125968 -6.740774) (xy 389.125968 -9.780016) (xy 389.125476 -9.863891)
			(xy 389.117494 -10.03145) (xy 389.101547 -10.198439) (xy 389.077674 -10.364481) (xy 389.045926 -10.529198)
			(xy 389.006377 -10.692219) (xy 388.959116 -10.853173) (xy 388.904249 -11.011695) (xy 388.841902 -11.167428)
			(xy 388.772216 -11.320018) (xy 388.695348 -11.469118) (xy 388.611473 -11.614393) (xy 388.52078 -11.755512)
			(xy 388.423475 -11.892156) (xy 388.319779 -12.024015) (xy 388.209926 -12.150791) (xy 388.094165 -12.272196)
			(xy 387.972758 -12.387955) (xy 387.845981 -12.497807) (xy 387.714121 -12.601501) (xy 387.577476 -12.698805)
			(xy 387.436355 -12.789496) (xy 387.29108 -12.873369) (xy 387.254814 -12.892065) (xy 431.46197 -12.892065)
			(xy 431.46197 -12.837535) (xy 431.46973 -12.783559) (xy 431.485093 -12.731238) (xy 431.507745 -12.681635)
			(xy 431.537225 -12.635761) (xy 431.572934 -12.594548) (xy 431.614145 -12.558837) (xy 431.660017 -12.529355)
			(xy 431.709619 -12.5067) (xy 431.76194 -12.491335) (xy 431.815915 -12.483572) (xy 431.84318 -12.483084)
			(xy 432.70678 -12.483084) (xy 432.734055 -12.483454) (xy 432.788051 -12.491215) (xy 432.840392 -12.506581)
			(xy 432.890014 -12.529241) (xy 432.935905 -12.558731) (xy 432.977133 -12.594453) (xy 433.012857 -12.635678)
			(xy 433.04235 -12.681569) (xy 433.065012 -12.731189) (xy 433.080381 -12.78353) (xy 433.088144 -12.837525)
			(xy 433.088144 -12.864846) (xy 445.45631 -12.864846) (xy 445.45631 -12.864592) (xy 445.456564 -12.850622)
			(xy 445.45717 -12.823469) (xy 445.46523 -12.769758) (xy 445.48082 -12.717731) (xy 445.503625 -12.668439)
			(xy 445.533186 -12.622876) (xy 445.568905 -12.581962) (xy 445.610062 -12.546522) (xy 445.655826 -12.517273)
			(xy 445.705273 -12.494804) (xy 445.757405 -12.47957) (xy 445.81117 -12.471876) (xy 445.838326 -12.4714)
			(xy 446.701926 -12.4714) (xy 446.72908 -12.471883) (xy 446.782838 -12.479582) (xy 446.834964 -12.494821)
			(xy 446.884404 -12.517293) (xy 446.93016 -12.546543) (xy 446.971311 -12.581982) (xy 447.007024 -12.622895)
			(xy 447.03658 -12.668455) (xy 447.059381 -12.717744) (xy 447.074968 -12.769766) (xy 447.083027 -12.823472)
			(xy 447.083688 -12.850622) (xy 447.083942 -12.864592) (xy 447.083942 -12.864846) (xy 447.083472 -12.892133)
			(xy 447.0757 -12.946152) (xy 447.06032 -12.998515) (xy 447.037645 -13.048157) (xy 447.008137 -13.094067)
			(xy 446.972397 -13.135311) (xy 446.931151 -13.171049) (xy 446.885239 -13.200555) (xy 446.835597 -13.223227)
			(xy 446.783233 -13.238604) (xy 446.729214 -13.246374) (xy 446.701926 -13.246862) (xy 446.679426 -13.246581)
			(xy 446.634732 -13.241355) (xy 446.612772 -13.236448) (xy 446.60693 -13.234924) (xy 445.933322 -13.234924)
			(xy 445.92748 -13.236448) (xy 445.905519 -13.241348) (xy 445.860825 -13.246566) (xy 445.838326 -13.246862)
			(xy 445.811041 -13.246305) (xy 445.757027 -13.238543) (xy 445.704666 -13.223173) (xy 445.655026 -13.200508)
			(xy 445.609117 -13.17101) (xy 445.567873 -13.135278) (xy 445.532133 -13.094041) (xy 445.502626 -13.048137)
			(xy 445.479952 -12.998501) (xy 445.464572 -12.946144) (xy 445.4568 -12.892131) (xy 445.45631 -12.864846)
			(xy 433.088144 -12.864846) (xy 433.088144 -12.892075) (xy 433.080381 -12.94607) (xy 433.065012 -12.998411)
			(xy 433.04235 -13.048031) (xy 433.012857 -13.093921) (xy 432.977133 -13.135147) (xy 432.935905 -13.170869)
			(xy 432.890014 -13.200359) (xy 432.840392 -13.223019) (xy 432.788051 -13.238385) (xy 432.734055 -13.246146)
			(xy 432.70678 -13.246608) (xy 431.84318 -13.246608) (xy 431.815915 -13.246028) (xy 431.76194 -13.238265)
			(xy 431.709619 -13.2229) (xy 431.660017 -13.200245) (xy 431.614145 -13.170763) (xy 431.572934 -13.135052)
			(xy 431.537225 -13.093839) (xy 431.507745 -13.047965) (xy 431.485093 -12.998362) (xy 431.46973 -12.946041)
			(xy 431.46197 -12.892065) (xy 387.254814 -12.892065) (xy 387.141978 -12.950235) (xy 386.989387 -13.01992)
			(xy 386.833654 -13.082265) (xy 386.675131 -13.137129) (xy 386.514176 -13.184388) (xy 386.351155 -13.223935)
			(xy 386.186437 -13.255681) (xy 386.020395 -13.279553) (xy 385.853406 -13.295497) (xy 385.685847 -13.303478)
			(xy 385.601972 -13.304012) (xy 320.726308 -13.304012) (xy 320.715132 -13.339318) (xy 320.706577 -13.364685)
			(xy 320.683356 -13.41292) (xy 320.65362 -13.457435) (xy 320.617953 -13.497357) (xy 320.577056 -13.531901)
			(xy 320.531732 -13.560389) (xy 320.482871 -13.582261) (xy 320.431432 -13.597089) (xy 320.378425 -13.60458)
			(xy 320.351658 -13.605002) (xy 320.324289 -13.604527) (xy 320.270114 -13.596698) (xy 320.217613 -13.581207)
			(xy 320.167866 -13.558371) (xy 320.121894 -13.528659) (xy 320.10096 -13.511022) (xy 320.089632 -13.501786)
			(xy 320.063075 -13.48961) (xy 320.034158 -13.485437) (xy 320.005241 -13.48961) (xy 319.978684 -13.501786)
			(xy 319.967356 -13.511022) (xy 319.946423 -13.528661) (xy 319.900455 -13.55838) (xy 319.850708 -13.581216)
			(xy 319.798205 -13.596699) (xy 319.744027 -13.604511) (xy 319.716658 -13.605002) (xy 319.689891 -13.604554)
			(xy 319.636881 -13.597076) (xy 319.585438 -13.582258) (xy 319.536573 -13.560393) (xy 319.491245 -13.531909)
			(xy 319.450346 -13.497367) (xy 319.414679 -13.457444) (xy 319.384946 -13.412927) (xy 319.361729 -13.364688)
			(xy 319.353184 -13.339318) (xy 319.342008 -13.304012) (xy 260.800088 -13.304012) (xy 260.768924 -13.304522)
			(xy 260.707128 -13.31266) (xy 260.646924 -13.328793) (xy 260.58934 -13.352646) (xy 260.535363 -13.383812)
			(xy 260.485915 -13.421756) (xy 260.441843 -13.46583) (xy 260.403901 -13.51528) (xy 260.372737 -13.569258)
			(xy 260.348886 -13.626843) (xy 260.332756 -13.687048) (xy 260.324621 -13.748844) (xy 260.324092 -13.780008)
			(xy 260.324092 -21.044662) (xy 260.32459 -21.059465) (xy 260.333067 -21.087832) (xy 260.349321 -21.112578)
			(xy 260.371987 -21.131625) (xy 260.399161 -21.143376) (xy 260.428564 -21.146842) (xy 260.457726 -21.141733)
			(xy 260.4842 -21.128479) (xy 260.505763 -21.108191) (xy 260.520604 -21.082574) (xy 260.524498 -21.068284)
			(xy 260.549167 -20.967779) (xy 260.60538 -20.768585) (xy 260.669369 -20.571751) (xy 260.741035 -20.377581)
			(xy 260.820269 -20.186374) (xy 260.906947 -19.998424) (xy 261.000937 -19.814022) (xy 261.102093 -19.633452)
			(xy 261.21026 -19.456992) (xy 261.32527 -19.284914) (xy 261.446946 -19.117483) (xy 261.575102 -18.954958)
			(xy 261.709538 -18.797589) (xy 261.850049 -18.645619) (xy 261.996417 -18.499282) (xy 262.148416 -18.358803)
			(xy 262.305814 -18.2244) (xy 262.468365 -18.096278) (xy 262.635821 -17.974637) (xy 262.807924 -17.859663)
			(xy 262.984406 -17.751534) (xy 263.164998 -17.650415) (xy 263.34942 -17.556464) (xy 263.537387 -17.469825)
			(xy 263.728611 -17.390632) (xy 263.922796 -17.319006) (xy 264.119644 -17.255059) (xy 264.31885 -17.198887)
			(xy 264.520107 -17.15058) (xy 264.723105 -17.11021) (xy 264.927532 -17.077839) (xy 265.133072 -17.053519)
			(xy 265.339409 -17.037286) (xy 265.546223 -17.029166) (xy 265.64971 -17.028668) (xy 265.751936 -17.029164)
			(xy 265.956233 -17.037092) (xy 266.16007 -17.052936) (xy 266.363139 -17.076672) (xy 266.565135 -17.108263)
			(xy 266.765754 -17.147664) (xy 266.964694 -17.194814) (xy 267.161656 -17.249643) (xy 267.356345 -17.312067)
			(xy 267.548466 -17.381994) (xy 267.737731 -17.459318) (xy 267.923856 -17.543922) (xy 268.106561 -17.63568)
			(xy 268.28557 -17.734453) (xy 268.460614 -17.840094) (xy 268.63143 -17.952442) (xy 268.797762 -18.071329)
			(xy 268.959359 -18.196576) (xy 269.115978 -18.327995) (xy 269.267383 -18.465388) (xy 269.413346 -18.608548)
			(xy 269.553649 -18.757261) (xy 269.68808 -18.911302) (xy 269.816437 -19.07044) (xy 269.938527 -19.234435)
			(xy 270.054166 -19.403042) (xy 270.16318 -19.576005) (xy 270.265406 -19.753065) (xy 270.360689 -19.933956)
			(xy 270.448886 -20.118405) (xy 270.529865 -20.306136) (xy 270.603504 -20.496865) (xy 270.669692 -20.690306)
			(xy 270.728329 -20.886169) (xy 270.779328 -21.084157) (xy 270.822611 -21.283975) (xy 270.858113 -21.48532)
			(xy 270.885782 -21.687891) (xy 270.905575 -21.891382) (xy 270.917463 -22.095487) (xy 270.921428 -22.2999)
			(xy 270.921427 -22.29993) (xy 375.62816 -22.29993) (xy 375.632174 -22.094246) (xy 375.64421 -21.888876)
			(xy 375.664249 -21.684132) (xy 375.692262 -21.480325) (xy 375.728205 -21.277766) (xy 375.772024 -21.076764)
			(xy 375.823651 -20.877625) (xy 375.883009 -20.680652) (xy 375.950007 -20.486144) (xy 376.024543 -20.294399)
			(xy 376.106503 -20.105708) (xy 376.195763 -19.920358) (xy 376.292186 -19.738632) (xy 376.395627 -19.560806)
			(xy 376.505926 -19.387152) (xy 376.622917 -19.217933) (xy 376.746421 -19.053407) (xy 376.87625 -18.893826)
			(xy 377.012207 -18.739431) (xy 377.154084 -18.590459) (xy 377.301665 -18.447135) (xy 377.454726 -18.309679)
			(xy 377.613033 -18.178299) (xy 377.776346 -18.053196) (xy 377.944415 -17.934559) (xy 378.116985 -17.822571)
			(xy 378.293793 -17.7174) (xy 378.47457 -17.619209) (xy 378.65904 -17.528145) (xy 378.846922 -17.444348)
			(xy 379.037932 -17.367945) (xy 379.231776 -17.299052) (xy 379.428161 -17.237775) (xy 379.626787 -17.184207)
			(xy 379.827352 -17.13843) (xy 380.02955 -17.100512) (xy 380.233074 -17.070513) (xy 380.437613 -17.048476)
			(xy 380.642856 -17.034437) (xy 380.848491 -17.028417) (xy 381.054204 -17.030424) (xy 381.259682 -17.040456)
			(xy 381.464612 -17.058497) (xy 381.668682 -17.08452) (xy 381.871582 -17.118485) (xy 382.073002 -17.16034)
			(xy 382.272635 -17.210022) (xy 382.470178 -17.267456) (xy 382.66533 -17.332553) (xy 382.857794 -17.405214)
			(xy 383.047276 -17.48533) (xy 383.233487 -17.572777) (xy 383.341348 -17.628666) (xy 389.660162 -17.628666)
			(xy 389.660162 -17.574134) (xy 389.667923 -17.520157) (xy 389.683286 -17.467834) (xy 389.705939 -17.41823)
			(xy 389.73542 -17.372354) (xy 389.77113 -17.331141) (xy 389.812342 -17.29543) (xy 389.858216 -17.265946)
			(xy 389.907819 -17.243291) (xy 389.960142 -17.227926) (xy 390.014118 -17.220163) (xy 390.041384 -17.219676)
			(xy 390.904984 -17.219676) (xy 390.932258 -17.220062) (xy 390.986252 -17.227824) (xy 391.038592 -17.24319)
			(xy 391.088212 -17.265849) (xy 391.134103 -17.295339) (xy 391.175329 -17.33106) (xy 391.211051 -17.372285)
			(xy 391.240543 -17.418174) (xy 391.263204 -17.467793) (xy 391.278573 -17.520132) (xy 391.286336 -17.574126)
			(xy 391.286336 -17.628666) (xy 395.248162 -17.628666) (xy 395.248162 -17.574134) (xy 395.255923 -17.520157)
			(xy 395.271286 -17.467834) (xy 395.293939 -17.41823) (xy 395.32342 -17.372354) (xy 395.35913 -17.331141)
			(xy 395.400342 -17.29543) (xy 395.446216 -17.265946) (xy 395.495819 -17.243291) (xy 395.548142 -17.227926)
			(xy 395.602118 -17.220163) (xy 395.629384 -17.219676) (xy 396.492984 -17.219676) (xy 396.520258 -17.220062)
			(xy 396.574252 -17.227824) (xy 396.626592 -17.24319) (xy 396.676212 -17.265849) (xy 396.722103 -17.295339)
			(xy 396.763329 -17.33106) (xy 396.799051 -17.372285) (xy 396.828543 -17.418174) (xy 396.851204 -17.467793)
			(xy 396.866573 -17.520132) (xy 396.874336 -17.574126) (xy 396.874336 -17.628666) (xy 400.836162 -17.628666)
			(xy 400.836162 -17.574134) (xy 400.843923 -17.520157) (xy 400.859286 -17.467834) (xy 400.881939 -17.41823)
			(xy 400.91142 -17.372354) (xy 400.94713 -17.331141) (xy 400.988342 -17.29543) (xy 401.034216 -17.265946)
			(xy 401.083819 -17.243291) (xy 401.136142 -17.227926) (xy 401.190118 -17.220163) (xy 401.217384 -17.219676)
			(xy 402.080984 -17.219676) (xy 402.108258 -17.220062) (xy 402.162252 -17.227824) (xy 402.214592 -17.24319)
			(xy 402.264212 -17.265849) (xy 402.310103 -17.295339) (xy 402.351329 -17.33106) (xy 402.387051 -17.372285)
			(xy 402.416543 -17.418174) (xy 402.439204 -17.467793) (xy 402.454573 -17.520132) (xy 402.462336 -17.574126)
			(xy 402.462336 -17.628666) (xy 406.424162 -17.628666) (xy 406.424162 -17.574134) (xy 406.431923 -17.520157)
			(xy 406.447286 -17.467834) (xy 406.469939 -17.41823) (xy 406.49942 -17.372354) (xy 406.53513 -17.331141)
			(xy 406.576342 -17.29543) (xy 406.622216 -17.265946) (xy 406.671819 -17.243291) (xy 406.724142 -17.227926)
			(xy 406.778118 -17.220163) (xy 406.805384 -17.219676) (xy 407.668984 -17.219676) (xy 407.696258 -17.220062)
			(xy 407.750252 -17.227824) (xy 407.802592 -17.24319) (xy 407.852212 -17.265849) (xy 407.898103 -17.295339)
			(xy 407.939329 -17.33106) (xy 407.975051 -17.372285) (xy 408.004543 -17.418174) (xy 408.027204 -17.467793)
			(xy 408.042573 -17.520132) (xy 408.050336 -17.574126) (xy 408.050336 -17.628666) (xy 412.012162 -17.628666)
			(xy 412.012162 -17.574134) (xy 412.019923 -17.520157) (xy 412.035286 -17.467834) (xy 412.057939 -17.41823)
			(xy 412.08742 -17.372354) (xy 412.12313 -17.331141) (xy 412.164342 -17.29543) (xy 412.210216 -17.265946)
			(xy 412.259819 -17.243291) (xy 412.312142 -17.227926) (xy 412.366118 -17.220163) (xy 412.393384 -17.219676)
			(xy 413.256984 -17.219676) (xy 413.284258 -17.220062) (xy 413.338252 -17.227824) (xy 413.390592 -17.24319)
			(xy 413.440212 -17.265849) (xy 413.486103 -17.295339) (xy 413.527329 -17.33106) (xy 413.563051 -17.372285)
			(xy 413.592543 -17.418174) (xy 413.615204 -17.467793) (xy 413.630573 -17.520132) (xy 413.638336 -17.574126)
			(xy 413.638336 -17.628667) (xy 417.905962 -17.628667) (xy 417.905962 -17.574133) (xy 417.913723 -17.520155)
			(xy 417.929087 -17.467831) (xy 417.951741 -17.418226) (xy 417.981224 -17.372349) (xy 418.016936 -17.331136)
			(xy 418.058149 -17.295424) (xy 418.104026 -17.265941) (xy 418.153631 -17.243287) (xy 418.205955 -17.227923)
			(xy 418.259933 -17.220162) (xy 418.2872 -17.219676) (xy 419.1508 -17.219676) (xy 419.178072 -17.220087)
			(xy 419.232061 -17.227849) (xy 419.284396 -17.243216) (xy 419.334011 -17.265874) (xy 419.379896 -17.295363)
			(xy 419.421118 -17.331082) (xy 419.456837 -17.372304) (xy 419.486326 -17.418189) (xy 419.508984 -17.467804)
			(xy 419.524351 -17.520139) (xy 419.532113 -17.574128) (xy 419.532113 -17.628667) (xy 423.493962 -17.628667)
			(xy 423.493962 -17.574133) (xy 423.501723 -17.520155) (xy 423.517087 -17.467831) (xy 423.539741 -17.418226)
			(xy 423.569224 -17.372349) (xy 423.604936 -17.331136) (xy 423.646149 -17.295424) (xy 423.692026 -17.265941)
			(xy 423.741631 -17.243287) (xy 423.793955 -17.227923) (xy 423.847933 -17.220162) (xy 423.8752 -17.219676)
			(xy 424.7388 -17.219676) (xy 424.766072 -17.220087) (xy 424.820061 -17.227849) (xy 424.872396 -17.243216)
			(xy 424.922011 -17.265874) (xy 424.967896 -17.295363) (xy 425.009118 -17.331082) (xy 425.044837 -17.372304)
			(xy 425.074326 -17.418189) (xy 425.096984 -17.467804) (xy 425.112351 -17.520139) (xy 425.120113 -17.574128)
			(xy 425.120113 -17.62867) (xy 429.11594 -17.62867) (xy 429.11594 -17.57413) (xy 429.123702 -17.520145)
			(xy 429.139068 -17.467815) (xy 429.161726 -17.418204) (xy 429.191214 -17.372324) (xy 429.226932 -17.331107)
			(xy 429.268152 -17.295393) (xy 429.314036 -17.265909) (xy 429.363649 -17.243256) (xy 429.415981 -17.227894)
			(xy 429.469966 -17.220137) (xy 429.497236 -17.219676) (xy 430.360836 -17.219676) (xy 430.388106 -17.220089)
			(xy 430.442091 -17.227856) (xy 430.494422 -17.243226) (xy 430.544032 -17.265886) (xy 430.589913 -17.295376)
			(xy 430.631131 -17.331095) (xy 430.666846 -17.372315) (xy 430.696331 -17.418199) (xy 430.718987 -17.467812)
			(xy 430.734352 -17.520144) (xy 430.742114 -17.57413) (xy 430.742114 -17.62867) (xy 430.734352 -17.682656)
			(xy 430.718987 -17.734988) (xy 430.696331 -17.784601) (xy 430.666846 -17.830485) (xy 430.631131 -17.871705)
			(xy 430.589913 -17.907424) (xy 430.544032 -17.936914) (xy 430.494422 -17.959574) (xy 430.442091 -17.974944)
			(xy 430.388106 -17.982711) (xy 430.360836 -17.9832) (xy 429.497236 -17.9832) (xy 429.469966 -17.982663)
			(xy 429.415981 -17.974906) (xy 429.363649 -17.959544) (xy 429.314036 -17.936891) (xy 429.268152 -17.907407)
			(xy 429.226932 -17.871693) (xy 429.191214 -17.830476) (xy 429.161726 -17.784596) (xy 429.139068 -17.734985)
			(xy 429.123702 -17.682655) (xy 429.11594 -17.62867) (xy 425.120113 -17.62867) (xy 425.120113 -17.628672)
			(xy 425.112351 -17.682661) (xy 425.096984 -17.734996) (xy 425.074326 -17.784611) (xy 425.044837 -17.830496)
			(xy 425.009118 -17.871718) (xy 424.967896 -17.907437) (xy 424.922011 -17.936926) (xy 424.872396 -17.959584)
			(xy 424.820061 -17.974951) (xy 424.766072 -17.982713) (xy 424.7388 -17.9832) (xy 423.8752 -17.9832)
			(xy 423.847933 -17.982638) (xy 423.793955 -17.974877) (xy 423.741631 -17.959513) (xy 423.692026 -17.936859)
			(xy 423.646149 -17.907376) (xy 423.604936 -17.871664) (xy 423.569224 -17.830451) (xy 423.539741 -17.784574)
			(xy 423.517087 -17.734969) (xy 423.501723 -17.682645) (xy 423.493962 -17.628667) (xy 419.532113 -17.628667)
			(xy 419.532113 -17.628672) (xy 419.524351 -17.682661) (xy 419.508984 -17.734996) (xy 419.486326 -17.784611)
			(xy 419.456837 -17.830496) (xy 419.421118 -17.871718) (xy 419.379896 -17.907437) (xy 419.334011 -17.936926)
			(xy 419.284396 -17.959584) (xy 419.232061 -17.974951) (xy 419.178072 -17.982713) (xy 419.1508 -17.9832)
			(xy 418.2872 -17.9832) (xy 418.259933 -17.982638) (xy 418.205955 -17.974877) (xy 418.153631 -17.959513)
			(xy 418.104026 -17.936859) (xy 418.058149 -17.907376) (xy 418.016936 -17.871664) (xy 417.981224 -17.830451)
			(xy 417.951741 -17.784574) (xy 417.929087 -17.734969) (xy 417.913723 -17.682645) (xy 417.905962 -17.628667)
			(xy 413.638336 -17.628667) (xy 413.638336 -17.628674) (xy 413.630573 -17.682668) (xy 413.615204 -17.735007)
			(xy 413.592543 -17.784626) (xy 413.563051 -17.830515) (xy 413.527329 -17.87174) (xy 413.486103 -17.907461)
			(xy 413.440212 -17.936951) (xy 413.390592 -17.95961) (xy 413.338252 -17.974976) (xy 413.284258 -17.982738)
			(xy 413.256984 -17.9832) (xy 412.393384 -17.9832) (xy 412.366118 -17.982637) (xy 412.312142 -17.974874)
			(xy 412.259819 -17.959509) (xy 412.210216 -17.936854) (xy 412.164342 -17.90737) (xy 412.12313 -17.871659)
			(xy 412.08742 -17.830446) (xy 412.057939 -17.78457) (xy 412.035286 -17.734966) (xy 412.019923 -17.682643)
			(xy 412.012162 -17.628666) (xy 408.050336 -17.628666) (xy 408.050336 -17.628674) (xy 408.042573 -17.682668)
			(xy 408.027204 -17.735007) (xy 408.004543 -17.784626) (xy 407.975051 -17.830515) (xy 407.939329 -17.87174)
			(xy 407.898103 -17.907461) (xy 407.852212 -17.936951) (xy 407.802592 -17.95961) (xy 407.750252 -17.974976)
			(xy 407.696258 -17.982738) (xy 407.668984 -17.9832) (xy 406.805384 -17.9832) (xy 406.778118 -17.982637)
			(xy 406.724142 -17.974874) (xy 406.671819 -17.959509) (xy 406.622216 -17.936854) (xy 406.576342 -17.90737)
			(xy 406.53513 -17.871659) (xy 406.49942 -17.830446) (xy 406.469939 -17.78457) (xy 406.447286 -17.734966)
			(xy 406.431923 -17.682643) (xy 406.424162 -17.628666) (xy 402.462336 -17.628666) (xy 402.462336 -17.628674)
			(xy 402.454573 -17.682668) (xy 402.439204 -17.735007) (xy 402.416543 -17.784626) (xy 402.387051 -17.830515)
			(xy 402.351329 -17.87174) (xy 402.310103 -17.907461) (xy 402.264212 -17.936951) (xy 402.214592 -17.95961)
			(xy 402.162252 -17.974976) (xy 402.108258 -17.982738) (xy 402.080984 -17.9832) (xy 401.217384 -17.9832)
			(xy 401.190118 -17.982637) (xy 401.136142 -17.974874) (xy 401.083819 -17.959509) (xy 401.034216 -17.936854)
			(xy 400.988342 -17.90737) (xy 400.94713 -17.871659) (xy 400.91142 -17.830446) (xy 400.881939 -17.78457)
			(xy 400.859286 -17.734966) (xy 400.843923 -17.682643) (xy 400.836162 -17.628666) (xy 396.874336 -17.628666)
			(xy 396.874336 -17.628674) (xy 396.866573 -17.682668) (xy 396.851204 -17.735007) (xy 396.828543 -17.784626)
			(xy 396.799051 -17.830515) (xy 396.763329 -17.87174) (xy 396.722103 -17.907461) (xy 396.676212 -17.936951)
			(xy 396.626592 -17.95961) (xy 396.574252 -17.974976) (xy 396.520258 -17.982738) (xy 396.492984 -17.9832)
			(xy 395.629384 -17.9832) (xy 395.602118 -17.982637) (xy 395.548142 -17.974874) (xy 395.495819 -17.959509)
			(xy 395.446216 -17.936854) (xy 395.400342 -17.90737) (xy 395.35913 -17.871659) (xy 395.32342 -17.830446)
			(xy 395.293939 -17.78457) (xy 395.271286 -17.734966) (xy 395.255923 -17.682643) (xy 395.248162 -17.628666)
			(xy 391.286336 -17.628666) (xy 391.286336 -17.628674) (xy 391.278573 -17.682668) (xy 391.263204 -17.735007)
			(xy 391.240543 -17.784626) (xy 391.211051 -17.830515) (xy 391.175329 -17.87174) (xy 391.134103 -17.907461)
			(xy 391.088212 -17.936951) (xy 391.038592 -17.95961) (xy 390.986252 -17.974976) (xy 390.932258 -17.982738)
			(xy 390.904984 -17.9832) (xy 390.041384 -17.9832) (xy 390.014118 -17.982637) (xy 389.960142 -17.974874)
			(xy 389.907819 -17.959509) (xy 389.858216 -17.936854) (xy 389.812342 -17.90737) (xy 389.77113 -17.871659)
			(xy 389.73542 -17.830446) (xy 389.705939 -17.78457) (xy 389.683286 -17.734966) (xy 389.667923 -17.682643)
			(xy 389.660162 -17.628666) (xy 383.341348 -17.628666) (xy 383.416146 -17.667423) (xy 383.594972 -17.769123)
			(xy 383.769694 -17.877723) (xy 383.940047 -17.993058) (xy 384.105769 -18.114951) (xy 384.26661 -18.243217)
			(xy 384.422323 -18.37766) (xy 384.572673 -18.518077) (xy 384.71743 -18.664253) (xy 384.856373 -18.815965)
			(xy 384.989291 -18.972983) (xy 385.115982 -19.135068) (xy 385.128663 -19.152666) (xy 392.454162 -19.152666)
			(xy 392.454162 -19.098134) (xy 392.461923 -19.044157) (xy 392.477286 -18.991834) (xy 392.499939 -18.94223)
			(xy 392.52942 -18.896354) (xy 392.56513 -18.855141) (xy 392.606342 -18.81943) (xy 392.652216 -18.789946)
			(xy 392.701819 -18.767291) (xy 392.754142 -18.751926) (xy 392.808118 -18.744163) (xy 392.835384 -18.743676)
			(xy 393.698984 -18.743676) (xy 393.726258 -18.744062) (xy 393.780252 -18.751824) (xy 393.832592 -18.76719)
			(xy 393.882212 -18.789849) (xy 393.928103 -18.819339) (xy 393.969329 -18.85506) (xy 394.005051 -18.896285)
			(xy 394.034543 -18.942174) (xy 394.057204 -18.991793) (xy 394.072573 -19.044132) (xy 394.080336 -19.098126)
			(xy 394.080336 -19.152666) (xy 398.042162 -19.152666) (xy 398.042162 -19.098134) (xy 398.049923 -19.044157)
			(xy 398.065286 -18.991834) (xy 398.087939 -18.94223) (xy 398.11742 -18.896354) (xy 398.15313 -18.855141)
			(xy 398.194342 -18.81943) (xy 398.240216 -18.789946) (xy 398.289819 -18.767291) (xy 398.342142 -18.751926)
			(xy 398.396118 -18.744163) (xy 398.423384 -18.743676) (xy 399.286984 -18.743676) (xy 399.314258 -18.744062)
			(xy 399.368252 -18.751824) (xy 399.420592 -18.76719) (xy 399.470212 -18.789849) (xy 399.516103 -18.819339)
			(xy 399.557329 -18.85506) (xy 399.593051 -18.896285) (xy 399.622543 -18.942174) (xy 399.645204 -18.991793)
			(xy 399.660573 -19.044132) (xy 399.668336 -19.098126) (xy 399.668336 -19.152666) (xy 403.630162 -19.152666)
			(xy 403.630162 -19.098134) (xy 403.637923 -19.044157) (xy 403.653286 -18.991834) (xy 403.675939 -18.94223)
			(xy 403.70542 -18.896354) (xy 403.74113 -18.855141) (xy 403.782342 -18.81943) (xy 403.828216 -18.789946)
			(xy 403.877819 -18.767291) (xy 403.930142 -18.751926) (xy 403.984118 -18.744163) (xy 404.011384 -18.743676)
			(xy 404.874984 -18.743676) (xy 404.902258 -18.744062) (xy 404.956252 -18.751824) (xy 405.008592 -18.76719)
			(xy 405.058212 -18.789849) (xy 405.104103 -18.819339) (xy 405.145329 -18.85506) (xy 405.181051 -18.896285)
			(xy 405.210543 -18.942174) (xy 405.233204 -18.991793) (xy 405.248573 -19.044132) (xy 405.256336 -19.098126)
			(xy 405.256336 -19.152666) (xy 409.218162 -19.152666) (xy 409.218162 -19.098134) (xy 409.225923 -19.044157)
			(xy 409.241286 -18.991834) (xy 409.263939 -18.94223) (xy 409.29342 -18.896354) (xy 409.32913 -18.855141)
			(xy 409.370342 -18.81943) (xy 409.416216 -18.789946) (xy 409.465819 -18.767291) (xy 409.518142 -18.751926)
			(xy 409.572118 -18.744163) (xy 409.599384 -18.743676) (xy 410.462984 -18.743676) (xy 410.490258 -18.744062)
			(xy 410.544252 -18.751824) (xy 410.596592 -18.76719) (xy 410.646212 -18.789849) (xy 410.692103 -18.819339)
			(xy 410.733329 -18.85506) (xy 410.769051 -18.896285) (xy 410.798543 -18.942174) (xy 410.821204 -18.991793)
			(xy 410.836573 -19.044132) (xy 410.844336 -19.098126) (xy 410.844336 -19.152667) (xy 415.111962 -19.152667)
			(xy 415.111962 -19.098133) (xy 415.119723 -19.044155) (xy 415.135087 -18.991831) (xy 415.157741 -18.942226)
			(xy 415.187224 -18.896349) (xy 415.222936 -18.855136) (xy 415.264149 -18.819424) (xy 415.310026 -18.789941)
			(xy 415.359631 -18.767287) (xy 415.411955 -18.751923) (xy 415.465933 -18.744162) (xy 415.4932 -18.743676)
			(xy 416.3568 -18.743676) (xy 416.384072 -18.744087) (xy 416.438061 -18.751849) (xy 416.490396 -18.767216)
			(xy 416.540011 -18.789874) (xy 416.585896 -18.819363) (xy 416.627118 -18.855082) (xy 416.662837 -18.896304)
			(xy 416.692326 -18.942189) (xy 416.714984 -18.991804) (xy 416.730351 -19.044139) (xy 416.738113 -19.098128)
			(xy 416.738113 -19.152667) (xy 420.699962 -19.152667) (xy 420.699962 -19.098133) (xy 420.707723 -19.044155)
			(xy 420.723087 -18.991831) (xy 420.745741 -18.942226) (xy 420.775224 -18.896349) (xy 420.810936 -18.855136)
			(xy 420.852149 -18.819424) (xy 420.898026 -18.789941) (xy 420.947631 -18.767287) (xy 420.999955 -18.751923)
			(xy 421.053933 -18.744162) (xy 421.0812 -18.743676) (xy 421.9448 -18.743676) (xy 421.972072 -18.744087)
			(xy 422.026061 -18.751849) (xy 422.078396 -18.767216) (xy 422.128011 -18.789874) (xy 422.173896 -18.819363)
			(xy 422.215118 -18.855082) (xy 422.250837 -18.896304) (xy 422.280326 -18.942189) (xy 422.302984 -18.991804)
			(xy 422.318351 -19.044139) (xy 422.326113 -19.098128) (xy 422.326113 -19.15267) (xy 426.32194 -19.15267)
			(xy 426.32194 -19.09813) (xy 426.329702 -19.044145) (xy 426.345068 -18.991815) (xy 426.367726 -18.942204)
			(xy 426.397214 -18.896324) (xy 426.432932 -18.855107) (xy 426.474152 -18.819393) (xy 426.520036 -18.789909)
			(xy 426.569649 -18.767256) (xy 426.621981 -18.751894) (xy 426.675966 -18.744137) (xy 426.703236 -18.743676)
			(xy 427.566836 -18.743676) (xy 427.594106 -18.744089) (xy 427.648091 -18.751856) (xy 427.700422 -18.767226)
			(xy 427.750032 -18.789886) (xy 427.795913 -18.819376) (xy 427.837131 -18.855095) (xy 427.872846 -18.896315)
			(xy 427.902331 -18.942199) (xy 427.924987 -18.991812) (xy 427.940352 -19.044144) (xy 427.948114 -19.09813)
			(xy 427.948114 -19.15267) (xy 431.90994 -19.15267) (xy 431.90994 -19.09813) (xy 431.917702 -19.044145)
			(xy 431.933068 -18.991815) (xy 431.955726 -18.942204) (xy 431.985214 -18.896324) (xy 432.020932 -18.855107)
			(xy 432.062152 -18.819393) (xy 432.108036 -18.789909) (xy 432.157649 -18.767256) (xy 432.209981 -18.751894)
			(xy 432.263966 -18.744137) (xy 432.291236 -18.743676) (xy 433.154836 -18.743676) (xy 433.182106 -18.744089)
			(xy 433.236091 -18.751856) (xy 433.288422 -18.767226) (xy 433.338032 -18.789886) (xy 433.383913 -18.819376)
			(xy 433.425131 -18.855095) (xy 433.460846 -18.896315) (xy 433.490331 -18.942199) (xy 433.512987 -18.991812)
			(xy 433.528352 -19.044144) (xy 433.536114 -19.09813) (xy 433.536114 -19.15267) (xy 433.528352 -19.206656)
			(xy 433.512987 -19.258988) (xy 433.490331 -19.308601) (xy 433.460846 -19.354485) (xy 433.425131 -19.395705)
			(xy 433.383913 -19.431424) (xy 433.338032 -19.460914) (xy 433.288422 -19.483574) (xy 433.236091 -19.498944)
			(xy 433.182106 -19.506711) (xy 433.154836 -19.5072) (xy 432.291236 -19.5072) (xy 432.263966 -19.506663)
			(xy 432.209981 -19.498906) (xy 432.157649 -19.483544) (xy 432.108036 -19.460891) (xy 432.062152 -19.431407)
			(xy 432.020932 -19.395693) (xy 431.985214 -19.354476) (xy 431.955726 -19.308596) (xy 431.933068 -19.258985)
			(xy 431.917702 -19.206655) (xy 431.90994 -19.15267) (xy 427.948114 -19.15267) (xy 427.940352 -19.206656)
			(xy 427.924987 -19.258988) (xy 427.902331 -19.308601) (xy 427.872846 -19.354485) (xy 427.837131 -19.395705)
			(xy 427.795913 -19.431424) (xy 427.750032 -19.460914) (xy 427.700422 -19.483574) (xy 427.648091 -19.498944)
			(xy 427.594106 -19.506711) (xy 427.566836 -19.5072) (xy 426.703236 -19.5072) (xy 426.675966 -19.506663)
			(xy 426.621981 -19.498906) (xy 426.569649 -19.483544) (xy 426.520036 -19.460891) (xy 426.474152 -19.431407)
			(xy 426.432932 -19.395693) (xy 426.397214 -19.354476) (xy 426.367726 -19.308596) (xy 426.345068 -19.258985)
			(xy 426.329702 -19.206655) (xy 426.32194 -19.15267) (xy 422.326113 -19.15267) (xy 422.326113 -19.152672)
			(xy 422.318351 -19.206661) (xy 422.302984 -19.258996) (xy 422.280326 -19.308611) (xy 422.250837 -19.354496)
			(xy 422.215118 -19.395718) (xy 422.173896 -19.431437) (xy 422.128011 -19.460926) (xy 422.078396 -19.483584)
			(xy 422.026061 -19.498951) (xy 421.972072 -19.506713) (xy 421.9448 -19.5072) (xy 421.0812 -19.5072)
			(xy 421.053933 -19.506638) (xy 420.999955 -19.498877) (xy 420.947631 -19.483513) (xy 420.898026 -19.460859)
			(xy 420.852149 -19.431376) (xy 420.810936 -19.395664) (xy 420.775224 -19.354451) (xy 420.745741 -19.308574)
			(xy 420.723087 -19.258969) (xy 420.707723 -19.206645) (xy 420.699962 -19.152667) (xy 416.738113 -19.152667)
			(xy 416.738113 -19.152672) (xy 416.730351 -19.206661) (xy 416.714984 -19.258996) (xy 416.692326 -19.308611)
			(xy 416.662837 -19.354496) (xy 416.627118 -19.395718) (xy 416.585896 -19.431437) (xy 416.540011 -19.460926)
			(xy 416.490396 -19.483584) (xy 416.438061 -19.498951) (xy 416.384072 -19.506713) (xy 416.3568 -19.5072)
			(xy 415.4932 -19.5072) (xy 415.465933 -19.506638) (xy 415.411955 -19.498877) (xy 415.359631 -19.483513)
			(xy 415.310026 -19.460859) (xy 415.264149 -19.431376) (xy 415.222936 -19.395664) (xy 415.187224 -19.354451)
			(xy 415.157741 -19.308574) (xy 415.135087 -19.258969) (xy 415.119723 -19.206645) (xy 415.111962 -19.152667)
			(xy 410.844336 -19.152667) (xy 410.844336 -19.152674) (xy 410.836573 -19.206668) (xy 410.821204 -19.259007)
			(xy 410.798543 -19.308626) (xy 410.769051 -19.354515) (xy 410.733329 -19.39574) (xy 410.692103 -19.431461)
			(xy 410.646212 -19.460951) (xy 410.596592 -19.48361) (xy 410.544252 -19.498976) (xy 410.490258 -19.506738)
			(xy 410.462984 -19.5072) (xy 409.599384 -19.5072) (xy 409.572118 -19.506637) (xy 409.518142 -19.498874)
			(xy 409.465819 -19.483509) (xy 409.416216 -19.460854) (xy 409.370342 -19.43137) (xy 409.32913 -19.395659)
			(xy 409.29342 -19.354446) (xy 409.263939 -19.30857) (xy 409.241286 -19.258966) (xy 409.225923 -19.206643)
			(xy 409.218162 -19.152666) (xy 405.256336 -19.152666) (xy 405.256336 -19.152674) (xy 405.248573 -19.206668)
			(xy 405.233204 -19.259007) (xy 405.210543 -19.308626) (xy 405.181051 -19.354515) (xy 405.145329 -19.39574)
			(xy 405.104103 -19.431461) (xy 405.058212 -19.460951) (xy 405.008592 -19.48361) (xy 404.956252 -19.498976)
			(xy 404.902258 -19.506738) (xy 404.874984 -19.5072) (xy 404.011384 -19.5072) (xy 403.984118 -19.506637)
			(xy 403.930142 -19.498874) (xy 403.877819 -19.483509) (xy 403.828216 -19.460854) (xy 403.782342 -19.43137)
			(xy 403.74113 -19.395659) (xy 403.70542 -19.354446) (xy 403.675939 -19.30857) (xy 403.653286 -19.258966)
			(xy 403.637923 -19.206643) (xy 403.630162 -19.152666) (xy 399.668336 -19.152666) (xy 399.668336 -19.152674)
			(xy 399.660573 -19.206668) (xy 399.645204 -19.259007) (xy 399.622543 -19.308626) (xy 399.593051 -19.354515)
			(xy 399.557329 -19.39574) (xy 399.516103 -19.431461) (xy 399.470212 -19.460951) (xy 399.420592 -19.48361)
			(xy 399.368252 -19.498976) (xy 399.314258 -19.506738) (xy 399.286984 -19.5072) (xy 398.423384 -19.5072)
			(xy 398.396118 -19.506637) (xy 398.342142 -19.498874) (xy 398.289819 -19.483509) (xy 398.240216 -19.460854)
			(xy 398.194342 -19.43137) (xy 398.15313 -19.395659) (xy 398.11742 -19.354446) (xy 398.087939 -19.30857)
			(xy 398.065286 -19.258966) (xy 398.049923 -19.206643) (xy 398.042162 -19.152666) (xy 394.080336 -19.152666)
			(xy 394.080336 -19.152674) (xy 394.072573 -19.206668) (xy 394.057204 -19.259007) (xy 394.034543 -19.308626)
			(xy 394.005051 -19.354515) (xy 393.969329 -19.39574) (xy 393.928103 -19.431461) (xy 393.882212 -19.460951)
			(xy 393.832592 -19.48361) (xy 393.780252 -19.498976) (xy 393.726258 -19.506738) (xy 393.698984 -19.5072)
			(xy 392.835384 -19.5072) (xy 392.808118 -19.506637) (xy 392.754142 -19.498874) (xy 392.701819 -19.483509)
			(xy 392.652216 -19.460854) (xy 392.606342 -19.43137) (xy 392.56513 -19.395659) (xy 392.52942 -19.354446)
			(xy 392.499939 -19.30857) (xy 392.477286 -19.258966) (xy 392.461923 -19.206643) (xy 392.454162 -19.152666)
			(xy 385.128663 -19.152666) (xy 385.236252 -19.301971) (xy 385.349919 -19.473441) (xy 385.456809 -19.649214)
			(xy 385.55676 -19.829024) (xy 385.649619 -20.012597) (xy 385.735246 -20.199653) (xy 385.813508 -20.389908)
			(xy 385.884289 -20.583071) (xy 385.947479 -20.778849) (xy 386.002982 -20.976943) (xy 386.050714 -21.177052)
			(xy 386.090603 -21.37887) (xy 386.122587 -21.582092) (xy 386.146617 -21.786406) (xy 386.162658 -21.991502)
			(xy 386.170684 -22.197069) (xy 386.171186 -22.29993) (xy 459.52817 -22.29993) (xy 459.532184 -22.094246)
			(xy 459.54422 -21.888876) (xy 459.564259 -21.684132) (xy 459.592272 -21.480325) (xy 459.628215 -21.277766)
			(xy 459.672034 -21.076764) (xy 459.723661 -20.877625) (xy 459.783019 -20.680652) (xy 459.850017 -20.486144)
			(xy 459.924553 -20.294399) (xy 460.006513 -20.105708) (xy 460.095773 -19.920358) (xy 460.192196 -19.738632)
			(xy 460.295637 -19.560806) (xy 460.405936 -19.387152) (xy 460.522927 -19.217933) (xy 460.646431 -19.053407)
			(xy 460.77626 -18.893826) (xy 460.912217 -18.739431) (xy 461.054094 -18.590459) (xy 461.201675 -18.447135)
			(xy 461.354736 -18.309679) (xy 461.513043 -18.178299) (xy 461.676356 -18.053196) (xy 461.844425 -17.934559)
			(xy 462.016995 -17.822571) (xy 462.193803 -17.7174) (xy 462.37458 -17.619209) (xy 462.55905 -17.528145)
			(xy 462.746932 -17.444348) (xy 462.937942 -17.367945) (xy 463.131786 -17.299052) (xy 463.328171 -17.237775)
			(xy 463.526797 -17.184207) (xy 463.727362 -17.13843) (xy 463.92956 -17.100512) (xy 464.133084 -17.070513)
			(xy 464.337623 -17.048476) (xy 464.542866 -17.034437) (xy 464.748501 -17.028417) (xy 464.954214 -17.030424)
			(xy 465.159692 -17.040456) (xy 465.364622 -17.058497) (xy 465.568692 -17.08452) (xy 465.771592 -17.118485)
			(xy 465.973012 -17.16034) (xy 466.172645 -17.210022) (xy 466.370188 -17.267456) (xy 466.56534 -17.332553)
			(xy 466.757804 -17.405214) (xy 466.947286 -17.48533) (xy 467.133497 -17.572777) (xy 467.316156 -17.667423)
			(xy 467.494982 -17.769123) (xy 467.669704 -17.877723) (xy 467.840057 -17.993058) (xy 468.005779 -18.114951)
			(xy 468.16662 -18.243217) (xy 468.322333 -18.37766) (xy 468.472683 -18.518077) (xy 468.61744 -18.664253)
			(xy 468.756383 -18.815965) (xy 468.889301 -18.972983) (xy 469.015992 -19.135068) (xy 469.136262 -19.301971)
			(xy 469.249929 -19.473441) (xy 469.356819 -19.649214) (xy 469.45677 -19.829024) (xy 469.549629 -20.012597)
			(xy 469.635256 -20.199653) (xy 469.713518 -20.389908) (xy 469.784299 -20.583071) (xy 469.847489 -20.778849)
			(xy 469.902992 -20.976943) (xy 469.950724 -21.177052) (xy 469.990613 -21.37887) (xy 470.022597 -21.582092)
			(xy 470.046627 -21.786406) (xy 470.062668 -21.991502) (xy 470.070694 -22.197069) (xy 470.071196 -22.29993)
			(xy 470.070694 -22.402791) (xy 470.062668 -22.608358) (xy 470.046627 -22.813454) (xy 470.022597 -23.017768)
			(xy 469.990613 -23.22099) (xy 469.950724 -23.422808) (xy 469.902992 -23.622917) (xy 469.847489 -23.821011)
			(xy 469.784299 -24.016789) (xy 469.713518 -24.209952) (xy 469.635256 -24.400207) (xy 469.549629 -24.587263)
			(xy 469.45677 -24.770836) (xy 469.356819 -24.950646) (xy 469.249929 -25.126419) (xy 469.136262 -25.297889)
			(xy 469.015992 -25.464792) (xy 468.889301 -25.626877) (xy 468.756383 -25.783895) (xy 468.61744 -25.935607)
			(xy 468.472683 -26.081783) (xy 468.322333 -26.2222) (xy 468.16662 -26.356643) (xy 468.005779 -26.484909)
			(xy 467.840057 -26.606802) (xy 467.669704 -26.722137) (xy 467.494982 -26.830737) (xy 467.316156 -26.932437)
			(xy 467.133497 -27.027083) (xy 466.947286 -27.11453) (xy 466.757804 -27.194646) (xy 466.56534 -27.267307)
			(xy 466.370188 -27.332404) (xy 466.172645 -27.389838) (xy 465.973012 -27.43952) (xy 465.771592 -27.481375)
			(xy 465.568692 -27.51534) (xy 465.364622 -27.541363) (xy 465.159692 -27.559404) (xy 464.954214 -27.569436)
			(xy 464.748501 -27.571443) (xy 464.542866 -27.565423) (xy 464.337623 -27.551384) (xy 464.133084 -27.529347)
			(xy 463.92956 -27.499348) (xy 463.727362 -27.46143) (xy 463.526797 -27.415653) (xy 463.328171 -27.362085)
			(xy 463.131786 -27.300808) (xy 462.937942 -27.231915) (xy 462.746932 -27.155512) (xy 462.55905 -27.071715)
			(xy 462.37458 -26.980651) (xy 462.193803 -26.88246) (xy 462.016995 -26.777289) (xy 461.844425 -26.665301)
			(xy 461.676356 -26.546664) (xy 461.513043 -26.421561) (xy 461.354736 -26.290181) (xy 461.201675 -26.152725)
			(xy 461.054094 -26.009401) (xy 460.912217 -25.860429) (xy 460.77626 -25.706034) (xy 460.646431 -25.546453)
			(xy 460.522927 -25.381927) (xy 460.405936 -25.212708) (xy 460.295637 -25.039054) (xy 460.192196 -24.861228)
			(xy 460.095773 -24.679502) (xy 460.006513 -24.494152) (xy 459.924553 -24.305461) (xy 459.850017 -24.113716)
			(xy 459.783019 -23.919208) (xy 459.723661 -23.722235) (xy 459.672034 -23.523096) (xy 459.628215 -23.322094)
			(xy 459.592272 -23.119535) (xy 459.564259 -22.915728) (xy 459.54422 -22.710984) (xy 459.532184 -22.505614)
			(xy 459.52817 -22.29993) (xy 386.171186 -22.29993) (xy 386.170684 -22.402791) (xy 386.162658 -22.608358)
			(xy 386.146617 -22.813454) (xy 386.122587 -23.017768) (xy 386.090603 -23.22099) (xy 386.050714 -23.422808)
			(xy 386.002982 -23.622917) (xy 385.947479 -23.821011) (xy 385.884289 -24.016789) (xy 385.813508 -24.209952)
			(xy 385.735246 -24.400207) (xy 385.649619 -24.587263) (xy 385.55676 -24.770836) (xy 385.456809 -24.950646)
			(xy 385.349919 -25.126419) (xy 385.236252 -25.297889) (xy 385.115982 -25.464792) (xy 385.1132 -25.468351)
			(xy 388.406603 -25.468351) (xy 388.406603 -25.413849) (xy 388.41436 -25.359901) (xy 388.429716 -25.307607)
			(xy 388.452359 -25.25803) (xy 388.481827 -25.212181) (xy 388.517521 -25.170992) (xy 388.558713 -25.135303)
			(xy 388.604565 -25.10584) (xy 388.654144 -25.083202) (xy 388.70644 -25.067852) (xy 388.760389 -25.0601)
			(xy 388.78764 -25.05964) (xy 389.65124 -25.05964) (xy 389.678493 -25.060033) (xy 389.732443 -25.067795)
			(xy 389.78474 -25.083155) (xy 389.834318 -25.105802) (xy 389.880169 -25.135273) (xy 389.92136 -25.170969)
			(xy 389.957051 -25.212163) (xy 389.986518 -25.258017) (xy 390.009159 -25.307598) (xy 390.024514 -25.359896)
			(xy 390.03227 -25.413847) (xy 390.03227 -25.468353) (xy 390.024514 -25.522304) (xy 390.009159 -25.574602)
			(xy 389.986518 -25.624183) (xy 389.957051 -25.670037) (xy 389.92136 -25.711231) (xy 389.880169 -25.746927)
			(xy 389.834318 -25.776398) (xy 389.78474 -25.799045) (xy 389.732443 -25.814405) (xy 389.678493 -25.822167)
			(xy 389.65124 -25.822656) (xy 388.78764 -25.822656) (xy 388.760389 -25.8221) (xy 388.70644 -25.814348)
			(xy 388.654144 -25.798998) (xy 388.604565 -25.77636) (xy 388.558713 -25.746897) (xy 388.517521 -25.711208)
			(xy 388.481827 -25.670019) (xy 388.452359 -25.62417) (xy 388.429716 -25.574593) (xy 388.41436 -25.522299)
			(xy 388.406603 -25.468351) (xy 385.1132 -25.468351) (xy 384.989291 -25.626877) (xy 384.856373 -25.783895)
			(xy 384.71743 -25.935607) (xy 384.572673 -26.081783) (xy 384.422323 -26.2222) (xy 384.26661 -26.356643)
			(xy 384.105769 -26.484909) (xy 383.940047 -26.606802) (xy 383.769694 -26.722137) (xy 383.594972 -26.830737)
			(xy 383.416146 -26.932437) (xy 383.233487 -27.027083) (xy 383.047276 -27.11453) (xy 382.857794 -27.194646)
			(xy 382.66533 -27.267307) (xy 382.470178 -27.332404) (xy 382.272635 -27.389838) (xy 382.073002 -27.43952)
			(xy 381.871582 -27.481375) (xy 381.668682 -27.51534) (xy 381.464612 -27.541363) (xy 381.259682 -27.559404)
			(xy 381.054204 -27.569436) (xy 380.848491 -27.571443) (xy 380.642856 -27.565423) (xy 380.437613 -27.551384)
			(xy 380.233074 -27.529347) (xy 380.02955 -27.499348) (xy 379.827352 -27.46143) (xy 379.626787 -27.415653)
			(xy 379.428161 -27.362085) (xy 379.231776 -27.300808) (xy 379.037932 -27.231915) (xy 378.846922 -27.155512)
			(xy 378.65904 -27.071715) (xy 378.47457 -26.980651) (xy 378.293793 -26.88246) (xy 378.116985 -26.777289)
			(xy 377.944415 -26.665301) (xy 377.776346 -26.546664) (xy 377.613033 -26.421561) (xy 377.454726 -26.290181)
			(xy 377.301665 -26.152725) (xy 377.154084 -26.009401) (xy 377.012207 -25.860429) (xy 376.87625 -25.706034)
			(xy 376.746421 -25.546453) (xy 376.622917 -25.381927) (xy 376.505926 -25.212708) (xy 376.395627 -25.039054)
			(xy 376.292186 -24.861228) (xy 376.195763 -24.679502) (xy 376.106503 -24.494152) (xy 376.024543 -24.305461)
			(xy 375.950007 -24.113716) (xy 375.883009 -23.919208) (xy 375.823651 -23.722235) (xy 375.772024 -23.523096)
			(xy 375.728205 -23.322094) (xy 375.692262 -23.119535) (xy 375.664249 -22.915728) (xy 375.64421 -22.710984)
			(xy 375.632174 -22.505614) (xy 375.62816 -22.29993) (xy 270.921427 -22.29993) (xy 270.917463 -22.504313)
			(xy 270.905575 -22.708418) (xy 270.885782 -22.911909) (xy 270.858113 -23.11448) (xy 270.822611 -23.315825)
			(xy 270.779328 -23.515643) (xy 270.728329 -23.713631) (xy 270.669692 -23.909494) (xy 270.603504 -24.102935)
			(xy 270.529865 -24.293664) (xy 270.448886 -24.481395) (xy 270.360689 -24.665844) (xy 270.265406 -24.846735)
			(xy 270.16318 -25.023795) (xy 270.054166 -25.196758) (xy 269.938527 -25.365365) (xy 269.816437 -25.52936)
			(xy 269.68808 -25.688498) (xy 269.553649 -25.842539) (xy 269.413346 -25.991252) (xy 269.267383 -26.134412)
			(xy 269.115978 -26.271805) (xy 268.959359 -26.403224) (xy 268.797762 -26.528471) (xy 268.63143 -26.647358)
			(xy 268.460614 -26.759706) (xy 268.28557 -26.865347) (xy 268.106561 -26.96412) (xy 267.923856 -27.055878)
			(xy 267.737731 -27.140482) (xy 267.548466 -27.217806) (xy 267.356345 -27.287733) (xy 267.161656 -27.350157)
			(xy 266.964694 -27.404986) (xy 266.765754 -27.452136) (xy 266.565135 -27.491537) (xy 266.363139 -27.523128)
			(xy 266.16007 -27.546864) (xy 265.956233 -27.562708) (xy 265.751936 -27.570636) (xy 265.64971 -27.571192)
			(xy 265.546225 -27.570682) (xy 265.339414 -27.562554) (xy 265.133081 -27.546315) (xy 264.927545 -27.521988)
			(xy 264.723122 -27.489612) (xy 264.520128 -27.449237) (xy 264.318875 -27.400924) (xy 264.119673 -27.344749)
			(xy 263.922831 -27.280797) (xy 263.72865 -27.209168) (xy 263.537431 -27.129972) (xy 263.349467 -27.043331)
			(xy 263.16505 -26.949378) (xy 262.984463 -26.848258) (xy 262.807984 -26.740128) (xy 262.635886 -26.625154)
			(xy 262.468434 -26.503512) (xy 262.305885 -26.375392) (xy 262.148492 -26.240989) (xy 261.996495 -26.100512)
			(xy 261.85013 -25.954176) (xy 261.709622 -25.802208) (xy 261.575187 -25.644841) (xy 261.447033 -25.482319)
			(xy 261.325358 -25.314892) (xy 261.210349 -25.142817) (xy 261.102183 -24.96636) (xy 261.001027 -24.785793)
			(xy 260.907036 -24.601395) (xy 260.820357 -24.41345) (xy 260.741122 -24.222246) (xy 260.669453 -24.02808)
			(xy 260.605462 -23.83125) (xy 260.549246 -23.63206) (xy 260.524498 -23.531576) (xy 260.520567 -23.517303)
			(xy 260.505726 -23.491703) (xy 260.48417 -23.471431) (xy 260.457708 -23.458187) (xy 260.42856 -23.453083)
			(xy 260.399172 -23.456548) (xy 260.372011 -23.46829) (xy 260.349354 -23.487324) (xy 260.333102 -23.512053)
			(xy 260.324621 -23.540402) (xy 260.324092 -23.555198) (xy 260.324092 -33.275016) (xy 260.323592 -33.358891)
			(xy 260.31561 -33.52645) (xy 260.299664 -33.693439) (xy 260.27579 -33.859481) (xy 260.244042 -34.024198)
			(xy 260.204493 -34.187219) (xy 260.157232 -34.348173) (xy 260.102366 -34.506696) (xy 260.04002 -34.662429)
			(xy 259.970334 -34.815018) (xy 259.893466 -34.964119) (xy 259.809591 -35.109394) (xy 259.718898 -35.250513)
			(xy 259.621594 -35.387158) (xy 259.517898 -35.519017) (xy 259.408045 -35.645793) (xy 259.292284 -35.767199)
			(xy 259.170878 -35.882958) (xy 259.044102 -35.99281) (xy 258.912242 -36.096506) (xy 258.775597 -36.193809)
			(xy 258.634477 -36.284501) (xy 258.489202 -36.368375) (xy 258.3401 -36.445242) (xy 258.18751 -36.514927)
			(xy 258.031777 -36.577273) (xy 257.873254 -36.632138) (xy 257.7123 -36.679398) (xy 257.549279 -36.718947)
			(xy 257.384561 -36.750693) (xy 257.218519 -36.774566) (xy 257.05153 -36.790511) (xy 256.883971 -36.798493)
			(xy 256.800096 -36.799012) (xy 225.300032 -36.799012) (xy 225.216156 -36.798522) (xy 225.048595 -36.790541)
			(xy 224.881603 -36.774597) (xy 224.715559 -36.750725) (xy 224.550839 -36.718979) (xy 224.387816 -36.679432)
			(xy 224.226859 -36.632172) (xy 224.068333 -36.577307) (xy 223.912598 -36.514961) (xy 223.760005 -36.445276)
			(xy 223.610901 -36.368409) (xy 223.465624 -36.284535) (xy 223.324502 -36.193842) (xy 223.187855 -36.096538)
			(xy 223.055993 -35.992842) (xy 222.929214 -35.882989) (xy 222.807806 -35.767228) (xy 222.692043 -35.645822)
			(xy 222.582189 -35.519044) (xy 222.478491 -35.387184) (xy 222.381184 -35.250538) (xy 222.29049 -35.109417)
			(xy 222.206614 -34.964141) (xy 222.129745 -34.815038) (xy 222.060058 -34.662446) (xy 221.99771 -34.506712)
			(xy 221.942843 -34.348187) (xy 221.895581 -34.187231) (xy 221.856031 -34.024208) (xy 221.824283 -33.859488)
			(xy 221.800409 -33.693445) (xy 221.784462 -33.526453) (xy 221.77648 -33.358892) (xy 221.776036 -33.275016)
			(xy 221.776036 -13.780008) (xy 221.775527 -13.748842) (xy 221.767392 -13.687042) (xy 221.751261 -13.626833)
			(xy 221.727409 -13.569244) (xy 221.696245 -13.515262) (xy 221.658302 -13.465808) (xy 221.614228 -13.42173)
			(xy 221.564778 -13.383782) (xy 221.510799 -13.352612) (xy 221.453212 -13.328754) (xy 221.393005 -13.312617)
			(xy 221.331206 -13.304476) (xy 221.30004 -13.304012) (xy 196.701918 -13.304012) (xy 196.617223 -13.303509)
			(xy 196.448027 -13.295372) (xy 196.279418 -13.279115) (xy 196.111785 -13.254776) (xy 195.945515 -13.222412)
			(xy 195.780992 -13.182097) (xy 195.618595 -13.133924) (xy 195.458701 -13.078004) (xy 195.301678 -13.014468)
			(xy 195.147888 -12.94346) (xy 194.997688 -12.865146) (xy 194.851424 -12.779706) (xy 194.709433 -12.687337)
			(xy 194.572044 -12.588254) (xy 194.439575 -12.482684) (xy 194.31233 -12.370871) (xy 194.190604 -12.253075)
			(xy 194.074678 -12.129566) (xy 193.96482 -12.000631) (xy 193.861283 -11.866566) (xy 193.764307 -11.727681)
			(xy 193.674115 -11.584298) (xy 193.632074 -11.510772) (xy 193.624643 -11.49858) (xy 193.604286 -11.478578)
			(xy 193.579189 -11.464991) (xy 193.551312 -11.458879) (xy 193.522832 -11.460722) (xy 193.495974 -11.470375)
			(xy 193.472837 -11.487083) (xy 193.455228 -11.509541) (xy 193.444521 -11.535996) (xy 193.44259 -11.550142)
			(xy 193.437496 -11.59417) (xy 193.420266 -11.681117) (xy 193.395141 -11.766119) (xy 193.362333 -11.848462)
			(xy 193.322118 -11.927452) (xy 193.274834 -12.002424) (xy 193.220879 -12.072749) (xy 193.160707 -12.137834)
			(xy 193.094825 -12.197131) (xy 193.023786 -12.250142) (xy 192.948188 -12.29642) (xy 192.868668 -12.335577)
			(xy 192.785895 -12.367282) (xy 192.700565 -12.391269) (xy 192.613395 -12.407337) (xy 192.52512 -12.415349)
			(xy 192.436483 -12.415239) (xy 192.348228 -12.407008) (xy 192.261099 -12.390724) (xy 192.175828 -12.366525)
			(xy 192.093134 -12.334614) (xy 192.013711 -12.29526) (xy 191.938229 -12.248794) (xy 191.867322 -12.195607)
			(xy 191.801587 -12.136146) (xy 191.741577 -12.070912) (xy 191.687797 -12.000454) (xy 191.640699 -11.925364)
			(xy 191.60068 -11.846275) (xy 191.568077 -11.763851) (xy 191.543163 -11.678787) (xy 191.526148 -11.591797)
			(xy 191.517177 -11.503614) (xy 191.516323 -11.414981) (xy 191.523594 -11.326642) (xy 191.53893 -11.239341)
			(xy 191.5622 -11.153812) (xy 191.59321 -11.070775) (xy 191.631698 -10.99093) (xy 191.677341 -10.914947)
			(xy 191.729754 -10.843466) (xy 191.788496 -10.777088) (xy 191.853074 -10.716372) (xy 191.922943 -10.661829)
			(xy 191.997516 -10.613918) (xy 192.076166 -10.573041) (xy 192.15823 -10.539543) (xy 192.243019 -10.513706)
			(xy 192.329818 -10.495747) (xy 192.417898 -10.485817) (xy 192.506517 -10.483999) (xy 192.59493 -10.49031)
			(xy 192.682393 -10.504695) (xy 192.768169 -10.527034) (xy 192.851538 -10.557139) (xy 192.931798 -10.594757)
			(xy 193.008272 -10.639571) (xy 193.080319 -10.691203) (xy 193.114168 -10.719816) (xy 193.125179 -10.728748)
			(xy 193.15087 -10.740713) (xy 193.17886 -10.745153) (xy 193.206993 -10.741725) (xy 193.233098 -10.730693)
			(xy 193.255164 -10.712909) (xy 193.271489 -10.689743) (xy 193.280814 -10.66298) (xy 193.282422 -10.634685)
			(xy 193.279776 -10.620756) (xy 193.260011 -10.538189) (xy 193.227481 -10.371539) (xy 193.20301 -10.203517)
			(xy 193.186654 -10.034511) (xy 193.178452 -9.864914) (xy 193.177922 -9.780016) (xy 193.177922 -6.803898)
			(xy 127.62611 -6.803898) (xy 127.62611 -9.560306) (xy 127.626547 -9.574024) (xy 127.633838 -9.600474)
			(xy 127.647916 -9.624022) (xy 127.667763 -9.642964) (xy 127.691942 -9.655929) (xy 127.718702 -9.661978)
			(xy 127.746107 -9.660673) (xy 127.772172 -9.652109) (xy 127.783844 -9.644888) (xy 127.82071 -9.621071)
			(xy 127.897991 -9.57945) (xy 127.978729 -9.545014) (xy 128.062259 -9.518045) (xy 128.147891 -9.498766)
			(xy 128.234919 -9.487338) (xy 128.322626 -9.483853) (xy 128.410286 -9.48834) (xy 128.497178 -9.500764)
			(xy 128.582584 -9.52102) (xy 128.6658 -9.548942) (xy 128.746139 -9.5843) (xy 128.822939 -9.626802)
			(xy 128.895565 -9.676097) (xy 128.963419 -9.731778) (xy 129.02594 -9.793387) (xy 129.082613 -9.860414)
			(xy 129.132971 -9.932308) (xy 129.176597 -10.008474) (xy 129.213133 -10.088284) (xy 129.242276 -10.171081)
			(xy 129.263786 -10.25618) (xy 129.266056 -10.270548) (xy 131.63909 -10.270548) (xy 131.63909 -10.216052)
			(xy 131.646845 -10.16211) (xy 131.662198 -10.10982) (xy 131.684835 -10.060247) (xy 131.714296 -10.014401)
			(xy 131.749982 -9.973213) (xy 131.791165 -9.937522) (xy 131.837009 -9.908056) (xy 131.886579 -9.885413)
			(xy 131.938866 -9.870055) (xy 131.992808 -9.862293) (xy 132.020056 -9.861804) (xy 132.883656 -9.861804)
			(xy 132.910912 -9.86224) (xy 132.964869 -9.869992) (xy 133.017174 -9.885345) (xy 133.066761 -9.907985)
			(xy 133.112622 -9.937453) (xy 133.153821 -9.973148) (xy 133.18952 -10.014343) (xy 133.218993 -10.0602)
			(xy 133.24164 -10.109785) (xy 133.256999 -10.162088) (xy 133.264757 -10.216044) (xy 133.264757 -10.270556)
			(xy 133.256999 -10.324512) (xy 133.24164 -10.376815) (xy 133.218993 -10.4264) (xy 133.18952 -10.472257)
			(xy 133.153821 -10.513452) (xy 133.112622 -10.549147) (xy 133.066761 -10.578615) (xy 133.017174 -10.601255)
			(xy 132.964869 -10.616608) (xy 132.910912 -10.62436) (xy 132.883656 -10.62482) (xy 132.020056 -10.62482)
			(xy 131.992808 -10.624307) (xy 131.938866 -10.616545) (xy 131.886579 -10.601187) (xy 131.837009 -10.578544)
			(xy 131.791165 -10.549078) (xy 131.749982 -10.513387) (xy 131.714296 -10.472199) (xy 131.684835 -10.426353)
			(xy 131.662198 -10.37678) (xy 131.646845 -10.32449) (xy 131.63909 -10.270548) (xy 129.266056 -10.270548)
			(xy 129.277485 -10.342879) (xy 129.283261 -10.430465) (xy 129.281067 -10.518213) (xy 129.270919 -10.6054)
			(xy 129.252902 -10.691306) (xy 129.227164 -10.775224) (xy 129.193919 -10.856459) (xy 129.153439 -10.934343)
			(xy 129.106059 -11.008233) (xy 129.087143 -11.032553) (xy 168.158867 -11.032553) (xy 168.158867 -10.978047)
			(xy 168.166625 -10.924096) (xy 168.181981 -10.871798) (xy 168.204625 -10.822218) (xy 168.234094 -10.776365)
			(xy 168.269789 -10.735173) (xy 168.310983 -10.699481) (xy 168.356837 -10.670014) (xy 168.406419 -10.647374)
			(xy 168.458717 -10.63202) (xy 168.512669 -10.624266) (xy 168.539922 -10.623804) (xy 169.403522 -10.623804)
			(xy 169.430773 -10.624267) (xy 169.48472 -10.632027) (xy 169.537014 -10.647384) (xy 169.58659 -10.670027)
			(xy 169.632439 -10.699495) (xy 169.673628 -10.735188) (xy 169.709318 -10.776379) (xy 169.738783 -10.822229)
			(xy 169.761424 -10.871807) (xy 169.776778 -10.924101) (xy 169.784534 -10.978049) (xy 169.784534 -11.032551)
			(xy 169.776778 -11.086499) (xy 169.761424 -11.138793) (xy 169.738783 -11.188371) (xy 169.709318 -11.234221)
			(xy 169.673628 -11.275412) (xy 169.632439 -11.311105) (xy 169.58659 -11.340573) (xy 169.537014 -11.363216)
			(xy 169.48472 -11.378573) (xy 169.430773 -11.386333) (xy 169.403522 -11.38682) (xy 168.539922 -11.38682)
			(xy 168.512669 -11.386334) (xy 168.458717 -11.37858) (xy 168.406419 -11.363226) (xy 168.356837 -11.340586)
			(xy 168.310983 -11.311119) (xy 168.269789 -11.275427) (xy 168.234094 -11.234235) (xy 168.204625 -11.188382)
			(xy 168.181981 -11.138802) (xy 168.166625 -11.086504) (xy 168.158867 -11.032553) (xy 129.087143 -11.032553)
			(xy 129.05217 -11.077519) (xy 128.992217 -11.141629) (xy 128.926694 -11.200035) (xy 128.856141 -11.252255)
			(xy 128.781141 -11.297857) (xy 128.702313 -11.336466) (xy 128.620307 -11.367764) (xy 128.535799 -11.391491)
			(xy 128.449487 -11.407452) (xy 128.362083 -11.415515) (xy 128.274307 -11.415615) (xy 128.186885 -11.40775)
			(xy 128.100537 -11.391984) (xy 128.015975 -11.368449) (xy 127.933898 -11.337338) (xy 127.854983 -11.298908)
			(xy 127.77988 -11.253476) (xy 127.709209 -11.201416) (xy 127.643553 -11.143159) (xy 127.583455 -11.079185)
			(xy 127.556006 -11.044936) (xy 127.546188 -11.033218) (xy 127.52109 -11.015788) (xy 127.491961 -11.006557)
			(xy 127.461404 -11.006351) (xy 127.432153 -11.015187) (xy 127.406822 -11.032277) (xy 127.387675 -11.056091)
			(xy 127.381508 -11.070082) (xy 127.350183 -11.148346) (xy 127.281032 -11.30211) (xy 127.204607 -11.452392)
			(xy 127.121082 -11.598846) (xy 127.030649 -11.741138) (xy 126.933515 -11.878943) (xy 126.829902 -12.011945)
			(xy 126.81237 -12.032356) (xy 166.354411 -12.032356) (xy 166.354411 -11.977844) (xy 166.362169 -11.923886)
			(xy 166.377527 -11.871582) (xy 166.400173 -11.821995) (xy 166.429645 -11.776137) (xy 166.465343 -11.734939)
			(xy 166.506541 -11.699241) (xy 166.552401 -11.66977) (xy 166.601987 -11.647125) (xy 166.654292 -11.631768)
			(xy 166.70825 -11.624011) (xy 166.735506 -11.623548) (xy 167.599106 -11.623548) (xy 167.626354 -11.624123)
			(xy 167.680295 -11.631879) (xy 167.732583 -11.647233) (xy 167.782153 -11.669872) (xy 167.827998 -11.699335)
			(xy 167.869182 -11.735022) (xy 167.904869 -11.776207) (xy 167.934331 -11.822052) (xy 167.956969 -11.871623)
			(xy 167.972322 -11.923911) (xy 167.980078 -11.977852) (xy 167.980078 -12.032348) (xy 167.980077 -12.032358)
			(xy 169.954311 -12.032358) (xy 169.954311 -11.977842) (xy 169.96207 -11.92388) (xy 169.97743 -11.871573)
			(xy 170.000079 -11.821984) (xy 170.029555 -11.776123) (xy 170.065258 -11.734924) (xy 170.106461 -11.699226)
			(xy 170.152326 -11.669756) (xy 170.201918 -11.647114) (xy 170.254227 -11.63176) (xy 170.30819 -11.624008)
			(xy 170.335448 -11.623548) (xy 171.199048 -11.623548) (xy 171.226294 -11.624125) (xy 171.28023 -11.631887)
			(xy 171.332513 -11.647244) (xy 171.382078 -11.669885) (xy 171.427917 -11.699349) (xy 171.469097 -11.735037)
			(xy 171.504779 -11.776221) (xy 171.534238 -11.822064) (xy 171.556873 -11.871632) (xy 171.572224 -11.923917)
			(xy 171.579978 -11.977854) (xy 171.579978 -12.032346) (xy 171.572224 -12.086283) (xy 171.556873 -12.138568)
			(xy 171.534238 -12.188136) (xy 171.504779 -12.233979) (xy 171.469097 -12.275163) (xy 171.427917 -12.310851)
			(xy 171.382078 -12.340315) (xy 171.332513 -12.362956) (xy 171.28023 -12.378313) (xy 171.226294 -12.386075)
			(xy 171.199048 -12.386564) (xy 170.335448 -12.386564) (xy 170.30819 -12.386192) (xy 170.254227 -12.37844)
			(xy 170.201918 -12.363086) (xy 170.152326 -12.340444) (xy 170.106461 -12.310974) (xy 170.065258 -12.275276)
			(xy 170.029555 -12.234077) (xy 170.000079 -12.188216) (xy 169.97743 -12.138627) (xy 169.96207 -12.08632)
			(xy 169.954311 -12.032358) (xy 167.980077 -12.032358) (xy 167.972322 -12.086289) (xy 167.956969 -12.138577)
			(xy 167.934331 -12.188148) (xy 167.904869 -12.233993) (xy 167.869182 -12.275178) (xy 167.827998 -12.310865)
			(xy 167.782153 -12.340328) (xy 167.732583 -12.362967) (xy 167.680295 -12.378321) (xy 167.626354 -12.386077)
			(xy 167.599106 -12.386564) (xy 166.735506 -12.386564) (xy 166.70825 -12.386189) (xy 166.654292 -12.378432)
			(xy 166.601987 -12.363075) (xy 166.552401 -12.34043) (xy 166.506541 -12.310959) (xy 166.465343 -12.275261)
			(xy 166.429645 -12.234063) (xy 166.400173 -12.188205) (xy 166.377527 -12.138618) (xy 166.362169 -12.086314)
			(xy 166.354411 -12.032356) (xy 126.81237 -12.032356) (xy 126.720046 -12.139839) (xy 126.6042 -12.262334)
			(xy 126.482628 -12.379148) (xy 126.355609 -12.490015) (xy 126.223433 -12.59468) (xy 126.086403 -12.692904)
			(xy 125.944832 -12.784463) (xy 125.799045 -12.869146) (xy 125.649374 -12.946761) (xy 125.496164 -13.017129)
			(xy 125.339763 -13.080089) (xy 125.18053 -13.135498) (xy 125.018829 -13.183228) (xy 124.855031 -13.22317)
			(xy 124.68951 -13.255234) (xy 124.522645 -13.279345) (xy 124.354818 -13.295448) (xy 124.186413 -13.303507)
			(xy 124.102114 -13.304012) (xy 83.70189 -13.304012) (xy 83.618015 -13.303513) (xy 83.450455 -13.29553)
			(xy 83.283465 -13.279584) (xy 83.117423 -13.255711) (xy 82.952705 -13.223964) (xy 82.789684 -13.184415)
			(xy 82.628729 -13.137154) (xy 82.470206 -13.082288) (xy 82.314472 -13.019942) (xy 82.161882 -12.950256)
			(xy 82.01278 -12.873388) (xy 81.867505 -12.789514) (xy 81.726385 -12.698821) (xy 81.58974 -12.601517)
			(xy 81.45788 -12.497821) (xy 81.331103 -12.387968) (xy 81.209696 -12.272208) (xy 81.093936 -12.150802)
			(xy 80.984083 -12.024025) (xy 80.880387 -11.892165) (xy 80.783082 -11.75552) (xy 80.69239 -11.6144)
			(xy 80.608514 -11.469125) (xy 80.531647 -11.320023) (xy 80.461961 -11.167433) (xy 80.399614 -11.0117)
			(xy 80.344748 -10.853176) (xy 80.297487 -10.692222) (xy 80.257938 -10.529201) (xy 80.22619 -10.364483)
			(xy 80.202316 -10.198441) (xy 80.18637 -10.031451) (xy 80.178388 -9.863891) (xy 80.177894 -9.780016)
			(xy 80.177894 -7.056628) (xy 80.177444 -7.042873) (xy 80.170105 -7.016359) (xy 80.155951 -6.992769)
			(xy 80.136011 -6.973816) (xy 80.111734 -6.960876) (xy 80.084883 -6.95489) (xy 80.057408 -6.956292)
			(xy 80.031306 -6.964981) (xy 80.019652 -6.9723) (xy 79.982471 -6.996608) (xy 79.904443 -7.039076)
			(xy 79.822844 -7.0742) (xy 79.738364 -7.101681) (xy 79.651718 -7.121287) (xy 79.563637 -7.132854)
			(xy 79.474866 -7.136282) (xy 79.386156 -7.131543) (xy 79.298255 -7.118678) (xy 79.211908 -7.097794)
			(xy 79.127843 -7.069069) (xy 79.046771 -7.032744) (xy 78.969379 -6.989128) (xy 78.896318 -6.938589)
			(xy 78.828208 -6.881553) (xy 78.765624 -6.818504) (xy 78.709095 -6.749973) (xy 78.659098 -6.676541)
			(xy 78.616056 -6.598827) (xy 78.580333 -6.517489) (xy 78.552231 -6.433214) (xy 78.531987 -6.346714)
			(xy 78.519773 -6.25872) (xy 78.515692 -6.169977) (xy 78.519777 -6.081234) (xy 78.531996 -5.993241)
			(xy 78.552243 -5.906742) (xy 78.580349 -5.822469) (xy 78.616076 -5.741132) (xy 78.659122 -5.66342)
			(xy 78.709122 -5.58999) (xy 78.765655 -5.521462) (xy 78.828242 -5.458416) (xy 78.896355 -5.401383)
			(xy 78.969417 -5.350847) (xy 79.046812 -5.307235) (xy 79.127885 -5.270915) (xy 79.211951 -5.242193)
			(xy 79.2983 -5.221313) (xy 79.386201 -5.208452) (xy 79.474912 -5.203718) (xy 79.563683 -5.20715)
			(xy 79.651763 -5.218721) (xy 79.738408 -5.238331) (xy 79.822887 -5.265816) (xy 79.904484 -5.300944)
			(xy 79.98251 -5.343416) (xy 80.019652 -5.367782) (xy 80.031322 -5.375072) (xy 80.057422 -5.383751)
			(xy 80.084892 -5.385149) (xy 80.111738 -5.379165) (xy 80.136013 -5.366232) (xy 80.155955 -5.347288)
			(xy 80.170118 -5.32371) (xy 80.177474 -5.297206) (xy 80.177894 -5.283454) (xy 80.177894 -1.524) (xy 14.626082 -1.524)
			(xy 14.626082 -4.377182) (xy 14.626518 -4.386931) (xy 14.633798 -4.405018) (xy 14.647311 -4.419073)
			(xy 14.665097 -4.42706) (xy 14.684579 -4.427821) (xy 14.6939 -4.424934) (xy 14.708886 -4.4196) (xy 14.715236 -4.41452)
			(xy 14.738096 -4.396994) (xy 14.773063 -4.371333) (xy 14.846818 -4.325685) (xy 14.92437 -4.286834)
			(xy 15.005094 -4.255093) (xy 15.088338 -4.230718) (xy 15.173432 -4.213906) (xy 15.259691 -4.204792)
			(xy 15.34642 -4.20345) (xy 15.43292 -4.209889) (xy 15.518494 -4.224059) (xy 15.602453 -4.245845)
			(xy 15.68412 -4.275071) (xy 15.762838 -4.311503) (xy 15.837971 -4.354846) (xy 15.908916 -4.404752)
			(xy 15.975099 -4.460818) (xy 16.035989 -4.522593) (xy 16.091095 -4.589579) (xy 16.139972 -4.661236)
			(xy 16.182226 -4.736987) (xy 16.217518 -4.816222) (xy 16.245563 -4.898303) (xy 16.266136 -4.982567)
			(xy 16.267242 -4.989901) (xy 20.44038 -4.989901) (xy 20.44038 -4.935399) (xy 20.448136 -4.881452)
			(xy 20.463491 -4.829158) (xy 20.486132 -4.779581) (xy 20.515597 -4.733731) (xy 20.551288 -4.692541)
			(xy 20.592478 -4.65685) (xy 20.638328 -4.627384) (xy 20.687904 -4.604742) (xy 20.740198 -4.589387)
			(xy 20.794145 -4.58163) (xy 20.821396 -4.581144) (xy 21.684996 -4.581144) (xy 21.712249 -4.581603)
			(xy 21.766201 -4.58936) (xy 21.818499 -4.604715) (xy 21.86808 -4.627358) (xy 21.913934 -4.656826)
			(xy 21.955128 -4.69252) (xy 21.990822 -4.733713) (xy 22.02029 -4.779566) (xy 22.042933 -4.829147)
			(xy 22.05829 -4.881445) (xy 22.066047 -4.935397) (xy 22.066047 -4.989901) (xy 24.04032 -4.989901)
			(xy 24.04032 -4.935399) (xy 24.048076 -4.881452) (xy 24.063431 -4.829157) (xy 24.086072 -4.779581)
			(xy 24.115538 -4.73373) (xy 24.151229 -4.692541) (xy 24.192419 -4.656849) (xy 24.238269 -4.627383)
			(xy 24.287846 -4.604742) (xy 24.34014 -4.589387) (xy 24.394087 -4.58163) (xy 24.421338 -4.581144)
			(xy 25.284938 -4.581144) (xy 25.312191 -4.581603) (xy 25.366143 -4.58936) (xy 25.418441 -4.604716)
			(xy 25.468021 -4.627358) (xy 25.513875 -4.656827) (xy 25.555068 -4.69252) (xy 25.590762 -4.733713)
			(xy 25.620231 -4.779567) (xy 25.642873 -4.829147) (xy 25.65823 -4.881446) (xy 25.665987 -4.935397)
			(xy 25.665987 -4.989903) (xy 25.66598 -4.989954) (xy 27.64023 -4.989954) (xy 27.64023 -4.935446)
			(xy 27.647987 -4.881493) (xy 27.663343 -4.829194) (xy 27.685985 -4.779612) (xy 27.715454 -4.733756)
			(xy 27.751147 -4.692562) (xy 27.79234 -4.656866) (xy 27.838194 -4.627395) (xy 27.887775 -4.60475)
			(xy 27.940074 -4.589391) (xy 27.994026 -4.581631) (xy 28.02128 -4.581144) (xy 28.88488 -4.581144)
			(xy 28.91213 -4.581702) (xy 28.966077 -4.589456) (xy 29.01837 -4.604808) (xy 29.067947 -4.627446)
			(xy 29.113797 -4.65691) (xy 29.154986 -4.692599) (xy 29.190678 -4.733787) (xy 29.220144 -4.779636)
			(xy 29.242785 -4.829211) (xy 29.25814 -4.881504) (xy 29.265897 -4.93545) (xy 29.265897 -4.98995)
			(xy 29.265896 -4.989954) (xy 31.24043 -4.989954) (xy 31.24043 -4.935446) (xy 31.248187 -4.881494)
			(xy 31.263543 -4.829195) (xy 31.286185 -4.779613) (xy 31.315653 -4.733758) (xy 31.351346 -4.692563)
			(xy 31.392538 -4.656867) (xy 31.438392 -4.627396) (xy 31.487972 -4.604751) (xy 31.540271 -4.589392)
			(xy 31.594222 -4.581632) (xy 31.621476 -4.581144) (xy 32.485076 -4.581144) (xy 32.512327 -4.581702)
			(xy 32.566273 -4.589455) (xy 32.618567 -4.604807) (xy 32.668144 -4.627445) (xy 32.713995 -4.656909)
			(xy 32.755185 -4.692598) (xy 32.790877 -4.733786) (xy 32.820343 -4.779635) (xy 32.842985 -4.82921)
			(xy 32.85834 -4.881503) (xy 32.866097 -4.935449) (xy 32.866097 -4.989951) (xy 32.866096 -4.989958)
			(xy 40.350307 -4.989958) (xy 40.350307 -4.935442) (xy 40.358066 -4.881481) (xy 40.373426 -4.829173)
			(xy 40.396074 -4.779584) (xy 40.42555 -4.733723) (xy 40.461252 -4.692524) (xy 40.502455 -4.656826)
			(xy 40.548319 -4.627355) (xy 40.59791 -4.604712) (xy 40.65022 -4.589358) (xy 40.704182 -4.581604)
			(xy 40.73144 -4.581144) (xy 41.59504 -4.581144) (xy 41.622286 -4.581729) (xy 41.676222 -4.589489)
			(xy 41.728506 -4.604846) (xy 41.778072 -4.627486) (xy 41.823911 -4.65695) (xy 41.865091 -4.692637)
			(xy 41.900774 -4.733821) (xy 41.930233 -4.779663) (xy 41.952868 -4.829232) (xy 41.968219 -4.881517)
			(xy 41.975974 -4.935454) (xy 41.975974 -4.989946) (xy 41.975973 -4.989954) (xy 43.95033 -4.989954)
			(xy 43.95033 -4.935446) (xy 43.958087 -4.881493) (xy 43.973443 -4.829193) (xy 43.996086 -4.779611)
			(xy 44.025554 -4.733756) (xy 44.061248 -4.692561) (xy 44.102441 -4.656865) (xy 44.148295 -4.627394)
			(xy 44.197876 -4.604749) (xy 44.250176 -4.589391) (xy 44.304128 -4.581631) (xy 44.331382 -4.581144)
			(xy 45.194982 -4.581144) (xy 45.222232 -4.581702) (xy 45.276178 -4.589456) (xy 45.328472 -4.604808)
			(xy 45.378048 -4.627447) (xy 45.423898 -4.656911) (xy 45.465087 -4.6926) (xy 45.500778 -4.733788)
			(xy 45.530244 -4.779636) (xy 45.552885 -4.829211) (xy 45.56824 -4.881504) (xy 45.575997 -4.93545)
			(xy 45.575997 -4.98995) (xy 45.575996 -4.989954) (xy 51.56043 -4.989954) (xy 51.56043 -4.935446)
			(xy 51.568187 -4.881494) (xy 51.583543 -4.829195) (xy 51.606185 -4.779613) (xy 51.635653 -4.733758)
			(xy 51.671346 -4.692563) (xy 51.712538 -4.656867) (xy 51.758392 -4.627396) (xy 51.807972 -4.604751)
			(xy 51.860271 -4.589392) (xy 51.914222 -4.581632) (xy 51.941476 -4.581144) (xy 52.805076 -4.581144)
			(xy 52.832327 -4.581702) (xy 52.886273 -4.589455) (xy 52.938567 -4.604807) (xy 52.988144 -4.627445)
			(xy 53.033995 -4.656909) (xy 53.075185 -4.692598) (xy 53.110877 -4.733786) (xy 53.140343 -4.779635)
			(xy 53.162985 -4.82921) (xy 53.17834 -4.881503) (xy 53.186097 -4.935449) (xy 53.186097 -4.989951)
			(xy 53.186096 -4.989957) (xy 55.160307 -4.989957) (xy 55.160307 -4.935443) (xy 55.168065 -4.881484)
			(xy 55.183424 -4.829178) (xy 55.206071 -4.77959) (xy 55.235544 -4.73373) (xy 55.271245 -4.692532)
			(xy 55.312445 -4.656834) (xy 55.358306 -4.627362) (xy 55.407894 -4.604718) (xy 55.460201 -4.589362)
			(xy 55.514161 -4.581606) (xy 55.541418 -4.581144) (xy 56.405018 -4.581144) (xy 56.432265 -4.581727)
			(xy 56.486204 -4.589485) (xy 56.53849 -4.60484) (xy 56.588058 -4.627479) (xy 56.633901 -4.656942)
			(xy 56.675084 -4.692629) (xy 56.710769 -4.733814) (xy 56.74023 -4.779657) (xy 56.762867 -4.829227)
			(xy 56.778219 -4.881514) (xy 56.785974 -4.935453) (xy 56.785974 -4.989947) (xy 56.778219 -5.043886)
			(xy 56.762867 -5.096173) (xy 56.74023 -5.145743) (xy 56.710769 -5.191586) (xy 56.675084 -5.232771)
			(xy 56.633901 -5.268458) (xy 56.588058 -5.297921) (xy 56.53849 -5.32056) (xy 56.486204 -5.335915)
			(xy 56.432265 -5.343673) (xy 56.405018 -5.34416) (xy 55.541418 -5.34416) (xy 55.514161 -5.343794)
			(xy 55.460201 -5.336038) (xy 55.407894 -5.320682) (xy 55.358306 -5.298038) (xy 55.312445 -5.268566)
			(xy 55.271245 -5.232868) (xy 55.235544 -5.19167) (xy 55.206071 -5.14581) (xy 55.183424 -5.096222)
			(xy 55.168065 -5.043916) (xy 55.160307 -4.989957) (xy 53.186096 -4.989957) (xy 53.17834 -5.043897)
			(xy 53.162985 -5.09619) (xy 53.140343 -5.145765) (xy 53.110877 -5.191614) (xy 53.075185 -5.232802)
			(xy 53.033995 -5.268491) (xy 52.988144 -5.297955) (xy 52.938567 -5.320593) (xy 52.886273 -5.335945)
			(xy 52.832327 -5.343698) (xy 52.805076 -5.34416) (xy 51.941476 -5.34416) (xy 51.914222 -5.343768)
			(xy 51.860271 -5.336008) (xy 51.807972 -5.320649) (xy 51.758392 -5.298004) (xy 51.712538 -5.268533)
			(xy 51.671346 -5.232837) (xy 51.635653 -5.191642) (xy 51.606185 -5.145787) (xy 51.583543 -5.096205)
			(xy 51.568187 -5.043906) (xy 51.56043 -4.989954) (xy 45.575996 -4.989954) (xy 45.56824 -5.043896)
			(xy 45.552885 -5.096189) (xy 45.530244 -5.145764) (xy 45.500778 -5.191612) (xy 45.465087 -5.2328)
			(xy 45.423898 -5.268489) (xy 45.378048 -5.297953) (xy 45.328472 -5.320592) (xy 45.276178 -5.335944)
			(xy 45.222232 -5.343698) (xy 45.194982 -5.34416) (xy 44.331382 -5.34416) (xy 44.304128 -5.343769)
			(xy 44.250176 -5.336009) (xy 44.197876 -5.320651) (xy 44.148295 -5.298006) (xy 44.102441 -5.268535)
			(xy 44.061248 -5.232839) (xy 44.025554 -5.191644) (xy 43.996086 -5.145789) (xy 43.973443 -5.096207)
			(xy 43.958087 -5.043907) (xy 43.95033 -4.989954) (xy 41.975973 -4.989954) (xy 41.968219 -5.043883)
			(xy 41.952868 -5.096168) (xy 41.930233 -5.145737) (xy 41.900774 -5.191579) (xy 41.865091 -5.232763)
			(xy 41.823911 -5.26845) (xy 41.778072 -5.297914) (xy 41.728506 -5.320554) (xy 41.676222 -5.335911)
			(xy 41.622286 -5.343671) (xy 41.59504 -5.34416) (xy 40.73144 -5.34416) (xy 40.704182 -5.343796) (xy 40.65022 -5.336042)
			(xy 40.59791 -5.320688) (xy 40.548319 -5.298045) (xy 40.502455 -5.268574) (xy 40.461252 -5.232876)
			(xy 40.42555 -5.191677) (xy 40.396074 -5.145816) (xy 40.373426 -5.096227) (xy 40.358066 -5.043919)
			(xy 40.350307 -4.989958) (xy 32.866096 -4.989958) (xy 32.85834 -5.043897) (xy 32.842985 -5.09619)
			(xy 32.820343 -5.145765) (xy 32.790877 -5.191614) (xy 32.755185 -5.232802) (xy 32.713995 -5.268491)
			(xy 32.668144 -5.297955) (xy 32.618567 -5.320593) (xy 32.566273 -5.335945) (xy 32.512327 -5.343698)
			(xy 32.485076 -5.34416) (xy 31.621476 -5.34416) (xy 31.594222 -5.343768) (xy 31.540271 -5.336008)
			(xy 31.487972 -5.320649) (xy 31.438392 -5.298004) (xy 31.392538 -5.268533) (xy 31.351346 -5.232837)
			(xy 31.315653 -5.191642) (xy 31.286185 -5.145787) (xy 31.263543 -5.096205) (xy 31.248187 -5.043906)
			(xy 31.24043 -4.989954) (xy 29.265896 -4.989954) (xy 29.25814 -5.043896) (xy 29.242785 -5.096189)
			(xy 29.220144 -5.145764) (xy 29.190678 -5.191613) (xy 29.154986 -5.232801) (xy 29.113797 -5.26849)
			(xy 29.067947 -5.297954) (xy 29.01837 -5.320592) (xy 28.966077 -5.335944) (xy 28.91213 -5.343698)
			(xy 28.88488 -5.34416) (xy 28.02128 -5.34416) (xy 27.994026 -5.343769) (xy 27.940074 -5.336009) (xy 27.887775 -5.32065)
			(xy 27.838194 -5.298005) (xy 27.79234 -5.268534) (xy 27.751147 -5.232838) (xy 27.715454 -5.191644)
			(xy 27.685985 -5.145788) (xy 27.663343 -5.096206) (xy 27.647987 -5.043907) (xy 27.64023 -4.989954)
			(xy 25.66598 -4.989954) (xy 25.65823 -5.043854) (xy 25.642873 -5.096153) (xy 25.620231 -5.145733)
			(xy 25.590762 -5.191587) (xy 25.555068 -5.23278) (xy 25.513875 -5.268473) (xy 25.468021 -5.297942)
			(xy 25.418441 -5.320584) (xy 25.366143 -5.33594) (xy 25.312191 -5.343697) (xy 25.284938 -5.34416)
			(xy 24.421338 -5.34416) (xy 24.394087 -5.34367) (xy 24.34014 -5.335913) (xy 24.287846 -5.320558)
			(xy 24.238269 -5.297917) (xy 24.192419 -5.268451) (xy 24.151229 -5.232759) (xy 24.115538 -5.19157)
			(xy 24.086072 -5.145719) (xy 24.063431 -5.096143) (xy 24.048076 -5.043848) (xy 24.04032 -4.989901)
			(xy 22.066047 -4.989901) (xy 22.066047 -4.989903) (xy 22.05829 -5.043855) (xy 22.042933 -5.096153)
			(xy 22.02029 -5.145734) (xy 21.990822 -5.191587) (xy 21.955128 -5.23278) (xy 21.913934 -5.268474)
			(xy 21.86808 -5.297942) (xy 21.818499 -5.320585) (xy 21.766201 -5.33594) (xy 21.712249 -5.343697)
			(xy 21.684996 -5.34416) (xy 20.821396 -5.34416) (xy 20.794145 -5.34367) (xy 20.740198 -5.335913)
			(xy 20.687904 -5.320558) (xy 20.638328 -5.297916) (xy 20.592478 -5.26845) (xy 20.551288 -5.232759)
			(xy 20.515597 -5.191569) (xy 20.486132 -5.145719) (xy 20.463491 -5.096142) (xy 20.448136 -5.043848)
			(xy 20.44038 -4.989901) (xy 16.267242 -4.989901) (xy 16.279069 -5.068337) (xy 16.28426 -5.154921)
			(xy 16.281666 -5.241621) (xy 16.271308 -5.32774) (xy 16.25327 -5.412583) (xy 16.227697 -5.495466)
			(xy 16.194795 -5.575723) (xy 16.154829 -5.652707) (xy 16.108121 -5.725796) (xy 16.055047 -5.794403)
			(xy 15.996036 -5.857975) (xy 15.931562 -5.915999) (xy 15.897098 -5.94233) (xy 15.862919 -5.967431)
			(xy 15.790907 -6.012223) (xy 15.715244 -6.050528) (xy 15.636514 -6.08205) (xy 15.555322 -6.106547)
			(xy 15.472296 -6.12383) (xy 15.388073 -6.133766) (xy 15.303304 -6.136278) (xy 15.218641 -6.131346)
			(xy 15.134737 -6.11901) (xy 15.052238 -6.099363) (xy 14.971779 -6.072558) (xy 14.893981 -6.0388)
			(xy 14.819443 -5.998351) (xy 14.783816 -5.97535) (xy 14.772146 -5.96815) (xy 14.746092 -5.959633)
			(xy 14.718712 -5.958358) (xy 14.69198 -5.964418) (xy 14.667825 -5.977375) (xy 14.647991 -5.996294)
			(xy 14.633909 -6.019811) (xy 14.626595 -6.046227) (xy 14.626082 -6.059932) (xy 14.626082 -6.751654)
			(xy 18.635651 -6.751654) (xy 18.635651 -6.697146) (xy 18.643409 -6.643192) (xy 18.658767 -6.590891)
			(xy 18.681411 -6.541309) (xy 18.710882 -6.495454) (xy 18.746579 -6.45426) (xy 18.787775 -6.418566)
			(xy 18.833632 -6.389099) (xy 18.883216 -6.366458) (xy 18.935517 -6.351104) (xy 18.989472 -6.34335)
			(xy 19.016726 -6.342888) (xy 19.880326 -6.342888) (xy 19.907576 -6.343384) (xy 19.96152 -6.351143)
			(xy 20.013811 -6.3665) (xy 20.063385 -6.389143) (xy 20.109231 -6.418609) (xy 20.150418 -6.4543) (xy 20.186106 -6.49549)
			(xy 20.21557 -6.541338) (xy 20.238209 -6.590913) (xy 20.253563 -6.643205) (xy 20.261318 -6.69715)
			(xy 20.261318 -6.75165) (xy 22.235674 -6.75165) (xy 22.235674 -6.69715) (xy 22.243429 -6.643204)
			(xy 22.258783 -6.590912) (xy 22.281422 -6.541336) (xy 22.310886 -6.495487) (xy 22.346574 -6.454297)
			(xy 22.387761 -6.418605) (xy 22.433608 -6.389138) (xy 22.483182 -6.366494) (xy 22.535473 -6.351136)
			(xy 22.589418 -6.343376) (xy 22.616668 -6.342888) (xy 23.480268 -6.342888) (xy 23.507522 -6.343357)
			(xy 23.561476 -6.35111) (xy 23.613777 -6.366463) (xy 23.663361 -6.389104) (xy 23.709217 -6.418571)
			(xy 23.750413 -6.454264) (xy 23.78611 -6.495457) (xy 23.815581 -6.541311) (xy 23.838225 -6.590893)
			(xy 23.853583 -6.643193) (xy 23.861341 -6.697146) (xy 23.861341 -6.751654) (xy 25.835551 -6.751654)
			(xy 25.835551 -6.697146) (xy 25.843309 -6.643194) (xy 25.858665 -6.590895) (xy 25.881309 -6.541314)
			(xy 25.910778 -6.495459) (xy 25.946473 -6.454266) (xy 25.987667 -6.418572) (xy 26.033522 -6.389104)
			(xy 26.083104 -6.366462) (xy 26.135404 -6.351107) (xy 26.189356 -6.343351) (xy 26.21661 -6.342888)
			(xy 27.08021 -6.342888) (xy 27.10746 -6.343382) (xy 27.161407 -6.35114) (xy 27.2137 -6.366496) (xy 27.263275 -6.389137)
			(xy 27.309124 -6.418604) (xy 27.350312 -6.454295) (xy 27.386002 -6.495484) (xy 27.415467 -6.541334)
			(xy 27.438108 -6.59091) (xy 27.453462 -6.643203) (xy 27.461218 -6.697149) (xy 27.461218 -6.751651)
			(xy 27.461218 -6.751653) (xy 29.435751 -6.751653) (xy 29.435751 -6.697147) (xy 29.443509 -6.643195)
			(xy 29.458865 -6.590896) (xy 29.481508 -6.541315) (xy 29.510977 -6.495461) (xy 29.546672 -6.454268)
			(xy 29.587866 -6.418574) (xy 29.63372 -6.389105) (xy 29.683301 -6.366463) (xy 29.7356 -6.351107)
			(xy 29.789553 -6.343351) (xy 29.816806 -6.342888) (xy 30.680406 -6.342888) (xy 30.707657 -6.343382)
			(xy 30.761603 -6.351139) (xy 30.813897 -6.366495) (xy 30.863473 -6.389136) (xy 30.909322 -6.418602)
			(xy 30.950511 -6.454293) (xy 30.986201 -6.495483) (xy 31.015667 -6.541333) (xy 31.038307 -6.590909)
			(xy 31.053662 -6.643203) (xy 31.061418 -6.697149) (xy 31.061418 -6.75165) (xy 38.545774 -6.75165)
			(xy 38.545774 -6.69715) (xy 38.55353 -6.643204) (xy 38.568883 -6.590911) (xy 38.591522 -6.541336)
			(xy 38.620986 -6.495486) (xy 38.656675 -6.454296) (xy 38.697862 -6.418604) (xy 38.743709 -6.389137)
			(xy 38.793283 -6.366494) (xy 38.845575 -6.351136) (xy 38.89952 -6.343376) (xy 38.92677 -6.342888)
			(xy 39.79037 -6.342888) (xy 39.817624 -6.343357) (xy 39.871578 -6.351111) (xy 39.923878 -6.366464)
			(xy 39.973462 -6.389105) (xy 40.019318 -6.418571) (xy 40.060514 -6.454265) (xy 40.096211 -6.495458)
			(xy 40.125681 -6.541312) (xy 40.148326 -6.590893) (xy 40.163683 -6.643193) (xy 40.171441 -6.697146)
			(xy 40.171441 -6.751654) (xy 42.145651 -6.751654) (xy 42.145651 -6.697146) (xy 42.153409 -6.643194)
			(xy 42.168766 -6.590894) (xy 42.191409 -6.541313) (xy 42.220879 -6.495459) (xy 42.256574 -6.454265)
			(xy 42.297768 -6.418571) (xy 42.343624 -6.389103) (xy 42.393206 -6.366461) (xy 42.445506 -6.351106)
			(xy 42.499458 -6.343351) (xy 42.526712 -6.342888) (xy 43.390312 -6.342888) (xy 43.417562 -6.343383)
			(xy 43.471508 -6.35114) (xy 43.523801 -6.366496) (xy 43.573376 -6.389138) (xy 43.619225 -6.418604)
			(xy 43.660413 -6.454295) (xy 43.696103 -6.495485) (xy 43.725568 -6.541334) (xy 43.748208 -6.59091)
			(xy 43.763562 -6.643203) (xy 43.771318 -6.69715) (xy 43.771318 -6.75165) (xy 43.771318 -6.751653)
			(xy 49.755751 -6.751653) (xy 49.755751 -6.697147) (xy 49.763509 -6.643195) (xy 49.778865 -6.590896)
			(xy 49.801508 -6.541315) (xy 49.830977 -6.495461) (xy 49.866672 -6.454268) (xy 49.907866 -6.418574)
			(xy 49.95372 -6.389105) (xy 50.003301 -6.366463) (xy 50.0556 -6.351107) (xy 50.109553 -6.343351)
			(xy 50.136806 -6.342888) (xy 51.000406 -6.342888) (xy 51.027657 -6.343382) (xy 51.081603 -6.351139)
			(xy 51.133897 -6.366495) (xy 51.183473 -6.389136) (xy 51.229322 -6.418602) (xy 51.270511 -6.454293)
			(xy 51.306201 -6.495483) (xy 51.335667 -6.541333) (xy 51.358307 -6.590909) (xy 51.373662 -6.643203)
			(xy 51.381418 -6.697149) (xy 51.381418 -6.751651) (xy 51.381417 -6.751655) (xy 53.355652 -6.751655)
			(xy 53.355652 -6.697145) (xy 53.36341 -6.643189) (xy 53.378768 -6.590887) (xy 53.401415 -6.541303)
			(xy 53.430887 -6.495447) (xy 53.466587 -6.454253) (xy 53.507785 -6.418559) (xy 53.553645 -6.389092)
			(xy 53.603232 -6.366452) (xy 53.655536 -6.3511) (xy 53.709493 -6.343348) (xy 53.736748 -6.342888)
			(xy 54.600348 -6.342888) (xy 54.627597 -6.343385) (xy 54.681539 -6.351147) (xy 54.733827 -6.366506)
			(xy 54.783398 -6.38915) (xy 54.829242 -6.418617) (xy 54.870426 -6.454308) (xy 54.906112 -6.495497)
			(xy 54.935573 -6.541344) (xy 54.958211 -6.590918) (xy 54.973563 -6.643208) (xy 54.981318 -6.697151)
			(xy 54.981318 -6.751649) (xy 54.981318 -6.751651) (xy 56.955674 -6.751651) (xy 56.955674 -6.697149)
			(xy 56.96343 -6.643201) (xy 56.978785 -6.590907) (xy 57.001426 -6.54133) (xy 57.030891 -6.49548)
			(xy 57.066582 -6.454289) (xy 57.107771 -6.418597) (xy 57.153621 -6.38913) (xy 57.203198 -6.366488)
			(xy 57.255492 -6.351132) (xy 57.309439 -6.343374) (xy 57.33669 -6.342888) (xy 58.20029 -6.342888)
			(xy 58.227543 -6.343359) (xy 58.281494 -6.351114) (xy 58.333793 -6.366469) (xy 58.383374 -6.389111)
			(xy 58.429228 -6.418578) (xy 58.470421 -6.454272) (xy 58.506116 -6.495464) (xy 58.535584 -6.541317)
			(xy 58.558227 -6.590898) (xy 58.573583 -6.643196) (xy 58.581341 -6.697147) (xy 58.581341 -6.751651)
			(xy 70.950574 -6.751651) (xy 70.950574 -6.697149) (xy 70.95833 -6.643203) (xy 70.973684 -6.590909)
			(xy 70.996324 -6.541332) (xy 71.025789 -6.495482) (xy 71.061479 -6.454292) (xy 71.102668 -6.4186)
			(xy 71.148516 -6.389133) (xy 71.198092 -6.366491) (xy 71.250385 -6.351134) (xy 71.304331 -6.343375)
			(xy 71.331582 -6.342888) (xy 72.195182 -6.342888) (xy 72.222435 -6.343358) (xy 72.276388 -6.351113)
			(xy 72.328687 -6.366467) (xy 72.378269 -6.389108) (xy 72.424124 -6.418576) (xy 72.465318 -6.454269)
			(xy 72.501014 -6.495462) (xy 72.530483 -6.541315) (xy 72.553126 -6.590896) (xy 72.568483 -6.643195)
			(xy 72.576241 -6.697147) (xy 72.576241 -6.751653) (xy 72.568483 -6.805605) (xy 72.553126 -6.857904)
			(xy 72.530483 -6.907485) (xy 72.501014 -6.953338) (xy 72.465318 -6.994531) (xy 72.424124 -7.030224)
			(xy 72.378269 -7.059692) (xy 72.328687 -7.082333) (xy 72.276388 -7.097687) (xy 72.222435 -7.105442)
			(xy 72.195182 -7.105904) (xy 71.331582 -7.105904) (xy 71.304331 -7.105425) (xy 71.250385 -7.097666)
			(xy 71.198092 -7.082309) (xy 71.148516 -7.059667) (xy 71.102668 -7.0302) (xy 71.061479 -6.994508)
			(xy 71.025789 -6.953318) (xy 70.996324 -6.907468) (xy 70.973684 -6.857891) (xy 70.95833 -6.805597)
			(xy 70.950574 -6.751651) (xy 58.581341 -6.751651) (xy 58.581341 -6.751653) (xy 58.573583 -6.805604)
			(xy 58.558227 -6.857902) (xy 58.535584 -6.907483) (xy 58.506116 -6.953336) (xy 58.470421 -6.994528)
			(xy 58.429228 -7.030222) (xy 58.383374 -7.059689) (xy 58.333793 -7.082331) (xy 58.281494 -7.097686)
			(xy 58.227543 -7.105441) (xy 58.20029 -7.105904) (xy 57.33669 -7.105904) (xy 57.309439 -7.105426)
			(xy 57.255492 -7.097668) (xy 57.203198 -7.082312) (xy 57.153621 -7.05967) (xy 57.107771 -7.030203)
			(xy 57.066582 -6.994511) (xy 57.030891 -6.95332) (xy 57.001426 -6.90747) (xy 56.978785 -6.857893)
			(xy 56.96343 -6.805599) (xy 56.955674 -6.751651) (xy 54.981318 -6.751651) (xy 54.973563 -6.805592)
			(xy 54.958211 -6.857882) (xy 54.935573 -6.907456) (xy 54.906112 -6.953303) (xy 54.870426 -6.994492)
			(xy 54.829242 -7.030183) (xy 54.783398 -7.05965) (xy 54.733827 -7.082294) (xy 54.681539 -7.097653)
			(xy 54.627597 -7.105415) (xy 54.600348 -7.105904) (xy 53.736748 -7.105904) (xy 53.709493 -7.105452)
			(xy 53.655536 -7.0977) (xy 53.603232 -7.082348) (xy 53.553645 -7.059708) (xy 53.507785 -7.030241)
			(xy 53.466587 -6.994547) (xy 53.430887 -6.953353) (xy 53.401415 -6.907497) (xy 53.378768 -6.857913)
			(xy 53.36341 -6.805611) (xy 53.355652 -6.751655) (xy 51.381417 -6.751655) (xy 51.373662 -6.805597)
			(xy 51.358307 -6.857891) (xy 51.335667 -6.907467) (xy 51.306201 -6.953317) (xy 51.270511 -6.994507)
			(xy 51.229322 -7.030198) (xy 51.183473 -7.059664) (xy 51.133897 -7.082305) (xy 51.081603 -7.097661)
			(xy 51.027657 -7.105418) (xy 51.000406 -7.105904) (xy 50.136806 -7.105904) (xy 50.109553 -7.105449)
			(xy 50.0556 -7.097693) (xy 50.003301 -7.082337) (xy 49.95372 -7.059695) (xy 49.907866 -7.030226)
			(xy 49.866672 -6.994532) (xy 49.830977 -6.953339) (xy 49.801508 -6.907485) (xy 49.778865 -6.857904)
			(xy 49.763509 -6.805605) (xy 49.755751 -6.751653) (xy 43.771318 -6.751653) (xy 43.763562 -6.805597)
			(xy 43.748208 -6.85789) (xy 43.725568 -6.907466) (xy 43.696103 -6.953315) (xy 43.660413 -6.994505)
			(xy 43.619225 -7.030196) (xy 43.573376 -7.059662) (xy 43.523801 -7.082304) (xy 43.471508 -7.09766)
			(xy 43.417562 -7.105417) (xy 43.390312 -7.105904) (xy 42.526712 -7.105904) (xy 42.499458 -7.105449)
			(xy 42.445506 -7.097694) (xy 42.393206 -7.082339) (xy 42.343624 -7.059697) (xy 42.297768 -7.030229)
			(xy 42.256574 -6.994535) (xy 42.220879 -6.953341) (xy 42.191409 -6.907487) (xy 42.168766 -6.857906)
			(xy 42.153409 -6.805606) (xy 42.145651 -6.751654) (xy 40.171441 -6.751654) (xy 40.163683 -6.805607)
			(xy 40.148326 -6.857907) (xy 40.125681 -6.907488) (xy 40.096211 -6.953342) (xy 40.060514 -6.994535)
			(xy 40.019318 -7.030229) (xy 39.973462 -7.059695) (xy 39.923878 -7.082336) (xy 39.871578 -7.097689)
			(xy 39.817624 -7.105443) (xy 39.79037 -7.105904) (xy 38.92677 -7.105904) (xy 38.89952 -7.105424)
			(xy 38.845575 -7.097664) (xy 38.793283 -7.082306) (xy 38.743709 -7.059663) (xy 38.697862 -7.030196)
			(xy 38.656675 -6.994504) (xy 38.620986 -6.953314) (xy 38.591522 -6.907464) (xy 38.568883 -6.857889)
			(xy 38.55353 -6.805596) (xy 38.545774 -6.75165) (xy 31.061418 -6.75165) (xy 31.061418 -6.751651)
			(xy 31.053662 -6.805597) (xy 31.038307 -6.857891) (xy 31.015667 -6.907467) (xy 30.986201 -6.953317)
			(xy 30.950511 -6.994507) (xy 30.909322 -7.030198) (xy 30.863473 -7.059664) (xy 30.813897 -7.082305)
			(xy 30.761603 -7.097661) (xy 30.707657 -7.105418) (xy 30.680406 -7.105904) (xy 29.816806 -7.105904)
			(xy 29.789553 -7.105449) (xy 29.7356 -7.097693) (xy 29.683301 -7.082337) (xy 29.63372 -7.059695)
			(xy 29.587866 -7.030226) (xy 29.546672 -6.994532) (xy 29.510977 -6.953339) (xy 29.481508 -6.907485)
			(xy 29.458865 -6.857904) (xy 29.443509 -6.805605) (xy 29.435751 -6.751653) (xy 27.461218 -6.751653)
			(xy 27.453462 -6.805597) (xy 27.438108 -6.85789) (xy 27.415467 -6.907466) (xy 27.386002 -6.953316)
			(xy 27.350312 -6.994505) (xy 27.309124 -7.030196) (xy 27.263275 -7.059663) (xy 27.2137 -7.082304)
			(xy 27.161407 -7.09766) (xy 27.10746 -7.105418) (xy 27.08021 -7.105904) (xy 26.21661 -7.105904) (xy 26.189356 -7.105449)
			(xy 26.135404 -7.097693) (xy 26.083104 -7.082338) (xy 26.033522 -7.059696) (xy 25.987667 -7.030228)
			(xy 25.946473 -6.994534) (xy 25.910778 -6.953341) (xy 25.881309 -6.907486) (xy 25.858665 -6.857905)
			(xy 25.843309 -6.805606) (xy 25.835551 -6.751654) (xy 23.861341 -6.751654) (xy 23.853583 -6.805607)
			(xy 23.838225 -6.857907) (xy 23.815581 -6.907489) (xy 23.78611 -6.953343) (xy 23.750413 -6.994536)
			(xy 23.709217 -7.030229) (xy 23.663361 -7.059696) (xy 23.613777 -7.082337) (xy 23.561476 -7.09769)
			(xy 23.507522 -7.105443) (xy 23.480268 -7.105904) (xy 22.616668 -7.105904) (xy 22.589418 -7.105424)
			(xy 22.535473 -7.097664) (xy 22.483182 -7.082306) (xy 22.433608 -7.059662) (xy 22.387761 -7.030195)
			(xy 22.346574 -6.994503) (xy 22.310886 -6.953313) (xy 22.281422 -6.907464) (xy 22.258783 -6.857888)
			(xy 22.243429 -6.805596) (xy 22.235674 -6.75165) (xy 20.261318 -6.75165) (xy 20.253563 -6.805595)
			(xy 20.238209 -6.857887) (xy 20.21557 -6.907462) (xy 20.186106 -6.95331) (xy 20.150418 -6.9945) (xy 20.109231 -7.030191)
			(xy 20.063385 -7.059657) (xy 20.013811 -7.0823) (xy 19.96152 -7.097657) (xy 19.907576 -7.105416)
			(xy 19.880326 -7.105904) (xy 19.016726 -7.105904) (xy 18.989472 -7.10545) (xy 18.935517 -7.097696)
			(xy 18.883216 -7.082342) (xy 18.833632 -7.059701) (xy 18.787775 -7.030234) (xy 18.746579 -6.99454)
			(xy 18.710882 -6.953346) (xy 18.681411 -6.907491) (xy 18.658767 -6.857909) (xy 18.643409 -6.805608)
			(xy 18.635651 -6.751654) (xy 14.626082 -6.751654) (xy 14.626082 -9.780016) (xy 14.625583 -9.863891)
			(xy 14.617601 -10.03145) (xy 14.601655 -10.198441) (xy 14.577781 -10.364483) (xy 14.546034 -10.529201)
			(xy 14.506486 -10.692222) (xy 14.459225 -10.853176) (xy 14.404359 -11.0117) (xy 14.342013 -11.167433)
			(xy 14.272327 -11.320024) (xy 14.195459 -11.469125) (xy 14.111585 -11.614401) (xy 14.020892 -11.755521)
			(xy 13.923588 -11.892166) (xy 13.819892 -12.024026) (xy 13.710039 -12.150802) (xy 13.594279 -12.272209)
			(xy 13.472872 -12.387969) (xy 13.346096 -12.497822) (xy 13.214236 -12.601518) (xy 13.077591 -12.698822)
			(xy 12.936471 -12.789515) (xy 12.791195 -12.873389) (xy 12.756354 -12.891351) (xy 56.954662 -12.891351)
			(xy 56.954662 -12.836849) (xy 56.962418 -12.782901) (xy 56.977772 -12.730606) (xy 57.000413 -12.681029)
			(xy 57.029878 -12.635178) (xy 57.065568 -12.593986) (xy 57.106757 -12.558293) (xy 57.152606 -12.528825)
			(xy 57.202182 -12.506181) (xy 57.254476 -12.490823) (xy 57.308423 -12.483064) (xy 57.335674 -12.482576)
			(xy 58.199274 -12.482576) (xy 58.226527 -12.48307) (xy 58.280478 -12.490823) (xy 58.332777 -12.506176)
			(xy 58.382358 -12.528816) (xy 58.428213 -12.558282) (xy 58.469407 -12.593975) (xy 58.505102 -12.635166)
			(xy 58.534571 -12.681019) (xy 58.557215 -12.730598) (xy 58.572571 -12.782896) (xy 58.580329 -12.836847)
			(xy 58.580329 -12.891353) (xy 58.580329 -12.891355) (xy 70.949739 -12.891355) (xy 70.949739 -12.836845)
			(xy 70.957497 -12.78289) (xy 70.972854 -12.730588) (xy 70.995499 -12.681005) (xy 71.024971 -12.635149)
			(xy 71.060668 -12.593954) (xy 71.101865 -12.558259) (xy 71.147722 -12.52879) (xy 71.197307 -12.506147)
			(xy 71.24961 -12.490793) (xy 71.303565 -12.483038) (xy 71.33082 -12.482576) (xy 72.19442 -12.482576)
			(xy 72.221669 -12.483096) (xy 72.275612 -12.490854) (xy 72.327902 -12.50621) (xy 72.377475 -12.528852)
			(xy 72.423321 -12.558317) (xy 72.464507 -12.594007) (xy 72.500195 -12.635195) (xy 72.529658 -12.681043)
			(xy 72.552297 -12.730616) (xy 72.56765 -12.782907) (xy 72.575406 -12.836851) (xy 72.575406 -12.891349)
			(xy 72.56765 -12.945293) (xy 72.552297 -12.997584) (xy 72.529658 -13.047157) (xy 72.500195 -13.093005)
			(xy 72.464507 -13.134193) (xy 72.423321 -13.169883) (xy 72.377475 -13.199348) (xy 72.327902 -13.22199)
			(xy 72.275612 -13.237346) (xy 72.221669 -13.245104) (xy 72.19442 -13.245592) (xy 71.33082 -13.245592)
			(xy 71.303565 -13.245162) (xy 71.24961 -13.237407) (xy 71.197307 -13.222053) (xy 71.147722 -13.19941)
			(xy 71.101865 -13.169941) (xy 71.060668 -13.134246) (xy 71.024971 -13.093051) (xy 70.995499 -13.047195)
			(xy 70.972854 -12.997612) (xy 70.957497 -12.94531) (xy 70.949739 -12.891355) (xy 58.580329 -12.891355)
			(xy 58.572571 -12.945304) (xy 58.557215 -12.997602) (xy 58.534571 -13.047181) (xy 58.505102 -13.093034)
			(xy 58.469407 -13.134225) (xy 58.428213 -13.169918) (xy 58.382358 -13.199384) (xy 58.332777 -13.222024)
			(xy 58.280478 -13.237377) (xy 58.226527 -13.24513) (xy 58.199274 -13.245592) (xy 57.335674 -13.245592)
			(xy 57.308423 -13.245136) (xy 57.254476 -13.237377) (xy 57.202182 -13.222019) (xy 57.152606 -13.199375)
			(xy 57.106757 -13.169907) (xy 57.065568 -13.134214) (xy 57.029878 -13.093022) (xy 57.000413 -13.047171)
			(xy 56.977772 -12.997594) (xy 56.962418 -12.945299) (xy 56.954662 -12.891351) (xy 12.756354 -12.891351)
			(xy 12.642094 -12.950257) (xy 12.489503 -13.019943) (xy 12.33377 -13.082289) (xy 12.175246 -13.137155)
			(xy 12.014292 -13.184416) (xy 11.851271 -13.223964) (xy 11.686553 -13.255711) (xy 11.520511 -13.279585)
			(xy 11.35352 -13.295531) (xy 11.185961 -13.303513) (xy 11.102086 -13.304012) (xy 1.999996 -13.304012)
			(xy 1.96883 -13.3045) (xy 1.907031 -13.312637) (xy 1.846823 -13.32877) (xy 1.789236 -13.352624) (xy 1.735255 -13.383791)
			(xy 1.685804 -13.421737) (xy 1.641729 -13.465813) (xy 1.603784 -13.515265) (xy 1.572619 -13.569247)
			(xy 1.548766 -13.626834) (xy 1.532634 -13.687043) (xy 1.524499 -13.748842) (xy 1.524 -13.780008)
			(xy 1.524 -15.222054) (xy 135.233343 -15.222054) (xy 135.233343 -15.167546) (xy 135.2411 -15.113592)
			(xy 135.256457 -15.061292) (xy 135.279101 -15.011709) (xy 135.308571 -14.965854) (xy 135.344267 -14.92466)
			(xy 135.385462 -14.888965) (xy 135.431318 -14.859497) (xy 135.480901 -14.836854) (xy 135.533202 -14.821498)
			(xy 135.587156 -14.813742) (xy 135.61441 -14.81328) (xy 136.47801 -14.81328) (xy 136.50526 -14.813791)
			(xy 136.559205 -14.821548) (xy 136.611497 -14.836904) (xy 136.661071 -14.859545) (xy 136.706919 -14.88901)
			(xy 136.748106 -14.924701) (xy 136.783796 -14.965889) (xy 136.81326 -15.011738) (xy 136.8359 -15.061313)
			(xy 136.851254 -15.113605) (xy 136.85901 -15.16755) (xy 136.85901 -15.22205) (xy 136.851254 -15.275995)
			(xy 136.8359 -15.328287) (xy 136.81326 -15.377862) (xy 136.783796 -15.423711) (xy 136.748106 -15.464899)
			(xy 136.706919 -15.50059) (xy 136.661071 -15.530055) (xy 136.611497 -15.552696) (xy 136.559205 -15.568052)
			(xy 136.50526 -15.575809) (xy 136.47801 -15.576296) (xy 135.61441 -15.576296) (xy 135.587156 -15.575858)
			(xy 135.533202 -15.568102) (xy 135.480901 -15.552746) (xy 135.431318 -15.530103) (xy 135.385462 -15.500635)
			(xy 135.344267 -15.46494) (xy 135.308571 -15.423746) (xy 135.279101 -15.377891) (xy 135.256457 -15.328308)
			(xy 135.2411 -15.276008) (xy 135.233343 -15.222054) (xy 1.524 -15.222054) (xy 1.524 -22.29993) (xy 1.728222 -22.29993)
			(xy 1.732236 -22.094246) (xy 1.744272 -21.888876) (xy 1.764311 -21.684132) (xy 1.792324 -21.480325)
			(xy 1.828267 -21.277766) (xy 1.872086 -21.076764) (xy 1.923713 -20.877625) (xy 1.983071 -20.680652)
			(xy 2.050069 -20.486144) (xy 2.124605 -20.294399) (xy 2.206565 -20.105708) (xy 2.295825 -19.920358)
			(xy 2.392248 -19.738632) (xy 2.495689 -19.560806) (xy 2.605988 -19.387152) (xy 2.722979 -19.217933)
			(xy 2.846483 -19.053407) (xy 2.976312 -18.893826) (xy 3.112269 -18.739431) (xy 3.254146 -18.590459)
			(xy 3.401727 -18.447135) (xy 3.554788 -18.309679) (xy 3.713095 -18.178299) (xy 3.876408 -18.053196)
			(xy 4.044477 -17.934559) (xy 4.217047 -17.822571) (xy 4.393855 -17.7174) (xy 4.574632 -17.619209)
			(xy 4.759102 -17.528145) (xy 4.946984 -17.444348) (xy 5.137994 -17.367945) (xy 5.331838 -17.299052)
			(xy 5.528223 -17.237775) (xy 5.726849 -17.184207) (xy 5.927414 -17.13843) (xy 6.129612 -17.100512)
			(xy 6.333136 -17.070513) (xy 6.537675 -17.048476) (xy 6.742918 -17.034437) (xy 6.948553 -17.028417)
			(xy 7.154266 -17.030424) (xy 7.359744 -17.040456) (xy 7.564674 -17.058497) (xy 7.768744 -17.08452)
			(xy 7.971644 -17.118485) (xy 8.173064 -17.16034) (xy 8.372697 -17.210022) (xy 8.57024 -17.267456)
			(xy 8.765392 -17.332553) (xy 8.957856 -17.405214) (xy 9.147338 -17.48533) (xy 9.333549 -17.572777)
			(xy 9.462533 -17.639611) (xy 15.152858 -17.639611) (xy 15.152858 -17.585109) (xy 15.160614 -17.531161)
			(xy 15.175969 -17.478867) (xy 15.19861 -17.42929) (xy 15.228076 -17.383439) (xy 15.263768 -17.342249)
			(xy 15.304958 -17.306558) (xy 15.350808 -17.277091) (xy 15.400385 -17.25445) (xy 15.452679 -17.239095)
			(xy 15.506627 -17.231338) (xy 15.533878 -17.230852) (xy 16.397478 -17.230852) (xy 16.424731 -17.231315)
			(xy 16.478682 -17.239072) (xy 16.53098 -17.254428) (xy 16.580561 -17.27707) (xy 16.626414 -17.306538)
			(xy 16.667607 -17.342232) (xy 16.703301 -17.383424) (xy 16.732769 -17.429278) (xy 16.755412 -17.478858)
			(xy 16.770768 -17.531156) (xy 16.778525 -17.585107) (xy 16.778525 -17.639611) (xy 20.740858 -17.639611)
			(xy 20.740858 -17.585109) (xy 20.748614 -17.531161) (xy 20.763969 -17.478867) (xy 20.78661 -17.42929)
			(xy 20.816076 -17.383439) (xy 20.851768 -17.342249) (xy 20.892958 -17.306558) (xy 20.938808 -17.277091)
			(xy 20.988385 -17.25445) (xy 21.040679 -17.239095) (xy 21.094627 -17.231338) (xy 21.121878 -17.230852)
			(xy 21.985478 -17.230852) (xy 22.012729 -17.231394) (xy 22.066677 -17.239147) (xy 22.118972 -17.2545)
			(xy 22.168549 -17.277139) (xy 22.2144 -17.306603) (xy 22.255591 -17.342293) (xy 22.291284 -17.383482)
			(xy 22.320751 -17.429331) (xy 22.343392 -17.478908) (xy 22.358748 -17.531202) (xy 22.366505 -17.585149)
			(xy 22.366505 -17.639651) (xy 22.366505 -17.639653) (xy 26.328838 -17.639653) (xy 26.328838 -17.585147)
			(xy 26.336595 -17.531195) (xy 26.35195 -17.478897) (xy 26.374592 -17.429316) (xy 26.404059 -17.383462)
			(xy 26.439752 -17.342268) (xy 26.480944 -17.306573) (xy 26.526797 -17.277103) (xy 26.576376 -17.254458)
			(xy 26.628674 -17.239099) (xy 26.682625 -17.231339) (xy 26.709878 -17.230852) (xy 27.573478 -17.230852)
			(xy 27.600729 -17.231394) (xy 27.654677 -17.239147) (xy 27.706972 -17.2545) (xy 27.756549 -17.277139)
			(xy 27.8024 -17.306603) (xy 27.843591 -17.342293) (xy 27.879284 -17.383482) (xy 27.908751 -17.429331)
			(xy 27.931392 -17.478908) (xy 27.946748 -17.531202) (xy 27.954505 -17.585149) (xy 27.954505 -17.639651)
			(xy 27.954505 -17.639653) (xy 31.916838 -17.639653) (xy 31.916838 -17.585147) (xy 31.924595 -17.531195)
			(xy 31.93995 -17.478897) (xy 31.962592 -17.429316) (xy 31.992059 -17.383462) (xy 32.027752 -17.342268)
			(xy 32.068944 -17.306573) (xy 32.114797 -17.277103) (xy 32.164376 -17.254458) (xy 32.216674 -17.239099)
			(xy 32.270625 -17.231339) (xy 32.297878 -17.230852) (xy 33.161478 -17.230852) (xy 33.188729 -17.231394)
			(xy 33.242677 -17.239147) (xy 33.294972 -17.2545) (xy 33.344549 -17.277139) (xy 33.3904 -17.306603)
			(xy 33.431591 -17.342293) (xy 33.467284 -17.383482) (xy 33.496751 -17.429331) (xy 33.519392 -17.478908)
			(xy 33.534748 -17.531202) (xy 33.542505 -17.585149) (xy 33.542505 -17.639651) (xy 33.542505 -17.639653)
			(xy 37.504838 -17.639653) (xy 37.504838 -17.585147) (xy 37.512595 -17.531195) (xy 37.52795 -17.478897)
			(xy 37.550592 -17.429316) (xy 37.580059 -17.383462) (xy 37.615752 -17.342268) (xy 37.656944 -17.306573)
			(xy 37.702797 -17.277103) (xy 37.752376 -17.254458) (xy 37.804674 -17.239099) (xy 37.858625 -17.231339)
			(xy 37.885878 -17.230852) (xy 38.749478 -17.230852) (xy 38.776729 -17.231394) (xy 38.830677 -17.239147)
			(xy 38.882972 -17.2545) (xy 38.932549 -17.277139) (xy 38.9784 -17.306603) (xy 39.019591 -17.342293)
			(xy 39.055284 -17.383482) (xy 39.084751 -17.429331) (xy 39.107392 -17.478908) (xy 39.122748 -17.531202)
			(xy 39.130505 -17.585149) (xy 39.130505 -17.639651) (xy 39.130505 -17.639654) (xy 43.398638 -17.639654)
			(xy 43.398638 -17.585146) (xy 43.406395 -17.531193) (xy 43.421751 -17.478894) (xy 43.444395 -17.429312)
			(xy 43.473863 -17.383457) (xy 43.509558 -17.342262) (xy 43.550752 -17.306567) (xy 43.596606 -17.277097)
			(xy 43.646188 -17.254454) (xy 43.698487 -17.239096) (xy 43.75244 -17.231338) (xy 43.779694 -17.230852)
			(xy 44.643294 -17.230852) (xy 44.670544 -17.231395) (xy 44.72449 -17.23915) (xy 44.776783 -17.254504)
			(xy 44.826359 -17.277144) (xy 44.872208 -17.306609) (xy 44.913397 -17.342299) (xy 44.949088 -17.383487)
			(xy 44.978553 -17.429336) (xy 45.001194 -17.478911) (xy 45.016548 -17.531204) (xy 45.024305 -17.58515)
			(xy 45.024305 -17.63965) (xy 45.024304 -17.639654) (xy 48.986638 -17.639654) (xy 48.986638 -17.585146)
			(xy 48.994395 -17.531193) (xy 49.009751 -17.478894) (xy 49.032395 -17.429312) (xy 49.061863 -17.383457)
			(xy 49.097558 -17.342262) (xy 49.138752 -17.306567) (xy 49.184606 -17.277097) (xy 49.234188 -17.254454)
			(xy 49.286487 -17.239096) (xy 49.34044 -17.231338) (xy 49.367694 -17.230852) (xy 50.231294 -17.230852)
			(xy 50.258544 -17.231395) (xy 50.31249 -17.23915) (xy 50.364783 -17.254504) (xy 50.414359 -17.277144)
			(xy 50.460208 -17.306609) (xy 50.501397 -17.342299) (xy 50.537088 -17.383487) (xy 50.566553 -17.429336)
			(xy 50.589194 -17.478911) (xy 50.604548 -17.531204) (xy 50.612305 -17.58515) (xy 50.612305 -17.63965)
			(xy 50.612304 -17.639657) (xy 54.608615 -17.639657) (xy 54.608615 -17.585143) (xy 54.616374 -17.531184)
			(xy 54.631733 -17.478878) (xy 54.65438 -17.42929) (xy 54.683854 -17.383431) (xy 54.719554 -17.342233)
			(xy 54.760755 -17.306536) (xy 54.806617 -17.277065) (xy 54.856206 -17.254422) (xy 54.908513 -17.239067)
			(xy 54.962473 -17.231313) (xy 54.98973 -17.230852) (xy 55.85333 -17.230852) (xy 55.880577 -17.23142)
			(xy 55.934516 -17.239179) (xy 55.986801 -17.254535) (xy 56.03637 -17.277176) (xy 56.082211 -17.30664)
			(xy 56.123394 -17.342328) (xy 56.159078 -17.383513) (xy 56.188538 -17.429357) (xy 56.211175 -17.478927)
			(xy 56.226527 -17.531214) (xy 56.234282 -17.585153) (xy 56.234282 -17.639647) (xy 56.226527 -17.693586)
			(xy 56.211175 -17.745873) (xy 56.188538 -17.795443) (xy 56.159078 -17.841287) (xy 56.123394 -17.882472)
			(xy 56.082211 -17.91816) (xy 56.03637 -17.947624) (xy 55.986801 -17.970265) (xy 55.934516 -17.985621)
			(xy 55.880577 -17.99338) (xy 55.85333 -17.993868) (xy 54.98973 -17.993868) (xy 54.962473 -17.993487)
			(xy 54.908513 -17.985733) (xy 54.856206 -17.970378) (xy 54.806617 -17.947735) (xy 54.760755 -17.918264)
			(xy 54.719554 -17.882567) (xy 54.683854 -17.841369) (xy 54.65438 -17.79551) (xy 54.631733 -17.745922)
			(xy 54.616374 -17.693616) (xy 54.608615 -17.639657) (xy 50.612304 -17.639657) (xy 50.604548 -17.693596)
			(xy 50.589194 -17.745889) (xy 50.566553 -17.795464) (xy 50.537088 -17.841313) (xy 50.501397 -17.882501)
			(xy 50.460208 -17.918191) (xy 50.414359 -17.947656) (xy 50.364783 -17.970296) (xy 50.31249 -17.98565)
			(xy 50.258544 -17.993405) (xy 50.231294 -17.993868) (xy 49.367694 -17.993868) (xy 49.34044 -17.993462)
			(xy 49.286487 -17.985704) (xy 49.234188 -17.970346) (xy 49.184606 -17.947703) (xy 49.138752 -17.918233)
			(xy 49.097558 -17.882538) (xy 49.061863 -17.841343) (xy 49.032395 -17.795488) (xy 49.009751 -17.745906)
			(xy 48.994395 -17.693607) (xy 48.986638 -17.639654) (xy 45.024304 -17.639654) (xy 45.016548 -17.693596)
			(xy 45.001194 -17.745889) (xy 44.978553 -17.795464) (xy 44.949088 -17.841313) (xy 44.913397 -17.882501)
			(xy 44.872208 -17.918191) (xy 44.826359 -17.947656) (xy 44.776783 -17.970296) (xy 44.72449 -17.98565)
			(xy 44.670544 -17.993405) (xy 44.643294 -17.993868) (xy 43.779694 -17.993868) (xy 43.75244 -17.993462)
			(xy 43.698487 -17.985704) (xy 43.646188 -17.970346) (xy 43.596606 -17.947703) (xy 43.550752 -17.918233)
			(xy 43.509558 -17.882538) (xy 43.473863 -17.841343) (xy 43.444395 -17.795488) (xy 43.421751 -17.745906)
			(xy 43.406395 -17.693607) (xy 43.398638 -17.639654) (xy 39.130505 -17.639654) (xy 39.122748 -17.693598)
			(xy 39.107392 -17.745892) (xy 39.084751 -17.795469) (xy 39.055284 -17.841318) (xy 39.019591 -17.882507)
			(xy 38.9784 -17.918197) (xy 38.932549 -17.947661) (xy 38.882972 -17.9703) (xy 38.830677 -17.985653)
			(xy 38.776729 -17.993406) (xy 38.749478 -17.993868) (xy 37.885878 -17.993868) (xy 37.858625 -17.993461)
			(xy 37.804674 -17.985701) (xy 37.752376 -17.970342) (xy 37.702797 -17.947697) (xy 37.656944 -17.918227)
			(xy 37.615752 -17.882532) (xy 37.580059 -17.841338) (xy 37.550592 -17.795484) (xy 37.52795 -17.745903)
			(xy 37.512595 -17.693605) (xy 37.504838 -17.639653) (xy 33.542505 -17.639653) (xy 33.534748 -17.693598)
			(xy 33.519392 -17.745892) (xy 33.496751 -17.795469) (xy 33.467284 -17.841318) (xy 33.431591 -17.882507)
			(xy 33.3904 -17.918197) (xy 33.344549 -17.947661) (xy 33.294972 -17.9703) (xy 33.242677 -17.985653)
			(xy 33.188729 -17.993406) (xy 33.161478 -17.993868) (xy 32.297878 -17.993868) (xy 32.270625 -17.993461)
			(xy 32.216674 -17.985701) (xy 32.164376 -17.970342) (xy 32.114797 -17.947697) (xy 32.068944 -17.918227)
			(xy 32.027752 -17.882532) (xy 31.992059 -17.841338) (xy 31.962592 -17.795484) (xy 31.93995 -17.745903)
			(xy 31.924595 -17.693605) (xy 31.916838 -17.639653) (xy 27.954505 -17.639653) (xy 27.946748 -17.693598)
			(xy 27.931392 -17.745892) (xy 27.908751 -17.795469) (xy 27.879284 -17.841318) (xy 27.843591 -17.882507)
			(xy 27.8024 -17.918197) (xy 27.756549 -17.947661) (xy 27.706972 -17.9703) (xy 27.654677 -17.985653)
			(xy 27.600729 -17.993406) (xy 27.573478 -17.993868) (xy 26.709878 -17.993868) (xy 26.682625 -17.993461)
			(xy 26.628674 -17.985701) (xy 26.576376 -17.970342) (xy 26.526797 -17.947697) (xy 26.480944 -17.918227)
			(xy 26.439752 -17.882532) (xy 26.404059 -17.841338) (xy 26.374592 -17.795484) (xy 26.35195 -17.745903)
			(xy 26.336595 -17.693605) (xy 26.328838 -17.639653) (xy 22.366505 -17.639653) (xy 22.358748 -17.693598)
			(xy 22.343392 -17.745892) (xy 22.320751 -17.795469) (xy 22.291284 -17.841318) (xy 22.255591 -17.882507)
			(xy 22.2144 -17.918197) (xy 22.168549 -17.947661) (xy 22.118972 -17.9703) (xy 22.066677 -17.985653)
			(xy 22.012729 -17.993406) (xy 21.985478 -17.993868) (xy 21.121878 -17.993868) (xy 21.094627 -17.993382)
			(xy 21.040679 -17.985625) (xy 20.988385 -17.97027) (xy 20.938808 -17.947629) (xy 20.892958 -17.918162)
			(xy 20.851768 -17.882471) (xy 20.816076 -17.841281) (xy 20.78661 -17.79543) (xy 20.763969 -17.745853)
			(xy 20.748614 -17.693559) (xy 20.740858 -17.639611) (xy 16.778525 -17.639611) (xy 16.778525 -17.639613)
			(xy 16.770768 -17.693564) (xy 16.755412 -17.745862) (xy 16.732769 -17.795442) (xy 16.703301 -17.841296)
			(xy 16.667607 -17.882488) (xy 16.626414 -17.918182) (xy 16.580561 -17.94765) (xy 16.53098 -17.970292)
			(xy 16.478682 -17.985648) (xy 16.424731 -17.993405) (xy 16.397478 -17.993868) (xy 15.533878 -17.993868)
			(xy 15.506627 -17.993382) (xy 15.452679 -17.985625) (xy 15.400385 -17.97027) (xy 15.350808 -17.947629)
			(xy 15.304958 -17.918162) (xy 15.263768 -17.882471) (xy 15.228076 -17.841281) (xy 15.19861 -17.79543)
			(xy 15.175969 -17.745853) (xy 15.160614 -17.693559) (xy 15.152858 -17.639611) (xy 9.462533 -17.639611)
			(xy 9.516208 -17.667423) (xy 9.695034 -17.769123) (xy 9.869756 -17.877723) (xy 10.040109 -17.993058)
			(xy 10.205831 -18.114951) (xy 10.366672 -18.243217) (xy 10.522385 -18.37766) (xy 10.672735 -18.518077)
			(xy 10.817492 -18.664253) (xy 10.956435 -18.815965) (xy 11.089353 -18.972983) (xy 11.216044 -19.135068)
			(xy 11.236612 -19.163611) (xy 17.946858 -19.163611) (xy 17.946858 -19.109109) (xy 17.954614 -19.055161)
			(xy 17.969969 -19.002867) (xy 17.99261 -18.95329) (xy 18.022076 -18.907439) (xy 18.057768 -18.866249)
			(xy 18.098958 -18.830558) (xy 18.144808 -18.801091) (xy 18.194385 -18.77845) (xy 18.246679 -18.763095)
			(xy 18.300627 -18.755338) (xy 18.327878 -18.754852) (xy 19.191478 -18.754852) (xy 19.218731 -18.755315)
			(xy 19.272682 -18.763072) (xy 19.32498 -18.778428) (xy 19.374561 -18.80107) (xy 19.420414 -18.830538)
			(xy 19.461607 -18.866232) (xy 19.497301 -18.907424) (xy 19.526769 -18.953278) (xy 19.549412 -19.002858)
			(xy 19.564768 -19.055156) (xy 19.572525 -19.109107) (xy 19.572525 -19.163613) (xy 19.572519 -19.163653)
			(xy 23.534838 -19.163653) (xy 23.534838 -19.109147) (xy 23.542595 -19.055195) (xy 23.55795 -19.002897)
			(xy 23.580592 -18.953316) (xy 23.610059 -18.907462) (xy 23.645752 -18.866268) (xy 23.686944 -18.830573)
			(xy 23.732797 -18.801103) (xy 23.782376 -18.778458) (xy 23.834674 -18.763099) (xy 23.888625 -18.755339)
			(xy 23.915878 -18.754852) (xy 24.779478 -18.754852) (xy 24.806729 -18.755394) (xy 24.860677 -18.763147)
			(xy 24.912972 -18.7785) (xy 24.962549 -18.801139) (xy 25.0084 -18.830603) (xy 25.049591 -18.866293)
			(xy 25.085284 -18.907482) (xy 25.114751 -18.953331) (xy 25.137392 -19.002908) (xy 25.152748 -19.055202)
			(xy 25.160505 -19.109149) (xy 25.160505 -19.163651) (xy 25.160505 -19.163653) (xy 29.122838 -19.163653)
			(xy 29.122838 -19.109147) (xy 29.130595 -19.055195) (xy 29.14595 -19.002897) (xy 29.168592 -18.953316)
			(xy 29.198059 -18.907462) (xy 29.233752 -18.866268) (xy 29.274944 -18.830573) (xy 29.320797 -18.801103)
			(xy 29.370376 -18.778458) (xy 29.422674 -18.763099) (xy 29.476625 -18.755339) (xy 29.503878 -18.754852)
			(xy 30.367478 -18.754852) (xy 30.394729 -18.755394) (xy 30.448677 -18.763147) (xy 30.500972 -18.7785)
			(xy 30.550549 -18.801139) (xy 30.5964 -18.830603) (xy 30.637591 -18.866293) (xy 30.673284 -18.907482)
			(xy 30.702751 -18.953331) (xy 30.725392 -19.002908) (xy 30.740748 -19.055202) (xy 30.748505 -19.109149)
			(xy 30.748505 -19.163651) (xy 30.748505 -19.163653) (xy 34.710838 -19.163653) (xy 34.710838 -19.109147)
			(xy 34.718595 -19.055195) (xy 34.73395 -19.002897) (xy 34.756592 -18.953316) (xy 34.786059 -18.907462)
			(xy 34.821752 -18.866268) (xy 34.862944 -18.830573) (xy 34.908797 -18.801103) (xy 34.958376 -18.778458)
			(xy 35.010674 -18.763099) (xy 35.064625 -18.755339) (xy 35.091878 -18.754852) (xy 35.955478 -18.754852)
			(xy 35.982729 -18.755394) (xy 36.036677 -18.763147) (xy 36.088972 -18.7785) (xy 36.138549 -18.801139)
			(xy 36.1844 -18.830603) (xy 36.225591 -18.866293) (xy 36.261284 -18.907482) (xy 36.290751 -18.953331)
			(xy 36.313392 -19.002908) (xy 36.328748 -19.055202) (xy 36.336505 -19.109149) (xy 36.336505 -19.163651)
			(xy 36.336505 -19.163654) (xy 40.604638 -19.163654) (xy 40.604638 -19.109146) (xy 40.612395 -19.055193)
			(xy 40.627751 -19.002894) (xy 40.650395 -18.953312) (xy 40.679863 -18.907457) (xy 40.715558 -18.866262)
			(xy 40.756752 -18.830567) (xy 40.802606 -18.801097) (xy 40.852188 -18.778454) (xy 40.904487 -18.763096)
			(xy 40.95844 -18.755338) (xy 40.985694 -18.754852) (xy 41.849294 -18.754852) (xy 41.876544 -18.755395)
			(xy 41.93049 -18.76315) (xy 41.982783 -18.778504) (xy 42.032359 -18.801144) (xy 42.078208 -18.830609)
			(xy 42.119397 -18.866299) (xy 42.155088 -18.907487) (xy 42.184553 -18.953336) (xy 42.207194 -19.002911)
			(xy 42.222548 -19.055204) (xy 42.230305 -19.10915) (xy 42.230305 -19.16365) (xy 42.230304 -19.163654)
			(xy 46.192638 -19.163654) (xy 46.192638 -19.109146) (xy 46.200395 -19.055193) (xy 46.215751 -19.002894)
			(xy 46.238395 -18.953312) (xy 46.267863 -18.907457) (xy 46.303558 -18.866262) (xy 46.344752 -18.830567)
			(xy 46.390606 -18.801097) (xy 46.440188 -18.778454) (xy 46.492487 -18.763096) (xy 46.54644 -18.755338)
			(xy 46.573694 -18.754852) (xy 47.437294 -18.754852) (xy 47.464544 -18.755395) (xy 47.51849 -18.76315)
			(xy 47.570783 -18.778504) (xy 47.620359 -18.801144) (xy 47.666208 -18.830609) (xy 47.707397 -18.866299)
			(xy 47.743088 -18.907487) (xy 47.772553 -18.953336) (xy 47.795194 -19.002911) (xy 47.810548 -19.055204)
			(xy 47.818305 -19.10915) (xy 47.818305 -19.16365) (xy 47.818304 -19.163657) (xy 51.814615 -19.163657)
			(xy 51.814615 -19.109143) (xy 51.822374 -19.055184) (xy 51.837733 -19.002878) (xy 51.86038 -18.95329)
			(xy 51.889854 -18.907431) (xy 51.925554 -18.866233) (xy 51.966755 -18.830536) (xy 52.012617 -18.801065)
			(xy 52.062206 -18.778422) (xy 52.114513 -18.763067) (xy 52.168473 -18.755313) (xy 52.19573 -18.754852)
			(xy 53.05933 -18.754852) (xy 53.086577 -18.75542) (xy 53.140516 -18.763179) (xy 53.192801 -18.778535)
			(xy 53.24237 -18.801176) (xy 53.288211 -18.83064) (xy 53.329394 -18.866328) (xy 53.365078 -18.907513)
			(xy 53.394538 -18.953357) (xy 53.417175 -19.002927) (xy 53.432527 -19.055214) (xy 53.440282 -19.109153)
			(xy 53.440282 -19.163647) (xy 53.440281 -19.163657) (xy 57.402615 -19.163657) (xy 57.402615 -19.109143)
			(xy 57.410374 -19.055184) (xy 57.425733 -19.002878) (xy 57.44838 -18.95329) (xy 57.477854 -18.907431)
			(xy 57.513554 -18.866233) (xy 57.554755 -18.830536) (xy 57.600617 -18.801065) (xy 57.650206 -18.778422)
			(xy 57.702513 -18.763067) (xy 57.756473 -18.755313) (xy 57.78373 -18.754852) (xy 58.64733 -18.754852)
			(xy 58.674577 -18.75542) (xy 58.728516 -18.763179) (xy 58.780801 -18.778535) (xy 58.83037 -18.801176)
			(xy 58.876211 -18.83064) (xy 58.917394 -18.866328) (xy 58.953078 -18.907513) (xy 58.982538 -18.953357)
			(xy 59.005175 -19.002927) (xy 59.020527 -19.055214) (xy 59.028282 -19.109153) (xy 59.028282 -19.163647)
			(xy 59.020527 -19.217586) (xy 59.005175 -19.269873) (xy 58.982538 -19.319443) (xy 58.953078 -19.365287)
			(xy 58.917394 -19.406472) (xy 58.876211 -19.44216) (xy 58.83037 -19.471624) (xy 58.780801 -19.494265)
			(xy 58.728516 -19.509621) (xy 58.674577 -19.51738) (xy 58.64733 -19.517868) (xy 57.78373 -19.517868)
			(xy 57.756473 -19.517487) (xy 57.702513 -19.509733) (xy 57.650206 -19.494378) (xy 57.600617 -19.471735)
			(xy 57.554755 -19.442264) (xy 57.513554 -19.406567) (xy 57.477854 -19.365369) (xy 57.44838 -19.31951)
			(xy 57.425733 -19.269922) (xy 57.410374 -19.217616) (xy 57.402615 -19.163657) (xy 53.440281 -19.163657)
			(xy 53.432527 -19.217586) (xy 53.417175 -19.269873) (xy 53.394538 -19.319443) (xy 53.365078 -19.365287)
			(xy 53.329394 -19.406472) (xy 53.288211 -19.44216) (xy 53.24237 -19.471624) (xy 53.192801 -19.494265)
			(xy 53.140516 -19.509621) (xy 53.086577 -19.51738) (xy 53.05933 -19.517868) (xy 52.19573 -19.517868)
			(xy 52.168473 -19.517487) (xy 52.114513 -19.509733) (xy 52.062206 -19.494378) (xy 52.012617 -19.471735)
			(xy 51.966755 -19.442264) (xy 51.925554 -19.406567) (xy 51.889854 -19.365369) (xy 51.86038 -19.31951)
			(xy 51.837733 -19.269922) (xy 51.822374 -19.217616) (xy 51.814615 -19.163657) (xy 47.818304 -19.163657)
			(xy 47.810548 -19.217596) (xy 47.795194 -19.269889) (xy 47.772553 -19.319464) (xy 47.743088 -19.365313)
			(xy 47.707397 -19.406501) (xy 47.666208 -19.442191) (xy 47.620359 -19.471656) (xy 47.570783 -19.494296)
			(xy 47.51849 -19.50965) (xy 47.464544 -19.517405) (xy 47.437294 -19.517868) (xy 46.573694 -19.517868)
			(xy 46.54644 -19.517462) (xy 46.492487 -19.509704) (xy 46.440188 -19.494346) (xy 46.390606 -19.471703)
			(xy 46.344752 -19.442233) (xy 46.303558 -19.406538) (xy 46.267863 -19.365343) (xy 46.238395 -19.319488)
			(xy 46.215751 -19.269906) (xy 46.200395 -19.217607) (xy 46.192638 -19.163654) (xy 42.230304 -19.163654)
			(xy 42.222548 -19.217596) (xy 42.207194 -19.269889) (xy 42.184553 -19.319464) (xy 42.155088 -19.365313)
			(xy 42.119397 -19.406501) (xy 42.078208 -19.442191) (xy 42.032359 -19.471656) (xy 41.982783 -19.494296)
			(xy 41.93049 -19.50965) (xy 41.876544 -19.517405) (xy 41.849294 -19.517868) (xy 40.985694 -19.517868)
			(xy 40.95844 -19.517462) (xy 40.904487 -19.509704) (xy 40.852188 -19.494346) (xy 40.802606 -19.471703)
			(xy 40.756752 -19.442233) (xy 40.715558 -19.406538) (xy 40.679863 -19.365343) (xy 40.650395 -19.319488)
			(xy 40.627751 -19.269906) (xy 40.612395 -19.217607) (xy 40.604638 -19.163654) (xy 36.336505 -19.163654)
			(xy 36.328748 -19.217598) (xy 36.313392 -19.269892) (xy 36.290751 -19.319469) (xy 36.261284 -19.365318)
			(xy 36.225591 -19.406507) (xy 36.1844 -19.442197) (xy 36.138549 -19.471661) (xy 36.088972 -19.4943)
			(xy 36.036677 -19.509653) (xy 35.982729 -19.517406) (xy 35.955478 -19.517868) (xy 35.091878 -19.517868)
			(xy 35.064625 -19.517461) (xy 35.010674 -19.509701) (xy 34.958376 -19.494342) (xy 34.908797 -19.471697)
			(xy 34.862944 -19.442227) (xy 34.821752 -19.406532) (xy 34.786059 -19.365338) (xy 34.756592 -19.319484)
			(xy 34.73395 -19.269903) (xy 34.718595 -19.217605) (xy 34.710838 -19.163653) (xy 30.748505 -19.163653)
			(xy 30.740748 -19.217598) (xy 30.725392 -19.269892) (xy 30.702751 -19.319469) (xy 30.673284 -19.365318)
			(xy 30.637591 -19.406507) (xy 30.5964 -19.442197) (xy 30.550549 -19.471661) (xy 30.500972 -19.4943)
			(xy 30.448677 -19.509653) (xy 30.394729 -19.517406) (xy 30.367478 -19.517868) (xy 29.503878 -19.517868)
			(xy 29.476625 -19.517461) (xy 29.422674 -19.509701) (xy 29.370376 -19.494342) (xy 29.320797 -19.471697)
			(xy 29.274944 -19.442227) (xy 29.233752 -19.406532) (xy 29.198059 -19.365338) (xy 29.168592 -19.319484)
			(xy 29.14595 -19.269903) (xy 29.130595 -19.217605) (xy 29.122838 -19.163653) (xy 25.160505 -19.163653)
			(xy 25.152748 -19.217598) (xy 25.137392 -19.269892) (xy 25.114751 -19.319469) (xy 25.085284 -19.365318)
			(xy 25.049591 -19.406507) (xy 25.0084 -19.442197) (xy 24.962549 -19.471661) (xy 24.912972 -19.4943)
			(xy 24.860677 -19.509653) (xy 24.806729 -19.517406) (xy 24.779478 -19.517868) (xy 23.915878 -19.517868)
			(xy 23.888625 -19.517461) (xy 23.834674 -19.509701) (xy 23.782376 -19.494342) (xy 23.732797 -19.471697)
			(xy 23.686944 -19.442227) (xy 23.645752 -19.406532) (xy 23.610059 -19.365338) (xy 23.580592 -19.319484)
			(xy 23.55795 -19.269903) (xy 23.542595 -19.217605) (xy 23.534838 -19.163653) (xy 19.572519 -19.163653)
			(xy 19.564768 -19.217564) (xy 19.549412 -19.269862) (xy 19.526769 -19.319442) (xy 19.497301 -19.365296)
			(xy 19.461607 -19.406488) (xy 19.420414 -19.442182) (xy 19.374561 -19.47165) (xy 19.32498 -19.494292)
			(xy 19.272682 -19.509648) (xy 19.218731 -19.517405) (xy 19.191478 -19.517868) (xy 18.327878 -19.517868)
			(xy 18.300627 -19.517382) (xy 18.246679 -19.509625) (xy 18.194385 -19.49427) (xy 18.144808 -19.471629)
			(xy 18.098958 -19.442162) (xy 18.057768 -19.406471) (xy 18.022076 -19.365281) (xy 17.99261 -19.31943)
			(xy 17.969969 -19.269853) (xy 17.954614 -19.217559) (xy 17.946858 -19.163611) (xy 11.236612 -19.163611)
			(xy 11.336314 -19.301971) (xy 11.449981 -19.473441) (xy 11.556871 -19.649214) (xy 11.656822 -19.829024)
			(xy 11.749681 -20.012597) (xy 11.835308 -20.199653) (xy 11.91357 -20.389908) (xy 11.984351 -20.583071)
			(xy 12.047541 -20.778849) (xy 12.103044 -20.976943) (xy 12.150776 -21.177052) (xy 12.190665 -21.37887)
			(xy 12.213074 -21.521251) (xy 15.232366 -21.521251) (xy 15.232366 -21.466749) (xy 15.240122 -21.412801)
			(xy 15.255477 -21.360506) (xy 15.278117 -21.310929) (xy 15.307582 -21.265078) (xy 15.343273 -21.223887)
			(xy 15.384462 -21.188194) (xy 15.430311 -21.158727) (xy 15.479888 -21.136084) (xy 15.532182 -21.120726)
			(xy 15.586129 -21.112967) (xy 15.61338 -21.11248) (xy 16.47698 -21.11248) (xy 16.504233 -21.112966)
			(xy 16.558184 -21.12072) (xy 16.610483 -21.136074) (xy 16.660064 -21.158715) (xy 16.705918 -21.188181)
			(xy 16.747112 -21.223874) (xy 16.782807 -21.265066) (xy 16.812276 -21.310918) (xy 16.834919 -21.360498)
			(xy 16.850275 -21.412796) (xy 16.858033 -21.466747) (xy 16.858033 -21.521253) (xy 16.850275 -21.575204)
			(xy 16.834919 -21.627502) (xy 16.812276 -21.677082) (xy 16.782807 -21.722934) (xy 16.747112 -21.764126)
			(xy 16.705918 -21.799819) (xy 16.660064 -21.829285) (xy 16.610483 -21.851926) (xy 16.558184 -21.86728)
			(xy 16.504233 -21.875034) (xy 16.47698 -21.875496) (xy 15.61338 -21.875496) (xy 15.586129 -21.875033)
			(xy 15.532182 -21.867274) (xy 15.479888 -21.851916) (xy 15.430311 -21.829273) (xy 15.384462 -21.799806)
			(xy 15.343273 -21.764113) (xy 15.307582 -21.722922) (xy 15.278117 -21.677071) (xy 15.255477 -21.627494)
			(xy 15.240122 -21.575199) (xy 15.232366 -21.521251) (xy 12.213074 -21.521251) (xy 12.222649 -21.582092)
			(xy 12.246679 -21.786406) (xy 12.26272 -21.991502) (xy 12.270746 -22.197069) (xy 12.271248 -22.29993)
			(xy 89.628224 -22.29993) (xy 89.632238 -22.094246) (xy 89.644274 -21.888876) (xy 89.664313 -21.684132)
			(xy 89.692326 -21.480325) (xy 89.728269 -21.277766) (xy 89.772088 -21.076764) (xy 89.823715 -20.877625)
			(xy 89.883073 -20.680652) (xy 89.950071 -20.486144) (xy 90.024607 -20.294399) (xy 90.106567 -20.105708)
			(xy 90.195827 -19.920358) (xy 90.29225 -19.738632) (xy 90.395691 -19.560806) (xy 90.50599 -19.387152)
			(xy 90.622981 -19.217933) (xy 90.746485 -19.053407) (xy 90.876314 -18.893826) (xy 91.012271 -18.739431)
			(xy 91.154148 -18.590459) (xy 91.301729 -18.447135) (xy 91.45479 -18.309679) (xy 91.613097 -18.178299)
			(xy 91.77641 -18.053196) (xy 91.944479 -17.934559) (xy 92.117049 -17.822571) (xy 92.293857 -17.7174)
			(xy 92.474634 -17.619209) (xy 92.659104 -17.528145) (xy 92.846986 -17.444348) (xy 93.037996 -17.367945)
			(xy 93.23184 -17.299052) (xy 93.428225 -17.237775) (xy 93.626851 -17.184207) (xy 93.827416 -17.13843)
			(xy 94.029614 -17.100512) (xy 94.233138 -17.070513) (xy 94.437677 -17.048476) (xy 94.64292 -17.034437)
			(xy 94.848555 -17.028417) (xy 95.054268 -17.030424) (xy 95.259746 -17.040456) (xy 95.464676 -17.058497)
			(xy 95.668746 -17.08452) (xy 95.871646 -17.118485) (xy 96.073066 -17.16034) (xy 96.272699 -17.210022)
			(xy 96.470242 -17.267456) (xy 96.665394 -17.332553) (xy 96.857858 -17.405214) (xy 97.04734 -17.48533)
			(xy 97.233551 -17.572777) (xy 97.41621 -17.667423) (xy 97.595036 -17.769123) (xy 97.769758 -17.877723)
			(xy 97.940111 -17.993058) (xy 98.105833 -18.114951) (xy 98.177304 -18.171947) (xy 131.633522 -18.171947)
			(xy 131.633522 -18.117453) (xy 131.641277 -18.063515) (xy 131.656629 -18.011229) (xy 131.679265 -17.961659)
			(xy 131.708725 -17.915816) (xy 131.744409 -17.874631) (xy 131.78559 -17.838944) (xy 131.831431 -17.80948)
			(xy 131.880999 -17.78684) (xy 131.933283 -17.771484) (xy 131.987221 -17.763724) (xy 132.014468 -17.763236)
			(xy 132.878068 -17.763236) (xy 132.905326 -17.763609) (xy 132.959286 -17.771363) (xy 133.011594 -17.786718)
			(xy 133.061184 -17.809361) (xy 133.107046 -17.838832) (xy 133.148248 -17.87453) (xy 133.183949 -17.915728)
			(xy 133.213423 -17.961588) (xy 133.236071 -18.011176) (xy 133.25143 -18.063483) (xy 133.259189 -18.117443)
			(xy 133.259189 -18.17195) (xy 137.033499 -18.17195) (xy 137.033499 -18.11745) (xy 137.041256 -18.063505)
			(xy 137.05661 -18.011212) (xy 137.079251 -17.961637) (xy 137.108716 -17.915789) (xy 137.144406 -17.874601)
			(xy 137.185595 -17.838911) (xy 137.231444 -17.809447) (xy 137.28102 -17.786807) (xy 137.333312 -17.771454)
			(xy 137.387258 -17.763699) (xy 137.414508 -17.763236) (xy 138.278108 -17.763236) (xy 138.305362 -17.763634)
			(xy 138.359315 -17.771393) (xy 138.411615 -17.78675) (xy 138.461197 -17.809395) (xy 138.507052 -17.838864)
			(xy 138.548246 -17.87456) (xy 138.58394 -17.915755) (xy 138.613409 -17.96161) (xy 138.636052 -18.011193)
			(xy 138.651409 -18.063493) (xy 138.659166 -18.117446) (xy 138.659166 -18.171946) (xy 140.633522 -18.171946)
			(xy 140.633522 -18.117454) (xy 140.641276 -18.063517) (xy 140.656627 -18.011232) (xy 140.679262 -17.961664)
			(xy 140.70872 -17.915822) (xy 140.744402 -17.874638) (xy 140.785582 -17.83895) (xy 140.83142 -17.809486)
			(xy 140.880986 -17.786845) (xy 140.933268 -17.771487) (xy 140.987204 -17.763726) (xy 141.01445 -17.763236)
			(xy 141.87805 -17.763236) (xy 141.905308 -17.763608) (xy 141.959271 -17.77136) (xy 142.011581 -17.786713)
			(xy 142.061173 -17.809355) (xy 142.107038 -17.838825) (xy 142.148241 -17.874523) (xy 142.183945 -17.915722)
			(xy 142.213421 -17.961583) (xy 142.236069 -18.011172) (xy 142.25143 -18.06348) (xy 142.259189 -18.117442)
			(xy 142.259189 -18.171951) (xy 185.748399 -18.171951) (xy 185.748399 -18.117449) (xy 185.756156 -18.063503)
			(xy 185.771511 -18.011209) (xy 185.794153 -17.961633) (xy 185.823619 -17.915784) (xy 185.859311 -17.874596)
			(xy 185.900502 -17.838906) (xy 185.946353 -17.809442) (xy 185.99593 -17.786804) (xy 186.048224 -17.771451)
			(xy 186.102171 -17.763698) (xy 186.129422 -17.763236) (xy 186.993022 -17.763236) (xy 187.020275 -17.763635)
			(xy 187.074227 -17.771395) (xy 187.126525 -17.786754) (xy 187.176105 -17.809399) (xy 187.221958 -17.838869)
			(xy 187.263151 -17.874565) (xy 187.298844 -17.915759) (xy 187.328311 -17.961614) (xy 187.350954 -18.011196)
			(xy 187.366309 -18.063495) (xy 187.374066 -18.117447) (xy 187.374066 -18.171953) (xy 187.366309 -18.225905)
			(xy 187.350954 -18.278204) (xy 187.328311 -18.327786) (xy 187.298844 -18.373641) (xy 187.263151 -18.414835)
			(xy 187.221958 -18.450531) (xy 187.176105 -18.480001) (xy 187.126525 -18.502646) (xy 187.074227 -18.518005)
			(xy 187.020275 -18.525765) (xy 186.993022 -18.526252) (xy 186.129422 -18.526252) (xy 186.102171 -18.525702)
			(xy 186.048224 -18.517949) (xy 185.99593 -18.502596) (xy 185.946353 -18.479958) (xy 185.900502 -18.450494)
			(xy 185.859311 -18.414804) (xy 185.823619 -18.373616) (xy 185.794153 -18.327767) (xy 185.771511 -18.278191)
			(xy 185.756156 -18.225897) (xy 185.748399 -18.171951) (xy 142.259189 -18.171951) (xy 142.259189 -18.171958)
			(xy 142.25143 -18.22592) (xy 142.236069 -18.278228) (xy 142.213421 -18.327817) (xy 142.183945 -18.373678)
			(xy 142.148241 -18.414877) (xy 142.107038 -18.450575) (xy 142.061173 -18.480045) (xy 142.011581 -18.502687)
			(xy 141.959271 -18.51804) (xy 141.905308 -18.525792) (xy 141.87805 -18.526252) (xy 141.01445 -18.526252)
			(xy 140.987204 -18.525674) (xy 140.933268 -18.517913) (xy 140.880986 -18.502555) (xy 140.83142 -18.479914)
			(xy 140.785582 -18.45045) (xy 140.744402 -18.414762) (xy 140.70872 -18.373578) (xy 140.679262 -18.327736)
			(xy 140.656627 -18.278168) (xy 140.641276 -18.225883) (xy 140.633522 -18.171946) (xy 138.659166 -18.171946)
			(xy 138.659166 -18.171954) (xy 138.651409 -18.225907) (xy 138.636052 -18.278207) (xy 138.613409 -18.32779)
			(xy 138.58394 -18.373645) (xy 138.548246 -18.41484) (xy 138.507052 -18.450536) (xy 138.461197 -18.480005)
			(xy 138.411615 -18.50265) (xy 138.359315 -18.518007) (xy 138.305362 -18.525766) (xy 138.278108 -18.526252)
			(xy 137.414508 -18.526252) (xy 137.387258 -18.525701) (xy 137.333312 -18.517946) (xy 137.28102 -18.502593)
			(xy 137.231444 -18.479953) (xy 137.185595 -18.450489) (xy 137.144406 -18.414799) (xy 137.108716 -18.373611)
			(xy 137.079251 -18.327763) (xy 137.05661 -18.278188) (xy 137.041256 -18.225895) (xy 137.033499 -18.17195)
			(xy 133.259189 -18.17195) (xy 133.259189 -18.171957) (xy 133.25143 -18.225917) (xy 133.236071 -18.278224)
			(xy 133.213423 -18.327812) (xy 133.183949 -18.373672) (xy 133.148248 -18.41487) (xy 133.107046 -18.450568)
			(xy 133.061184 -18.480039) (xy 133.011594 -18.502682) (xy 132.959286 -18.518037) (xy 132.905326 -18.525791)
			(xy 132.878068 -18.526252) (xy 132.014468 -18.526252) (xy 131.987221 -18.525676) (xy 131.933283 -18.517916)
			(xy 131.880999 -18.50256) (xy 131.831431 -18.47992) (xy 131.78559 -18.450456) (xy 131.744409 -18.414769)
			(xy 131.708725 -18.373584) (xy 131.679265 -18.327741) (xy 131.656629 -18.278171) (xy 131.641277 -18.225885)
			(xy 131.633522 -18.171947) (xy 98.177304 -18.171947) (xy 98.266674 -18.243217) (xy 98.422387 -18.37766)
			(xy 98.572737 -18.518077) (xy 98.717494 -18.664253) (xy 98.856437 -18.815965) (xy 98.989355 -18.972983)
			(xy 99.116046 -19.135068) (xy 99.236316 -19.301971) (xy 99.349983 -19.473441) (xy 99.456873 -19.649214)
			(xy 99.556824 -19.829024) (xy 99.649683 -20.012597) (xy 99.729862 -20.187751) (xy 138.828766 -20.187751)
			(xy 138.828766 -20.133249) (xy 138.836522 -20.079301) (xy 138.851877 -20.027006) (xy 138.874517 -19.977429)
			(xy 138.903982 -19.931578) (xy 138.939673 -19.890387) (xy 138.980862 -19.854694) (xy 139.026711 -19.825227)
			(xy 139.076288 -19.802584) (xy 139.128582 -19.787226) (xy 139.182529 -19.779467) (xy 139.20978 -19.77898)
			(xy 140.07338 -19.77898) (xy 140.100633 -19.779466) (xy 140.154584 -19.78722) (xy 140.206883 -19.802574)
			(xy 140.256464 -19.825215) (xy 140.302318 -19.854681) (xy 140.343512 -19.890374) (xy 140.379207 -19.931566)
			(xy 140.408676 -19.977418) (xy 140.431319 -20.026998) (xy 140.446675 -20.079296) (xy 140.454433 -20.133247)
			(xy 140.454433 -20.187753) (xy 140.446675 -20.241704) (xy 140.431319 -20.294002) (xy 140.408676 -20.343582)
			(xy 140.379207 -20.389434) (xy 140.343512 -20.430626) (xy 140.302318 -20.466319) (xy 140.256464 -20.495785)
			(xy 140.206883 -20.518426) (xy 140.154584 -20.53378) (xy 140.100633 -20.541534) (xy 140.07338 -20.541996)
			(xy 139.20978 -20.541996) (xy 139.182529 -20.541533) (xy 139.128582 -20.533774) (xy 139.076288 -20.518416)
			(xy 139.026711 -20.495773) (xy 138.980862 -20.466306) (xy 138.939673 -20.430613) (xy 138.903982 -20.389422)
			(xy 138.874517 -20.343571) (xy 138.851877 -20.293994) (xy 138.836522 -20.241699) (xy 138.828766 -20.187751)
			(xy 99.729862 -20.187751) (xy 99.73531 -20.199653) (xy 99.813572 -20.389908) (xy 99.884353 -20.583071)
			(xy 99.947543 -20.778849) (xy 100.003046 -20.976943) (xy 100.050778 -21.177052) (xy 100.090667 -21.37887)
			(xy 100.122651 -21.582092) (xy 100.146681 -21.786406) (xy 100.162722 -21.991502) (xy 100.170748 -22.197069)
			(xy 100.17125 -22.29993) (xy 198.128134 -22.29993) (xy 198.132148 -22.094246) (xy 198.144184 -21.888876)
			(xy 198.164223 -21.684132) (xy 198.192236 -21.480325) (xy 198.228179 -21.277766) (xy 198.271998 -21.076764)
			(xy 198.323625 -20.877625) (xy 198.382983 -20.680652) (xy 198.449981 -20.486144) (xy 198.524517 -20.294399)
			(xy 198.606477 -20.105708) (xy 198.695737 -19.920358) (xy 198.79216 -19.738632) (xy 198.895601 -19.560806)
			(xy 199.0059 -19.387152) (xy 199.122891 -19.217933) (xy 199.246395 -19.053407) (xy 199.376224 -18.893826)
			(xy 199.512181 -18.739431) (xy 199.654058 -18.590459) (xy 199.801639 -18.447135) (xy 199.9547 -18.309679)
			(xy 200.113007 -18.178299) (xy 200.27632 -18.053196) (xy 200.444389 -17.934559) (xy 200.616959 -17.822571)
			(xy 200.793767 -17.7174) (xy 200.974544 -17.619209) (xy 201.159014 -17.528145) (xy 201.346896 -17.444348)
			(xy 201.537906 -17.367945) (xy 201.73175 -17.299052) (xy 201.928135 -17.237775) (xy 202.126761 -17.184207)
			(xy 202.327326 -17.13843) (xy 202.529524 -17.100512) (xy 202.733048 -17.070513) (xy 202.937587 -17.048476)
			(xy 203.14283 -17.034437) (xy 203.348465 -17.028417) (xy 203.554178 -17.030424) (xy 203.759656 -17.040456)
			(xy 203.964586 -17.058497) (xy 204.168656 -17.08452) (xy 204.371556 -17.118485) (xy 204.572976 -17.16034)
			(xy 204.772609 -17.210022) (xy 204.970152 -17.267456) (xy 205.165304 -17.332553) (xy 205.357768 -17.405214)
			(xy 205.54725 -17.48533) (xy 205.733461 -17.572777) (xy 205.91612 -17.667423) (xy 206.094946 -17.769123)
			(xy 206.185737 -17.825555) (xy 218.803143 -17.825555) (xy 218.803143 -17.771045) (xy 218.810901 -17.717091)
			(xy 218.826258 -17.66479) (xy 218.848903 -17.615207) (xy 218.878374 -17.569351) (xy 218.914071 -17.528157)
			(xy 218.955267 -17.492462) (xy 219.001124 -17.462993) (xy 219.050709 -17.440351) (xy 219.10301 -17.424996)
			(xy 219.156965 -17.417242) (xy 219.18422 -17.41678) (xy 220.04782 -17.41678) (xy 220.075069 -17.417292)
			(xy 220.129013 -17.42505) (xy 220.181304 -17.440407) (xy 220.230877 -17.463048) (xy 220.276723 -17.492514)
			(xy 220.31791 -17.528204) (xy 220.353598 -17.569393) (xy 220.383062 -17.615241) (xy 220.4057 -17.664815)
			(xy 220.421054 -17.717106) (xy 220.42881 -17.771051) (xy 220.42881 -17.825549) (xy 220.421054 -17.879494)
			(xy 220.4057 -17.931785) (xy 220.383062 -17.981359) (xy 220.353598 -18.027207) (xy 220.31791 -18.068396)
			(xy 220.276723 -18.104086) (xy 220.230877 -18.133552) (xy 220.181304 -18.156193) (xy 220.129013 -18.17155)
			(xy 220.075069 -18.179308) (xy 220.04782 -18.179796) (xy 219.18422 -18.179796) (xy 219.156965 -18.179358)
			(xy 219.10301 -18.171604) (xy 219.050709 -18.156249) (xy 219.001124 -18.133607) (xy 218.955267 -18.104138)
			(xy 218.914071 -18.068443) (xy 218.878374 -18.027249) (xy 218.848903 -17.981393) (xy 218.826258 -17.93181)
			(xy 218.810901 -17.879509) (xy 218.803143 -17.825555) (xy 206.185737 -17.825555) (xy 206.269668 -17.877723)
			(xy 206.440021 -17.993058) (xy 206.605743 -18.114951) (xy 206.766584 -18.243217) (xy 206.922297 -18.37766)
			(xy 207.072647 -18.518077) (xy 207.217404 -18.664253) (xy 207.356347 -18.815965) (xy 207.489265 -18.972983)
			(xy 207.615956 -19.135068) (xy 207.736226 -19.301971) (xy 207.849893 -19.473441) (xy 207.956783 -19.649214)
			(xy 208.056734 -19.829024) (xy 208.149593 -20.012597) (xy 208.23522 -20.199653) (xy 208.313482 -20.389908)
			(xy 208.384263 -20.583071) (xy 208.447453 -20.778849) (xy 208.502956 -20.976943) (xy 208.550688 -21.177052)
			(xy 208.590577 -21.37887) (xy 208.622561 -21.582092) (xy 208.646591 -21.786406) (xy 208.662632 -21.991502)
			(xy 208.670658 -22.197069) (xy 208.67116 -22.29993) (xy 208.670658 -22.402791) (xy 208.662632 -22.608358)
			(xy 208.646591 -22.813454) (xy 208.622561 -23.017768) (xy 208.590577 -23.22099) (xy 208.550688 -23.422808)
			(xy 208.502956 -23.622917) (xy 208.447453 -23.821011) (xy 208.384263 -24.016789) (xy 208.313482 -24.209952)
			(xy 208.23522 -24.400207) (xy 208.149593 -24.587263) (xy 208.056734 -24.770836) (xy 207.956783 -24.950646)
			(xy 207.849893 -25.126419) (xy 207.736226 -25.297889) (xy 207.615956 -25.464792) (xy 207.489265 -25.626877)
			(xy 207.356347 -25.783895) (xy 207.217404 -25.935607) (xy 207.072647 -26.081783) (xy 206.922297 -26.2222)
			(xy 206.766584 -26.356643) (xy 206.605743 -26.484909) (xy 206.440021 -26.606802) (xy 206.269668 -26.722137)
			(xy 206.094946 -26.830737) (xy 205.91612 -26.932437) (xy 205.733461 -27.027083) (xy 205.54725 -27.11453)
			(xy 205.357768 -27.194646) (xy 205.165304 -27.267307) (xy 204.970152 -27.332404) (xy 204.772609 -27.389838)
			(xy 204.572976 -27.43952) (xy 204.371556 -27.481375) (xy 204.168656 -27.51534) (xy 203.964586 -27.541363)
			(xy 203.759656 -27.559404) (xy 203.554178 -27.569436) (xy 203.348465 -27.571443) (xy 203.14283 -27.565423)
			(xy 202.937587 -27.551384) (xy 202.733048 -27.529347) (xy 202.529524 -27.499348) (xy 202.327326 -27.46143)
			(xy 202.126761 -27.415653) (xy 201.928135 -27.362085) (xy 201.73175 -27.300808) (xy 201.537906 -27.231915)
			(xy 201.346896 -27.155512) (xy 201.159014 -27.071715) (xy 200.974544 -26.980651) (xy 200.793767 -26.88246)
			(xy 200.616959 -26.777289) (xy 200.444389 -26.665301) (xy 200.27632 -26.546664) (xy 200.113007 -26.421561)
			(xy 199.9547 -26.290181) (xy 199.801639 -26.152725) (xy 199.654058 -26.009401) (xy 199.512181 -25.860429)
			(xy 199.376224 -25.706034) (xy 199.246395 -25.546453) (xy 199.122891 -25.381927) (xy 199.0059 -25.212708)
			(xy 198.895601 -25.039054) (xy 198.79216 -24.861228) (xy 198.695737 -24.679502) (xy 198.606477 -24.494152)
			(xy 198.524517 -24.305461) (xy 198.449981 -24.113716) (xy 198.382983 -23.919208) (xy 198.323625 -23.722235)
			(xy 198.271998 -23.523096) (xy 198.228179 -23.322094) (xy 198.192236 -23.119535) (xy 198.164223 -22.915728)
			(xy 198.144184 -22.710984) (xy 198.132148 -22.505614) (xy 198.128134 -22.29993) (xy 100.17125 -22.29993)
			(xy 100.170748 -22.402791) (xy 100.162722 -22.608358) (xy 100.146681 -22.813454) (xy 100.122651 -23.017768)
			(xy 100.090667 -23.22099) (xy 100.050778 -23.422808) (xy 100.003046 -23.622917) (xy 99.947543 -23.821011)
			(xy 99.884353 -24.016789) (xy 99.813572 -24.209952) (xy 99.73531 -24.400207) (xy 99.649683 -24.587263)
			(xy 99.556824 -24.770836) (xy 99.468717 -24.929338) (xy 133.555232 -24.929338) (xy 133.555232 -24.065738)
			(xy 133.555718 -24.038487) (xy 133.563474 -23.984539) (xy 133.578829 -23.932244) (xy 133.601471 -23.882667)
			(xy 133.630937 -23.836817) (xy 133.666628 -23.795626) (xy 133.707819 -23.759935) (xy 133.753669 -23.730469)
			(xy 133.803246 -23.707827) (xy 133.855541 -23.692472) (xy 133.909489 -23.684716) (xy 133.963991 -23.684716)
			(xy 134.017939 -23.692472) (xy 134.070234 -23.707827) (xy 134.119811 -23.730469) (xy 134.165661 -23.759935)
			(xy 134.206852 -23.795626) (xy 134.242543 -23.836817) (xy 134.272009 -23.882667) (xy 134.294651 -23.932244)
			(xy 134.310006 -23.984539) (xy 134.317762 -24.038487) (xy 134.318248 -24.065738) (xy 134.318248 -24.929338)
			(xy 134.317762 -24.956589) (xy 134.310006 -25.010537) (xy 134.294651 -25.062832) (xy 134.272009 -25.112409)
			(xy 134.242543 -25.158259) (xy 134.206852 -25.19945) (xy 134.165661 -25.235141) (xy 134.119811 -25.264607)
			(xy 134.070234 -25.287249) (xy 134.017939 -25.302604) (xy 133.963991 -25.31036) (xy 133.909489 -25.31036)
			(xy 133.855541 -25.302604) (xy 133.803246 -25.287249) (xy 133.753669 -25.264607) (xy 133.707819 -25.235141)
			(xy 133.666628 -25.19945) (xy 133.630937 -25.158259) (xy 133.601471 -25.112409) (xy 133.578829 -25.062832)
			(xy 133.563474 -25.010537) (xy 133.555718 -24.956589) (xy 133.555232 -24.929338) (xy 99.468717 -24.929338)
			(xy 99.456873 -24.950646) (xy 99.349983 -25.126419) (xy 99.236316 -25.297889) (xy 99.116046 -25.464792)
			(xy 98.989355 -25.626877) (xy 98.856437 -25.783895) (xy 98.717494 -25.935607) (xy 98.572737 -26.081783)
			(xy 98.422387 -26.2222) (xy 98.266674 -26.356643) (xy 98.105833 -26.484909) (xy 97.940111 -26.606802)
			(xy 97.769758 -26.722137) (xy 97.595036 -26.830737) (xy 97.41621 -26.932437) (xy 97.233551 -27.027083)
			(xy 97.04734 -27.11453) (xy 96.857858 -27.194646) (xy 96.665394 -27.267307) (xy 96.470242 -27.332404)
			(xy 96.272699 -27.389838) (xy 96.073066 -27.43952) (xy 95.871646 -27.481375) (xy 95.668746 -27.51534)
			(xy 95.464676 -27.541363) (xy 95.259746 -27.559404) (xy 95.054268 -27.569436) (xy 94.848555 -27.571443)
			(xy 94.64292 -27.565423) (xy 94.437677 -27.551384) (xy 94.233138 -27.529347) (xy 94.029614 -27.499348)
			(xy 93.827416 -27.46143) (xy 93.626851 -27.415653) (xy 93.428225 -27.362085) (xy 93.23184 -27.300808)
			(xy 93.037996 -27.231915) (xy 92.846986 -27.155512) (xy 92.659104 -27.071715) (xy 92.474634 -26.980651)
			(xy 92.293857 -26.88246) (xy 92.117049 -26.777289) (xy 91.944479 -26.665301) (xy 91.77641 -26.546664)
			(xy 91.613097 -26.421561) (xy 91.45479 -26.290181) (xy 91.301729 -26.152725) (xy 91.154148 -26.009401)
			(xy 91.012271 -25.860429) (xy 90.876314 -25.706034) (xy 90.746485 -25.546453) (xy 90.622981 -25.381927)
			(xy 90.50599 -25.212708) (xy 90.395691 -25.039054) (xy 90.29225 -24.861228) (xy 90.195827 -24.679502)
			(xy 90.106567 -24.494152) (xy 90.024607 -24.305461) (xy 89.950071 -24.113716) (xy 89.883073 -23.919208)
			(xy 89.823715 -23.722235) (xy 89.772088 -23.523096) (xy 89.728269 -23.322094) (xy 89.692326 -23.119535)
			(xy 89.664313 -22.915728) (xy 89.644274 -22.710984) (xy 89.632238 -22.505614) (xy 89.628224 -22.29993)
			(xy 12.271248 -22.29993) (xy 12.270746 -22.402791) (xy 12.26272 -22.608358) (xy 12.246679 -22.813454)
			(xy 12.222649 -23.017768) (xy 12.190665 -23.22099) (xy 12.150776 -23.422808) (xy 12.103044 -23.622917)
			(xy 12.047541 -23.821011) (xy 11.984351 -24.016789) (xy 11.91357 -24.209952) (xy 11.835308 -24.400207)
			(xy 11.749681 -24.587263) (xy 11.656822 -24.770836) (xy 11.556871 -24.950646) (xy 11.449981 -25.126419)
			(xy 11.336314 -25.297889) (xy 11.216044 -25.464792) (xy 11.089353 -25.626877) (xy 10.956435 -25.783895)
			(xy 10.817492 -25.935607) (xy 10.672735 -26.081783) (xy 10.522385 -26.2222) (xy 10.366672 -26.356643)
			(xy 10.205831 -26.484909) (xy 10.040109 -26.606802) (xy 9.869756 -26.722137) (xy 9.695034 -26.830737)
			(xy 9.516208 -26.932437) (xy 9.333549 -27.027083) (xy 9.147338 -27.11453) (xy 8.957856 -27.194646)
			(xy 8.765392 -27.267307) (xy 8.57024 -27.332404) (xy 8.372697 -27.389838) (xy 8.173064 -27.43952)
			(xy 7.971644 -27.481375) (xy 7.768744 -27.51534) (xy 7.564674 -27.541363) (xy 7.359744 -27.559404)
			(xy 7.154266 -27.569436) (xy 6.948553 -27.571443) (xy 6.742918 -27.565423) (xy 6.537675 -27.551384)
			(xy 6.333136 -27.529347) (xy 6.129612 -27.499348) (xy 5.927414 -27.46143) (xy 5.726849 -27.415653)
			(xy 5.528223 -27.362085) (xy 5.331838 -27.300808) (xy 5.137994 -27.231915) (xy 4.946984 -27.155512)
			(xy 4.759102 -27.071715) (xy 4.574632 -26.980651) (xy 4.393855 -26.88246) (xy 4.217047 -26.777289)
			(xy 4.044477 -26.665301) (xy 3.876408 -26.546664) (xy 3.713095 -26.421561) (xy 3.554788 -26.290181)
			(xy 3.401727 -26.152725) (xy 3.254146 -26.009401) (xy 3.112269 -25.860429) (xy 2.976312 -25.706034)
			(xy 2.846483 -25.546453) (xy 2.722979 -25.381927) (xy 2.605988 -25.212708) (xy 2.495689 -25.039054)
			(xy 2.392248 -24.861228) (xy 2.295825 -24.679502) (xy 2.206565 -24.494152) (xy 2.124605 -24.305461)
			(xy 2.050069 -24.113716) (xy 1.983071 -23.919208) (xy 1.923713 -23.722235) (xy 1.872086 -23.523096)
			(xy 1.828267 -23.322094) (xy 1.792324 -23.119535) (xy 1.764311 -22.915728) (xy 1.744272 -22.710984)
			(xy 1.732236 -22.505614) (xy 1.728222 -22.29993) (xy 1.524 -22.29993) (xy 1.524 -29.070615) (xy 12.244307 -29.070615)
			(xy 12.252198 -28.941486) (xy 12.268182 -28.813107) (xy 12.292195 -28.685984) (xy 12.324144 -28.560621)
			(xy 12.363901 -28.437511) (xy 12.41131 -28.31714) (xy 12.466183 -28.199984) (xy 12.528305 -28.086504)
			(xy 12.59743 -27.97715) (xy 12.673285 -27.872351) (xy 12.75557 -27.772522) (xy 12.843962 -27.678057)
			(xy 12.938111 -27.589329) (xy 13.037646 -27.506688) (xy 13.142173 -27.43046) (xy 13.25128 -27.360945)
			(xy 13.364537 -27.298419) (xy 13.481497 -27.243128) (xy 13.601698 -27.19529) (xy 13.724665 -27.155093)
			(xy 13.849914 -27.122698) (xy 13.97695 -27.098231) (xy 14.105271 -27.081789) (xy 14.234372 -27.073437)
			(xy 14.363742 -27.073208) (xy 14.492871 -27.081103) (xy 14.62125 -27.097091) (xy 14.748372 -27.121108)
			(xy 14.873734 -27.15306) (xy 14.996843 -27.19282) (xy 15.117212 -27.240232) (xy 15.234367 -27.295109)
			(xy 15.347845 -27.357234) (xy 15.457198 -27.426362) (xy 15.561994 -27.50222) (xy 15.661821 -27.584508)
			(xy 15.709392 -27.628342) (xy 16.877792 -28.721304) (xy 16.92464 -28.765906) (xy 17.013363 -28.860052)
			(xy 17.096 -28.959584) (xy 17.172224 -29.064107) (xy 17.241734 -29.17321) (xy 17.304257 -29.286463)
			(xy 17.359545 -29.403418) (xy 17.407381 -29.523614) (xy 17.447575 -29.646576) (xy 17.479969 -29.771819)
			(xy 17.504435 -29.898849) (xy 17.520877 -30.027165) (xy 17.529229 -30.15626) (xy 17.529459 -30.285624)
			(xy 17.521566 -30.414748) (xy 17.50558 -30.543122) (xy 17.481566 -30.670238) (xy 17.449617 -30.795596)
			(xy 17.40986 -30.9187) (xy 17.362452 -31.039065) (xy 17.30758 -31.156215) (xy 17.24546 -31.26969)
			(xy 17.176338 -31.379039) (xy 17.100486 -31.483833) (xy 17.018204 -31.583657) (xy 16.929816 -31.678118)
			(xy 16.835671 -31.766843) (xy 16.736141 -31.849481) (xy 16.631619 -31.925706) (xy 16.522517 -31.995218)
			(xy 16.409265 -32.057743) (xy 16.292311 -32.113033) (xy 16.172116 -32.16087) (xy 16.049154 -32.201066)
			(xy 15.923911 -32.233462) (xy 15.796882 -32.25793) (xy 15.668566 -32.274374) (xy 15.539471 -32.282728)
			(xy 15.410107 -32.28296) (xy 15.280983 -32.275069) (xy 15.152609 -32.259085) (xy 15.025493 -32.235073)
			(xy 14.900134 -32.203126) (xy 14.77703 -32.163371) (xy 14.656664 -32.115965) (xy 14.539512 -32.061094)
			(xy 14.426037 -31.998976) (xy 14.316687 -31.929855) (xy 14.211892 -31.854005) (xy 14.112066 -31.771724)
			(xy 14.064488 -31.727902) (xy 12.896088 -30.63494) (xy 12.849198 -30.590378) (xy 12.760467 -30.496232)
			(xy 12.677823 -30.3967) (xy 12.601592 -30.292174) (xy 12.532074 -30.183069) (xy 12.469545 -30.069814)
			(xy 12.41425 -29.952855) (xy 12.366409 -29.832656) (xy 12.32621 -29.70969) (xy 12.293811 -29.584442)
			(xy 12.26934 -29.457407) (xy 12.252895 -29.329086) (xy 12.244539 -29.199985) (xy 12.244307 -29.070615)
			(xy 1.524 -29.070615) (xy 1.524 -43.999912) (xy 16.983969 -43.999912) (xy 16.987993 -43.914144) (xy 17.000031 -43.82913)
			(xy 17.019978 -43.745616) (xy 17.047657 -43.664337) (xy 17.082825 -43.586008) (xy 17.125174 -43.511315)
			(xy 17.174331 -43.440917) (xy 17.229864 -43.375431) (xy 17.291286 -43.315433) (xy 17.358055 -43.26145)
			(xy 17.429587 -43.213957) (xy 17.505251 -43.173371) (xy 17.584384 -43.140048) (xy 17.666289 -43.114282)
			(xy 17.750247 -43.096299) (xy 17.835521 -43.086257) (xy 17.92136 -43.084244) (xy 18.00701 -43.090278)
			(xy 18.091718 -43.104306) (xy 18.174741 -43.126205) (xy 18.255349 -43.155782) (xy 18.332833 -43.192777)
			(xy 18.406512 -43.236865) (xy 18.475738 -43.287659) (xy 18.539905 -43.344712) (xy 18.598446 -43.407523)
			(xy 18.650849 -43.47554) (xy 18.696652 -43.548165) (xy 18.735453 -43.62476) (xy 18.766912 -43.704652)
			(xy 18.790751 -43.787139) (xy 18.806761 -43.871496) (xy 18.814801 -43.956981) (xy 18.815304 -43.999912)
			(xy 18.814801 -44.042843) (xy 18.806761 -44.128328) (xy 18.790751 -44.212685) (xy 18.766912 -44.295172)
			(xy 18.735453 -44.375064) (xy 18.696652 -44.451659) (xy 18.650849 -44.524284) (xy 18.598446 -44.592301)
			(xy 18.539905 -44.655112) (xy 18.475738 -44.712165) (xy 18.406512 -44.762959) (xy 18.332833 -44.807047)
			(xy 18.255349 -44.844042) (xy 18.174741 -44.873619) (xy 18.091718 -44.895518) (xy 18.00701 -44.909546)
			(xy 17.92136 -44.91558) (xy 17.835521 -44.913567) (xy 17.750247 -44.903525) (xy 17.666289 -44.885542)
			(xy 17.584384 -44.859776) (xy 17.505251 -44.826453) (xy 17.429587 -44.785867) (xy 17.358055 -44.738374)
			(xy 17.291286 -44.684391) (xy 17.229864 -44.624393) (xy 17.174331 -44.558907) (xy 17.125174 -44.488509)
			(xy 17.082825 -44.413816) (xy 17.047657 -44.335487) (xy 17.019978 -44.254208) (xy 17.000031 -44.170694)
			(xy 16.987993 -44.08568) (xy 16.983969 -43.999912) (xy 1.524 -43.999912) (xy 1.524 -59.99988) (xy 16.983969 -59.99988)
			(xy 16.987993 -59.914112) (xy 17.000031 -59.829098) (xy 17.019978 -59.745584) (xy 17.047657 -59.664305)
			(xy 17.082825 -59.585976) (xy 17.125174 -59.511283) (xy 17.174331 -59.440885) (xy 17.229864 -59.375399)
			(xy 17.291286 -59.315401) (xy 17.358055 -59.261418) (xy 17.429587 -59.213925) (xy 17.505251 -59.173339)
			(xy 17.584384 -59.140016) (xy 17.666289 -59.11425) (xy 17.750247 -59.096267) (xy 17.835521 -59.086225)
			(xy 17.92136 -59.084212) (xy 18.00701 -59.090246) (xy 18.091718 -59.104274) (xy 18.174741 -59.126173)
			(xy 18.255349 -59.15575) (xy 18.332833 -59.192745) (xy 18.406512 -59.236833) (xy 18.475738 -59.287627)
			(xy 18.539905 -59.34468) (xy 18.598446 -59.407491) (xy 18.650849 -59.475508) (xy 18.696652 -59.548133)
			(xy 18.735453 -59.624728) (xy 18.766912 -59.70462) (xy 18.790751 -59.787107) (xy 18.806761 -59.871464)
			(xy 18.814801 -59.956949) (xy 18.815304 -59.99988) (xy 18.814801 -60.042811) (xy 18.806761 -60.128296)
			(xy 18.790751 -60.212653) (xy 18.766912 -60.29514) (xy 18.735453 -60.375032) (xy 18.696652 -60.451627)
			(xy 18.650849 -60.524252) (xy 18.598446 -60.592269) (xy 18.539905 -60.65508) (xy 18.475738 -60.712133)
			(xy 18.406512 -60.762927) (xy 18.332833 -60.807015) (xy 18.255349 -60.84401) (xy 18.174741 -60.873587)
			(xy 18.091718 -60.895486) (xy 18.00701 -60.909514) (xy 17.92136 -60.915548) (xy 17.835521 -60.913535)
			(xy 17.750247 -60.903493) (xy 17.666289 -60.88551) (xy 17.584384 -60.859744) (xy 17.505251 -60.826421)
			(xy 17.429587 -60.785835) (xy 17.358055 -60.738342) (xy 17.291286 -60.684359) (xy 17.229864 -60.624361)
			(xy 17.174331 -60.558875) (xy 17.125174 -60.488477) (xy 17.082825 -60.413784) (xy 17.047657 -60.335455)
			(xy 17.019978 -60.254176) (xy 17.000031 -60.170662) (xy 16.987993 -60.085648) (xy 16.983969 -59.99988)
			(xy 1.524 -59.99988) (xy 1.524 -77.671676) (xy 1.524528 -77.702818) (xy 1.532691 -77.764566) (xy 1.548839 -77.824722)
			(xy 1.572695 -77.882257) (xy 1.603853 -77.936189) (xy 1.64178 -77.985596) (xy 1.663446 -78.007972)
			(xy 2.491994 -78.83652) (xy 2.552767 -78.898052) (xy 2.668915 -79.026219) (xy 2.778636 -79.15993)
			(xy 2.881665 -79.298863) (xy 2.977754 -79.442682) (xy 3.066672 -79.591043) (xy 3.148205 -79.743587)
			(xy 3.222155 -79.899947) (xy 3.288346 -80.059747) (xy 3.346618 -80.222601) (xy 3.39683 -80.388119)
			(xy 3.438862 -80.5559) (xy 3.472612 -80.725541) (xy 3.497999 -80.896634) (xy 3.514962 -81.068766)
			(xy 3.52346 -81.241523) (xy 3.523996 -81.328006) (xy 3.523996 -85.764678) (xy 10.421355 -85.764678)
			(xy 10.421355 -85.635538) (xy 10.429305 -85.506643) (xy 10.445175 -85.378483) (xy 10.468904 -85.251542)
			(xy 10.500403 -85.126303) (xy 10.539552 -85.00324) (xy 10.586203 -84.882821) (xy 10.640178 -84.765502)
			(xy 10.701273 -84.651728) (xy 10.769256 -84.541931) (xy 10.84387 -84.436528) (xy 10.924831 -84.335918)
			(xy 11.011831 -84.240483) (xy 11.104542 -84.150584) (xy 11.202612 -84.066563) (xy 11.305667 -83.988739)
			(xy 11.413318 -83.917407) (xy 11.525157 -83.852837) (xy 11.640758 -83.795275) (xy 11.759683 -83.744938)
			(xy 11.881482 -83.702018) (xy 12.005692 -83.666677) (xy 12.131841 -83.63905) (xy 12.259453 -83.619241)
			(xy 12.388042 -83.607325) (xy 12.51712 -83.603349) (xy 12.646198 -83.607325) (xy 12.774787 -83.619241)
			(xy 12.902399 -83.63905) (xy 13.028548 -83.666677) (xy 13.152758 -83.702018) (xy 13.274557 -83.744938)
			(xy 13.393482 -83.795275) (xy 13.509083 -83.852837) (xy 13.620922 -83.917407) (xy 13.728573 -83.988739)
			(xy 13.831628 -84.066563) (xy 13.929698 -84.150584) (xy 14.022409 -84.240483) (xy 14.109409 -84.335918)
			(xy 14.19037 -84.436528) (xy 14.264984 -84.541931) (xy 14.332967 -84.651728) (xy 14.394062 -84.765502)
			(xy 14.448037 -84.882821) (xy 14.494688 -85.00324) (xy 14.533837 -85.126303) (xy 14.565336 -85.251542)
			(xy 14.589065 -85.378483) (xy 14.604935 -85.506643) (xy 14.612885 -85.635538) (xy 14.613382 -85.700108)
			(xy 14.612885 -85.764678) (xy 14.604935 -85.893573) (xy 14.589065 -86.021733) (xy 14.565336 -86.148674)
			(xy 14.533837 -86.273913) (xy 14.494688 -86.396976) (xy 14.448037 -86.517395) (xy 14.394062 -86.634714)
			(xy 14.332967 -86.748488) (xy 14.264984 -86.858285) (xy 14.19037 -86.963688) (xy 14.109409 -87.064298)
			(xy 14.022409 -87.159733) (xy 13.929698 -87.249632) (xy 13.831628 -87.333653) (xy 13.728573 -87.411477)
			(xy 13.620922 -87.482809) (xy 13.509083 -87.547379) (xy 13.393482 -87.604941) (xy 13.274557 -87.655278)
			(xy 13.152758 -87.698198) (xy 13.028548 -87.733539) (xy 12.902399 -87.761166) (xy 12.774787 -87.780975)
			(xy 12.646198 -87.792891) (xy 12.51712 -87.796868) (xy 12.388042 -87.792891) (xy 12.259453 -87.780975)
			(xy 12.131841 -87.761166) (xy 12.005692 -87.733539) (xy 11.881482 -87.698198) (xy 11.759683 -87.655278)
			(xy 11.640758 -87.604941) (xy 11.525157 -87.547379) (xy 11.413318 -87.482809) (xy 11.305667 -87.411477)
			(xy 11.202612 -87.333653) (xy 11.104542 -87.249632) (xy 11.011831 -87.159733) (xy 10.924831 -87.064298)
			(xy 10.84387 -86.963688) (xy 10.769256 -86.858285) (xy 10.701273 -86.748488) (xy 10.640178 -86.634714)
			(xy 10.586203 -86.517395) (xy 10.539552 -86.396976) (xy 10.500403 -86.273913) (xy 10.468904 -86.148674)
			(xy 10.445175 -86.021733) (xy 10.429305 -85.893573) (xy 10.421355 -85.764678) (xy 3.523996 -85.764678)
			(xy 3.523996 -106.40187) (xy 11.713464 -106.40187) (xy 11.713464 -105.53827) (xy 11.71395 -105.511001)
			(xy 11.721712 -105.457017) (xy 11.737077 -105.404687) (xy 11.759734 -105.355077) (xy 11.78922 -105.309196)
			(xy 11.824935 -105.267979) (xy 11.866152 -105.232264) (xy 11.912033 -105.202778) (xy 11.961643 -105.180121)
			(xy 12.013973 -105.164756) (xy 12.067957 -105.156994) (xy 12.122495 -105.156994) (xy 12.176479 -105.164756)
			(xy 12.228809 -105.180121) (xy 12.278419 -105.202778) (xy 12.3243 -105.232264) (xy 12.365517 -105.267979)
			(xy 12.401232 -105.309196) (xy 12.430718 -105.355077) (xy 12.453375 -105.404687) (xy 12.46874 -105.457017)
			(xy 12.476502 -105.511001) (xy 12.476988 -105.53827) (xy 12.476988 -105.664) (xy 15.57274 -105.664)
			(xy 15.57274 -104.8004) (xy 15.573226 -104.773131) (xy 15.580988 -104.719147) (xy 15.596353 -104.666817)
			(xy 15.61901 -104.617207) (xy 15.648496 -104.571326) (xy 15.684211 -104.530109) (xy 15.725428 -104.494394)
			(xy 15.771309 -104.464908) (xy 15.820919 -104.442251) (xy 15.873249 -104.426886) (xy 15.927233 -104.419124)
			(xy 15.981771 -104.419124) (xy 16.035755 -104.426886) (xy 16.088085 -104.442251) (xy 16.137695 -104.464908)
			(xy 16.183576 -104.494394) (xy 16.224793 -104.530109) (xy 16.260508 -104.571326) (xy 16.289994 -104.617207)
			(xy 16.312651 -104.666817) (xy 16.328016 -104.719147) (xy 16.335778 -104.773131) (xy 16.336264 -104.8004)
			(xy 16.336264 -105.664) (xy 16.335778 -105.691269) (xy 16.328016 -105.745253) (xy 16.312651 -105.797583)
			(xy 16.289994 -105.847193) (xy 16.260508 -105.893074) (xy 16.224793 -105.934291) (xy 16.183576 -105.970006)
			(xy 16.137695 -105.999492) (xy 16.088085 -106.022149) (xy 16.035755 -106.037514) (xy 15.981771 -106.045276)
			(xy 15.927233 -106.045276) (xy 15.873249 -106.037514) (xy 15.820919 -106.022149) (xy 15.771309 -105.999492)
			(xy 15.725428 -105.970006) (xy 15.684211 -105.934291) (xy 15.648496 -105.893074) (xy 15.61901 -105.847193)
			(xy 15.596353 -105.797583) (xy 15.580988 -105.745253) (xy 15.573226 -105.691269) (xy 15.57274 -105.664)
			(xy 12.476988 -105.664) (xy 12.476988 -106.40187) (xy 12.476502 -106.429139) (xy 12.46874 -106.483123)
			(xy 12.453375 -106.535453) (xy 12.430718 -106.585063) (xy 12.401232 -106.630944) (xy 12.365517 -106.672161)
			(xy 12.3243 -106.707876) (xy 12.278419 -106.737362) (xy 12.228809 -106.760019) (xy 12.176479 -106.775384)
			(xy 12.122495 -106.783146) (xy 12.067957 -106.783146) (xy 12.013973 -106.775384) (xy 11.961643 -106.760019)
			(xy 11.912033 -106.737362) (xy 11.866152 -106.707876) (xy 11.824935 -106.672161) (xy 11.78922 -106.630944)
			(xy 11.759734 -106.585063) (xy 11.737077 -106.535453) (xy 11.721712 -106.483123) (xy 11.71395 -106.429139)
			(xy 11.713464 -106.40187) (xy 3.523996 -106.40187) (xy 3.523996 -108.943971) (xy 11.292822 -108.943971)
			(xy 11.292822 -108.889469) (xy 11.300578 -108.835522) (xy 11.315933 -108.783228) (xy 11.338574 -108.733651)
			(xy 11.36804 -108.687801) (xy 11.403731 -108.646611) (xy 11.444921 -108.61092) (xy 11.490771 -108.581454)
			(xy 11.540348 -108.558813) (xy 11.592642 -108.543458) (xy 11.646589 -108.535702) (xy 11.67384 -108.535216)
			(xy 12.53744 -108.535216) (xy 12.564692 -108.535694) (xy 12.61864 -108.54345) (xy 12.670935 -108.558806)
			(xy 12.720513 -108.581447) (xy 12.766364 -108.610914) (xy 12.807554 -108.646606) (xy 12.843246 -108.687796)
			(xy 12.872713 -108.733647) (xy 12.895354 -108.783225) (xy 12.91071 -108.83552) (xy 12.918466 -108.889468)
			(xy 12.918466 -108.943972) (xy 12.918466 -108.943973) (xy 15.156389 -108.943973) (xy 15.156389 -108.889467)
			(xy 15.164146 -108.835517) (xy 15.179502 -108.783219) (xy 15.202145 -108.733639) (xy 15.231613 -108.687786)
			(xy 15.267307 -108.646594) (xy 15.308499 -108.610901) (xy 15.354353 -108.581433) (xy 15.403933 -108.558791)
			(xy 15.45623 -108.543435) (xy 15.510181 -108.535679) (xy 15.537434 -108.535216) (xy 16.401034 -108.535216)
			(xy 16.428285 -108.535694) (xy 16.482233 -108.543451) (xy 16.534528 -108.558807) (xy 16.584105 -108.581448)
			(xy 16.629956 -108.610915) (xy 16.671146 -108.646607) (xy 16.706837 -108.687798) (xy 16.736304 -108.733648)
			(xy 16.758945 -108.783226) (xy 16.7743 -108.835521) (xy 16.782056 -108.889469) (xy 16.782056 -108.943971)
			(xy 16.7743 -108.997919) (xy 16.758945 -109.050214) (xy 16.736304 -109.099792) (xy 16.706837 -109.145642)
			(xy 16.671146 -109.186833) (xy 16.629956 -109.222525) (xy 16.584105 -109.251992) (xy 16.534528 -109.274633)
			(xy 16.482233 -109.289989) (xy 16.428285 -109.297746) (xy 16.401034 -109.298232) (xy 15.537434 -109.298232)
			(xy 15.510181 -109.297761) (xy 15.45623 -109.290005) (xy 15.403933 -109.274649) (xy 15.354353 -109.252007)
			(xy 15.308499 -109.222539) (xy 15.267307 -109.186846) (xy 15.231613 -109.145654) (xy 15.202145 -109.099801)
			(xy 15.179502 -109.050221) (xy 15.164146 -108.997923) (xy 15.156389 -108.943973) (xy 12.918466 -108.943973)
			(xy 12.91071 -108.99792) (xy 12.895354 -109.050215) (xy 12.872713 -109.099793) (xy 12.843246 -109.145644)
			(xy 12.807554 -109.186834) (xy 12.766364 -109.222526) (xy 12.720513 -109.251993) (xy 12.670935 -109.274634)
			(xy 12.61864 -109.28999) (xy 12.564692 -109.297746) (xy 12.53744 -109.298232) (xy 11.67384 -109.298232)
			(xy 11.646589 -109.297738) (xy 11.592642 -109.289982) (xy 11.540348 -109.274627) (xy 11.490771 -109.251986)
			(xy 11.444921 -109.22252) (xy 11.403731 -109.186829) (xy 11.36804 -109.145639) (xy 11.338574 -109.099789)
			(xy 11.315933 -109.050212) (xy 11.300578 -108.997918) (xy 11.292822 -108.943971) (xy 3.523996 -108.943971)
			(xy 3.523996 -114.734161) (xy 11.255226 -114.734161) (xy 11.255226 -114.679659) (xy 11.262982 -114.625711)
			(xy 11.278337 -114.573416) (xy 11.300979 -114.523839) (xy 11.330445 -114.477988) (xy 11.366136 -114.436798)
			(xy 11.407326 -114.401106) (xy 11.453177 -114.371639) (xy 11.502754 -114.348998) (xy 11.555049 -114.333643)
			(xy 11.608997 -114.325886) (xy 11.636248 -114.3254) (xy 12.499848 -114.3254) (xy 12.527101 -114.325867)
			(xy 12.581052 -114.333624) (xy 12.633349 -114.34898) (xy 12.68293 -114.371622) (xy 12.728783 -114.40109)
			(xy 12.769975 -114.436783) (xy 12.805669 -114.477976) (xy 12.835137 -114.523829) (xy 12.85778 -114.573409)
			(xy 12.873136 -114.625706) (xy 12.880893 -114.679657) (xy 12.880893 -114.734163) (xy 12.873136 -114.788114)
			(xy 12.85778 -114.840411) (xy 12.835137 -114.889991) (xy 12.805669 -114.935844) (xy 12.769975 -114.977037)
			(xy 12.728783 -115.01273) (xy 12.68293 -115.042198) (xy 12.633349 -115.06484) (xy 12.581052 -115.080196)
			(xy 12.527101 -115.087953) (xy 12.499848 -115.088416) (xy 11.636248 -115.088416) (xy 11.608997 -115.087934)
			(xy 11.555049 -115.080177) (xy 11.502754 -115.064822) (xy 11.453177 -115.042181) (xy 11.407326 -115.012714)
			(xy 11.366136 -114.977022) (xy 11.330445 -114.935832) (xy 11.300979 -114.889981) (xy 11.278337 -114.840404)
			(xy 11.262982 -114.788109) (xy 11.255226 -114.734161) (xy 3.523996 -114.734161) (xy 3.523996 -126.774448)
			(xy 24.95296 -126.774448) (xy 24.95296 -44.882308) (xy 24.953504 -44.857346) (xy 24.96324 -44.808381)
			(xy 24.982358 -44.762263) (xy 25.01012 -44.72077) (xy 25.027382 -44.70273) (xy 32.423862 -37.30625)
			(xy 32.441918 -37.28901) (xy 32.483415 -37.261268) (xy 32.529527 -37.242155) (xy 32.578482 -37.232405)
			(xy 32.60344 -37.231828) (xy 91.408504 -37.231828) (xy 96.955356 -31.684976) (xy 96.949514 -31.657798)
			(xy 96.94557 -31.638032) (xy 96.941368 -31.597943) (xy 96.941132 -31.577788) (xy 96.941544 -31.550533)
			(xy 96.949303 -31.496578) (xy 96.964663 -31.444277) (xy 96.98731 -31.394694) (xy 97.016783 -31.348839)
			(xy 97.052482 -31.307645) (xy 97.093681 -31.271952) (xy 97.13954 -31.242485) (xy 97.189126 -31.219845)
			(xy 97.241429 -31.204492) (xy 97.295385 -31.19674) (xy 97.32264 -31.19628) (xy 97.349611 -31.19671)
			(xy 97.403026 -31.204227) (xy 97.429066 -31.211266) (xy 97.435162 -31.20517) (xy 97.453221 -31.187933)
			(xy 97.494717 -31.16019) (xy 97.540828 -31.141076) (xy 97.589782 -31.131325) (xy 97.61474 -31.130748)
			(xy 139.629896 -31.130748) (xy 139.637516 -31.089092) (xy 139.643084 -31.061765) (xy 139.661096 -31.008987)
			(xy 139.6866 -30.959394) (xy 139.719052 -30.914042) (xy 139.757761 -30.873898) (xy 139.801902 -30.839817)
			(xy 139.850535 -30.812525) (xy 139.902623 -30.792605) (xy 139.957056 -30.780481) (xy 140.012674 -30.776411)
			(xy 140.068292 -30.780481) (xy 140.122725 -30.792605) (xy 140.174813 -30.812525) (xy 140.223446 -30.839817)
			(xy 140.267587 -30.873898) (xy 140.306296 -30.914042) (xy 140.338748 -30.959394) (xy 140.364252 -31.008987)
			(xy 140.382264 -31.061765) (xy 140.387832 -31.089092) (xy 140.395452 -31.130748) (xy 160.5788 -31.130748)
			(xy 160.603762 -31.13129) (xy 160.652727 -31.141027) (xy 160.698845 -31.160146) (xy 160.740338 -31.187908)
			(xy 160.758378 -31.20517) (xy 161.850578 -32.29737) (xy 161.867795 -32.315444) (xy 161.89553 -32.356938)
			(xy 161.914637 -32.403045) (xy 161.924384 -32.451993) (xy 161.925 -32.476948) (xy 161.925 -37.099629)
			(xy 170.600616 -37.099629) (xy 170.600616 -37.000299) (xy 170.608608 -36.901292) (xy 170.624542 -36.803249)
			(xy 170.648313 -36.706806) (xy 170.679768 -36.612588) (xy 170.718701 -36.521208) (xy 170.764862 -36.433256)
			(xy 170.81795 -36.349304) (xy 170.877621 -36.269895) (xy 170.943489 -36.195546) (xy 171.015126 -36.126738)
			(xy 171.092067 -36.063918) (xy 171.173813 -36.007493) (xy 171.259835 -35.957828) (xy 171.349574 -35.915246)
			(xy 171.442448 -35.880024) (xy 171.537856 -35.852388) (xy 171.635178 -35.83252) (xy 171.733783 -35.820547)
			(xy 171.833032 -35.816548) (xy 171.932281 -35.820547) (xy 172.030886 -35.83252) (xy 172.128208 -35.852388)
			(xy 172.223616 -35.880024) (xy 172.31649 -35.915246) (xy 172.406229 -35.957828) (xy 172.492251 -36.007493)
			(xy 172.573997 -36.063918) (xy 172.650938 -36.126738) (xy 172.722575 -36.195546) (xy 172.788443 -36.269895)
			(xy 172.848114 -36.349304) (xy 172.901202 -36.433256) (xy 172.947363 -36.521208) (xy 172.986296 -36.612588)
			(xy 173.017751 -36.706806) (xy 173.041522 -36.803249) (xy 173.057456 -36.901292) (xy 173.065448 -37.000299)
			(xy 173.065948 -37.049964) (xy 173.065448 -37.099629) (xy 173.057456 -37.198636) (xy 173.041522 -37.296679)
			(xy 173.017751 -37.393122) (xy 172.986296 -37.48734) (xy 172.947363 -37.57872) (xy 172.901202 -37.666672)
			(xy 172.848114 -37.750624) (xy 172.788443 -37.830033) (xy 172.722575 -37.904382) (xy 172.650938 -37.97319)
			(xy 172.573997 -38.03601) (xy 172.492251 -38.092435) (xy 172.406229 -38.1421) (xy 172.31649 -38.184682)
			(xy 172.223616 -38.219904) (xy 172.128208 -38.24754) (xy 172.030886 -38.267408) (xy 171.932281 -38.279381)
			(xy 171.833032 -38.283381) (xy 171.733783 -38.279381) (xy 171.635178 -38.267408) (xy 171.537856 -38.24754)
			(xy 171.442448 -38.219904) (xy 171.349574 -38.184682) (xy 171.259835 -38.1421) (xy 171.173813 -38.092435)
			(xy 171.092067 -38.03601) (xy 171.015126 -37.97319) (xy 170.943489 -37.904382) (xy 170.877621 -37.830033)
			(xy 170.81795 -37.750624) (xy 170.764862 -37.666672) (xy 170.718701 -37.57872) (xy 170.679768 -37.48734)
			(xy 170.648313 -37.393122) (xy 170.624542 -37.296679) (xy 170.608608 -37.198636) (xy 170.600616 -37.099629)
			(xy 161.925 -37.099629) (xy 161.925 -40.744902) (xy 235.083357 -40.744902) (xy 235.087362 -40.656994)
			(xy 235.099345 -40.569814) (xy 235.119205 -40.484085) (xy 235.14678 -40.400517) (xy 235.181839 -40.319803)
			(xy 235.224092 -40.242611) (xy 235.27319 -40.169582) (xy 235.328726 -40.10132) (xy 235.390238 -40.03839)
			(xy 235.457219 -39.981316) (xy 235.529112 -39.930568) (xy 235.605321 -39.886568) (xy 235.685216 -39.849681)
			(xy 235.768135 -39.820212) (xy 235.85339 -39.798405) (xy 235.940274 -39.784441) (xy 236.028068 -39.778435)
			(xy 236.116045 -39.780439) (xy 236.203475 -39.790434) (xy 236.289634 -39.808338) (xy 236.373808 -39.834002)
			(xy 236.455299 -39.867215) (xy 236.533433 -39.907701) (xy 236.607561 -39.955123) (xy 236.677069 -40.00909)
			(xy 236.741383 -40.069155) (xy 236.799967 -40.134819) (xy 236.852338 -40.205538) (xy 236.898061 -40.280726)
			(xy 236.936758 -40.359761) (xy 236.968107 -40.441987) (xy 236.991849 -40.526723) (xy 237.007787 -40.613267)
			(xy 237.015789 -40.700902) (xy 237.01629 -40.744902) (xy 237.015789 -40.788902) (xy 237.007787 -40.876537)
			(xy 236.991849 -40.963081) (xy 236.968107 -41.047817) (xy 236.936758 -41.130043) (xy 236.898061 -41.209078)
			(xy 236.852338 -41.284266) (xy 236.799967 -41.354985) (xy 236.741383 -41.420649) (xy 236.677069 -41.480714)
			(xy 236.607561 -41.534681) (xy 236.533433 -41.582103) (xy 236.455299 -41.622589) (xy 236.373808 -41.655802)
			(xy 236.289634 -41.681466) (xy 236.203475 -41.69937) (xy 236.116045 -41.709365) (xy 236.028068 -41.711369)
			(xy 235.940274 -41.705363) (xy 235.85339 -41.691399) (xy 235.768135 -41.669592) (xy 235.685216 -41.640123)
			(xy 235.605321 -41.603236) (xy 235.529112 -41.559236) (xy 235.457219 -41.508488) (xy 235.390238 -41.451414)
			(xy 235.328726 -41.388484) (xy 235.27319 -41.320222) (xy 235.224092 -41.247193) (xy 235.181839 -41.170001)
			(xy 235.14678 -41.089287) (xy 235.119205 -41.005719) (xy 235.099345 -40.91999) (xy 235.087362 -40.83281)
			(xy 235.083357 -40.744902) (xy 161.925 -40.744902) (xy 161.925 -43.481752) (xy 178.891692 -43.481752)
			(xy 178.891692 -42.618152) (xy 178.892178 -42.590901) (xy 178.899934 -42.536953) (xy 178.915289 -42.484658)
			(xy 178.937931 -42.435081) (xy 178.967397 -42.389231) (xy 179.003088 -42.34804) (xy 179.044279 -42.312349)
			(xy 179.090129 -42.282883) (xy 179.139706 -42.260241) (xy 179.192001 -42.244886) (xy 179.245949 -42.23713)
			(xy 179.300451 -42.23713) (xy 179.354399 -42.244886) (xy 179.406694 -42.260241) (xy 179.456271 -42.282883)
			(xy 179.502121 -42.312349) (xy 179.543312 -42.34804) (xy 179.579003 -42.389231) (xy 179.608469 -42.435081)
			(xy 179.631111 -42.484658) (xy 179.646466 -42.536953) (xy 179.654222 -42.590901) (xy 179.654708 -42.618152)
			(xy 179.654708 -43.481752) (xy 179.654222 -43.509003) (xy 179.646466 -43.562951) (xy 179.631111 -43.615246)
			(xy 179.608469 -43.664823) (xy 179.579003 -43.710673) (xy 179.543312 -43.751864) (xy 179.502121 -43.787555)
			(xy 179.456271 -43.817021) (xy 179.406694 -43.839663) (xy 179.354399 -43.855018) (xy 179.300451 -43.862774)
			(xy 179.245949 -43.862774) (xy 179.192001 -43.855018) (xy 179.139706 -43.839663) (xy 179.090129 -43.817021)
			(xy 179.044279 -43.787555) (xy 179.003088 -43.751864) (xy 178.967397 -43.710673) (xy 178.937931 -43.664823)
			(xy 178.915289 -43.615246) (xy 178.899934 -43.562951) (xy 178.892178 -43.509003) (xy 178.891692 -43.481752)
			(xy 161.925 -43.481752) (xy 161.925 -44.980098) (xy 181.659784 -44.980098) (xy 181.659784 -44.116498)
			(xy 181.66027 -44.089247) (xy 181.668026 -44.035299) (xy 181.683381 -43.983004) (xy 181.706023 -43.933427)
			(xy 181.735489 -43.887577) (xy 181.77118 -43.846386) (xy 181.812371 -43.810695) (xy 181.858221 -43.781229)
			(xy 181.907798 -43.758587) (xy 181.960093 -43.743232) (xy 182.014041 -43.735476) (xy 182.068543 -43.735476)
			(xy 182.122491 -43.743232) (xy 182.174786 -43.758587) (xy 182.224363 -43.781229) (xy 182.270213 -43.810695)
			(xy 182.311404 -43.846386) (xy 182.347095 -43.887577) (xy 182.376561 -43.933427) (xy 182.399203 -43.983004)
			(xy 182.414558 -44.035299) (xy 182.422314 -44.089247) (xy 182.4228 -44.116498) (xy 182.4228 -44.980098)
			(xy 182.422314 -45.007349) (xy 182.414558 -45.061297) (xy 182.399203 -45.113592) (xy 182.376561 -45.163169)
			(xy 182.347095 -45.209019) (xy 182.311404 -45.25021) (xy 182.270213 -45.285901) (xy 182.224363 -45.315367)
			(xy 182.174786 -45.338009) (xy 182.122491 -45.353364) (xy 182.068543 -45.36112) (xy 182.014041 -45.36112)
			(xy 181.960093 -45.353364) (xy 181.907798 -45.338009) (xy 181.858221 -45.315367) (xy 181.812371 -45.285901)
			(xy 181.77118 -45.25021) (xy 181.735489 -45.209019) (xy 181.706023 -45.163169) (xy 181.683381 -45.113592)
			(xy 181.668026 -45.061297) (xy 181.66027 -45.007349) (xy 181.659784 -44.980098) (xy 161.925 -44.980098)
			(xy 161.925 -46.481746) (xy 178.630072 -46.481746) (xy 178.630072 -45.618146) (xy 178.630558 -45.590895)
			(xy 178.638314 -45.536947) (xy 178.653669 -45.484652) (xy 178.676311 -45.435075) (xy 178.705777 -45.389225)
			(xy 178.741468 -45.348034) (xy 178.782659 -45.312343) (xy 178.828509 -45.282877) (xy 178.878086 -45.260235)
			(xy 178.930381 -45.24488) (xy 178.984329 -45.237124) (xy 179.038831 -45.237124) (xy 179.092779 -45.24488)
			(xy 179.145074 -45.260235) (xy 179.194651 -45.282877) (xy 179.240501 -45.312343) (xy 179.281692 -45.348034)
			(xy 179.317383 -45.389225) (xy 179.346849 -45.435075) (xy 179.369491 -45.484652) (xy 179.384846 -45.536947)
			(xy 179.392602 -45.590895) (xy 179.393088 -45.618146) (xy 179.393088 -46.481746) (xy 179.392602 -46.508997)
			(xy 179.384846 -46.562945) (xy 179.369491 -46.61524) (xy 179.346849 -46.664817) (xy 179.317383 -46.710667)
			(xy 179.281692 -46.751858) (xy 179.240501 -46.787549) (xy 179.194651 -46.817015) (xy 179.145074 -46.839657)
			(xy 179.092779 -46.855012) (xy 179.038831 -46.862768) (xy 178.984329 -46.862768) (xy 178.930381 -46.855012)
			(xy 178.878086 -46.839657) (xy 178.828509 -46.817015) (xy 178.782659 -46.787549) (xy 178.741468 -46.751858)
			(xy 178.705777 -46.710667) (xy 178.676311 -46.664817) (xy 178.653669 -46.61524) (xy 178.638314 -46.562945)
			(xy 178.630558 -46.508997) (xy 178.630072 -46.481746) (xy 161.925 -46.481746) (xy 161.925 -48.028098)
			(xy 181.659784 -48.028098) (xy 181.659784 -47.164498) (xy 181.66027 -47.137247) (xy 181.668026 -47.083299)
			(xy 181.683381 -47.031004) (xy 181.706023 -46.981427) (xy 181.735489 -46.935577) (xy 181.77118 -46.894386)
			(xy 181.812371 -46.858695) (xy 181.858221 -46.829229) (xy 181.907798 -46.806587) (xy 181.960093 -46.791232)
			(xy 182.014041 -46.783476) (xy 182.068543 -46.783476) (xy 182.122491 -46.791232) (xy 182.174786 -46.806587)
			(xy 182.224363 -46.829229) (xy 182.270213 -46.858695) (xy 182.311404 -46.894386) (xy 182.347095 -46.935577)
			(xy 182.376561 -46.981427) (xy 182.399203 -47.031004) (xy 182.414558 -47.083299) (xy 182.422314 -47.137247)
			(xy 182.4228 -47.164498) (xy 182.4228 -48.028098) (xy 182.422314 -48.055349) (xy 182.414558 -48.109297)
			(xy 182.399203 -48.161592) (xy 182.376561 -48.211169) (xy 182.347095 -48.257019) (xy 182.311404 -48.29821)
			(xy 182.270213 -48.333901) (xy 182.224363 -48.363367) (xy 182.174786 -48.386009) (xy 182.122491 -48.401364)
			(xy 182.068543 -48.40912) (xy 182.014041 -48.40912) (xy 181.960093 -48.401364) (xy 181.907798 -48.386009)
			(xy 181.858221 -48.363367) (xy 181.812371 -48.333901) (xy 181.77118 -48.29821) (xy 181.735489 -48.257019)
			(xy 181.706023 -48.211169) (xy 181.683381 -48.161592) (xy 181.668026 -48.109297) (xy 181.66027 -48.055349)
			(xy 181.659784 -48.028098) (xy 161.925 -48.028098) (xy 161.925 -49.48174) (xy 178.630072 -49.48174)
			(xy 178.630072 -48.61814) (xy 178.630558 -48.590889) (xy 178.638314 -48.536941) (xy 178.653669 -48.484646)
			(xy 178.676311 -48.435069) (xy 178.705777 -48.389219) (xy 178.741468 -48.348028) (xy 178.782659 -48.312337)
			(xy 178.828509 -48.282871) (xy 178.878086 -48.260229) (xy 178.930381 -48.244874) (xy 178.984329 -48.237118)
			(xy 179.038831 -48.237118) (xy 179.092779 -48.244874) (xy 179.145074 -48.260229) (xy 179.194651 -48.282871)
			(xy 179.240501 -48.312337) (xy 179.281692 -48.348028) (xy 179.317383 -48.389219) (xy 179.346849 -48.435069)
			(xy 179.369491 -48.484646) (xy 179.384846 -48.536941) (xy 179.392602 -48.590889) (xy 179.393088 -48.61814)
			(xy 179.393088 -49.48174) (xy 179.392602 -49.508991) (xy 179.384846 -49.562939) (xy 179.369491 -49.615234)
			(xy 179.346849 -49.664811) (xy 179.317383 -49.710661) (xy 179.281692 -49.751852) (xy 179.240501 -49.787543)
			(xy 179.194651 -49.817009) (xy 179.145074 -49.839651) (xy 179.092779 -49.855006) (xy 179.038831 -49.862762)
			(xy 178.984329 -49.862762) (xy 178.930381 -49.855006) (xy 178.878086 -49.839651) (xy 178.828509 -49.817009)
			(xy 178.782659 -49.787543) (xy 178.741468 -49.751852) (xy 178.705777 -49.710661) (xy 178.676311 -49.664811)
			(xy 178.653669 -49.615234) (xy 178.638314 -49.562939) (xy 178.630558 -49.508991) (xy 178.630072 -49.48174)
			(xy 161.925 -49.48174) (xy 161.925 -50.949098) (xy 181.659784 -50.949098) (xy 181.659784 -50.085498)
			(xy 181.66027 -50.058247) (xy 181.668026 -50.004299) (xy 181.683381 -49.952004) (xy 181.706023 -49.902427)
			(xy 181.735489 -49.856577) (xy 181.77118 -49.815386) (xy 181.812371 -49.779695) (xy 181.858221 -49.750229)
			(xy 181.907798 -49.727587) (xy 181.960093 -49.712232) (xy 182.014041 -49.704476) (xy 182.068543 -49.704476)
			(xy 182.122491 -49.712232) (xy 182.174786 -49.727587) (xy 182.224363 -49.750229) (xy 182.270213 -49.779695)
			(xy 182.311404 -49.815386) (xy 182.347095 -49.856577) (xy 182.376561 -49.902427) (xy 182.399203 -49.952004)
			(xy 182.414558 -50.004299) (xy 182.422314 -50.058247) (xy 182.4228 -50.085498) (xy 182.4228 -50.949098)
			(xy 182.422314 -50.976349) (xy 182.414558 -51.030297) (xy 182.399203 -51.082592) (xy 182.376561 -51.132169)
			(xy 182.347095 -51.178019) (xy 182.311404 -51.21921) (xy 182.270213 -51.254901) (xy 182.224363 -51.284367)
			(xy 182.174786 -51.307009) (xy 182.122491 -51.322364) (xy 182.068543 -51.33012) (xy 182.014041 -51.33012)
			(xy 181.960093 -51.322364) (xy 181.907798 -51.307009) (xy 181.858221 -51.284367) (xy 181.812371 -51.254901)
			(xy 181.77118 -51.21921) (xy 181.735489 -51.178019) (xy 181.706023 -51.132169) (xy 181.683381 -51.082592)
			(xy 181.668026 -51.030297) (xy 181.66027 -50.976349) (xy 181.659784 -50.949098) (xy 161.925 -50.949098)
			(xy 161.925 -52.481734) (xy 178.630072 -52.481734) (xy 178.630072 -51.618134) (xy 178.630558 -51.590883)
			(xy 178.638314 -51.536935) (xy 178.653669 -51.48464) (xy 178.676311 -51.435063) (xy 178.705777 -51.389213)
			(xy 178.741468 -51.348022) (xy 178.782659 -51.312331) (xy 178.828509 -51.282865) (xy 178.878086 -51.260223)
			(xy 178.930381 -51.244868) (xy 178.984329 -51.237112) (xy 179.038831 -51.237112) (xy 179.092779 -51.244868)
			(xy 179.145074 -51.260223) (xy 179.194651 -51.282865) (xy 179.240501 -51.312331) (xy 179.281692 -51.348022)
			(xy 179.317383 -51.389213) (xy 179.346849 -51.435063) (xy 179.369491 -51.48464) (xy 179.384846 -51.536935)
			(xy 179.392602 -51.590883) (xy 179.393088 -51.618134) (xy 179.393088 -51.999896) (xy 199.373496 -51.999896)
			(xy 199.37751 -51.794212) (xy 199.389546 -51.588842) (xy 199.409585 -51.384098) (xy 199.437598 -51.180291)
			(xy 199.473541 -50.977732) (xy 199.51736 -50.77673) (xy 199.568987 -50.577591) (xy 199.628345 -50.380618)
			(xy 199.695343 -50.18611) (xy 199.769879 -49.994365) (xy 199.851839 -49.805674) (xy 199.941099 -49.620324)
			(xy 200.037522 -49.438598) (xy 200.140963 -49.260772) (xy 200.251262 -49.087118) (xy 200.368253 -48.917899)
			(xy 200.491757 -48.753373) (xy 200.621586 -48.593792) (xy 200.757543 -48.439397) (xy 200.89942 -48.290425)
			(xy 201.047001 -48.147101) (xy 201.200062 -48.009645) (xy 201.358369 -47.878265) (xy 201.521682 -47.753162)
			(xy 201.689751 -47.634525) (xy 201.862321 -47.522537) (xy 202.039129 -47.417366) (xy 202.219906 -47.319175)
			(xy 202.404376 -47.228111) (xy 202.592258 -47.144314) (xy 202.783268 -47.067911) (xy 202.977112 -46.999018)
			(xy 203.173497 -46.937741) (xy 203.372123 -46.884173) (xy 203.572688 -46.838396) (xy 203.774886 -46.800478)
			(xy 203.97841 -46.770479) (xy 204.182949 -46.748442) (xy 204.388192 -46.734403) (xy 204.593827 -46.728383)
			(xy 204.79954 -46.73039) (xy 205.005018 -46.740422) (xy 205.209948 -46.758463) (xy 205.414018 -46.784486)
			(xy 205.616918 -46.818451) (xy 205.818338 -46.860306) (xy 206.017971 -46.909988) (xy 206.215514 -46.967422)
			(xy 206.410666 -47.032519) (xy 206.60313 -47.10518) (xy 206.792612 -47.185296) (xy 206.978823 -47.272743)
			(xy 207.161482 -47.367389) (xy 207.340308 -47.469089) (xy 207.51503 -47.577689) (xy 207.685383 -47.693024)
			(xy 207.851105 -47.814917) (xy 208.011946 -47.943183) (xy 208.167659 -48.077626) (xy 208.318009 -48.218043)
			(xy 208.462766 -48.364219) (xy 208.601709 -48.515931) (xy 208.734627 -48.672949) (xy 208.861318 -48.835034)
			(xy 208.981588 -49.001937) (xy 209.095255 -49.173407) (xy 209.202145 -49.34918) (xy 209.302096 -49.52899)
			(xy 209.394955 -49.712563) (xy 209.480582 -49.899619) (xy 209.558844 -50.089874) (xy 209.622578 -50.263806)
			(xy 239.457992 -50.263806) (xy 239.457992 -49.400206) (xy 239.458478 -49.372955) (xy 239.466234 -49.319007)
			(xy 239.481589 -49.266712) (xy 239.504231 -49.217135) (xy 239.533697 -49.171285) (xy 239.569388 -49.130094)
			(xy 239.610579 -49.094403) (xy 239.656429 -49.064937) (xy 239.706006 -49.042295) (xy 239.758301 -49.02694)
			(xy 239.812249 -49.019184) (xy 239.866751 -49.019184) (xy 239.920699 -49.02694) (xy 239.972994 -49.042295)
			(xy 240.022571 -49.064937) (xy 240.068421 -49.094403) (xy 240.109612 -49.130094) (xy 240.145303 -49.171285)
			(xy 240.174769 -49.217135) (xy 240.197411 -49.266712) (xy 240.212766 -49.319007) (xy 240.220522 -49.372955)
			(xy 240.221008 -49.400206) (xy 240.221008 -50.263806) (xy 240.220522 -50.291057) (xy 240.212766 -50.345005)
			(xy 240.197411 -50.3973) (xy 240.174769 -50.446877) (xy 240.145303 -50.492727) (xy 240.109612 -50.533918)
			(xy 240.068421 -50.569609) (xy 240.022571 -50.599075) (xy 239.972994 -50.621717) (xy 239.920699 -50.637072)
			(xy 239.866751 -50.644828) (xy 239.812249 -50.644828) (xy 239.758301 -50.637072) (xy 239.706006 -50.621717)
			(xy 239.656429 -50.599075) (xy 239.610579 -50.569609) (xy 239.569388 -50.533918) (xy 239.533697 -50.492727)
			(xy 239.504231 -50.446877) (xy 239.481589 -50.3973) (xy 239.466234 -50.345005) (xy 239.458478 -50.291057)
			(xy 239.457992 -50.263806) (xy 209.622578 -50.263806) (xy 209.629625 -50.283037) (xy 209.692815 -50.478815)
			(xy 209.748318 -50.676909) (xy 209.79605 -50.877018) (xy 209.835939 -51.078836) (xy 209.867923 -51.282058)
			(xy 209.891953 -51.486372) (xy 209.907994 -51.691468) (xy 209.91602 -51.897035) (xy 209.916522 -51.999896)
			(xy 209.91602 -52.102757) (xy 209.907994 -52.308324) (xy 209.891953 -52.51342) (xy 209.867923 -52.717734)
			(xy 209.838186 -52.906676) (xy 228.815392 -52.906676) (xy 228.815392 -52.043076) (xy 228.815878 -52.015825)
			(xy 228.823634 -51.961877) (xy 228.838989 -51.909582) (xy 228.861631 -51.860005) (xy 228.891097 -51.814155)
			(xy 228.926788 -51.772964) (xy 228.967979 -51.737273) (xy 229.013829 -51.707807) (xy 229.063406 -51.685165)
			(xy 229.115701 -51.66981) (xy 229.169649 -51.662054) (xy 229.224151 -51.662054) (xy 229.278099 -51.66981)
			(xy 229.330394 -51.685165) (xy 229.379971 -51.707807) (xy 229.425821 -51.737273) (xy 229.467012 -51.772964)
			(xy 229.502703 -51.814155) (xy 229.532169 -51.860005) (xy 229.554811 -51.909582) (xy 229.570166 -51.961877)
			(xy 229.577922 -52.015825) (xy 229.578408 -52.043076) (xy 229.578408 -52.90185) (xy 241.926872 -52.90185)
			(xy 241.926872 -52.03825) (xy 241.927358 -52.010999) (xy 241.935114 -51.957051) (xy 241.950469 -51.904756)
			(xy 241.973111 -51.855179) (xy 242.002577 -51.809329) (xy 242.038268 -51.768138) (xy 242.079459 -51.732447)
			(xy 242.125309 -51.702981) (xy 242.174886 -51.680339) (xy 242.227181 -51.664984) (xy 242.281129 -51.657228)
			(xy 242.335631 -51.657228) (xy 242.389579 -51.664984) (xy 242.441874 -51.680339) (xy 242.491451 -51.702981)
			(xy 242.537301 -51.732447) (xy 242.578492 -51.768138) (xy 242.614183 -51.809329) (xy 242.643649 -51.855179)
			(xy 242.666291 -51.904756) (xy 242.681646 -51.957051) (xy 242.689402 -52.010999) (xy 242.689888 -52.03825)
			(xy 242.689888 -52.90185) (xy 242.689402 -52.929101) (xy 242.681646 -52.983049) (xy 242.666291 -53.035344)
			(xy 242.643649 -53.084921) (xy 242.614183 -53.130771) (xy 242.578492 -53.171962) (xy 242.537301 -53.207653)
			(xy 242.491451 -53.237119) (xy 242.441874 -53.259761) (xy 242.389579 -53.275116) (xy 242.335631 -53.282872)
			(xy 242.281129 -53.282872) (xy 242.227181 -53.275116) (xy 242.174886 -53.259761) (xy 242.125309 -53.237119)
			(xy 242.079459 -53.207653) (xy 242.038268 -53.171962) (xy 242.002577 -53.130771) (xy 241.973111 -53.084921)
			(xy 241.950469 -53.035344) (xy 241.935114 -52.983049) (xy 241.927358 -52.929101) (xy 241.926872 -52.90185)
			(xy 229.578408 -52.90185) (xy 229.578408 -52.906676) (xy 229.577922 -52.933927) (xy 229.570166 -52.987875)
			(xy 229.554811 -53.04017) (xy 229.532169 -53.089747) (xy 229.502703 -53.135597) (xy 229.467012 -53.176788)
			(xy 229.425821 -53.212479) (xy 229.379971 -53.241945) (xy 229.330394 -53.264587) (xy 229.278099 -53.279942)
			(xy 229.224151 -53.287698) (xy 229.169649 -53.287698) (xy 229.115701 -53.279942) (xy 229.063406 -53.264587)
			(xy 229.013829 -53.241945) (xy 228.967979 -53.212479) (xy 228.926788 -53.176788) (xy 228.891097 -53.135597)
			(xy 228.861631 -53.089747) (xy 228.838989 -53.04017) (xy 228.823634 -52.987875) (xy 228.815878 -52.933927)
			(xy 228.815392 -52.906676) (xy 209.838186 -52.906676) (xy 209.835939 -52.920956) (xy 209.79605 -53.122774)
			(xy 209.748318 -53.322883) (xy 209.692815 -53.520977) (xy 209.629625 -53.716755) (xy 209.558844 -53.909918)
			(xy 209.480582 -54.100173) (xy 209.394955 -54.287229) (xy 209.302096 -54.470802) (xy 209.202145 -54.650612)
			(xy 209.168147 -54.70652) (xy 230.115872 -54.70652) (xy 230.115872 -53.84292) (xy 230.116358 -53.815669)
			(xy 230.124114 -53.761721) (xy 230.139469 -53.709426) (xy 230.162111 -53.659849) (xy 230.191577 -53.613999)
			(xy 230.227268 -53.572808) (xy 230.268459 -53.537117) (xy 230.314309 -53.507651) (xy 230.363886 -53.485009)
			(xy 230.416181 -53.469654) (xy 230.470129 -53.461898) (xy 230.524631 -53.461898) (xy 230.578579 -53.469654)
			(xy 230.630874 -53.485009) (xy 230.680451 -53.507651) (xy 230.726301 -53.537117) (xy 230.767492 -53.572808)
			(xy 230.803183 -53.613999) (xy 230.832649 -53.659849) (xy 230.855291 -53.709426) (xy 230.870646 -53.761721)
			(xy 230.878402 -53.815669) (xy 230.878888 -53.84292) (xy 230.878888 -54.70652) (xy 230.878811 -54.710838)
			(xy 240.282476 -54.710838) (xy 240.282476 -53.847238) (xy 240.282962 -53.819987) (xy 240.290718 -53.766039)
			(xy 240.306073 -53.713744) (xy 240.328715 -53.664167) (xy 240.358181 -53.618317) (xy 240.393872 -53.577126)
			(xy 240.435063 -53.541435) (xy 240.480913 -53.511969) (xy 240.53049 -53.489327) (xy 240.582785 -53.473972)
			(xy 240.636733 -53.466216) (xy 240.691235 -53.466216) (xy 240.745183 -53.473972) (xy 240.797478 -53.489327)
			(xy 240.847055 -53.511969) (xy 240.892905 -53.541435) (xy 240.934096 -53.577126) (xy 240.969787 -53.618317)
			(xy 240.999253 -53.664167) (xy 241.021895 -53.713744) (xy 241.03725 -53.766039) (xy 241.045006 -53.819987)
			(xy 241.045492 -53.847238) (xy 241.045492 -54.710838) (xy 241.045006 -54.738089) (xy 241.03725 -54.792037)
			(xy 241.021895 -54.844332) (xy 240.999253 -54.893909) (xy 240.969787 -54.939759) (xy 240.934096 -54.98095)
			(xy 240.892905 -55.016641) (xy 240.847055 -55.046107) (xy 240.797478 -55.068749) (xy 240.745183 -55.084104)
			(xy 240.691235 -55.09186) (xy 240.636733 -55.09186) (xy 240.582785 -55.084104) (xy 240.53049 -55.068749)
			(xy 240.480913 -55.046107) (xy 240.435063 -55.016641) (xy 240.393872 -54.98095) (xy 240.358181 -54.939759)
			(xy 240.328715 -54.893909) (xy 240.306073 -54.844332) (xy 240.290718 -54.792037) (xy 240.282962 -54.738089)
			(xy 240.282476 -54.710838) (xy 230.878811 -54.710838) (xy 230.878402 -54.733771) (xy 230.870646 -54.787719)
			(xy 230.855291 -54.840014) (xy 230.832649 -54.889591) (xy 230.803183 -54.935441) (xy 230.767492 -54.976632)
			(xy 230.726301 -55.012323) (xy 230.680451 -55.041789) (xy 230.630874 -55.064431) (xy 230.578579 -55.079786)
			(xy 230.524631 -55.087542) (xy 230.470129 -55.087542) (xy 230.416181 -55.079786) (xy 230.363886 -55.064431)
			(xy 230.314309 -55.041789) (xy 230.268459 -55.012323) (xy 230.227268 -54.976632) (xy 230.191577 -54.935441)
			(xy 230.162111 -54.889591) (xy 230.139469 -54.840014) (xy 230.124114 -54.787719) (xy 230.116358 -54.733771)
			(xy 230.115872 -54.70652) (xy 209.168147 -54.70652) (xy 209.095255 -54.826385) (xy 208.981588 -54.997855)
			(xy 208.861318 -55.164758) (xy 208.734627 -55.326843) (xy 208.601709 -55.483861) (xy 208.462766 -55.635573)
			(xy 208.318009 -55.781749) (xy 208.167659 -55.922166) (xy 208.011946 -56.056609) (xy 207.851105 -56.184875)
			(xy 207.685383 -56.306768) (xy 207.51503 -56.422103) (xy 207.378649 -56.506872) (xy 228.815392 -56.506872)
			(xy 228.815392 -55.643272) (xy 228.815878 -55.616021) (xy 228.823634 -55.562073) (xy 228.838989 -55.509778)
			(xy 228.861631 -55.460201) (xy 228.891097 -55.414351) (xy 228.926788 -55.37316) (xy 228.967979 -55.337469)
			(xy 229.013829 -55.308003) (xy 229.063406 -55.285361) (xy 229.115701 -55.270006) (xy 229.169649 -55.26225)
			(xy 229.224151 -55.26225) (xy 229.278099 -55.270006) (xy 229.330394 -55.285361) (xy 229.379971 -55.308003)
			(xy 229.425821 -55.337469) (xy 229.467012 -55.37316) (xy 229.502703 -55.414351) (xy 229.532169 -55.460201)
			(xy 229.554811 -55.509778) (xy 229.570166 -55.562073) (xy 229.577922 -55.616021) (xy 229.578408 -55.643272)
			(xy 229.578408 -56.506872) (xy 229.577922 -56.534123) (xy 229.570166 -56.588071) (xy 229.554811 -56.640366)
			(xy 229.532169 -56.689943) (xy 229.502703 -56.735793) (xy 229.467012 -56.776984) (xy 229.425821 -56.812675)
			(xy 229.379971 -56.842141) (xy 229.330394 -56.864783) (xy 229.278099 -56.880138) (xy 229.224151 -56.887894)
			(xy 229.169649 -56.887894) (xy 229.115701 -56.880138) (xy 229.063406 -56.864783) (xy 229.013829 -56.842141)
			(xy 228.967979 -56.812675) (xy 228.926788 -56.776984) (xy 228.891097 -56.735793) (xy 228.861631 -56.689943)
			(xy 228.838989 -56.640366) (xy 228.823634 -56.588071) (xy 228.815878 -56.534123) (xy 228.815392 -56.506872)
			(xy 207.378649 -56.506872) (xy 207.340308 -56.530703) (xy 207.161482 -56.632403) (xy 206.978823 -56.727049)
			(xy 206.792612 -56.814496) (xy 206.60313 -56.894612) (xy 206.410666 -56.967273) (xy 206.215514 -57.03237)
			(xy 206.017971 -57.089804) (xy 205.818338 -57.139486) (xy 205.616918 -57.181341) (xy 205.414018 -57.215306)
			(xy 205.209948 -57.241329) (xy 205.005018 -57.25937) (xy 204.79954 -57.269402) (xy 204.593827 -57.271409)
			(xy 204.388192 -57.265389) (xy 204.182949 -57.25135) (xy 203.97841 -57.229313) (xy 203.774886 -57.199314)
			(xy 203.572688 -57.161396) (xy 203.372123 -57.115619) (xy 203.173497 -57.062051) (xy 202.977112 -57.000774)
			(xy 202.783268 -56.931881) (xy 202.592258 -56.855478) (xy 202.404376 -56.771681) (xy 202.219906 -56.680617)
			(xy 202.039129 -56.582426) (xy 201.862321 -56.477255) (xy 201.689751 -56.365267) (xy 201.521682 -56.24663)
			(xy 201.358369 -56.121527) (xy 201.200062 -55.990147) (xy 201.047001 -55.852691) (xy 200.89942 -55.709367)
			(xy 200.757543 -55.560395) (xy 200.621586 -55.406) (xy 200.491757 -55.246419) (xy 200.368253 -55.081893)
			(xy 200.251262 -54.912674) (xy 200.140963 -54.73902) (xy 200.037522 -54.561194) (xy 199.941099 -54.379468)
			(xy 199.851839 -54.194118) (xy 199.769879 -54.005427) (xy 199.695343 -53.813682) (xy 199.628345 -53.619174)
			(xy 199.568987 -53.422201) (xy 199.51736 -53.223062) (xy 199.473541 -53.02206) (xy 199.437598 -52.819501)
			(xy 199.409585 -52.615694) (xy 199.389546 -52.41095) (xy 199.37751 -52.20558) (xy 199.373496 -51.999896)
			(xy 179.393088 -51.999896) (xy 179.393088 -52.481734) (xy 179.392602 -52.508985) (xy 179.384846 -52.562933)
			(xy 179.369491 -52.615228) (xy 179.346849 -52.664805) (xy 179.317383 -52.710655) (xy 179.281692 -52.751846)
			(xy 179.240501 -52.787537) (xy 179.194651 -52.817003) (xy 179.145074 -52.839645) (xy 179.092779 -52.855)
			(xy 179.038831 -52.862756) (xy 178.984329 -52.862756) (xy 178.930381 -52.855) (xy 178.878086 -52.839645)
			(xy 178.828509 -52.817003) (xy 178.782659 -52.787537) (xy 178.741468 -52.751846) (xy 178.705777 -52.710655)
			(xy 178.676311 -52.664805) (xy 178.653669 -52.615228) (xy 178.638314 -52.562933) (xy 178.630558 -52.508985)
			(xy 178.630072 -52.481734) (xy 161.925 -52.481734) (xy 161.925 -53.954934) (xy 181.659784 -53.954934)
			(xy 181.659784 -53.091334) (xy 181.66027 -53.064083) (xy 181.668026 -53.010135) (xy 181.683381 -52.95784)
			(xy 181.706023 -52.908263) (xy 181.735489 -52.862413) (xy 181.77118 -52.821222) (xy 181.812371 -52.785531)
			(xy 181.858221 -52.756065) (xy 181.907798 -52.733423) (xy 181.960093 -52.718068) (xy 182.014041 -52.710312)
			(xy 182.068543 -52.710312) (xy 182.122491 -52.718068) (xy 182.174786 -52.733423) (xy 182.224363 -52.756065)
			(xy 182.270213 -52.785531) (xy 182.311404 -52.821222) (xy 182.347095 -52.862413) (xy 182.376561 -52.908263)
			(xy 182.399203 -52.95784) (xy 182.414558 -53.010135) (xy 182.422314 -53.064083) (xy 182.4228 -53.091334)
			(xy 182.4228 -53.954934) (xy 182.422314 -53.982185) (xy 182.414558 -54.036133) (xy 182.399203 -54.088428)
			(xy 182.376561 -54.138005) (xy 182.347095 -54.183855) (xy 182.311404 -54.225046) (xy 182.270213 -54.260737)
			(xy 182.224363 -54.290203) (xy 182.174786 -54.312845) (xy 182.122491 -54.3282) (xy 182.068543 -54.335956)
			(xy 182.014041 -54.335956) (xy 181.960093 -54.3282) (xy 181.907798 -54.312845) (xy 181.858221 -54.290203)
			(xy 181.812371 -54.260737) (xy 181.77118 -54.225046) (xy 181.735489 -54.183855) (xy 181.706023 -54.138005)
			(xy 181.683381 -54.088428) (xy 181.668026 -54.036133) (xy 181.66027 -53.982185) (xy 181.659784 -53.954934)
			(xy 161.925 -53.954934) (xy 161.925 -55.481728) (xy 178.630072 -55.481728) (xy 178.630072 -54.618128)
			(xy 178.630558 -54.590877) (xy 178.638314 -54.536929) (xy 178.653669 -54.484634) (xy 178.676311 -54.435057)
			(xy 178.705777 -54.389207) (xy 178.741468 -54.348016) (xy 178.782659 -54.312325) (xy 178.828509 -54.282859)
			(xy 178.878086 -54.260217) (xy 178.930381 -54.244862) (xy 178.984329 -54.237106) (xy 179.038831 -54.237106)
			(xy 179.092779 -54.244862) (xy 179.145074 -54.260217) (xy 179.194651 -54.282859) (xy 179.240501 -54.312325)
			(xy 179.281692 -54.348016) (xy 179.317383 -54.389207) (xy 179.346849 -54.435057) (xy 179.369491 -54.484634)
			(xy 179.384846 -54.536929) (xy 179.392602 -54.590877) (xy 179.393088 -54.618128) (xy 179.393088 -55.481728)
			(xy 179.392602 -55.508979) (xy 179.384846 -55.562927) (xy 179.369491 -55.615222) (xy 179.346849 -55.664799)
			(xy 179.317383 -55.710649) (xy 179.281692 -55.75184) (xy 179.240501 -55.787531) (xy 179.194651 -55.816997)
			(xy 179.145074 -55.839639) (xy 179.092779 -55.854994) (xy 179.038831 -55.86275) (xy 178.984329 -55.86275)
			(xy 178.930381 -55.854994) (xy 178.878086 -55.839639) (xy 178.828509 -55.816997) (xy 178.782659 -55.787531)
			(xy 178.741468 -55.75184) (xy 178.705777 -55.710649) (xy 178.676311 -55.664799) (xy 178.653669 -55.615222)
			(xy 178.638314 -55.562927) (xy 178.630558 -55.508979) (xy 178.630072 -55.481728) (xy 161.925 -55.481728)
			(xy 161.925 -56.958992) (xy 162.060443 -57.094435) (xy 170.841915 -57.094435) (xy 170.841915 -57.005413)
			(xy 170.849895 -56.916749) (xy 170.865791 -56.829158) (xy 170.889474 -56.743343) (xy 170.920754 -56.659998)
			(xy 170.95938 -56.579792) (xy 171.005039 -56.503371) (xy 171.057365 -56.43135) (xy 171.115936 -56.36431)
			(xy 171.180281 -56.30279) (xy 171.249881 -56.247286) (xy 171.324177 -56.198244) (xy 171.402569 -56.156059)
			(xy 171.484428 -56.121071) (xy 171.569093 -56.093562) (xy 171.655883 -56.073752) (xy 171.744099 -56.061802)
			(xy 171.833032 -56.057809) (xy 171.921965 -56.061802) (xy 172.010181 -56.073752) (xy 172.096971 -56.093562)
			(xy 172.181636 -56.121071) (xy 172.263495 -56.156059) (xy 172.341887 -56.198244) (xy 172.416183 -56.247286)
			(xy 172.485783 -56.30279) (xy 172.550128 -56.36431) (xy 172.608699 -56.43135) (xy 172.661025 -56.503371)
			(xy 172.706684 -56.579792) (xy 172.74531 -56.659998) (xy 172.77659 -56.743343) (xy 172.800273 -56.829158)
			(xy 172.816169 -56.916749) (xy 172.824149 -57.005413) (xy 172.824648 -57.049924) (xy 172.824149 -57.094435)
			(xy 172.816169 -57.183099) (xy 172.800273 -57.27069) (xy 172.77659 -57.356505) (xy 172.74531 -57.43985)
			(xy 172.706684 -57.520056) (xy 172.661025 -57.596477) (xy 172.608699 -57.668498) (xy 172.550128 -57.735538)
			(xy 172.485783 -57.797058) (xy 172.416183 -57.852562) (xy 172.341887 -57.901604) (xy 172.263495 -57.943789)
			(xy 172.181636 -57.978777) (xy 172.096971 -58.006286) (xy 172.010181 -58.026096) (xy 171.921965 -58.038046)
			(xy 171.833032 -58.04204) (xy 171.744099 -58.038046) (xy 171.655883 -58.026096) (xy 171.569093 -58.006286)
			(xy 171.484428 -57.978777) (xy 171.402569 -57.943789) (xy 171.324177 -57.901604) (xy 171.249881 -57.852562)
			(xy 171.180281 -57.797058) (xy 171.115936 -57.735538) (xy 171.057365 -57.668498) (xy 171.005039 -57.596477)
			(xy 170.95938 -57.520056) (xy 170.920754 -57.43985) (xy 170.889474 -57.356505) (xy 170.865791 -57.27069)
			(xy 170.849895 -57.183099) (xy 170.841915 -57.094435) (xy 162.060443 -57.094435) (xy 163.272724 -58.306716)
			(xy 230.115872 -58.306716) (xy 230.115872 -57.443116) (xy 230.116358 -57.415865) (xy 230.124114 -57.361917)
			(xy 230.139469 -57.309622) (xy 230.162111 -57.260045) (xy 230.191577 -57.214195) (xy 230.227268 -57.173004)
			(xy 230.268459 -57.137313) (xy 230.314309 -57.107847) (xy 230.363886 -57.085205) (xy 230.416181 -57.06985)
			(xy 230.470129 -57.062094) (xy 230.524631 -57.062094) (xy 230.578579 -57.06985) (xy 230.630874 -57.085205)
			(xy 230.680451 -57.107847) (xy 230.726301 -57.137313) (xy 230.767492 -57.173004) (xy 230.803183 -57.214195)
			(xy 230.832649 -57.260045) (xy 230.855291 -57.309622) (xy 230.870646 -57.361917) (xy 230.878402 -57.415865)
			(xy 230.878888 -57.443116) (xy 230.878888 -58.30189) (xy 240.282476 -58.30189) (xy 240.282476 -57.43829)
			(xy 240.282962 -57.411039) (xy 240.290718 -57.357091) (xy 240.306073 -57.304796) (xy 240.328715 -57.255219)
			(xy 240.358181 -57.209369) (xy 240.393872 -57.168178) (xy 240.435063 -57.132487) (xy 240.480913 -57.103021)
			(xy 240.53049 -57.080379) (xy 240.582785 -57.065024) (xy 240.636733 -57.057268) (xy 240.691235 -57.057268)
			(xy 240.745183 -57.065024) (xy 240.797478 -57.080379) (xy 240.847055 -57.103021) (xy 240.892905 -57.132487)
			(xy 240.934096 -57.168178) (xy 240.969787 -57.209369) (xy 240.999253 -57.255219) (xy 241.021895 -57.304796)
			(xy 241.03725 -57.357091) (xy 241.045006 -57.411039) (xy 241.045492 -57.43829) (xy 241.045492 -58.30189)
			(xy 241.045006 -58.329141) (xy 241.03725 -58.383089) (xy 241.021895 -58.435384) (xy 240.999253 -58.484961)
			(xy 240.969787 -58.530811) (xy 240.941894 -58.563002) (xy 242.736116 -58.563002) (xy 242.736116 -57.699402)
			(xy 242.736602 -57.672151) (xy 242.744358 -57.618203) (xy 242.759713 -57.565908) (xy 242.782355 -57.516331)
			(xy 242.811821 -57.470481) (xy 242.847512 -57.42929) (xy 242.888703 -57.393599) (xy 242.934553 -57.364133)
			(xy 242.98413 -57.341491) (xy 243.036425 -57.326136) (xy 243.090373 -57.31838) (xy 243.144875 -57.31838)
			(xy 243.198823 -57.326136) (xy 243.251118 -57.341491) (xy 243.300695 -57.364133) (xy 243.346545 -57.393599)
			(xy 243.387736 -57.42929) (xy 243.423427 -57.470481) (xy 243.452893 -57.516331) (xy 243.475535 -57.565908)
			(xy 243.49089 -57.618203) (xy 243.498646 -57.672151) (xy 243.499132 -57.699402) (xy 243.499132 -58.563002)
			(xy 243.498646 -58.590253) (xy 243.49089 -58.644201) (xy 243.475535 -58.696496) (xy 243.452893 -58.746073)
			(xy 243.423427 -58.791923) (xy 243.387736 -58.833114) (xy 243.346545 -58.868805) (xy 243.300695 -58.898271)
			(xy 243.251118 -58.920913) (xy 243.198823 -58.936268) (xy 243.144875 -58.944024) (xy 243.090373 -58.944024)
			(xy 243.036425 -58.936268) (xy 242.98413 -58.920913) (xy 242.934553 -58.898271) (xy 242.888703 -58.868805)
			(xy 242.847512 -58.833114) (xy 242.811821 -58.791923) (xy 242.782355 -58.746073) (xy 242.759713 -58.696496)
			(xy 242.744358 -58.644201) (xy 242.736602 -58.590253) (xy 242.736116 -58.563002) (xy 240.941894 -58.563002)
			(xy 240.934096 -58.572002) (xy 240.892905 -58.607693) (xy 240.847055 -58.637159) (xy 240.797478 -58.659801)
			(xy 240.745183 -58.675156) (xy 240.691235 -58.682912) (xy 240.636733 -58.682912) (xy 240.582785 -58.675156)
			(xy 240.53049 -58.659801) (xy 240.480913 -58.637159) (xy 240.435063 -58.607693) (xy 240.393872 -58.572002)
			(xy 240.358181 -58.530811) (xy 240.328715 -58.484961) (xy 240.306073 -58.435384) (xy 240.290718 -58.383089)
			(xy 240.282962 -58.329141) (xy 240.282476 -58.30189) (xy 230.878888 -58.30189) (xy 230.878888 -58.306716)
			(xy 230.878402 -58.333967) (xy 230.870646 -58.387915) (xy 230.855291 -58.44021) (xy 230.832649 -58.489787)
			(xy 230.803183 -58.535637) (xy 230.767492 -58.576828) (xy 230.726301 -58.612519) (xy 230.680451 -58.641985)
			(xy 230.630874 -58.664627) (xy 230.578579 -58.679982) (xy 230.524631 -58.687738) (xy 230.470129 -58.687738)
			(xy 230.416181 -58.679982) (xy 230.363886 -58.664627) (xy 230.314309 -58.641985) (xy 230.268459 -58.612519)
			(xy 230.227268 -58.576828) (xy 230.191577 -58.535637) (xy 230.162111 -58.489787) (xy 230.139469 -58.44021)
			(xy 230.124114 -58.387915) (xy 230.116358 -58.333967) (xy 230.115872 -58.306716) (xy 163.272724 -58.306716)
			(xy 164.849556 -59.883548) (xy 209.33664 -59.883548) (xy 209.3616 -59.884127) (xy 209.410563 -59.893853)
			(xy 209.456682 -59.91296) (xy 209.498176 -59.940713) (xy 209.516218 -59.95797) (xy 209.933286 -60.375038)
			(xy 233.333297 -60.375038) (xy 233.337302 -60.28713) (xy 233.349285 -60.19995) (xy 233.369145 -60.114221)
			(xy 233.39672 -60.030653) (xy 233.431779 -59.949939) (xy 233.474032 -59.872747) (xy 233.52313 -59.799718)
			(xy 233.578666 -59.731456) (xy 233.640178 -59.668526) (xy 233.707159 -59.611452) (xy 233.779052 -59.560704)
			(xy 233.855261 -59.516704) (xy 233.935156 -59.479817) (xy 234.018075 -59.450348) (xy 234.10333 -59.428541)
			(xy 234.190214 -59.414577) (xy 234.278008 -59.408571) (xy 234.365985 -59.410575) (xy 234.453415 -59.42057)
			(xy 234.539574 -59.438474) (xy 234.623748 -59.464138) (xy 234.705239 -59.497351) (xy 234.783373 -59.537837)
			(xy 234.857501 -59.585259) (xy 234.927009 -59.639226) (xy 234.991323 -59.699291) (xy 235.049907 -59.764955)
			(xy 235.102278 -59.835674) (xy 235.148001 -59.910862) (xy 235.186698 -59.989897) (xy 235.218047 -60.072123)
			(xy 235.241789 -60.156859) (xy 235.257727 -60.243403) (xy 235.265729 -60.331038) (xy 235.26623 -60.375038)
			(xy 235.265729 -60.419038) (xy 235.257727 -60.506673) (xy 235.241789 -60.593217) (xy 235.218047 -60.677953)
			(xy 235.186698 -60.760179) (xy 235.148001 -60.839214) (xy 235.102278 -60.914402) (xy 235.049907 -60.985121)
			(xy 234.991323 -61.050785) (xy 234.927009 -61.11085) (xy 234.857501 -61.164817) (xy 234.783373 -61.212239)
			(xy 234.705239 -61.252725) (xy 234.623748 -61.285938) (xy 234.539574 -61.311602) (xy 234.453415 -61.329506)
			(xy 234.365985 -61.339501) (xy 234.278008 -61.341505) (xy 234.190214 -61.335499) (xy 234.10333 -61.321535)
			(xy 234.018075 -61.299728) (xy 233.935156 -61.270259) (xy 233.855261 -61.233372) (xy 233.779052 -61.189372)
			(xy 233.707159 -61.138624) (xy 233.640178 -61.08155) (xy 233.578666 -61.01862) (xy 233.52313 -60.950358)
			(xy 233.474032 -60.877329) (xy 233.431779 -60.800137) (xy 233.39672 -60.719423) (xy 233.369145 -60.635855)
			(xy 233.349285 -60.550126) (xy 233.337302 -60.462946) (xy 233.333297 -60.375038) (xy 209.933286 -60.375038)
			(xy 210.806538 -61.24829) (xy 210.823789 -61.266336) (xy 210.85153 -61.307837) (xy 210.87064 -61.353952)
			(xy 210.880386 -61.402909) (xy 210.88096 -61.427868) (xy 210.88096 -66.847974) (xy 210.909154 -66.861944)
			(xy 210.934166 -66.87496) (xy 210.980356 -66.907299) (xy 211.021284 -66.946082) (xy 211.056058 -66.990467)
			(xy 211.083923 -67.039485) (xy 211.104271 -67.09207) (xy 211.11666 -67.147078) (xy 211.120818 -67.203309)
			(xy 211.116657 -67.25954) (xy 211.104266 -67.314547) (xy 211.083916 -67.367131) (xy 211.056048 -67.416148)
			(xy 211.021272 -67.460531) (xy 210.980342 -67.499313) (xy 210.934151 -67.531649) (xy 210.909154 -67.544696)
			(xy 210.88096 -67.558666) (xy 210.88096 -68.61048) (xy 210.91271 -68.62318) (xy 210.938757 -68.634211)
			(xy 210.987455 -68.662992) (xy 211.031371 -68.698645) (xy 211.069543 -68.74039) (xy 211.101135 -68.787313)
			(xy 211.125454 -68.838385) (xy 211.141968 -68.892487) (xy 211.150316 -68.948435) (xy 211.150313 -69.005001)
			(xy 211.14196 -69.060948) (xy 211.125441 -69.115049) (xy 211.101117 -69.166118) (xy 211.06952 -69.213038)
			(xy 211.031344 -69.25478) (xy 210.987425 -69.290429) (xy 210.938724 -69.319205) (xy 210.91271 -69.330316)
			(xy 210.88096 -69.343016) (xy 210.88096 -69.493384) (xy 210.913218 -69.506084) (xy 210.939632 -69.517014)
			(xy 210.989166 -69.545544) (xy 211.03389 -69.581144) (xy 211.072803 -69.623016) (xy 211.105035 -69.670224)
			(xy 211.129865 -69.721712) (xy 211.146737 -69.776328) (xy 211.155274 -69.832849) (xy 211.155788 -69.86143)
			(xy 211.15524 -69.890584) (xy 211.14637 -69.948212) (xy 211.128841 -70.003822) (xy 211.103059 -70.05612)
			(xy 211.069626 -70.10389) (xy 211.04987 -70.125336) (xy 211.04 -70.136289) (xy 211.026531 -70.162504)
			(xy 211.021124 -70.191477) (xy 211.02423 -70.220786) (xy 211.035589 -70.247981) (xy 211.044536 -70.259702)
			(xy 211.060693 -70.280211) (xy 211.087869 -70.324789) (xy 211.108711 -70.372658) (xy 211.122828 -70.422923)
			(xy 211.129957 -70.474643) (xy 211.130388 -70.500748) (xy 211.129869 -70.528021) (xy 211.122101 -70.58201)
			(xy 211.106729 -70.634344) (xy 211.084067 -70.683958) (xy 211.054576 -70.729843) (xy 211.018855 -70.771065)
			(xy 210.998562 -70.789292) (xy 210.988338 -70.798766) (xy 210.972971 -70.822003) (xy 210.964466 -70.848532)
			(xy 210.96346 -70.876373) (xy 210.970027 -70.903447) (xy 210.983678 -70.927732) (xy 210.993228 -70.937882)
			(xy 211.014028 -70.959481) (xy 211.049286 -71.007981) (xy 211.076517 -71.061402) (xy 211.095051 -71.118427)
			(xy 211.104432 -71.177649) (xy 211.104988 -71.20763) (xy 211.104484 -71.234949) (xy 211.096686 -71.289027)
			(xy 211.081254 -71.341441) (xy 211.058503 -71.391117) (xy 211.0289 -71.43704) (xy 210.993048 -71.47827)
			(xy 210.951682 -71.513965) (xy 210.905648 -71.543395) (xy 210.88096 -71.555102) (xy 210.88096 -74.002138)
			(xy 210.91017 -74.015854) (xy 210.934498 -74.027705) (xy 210.979818 -74.057277) (xy 211.020502 -74.092958)
			(xy 211.055735 -74.134031) (xy 211.084808 -74.179672) (xy 211.107138 -74.228965) (xy 211.122276 -74.280919)
			(xy 211.129919 -74.334491) (xy 211.130388 -74.361548) (xy 211.130127 -74.38125) (xy 211.126051 -74.420444)
			(xy 211.12226 -74.43978) (xy 211.116672 -74.466704) (xy 213.195916 -76.545948) (xy 234.794298 -76.545948)
			(xy 234.903316 -76.523157) (xy 235.122884 -76.485664) (xy 235.343839 -76.457477) (xy 235.565787 -76.438644)
			(xy 235.788333 -76.429201) (xy 235.899706 -76.4286) (xy 236.011079 -76.429198) (xy 236.233626 -76.438629)
			(xy 236.455576 -76.457455) (xy 236.676531 -76.485644) (xy 236.896098 -76.523145) (xy 237.005114 -76.545948)
			(xy 257.923538 -76.545948) (xy 257.94208 -76.54544) (xy 257.960622 -76.545948) (xy 271.700244 -76.545948)
			(xy 271.9832 -76.262992) (xy 271.9832 -57.671208) (xy 271.983733 -57.646245) (xy 271.99347 -57.597279)
			(xy 272.012591 -57.55116) (xy 272.040358 -57.509669) (xy 272.057622 -57.49163) (xy 273.74596 -55.803292)
			(xy 273.74596 -53.968142) (xy 273.745572 -53.95406) (xy 273.737892 -53.926962) (xy 273.723103 -53.902993)
			(xy 273.70233 -53.883974) (xy 273.677152 -53.871351) (xy 273.649484 -53.866085) (xy 273.62143 -53.868574)
			(xy 273.595122 -53.878631) (xy 273.572561 -53.895491) (xy 273.555462 -53.917871) (xy 273.549872 -53.930804)
			(xy 273.512231 -54.025243) (xy 273.430502 -54.211419) (xy 273.341654 -54.394305) (xy 273.24582 -54.57363)
			(xy 273.143142 -54.749125) (xy 273.033773 -54.92053) (xy 272.917875 -55.08759) (xy 272.795621 -55.250056)
			(xy 272.667194 -55.407688) (xy 272.532783 -55.56025) (xy 272.392589 -55.707515) (xy 272.246821 -55.849264)
			(xy 272.095695 -55.985287) (xy 271.939435 -56.115381) (xy 271.778276 -56.239352) (xy 271.612456 -56.357017)
			(xy 271.442221 -56.4682) (xy 271.267826 -56.572735) (xy 271.089529 -56.670468) (xy 270.907597 -56.761252)
			(xy 270.722298 -56.844953) (xy 270.53391 -56.921447) (xy 270.342713 -56.990618) (xy 270.14899 -57.052366)
			(xy 269.95303 -57.106597) (xy 269.755124 -57.153231) (xy 269.555568 -57.192199) (xy 269.354657 -57.223443)
			(xy 269.152691 -57.246915) (xy 268.949969 -57.262582) (xy 268.746795 -57.27042) (xy 268.645132 -57.270904)
			(xy 268.54291 -57.270423) (xy 268.338619 -57.262497) (xy 268.13479 -57.246656) (xy 267.931728 -57.222922)
			(xy 267.729739 -57.191333) (xy 267.529127 -57.151935) (xy 267.330194 -57.104788) (xy 267.133238 -57.049963)
			(xy 266.938556 -56.987541) (xy 266.746441 -56.917618) (xy 266.557182 -56.840298) (xy 266.371063 -56.755698)
			(xy 266.188365 -56.663945) (xy 266.009361 -56.565176) (xy 265.834323 -56.45954) (xy 265.663512 -56.347197)
			(xy 265.497185 -56.228315) (xy 265.335594 -56.103073) (xy 265.17898 -55.971659) (xy 265.02758 -55.834272)
			(xy 264.88162 -55.691117) (xy 264.741322 -55.54241) (xy 264.606895 -55.388375) (xy 264.478542 -55.229243)
			(xy 264.356456 -55.065254) (xy 264.240821 -54.896654) (xy 264.13181 -54.723697) (xy 264.029587 -54.546644)
			(xy 263.934307 -54.36576) (xy 263.846113 -54.181317) (xy 263.765136 -53.993593) (xy 263.6915 -53.802871)
			(xy 263.625314 -53.609436) (xy 263.566678 -53.413581) (xy 263.515681 -53.215599) (xy 263.4724 -53.015789)
			(xy 263.436898 -52.814451) (xy 263.40923 -52.611888) (xy 263.389438 -52.408404) (xy 263.37755 -52.204306)
			(xy 263.373586 -51.9999) (xy 263.37755 -51.795494) (xy 263.389438 -51.591396) (xy 263.40923 -51.387912)
			(xy 263.436898 -51.185349) (xy 263.4724 -50.984011) (xy 263.515681 -50.784201) (xy 263.566678 -50.586219)
			(xy 263.625314 -50.390364) (xy 263.6915 -50.196929) (xy 263.765136 -50.006207) (xy 263.846113 -49.818483)
			(xy 263.934307 -49.63404) (xy 264.029587 -49.453156) (xy 264.13181 -49.276103) (xy 264.240821 -49.103146)
			(xy 264.356456 -48.934546) (xy 264.478542 -48.770557) (xy 264.606895 -48.611425) (xy 264.741322 -48.45739)
			(xy 264.88162 -48.308683) (xy 265.02758 -48.165528) (xy 265.17898 -48.028141) (xy 265.335594 -47.896727)
			(xy 265.497185 -47.771485) (xy 265.663512 -47.652603) (xy 265.834323 -47.54026) (xy 266.009361 -47.434624)
			(xy 266.188365 -47.335855) (xy 266.371063 -47.244102) (xy 266.557182 -47.159502) (xy 266.746441 -47.082182)
			(xy 266.938556 -47.012259) (xy 267.133238 -46.949837) (xy 267.330194 -46.895012) (xy 267.529127 -46.847865)
			(xy 267.729739 -46.808467) (xy 267.931728 -46.776878) (xy 268.13479 -46.753144) (xy 268.338619 -46.737303)
			(xy 268.54291 -46.729377) (xy 268.645132 -46.728888) (xy 268.746794 -46.729408) (xy 268.949966 -46.737249)
			(xy 269.152684 -46.75292) (xy 269.354647 -46.776395) (xy 269.555555 -46.807642) (xy 269.755109 -46.846612)
			(xy 269.953012 -46.893248) (xy 270.148969 -46.947481) (xy 270.342688 -47.00923) (xy 270.533883 -47.078403)
			(xy 270.722268 -47.154897) (xy 270.907564 -47.238598) (xy 271.089494 -47.329383) (xy 271.267788 -47.427115)
			(xy 271.44218 -47.53165) (xy 271.612412 -47.642832) (xy 271.77823 -47.760496) (xy 271.939387 -47.884466)
			(xy 272.095644 -48.014559) (xy 272.246769 -48.15058) (xy 272.392536 -48.292328) (xy 272.532728 -48.439591)
			(xy 272.667138 -48.59215) (xy 272.795565 -48.749779) (xy 272.917817 -48.912243) (xy 273.033715 -49.0793)
			(xy 273.143084 -49.250703) (xy 273.245762 -49.426195) (xy 273.341597 -49.605516) (xy 273.430445 -49.788399)
			(xy 273.512176 -49.974572) (xy 273.549872 -50.068988) (xy 273.555511 -50.081894) (xy 273.572599 -50.104263)
			(xy 273.595148 -50.121115) (xy 273.621441 -50.131167) (xy 273.649481 -50.133655) (xy 273.677134 -50.128391)
			(xy 273.702298 -50.115775) (xy 273.723059 -50.096765) (xy 273.737839 -50.072808) (xy 273.745514 -50.045725)
			(xy 273.74596 -50.03165) (xy 273.74596 -37.132768) (xy 273.746541 -37.107808) (xy 273.756265 -37.058844)
			(xy 273.775372 -37.012726) (xy 273.803125 -36.971232) (xy 273.820382 -36.95319) (xy 287.196022 -23.57755)
			(xy 287.214053 -23.560282) (xy 287.255559 -23.532545) (xy 287.301679 -23.513439) (xy 287.35064 -23.503699)
			(xy 287.3756 -23.503128) (xy 320.832988 -23.503128) (xy 320.842132 -23.464012) (xy 320.849192 -23.43652)
			(xy 320.870332 -23.383846) (xy 320.899041 -23.334884) (xy 320.934684 -23.290714) (xy 320.976475 -23.252309)
			(xy 321.023493 -23.220516) (xy 321.074701 -23.196037) (xy 321.128969 -23.179411) (xy 321.185101 -23.171006)
			(xy 321.241859 -23.171006) (xy 321.297991 -23.179411) (xy 321.352259 -23.196037) (xy 321.403467 -23.220516)
			(xy 321.450485 -23.252309) (xy 321.492276 -23.290714) (xy 321.527919 -23.334884) (xy 321.556628 -23.383846)
			(xy 321.577768 -23.43652) (xy 321.584828 -23.464012) (xy 321.593972 -23.503128) (xy 328.076306 -23.503128)
			(xy 328.088466 -23.480186) (xy 328.118489 -23.437823) (xy 328.154386 -23.400308) (xy 328.195385 -23.368448)
			(xy 328.240603 -23.342927) (xy 328.289068 -23.324296) (xy 328.339737 -23.312954) (xy 328.39152 -23.309146)
			(xy 328.443303 -23.312954) (xy 328.493972 -23.324296) (xy 328.542437 -23.342927) (xy 328.587655 -23.368448)
			(xy 328.628654 -23.400308) (xy 328.664551 -23.437823) (xy 328.694574 -23.480186) (xy 328.706734 -23.503128)
			(xy 329.526138 -23.503128) (xy 329.540362 -23.475696) (xy 329.55261 -23.452972) (xy 329.582692 -23.411024)
			(xy 329.618556 -23.373896) (xy 329.659437 -23.342379) (xy 329.704467 -23.317142) (xy 329.752689 -23.298723)
			(xy 329.803077 -23.287512) (xy 329.85456 -23.283748) (xy 329.906043 -23.287512) (xy 329.956431 -23.298723)
			(xy 330.004653 -23.317142) (xy 330.049683 -23.342379) (xy 330.090564 -23.373896) (xy 330.126428 -23.411024)
			(xy 330.15651 -23.452972) (xy 330.168758 -23.475696) (xy 330.182982 -23.503128) (xy 333.600806 -23.503128)
			(xy 333.610966 -23.498556) (xy 333.636156 -23.487416) (xy 333.688946 -23.471704) (xy 333.743447 -23.46375)
			(xy 333.770986 -23.46325) (xy 333.798524 -23.46376) (xy 333.853023 -23.471718) (xy 333.905812 -23.487427)
			(xy 333.931006 -23.498556) (xy 333.941166 -23.503128) (xy 334.01889 -23.503128) (xy 334.031844 -23.471378)
			(xy 334.042918 -23.445327) (xy 334.071637 -23.396547) (xy 334.107252 -23.352549) (xy 334.14898 -23.314301)
			(xy 334.195905 -23.282641) (xy 334.246994 -23.258267) (xy 334.301125 -23.241714) (xy 334.357109 -23.233345)
			(xy 334.413715 -23.233345) (xy 334.469699 -23.241714) (xy 334.52383 -23.258267) (xy 334.574919 -23.282641)
			(xy 334.621844 -23.314301) (xy 334.663572 -23.352549) (xy 334.699187 -23.396547) (xy 334.727906 -23.445327)
			(xy 334.73898 -23.471378) (xy 334.751934 -23.503128) (xy 353.740466 -23.503128) (xy 353.749864 -23.499318)
			(xy 353.771433 -23.490725) (xy 353.81626 -23.478633) (xy 353.862286 -23.472521) (xy 353.8855 -23.47214)
			(xy 353.908713 -23.472533) (xy 353.954736 -23.478653) (xy 353.999564 -23.490736) (xy 354.021136 -23.499318)
			(xy 354.030534 -23.503128) (xy 373.04472 -23.503128) (xy 373.069679 -23.503725) (xy 373.118641 -23.513446)
			(xy 373.164759 -23.532548) (xy 373.206255 -23.560295) (xy 373.224298 -23.57755) (xy 383.546858 -33.90011)
			(xy 462.69148 -33.90011) (xy 462.69148 -32.29991) (xy 462.691988 -32.23523) (xy 462.700111 -32.106124)
			(xy 462.716324 -31.977784) (xy 462.740564 -31.850714) (xy 462.772734 -31.725418) (xy 462.812709 -31.602388)
			(xy 462.86033 -31.482112) (xy 462.915409 -31.365063) (xy 462.977729 -31.251703) (xy 463.047044 -31.14248)
			(xy 463.12308 -31.037825) (xy 463.205538 -30.938151) (xy 463.294091 -30.843851) (xy 463.388391 -30.755298)
			(xy 463.488065 -30.67284) (xy 463.59272 -30.596804) (xy 463.701943 -30.527489) (xy 463.815303 -30.465169)
			(xy 463.932352 -30.41009) (xy 464.052628 -30.362469) (xy 464.175658 -30.322494) (xy 464.300954 -30.290324)
			(xy 464.428024 -30.266084) (xy 464.556364 -30.249871) (xy 464.68547 -30.241748) (xy 464.81483 -30.241748)
			(xy 464.943936 -30.249871) (xy 465.072276 -30.266084) (xy 465.199346 -30.290324) (xy 465.324642 -30.322494)
			(xy 465.447672 -30.362469) (xy 465.567948 -30.41009) (xy 465.684997 -30.465169) (xy 465.798357 -30.527489)
			(xy 465.90758 -30.596804) (xy 466.012235 -30.67284) (xy 466.111909 -30.755298) (xy 466.206209 -30.843851)
			(xy 466.294762 -30.938151) (xy 466.37722 -31.037825) (xy 466.453256 -31.14248) (xy 466.522571 -31.251703)
			(xy 466.584891 -31.365063) (xy 466.63997 -31.482112) (xy 466.687591 -31.602388) (xy 466.727566 -31.725418)
			(xy 466.759736 -31.850714) (xy 466.783976 -31.977784) (xy 466.800189 -32.106124) (xy 466.808312 -32.23523)
			(xy 466.80882 -32.29991) (xy 466.80882 -33.90011) (xy 466.808312 -33.96479) (xy 466.800189 -34.093896)
			(xy 466.783976 -34.222236) (xy 466.759736 -34.349306) (xy 466.727566 -34.474602) (xy 466.687591 -34.597632)
			(xy 466.63997 -34.717908) (xy 466.584891 -34.834957) (xy 466.522571 -34.948317) (xy 466.453256 -35.05754)
			(xy 466.37722 -35.162195) (xy 466.294762 -35.261869) (xy 466.206209 -35.356169) (xy 466.111909 -35.444722)
			(xy 466.012235 -35.52718) (xy 465.90758 -35.603216) (xy 465.798357 -35.672531) (xy 465.684997 -35.734851)
			(xy 465.567948 -35.78993) (xy 465.447672 -35.837551) (xy 465.324642 -35.877526) (xy 465.199346 -35.909696)
			(xy 465.072276 -35.933936) (xy 464.943936 -35.950149) (xy 464.81483 -35.958272) (xy 464.68547 -35.958272)
			(xy 464.556364 -35.950149) (xy 464.428024 -35.933936) (xy 464.300954 -35.909696) (xy 464.175658 -35.877526)
			(xy 464.052628 -35.837551) (xy 463.932352 -35.78993) (xy 463.815303 -35.734851) (xy 463.701943 -35.672531)
			(xy 463.59272 -35.603216) (xy 463.488065 -35.52718) (xy 463.388391 -35.444722) (xy 463.294091 -35.356169)
			(xy 463.205538 -35.261869) (xy 463.12308 -35.162195) (xy 463.047044 -35.05754) (xy 462.977729 -34.948317)
			(xy 462.915409 -34.834957) (xy 462.86033 -34.717908) (xy 462.812709 -34.597632) (xy 462.772734 -34.474602)
			(xy 462.740564 -34.349306) (xy 462.716324 -34.222236) (xy 462.700111 -34.093896) (xy 462.691988 -33.96479)
			(xy 462.69148 -33.90011) (xy 383.546858 -33.90011) (xy 386.291836 -36.645088) (xy 425.80052 -36.645088)
			(xy 425.817528 -36.606561) (xy 425.857724 -36.532548) (xy 425.904641 -36.462604) (xy 425.957873 -36.397336)
			(xy 426.016956 -36.337313) (xy 426.081375 -36.283057) (xy 426.15057 -36.235041) (xy 426.223939 -36.193683)
			(xy 426.300843 -36.159342) (xy 426.380613 -36.132317) (xy 426.462554 -36.112844) (xy 426.545953 -36.101091)
			(xy 426.630084 -36.097163) (xy 426.714215 -36.101091) (xy 426.797614 -36.112844) (xy 426.879555 -36.132317)
			(xy 426.959325 -36.159342) (xy 427.036229 -36.193683) (xy 427.109598 -36.235041) (xy 427.178793 -36.283057)
			(xy 427.243212 -36.337313) (xy 427.302295 -36.397336) (xy 427.355527 -36.462604) (xy 427.402444 -36.532548)
			(xy 427.44264 -36.606561) (xy 427.459648 -36.645088) (xy 428.34052 -36.645088) (xy 428.357528 -36.606561)
			(xy 428.397724 -36.532548) (xy 428.444641 -36.462604) (xy 428.497873 -36.397336) (xy 428.556956 -36.337313)
			(xy 428.621375 -36.283057) (xy 428.69057 -36.235041) (xy 428.763939 -36.193683) (xy 428.840843 -36.159342)
			(xy 428.920613 -36.132317) (xy 429.002554 -36.112844) (xy 429.085953 -36.101091) (xy 429.170084 -36.097163)
			(xy 429.254215 -36.101091) (xy 429.337614 -36.112844) (xy 429.419555 -36.132317) (xy 429.499325 -36.159342)
			(xy 429.576229 -36.193683) (xy 429.649598 -36.235041) (xy 429.718793 -36.283057) (xy 429.783212 -36.337313)
			(xy 429.842295 -36.397336) (xy 429.895527 -36.462604) (xy 429.942444 -36.532548) (xy 429.98264 -36.606561)
			(xy 429.999648 -36.645088) (xy 448.15252 -36.645088) (xy 448.17748 -36.645668) (xy 448.226444 -36.655391)
			(xy 448.272563 -36.674498) (xy 448.314057 -36.702252) (xy 448.332098 -36.71951) (xy 452.556118 -40.94353)
			(xy 452.573337 -40.961605) (xy 452.601085 -41.003095) (xy 452.620204 -41.049201) (xy 452.62996 -41.098152)
			(xy 452.63054 -41.123108) (xy 452.63054 -70.932548) (xy 452.629969 -70.957509) (xy 452.620241 -71.006472)
			(xy 452.601132 -71.052591) (xy 452.573377 -71.094085) (xy 452.556118 -71.112126) (xy 451.146418 -72.521826)
			(xy 451.128366 -72.539071) (xy 451.086868 -72.566813) (xy 451.040755 -72.585926) (xy 450.991798 -72.595673)
			(xy 450.96684 -72.596248) (xy 432.311556 -72.596248) (xy 432.311556 -74.767948) (xy 432.311051 -74.873472)
			(xy 432.302967 -75.084366) (xy 432.286811 -75.294795) (xy 432.262608 -75.504452) (xy 432.230391 -75.713027)
			(xy 432.190209 -75.920215) (xy 432.142121 -76.125712) (xy 432.086197 -76.329216) (xy 432.02252 -76.530429)
			(xy 431.951182 -76.729056) (xy 431.872288 -76.924804) (xy 431.785955 -77.117386) (xy 431.692308 -77.306521)
			(xy 431.591486 -77.49193) (xy 431.483636 -77.673341) (xy 431.368917 -77.850488) (xy 431.247497 -78.02311)
			(xy 431.119554 -78.190956) (xy 430.985276 -78.353778) (xy 430.84486 -78.511337) (xy 430.698512 -78.663402)
			(xy 430.546447 -78.80975) (xy 430.388888 -78.950166) (xy 430.226066 -79.084444) (xy 430.05822 -79.212387)
			(xy 429.885598 -79.333807) (xy 429.708451 -79.448526) (xy 429.52704 -79.556376) (xy 429.341631 -79.657198)
			(xy 429.152496 -79.750845) (xy 428.959914 -79.837178) (xy 428.764166 -79.916072) (xy 428.565539 -79.98741)
			(xy 428.364326 -80.051087) (xy 428.160822 -80.107011) (xy 427.955325 -80.155099) (xy 427.748137 -80.195281)
			(xy 427.539562 -80.227498) (xy 427.329905 -80.251701) (xy 427.119476 -80.267857) (xy 426.908582 -80.275941)
			(xy 426.697534 -80.275941) (xy 426.48664 -80.267857) (xy 426.276211 -80.251701) (xy 426.066554 -80.227498)
			(xy 425.857979 -80.195281) (xy 425.650791 -80.155099) (xy 425.445294 -80.107011) (xy 425.24179 -80.051087)
			(xy 425.040577 -79.98741) (xy 424.84195 -79.916072) (xy 424.646202 -79.837178) (xy 424.45362 -79.750845)
			(xy 424.264485 -79.657198) (xy 424.079076 -79.556376) (xy 423.897665 -79.448526) (xy 423.720518 -79.333807)
			(xy 423.547896 -79.212387) (xy 423.38005 -79.084444) (xy 423.217228 -78.950166) (xy 423.059669 -78.80975)
			(xy 422.907604 -78.663402) (xy 422.761256 -78.511337) (xy 422.62084 -78.353778) (xy 422.486562 -78.190956)
			(xy 422.358619 -78.02311) (xy 422.237199 -77.850488) (xy 422.12248 -77.673341) (xy 422.01463 -77.49193)
			(xy 421.913808 -77.306521) (xy 421.820161 -77.117386) (xy 421.733828 -76.924804) (xy 421.654934 -76.729056)
			(xy 421.583596 -76.530429) (xy 421.519919 -76.329216) (xy 421.463995 -76.125712) (xy 421.415907 -75.920215)
			(xy 421.375725 -75.713027) (xy 421.343508 -75.504452) (xy 421.319305 -75.294795) (xy 421.303149 -75.084366)
			(xy 421.295065 -74.873472) (xy 421.29456 -74.767948) (xy 421.29456 -72.596248) (xy 396.797276 -72.596248)
			(xy 391.13714 -78.256384) (xy 391.13714 -94.404688) (xy 391.136594 -94.42965) (xy 391.126859 -94.478615)
			(xy 391.107741 -94.524733) (xy 391.07998 -94.566226) (xy 391.062718 -94.584266) (xy 382.027938 -103.619046)
			(xy 382.009881 -103.636285) (xy 381.968384 -103.664028) (xy 381.922273 -103.683141) (xy 381.873318 -103.692891)
			(xy 381.84836 -103.693468) (xy 378.815854 -103.693468) (xy 378.797521 -103.712401) (xy 378.756243 -103.745163)
			(xy 378.710557 -103.771431) (xy 378.661476 -103.790621) (xy 378.610089 -103.802308) (xy 378.557536 -103.806233)
			(xy 378.504983 -103.802308) (xy 378.453596 -103.790621) (xy 378.404515 -103.771431) (xy 378.358829 -103.745163)
			(xy 378.317551 -103.712401) (xy 378.299218 -103.693468) (xy 368.427508 -103.693468) (xy 368.410817 -103.715167)
			(xy 368.372245 -103.754012) (xy 368.328515 -103.786944) (xy 368.280527 -103.813287) (xy 368.229267 -103.8325)
			(xy 368.175786 -103.844187) (xy 368.121184 -103.84811) (xy 368.066582 -103.844187) (xy 368.013101 -103.8325)
			(xy 367.961841 -103.813287) (xy 367.913853 -103.786944) (xy 367.870123 -103.754012) (xy 367.831551 -103.715167)
			(xy 367.81486 -103.693468) (xy 364.584996 -103.693468) (xy 340.586006 -127.692458) (xy 458.401155 -127.692458)
			(xy 458.401155 -127.563318) (xy 458.409105 -127.434423) (xy 458.424975 -127.306263) (xy 458.448704 -127.179322)
			(xy 458.480203 -127.054083) (xy 458.519352 -126.93102) (xy 458.566003 -126.810601) (xy 458.619978 -126.693282)
			(xy 458.681073 -126.579508) (xy 458.749056 -126.469711) (xy 458.82367 -126.364308) (xy 458.904631 -126.263698)
			(xy 458.991631 -126.168263) (xy 459.084342 -126.078364) (xy 459.182412 -125.994343) (xy 459.285467 -125.916519)
			(xy 459.393118 -125.845187) (xy 459.504957 -125.780617) (xy 459.620558 -125.723055) (xy 459.739483 -125.672718)
			(xy 459.861282 -125.629798) (xy 459.985492 -125.594457) (xy 460.111641 -125.56683) (xy 460.239253 -125.547021)
			(xy 460.367842 -125.535105) (xy 460.49692 -125.531129) (xy 460.625998 -125.535105) (xy 460.754587 -125.547021)
			(xy 460.882199 -125.56683) (xy 461.008348 -125.594457) (xy 461.132558 -125.629798) (xy 461.254357 -125.672718)
			(xy 461.373282 -125.723055) (xy 461.488883 -125.780617) (xy 461.600722 -125.845187) (xy 461.708373 -125.916519)
			(xy 461.811428 -125.994343) (xy 461.909498 -126.078364) (xy 462.002209 -126.168263) (xy 462.089209 -126.263698)
			(xy 462.17017 -126.364308) (xy 462.244784 -126.469711) (xy 462.312767 -126.579508) (xy 462.373862 -126.693282)
			(xy 462.427837 -126.810601) (xy 462.474488 -126.93102) (xy 462.513637 -127.054083) (xy 462.545136 -127.179322)
			(xy 462.568865 -127.306263) (xy 462.584735 -127.434423) (xy 462.592685 -127.563318) (xy 462.593182 -127.627888)
			(xy 462.592685 -127.692458) (xy 462.584735 -127.821353) (xy 462.568865 -127.949513) (xy 462.545136 -128.076454)
			(xy 462.513637 -128.201693) (xy 462.474488 -128.324756) (xy 462.427837 -128.445175) (xy 462.373862 -128.562494)
			(xy 462.312767 -128.676268) (xy 462.244784 -128.786065) (xy 462.17017 -128.891468) (xy 462.089209 -128.992078)
			(xy 462.002209 -129.087513) (xy 461.909498 -129.177412) (xy 461.811428 -129.261433) (xy 461.708373 -129.339257)
			(xy 461.600722 -129.410589) (xy 461.488883 -129.475159) (xy 461.373282 -129.532721) (xy 461.254357 -129.583058)
			(xy 461.132558 -129.625978) (xy 461.008348 -129.661319) (xy 460.882199 -129.688946) (xy 460.754587 -129.708755)
			(xy 460.625998 -129.720671) (xy 460.49692 -129.724648) (xy 460.367842 -129.720671) (xy 460.239253 -129.708755)
			(xy 460.111641 -129.688946) (xy 459.985492 -129.661319) (xy 459.861282 -129.625978) (xy 459.739483 -129.583058)
			(xy 459.620558 -129.532721) (xy 459.504957 -129.475159) (xy 459.393118 -129.410589) (xy 459.285467 -129.339257)
			(xy 459.182412 -129.261433) (xy 459.084342 -129.177412) (xy 458.991631 -129.087513) (xy 458.904631 -128.992078)
			(xy 458.82367 -128.891468) (xy 458.749056 -128.786065) (xy 458.681073 -128.676268) (xy 458.619978 -128.562494)
			(xy 458.566003 -128.445175) (xy 458.519352 -128.324756) (xy 458.480203 -128.201693) (xy 458.448704 -128.076454)
			(xy 458.424975 -127.949513) (xy 458.409105 -127.821353) (xy 458.401155 -127.692458) (xy 340.586006 -127.692458)
			(xy 334.087978 -134.190486) (xy 334.069927 -134.207729) (xy 334.028425 -134.235459) (xy 333.982311 -134.254559)
			(xy 333.933357 -134.264296) (xy 333.9084 -134.264908) (xy 298.202858 -134.264908) (xy 298.189226 -134.288055)
			(xy 298.156462 -134.330627) (xy 298.118051 -134.368181) (xy 298.074752 -134.399975) (xy 298.02742 -134.425381)
			(xy 297.976992 -134.443895) (xy 297.924466 -134.455153) (xy 297.87088 -134.45893) (xy 297.817294 -134.455153)
			(xy 297.764768 -134.443895) (xy 297.71434 -134.425381) (xy 297.667008 -134.399975) (xy 297.623709 -134.368181)
			(xy 297.585298 -134.330627) (xy 297.552534 -134.288055) (xy 297.538902 -134.264908) (xy 255.447038 -134.264908)
			(xy 255.422076 -134.264355) (xy 255.373111 -134.254623) (xy 255.326993 -134.235508) (xy 255.2855 -134.207748)
			(xy 255.26746 -134.190486) (xy 240.114582 -119.037608) (xy 223.203516 -119.037608) (xy 219.147136 -123.093988)
			(xy 227.217732 -123.093988) (xy 227.217732 -122.230388) (xy 227.218218 -122.203137) (xy 227.225974 -122.149189)
			(xy 227.241329 -122.096894) (xy 227.263971 -122.047317) (xy 227.293437 -122.001467) (xy 227.329128 -121.960276)
			(xy 227.370319 -121.924585) (xy 227.416169 -121.895119) (xy 227.465746 -121.872477) (xy 227.518041 -121.857122)
			(xy 227.571989 -121.849366) (xy 227.626491 -121.849366) (xy 227.680439 -121.857122) (xy 227.732734 -121.872477)
			(xy 227.782311 -121.895119) (xy 227.828161 -121.924585) (xy 227.869352 -121.960276) (xy 227.905043 -122.001467)
			(xy 227.934509 -122.047317) (xy 227.957151 -122.096894) (xy 227.972506 -122.149189) (xy 227.980262 -122.203137)
			(xy 227.980748 -122.230388) (xy 227.980748 -123.093988) (xy 227.980262 -123.121239) (xy 227.972506 -123.175187)
			(xy 227.957151 -123.227482) (xy 227.934509 -123.277059) (xy 227.905043 -123.322909) (xy 227.869352 -123.3641)
			(xy 227.828161 -123.399791) (xy 227.782311 -123.429257) (xy 227.732734 -123.451899) (xy 227.680439 -123.467254)
			(xy 227.626491 -123.47501) (xy 227.571989 -123.47501) (xy 227.518041 -123.467254) (xy 227.465746 -123.451899)
			(xy 227.416169 -123.429257) (xy 227.370319 -123.399791) (xy 227.329128 -123.3641) (xy 227.293437 -123.322909)
			(xy 227.263971 -123.277059) (xy 227.241329 -123.227482) (xy 227.225974 -123.175187) (xy 227.218218 -123.121239)
			(xy 227.217732 -123.093988) (xy 219.147136 -123.093988) (xy 217.019378 -125.221746) (xy 225.535744 -125.221746)
			(xy 225.535744 -124.358146) (xy 225.53623 -124.330877) (xy 225.543992 -124.276893) (xy 225.559357 -124.224563)
			(xy 225.582014 -124.174953) (xy 225.6115 -124.129072) (xy 225.647215 -124.087855) (xy 225.688432 -124.05214)
			(xy 225.734313 -124.022654) (xy 225.783923 -123.999997) (xy 225.836253 -123.984632) (xy 225.890237 -123.97687)
			(xy 225.944775 -123.97687) (xy 225.998759 -123.984632) (xy 226.051089 -123.999997) (xy 226.100699 -124.022654)
			(xy 226.14658 -124.05214) (xy 226.187797 -124.087855) (xy 226.223512 -124.129072) (xy 226.252998 -124.174953)
			(xy 226.275655 -124.224563) (xy 226.29102 -124.276893) (xy 226.298782 -124.330877) (xy 226.299268 -124.358146)
			(xy 226.299268 -125.221746) (xy 226.298782 -125.249015) (xy 226.29102 -125.302999) (xy 226.275655 -125.355329)
			(xy 226.252998 -125.404939) (xy 226.223512 -125.45082) (xy 226.187797 -125.492037) (xy 226.14658 -125.527752)
			(xy 226.100699 -125.557238) (xy 226.051089 -125.579895) (xy 225.998759 -125.59526) (xy 225.944775 -125.603022)
			(xy 225.890237 -125.603022) (xy 225.836253 -125.59526) (xy 225.783923 -125.579895) (xy 225.734313 -125.557238)
			(xy 225.688432 -125.527752) (xy 225.647215 -125.492037) (xy 225.6115 -125.45082) (xy 225.582014 -125.404939)
			(xy 225.559357 -125.355329) (xy 225.543992 -125.302999) (xy 225.53623 -125.249015) (xy 225.535744 -125.221746)
			(xy 217.019378 -125.221746) (xy 214.915496 -127.325628) (xy 227.034852 -127.325628) (xy 227.034852 -126.462028)
			(xy 227.035338 -126.434777) (xy 227.043094 -126.380829) (xy 227.058449 -126.328534) (xy 227.081091 -126.278957)
			(xy 227.110557 -126.233107) (xy 227.146248 -126.191916) (xy 227.187439 -126.156225) (xy 227.233289 -126.126759)
			(xy 227.282866 -126.104117) (xy 227.335161 -126.088762) (xy 227.389109 -126.081006) (xy 227.443611 -126.081006)
			(xy 227.497559 -126.088762) (xy 227.549854 -126.104117) (xy 227.599431 -126.126759) (xy 227.645281 -126.156225)
			(xy 227.686472 -126.191916) (xy 227.722163 -126.233107) (xy 227.751629 -126.278957) (xy 227.774271 -126.328534)
			(xy 227.789626 -126.380829) (xy 227.797382 -126.434777) (xy 227.797868 -126.462028) (xy 227.797868 -127.140208)
			(xy 242.041172 -127.140208) (xy 242.041172 -126.276608) (xy 242.041658 -126.249357) (xy 242.049414 -126.195409)
			(xy 242.064769 -126.143114) (xy 242.087411 -126.093537) (xy 242.116877 -126.047687) (xy 242.152568 -126.006496)
			(xy 242.193759 -125.970805) (xy 242.239609 -125.941339) (xy 242.289186 -125.918697) (xy 242.341481 -125.903342)
			(xy 242.395429 -125.895586) (xy 242.449931 -125.895586) (xy 242.503879 -125.903342) (xy 242.556174 -125.918697)
			(xy 242.605751 -125.941339) (xy 242.651601 -125.970805) (xy 242.692792 -126.006496) (xy 242.728483 -126.047687)
			(xy 242.757949 -126.093537) (xy 242.780591 -126.143114) (xy 242.795946 -126.195409) (xy 242.803702 -126.249357)
			(xy 242.804188 -126.276608) (xy 242.804188 -127.140208) (xy 242.803702 -127.167459) (xy 242.795946 -127.221407)
			(xy 242.780591 -127.273702) (xy 242.757949 -127.323279) (xy 242.728483 -127.369129) (xy 242.692792 -127.41032)
			(xy 242.651601 -127.446011) (xy 242.605751 -127.475477) (xy 242.556174 -127.498119) (xy 242.503879 -127.513474)
			(xy 242.449931 -127.52123) (xy 242.395429 -127.52123) (xy 242.341481 -127.513474) (xy 242.289186 -127.498119)
			(xy 242.239609 -127.475477) (xy 242.193759 -127.446011) (xy 242.152568 -127.41032) (xy 242.116877 -127.369129)
			(xy 242.087411 -127.323279) (xy 242.064769 -127.273702) (xy 242.049414 -127.221407) (xy 242.041658 -127.167459)
			(xy 242.041172 -127.140208) (xy 227.797868 -127.140208) (xy 227.797868 -127.325628) (xy 227.797382 -127.352879)
			(xy 227.789626 -127.406827) (xy 227.774271 -127.459122) (xy 227.751629 -127.508699) (xy 227.722163 -127.554549)
			(xy 227.686472 -127.59574) (xy 227.645281 -127.631431) (xy 227.599431 -127.660897) (xy 227.549854 -127.683539)
			(xy 227.497559 -127.698894) (xy 227.443611 -127.70665) (xy 227.389109 -127.70665) (xy 227.335161 -127.698894)
			(xy 227.282866 -127.683539) (xy 227.233289 -127.660897) (xy 227.187439 -127.631431) (xy 227.146248 -127.59574)
			(xy 227.110557 -127.554549) (xy 227.081091 -127.508699) (xy 227.058449 -127.459122) (xy 227.043094 -127.406827)
			(xy 227.035338 -127.352879) (xy 227.034852 -127.325628) (xy 214.915496 -127.325628) (xy 213.167976 -129.073148)
			(xy 223.562672 -129.073148) (xy 223.562672 -128.209548) (xy 223.563115 -128.182788) (xy 223.570596 -128.129795)
			(xy 223.585403 -128.078365) (xy 223.607247 -128.029506) (xy 223.621092 -128.006602) (xy 223.636032 -127.983032)
			(xy 223.671662 -127.940084) (xy 223.713174 -127.902792) (xy 223.759681 -127.871951) (xy 223.810187 -127.848221)
			(xy 223.863614 -127.832109) (xy 223.918819 -127.823961) (xy 223.94672 -127.823468) (xy 223.973934 -127.823967)
			(xy 224.027808 -127.831715) (xy 224.080031 -127.84705) (xy 224.12954 -127.869661) (xy 224.175327 -127.899088)
			(xy 224.216462 -127.93473) (xy 224.252105 -127.975863) (xy 224.281533 -128.02165) (xy 224.304145 -128.071158)
			(xy 224.319483 -128.123381) (xy 224.327232 -128.177254) (xy 224.32772 -128.204468) (xy 224.32772 -128.204722)
			(xy 224.325942 -128.241552) (xy 224.325688 -128.243838) (xy 224.325688 -129.019808) (xy 240.086896 -129.019808)
			(xy 240.086896 -128.156208) (xy 240.087382 -128.128939) (xy 240.095144 -128.074955) (xy 240.110509 -128.022625)
			(xy 240.133166 -127.973015) (xy 240.162652 -127.927134) (xy 240.198367 -127.885917) (xy 240.239584 -127.850202)
			(xy 240.285465 -127.820716) (xy 240.335075 -127.798059) (xy 240.387405 -127.782694) (xy 240.441389 -127.774932)
			(xy 240.495927 -127.774932) (xy 240.549911 -127.782694) (xy 240.602241 -127.798059) (xy 240.651851 -127.820716)
			(xy 240.697732 -127.850202) (xy 240.738949 -127.885917) (xy 240.774664 -127.927134) (xy 240.80415 -127.973015)
			(xy 240.826807 -128.022625) (xy 240.842172 -128.074955) (xy 240.849934 -128.128939) (xy 240.85042 -128.156208)
			(xy 240.85042 -129.019808) (xy 240.849934 -129.047077) (xy 240.842172 -129.101061) (xy 240.826807 -129.153391)
			(xy 240.80415 -129.203001) (xy 240.774664 -129.248882) (xy 240.738949 -129.290099) (xy 240.697732 -129.325814)
			(xy 240.651851 -129.3553) (xy 240.602241 -129.377957) (xy 240.549911 -129.393322) (xy 240.495927 -129.401084)
			(xy 240.441389 -129.401084) (xy 240.387405 -129.393322) (xy 240.335075 -129.377957) (xy 240.285465 -129.3553)
			(xy 240.239584 -129.325814) (xy 240.198367 -129.290099) (xy 240.162652 -129.248882) (xy 240.133166 -129.203001)
			(xy 240.110509 -129.153391) (xy 240.095144 -129.101061) (xy 240.087382 -129.047077) (xy 240.086896 -129.019808)
			(xy 224.325688 -129.019808) (xy 224.325942 -129.022602) (xy 224.327226 -129.033861) (xy 224.328622 -129.056482)
			(xy 224.328736 -129.067814) (xy 224.328736 -129.068068) (xy 224.328226 -129.095352) (xy 224.320425 -129.14936)
			(xy 224.305035 -129.201713) (xy 224.282367 -129.251351) (xy 224.26803 -129.27457) (xy 224.253042 -129.297814)
			(xy 224.217376 -129.340083) (xy 224.175977 -129.376756) (xy 224.129714 -129.407061) (xy 224.079557 -129.430365)
			(xy 224.026559 -129.446176) (xy 223.971833 -129.454165) (xy 223.94418 -129.454656) (xy 223.91693 -129.454141)
			(xy 223.862986 -129.446383) (xy 223.810695 -129.431028) (xy 223.761121 -129.408388) (xy 223.715273 -129.378924)
			(xy 223.674084 -129.343236) (xy 223.638393 -129.30205) (xy 223.608926 -129.256204) (xy 223.586282 -129.206631)
			(xy 223.570923 -129.154341) (xy 223.563161 -129.100398) (xy 223.562672 -129.073148) (xy 213.167976 -129.073148)
			(xy 211.946744 -130.29438) (xy 211.933032 -130.307622) (xy 211.902353 -130.330245) (xy 211.868625 -130.348004)
			(xy 211.850732 -130.354578) (xy 211.844096 -130.382581) (xy 211.823553 -130.436336) (xy 211.795173 -130.486397)
			(xy 211.759598 -130.531631) (xy 211.717636 -130.571011) (xy 211.670237 -130.603644) (xy 211.618476 -130.628792)
			(xy 211.563526 -130.645884) (xy 211.506633 -130.654532) (xy 211.47786 -130.65506) (xy 211.448595 -130.654545)
			(xy 211.390752 -130.645614) (xy 211.334951 -130.627953) (xy 211.282502 -130.601976) (xy 211.234637 -130.568292)
			(xy 211.192478 -130.527693) (xy 211.157015 -130.481131) (xy 211.129081 -130.429698) (xy 211.118704 -130.40233)
			(xy 211.106766 -130.368802) (xy 203.972668 -130.368802) (xy 203.961238 -130.404108) (xy 203.952088 -130.430876)
			(xy 203.927005 -130.481578) (xy 203.894711 -130.528021) (xy 203.855914 -130.569187) (xy 203.811464 -130.604174)
			(xy 203.762336 -130.632215) (xy 203.709606 -130.652695) (xy 203.65443 -130.665166) (xy 203.598018 -130.669353)
			(xy 203.541606 -130.665166) (xy 203.48643 -130.652695) (xy 203.4337 -130.632215) (xy 203.384572 -130.604174)
			(xy 203.340122 -130.569187) (xy 203.301325 -130.528021) (xy 203.269031 -130.481578) (xy 203.243948 -130.430876)
			(xy 203.234798 -130.404108) (xy 203.223368 -130.368802) (xy 202.873864 -130.368802) (xy 202.859053 -130.393001)
			(xy 202.823401 -130.437134) (xy 202.781609 -130.475505) (xy 202.734599 -130.507267) (xy 202.683406 -130.531722)
			(xy 202.629157 -130.548331) (xy 202.573047 -130.556728) (xy 202.516313 -130.556728) (xy 202.460203 -130.548331)
			(xy 202.405954 -130.531722) (xy 202.354761 -130.507267) (xy 202.307751 -130.475505) (xy 202.265959 -130.437134)
			(xy 202.230307 -130.393001) (xy 202.215496 -130.368802) (xy 201.962258 -130.368802) (xy 201.949812 -130.401568)
			(xy 201.939789 -130.426825) (xy 201.913617 -130.474445) (xy 201.880951 -130.517867) (xy 201.842451 -130.556213)
			(xy 201.798898 -130.588705) (xy 201.751174 -130.614686) (xy 201.700245 -130.633628) (xy 201.647142 -130.64515)
			(xy 201.592942 -130.649016) (xy 201.538742 -130.64515) (xy 201.485639 -130.633628) (xy 201.43471 -130.614686)
			(xy 201.386986 -130.588705) (xy 201.343433 -130.556213) (xy 201.304933 -130.517867) (xy 201.272267 -130.474445)
			(xy 201.246095 -130.426825) (xy 201.236072 -130.401568) (xy 201.223626 -130.368802) (xy 199.145398 -130.368802)
			(xy 199.135746 -130.37312) (xy 199.111637 -130.383096) (xy 199.061383 -130.397122) (xy 199.009688 -130.404187)
			(xy 198.9836 -130.404616) (xy 198.957509 -130.404237) (xy 198.905808 -130.397177) (xy 198.855556 -130.383121)
			(xy 198.831454 -130.37312) (xy 198.821802 -130.368802) (xy 155.752038 -130.368802) (xy 155.738713 -130.392948)
			(xy 155.706171 -130.437473) (xy 155.667555 -130.476845) (xy 155.623669 -130.510244) (xy 155.575429 -130.536972)
			(xy 155.523843 -130.556472) (xy 155.469985 -130.568337) (xy 155.41498 -130.57232) (xy 155.359975 -130.568337)
			(xy 155.306117 -130.556472) (xy 155.254531 -130.536972) (xy 155.206291 -130.510244) (xy 155.162405 -130.476845)
			(xy 155.123789 -130.437473) (xy 155.091247 -130.392948) (xy 155.077922 -130.368802) (xy 151.123904 -130.368802)
			(xy 151.112982 -130.374644) (xy 151.085643 -130.388193) (xy 151.02771 -130.407331) (xy 150.967467 -130.416996)
			(xy 150.93696 -130.41757) (xy 150.906456 -130.416967) (xy 150.84622 -130.407292) (xy 150.788289 -130.388162)
			(xy 150.760938 -130.374644) (xy 150.750016 -130.368802) (xy 109.843824 -130.368802) (xy 109.831559 -130.391474)
			(xy 109.801462 -130.43332) (xy 109.765607 -130.470352) (xy 109.724754 -130.501784) (xy 109.67977 -130.526951)
			(xy 109.631608 -130.545318) (xy 109.581289 -130.556496) (xy 109.52988 -130.560249) (xy 109.478471 -130.556496)
			(xy 109.428152 -130.545318) (xy 109.37999 -130.526951) (xy 109.335006 -130.501784) (xy 109.294153 -130.470352)
			(xy 109.258298 -130.43332) (xy 109.228201 -130.391474) (xy 109.215936 -130.368802) (xy 62.791848 -130.368802)
			(xy 62.786514 -130.413506) (xy 62.78277 -130.440979) (xy 62.768364 -130.494521) (xy 62.746357 -130.545412)
			(xy 62.717211 -130.59258) (xy 62.681542 -130.63503) (xy 62.640102 -130.671866) (xy 62.593764 -130.702313)
			(xy 62.543504 -130.725728) (xy 62.490384 -130.741618) (xy 62.435523 -130.749648) (xy 62.380077 -130.749648)
			(xy 62.325216 -130.741618) (xy 62.272096 -130.725728) (xy 62.221836 -130.702313) (xy 62.175498 -130.671866)
			(xy 62.134058 -130.63503) (xy 62.098389 -130.59258) (xy 62.069243 -130.545412) (xy 62.047236 -130.494521)
			(xy 62.03283 -130.440979) (xy 62.029086 -130.413506) (xy 62.023752 -130.368802) (xy 41.66743 -130.368802)
			(xy 41.652625 -130.392975) (xy 41.616992 -130.437058) (xy 41.575229 -130.475384) (xy 41.528254 -130.507109)
			(xy 41.477104 -130.531535) (xy 41.422902 -130.548124) (xy 41.366842 -130.55651) (xy 41.310158 -130.55651)
			(xy 41.254098 -130.548124) (xy 41.199896 -130.531535) (xy 41.148746 -130.507109) (xy 41.101771 -130.475384)
			(xy 41.060008 -130.437058) (xy 41.024375 -130.392975) (xy 41.00957 -130.368802) (xy 40.547798 -130.368802)
			(xy 39.81958 -131.09702) (xy 228.682804 -131.09702) (xy 228.682804 -130.23342) (xy 228.68329 -130.206151)
			(xy 228.691052 -130.152167) (xy 228.706417 -130.099837) (xy 228.729074 -130.050227) (xy 228.75856 -130.004346)
			(xy 228.794275 -129.963129) (xy 228.835492 -129.927414) (xy 228.881373 -129.897928) (xy 228.930983 -129.875271)
			(xy 228.983313 -129.859906) (xy 229.037297 -129.852144) (xy 229.091835 -129.852144) (xy 229.145819 -129.859906)
			(xy 229.198149 -129.875271) (xy 229.247759 -129.897928) (xy 229.29364 -129.927414) (xy 229.334857 -129.963129)
			(xy 229.370572 -130.004346) (xy 229.400058 -130.050227) (xy 229.422715 -130.099837) (xy 229.43808 -130.152167)
			(xy 229.445842 -130.206151) (xy 229.446328 -130.23342) (xy 229.446328 -130.721608) (xy 242.041172 -130.721608)
			(xy 242.041172 -129.858008) (xy 242.041658 -129.830757) (xy 242.049414 -129.776809) (xy 242.064769 -129.724514)
			(xy 242.087411 -129.674937) (xy 242.116877 -129.629087) (xy 242.152568 -129.587896) (xy 242.193759 -129.552205)
			(xy 242.239609 -129.522739) (xy 242.289186 -129.500097) (xy 242.341481 -129.484742) (xy 242.395429 -129.476986)
			(xy 242.449931 -129.476986) (xy 242.503879 -129.484742) (xy 242.556174 -129.500097) (xy 242.605751 -129.522739)
			(xy 242.651601 -129.552205) (xy 242.692792 -129.587896) (xy 242.728483 -129.629087) (xy 242.757949 -129.674937)
			(xy 242.780591 -129.724514) (xy 242.795946 -129.776809) (xy 242.803702 -129.830757) (xy 242.804188 -129.858008)
			(xy 242.804188 -130.721608) (xy 242.803702 -130.748859) (xy 242.795946 -130.802807) (xy 242.780591 -130.855102)
			(xy 242.757949 -130.904679) (xy 242.728483 -130.950529) (xy 242.692792 -130.99172) (xy 242.651601 -131.027411)
			(xy 242.605751 -131.056877) (xy 242.556174 -131.079519) (xy 242.503879 -131.094874) (xy 242.449931 -131.10263)
			(xy 242.395429 -131.10263) (xy 242.341481 -131.094874) (xy 242.289186 -131.079519) (xy 242.239609 -131.056877)
			(xy 242.193759 -131.027411) (xy 242.152568 -130.99172) (xy 242.116877 -130.950529) (xy 242.087411 -130.904679)
			(xy 242.064769 -130.855102) (xy 242.049414 -130.802807) (xy 242.041658 -130.748859) (xy 242.041172 -130.721608)
			(xy 229.446328 -130.721608) (xy 229.446328 -131.09702) (xy 229.445842 -131.124289) (xy 229.43808 -131.178273)
			(xy 229.422715 -131.230603) (xy 229.400058 -131.280213) (xy 229.370572 -131.326094) (xy 229.334857 -131.367311)
			(xy 229.29364 -131.403026) (xy 229.247759 -131.432512) (xy 229.198149 -131.455169) (xy 229.145819 -131.470534)
			(xy 229.091835 -131.478296) (xy 229.037297 -131.478296) (xy 228.983313 -131.470534) (xy 228.930983 -131.455169)
			(xy 228.881373 -131.432512) (xy 228.835492 -131.403026) (xy 228.794275 -131.367311) (xy 228.75856 -131.326094)
			(xy 228.729074 -131.280213) (xy 228.706417 -131.230603) (xy 228.691052 -131.178273) (xy 228.68329 -131.124289)
			(xy 228.682804 -131.09702) (xy 39.81958 -131.09702) (xy 39.027354 -131.889246) (xy 39.00929 -131.906478)
			(xy 38.967796 -131.934221) (xy 38.921686 -131.953337) (xy 38.872733 -131.963089) (xy 38.847776 -131.963668)
			(xy 30.14218 -131.963668) (xy 30.117221 -131.963072) (xy 30.068259 -131.953351) (xy 30.02214 -131.934248)
			(xy 29.980645 -131.906501) (xy 29.962602 -131.889246) (xy 25.027382 -126.954026) (xy 25.010142 -126.93597)
			(xy 24.982398 -126.894473) (xy 24.963285 -126.848361) (xy 24.953536 -126.799406) (xy 24.95296 -126.774448)
			(xy 3.523996 -126.774448) (xy 3.523996 -132.529347) (xy 231.621126 -132.529347) (xy 231.621126 -132.474853)
			(xy 231.628881 -132.420915) (xy 231.644233 -132.368628) (xy 231.666869 -132.319059) (xy 231.69633 -132.273216)
			(xy 231.732014 -132.232031) (xy 231.773196 -132.196344) (xy 231.819038 -132.166881) (xy 231.868606 -132.144241)
			(xy 231.920891 -132.128886) (xy 231.974829 -132.121128) (xy 232.002076 -132.12064) (xy 232.865676 -132.12064)
			(xy 232.892933 -132.121005) (xy 232.946894 -132.128761) (xy 232.999201 -132.144116) (xy 233.048791 -132.16676)
			(xy 233.094653 -132.196231) (xy 233.135853 -132.23193) (xy 233.171554 -132.273128) (xy 233.201028 -132.318988)
			(xy 233.223675 -132.368576) (xy 233.239034 -132.420883) (xy 233.246793 -132.474843) (xy 233.246793 -132.529357)
			(xy 233.239034 -132.583317) (xy 233.223675 -132.635624) (xy 233.201028 -132.685212) (xy 233.171554 -132.731072)
			(xy 233.135853 -132.77227) (xy 233.094653 -132.807968) (xy 233.048791 -132.83744) (xy 232.999201 -132.860084)
			(xy 232.946894 -132.875439) (xy 232.892933 -132.883195) (xy 232.865676 -132.883656) (xy 232.002076 -132.883656)
			(xy 231.974829 -132.883072) (xy 231.920891 -132.875314) (xy 231.868606 -132.859959) (xy 231.819038 -132.837319)
			(xy 231.773196 -132.807856) (xy 231.732014 -132.772169) (xy 231.69633 -132.730984) (xy 231.666869 -132.685141)
			(xy 231.644233 -132.635572) (xy 231.628881 -132.583285) (xy 231.621126 -132.529347) (xy 3.523996 -132.529347)
			(xy 3.523996 -135.31065) (xy 225.204003 -135.31065) (xy 225.204003 -135.25615) (xy 225.21176 -135.202204)
			(xy 225.227115 -135.149911) (xy 225.249756 -135.100336) (xy 225.279222 -135.054487) (xy 225.314914 -135.013299)
			(xy 225.356103 -134.97761) (xy 225.401953 -134.948146) (xy 225.45153 -134.925508) (xy 225.503823 -134.910156)
			(xy 225.55777 -134.902402) (xy 225.58502 -134.90194) (xy 226.44862 -134.90194) (xy 226.475874 -134.902331)
			(xy 226.529826 -134.910091) (xy 226.582125 -134.92545) (xy 226.631706 -134.948095) (xy 226.67756 -134.977566)
			(xy 226.718753 -135.013262) (xy 226.754446 -135.054456) (xy 226.755856 -135.05665) (xy 228.531403 -135.05665)
			(xy 228.531403 -135.00215) (xy 228.53916 -134.948204) (xy 228.554515 -134.895911) (xy 228.577156 -134.846336)
			(xy 228.606622 -134.800487) (xy 228.642314 -134.759299) (xy 228.683503 -134.72361) (xy 228.729353 -134.694146)
			(xy 228.77893 -134.671508) (xy 228.831223 -134.656156) (xy 228.88517 -134.648402) (xy 228.91242 -134.64794)
			(xy 229.77602 -134.64794) (xy 229.803274 -134.648331) (xy 229.857226 -134.656091) (xy 229.909525 -134.67145)
			(xy 229.959106 -134.694095) (xy 230.00496 -134.723566) (xy 230.046153 -134.759262) (xy 230.081846 -134.800456)
			(xy 230.111315 -134.846312) (xy 230.133957 -134.895894) (xy 230.149313 -134.948193) (xy 230.15707 -135.002146)
			(xy 230.15707 -135.056654) (xy 230.149313 -135.110607) (xy 230.145996 -135.121904) (xy 234.029504 -135.121904)
			(xy 234.029504 -134.258304) (xy 234.02999 -134.231035) (xy 234.037752 -134.177051) (xy 234.053117 -134.124721)
			(xy 234.075774 -134.075111) (xy 234.10526 -134.02923) (xy 234.140975 -133.988013) (xy 234.182192 -133.952298)
			(xy 234.228073 -133.922812) (xy 234.277683 -133.900155) (xy 234.330013 -133.88479) (xy 234.383997 -133.877028)
			(xy 234.438535 -133.877028) (xy 234.492519 -133.88479) (xy 234.544849 -133.900155) (xy 234.594459 -133.922812)
			(xy 234.64034 -133.952298) (xy 234.681557 -133.988013) (xy 234.717272 -134.02923) (xy 234.746758 -134.075111)
			(xy 234.769415 -134.124721) (xy 234.78478 -134.177051) (xy 234.792542 -134.231035) (xy 234.793028 -134.258304)
			(xy 234.793028 -134.768971) (xy 236.02439 -134.768971) (xy 236.02439 -134.714429) (xy 236.032152 -134.660443)
			(xy 236.047518 -134.608111) (xy 236.070174 -134.558498) (xy 236.09966 -134.512615) (xy 236.135376 -134.471394)
			(xy 236.176594 -134.435676) (xy 236.222475 -134.406186) (xy 236.272087 -134.383527) (xy 236.324418 -134.368158)
			(xy 236.378403 -134.360392) (xy 236.405674 -134.359904) (xy 237.178342 -134.359904) (xy 237.205607 -134.360461)
			(xy 237.259581 -134.368227) (xy 237.311901 -134.383595) (xy 237.361502 -134.406251) (xy 237.407373 -134.435736)
			(xy 237.448582 -134.471448) (xy 237.48429 -134.512661) (xy 237.513769 -134.558535) (xy 237.53642 -134.608138)
			(xy 237.551782 -134.66046) (xy 237.559542 -134.714435) (xy 237.559542 -134.768965) (xy 237.551782 -134.82294)
			(xy 237.53642 -134.875262) (xy 237.513769 -134.924865) (xy 237.48429 -134.970739) (xy 237.448582 -135.011952)
			(xy 237.407373 -135.047664) (xy 237.361502 -135.077149) (xy 237.311901 -135.099805) (xy 237.259581 -135.115173)
			(xy 237.205607 -135.122939) (xy 237.178342 -135.123428) (xy 236.405674 -135.123428) (xy 236.378403 -135.123008)
			(xy 236.324418 -135.115242) (xy 236.272087 -135.099873) (xy 236.222475 -135.077214) (xy 236.176594 -135.047724)
			(xy 236.135376 -135.012006) (xy 236.09966 -134.970785) (xy 236.070174 -134.924902) (xy 236.047518 -134.875289)
			(xy 236.032152 -134.822957) (xy 236.02439 -134.768971) (xy 234.793028 -134.768971) (xy 234.793028 -135.121904)
			(xy 234.792542 -135.149173) (xy 234.786383 -135.192008) (xy 238.645192 -135.192008) (xy 238.645192 -134.328408)
			(xy 238.645678 -134.301157) (xy 238.653434 -134.247209) (xy 238.668789 -134.194914) (xy 238.691431 -134.145337)
			(xy 238.720897 -134.099487) (xy 238.756588 -134.058296) (xy 238.797779 -134.022605) (xy 238.843629 -133.993139)
			(xy 238.893206 -133.970497) (xy 238.945501 -133.955142) (xy 238.999449 -133.947386) (xy 239.053951 -133.947386)
			(xy 239.107899 -133.955142) (xy 239.160194 -133.970497) (xy 239.209771 -133.993139) (xy 239.255621 -134.022605)
			(xy 239.271831 -134.036651) (xy 242.034062 -134.036651) (xy 242.034062 -133.982149) (xy 242.041817 -133.928203)
			(xy 242.057171 -133.875909) (xy 242.07981 -133.826333) (xy 242.109274 -133.780482) (xy 242.144963 -133.739291)
			(xy 242.18615 -133.703598) (xy 242.231997 -133.67413) (xy 242.281572 -133.651485) (xy 242.333864 -133.636126)
			(xy 242.387809 -133.628365) (xy 242.41506 -133.627876) (xy 243.27866 -133.627876) (xy 243.305914 -133.628369)
			(xy 243.359867 -133.636121) (xy 243.412167 -133.651473) (xy 243.46175 -133.674112) (xy 243.507606 -133.703577)
			(xy 243.548802 -133.73927) (xy 243.584499 -133.780462) (xy 243.613969 -133.826315) (xy 243.636613 -133.875895)
			(xy 243.651971 -133.928194) (xy 243.659729 -133.982146) (xy 243.659729 -134.036654) (xy 243.651971 -134.090606)
			(xy 243.636613 -134.142905) (xy 243.613969 -134.192485) (xy 243.584499 -134.238338) (xy 243.548802 -134.27953)
			(xy 243.507606 -134.315223) (xy 243.46175 -134.344688) (xy 243.412167 -134.367327) (xy 243.359867 -134.382679)
			(xy 243.305914 -134.390431) (xy 243.27866 -134.390892) (xy 242.41506 -134.390892) (xy 242.387809 -134.390435)
			(xy 242.333864 -134.382674) (xy 242.281572 -134.367315) (xy 242.231997 -134.34467) (xy 242.18615 -134.315202)
			(xy 242.144963 -134.279509) (xy 242.109274 -134.238318) (xy 242.07981 -134.192467) (xy 242.057171 -134.142891)
			(xy 242.041817 -134.090597) (xy 242.034062 -134.036651) (xy 239.271831 -134.036651) (xy 239.296812 -134.058296)
			(xy 239.332503 -134.099487) (xy 239.361969 -134.145337) (xy 239.384611 -134.194914) (xy 239.399966 -134.247209)
			(xy 239.407722 -134.301157) (xy 239.408208 -134.328408) (xy 239.408208 -135.192008) (xy 239.407722 -135.219259)
			(xy 239.399966 -135.273207) (xy 239.384611 -135.325502) (xy 239.361969 -135.375079) (xy 239.332503 -135.420929)
			(xy 239.296812 -135.46212) (xy 239.255621 -135.497811) (xy 239.250425 -135.50115) (xy 244.457203 -135.50115)
			(xy 244.457203 -135.44665) (xy 244.46496 -135.392704) (xy 244.480315 -135.340411) (xy 244.502956 -135.290836)
			(xy 244.532422 -135.244987) (xy 244.568114 -135.203799) (xy 244.609303 -135.16811) (xy 244.655153 -135.138646)
			(xy 244.70473 -135.116008) (xy 244.757023 -135.100656) (xy 244.81097 -135.092902) (xy 244.83822 -135.09244)
			(xy 245.70182 -135.09244) (xy 245.729074 -135.092831) (xy 245.783026 -135.100591) (xy 245.835325 -135.11595)
			(xy 245.884906 -135.138595) (xy 245.93076 -135.168066) (xy 245.971953 -135.203762) (xy 246.007646 -135.244956)
			(xy 246.037115 -135.290812) (xy 246.059757 -135.340394) (xy 246.075113 -135.392693) (xy 246.08287 -135.446646)
			(xy 246.08287 -135.501154) (xy 246.075113 -135.555107) (xy 246.059757 -135.607406) (xy 246.037115 -135.656988)
			(xy 246.007646 -135.702844) (xy 245.971953 -135.744038) (xy 245.93076 -135.779734) (xy 245.884906 -135.809205)
			(xy 245.835325 -135.83185) (xy 245.783026 -135.847209) (xy 245.729074 -135.854969) (xy 245.70182 -135.855456)
			(xy 244.83822 -135.855456) (xy 244.81097 -135.854898) (xy 244.757023 -135.847144) (xy 244.70473 -135.831792)
			(xy 244.655153 -135.809154) (xy 244.609303 -135.77969) (xy 244.568114 -135.744001) (xy 244.532422 -135.702813)
			(xy 244.502956 -135.656964) (xy 244.480315 -135.607389) (xy 244.46496 -135.555096) (xy 244.457203 -135.50115)
			(xy 239.250425 -135.50115) (xy 239.209771 -135.527277) (xy 239.160194 -135.549919) (xy 239.107899 -135.565274)
			(xy 239.053951 -135.57303) (xy 238.999449 -135.57303) (xy 238.945501 -135.565274) (xy 238.893206 -135.549919)
			(xy 238.843629 -135.527277) (xy 238.797779 -135.497811) (xy 238.756588 -135.46212) (xy 238.720897 -135.420929)
			(xy 238.691431 -135.375079) (xy 238.668789 -135.325502) (xy 238.653434 -135.273207) (xy 238.645678 -135.219259)
			(xy 238.645192 -135.192008) (xy 234.786383 -135.192008) (xy 234.78478 -135.203157) (xy 234.769415 -135.255487)
			(xy 234.746758 -135.305097) (xy 234.717272 -135.350978) (xy 234.681557 -135.392195) (xy 234.64034 -135.42791)
			(xy 234.594459 -135.457396) (xy 234.544849 -135.480053) (xy 234.492519 -135.495418) (xy 234.438535 -135.50318)
			(xy 234.383997 -135.50318) (xy 234.330013 -135.495418) (xy 234.277683 -135.480053) (xy 234.228073 -135.457396)
			(xy 234.182192 -135.42791) (xy 234.140975 -135.392195) (xy 234.10526 -135.350978) (xy 234.075774 -135.305097)
			(xy 234.053117 -135.255487) (xy 234.037752 -135.203157) (xy 234.02999 -135.149173) (xy 234.029504 -135.121904)
			(xy 230.145996 -135.121904) (xy 230.133957 -135.162906) (xy 230.111315 -135.212488) (xy 230.081846 -135.258344)
			(xy 230.046153 -135.299538) (xy 230.00496 -135.335234) (xy 229.959106 -135.364705) (xy 229.909525 -135.38735)
			(xy 229.857226 -135.402709) (xy 229.803274 -135.410469) (xy 229.77602 -135.410956) (xy 228.91242 -135.410956)
			(xy 228.88517 -135.410398) (xy 228.831223 -135.402644) (xy 228.77893 -135.387292) (xy 228.729353 -135.364654)
			(xy 228.683503 -135.33519) (xy 228.642314 -135.299501) (xy 228.606622 -135.258313) (xy 228.577156 -135.212464)
			(xy 228.554515 -135.162889) (xy 228.53916 -135.110596) (xy 228.531403 -135.05665) (xy 226.755856 -135.05665)
			(xy 226.783915 -135.100312) (xy 226.806557 -135.149894) (xy 226.821913 -135.202193) (xy 226.82967 -135.256146)
			(xy 226.82967 -135.310654) (xy 226.821913 -135.364607) (xy 226.806557 -135.416906) (xy 226.783915 -135.466488)
			(xy 226.754446 -135.512344) (xy 226.718753 -135.553538) (xy 226.67756 -135.589234) (xy 226.631706 -135.618705)
			(xy 226.582125 -135.64135) (xy 226.529826 -135.656709) (xy 226.475874 -135.664469) (xy 226.44862 -135.664956)
			(xy 225.58502 -135.664956) (xy 225.55777 -135.664398) (xy 225.503823 -135.656644) (xy 225.45153 -135.641292)
			(xy 225.401953 -135.618654) (xy 225.356103 -135.58919) (xy 225.314914 -135.553501) (xy 225.279222 -135.512313)
			(xy 225.249756 -135.466464) (xy 225.227115 -135.416889) (xy 225.21176 -135.364596) (xy 225.204003 -135.31065)
			(xy 3.523996 -135.31065) (xy 3.523996 -137.199664) (xy 337.46447 -137.199664) (xy 337.46447 -137.145136)
			(xy 337.47223 -137.091163) (xy 337.487591 -137.038843) (xy 337.510241 -136.989242) (xy 337.539719 -136.943369)
			(xy 337.575425 -136.902158) (xy 337.616632 -136.866447) (xy 337.662502 -136.836963) (xy 337.7121 -136.814307)
			(xy 337.764418 -136.79894) (xy 337.81839 -136.791173) (xy 337.845654 -136.790684) (xy 338.618322 -136.790684)
			(xy 338.645594 -136.79108) (xy 338.699581 -136.798845) (xy 338.751915 -136.814214) (xy 338.801528 -136.836874)
			(xy 338.847412 -136.866364) (xy 338.888632 -136.902084) (xy 338.924349 -136.943306) (xy 338.953836 -136.989191)
			(xy 338.976493 -137.038806) (xy 338.991859 -137.09114) (xy 338.999622 -137.145128) (xy 338.999622 -137.199672)
			(xy 338.991859 -137.25366) (xy 338.976493 -137.305994) (xy 338.953836 -137.355609) (xy 338.924349 -137.401494)
			(xy 338.888632 -137.442716) (xy 338.847412 -137.478436) (xy 338.801528 -137.507926) (xy 338.751915 -137.530586)
			(xy 338.699581 -137.545955) (xy 338.645594 -137.55372) (xy 338.618322 -137.554208) (xy 337.845654 -137.554208)
			(xy 337.81839 -137.553627) (xy 337.764418 -137.54586) (xy 337.7121 -137.530493) (xy 337.662502 -137.507837)
			(xy 337.616632 -137.478353) (xy 337.575425 -137.442642) (xy 337.539719 -137.401431) (xy 337.510241 -137.355558)
			(xy 337.487591 -137.305957) (xy 337.47223 -137.253637) (xy 337.46447 -137.199664) (xy 3.523996 -137.199664)
			(xy 3.523996 -137.622788) (xy 340.085172 -137.622788) (xy 340.085172 -136.759188) (xy 340.085658 -136.731937)
			(xy 340.093414 -136.677989) (xy 340.108769 -136.625694) (xy 340.131411 -136.576117) (xy 340.160877 -136.530267)
			(xy 340.196568 -136.489076) (xy 340.237759 -136.453385) (xy 340.283609 -136.423919) (xy 340.333186 -136.401277)
			(xy 340.385481 -136.385922) (xy 340.439429 -136.378166) (xy 340.493931 -136.378166) (xy 340.547879 -136.385922)
			(xy 340.600174 -136.401277) (xy 340.649751 -136.423919) (xy 340.695601 -136.453385) (xy 340.736792 -136.489076)
			(xy 340.772483 -136.530267) (xy 340.801949 -136.576117) (xy 340.824591 -136.625694) (xy 340.839946 -136.677989)
			(xy 340.847702 -136.731937) (xy 340.848188 -136.759188) (xy 340.848188 -137.622788) (xy 340.847702 -137.650039)
			(xy 340.839946 -137.703987) (xy 340.824591 -137.756282) (xy 340.801949 -137.805859) (xy 340.772483 -137.851709)
			(xy 340.736792 -137.8929) (xy 340.695601 -137.928591) (xy 340.649751 -137.958057) (xy 340.600174 -137.980699)
			(xy 340.547879 -137.996054) (xy 340.493931 -138.00381) (xy 340.439429 -138.00381) (xy 340.385481 -137.996054)
			(xy 340.333186 -137.980699) (xy 340.283609 -137.958057) (xy 340.237759 -137.928591) (xy 340.196568 -137.8929)
			(xy 340.160877 -137.851709) (xy 340.131411 -137.805859) (xy 340.108769 -137.756282) (xy 340.093414 -137.703987)
			(xy 340.085658 -137.650039) (xy 340.085172 -137.622788) (xy 3.523996 -137.622788) (xy 3.523996 -160.465845)
			(xy 5.068429 -160.465845) (xy 5.073758 -160.260626) (xy 5.087074 -160.05577) (xy 5.108356 -159.851588)
			(xy 5.137571 -159.64839) (xy 5.174676 -159.446483) (xy 5.219614 -159.246174) (xy 5.272318 -159.047766)
			(xy 5.332706 -158.851561) (xy 5.400688 -158.657856) (xy 5.47616 -158.466945) (xy 5.559009 -158.279117)
			(xy 5.649107 -158.094658) (xy 5.74632 -157.913846) (xy 5.850499 -157.736956) (xy 5.961486 -157.564257)
			(xy 6.079113 -157.39601) (xy 6.203201 -157.232471) (xy 6.333563 -157.073886) (xy 6.470001 -156.920498)
			(xy 6.612307 -156.772539) (xy 6.760267 -156.630232) (xy 6.913655 -156.493795) (xy 7.072239 -156.363432)
			(xy 7.235778 -156.239344) (xy 7.404025 -156.121717) (xy 7.576725 -156.01073) (xy 7.753614 -155.906551)
			(xy 7.934426 -155.809338) (xy 8.118886 -155.719239) (xy 8.306713 -155.636391) (xy 8.497625 -155.560919)
			(xy 8.69133 -155.492937) (xy 8.887535 -155.432548) (xy 9.085942 -155.379845) (xy 9.286251 -155.334907)
			(xy 9.488158 -155.297802) (xy 9.691356 -155.268586) (xy 9.895538 -155.247304) (xy 10.100394 -155.233988)
			(xy 10.305613 -155.228659) (xy 10.510883 -155.231324) (xy 10.715895 -155.241979) (xy 10.920336 -155.260609)
			(xy 11.123896 -155.287184) (xy 11.326268 -155.321665) (xy 11.527143 -155.363999) (xy 11.726218 -155.414122)
			(xy 11.923191 -155.471958) (xy 12.117762 -155.53742) (xy 12.309637 -155.610408) (xy 12.498524 -155.690811)
			(xy 12.684138 -155.778507) (xy 12.866196 -155.873364) (xy 13.044424 -155.975238) (xy 13.218549 -156.083974)
			(xy 13.388309 -156.199407) (xy 13.553445 -156.321362) (xy 13.713708 -156.449655) (xy 13.868855 -156.58409)
			(xy 14.018649 -156.724463) (xy 14.162864 -156.870563) (xy 14.301282 -157.022167) (xy 14.433691 -157.179045)
			(xy 14.559893 -157.34096) (xy 14.679694 -157.507666) (xy 14.792913 -157.67891) (xy 14.89938 -157.854432)
			(xy 14.998931 -158.033967) (xy 15.091417 -158.217242) (xy 15.176697 -158.403978) (xy 15.254641 -158.593893)
			(xy 15.325132 -158.7867) (xy 15.388062 -158.982104) (xy 15.443337 -159.179811) (xy 15.490871 -159.379519)
			(xy 15.530594 -159.580928) (xy 15.562445 -159.78373) (xy 15.586376 -159.987618) (xy 15.60235 -160.192284)
			(xy 15.610343 -160.397416) (xy 15.61084 -160.50006) (xy 15.610795 -160.537466) (xy 15.60978 -160.612272)
			(xy 15.608808 -160.649666) (xy 15.608941 -160.664851) (xy 15.617041 -160.694101) (xy 15.633374 -160.719682)
			(xy 15.656499 -160.739339) (xy 15.684376 -160.751339) (xy 15.714549 -160.754624) (xy 15.744355 -160.748903)
			(xy 15.771168 -160.734681) (xy 15.78229 -160.724342) (xy 17.600422 -158.90621) (xy 17.618472 -158.888966)
			(xy 17.659975 -158.861237) (xy 17.706089 -158.842137) (xy 17.755043 -158.832399) (xy 17.78 -158.831788)
			(xy 27.341322 -158.831788) (xy 27.356351 -158.831252) (xy 27.385106 -158.822499) (xy 27.410069 -158.805757)
			(xy 27.42908 -158.782475) (xy 27.440494 -158.754669) (xy 27.443321 -158.724744) (xy 27.437318 -158.695292)
			(xy 27.423005 -158.668862) (xy 27.401619 -158.64774) (xy 27.388566 -158.640272) (xy 27.297508 -158.591788)
			(xy 27.118677 -158.48889) (xy 26.943824 -158.379368) (xy 26.773195 -158.263376) (xy 26.607029 -158.141076)
			(xy 26.445559 -158.012641) (xy 26.289011 -157.878249) (xy 26.137605 -157.738089) (xy 25.991553 -157.592359)
			(xy 25.85106 -157.441262) (xy 25.716324 -157.285011) (xy 25.587532 -157.123824) (xy 25.464867 -156.957927)
			(xy 25.348499 -156.787554) (xy 25.238592 -156.612944) (xy 25.1353 -156.43434) (xy 25.038769 -156.251994)
			(xy 24.949133 -156.066161) (xy 24.866518 -155.877102) (xy 24.79104 -155.685083) (xy 24.722804 -155.490372)
			(xy 24.661908 -155.293242) (xy 24.608435 -155.093971) (xy 24.562462 -154.892837) (xy 24.524051 -154.690123)
			(xy 24.493259 -154.486112) (xy 24.470126 -154.281092) (xy 24.454687 -154.075349) (xy 24.446962 -153.869173)
			(xy 24.446484 -153.766012) (xy 24.446989 -153.660488) (xy 24.455073 -153.449594) (xy 24.471229 -153.239165)
			(xy 24.495432 -153.029508) (xy 24.527649 -152.820933) (xy 24.567831 -152.613745) (xy 24.615919 -152.408248)
			(xy 24.671843 -152.204744) (xy 24.73552 -152.003531) (xy 24.806858 -151.804904) (xy 24.885752 -151.609156)
			(xy 24.972085 -151.416574) (xy 25.065732 -151.227439) (xy 25.166554 -151.04203) (xy 25.274404 -150.860619)
			(xy 25.389123 -150.683472) (xy 25.510543 -150.51085) (xy 25.638486 -150.343004) (xy 25.772764 -150.180182)
			(xy 25.91318 -150.022623) (xy 26.059528 -149.870558) (xy 26.211593 -149.72421) (xy 26.369152 -149.583794)
			(xy 26.531974 -149.449516) (xy 26.69982 -149.321573) (xy 26.872442 -149.200153) (xy 27.049589 -149.085434)
			(xy 27.231 -148.977584) (xy 27.416409 -148.876762) (xy 27.605544 -148.783115) (xy 27.798126 -148.696782)
			(xy 27.993874 -148.617888) (xy 28.192501 -148.54655) (xy 28.393714 -148.482873) (xy 28.597218 -148.426949)
			(xy 28.802715 -148.378861) (xy 29.009903 -148.338679) (xy 29.218478 -148.306462) (xy 29.428135 -148.282259)
			(xy 29.638564 -148.266103) (xy 29.849458 -148.258019) (xy 30.060506 -148.258019) (xy 30.2714 -148.266103)
			(xy 30.481829 -148.282259) (xy 30.691486 -148.306462) (xy 30.900061 -148.338679) (xy 31.107249 -148.378861)
			(xy 31.312746 -148.426949) (xy 31.51625 -148.482873) (xy 31.717463 -148.54655) (xy 31.91609 -148.617888)
			(xy 32.111838 -148.696782) (xy 32.30442 -148.783115) (xy 32.493555 -148.876762) (xy 32.678964 -148.977584)
			(xy 32.860375 -149.085434) (xy 33.037522 -149.200153) (xy 33.210144 -149.321573) (xy 33.37799 -149.449516)
			(xy 33.540812 -149.583794) (xy 33.698371 -149.72421) (xy 33.850436 -149.870558) (xy 33.996784 -150.022623)
			(xy 34.1372 -150.180182) (xy 34.271478 -150.343004) (xy 34.399421 -150.51085) (xy 34.520841 -150.683472)
			(xy 34.63556 -150.860619) (xy 34.74341 -151.04203) (xy 34.844232 -151.227439) (xy 34.937879 -151.416574)
			(xy 35.024212 -151.609156) (xy 35.103106 -151.804904) (xy 35.174444 -152.003531) (xy 35.238121 -152.204744)
			(xy 35.294045 -152.408248) (xy 35.342133 -152.613745) (xy 35.382315 -152.820933) (xy 35.414532 -153.029508)
			(xy 35.438735 -153.239165) (xy 35.454891 -153.449594) (xy 35.462975 -153.660488) (xy 35.46348 -153.766012)
			(xy 35.462984 -153.869172) (xy 35.455258 -154.075348) (xy 35.439818 -154.28109) (xy 35.416685 -154.48611)
			(xy 35.385892 -154.690119) (xy 35.347481 -154.892833) (xy 35.301507 -155.093966) (xy 35.248034 -155.293237)
			(xy 35.187137 -155.490365) (xy 35.118902 -155.685076) (xy 35.043424 -155.877095) (xy 34.96081 -156.066153)
			(xy 34.871174 -156.251985) (xy 34.774643 -156.43433) (xy 34.671352 -156.612934) (xy 34.561446 -156.787544)
			(xy 34.445079 -156.957917) (xy 34.322414 -157.123813) (xy 34.193624 -157.285) (xy 34.058889 -157.441251)
			(xy 33.918397 -157.592348) (xy 33.772347 -157.738079) (xy 33.620942 -157.878239) (xy 33.464395 -158.012631)
			(xy 33.302926 -158.141068) (xy 33.136762 -158.263368) (xy 32.966134 -158.379361) (xy 32.791283 -158.488884)
			(xy 32.612454 -158.591783) (xy 32.521398 -158.640272) (xy 32.508325 -158.647715) (xy 32.486922 -158.668835)
			(xy 32.472595 -158.695272) (xy 32.466585 -158.724735) (xy 32.469413 -158.754671) (xy 32.480833 -158.782487)
			(xy 32.499857 -158.805774) (xy 32.524836 -158.822513) (xy 32.553607 -158.831255) (xy 32.568642 -158.831788)
			(xy 47.834296 -158.831788) (xy 48.884078 -157.782006) (xy 48.884078 -139.17295) (xy 48.884643 -139.147989)
			(xy 48.894371 -139.099024) (xy 48.913483 -139.052906) (xy 48.94124 -139.011413) (xy 48.9585 -138.993372)
			(xy 49.6316 -138.320272) (xy 49.649644 -138.303018) (xy 49.691145 -138.275277) (xy 49.737261 -138.256168)
			(xy 49.786219 -138.246424) (xy 49.811178 -138.24585) (xy 98.148902 -138.24585) (xy 98.173864 -138.246391)
			(xy 98.222829 -138.256128) (xy 98.268947 -138.275247) (xy 98.31044 -138.30301) (xy 98.32848 -138.320272)
			(xy 114.247676 -154.239468) (xy 186.742832 -154.239468) (xy 186.742832 -153.375868) (xy 186.743318 -153.348617)
			(xy 186.751074 -153.294669) (xy 186.766429 -153.242374) (xy 186.789071 -153.192797) (xy 186.818537 -153.146947)
			(xy 186.854228 -153.105756) (xy 186.895419 -153.070065) (xy 186.941269 -153.040599) (xy 186.990846 -153.017957)
			(xy 187.043141 -153.002602) (xy 187.097089 -152.994846) (xy 187.151591 -152.994846) (xy 187.205539 -153.002602)
			(xy 187.257834 -153.017957) (xy 187.307411 -153.040599) (xy 187.353261 -153.070065) (xy 187.394452 -153.105756)
			(xy 187.430143 -153.146947) (xy 187.459609 -153.192797) (xy 187.482251 -153.242374) (xy 187.497606 -153.294669)
			(xy 187.505362 -153.348617) (xy 187.505848 -153.375868) (xy 187.505848 -153.774902) (xy 188.445657 -153.774902)
			(xy 188.44965 -153.565161) (xy 188.461626 -153.355724) (xy 188.481567 -153.146895) (xy 188.509444 -152.938976)
			(xy 188.545216 -152.732269) (xy 188.588831 -152.527074) (xy 188.640227 -152.323689) (xy 188.699329 -152.122407)
			(xy 188.766051 -151.923521) (xy 188.840296 -151.72732) (xy 188.921956 -151.534088) (xy 189.010914 -151.344104)
			(xy 189.107041 -151.157645) (xy 189.210196 -150.974981) (xy 189.320231 -150.796376) (xy 189.436985 -150.62209)
			(xy 189.56029 -150.452375) (xy 189.689967 -150.287477) (xy 189.825828 -150.127636) (xy 189.967675 -149.973083)
			(xy 190.115304 -149.824043) (xy 190.268499 -149.68073) (xy 190.42704 -149.543354) (xy 190.590695 -149.412113)
			(xy 190.759229 -149.287198) (xy 190.932395 -149.16879) (xy 191.109945 -149.05706) (xy 191.291619 -148.95217)
			(xy 191.477154 -148.854273) (xy 191.666282 -148.763511) (xy 191.858729 -148.680014) (xy 192.054214 -148.603904)
			(xy 192.252456 -148.535292) (xy 192.453166 -148.474277) (xy 192.656053 -148.420948) (xy 192.860823 -148.375381)
			(xy 193.06718 -148.337642) (xy 193.274824 -148.307788) (xy 193.483454 -148.28586) (xy 193.692767 -148.271891)
			(xy 193.902461 -148.2659) (xy 194.11223 -148.267897) (xy 194.321772 -148.277879) (xy 194.530782 -148.295831)
			(xy 194.738956 -148.321727) (xy 194.945994 -148.355529) (xy 195.151595 -148.397189) (xy 195.355461 -148.446647)
			(xy 195.557296 -148.50383) (xy 195.756808 -148.568655) (xy 195.953707 -148.641029) (xy 196.147708 -148.720846)
			(xy 196.33853 -148.807992) (xy 196.525896 -148.902339) (xy 196.709534 -149.00375) (xy 196.889178 -149.11208)
			(xy 197.064568 -149.22717) (xy 197.235449 -149.348854) (xy 197.401573 -149.476955) (xy 197.5627 -149.611288)
			(xy 197.718597 -149.751657) (xy 197.869036 -149.89786) (xy 198.0138 -150.049684) (xy 198.152679 -150.20691)
			(xy 198.285472 -150.369309) (xy 198.411986 -150.536645) (xy 198.532038 -150.708677) (xy 198.645453 -150.885154)
			(xy 198.752067 -151.065822) (xy 198.851726 -151.250417) (xy 198.944285 -151.438672) (xy 199.02961 -151.630315)
			(xy 199.107577 -151.825067) (xy 199.178073 -152.022647) (xy 199.240996 -152.222766) (xy 199.296255 -152.425137)
			(xy 199.343769 -152.629464) (xy 199.38347 -152.835452) (xy 199.4153 -153.042803) (xy 199.439213 -153.251214)
			(xy 199.455174 -153.460385) (xy 199.463161 -153.670012) (xy 199.463618 -153.766012) (xy 272.385799 -153.766012)
			(xy 272.389792 -153.556271) (xy 272.401768 -153.346834) (xy 272.421709 -153.138005) (xy 272.449586 -152.930086)
			(xy 272.485358 -152.723379) (xy 272.528973 -152.518184) (xy 272.580369 -152.314799) (xy 272.639471 -152.113517)
			(xy 272.706193 -151.914631) (xy 272.780438 -151.71843) (xy 272.862098 -151.525198) (xy 272.951056 -151.335214)
			(xy 273.047183 -151.148755) (xy 273.150338 -150.966091) (xy 273.260373 -150.787486) (xy 273.377127 -150.6132)
			(xy 273.500432 -150.443485) (xy 273.630109 -150.278587) (xy 273.76597 -150.118746) (xy 273.907817 -149.964193)
			(xy 274.055446 -149.815153) (xy 274.208641 -149.67184) (xy 274.367182 -149.534464) (xy 274.530837 -149.403223)
			(xy 274.699371 -149.278308) (xy 274.872537 -149.1599) (xy 275.050087 -149.04817) (xy 275.231761 -148.94328)
			(xy 275.417296 -148.845383) (xy 275.606424 -148.754621) (xy 275.798871 -148.671124) (xy 275.994356 -148.595014)
			(xy 276.192598 -148.526402) (xy 276.393308 -148.465387) (xy 276.596195 -148.412058) (xy 276.800965 -148.366491)
			(xy 277.007322 -148.328752) (xy 277.214966 -148.298898) (xy 277.423596 -148.27697) (xy 277.632909 -148.263001)
			(xy 277.842603 -148.25701) (xy 278.052372 -148.259007) (xy 278.261914 -148.268989) (xy 278.470924 -148.286941)
			(xy 278.679098 -148.312837) (xy 278.886136 -148.346639) (xy 279.091737 -148.388299) (xy 279.295603 -148.437757)
			(xy 279.497438 -148.49494) (xy 279.69695 -148.559765) (xy 279.893849 -148.632139) (xy 280.08785 -148.711956)
			(xy 280.278672 -148.799102) (xy 280.466038 -148.893449) (xy 280.649676 -148.99486) (xy 280.82932 -149.10319)
			(xy 281.00471 -149.21828) (xy 281.175591 -149.339964) (xy 281.341715 -149.468065) (xy 281.502842 -149.602398)
			(xy 281.658739 -149.742767) (xy 281.809178 -149.88897) (xy 281.953942 -150.040794) (xy 282.092821 -150.19802)
			(xy 282.225614 -150.360419) (xy 282.352128 -150.527755) (xy 282.47218 -150.699787) (xy 282.585595 -150.876264)
			(xy 282.692209 -151.056932) (xy 282.791868 -151.241527) (xy 282.884427 -151.429782) (xy 282.969752 -151.621425)
			(xy 283.047719 -151.816177) (xy 283.118215 -152.013757) (xy 283.181138 -152.213876) (xy 283.236397 -152.416247)
			(xy 283.283911 -152.620574) (xy 283.323612 -152.826562) (xy 283.355442 -153.033913) (xy 283.379355 -153.242324)
			(xy 283.395316 -153.451495) (xy 283.403303 -153.661122) (xy 283.403802 -153.766012) (xy 283.403303 -153.870902)
			(xy 283.395316 -154.080529) (xy 283.379355 -154.2897) (xy 283.355442 -154.498111) (xy 283.323612 -154.705462)
			(xy 283.283911 -154.91145) (xy 283.236397 -155.115777) (xy 283.181138 -155.318148) (xy 283.118215 -155.518267)
			(xy 283.047719 -155.715847) (xy 282.969752 -155.910599) (xy 282.884427 -156.102242) (xy 282.791868 -156.290497)
			(xy 282.692209 -156.475092) (xy 282.585595 -156.65576) (xy 282.47218 -156.832237) (xy 282.352128 -157.004269)
			(xy 282.225614 -157.171605) (xy 282.092821 -157.334004) (xy 281.953942 -157.49123) (xy 281.809178 -157.643054)
			(xy 281.658739 -157.789257) (xy 281.502842 -157.929626) (xy 281.341715 -158.063959) (xy 281.175591 -158.19206)
			(xy 281.00471 -158.313744) (xy 280.82932 -158.428834) (xy 280.649676 -158.537164) (xy 280.466038 -158.638575)
			(xy 280.278672 -158.732922) (xy 280.08785 -158.820068) (xy 279.893849 -158.899885) (xy 279.69695 -158.972259)
			(xy 279.497438 -159.037084) (xy 279.295603 -159.094267) (xy 279.091737 -159.143725) (xy 278.886136 -159.185385)
			(xy 278.679098 -159.219187) (xy 278.470924 -159.245083) (xy 278.261914 -159.263035) (xy 278.052372 -159.273017)
			(xy 277.842603 -159.275014) (xy 277.632909 -159.269023) (xy 277.423596 -159.255054) (xy 277.214966 -159.233126)
			(xy 277.007322 -159.203272) (xy 276.800965 -159.165533) (xy 276.596195 -159.119966) (xy 276.393308 -159.066637)
			(xy 276.192598 -159.005622) (xy 275.994356 -158.93701) (xy 275.798871 -158.8609) (xy 275.606424 -158.777403)
			(xy 275.417296 -158.686641) (xy 275.231761 -158.588744) (xy 275.050087 -158.483854) (xy 274.872537 -158.372124)
			(xy 274.699371 -158.253716) (xy 274.530837 -158.128801) (xy 274.367182 -157.99756) (xy 274.208641 -157.860184)
			(xy 274.055446 -157.716871) (xy 273.907817 -157.567831) (xy 273.76597 -157.413278) (xy 273.630109 -157.253437)
			(xy 273.500432 -157.088539) (xy 273.377127 -156.918824) (xy 273.260373 -156.744538) (xy 273.150338 -156.565933)
			(xy 273.047183 -156.383269) (xy 272.951056 -156.19681) (xy 272.862098 -156.006826) (xy 272.780438 -155.813594)
			(xy 272.706193 -155.617393) (xy 272.639471 -155.418507) (xy 272.580369 -155.217225) (xy 272.528973 -155.01384)
			(xy 272.485358 -154.808645) (xy 272.449586 -154.601938) (xy 272.421709 -154.394019) (xy 272.401768 -154.18519)
			(xy 272.389792 -153.975753) (xy 272.385799 -153.766012) (xy 199.463618 -153.766012) (xy 199.46366 -153.774902)
			(xy 199.463161 -153.879792) (xy 199.455174 -154.089419) (xy 199.439213 -154.29859) (xy 199.4153 -154.507001)
			(xy 199.38347 -154.714352) (xy 199.343769 -154.92034) (xy 199.296255 -155.124667) (xy 199.240996 -155.327038)
			(xy 199.178073 -155.527157) (xy 199.107577 -155.724737) (xy 199.02961 -155.919489) (xy 198.944285 -156.111132)
			(xy 198.851726 -156.299387) (xy 198.752067 -156.483982) (xy 198.645453 -156.66465) (xy 198.532038 -156.841127)
			(xy 198.411986 -157.013159) (xy 198.285472 -157.180495) (xy 198.152679 -157.342894) (xy 198.0138 -157.50012)
			(xy 197.869036 -157.651944) (xy 197.718597 -157.798147) (xy 197.5627 -157.938516) (xy 197.401573 -158.072849)
			(xy 197.235449 -158.20095) (xy 197.064568 -158.322634) (xy 196.889178 -158.437724) (xy 196.709534 -158.546054)
			(xy 196.525896 -158.647465) (xy 196.33853 -158.741812) (xy 196.147708 -158.828958) (xy 195.953707 -158.908775)
			(xy 195.756808 -158.981149) (xy 195.557296 -159.045974) (xy 195.355461 -159.103157) (xy 195.151595 -159.152615)
			(xy 194.945994 -159.194275) (xy 194.738956 -159.228077) (xy 194.530782 -159.253973) (xy 194.321772 -159.271925)
			(xy 194.11223 -159.281907) (xy 193.902461 -159.283904) (xy 193.692767 -159.277913) (xy 193.483454 -159.263944)
			(xy 193.274824 -159.242016) (xy 193.06718 -159.212162) (xy 192.860823 -159.174423) (xy 192.656053 -159.128856)
			(xy 192.453166 -159.075527) (xy 192.252456 -159.014512) (xy 192.054214 -158.9459) (xy 191.858729 -158.86979)
			(xy 191.666282 -158.786293) (xy 191.477154 -158.695531) (xy 191.291619 -158.597634) (xy 191.109945 -158.492744)
			(xy 190.932395 -158.381014) (xy 190.759229 -158.262606) (xy 190.590695 -158.137691) (xy 190.42704 -158.00645)
			(xy 190.268499 -157.869074) (xy 190.115304 -157.725761) (xy 189.967675 -157.576721) (xy 189.825828 -157.422168)
			(xy 189.689967 -157.262327) (xy 189.56029 -157.097429) (xy 189.436985 -156.927714) (xy 189.320231 -156.753428)
			(xy 189.210196 -156.574823) (xy 189.107041 -156.392159) (xy 189.010914 -156.2057) (xy 188.921956 -156.015716)
			(xy 188.840296 -155.822484) (xy 188.766051 -155.626283) (xy 188.699329 -155.427397) (xy 188.640227 -155.226115)
			(xy 188.588831 -155.02273) (xy 188.545216 -154.817535) (xy 188.509444 -154.610828) (xy 188.481567 -154.402909)
			(xy 188.461626 -154.19408) (xy 188.44965 -153.984643) (xy 188.445657 -153.774902) (xy 187.505848 -153.774902)
			(xy 187.505848 -154.239468) (xy 187.505362 -154.266719) (xy 187.497606 -154.320667) (xy 187.482251 -154.372962)
			(xy 187.459609 -154.422539) (xy 187.430143 -154.468389) (xy 187.394452 -154.50958) (xy 187.353261 -154.545271)
			(xy 187.307411 -154.574737) (xy 187.257834 -154.597379) (xy 187.205539 -154.612734) (xy 187.151591 -154.62049)
			(xy 187.097089 -154.62049) (xy 187.043141 -154.612734) (xy 186.990846 -154.597379) (xy 186.941269 -154.574737)
			(xy 186.895419 -154.545271) (xy 186.854228 -154.50958) (xy 186.818537 -154.468389) (xy 186.789071 -154.422539)
			(xy 186.766429 -154.372962) (xy 186.751074 -154.320667) (xy 186.743318 -154.266719) (xy 186.742832 -154.239468)
			(xy 114.247676 -154.239468) (xy 120.508268 -160.50006) (xy 162.628078 -160.50006) (xy 162.632092 -160.294376)
			(xy 162.644128 -160.089006) (xy 162.664167 -159.884262) (xy 162.69218 -159.680455) (xy 162.728123 -159.477896)
			(xy 162.771942 -159.276894) (xy 162.823569 -159.077755) (xy 162.882927 -158.880782) (xy 162.949925 -158.686274)
			(xy 163.024461 -158.494529) (xy 163.106421 -158.305838) (xy 163.195681 -158.120488) (xy 163.292104 -157.938762)
			(xy 163.395545 -157.760936) (xy 163.505844 -157.587282) (xy 163.622835 -157.418063) (xy 163.746339 -157.253537)
			(xy 163.876168 -157.093956) (xy 164.012125 -156.939561) (xy 164.154002 -156.790589) (xy 164.301583 -156.647265)
			(xy 164.454644 -156.509809) (xy 164.612951 -156.378429) (xy 164.776264 -156.253326) (xy 164.944333 -156.134689)
			(xy 165.116903 -156.022701) (xy 165.293711 -155.91753) (xy 165.474488 -155.819339) (xy 165.658958 -155.728275)
			(xy 165.84684 -155.644478) (xy 166.03785 -155.568075) (xy 166.231694 -155.499182) (xy 166.428079 -155.437905)
			(xy 166.626705 -155.384337) (xy 166.82727 -155.33856) (xy 167.029468 -155.300642) (xy 167.232992 -155.270643)
			(xy 167.437531 -155.248606) (xy 167.642774 -155.234567) (xy 167.848409 -155.228547) (xy 168.054122 -155.230554)
			(xy 168.2596 -155.240586) (xy 168.46453 -155.258627) (xy 168.6686 -155.28465) (xy 168.8715 -155.318615)
			(xy 169.07292 -155.36047) (xy 169.272553 -155.410152) (xy 169.470096 -155.467586) (xy 169.665248 -155.532683)
			(xy 169.857712 -155.605344) (xy 170.047194 -155.68546) (xy 170.233405 -155.772907) (xy 170.416064 -155.867553)
			(xy 170.59489 -155.969253) (xy 170.769612 -156.077853) (xy 170.939965 -156.193188) (xy 171.105687 -156.315081)
			(xy 171.266528 -156.443347) (xy 171.422241 -156.57779) (xy 171.572591 -156.718207) (xy 171.717348 -156.864383)
			(xy 171.856291 -157.016095) (xy 171.989209 -157.173113) (xy 172.1159 -157.335198) (xy 172.23617 -157.502101)
			(xy 172.349837 -157.673571) (xy 172.456727 -157.849344) (xy 172.556678 -158.029154) (xy 172.649537 -158.212727)
			(xy 172.735164 -158.399783) (xy 172.813426 -158.590038) (xy 172.884207 -158.783201) (xy 172.947397 -158.978979)
			(xy 173.0029 -159.177073) (xy 173.050632 -159.377182) (xy 173.090521 -159.579) (xy 173.122505 -159.782222)
			(xy 173.146535 -159.986536) (xy 173.162576 -160.191632) (xy 173.170602 -160.397199) (xy 173.171104 -160.50006)
			(xy 317.628276 -160.50006) (xy 317.63229 -160.294376) (xy 317.644326 -160.089006) (xy 317.664365 -159.884262)
			(xy 317.692378 -159.680455) (xy 317.728321 -159.477896) (xy 317.77214 -159.276894) (xy 317.823767 -159.077755)
			(xy 317.883125 -158.880782) (xy 317.950123 -158.686274) (xy 318.024659 -158.494529) (xy 318.106619 -158.305838)
			(xy 318.195879 -158.120488) (xy 318.292302 -157.938762) (xy 318.395743 -157.760936) (xy 318.506042 -157.587282)
			(xy 318.623033 -157.418063) (xy 318.746537 -157.253537) (xy 318.876366 -157.093956) (xy 319.012323 -156.939561)
			(xy 319.1542 -156.790589) (xy 319.301781 -156.647265) (xy 319.454842 -156.509809) (xy 319.613149 -156.378429)
			(xy 319.776462 -156.253326) (xy 319.944531 -156.134689) (xy 320.117101 -156.022701) (xy 320.293909 -155.91753)
			(xy 320.474686 -155.819339) (xy 320.659156 -155.728275) (xy 320.847038 -155.644478) (xy 321.038048 -155.568075)
			(xy 321.231892 -155.499182) (xy 321.428277 -155.437905) (xy 321.626903 -155.384337) (xy 321.827468 -155.33856)
			(xy 322.029666 -155.300642) (xy 322.23319 -155.270643) (xy 322.437729 -155.248606) (xy 322.642972 -155.234567)
			(xy 322.848607 -155.228547) (xy 323.05432 -155.230554) (xy 323.259798 -155.240586) (xy 323.464728 -155.258627)
			(xy 323.668798 -155.28465) (xy 323.871698 -155.318615) (xy 324.073118 -155.36047) (xy 324.272751 -155.410152)
			(xy 324.470294 -155.467586) (xy 324.665446 -155.532683) (xy 324.85791 -155.605344) (xy 325.047392 -155.68546)
			(xy 325.233603 -155.772907) (xy 325.416262 -155.867553) (xy 325.595088 -155.969253) (xy 325.76981 -156.077853)
			(xy 325.940163 -156.193188) (xy 326.105885 -156.315081) (xy 326.266726 -156.443347) (xy 326.422439 -156.57779)
			(xy 326.572789 -156.718207) (xy 326.717546 -156.864383) (xy 326.856489 -157.016095) (xy 326.989407 -157.173113)
			(xy 327.116098 -157.335198) (xy 327.236368 -157.502101) (xy 327.350035 -157.673571) (xy 327.456925 -157.849344)
			(xy 327.556876 -158.029154) (xy 327.649735 -158.212727) (xy 327.735362 -158.399783) (xy 327.813624 -158.590038)
			(xy 327.884405 -158.783201) (xy 327.947595 -158.978979) (xy 328.003098 -159.177073) (xy 328.05083 -159.377182)
			(xy 328.090719 -159.579) (xy 328.122703 -159.782222) (xy 328.146733 -159.986536) (xy 328.162774 -160.191632)
			(xy 328.1708 -160.397199) (xy 328.171302 -160.50006) (xy 328.1708 -160.602921) (xy 328.162774 -160.808488)
			(xy 328.146733 -161.013584) (xy 328.122703 -161.217898) (xy 328.090719 -161.42112) (xy 328.05083 -161.622938)
			(xy 328.003098 -161.823047) (xy 327.947595 -162.021141) (xy 327.884405 -162.216919) (xy 327.813624 -162.410082)
			(xy 327.735362 -162.600337) (xy 327.649735 -162.787393) (xy 327.556876 -162.970966) (xy 327.456925 -163.150776)
			(xy 327.350035 -163.326549) (xy 327.236368 -163.498019) (xy 327.116098 -163.664922) (xy 326.989407 -163.827007)
			(xy 326.856489 -163.984025) (xy 326.717546 -164.135737) (xy 326.572789 -164.281913) (xy 326.422439 -164.42233)
			(xy 326.266726 -164.556773) (xy 326.105885 -164.685039) (xy 325.940163 -164.806932) (xy 325.76981 -164.922267)
			(xy 325.595088 -165.030867) (xy 325.416262 -165.132567) (xy 325.233603 -165.227213) (xy 325.047392 -165.31466)
			(xy 324.85791 -165.394776) (xy 324.665446 -165.467437) (xy 324.470294 -165.532534) (xy 324.272751 -165.589968)
			(xy 324.073118 -165.63965) (xy 323.871698 -165.681505) (xy 323.668798 -165.71547) (xy 323.464728 -165.741493)
			(xy 323.259798 -165.759534) (xy 323.05432 -165.769566) (xy 322.848607 -165.771573) (xy 322.642972 -165.765553)
			(xy 322.437729 -165.751514) (xy 322.23319 -165.729477) (xy 322.029666 -165.699478) (xy 321.827468 -165.66156)
			(xy 321.626903 -165.615783) (xy 321.428277 -165.562215) (xy 321.231892 -165.500938) (xy 321.038048 -165.432045)
			(xy 320.847038 -165.355642) (xy 320.659156 -165.271845) (xy 320.474686 -165.180781) (xy 320.293909 -165.08259)
			(xy 320.117101 -164.977419) (xy 319.944531 -164.865431) (xy 319.776462 -164.746794) (xy 319.613149 -164.621691)
			(xy 319.454842 -164.490311) (xy 319.301781 -164.352855) (xy 319.1542 -164.209531) (xy 319.012323 -164.060559)
			(xy 318.876366 -163.906164) (xy 318.746537 -163.746583) (xy 318.623033 -163.582057) (xy 318.506042 -163.412838)
			(xy 318.395743 -163.239184) (xy 318.292302 -163.061358) (xy 318.195879 -162.879632) (xy 318.106619 -162.694282)
			(xy 318.024659 -162.505591) (xy 317.950123 -162.313846) (xy 317.883125 -162.119338) (xy 317.823767 -161.922365)
			(xy 317.77214 -161.723226) (xy 317.728321 -161.522224) (xy 317.692378 -161.319665) (xy 317.664365 -161.115858)
			(xy 317.644326 -160.911114) (xy 317.63229 -160.705744) (xy 317.628276 -160.50006) (xy 173.171104 -160.50006)
			(xy 173.170602 -160.602921) (xy 173.162576 -160.808488) (xy 173.146535 -161.013584) (xy 173.122505 -161.217898)
			(xy 173.090521 -161.42112) (xy 173.058239 -161.58445) (xy 296.753286 -161.58445) (xy 296.753286 -161.52995)
			(xy 296.761042 -161.476005) (xy 296.776395 -161.423713) (xy 296.799035 -161.374138) (xy 296.828498 -161.32829)
			(xy 296.864187 -161.287101) (xy 296.905374 -161.25141) (xy 296.951221 -161.221944) (xy 297.000795 -161.199302)
			(xy 297.053086 -161.183946) (xy 297.10703 -161.176187) (xy 297.13428 -161.1757) (xy 297.99788 -161.1757)
			(xy 298.025134 -161.176146) (xy 298.079089 -161.183901) (xy 298.13139 -161.199255) (xy 298.180974 -161.221897)
			(xy 298.22683 -161.251365) (xy 298.268026 -161.28706) (xy 298.303723 -161.328254) (xy 298.333193 -161.374109)
			(xy 298.355838 -161.423691) (xy 298.371195 -161.475992) (xy 298.378953 -161.529946) (xy 298.378953 -161.584454)
			(xy 298.371195 -161.638408) (xy 298.355838 -161.690709) (xy 298.333193 -161.740291) (xy 298.303723 -161.786146)
			(xy 298.268026 -161.82734) (xy 298.22683 -161.863035) (xy 298.180974 -161.892503) (xy 298.13139 -161.915145)
			(xy 298.079089 -161.930499) (xy 298.025134 -161.938254) (xy 297.99788 -161.938716) (xy 297.13428 -161.938716)
			(xy 297.10703 -161.938213) (xy 297.053086 -161.930454) (xy 297.000795 -161.915098) (xy 296.951221 -161.892456)
			(xy 296.905374 -161.86299) (xy 296.864187 -161.827299) (xy 296.828498 -161.78611) (xy 296.799035 -161.740262)
			(xy 296.776395 -161.690687) (xy 296.761042 -161.638395) (xy 296.753286 -161.58445) (xy 173.058239 -161.58445)
			(xy 173.050632 -161.622938) (xy 173.0029 -161.823047) (xy 172.947397 -162.021141) (xy 172.91289 -162.128053)
			(xy 292.574946 -162.128053) (xy 292.574946 -162.073547) (xy 292.582702 -162.019597) (xy 292.598058 -161.967299)
			(xy 292.620699 -161.917719) (xy 292.650166 -161.871866) (xy 292.685859 -161.830673) (xy 292.72705 -161.794978)
			(xy 292.772902 -161.765509) (xy 292.822481 -161.742865) (xy 292.874777 -161.727507) (xy 292.928727 -161.719747)
			(xy 292.95598 -161.71926) (xy 293.81958 -161.71926) (xy 293.846832 -161.719786) (xy 293.90078 -161.72754)
			(xy 293.953076 -161.742893) (xy 294.002654 -161.765532) (xy 294.048506 -161.794997) (xy 294.089698 -161.830688)
			(xy 294.125391 -161.871878) (xy 294.154858 -161.917728) (xy 294.1775 -161.967305) (xy 294.192856 -162.0196)
			(xy 294.200613 -162.073549) (xy 294.200613 -162.128051) (xy 294.192856 -162.182) (xy 294.1775 -162.234295)
			(xy 294.154858 -162.283872) (xy 294.125391 -162.329722) (xy 294.089698 -162.370912) (xy 294.048506 -162.406603)
			(xy 294.002654 -162.436068) (xy 293.953076 -162.458707) (xy 293.90078 -162.47406) (xy 293.846832 -162.481814)
			(xy 293.81958 -162.482276) (xy 292.95598 -162.482276) (xy 292.928727 -162.481853) (xy 292.874777 -162.474093)
			(xy 292.822481 -162.458735) (xy 292.772902 -162.436091) (xy 292.72705 -162.406622) (xy 292.685859 -162.370927)
			(xy 292.650166 -162.329734) (xy 292.620699 -162.283881) (xy 292.598058 -162.234301) (xy 292.582702 -162.182003)
			(xy 292.574946 -162.128053) (xy 172.91289 -162.128053) (xy 172.884207 -162.216919) (xy 172.813426 -162.410082)
			(xy 172.735164 -162.600337) (xy 172.649537 -162.787393) (xy 172.556678 -162.970966) (xy 172.471805 -163.123651)
			(xy 294.731403 -163.123651) (xy 294.731403 -163.069149) (xy 294.73916 -163.015201) (xy 294.754516 -162.962907)
			(xy 294.777159 -162.91333) (xy 294.806627 -162.867481) (xy 294.842321 -162.826292) (xy 294.883513 -162.790603)
			(xy 294.929365 -162.76114) (xy 294.978944 -162.738502) (xy 295.03124 -162.723152) (xy 295.085189 -162.7154)
			(xy 295.11244 -162.71494) (xy 295.97604 -162.71494) (xy 296.003293 -162.715333) (xy 296.057243 -162.723095)
			(xy 296.10954 -162.738455) (xy 296.159118 -162.761102) (xy 296.204969 -162.790573) (xy 296.24616 -162.826269)
			(xy 296.281851 -162.867463) (xy 296.311318 -162.913317) (xy 296.333959 -162.962898) (xy 296.349314 -163.015196)
			(xy 296.35707 -163.069147) (xy 296.35707 -163.110951) (xy 300.192403 -163.110951) (xy 300.192403 -163.056449)
			(xy 300.20016 -163.002501) (xy 300.215516 -162.950207) (xy 300.238159 -162.90063) (xy 300.267627 -162.854781)
			(xy 300.303321 -162.813592) (xy 300.344513 -162.777903) (xy 300.390365 -162.74844) (xy 300.439944 -162.725802)
			(xy 300.49224 -162.710452) (xy 300.546189 -162.7027) (xy 300.57344 -162.70224) (xy 301.43704 -162.70224)
			(xy 301.464293 -162.702633) (xy 301.518243 -162.710395) (xy 301.57054 -162.725755) (xy 301.620118 -162.748402)
			(xy 301.665969 -162.777873) (xy 301.70716 -162.813569) (xy 301.742851 -162.854763) (xy 301.772318 -162.900617)
			(xy 301.794959 -162.950198) (xy 301.810314 -163.002496) (xy 301.81807 -163.056447) (xy 301.81807 -163.110953)
			(xy 301.810314 -163.164904) (xy 301.794959 -163.217202) (xy 301.772318 -163.266783) (xy 301.742851 -163.312637)
			(xy 301.70716 -163.353831) (xy 301.665969 -163.389527) (xy 301.620118 -163.418998) (xy 301.57054 -163.441645)
			(xy 301.518243 -163.457005) (xy 301.464293 -163.464767) (xy 301.43704 -163.465256) (xy 300.57344 -163.465256)
			(xy 300.546189 -163.4647) (xy 300.49224 -163.456948) (xy 300.439944 -163.441598) (xy 300.390365 -163.41896)
			(xy 300.344513 -163.389497) (xy 300.303321 -163.353808) (xy 300.267627 -163.312619) (xy 300.238159 -163.26677)
			(xy 300.215516 -163.217193) (xy 300.20016 -163.164899) (xy 300.192403 -163.110951) (xy 296.35707 -163.110951)
			(xy 296.35707 -163.123653) (xy 296.349314 -163.177604) (xy 296.333959 -163.229902) (xy 296.311318 -163.279483)
			(xy 296.281851 -163.325337) (xy 296.24616 -163.366531) (xy 296.204969 -163.402227) (xy 296.159118 -163.431698)
			(xy 296.10954 -163.454345) (xy 296.057243 -163.469705) (xy 296.003293 -163.477467) (xy 295.97604 -163.477956)
			(xy 295.11244 -163.477956) (xy 295.085189 -163.4774) (xy 295.03124 -163.469648) (xy 294.978944 -163.454298)
			(xy 294.929365 -163.43166) (xy 294.883513 -163.402197) (xy 294.842321 -163.366508) (xy 294.806627 -163.325319)
			(xy 294.777159 -163.27947) (xy 294.754516 -163.229893) (xy 294.73916 -163.177599) (xy 294.731403 -163.123651)
			(xy 172.471805 -163.123651) (xy 172.456727 -163.150776) (xy 172.349837 -163.326549) (xy 172.23617 -163.498019)
			(xy 172.1159 -163.664922) (xy 171.989209 -163.827007) (xy 171.856291 -163.984025) (xy 171.717348 -164.135737)
			(xy 171.572591 -164.281913) (xy 171.422241 -164.42233) (xy 171.266528 -164.556773) (xy 171.105687 -164.685039)
			(xy 170.939965 -164.806932) (xy 170.769612 -164.922267) (xy 170.59489 -165.030867) (xy 170.416064 -165.132567)
			(xy 170.233405 -165.227213) (xy 170.047194 -165.31466) (xy 169.857712 -165.394776) (xy 169.665248 -165.467437)
			(xy 169.470096 -165.532534) (xy 169.272553 -165.589968) (xy 169.07292 -165.63965) (xy 168.8715 -165.681505)
			(xy 168.6686 -165.71547) (xy 168.46453 -165.741493) (xy 168.2596 -165.759534) (xy 168.054122 -165.769566)
			(xy 167.848409 -165.771573) (xy 167.642774 -165.765553) (xy 167.437531 -165.751514) (xy 167.232992 -165.729477)
			(xy 167.029468 -165.699478) (xy 166.82727 -165.66156) (xy 166.626705 -165.615783) (xy 166.428079 -165.562215)
			(xy 166.231694 -165.500938) (xy 166.03785 -165.432045) (xy 165.84684 -165.355642) (xy 165.658958 -165.271845)
			(xy 165.474488 -165.180781) (xy 165.293711 -165.08259) (xy 165.116903 -164.977419) (xy 164.944333 -164.865431)
			(xy 164.776264 -164.746794) (xy 164.612951 -164.621691) (xy 164.454644 -164.490311) (xy 164.301583 -164.352855)
			(xy 164.154002 -164.209531) (xy 164.012125 -164.060559) (xy 163.876168 -163.906164) (xy 163.746339 -163.746583)
			(xy 163.622835 -163.582057) (xy 163.505844 -163.412838) (xy 163.395545 -163.239184) (xy 163.292104 -163.061358)
			(xy 163.195681 -162.879632) (xy 163.106421 -162.694282) (xy 163.024461 -162.505591) (xy 162.949925 -162.313846)
			(xy 162.882927 -162.119338) (xy 162.823569 -161.922365) (xy 162.771942 -161.723226) (xy 162.728123 -161.522224)
			(xy 162.69218 -161.319665) (xy 162.664167 -161.115858) (xy 162.644128 -160.911114) (xy 162.632092 -160.705744)
			(xy 162.628078 -160.50006) (xy 120.508268 -160.50006) (xy 152.701498 -192.69329) (xy 169.92981 -192.69329)
			(xy 169.951923 -192.680751) (xy 169.998764 -192.660999) (xy 170.04781 -192.647631) (xy 170.098195 -192.640881)
			(xy 170.123612 -192.640458) (xy 170.149032 -192.640864) (xy 170.199423 -192.64759) (xy 170.248472 -192.66096)
			(xy 170.295306 -192.680738) (xy 170.317414 -192.69329) (xy 193.326512 -192.69329) (xy 193.336672 -192.655952)
			(xy 193.344464 -192.629432) (xy 193.366639 -192.578803) (xy 193.395885 -192.531901) (xy 193.43159 -192.489708)
			(xy 193.473007 -192.453107) (xy 193.519271 -192.422863) (xy 193.569414 -192.399608) (xy 193.622387 -192.38383)
			(xy 193.677082 -192.375857) (xy 193.732354 -192.375857) (xy 193.787049 -192.38383) (xy 193.840022 -192.399608)
			(xy 193.890165 -192.422863) (xy 193.936429 -192.453107) (xy 193.977846 -192.489708) (xy 194.013551 -192.531901)
			(xy 194.042797 -192.578803) (xy 194.064972 -192.629432) (xy 194.072764 -192.655952) (xy 194.082924 -192.69329)
			(xy 212.28558 -192.69329) (xy 212.297772 -192.659762) (xy 212.307453 -192.634488) (xy 212.333387 -192.586988)
			(xy 212.366257 -192.543996) (xy 212.405296 -192.506515) (xy 212.449591 -192.475423) (xy 212.498108 -192.451444)
			(xy 212.549712 -192.435141) (xy 212.603199 -192.426892) (xy 212.657317 -192.426892) (xy 212.710804 -192.435141)
			(xy 212.762408 -192.451444) (xy 212.810925 -192.475423) (xy 212.845933 -192.499996) (xy 231.378004 -192.499996)
			(xy 231.382018 -192.294312) (xy 231.394054 -192.088942) (xy 231.414093 -191.884198) (xy 231.442106 -191.680391)
			(xy 231.478049 -191.477832) (xy 231.521868 -191.27683) (xy 231.573495 -191.077691) (xy 231.632853 -190.880718)
			(xy 231.699851 -190.68621) (xy 231.774387 -190.494465) (xy 231.856347 -190.305774) (xy 231.945607 -190.120424)
			(xy 232.04203 -189.938698) (xy 232.145471 -189.760872) (xy 232.25577 -189.587218) (xy 232.372761 -189.417999)
			(xy 232.496265 -189.253473) (xy 232.626094 -189.093892) (xy 232.762051 -188.939497) (xy 232.903928 -188.790525)
			(xy 233.051509 -188.647201) (xy 233.20457 -188.509745) (xy 233.362877 -188.378365) (xy 233.52619 -188.253262)
			(xy 233.694259 -188.134625) (xy 233.866829 -188.022637) (xy 234.043637 -187.917466) (xy 234.224414 -187.819275)
			(xy 234.408884 -187.728211) (xy 234.596766 -187.644414) (xy 234.787776 -187.568011) (xy 234.98162 -187.499118)
			(xy 235.178005 -187.437841) (xy 235.376631 -187.384273) (xy 235.577196 -187.338496) (xy 235.779394 -187.300578)
			(xy 235.982918 -187.270579) (xy 236.187457 -187.248542) (xy 236.3927 -187.234503) (xy 236.598335 -187.228483)
			(xy 236.804048 -187.23049) (xy 237.009526 -187.240522) (xy 237.214456 -187.258563) (xy 237.418526 -187.284586)
			(xy 237.621426 -187.318551) (xy 237.822846 -187.360406) (xy 238.022479 -187.410088) (xy 238.220022 -187.467522)
			(xy 238.415174 -187.532619) (xy 238.607638 -187.60528) (xy 238.79712 -187.685396) (xy 238.983331 -187.772843)
			(xy 239.16599 -187.867489) (xy 239.344816 -187.969189) (xy 239.519538 -188.077789) (xy 239.689891 -188.193124)
			(xy 239.855613 -188.315017) (xy 240.016454 -188.443283) (xy 240.172167 -188.577726) (xy 240.322517 -188.718143)
			(xy 240.467274 -188.864319) (xy 240.606217 -189.016031) (xy 240.739135 -189.173049) (xy 240.865826 -189.335134)
			(xy 240.986096 -189.502037) (xy 241.099763 -189.673507) (xy 241.206653 -189.84928) (xy 241.306604 -190.02909)
			(xy 241.399463 -190.212663) (xy 241.48509 -190.399719) (xy 241.563352 -190.589974) (xy 241.634133 -190.783137)
			(xy 241.697323 -190.978915) (xy 241.752826 -191.177009) (xy 241.800558 -191.377118) (xy 241.840447 -191.578936)
			(xy 241.872431 -191.782158) (xy 241.896461 -191.986472) (xy 241.912502 -192.191568) (xy 241.920528 -192.397135)
			(xy 241.92103 -192.499996) (xy 241.920528 -192.602857) (xy 241.912502 -192.808424) (xy 241.896461 -193.01352)
			(xy 241.872431 -193.217834) (xy 241.840447 -193.421056) (xy 241.800558 -193.622874) (xy 241.752826 -193.822983)
			(xy 241.697323 -194.021077) (xy 241.634133 -194.216855) (xy 241.563352 -194.410018) (xy 241.48509 -194.600273)
			(xy 241.399463 -194.787329) (xy 241.306604 -194.970902) (xy 241.206653 -195.150712) (xy 241.099763 -195.326485)
			(xy 240.986096 -195.497955) (xy 240.865826 -195.664858) (xy 240.739135 -195.826943) (xy 240.606217 -195.983961)
			(xy 240.467274 -196.135673) (xy 240.322517 -196.281849) (xy 240.172167 -196.422266) (xy 240.016454 -196.556709)
			(xy 239.855613 -196.684975) (xy 239.689891 -196.806868) (xy 239.519538 -196.922203) (xy 239.344816 -197.030803)
			(xy 239.16599 -197.132503) (xy 238.983331 -197.227149) (xy 238.79712 -197.314596) (xy 238.607638 -197.394712)
			(xy 238.415174 -197.467373) (xy 238.220022 -197.53247) (xy 238.022479 -197.589904) (xy 237.822846 -197.639586)
			(xy 237.621426 -197.681441) (xy 237.418526 -197.715406) (xy 237.214456 -197.741429) (xy 237.009526 -197.75947)
			(xy 236.804048 -197.769502) (xy 236.598335 -197.771509) (xy 236.3927 -197.765489) (xy 236.187457 -197.75145)
			(xy 235.982918 -197.729413) (xy 235.779394 -197.699414) (xy 235.577196 -197.661496) (xy 235.376631 -197.615719)
			(xy 235.178005 -197.562151) (xy 234.98162 -197.500874) (xy 234.787776 -197.431981) (xy 234.596766 -197.355578)
			(xy 234.408884 -197.271781) (xy 234.224414 -197.180717) (xy 234.043637 -197.082526) (xy 233.866829 -196.977355)
			(xy 233.694259 -196.865367) (xy 233.52619 -196.74673) (xy 233.362877 -196.621627) (xy 233.20457 -196.490247)
			(xy 233.051509 -196.352791) (xy 232.903928 -196.209467) (xy 232.762051 -196.060495) (xy 232.626094 -195.9061)
			(xy 232.496265 -195.746519) (xy 232.372761 -195.581993) (xy 232.25577 -195.412774) (xy 232.145471 -195.23912)
			(xy 232.04203 -195.061294) (xy 231.945607 -194.879568) (xy 231.856347 -194.694218) (xy 231.774387 -194.505527)
			(xy 231.699851 -194.313782) (xy 231.632853 -194.119274) (xy 231.573495 -193.922301) (xy 231.521868 -193.723162)
			(xy 231.478049 -193.52216) (xy 231.442106 -193.319601) (xy 231.414093 -193.115794) (xy 231.394054 -192.91105)
			(xy 231.382018 -192.70568) (xy 231.378004 -192.499996) (xy 212.845933 -192.499996) (xy 212.85522 -192.506515)
			(xy 212.894259 -192.543996) (xy 212.927129 -192.586988) (xy 212.953063 -192.634488) (xy 212.962744 -192.659762)
			(xy 212.974936 -192.69329) (xy 216.315798 -192.69329) (xy 216.340761 -192.693821) (xy 216.389727 -192.70356)
			(xy 216.435845 -192.722681) (xy 216.477337 -192.750448) (xy 216.495376 -192.767712) (xy 216.878408 -193.150744)
			(xy 216.902041 -193.135554) (xy 216.952824 -193.111529) (xy 217.006583 -193.09522) (xy 217.062155 -193.086979)
			(xy 217.090244 -193.086482) (xy 217.090498 -193.086482) (xy 217.117749 -193.08698) (xy 217.171696 -193.094736)
			(xy 217.223989 -193.11009) (xy 217.273566 -193.13273) (xy 217.319416 -193.162195) (xy 217.360606 -193.197886)
			(xy 217.396298 -193.239074) (xy 217.425764 -193.284923) (xy 217.448406 -193.334499) (xy 217.463762 -193.386793)
			(xy 217.47152 -193.440739) (xy 217.472006 -193.46799) (xy 217.472006 -193.468244) (xy 217.471473 -193.496331)
			(xy 217.463223 -193.551896) (xy 217.446922 -193.605653) (xy 217.422921 -193.656441) (xy 217.407744 -193.68008)
			(xy 217.973656 -194.245992) (xy 217.990911 -194.264035) (xy 218.01865 -194.305537) (xy 218.037759 -194.351653)
			(xy 218.047504 -194.400611) (xy 218.048078 -194.42557) (xy 218.048078 -247.620536) (xy 228.175312 -247.620536)
			(xy 228.175312 -246.756936) (xy 228.175798 -246.729685) (xy 228.183554 -246.675737) (xy 228.198909 -246.623442)
			(xy 228.221551 -246.573865) (xy 228.251017 -246.528015) (xy 228.286708 -246.486824) (xy 228.327899 -246.451133)
			(xy 228.373749 -246.421667) (xy 228.423326 -246.399025) (xy 228.475621 -246.38367) (xy 228.529569 -246.375914)
			(xy 228.584071 -246.375914) (xy 228.638019 -246.38367) (xy 228.690314 -246.399025) (xy 228.739891 -246.421667)
			(xy 228.785741 -246.451133) (xy 228.826932 -246.486824) (xy 228.862623 -246.528015) (xy 228.892089 -246.573865)
			(xy 228.914731 -246.623442) (xy 228.930086 -246.675737) (xy 228.937842 -246.729685) (xy 228.938328 -246.756936)
			(xy 228.938328 -247.620536) (xy 228.937842 -247.647787) (xy 228.930086 -247.701735) (xy 228.914731 -247.75403)
			(xy 228.892089 -247.803607) (xy 228.862623 -247.849457) (xy 228.826932 -247.890648) (xy 228.785741 -247.926339)
			(xy 228.739891 -247.955805) (xy 228.690314 -247.978447) (xy 228.638019 -247.993802) (xy 228.584071 -248.001558)
			(xy 228.529569 -248.001558) (xy 228.475621 -247.993802) (xy 228.423326 -247.978447) (xy 228.373749 -247.955805)
			(xy 228.327899 -247.926339) (xy 228.286708 -247.890648) (xy 228.251017 -247.849457) (xy 228.221551 -247.803607)
			(xy 228.198909 -247.75403) (xy 228.183554 -247.701735) (xy 228.175798 -247.647787) (xy 228.175312 -247.620536)
			(xy 218.048078 -247.620536) (xy 218.048078 -272.499836) (xy 231.378004 -272.499836) (xy 231.382018 -272.294152)
			(xy 231.394054 -272.088782) (xy 231.414093 -271.884038) (xy 231.442106 -271.680231) (xy 231.478049 -271.477672)
			(xy 231.521868 -271.27667) (xy 231.573495 -271.077531) (xy 231.632853 -270.880558) (xy 231.699851 -270.68605)
			(xy 231.774387 -270.494305) (xy 231.856347 -270.305614) (xy 231.945607 -270.120264) (xy 232.04203 -269.938538)
			(xy 232.145471 -269.760712) (xy 232.25577 -269.587058) (xy 232.372761 -269.417839) (xy 232.496265 -269.253313)
			(xy 232.626094 -269.093732) (xy 232.762051 -268.939337) (xy 232.903928 -268.790365) (xy 233.051509 -268.647041)
			(xy 233.20457 -268.509585) (xy 233.362877 -268.378205) (xy 233.52619 -268.253102) (xy 233.694259 -268.134465)
			(xy 233.866829 -268.022477) (xy 234.043637 -267.917306) (xy 234.224414 -267.819115) (xy 234.408884 -267.728051)
			(xy 234.596766 -267.644254) (xy 234.787776 -267.567851) (xy 234.98162 -267.498958) (xy 235.178005 -267.437681)
			(xy 235.376631 -267.384113) (xy 235.577196 -267.338336) (xy 235.779394 -267.300418) (xy 235.982918 -267.270419)
			(xy 236.187457 -267.248382) (xy 236.3927 -267.234343) (xy 236.598335 -267.228323) (xy 236.804048 -267.23033)
			(xy 237.009526 -267.240362) (xy 237.214456 -267.258403) (xy 237.418526 -267.284426) (xy 237.621426 -267.318391)
			(xy 237.822846 -267.360246) (xy 238.022479 -267.409928) (xy 238.220022 -267.467362) (xy 238.415174 -267.532459)
			(xy 238.607638 -267.60512) (xy 238.79712 -267.685236) (xy 238.983331 -267.772683) (xy 239.16599 -267.867329)
			(xy 239.344816 -267.969029) (xy 239.519538 -268.077629) (xy 239.689891 -268.192964) (xy 239.855613 -268.314857)
			(xy 240.016454 -268.443123) (xy 240.172167 -268.577566) (xy 240.322517 -268.717983) (xy 240.467274 -268.864159)
			(xy 240.606217 -269.015871) (xy 240.739135 -269.172889) (xy 240.865826 -269.334974) (xy 240.986096 -269.501877)
			(xy 241.099763 -269.673347) (xy 241.206653 -269.84912) (xy 241.306604 -270.02893) (xy 241.399463 -270.212503)
			(xy 241.48509 -270.399559) (xy 241.563352 -270.589814) (xy 241.634133 -270.782977) (xy 241.697323 -270.978755)
			(xy 241.752826 -271.176849) (xy 241.800558 -271.376958) (xy 241.840447 -271.578776) (xy 241.872431 -271.781998)
			(xy 241.896461 -271.986312) (xy 241.912502 -272.191408) (xy 241.920528 -272.396975) (xy 241.92103 -272.499836)
			(xy 241.920528 -272.602697) (xy 241.912502 -272.808264) (xy 241.896461 -273.01336) (xy 241.872431 -273.217674)
			(xy 241.840447 -273.420896) (xy 241.800558 -273.622714) (xy 241.752826 -273.822823) (xy 241.697323 -274.020917)
			(xy 241.634133 -274.216695) (xy 241.563352 -274.409858) (xy 241.48509 -274.600113) (xy 241.399463 -274.787169)
			(xy 241.306604 -274.970742) (xy 241.206653 -275.150552) (xy 241.099763 -275.326325) (xy 240.986096 -275.497795)
			(xy 240.865826 -275.664698) (xy 240.739135 -275.826783) (xy 240.606217 -275.983801) (xy 240.467274 -276.135513)
			(xy 240.322517 -276.281689) (xy 240.172167 -276.422106) (xy 240.016454 -276.556549) (xy 239.855613 -276.684815)
			(xy 239.689891 -276.806708) (xy 239.519538 -276.922043) (xy 239.344816 -277.030643) (xy 239.16599 -277.132343)
			(xy 238.983331 -277.226989) (xy 238.79712 -277.314436) (xy 238.607638 -277.394552) (xy 238.415174 -277.467213)
			(xy 238.220022 -277.53231) (xy 238.022479 -277.589744) (xy 237.822846 -277.639426) (xy 237.621426 -277.681281)
			(xy 237.418526 -277.715246) (xy 237.214456 -277.741269) (xy 237.009526 -277.75931) (xy 236.804048 -277.769342)
			(xy 236.598335 -277.771349) (xy 236.3927 -277.765329) (xy 236.187457 -277.75129) (xy 235.982918 -277.729253)
			(xy 235.779394 -277.699254) (xy 235.577196 -277.661336) (xy 235.376631 -277.615559) (xy 235.178005 -277.561991)
			(xy 234.98162 -277.500714) (xy 234.787776 -277.431821) (xy 234.596766 -277.355418) (xy 234.408884 -277.271621)
			(xy 234.224414 -277.180557) (xy 234.043637 -277.082366) (xy 233.866829 -276.977195) (xy 233.694259 -276.865207)
			(xy 233.52619 -276.74657) (xy 233.362877 -276.621467) (xy 233.20457 -276.490087) (xy 233.051509 -276.352631)
			(xy 232.903928 -276.209307) (xy 232.762051 -276.060335) (xy 232.626094 -275.90594) (xy 232.496265 -275.746359)
			(xy 232.372761 -275.581833) (xy 232.25577 -275.412614) (xy 232.145471 -275.23896) (xy 232.04203 -275.061134)
			(xy 231.945607 -274.879408) (xy 231.856347 -274.694058) (xy 231.774387 -274.505367) (xy 231.699851 -274.313622)
			(xy 231.632853 -274.119114) (xy 231.573495 -273.922141) (xy 231.521868 -273.723002) (xy 231.478049 -273.522)
			(xy 231.442106 -273.319441) (xy 231.414093 -273.115634) (xy 231.394054 -272.91089) (xy 231.382018 -272.70552)
			(xy 231.378004 -272.499836) (xy 218.048078 -272.499836) (xy 218.048078 -352.49993) (xy 231.378004 -352.49993)
			(xy 231.382018 -352.294246) (xy 231.394054 -352.088876) (xy 231.414093 -351.884132) (xy 231.442106 -351.680325)
			(xy 231.478049 -351.477766) (xy 231.521868 -351.276764) (xy 231.573495 -351.077625) (xy 231.632853 -350.880652)
			(xy 231.699851 -350.686144) (xy 231.774387 -350.494399) (xy 231.856347 -350.305708) (xy 231.945607 -350.120358)
			(xy 232.04203 -349.938632) (xy 232.145471 -349.760806) (xy 232.25577 -349.587152) (xy 232.372761 -349.417933)
			(xy 232.496265 -349.253407) (xy 232.626094 -349.093826) (xy 232.762051 -348.939431) (xy 232.903928 -348.790459)
			(xy 233.051509 -348.647135) (xy 233.20457 -348.509679) (xy 233.362877 -348.378299) (xy 233.52619 -348.253196)
			(xy 233.694259 -348.134559) (xy 233.866829 -348.022571) (xy 234.043637 -347.9174) (xy 234.224414 -347.819209)
			(xy 234.408884 -347.728145) (xy 234.596766 -347.644348) (xy 234.787776 -347.567945) (xy 234.98162 -347.499052)
			(xy 235.178005 -347.437775) (xy 235.376631 -347.384207) (xy 235.577196 -347.33843) (xy 235.779394 -347.300512)
			(xy 235.982918 -347.270513) (xy 236.187457 -347.248476) (xy 236.3927 -347.234437) (xy 236.598335 -347.228417)
			(xy 236.804048 -347.230424) (xy 237.009526 -347.240456) (xy 237.214456 -347.258497) (xy 237.418526 -347.28452)
			(xy 237.621426 -347.318485) (xy 237.822846 -347.36034) (xy 238.022479 -347.410022) (xy 238.220022 -347.467456)
			(xy 238.415174 -347.532553) (xy 238.607638 -347.605214) (xy 238.79712 -347.68533) (xy 238.983331 -347.772777)
			(xy 239.16599 -347.867423) (xy 239.344816 -347.969123) (xy 239.519538 -348.077723) (xy 239.689891 -348.193058)
			(xy 239.855613 -348.314951) (xy 240.016454 -348.443217) (xy 240.172167 -348.57766) (xy 240.322517 -348.718077)
			(xy 240.467274 -348.864253) (xy 240.606217 -349.015965) (xy 240.739135 -349.172983) (xy 240.865826 -349.335068)
			(xy 240.986096 -349.501971) (xy 241.099763 -349.673441) (xy 241.206653 -349.849214) (xy 241.306604 -350.029024)
			(xy 241.399463 -350.212597) (xy 241.48509 -350.399653) (xy 241.563352 -350.589908) (xy 241.634133 -350.783071)
			(xy 241.697323 -350.978849) (xy 241.752826 -351.176943) (xy 241.800558 -351.377052) (xy 241.840447 -351.57887)
			(xy 241.872431 -351.782092) (xy 241.896461 -351.986406) (xy 241.912502 -352.191502) (xy 241.920528 -352.397069)
			(xy 241.92103 -352.49993) (xy 241.920528 -352.602791) (xy 241.912502 -352.808358) (xy 241.896461 -353.013454)
			(xy 241.872431 -353.217768) (xy 241.840447 -353.42099) (xy 241.800558 -353.622808) (xy 241.752826 -353.822917)
			(xy 241.697323 -354.021011) (xy 241.634133 -354.216789) (xy 241.563352 -354.409952) (xy 241.48509 -354.600207)
			(xy 241.399463 -354.787263) (xy 241.306604 -354.970836) (xy 241.206653 -355.150646) (xy 241.099763 -355.326419)
			(xy 240.986096 -355.497889) (xy 240.865826 -355.664792) (xy 240.739135 -355.826877) (xy 240.606217 -355.983895)
			(xy 240.467274 -356.135607) (xy 240.322517 -356.281783) (xy 240.172167 -356.4222) (xy 240.016454 -356.556643)
			(xy 239.855613 -356.684909) (xy 239.689891 -356.806802) (xy 239.519538 -356.922137) (xy 239.344816 -357.030737)
			(xy 239.16599 -357.132437) (xy 238.983331 -357.227083) (xy 238.79712 -357.31453) (xy 238.607638 -357.394646)
			(xy 238.415174 -357.467307) (xy 238.220022 -357.532404) (xy 238.022479 -357.589838) (xy 237.822846 -357.63952)
			(xy 237.621426 -357.681375) (xy 237.418526 -357.71534) (xy 237.214456 -357.741363) (xy 237.009526 -357.759404)
			(xy 236.804048 -357.769436) (xy 236.598335 -357.771443) (xy 236.3927 -357.765423) (xy 236.187457 -357.751384)
			(xy 235.982918 -357.729347) (xy 235.779394 -357.699348) (xy 235.577196 -357.66143) (xy 235.376631 -357.615653)
			(xy 235.178005 -357.562085) (xy 234.98162 -357.500808) (xy 234.787776 -357.431915) (xy 234.596766 -357.355512)
			(xy 234.408884 -357.271715) (xy 234.224414 -357.180651) (xy 234.043637 -357.08246) (xy 233.866829 -356.977289)
			(xy 233.694259 -356.865301) (xy 233.52619 -356.746664) (xy 233.362877 -356.621561) (xy 233.20457 -356.490181)
			(xy 233.051509 -356.352725) (xy 232.903928 -356.209401) (xy 232.762051 -356.060429) (xy 232.626094 -355.906034)
			(xy 232.496265 -355.746453) (xy 232.372761 -355.581927) (xy 232.25577 -355.412708) (xy 232.145471 -355.239054)
			(xy 232.04203 -355.061228) (xy 231.945607 -354.879502) (xy 231.856347 -354.694152) (xy 231.774387 -354.505461)
			(xy 231.699851 -354.313716) (xy 231.632853 -354.119208) (xy 231.573495 -353.922235) (xy 231.521868 -353.723096)
			(xy 231.478049 -353.522094) (xy 231.442106 -353.319535) (xy 231.414093 -353.115728) (xy 231.394054 -352.910984)
			(xy 231.382018 -352.705614) (xy 231.378004 -352.49993) (xy 218.048078 -352.49993) (xy 218.048078 -356.32771)
			(xy 218.047534 -356.352672) (xy 218.037796 -356.401636) (xy 218.018678 -356.447754) (xy 217.990917 -356.489247)
			(xy 217.973656 -356.507288) (xy 217.423492 -357.057452) (xy 217.45829 -357.09352) (xy 217.528605 -357.166715)
			(xy 217.664237 -357.317745) (xy 217.793953 -357.473884) (xy 217.91756 -357.634903) (xy 218.034877 -357.800561)
			(xy 218.145728 -357.970614) (xy 218.249949 -358.144808) (xy 218.347386 -358.322887) (xy 218.437894 -358.504585)
			(xy 218.521339 -358.689633) (xy 218.597597 -358.877757) (xy 218.666554 -359.068677) (xy 218.72811 -359.262111)
			(xy 218.782172 -359.457772) (xy 218.82866 -359.655369) (xy 218.867506 -359.85461) (xy 218.898651 -360.055198)
			(xy 218.92205 -360.256838) (xy 218.937668 -360.459228) (xy 218.945482 -360.66207) (xy 218.945968 -360.763566)
			(xy 218.945968 -360.76382) (xy 252.853952 -360.76382) (xy 252.854424 -360.661891) (xy 252.862306 -360.458186)
			(xy 252.878057 -360.254937) (xy 252.901656 -360.05245) (xy 252.933066 -359.851027) (xy 252.97224 -359.650968)
			(xy 253.01912 -359.452574) (xy 253.073637 -359.256141) (xy 253.135707 -359.061962) (xy 253.205239 -358.870329)
			(xy 253.282128 -358.681527) (xy 253.36626 -358.49584) (xy 253.457508 -358.313544) (xy 253.555737 -358.134913)
			(xy 253.660799 -357.960213) (xy 253.772537 -357.789706) (xy 253.890784 -357.623647) (xy 254.015363 -357.462284)
			(xy 254.146088 -357.305859) (xy 254.282764 -357.154605) (xy 254.425186 -357.008748) (xy 254.57314 -356.868508)
			(xy 254.726407 -356.734093) (xy 254.884756 -356.605704) (xy 255.04795 -356.483534) (xy 255.13157 -356.425246)
			(xy 255.143523 -356.416384) (xy 255.162137 -356.393191) (xy 255.173274 -356.365615) (xy 255.175986 -356.335999)
			(xy 255.170044 -356.306859) (xy 255.155952 -356.28067) (xy 255.145794 -356.269798) (xy 253.619 -354.743004)
			(xy 253.601767 -354.724944) (xy 253.574036 -354.683445) (xy 253.554933 -354.637334) (xy 253.545192 -354.588382)
			(xy 253.544578 -354.563426) (xy 253.544578 -194.91071) (xy 253.545118 -194.885748) (xy 253.554854 -194.836782)
			(xy 253.573973 -194.790664) (xy 253.601737 -194.749171) (xy 253.619 -194.731132) (xy 254.39624 -193.953892)
			(xy 254.414322 -193.936684) (xy 254.455814 -193.908949) (xy 254.501918 -193.889839) (xy 254.550864 -193.880089)
			(xy 254.575818 -193.87947) (xy 318.06388 -193.87947) (xy 318.06388 -185.969148) (xy 318.064443 -185.944187)
			(xy 318.074172 -185.895222) (xy 318.093284 -185.849104) (xy 318.121042 -185.807611) (xy 318.138302 -185.78957)
			(xy 355.746304 -148.181568) (xy 355.764345 -148.164311) (xy 355.805847 -148.136571) (xy 355.851964 -148.117463)
			(xy 355.900923 -148.107719) (xy 355.925882 -148.107146) (xy 396.387574 -148.107146) (xy 396.409883 -148.09071)
			(xy 396.458302 -148.063769) (xy 396.510108 -148.044111) (xy 396.564212 -148.032148) (xy 396.619476 -148.028133)
			(xy 396.67474 -148.032148) (xy 396.728844 -148.044111) (xy 396.78065 -148.063769) (xy 396.829069 -148.09071)
			(xy 396.851378 -148.107146) (xy 407.916634 -148.107146) (xy 407.933209 -148.084393) (xy 407.971957 -148.04356)
			(xy 408.016288 -148.008868) (xy 408.065238 -147.98107) (xy 408.117743 -147.960772) (xy 408.172661 -147.948414)
			(xy 408.2288 -147.944265) (xy 408.284939 -147.948414) (xy 408.339857 -147.960772) (xy 408.392362 -147.98107)
			(xy 408.441312 -148.008868) (xy 408.485643 -148.04356) (xy 408.524391 -148.084393) (xy 408.540966 -148.107146)
			(xy 410.120338 -148.107146) (xy 410.138575 -148.086119) (xy 410.1801 -148.049055) (xy 410.226566 -148.018415)
			(xy 410.27699 -147.994848) (xy 410.330301 -147.978853) (xy 410.38537 -147.97077) (xy 410.44103 -147.97077)
			(xy 410.496099 -147.978853) (xy 410.54941 -147.994848) (xy 410.599834 -148.018415) (xy 410.6463 -148.049055)
			(xy 410.687825 -148.086119) (xy 410.706062 -148.107146) (xy 418.927534 -148.107146) (xy 418.952494 -148.10773)
			(xy 419.001457 -148.117454) (xy 419.047575 -148.13656) (xy 419.08907 -148.164311) (xy 419.107112 -148.181568)
			(xy 421.235886 -150.310342) (xy 421.253091 -150.328427) (xy 421.280828 -150.369917) (xy 421.299938 -150.416021)
			(xy 421.309689 -150.464966) (xy 421.310308 -150.48992) (xy 421.310308 -153.774902) (xy 436.385725 -153.774902)
			(xy 436.389718 -153.565161) (xy 436.401694 -153.355724) (xy 436.421635 -153.146895) (xy 436.449512 -152.938976)
			(xy 436.485284 -152.732269) (xy 436.528899 -152.527074) (xy 436.580295 -152.323689) (xy 436.639397 -152.122407)
			(xy 436.706119 -151.923521) (xy 436.780364 -151.72732) (xy 436.862024 -151.534088) (xy 436.950982 -151.344104)
			(xy 437.047109 -151.157645) (xy 437.150264 -150.974981) (xy 437.260299 -150.796376) (xy 437.377053 -150.62209)
			(xy 437.500358 -150.452375) (xy 437.630035 -150.287477) (xy 437.765896 -150.127636) (xy 437.907743 -149.973083)
			(xy 438.055372 -149.824043) (xy 438.208567 -149.68073) (xy 438.367108 -149.543354) (xy 438.530763 -149.412113)
			(xy 438.699297 -149.287198) (xy 438.872463 -149.16879) (xy 439.050013 -149.05706) (xy 439.231687 -148.95217)
			(xy 439.417222 -148.854273) (xy 439.60635 -148.763511) (xy 439.798797 -148.680014) (xy 439.994282 -148.603904)
			(xy 440.192524 -148.535292) (xy 440.393234 -148.474277) (xy 440.596121 -148.420948) (xy 440.800891 -148.375381)
			(xy 441.007248 -148.337642) (xy 441.214892 -148.307788) (xy 441.423522 -148.28586) (xy 441.632835 -148.271891)
			(xy 441.842529 -148.2659) (xy 442.052298 -148.267897) (xy 442.26184 -148.277879) (xy 442.47085 -148.295831)
			(xy 442.679024 -148.321727) (xy 442.886062 -148.355529) (xy 443.091663 -148.397189) (xy 443.295529 -148.446647)
			(xy 443.497364 -148.50383) (xy 443.696876 -148.568655) (xy 443.893775 -148.641029) (xy 444.087776 -148.720846)
			(xy 444.278598 -148.807992) (xy 444.465964 -148.902339) (xy 444.649602 -149.00375) (xy 444.829246 -149.11208)
			(xy 445.004636 -149.22717) (xy 445.175517 -149.348854) (xy 445.341641 -149.476955) (xy 445.502768 -149.611288)
			(xy 445.658665 -149.751657) (xy 445.809104 -149.89786) (xy 445.953868 -150.049684) (xy 446.092747 -150.20691)
			(xy 446.22554 -150.369309) (xy 446.352054 -150.536645) (xy 446.472106 -150.708677) (xy 446.585521 -150.885154)
			(xy 446.692135 -151.065822) (xy 446.791794 -151.250417) (xy 446.884353 -151.438672) (xy 446.969678 -151.630315)
			(xy 447.047645 -151.825067) (xy 447.118141 -152.022647) (xy 447.181064 -152.222766) (xy 447.236323 -152.425137)
			(xy 447.283837 -152.629464) (xy 447.323538 -152.835452) (xy 447.355368 -153.042803) (xy 447.379281 -153.251214)
			(xy 447.395242 -153.460385) (xy 447.403229 -153.670012) (xy 447.403728 -153.774902) (xy 447.403229 -153.879792)
			(xy 447.395242 -154.089419) (xy 447.379281 -154.29859) (xy 447.355368 -154.507001) (xy 447.323538 -154.714352)
			(xy 447.283837 -154.92034) (xy 447.236323 -155.124667) (xy 447.181064 -155.327038) (xy 447.118141 -155.527157)
			(xy 447.047645 -155.724737) (xy 446.969678 -155.919489) (xy 446.884353 -156.111132) (xy 446.791794 -156.299387)
			(xy 446.692135 -156.483982) (xy 446.585521 -156.66465) (xy 446.472106 -156.841127) (xy 446.352054 -157.013159)
			(xy 446.22554 -157.180495) (xy 446.092747 -157.342894) (xy 445.953868 -157.50012) (xy 445.809104 -157.651944)
			(xy 445.658665 -157.798147) (xy 445.502768 -157.938516) (xy 445.341641 -158.072849) (xy 445.175517 -158.20095)
			(xy 445.004636 -158.322634) (xy 444.829246 -158.437724) (xy 444.649602 -158.546054) (xy 444.465964 -158.647465)
			(xy 444.278598 -158.741812) (xy 444.087776 -158.828958) (xy 443.893775 -158.908775) (xy 443.696876 -158.981149)
			(xy 443.497364 -159.045974) (xy 443.295529 -159.103157) (xy 443.091663 -159.152615) (xy 442.886062 -159.194275)
			(xy 442.679024 -159.228077) (xy 442.47085 -159.253973) (xy 442.26184 -159.271925) (xy 442.052298 -159.281907)
			(xy 441.842529 -159.283904) (xy 441.632835 -159.277913) (xy 441.423522 -159.263944) (xy 441.214892 -159.242016)
			(xy 441.007248 -159.212162) (xy 440.800891 -159.174423) (xy 440.596121 -159.128856) (xy 440.393234 -159.075527)
			(xy 440.192524 -159.014512) (xy 439.994282 -158.9459) (xy 439.798797 -158.86979) (xy 439.60635 -158.786293)
			(xy 439.417222 -158.695531) (xy 439.231687 -158.597634) (xy 439.050013 -158.492744) (xy 438.872463 -158.381014)
			(xy 438.699297 -158.262606) (xy 438.530763 -158.137691) (xy 438.367108 -158.00645) (xy 438.208567 -157.869074)
			(xy 438.055372 -157.725761) (xy 437.907743 -157.576721) (xy 437.765896 -157.422168) (xy 437.630035 -157.262327)
			(xy 437.500358 -157.097429) (xy 437.377053 -156.927714) (xy 437.260299 -156.753428) (xy 437.150264 -156.574823)
			(xy 437.047109 -156.392159) (xy 436.950982 -156.2057) (xy 436.862024 -156.015716) (xy 436.780364 -155.822484)
			(xy 436.706119 -155.626283) (xy 436.639397 -155.427397) (xy 436.580295 -155.226115) (xy 436.528899 -155.02273)
			(xy 436.485284 -154.817535) (xy 436.449512 -154.610828) (xy 436.421635 -154.402909) (xy 436.401694 -154.19408)
			(xy 436.389718 -153.984643) (xy 436.385725 -153.774902) (xy 421.310308 -153.774902) (xy 421.310308 -157.585918)
			(xy 421.310816 -157.589728) (xy 421.312941 -157.60424) (xy 421.31523 -157.633482) (xy 421.315388 -157.648148)
			(xy 421.315228 -157.662814) (xy 421.312943 -157.692056) (xy 421.310816 -157.706568) (xy 421.310308 -157.710378)
			(xy 421.310308 -162.088068) (xy 421.335068 -162.099742) (xy 421.381259 -162.129115) (xy 421.422775 -162.164791)
			(xy 421.458763 -162.206037) (xy 421.488483 -162.252005) (xy 421.511325 -162.301751) (xy 421.526819 -162.354251)
			(xy 421.534646 -162.408428) (xy 421.534647 -162.463167) (xy 421.52682 -162.517344) (xy 421.511327 -162.569845)
			(xy 421.488485 -162.61959) (xy 421.458766 -162.665559) (xy 421.422778 -162.706805) (xy 421.381263 -162.742482)
			(xy 421.335072 -162.771856) (xy 421.310308 -162.78352) (xy 421.310308 -169.35323) (xy 421.594788 -169.63771)
			(xy 426.620432 -169.63771) (xy 426.636192 -169.597723) (xy 426.67435 -169.520702) (xy 426.719758 -169.44772)
			(xy 426.771992 -169.379457) (xy 426.830567 -169.31655) (xy 426.894936 -169.259586) (xy 426.964499 -169.209095)
			(xy 427.038606 -169.165548) (xy 427.116568 -169.129352) (xy 427.197658 -169.100843) (xy 427.281119 -169.080287)
			(xy 427.366173 -169.067877) (xy 427.452028 -169.063727) (xy 427.537883 -169.067877) (xy 427.622937 -169.080287)
			(xy 427.706398 -169.100843) (xy 427.787488 -169.129352) (xy 427.86545 -169.165548) (xy 427.939557 -169.209095)
			(xy 428.00912 -169.259586) (xy 428.073489 -169.31655) (xy 428.132064 -169.379457) (xy 428.184298 -169.44772)
			(xy 428.229706 -169.520702) (xy 428.267864 -169.597723) (xy 428.283624 -169.63771) (xy 442.70676 -169.63771)
			(xy 442.73172 -169.638288) (xy 442.780683 -169.648015) (xy 442.826801 -169.667124) (xy 442.868296 -169.694875)
			(xy 442.886338 -169.712132) (xy 442.898022 -169.723816) (xy 442.905378 -169.731256) (xy 442.918986 -169.747149)
			(xy 442.9252 -169.755566) (xy 442.92774 -169.759122) (xy 443.525656 -170.357292) (xy 443.542911 -170.375335)
			(xy 443.57065 -170.416837) (xy 443.589759 -170.462953) (xy 443.599504 -170.511911) (xy 443.600078 -170.53687)
			(xy 443.600078 -194.497198) (xy 443.620781 -194.515774) (xy 443.65674 -194.558206) (xy 443.685659 -194.605715)
			(xy 443.706834 -194.657146) (xy 443.719749 -194.711245) (xy 443.72409 -194.766695) (xy 443.719751 -194.822144)
			(xy 443.706837 -194.876244) (xy 443.685664 -194.927675) (xy 443.656746 -194.975186) (xy 443.620788 -195.017619)
			(xy 443.600078 -195.036186) (xy 443.600078 -195.347082) (xy 443.620765 -195.365675) (xy 443.656724 -195.408104)
			(xy 443.685644 -195.455612) (xy 443.706819 -195.50704) (xy 443.719736 -195.561137) (xy 443.724078 -195.616584)
			(xy 443.719741 -195.672032) (xy 443.706829 -195.72613) (xy 443.685658 -195.77756) (xy 443.656742 -195.82507)
			(xy 443.620787 -195.867503) (xy 443.600078 -195.88607) (xy 443.600078 -197.047104) (xy 443.620787 -197.065673)
			(xy 443.656746 -197.108106) (xy 443.685665 -197.155617) (xy 443.70684 -197.207049) (xy 443.719754 -197.261148)
			(xy 443.724095 -197.316599) (xy 443.719755 -197.372049) (xy 443.70684 -197.426149) (xy 443.685666 -197.477581)
			(xy 443.656747 -197.525092) (xy 443.620789 -197.567525) (xy 443.600078 -197.586092) (xy 443.600078 -198.747126)
			(xy 443.620809 -198.765672) (xy 443.656768 -198.808108) (xy 443.685686 -198.855622) (xy 443.70686 -198.907057)
			(xy 443.719773 -198.96116) (xy 443.724111 -199.016613) (xy 443.719769 -199.072066) (xy 443.706852 -199.126168)
			(xy 443.685674 -199.177601) (xy 443.656753 -199.225113) (xy 443.620791 -199.267547) (xy 443.600078 -199.286114)
			(xy 443.600078 -201.297286) (xy 443.620769 -201.315875) (xy 443.656728 -201.358305) (xy 443.685647 -201.405813)
			(xy 443.706823 -201.457242) (xy 443.719739 -201.511339) (xy 443.724081 -201.566787) (xy 443.719743 -201.622235)
			(xy 443.706831 -201.676334) (xy 443.685659 -201.727764) (xy 443.656743 -201.775274) (xy 443.620787 -201.817707)
			(xy 443.600078 -201.836274) (xy 443.600078 -202.997308) (xy 443.620791 -203.015873) (xy 443.65675 -203.058307)
			(xy 443.685669 -203.105818) (xy 443.706843 -203.15725) (xy 443.719758 -203.21135) (xy 443.724098 -203.266801)
			(xy 443.719757 -203.322252) (xy 443.706843 -203.376352) (xy 443.685668 -203.427784) (xy 443.656748 -203.475296)
			(xy 443.620789 -203.517729) (xy 443.600078 -203.536296) (xy 443.600078 -204.697076) (xy 443.620759 -204.715675)
			(xy 443.656718 -204.758104) (xy 443.685638 -204.80561) (xy 443.706814 -204.857038) (xy 443.719731 -204.911134)
			(xy 443.724074 -204.96658) (xy 443.719737 -205.022028) (xy 443.706826 -205.076125) (xy 443.685655 -205.127555)
			(xy 443.656741 -205.175064) (xy 443.620787 -205.217497) (xy 443.600078 -205.236064) (xy 443.600078 -206.397098)
			(xy 443.620781 -206.415674) (xy 443.65674 -206.458106) (xy 443.685659 -206.505615) (xy 443.706834 -206.557046)
			(xy 443.719749 -206.611145) (xy 443.72409 -206.666595) (xy 443.719751 -206.722044) (xy 443.706837 -206.776144)
			(xy 443.685664 -206.827575) (xy 443.656746 -206.875086) (xy 443.620788 -206.917519) (xy 443.600078 -206.936086)
			(xy 443.600078 -208.09712) (xy 443.620803 -208.115672) (xy 443.656762 -208.158108) (xy 443.68568 -208.205621)
			(xy 443.706854 -208.257055) (xy 443.719768 -208.311157) (xy 443.724107 -208.366609) (xy 443.719765 -208.422061)
			(xy 443.706849 -208.476163) (xy 443.685672 -208.527596) (xy 443.656751 -208.575107) (xy 443.62079 -208.617541)
			(xy 443.600078 -208.636108) (xy 443.600078 -210.64728) (xy 443.620763 -210.665875) (xy 443.656722 -210.708304)
			(xy 443.685642 -210.755811) (xy 443.706818 -210.807239) (xy 443.719734 -210.861336) (xy 443.724077 -210.916783)
			(xy 443.719739 -210.972231) (xy 443.706828 -211.026328) (xy 443.685657 -211.077759) (xy 443.656742 -211.125268)
			(xy 443.620787 -211.167701) (xy 443.600078 -211.186268) (xy 443.600078 -212.347302) (xy 443.620785 -212.365874)
			(xy 443.656744 -212.408306) (xy 443.685663 -212.455816) (xy 443.706838 -212.507248) (xy 443.719753 -212.561347)
			(xy 443.724093 -212.616797) (xy 443.719754 -212.672248) (xy 443.706839 -212.726347) (xy 443.685665 -212.777779)
			(xy 443.656747 -212.82529) (xy 443.620789 -212.867723) (xy 443.600078 -212.88629) (xy 443.600078 -214.04707)
			(xy 443.620753 -214.065676) (xy 443.656712 -214.108103) (xy 443.685632 -214.155609) (xy 443.706808 -214.207035)
			(xy 443.719726 -214.26113) (xy 443.724069 -214.316576) (xy 443.719733 -214.372023) (xy 443.706823 -214.42612)
			(xy 443.685653 -214.477549) (xy 443.65674 -214.525059) (xy 443.620786 -214.567491) (xy 443.600078 -214.586058)
			(xy 443.600078 -215.747092) (xy 443.620775 -215.765674) (xy 443.656734 -215.808105) (xy 443.685653 -215.855614)
			(xy 443.706829 -215.907044) (xy 443.719744 -215.961142) (xy 443.724086 -216.016591) (xy 443.719747 -216.07204)
			(xy 443.706834 -216.126139) (xy 443.685661 -216.17757) (xy 443.656745 -216.22508) (xy 443.620788 -216.267513)
			(xy 443.600078 -216.28608) (xy 443.600078 -217.447114) (xy 443.620797 -217.465673) (xy 443.656756 -217.508107)
			(xy 443.685675 -217.555619) (xy 443.706849 -217.607052) (xy 443.719763 -217.661154) (xy 443.724102 -217.716605)
			(xy 443.719761 -217.772057) (xy 443.706846 -217.826158) (xy 443.68567 -217.87759) (xy 443.65675 -217.925101)
			(xy 443.62079 -217.967535) (xy 443.600078 -217.986102) (xy 443.600078 -219.997274) (xy 443.620757 -220.015875)
			(xy 443.656716 -220.058304) (xy 443.685636 -220.10581) (xy 443.706812 -220.157237) (xy 443.719729 -220.211332)
			(xy 443.724072 -220.266779) (xy 443.719735 -220.322226) (xy 443.706825 -220.376323) (xy 443.685655 -220.427753)
			(xy 443.65674 -220.475263) (xy 443.620787 -220.517695) (xy 443.600078 -220.536262) (xy 443.600078 -221.697296)
			(xy 443.620779 -221.715874) (xy 443.656738 -221.758305) (xy 443.685657 -221.805815) (xy 443.706832 -221.857245)
			(xy 443.719748 -221.911344) (xy 443.724089 -221.966793) (xy 443.71975 -222.022243) (xy 443.706836 -222.076342)
			(xy 443.685663 -222.127773) (xy 443.656746 -222.175284) (xy 443.620788 -222.217717) (xy 443.600078 -222.236284)
			(xy 443.600078 -223.397064) (xy 443.620747 -223.415676) (xy 443.656706 -223.458103) (xy 443.685626 -223.505607)
			(xy 443.706803 -223.557033) (xy 443.71972 -223.611127) (xy 443.724064 -223.666573) (xy 443.719729 -223.722019)
			(xy 443.70682 -223.776115) (xy 443.685651 -223.827544) (xy 443.656738 -223.875053) (xy 443.620786 -223.917485)
			(xy 443.600078 -223.936052) (xy 443.600078 -225.097086) (xy 443.620769 -225.115675) (xy 443.656728 -225.158105)
			(xy 443.685647 -225.205613) (xy 443.706823 -225.257042) (xy 443.719739 -225.311139) (xy 443.724081 -225.366587)
			(xy 443.719743 -225.422035) (xy 443.706831 -225.476134) (xy 443.685659 -225.527564) (xy 443.656743 -225.575074)
			(xy 443.620787 -225.617507) (xy 443.600078 -225.636074) (xy 443.600078 -226.797108) (xy 443.620791 -226.815673)
			(xy 443.65675 -226.858107) (xy 443.685669 -226.905618) (xy 443.706843 -226.95705) (xy 443.719758 -227.01115)
			(xy 443.724098 -227.066601) (xy 443.719757 -227.122052) (xy 443.706843 -227.176152) (xy 443.685668 -227.227584)
			(xy 443.656748 -227.275096) (xy 443.620789 -227.317529) (xy 443.600078 -227.336096) (xy 443.600078 -229.347268)
			(xy 443.620751 -229.365876) (xy 443.65671 -229.408303) (xy 443.68563 -229.455808) (xy 443.706806 -229.507235)
			(xy 443.719724 -229.561329) (xy 443.724067 -229.616775) (xy 443.719732 -229.672222) (xy 443.706822 -229.726318)
			(xy 443.685652 -229.777747) (xy 443.656739 -229.825257) (xy 443.620786 -229.867689) (xy 443.600078 -229.886256)
			(xy 443.600078 -231.04729) (xy 443.620773 -231.065874) (xy 443.656732 -231.108305) (xy 443.685651 -231.155814)
			(xy 443.706827 -231.207243) (xy 443.719743 -231.261341) (xy 443.724084 -231.31679) (xy 443.719746 -231.372238)
			(xy 443.706833 -231.426337) (xy 443.685661 -231.477768) (xy 443.656744 -231.525278) (xy 443.620788 -231.567711)
			(xy 443.600078 -231.586278) (xy 443.600078 -232.747312) (xy 443.620795 -232.765873) (xy 443.656754 -232.808307)
			(xy 443.685673 -232.855819) (xy 443.706847 -232.907252) (xy 443.719761 -232.961353) (xy 443.724101 -233.016804)
			(xy 443.71976 -233.072255) (xy 443.706845 -233.126356) (xy 443.685669 -233.177788) (xy 443.656749 -233.225299)
			(xy 443.620789 -233.267733) (xy 443.600078 -233.2863) (xy 443.600078 -234.44708) (xy 443.620763 -234.465675)
			(xy 443.656722 -234.508104) (xy 443.685642 -234.555611) (xy 443.706818 -234.607039) (xy 443.719734 -234.661136)
			(xy 443.724077 -234.716583) (xy 443.719739 -234.772031) (xy 443.706828 -234.826128) (xy 443.685657 -234.877559)
			(xy 443.656742 -234.925068) (xy 443.620787 -234.967501) (xy 443.600078 -234.986068) (xy 443.600078 -236.147102)
			(xy 443.620785 -236.165674) (xy 443.656744 -236.208106) (xy 443.685663 -236.255616) (xy 443.706838 -236.307048)
			(xy 443.719753 -236.361147) (xy 443.724093 -236.416597) (xy 443.719754 -236.472048) (xy 443.706839 -236.526147)
			(xy 443.685665 -236.577579) (xy 443.656747 -236.62509) (xy 443.620789 -236.667523) (xy 443.600078 -236.68609)
			(xy 443.600078 -238.697262) (xy 443.620745 -238.715876) (xy 443.656704 -238.758303) (xy 443.685624 -238.805807)
			(xy 443.706801 -238.857232) (xy 443.719719 -238.911326) (xy 443.724063 -238.966771) (xy 443.719728 -239.022217)
			(xy 443.706819 -239.076313) (xy 443.68565 -239.127742) (xy 443.656738 -239.175251) (xy 443.620786 -239.217683)
			(xy 443.600078 -239.23625) (xy 443.600078 -240.397284) (xy 443.620767 -240.415875) (xy 443.656726 -240.458304)
			(xy 443.685645 -240.505812) (xy 443.706821 -240.557241) (xy 443.719737 -240.611338) (xy 443.72408 -240.666786)
			(xy 443.719742 -240.722234) (xy 443.70683 -240.776332) (xy 443.685658 -240.827762) (xy 443.656743 -240.875272)
			(xy 443.620787 -240.917705) (xy 443.600078 -240.936272) (xy 443.600078 -242.097306) (xy 443.620789 -242.115873)
			(xy 443.656748 -242.158306) (xy 443.685667 -242.205817) (xy 443.706841 -242.257249) (xy 443.719756 -242.311349)
			(xy 443.724096 -242.3668) (xy 443.719756 -242.422251) (xy 443.706841 -242.476351) (xy 443.685667 -242.527783)
			(xy 443.656748 -242.575294) (xy 443.620789 -242.617727) (xy 443.600078 -242.636294) (xy 443.600078 -242.98529)
			(xy 443.617828 -243.003876) (xy 443.647943 -243.045516) (xy 443.671199 -243.091342) (xy 443.687026 -243.140233)
			(xy 443.695039 -243.190994) (xy 443.695041 -243.242383) (xy 443.687032 -243.293145) (xy 443.671207 -243.342037)
			(xy 443.647955 -243.387864) (xy 443.617842 -243.429507) (xy 443.600078 -243.448078) (xy 443.600078 -243.835174)
			(xy 443.617812 -243.853774) (xy 443.647927 -243.895412) (xy 443.671184 -243.941236) (xy 443.687013 -243.990125)
			(xy 443.695027 -244.040884) (xy 443.69503 -244.092271) (xy 443.687023 -244.143031) (xy 443.671201 -244.191922)
			(xy 443.647951 -244.237749) (xy 443.617841 -244.279391) (xy 443.600078 -244.297962) (xy 443.600078 -244.647212)
			(xy 443.620795 -244.665773) (xy 443.656754 -244.708207) (xy 443.685673 -244.755719) (xy 443.706847 -244.807152)
			(xy 443.719761 -244.861253) (xy 443.724101 -244.916704) (xy 443.71976 -244.972155) (xy 443.706845 -245.026256)
			(xy 443.685669 -245.077688) (xy 443.656749 -245.125199) (xy 443.620789 -245.167633) (xy 443.600078 -245.1862)
			(xy 443.600078 -245.535196) (xy 443.617834 -245.553776) (xy 443.647949 -245.595418) (xy 443.671204 -245.641245)
			(xy 443.687031 -245.690137) (xy 443.695044 -245.740898) (xy 443.695045 -245.792288) (xy 443.687035 -245.84305)
			(xy 443.67121 -245.891942) (xy 443.647956 -245.93777) (xy 443.617843 -245.979413) (xy 443.600078 -245.997984)
			(xy 443.600078 -246.347234) (xy 443.620817 -246.365771) (xy 443.656776 -246.408209) (xy 443.685694 -246.455724)
			(xy 443.706867 -246.50716) (xy 443.71978 -246.561264) (xy 443.724117 -246.616718) (xy 443.719774 -246.672172)
			(xy 443.706856 -246.726275) (xy 443.685677 -246.777708) (xy 443.656754 -246.825221) (xy 443.620791 -246.867655)
			(xy 443.600078 -246.886222) (xy 443.600078 -248.047256) (xy 443.620839 -248.06577) (xy 443.656798 -248.108211)
			(xy 443.685715 -248.155729) (xy 443.706888 -248.207169) (xy 443.719799 -248.261276) (xy 443.724134 -248.316733)
			(xy 443.719788 -248.372189) (xy 443.706867 -248.426293) (xy 443.685686 -248.477729) (xy 443.656759 -248.525242)
			(xy 443.620793 -248.567677) (xy 443.600078 -248.586244) (xy 443.600078 -249.747278) (xy 443.620761 -249.765875)
			(xy 443.65672 -249.808304) (xy 443.68564 -249.855811) (xy 443.706816 -249.907238) (xy 443.719732 -249.961335)
			(xy 443.724075 -250.016782) (xy 443.719738 -250.072229) (xy 443.706827 -250.126327) (xy 443.685656 -250.177757)
			(xy 443.656741 -250.225266) (xy 443.620787 -250.267699) (xy 443.600078 -250.286266) (xy 443.600078 -251.4473)
			(xy 443.620783 -251.465874) (xy 443.656742 -251.508306) (xy 443.685661 -251.555816) (xy 443.706836 -251.607247)
			(xy 443.719751 -251.661346) (xy 443.724092 -251.716796) (xy 443.719752 -251.772246) (xy 443.706838 -251.826346)
			(xy 443.685665 -251.877777) (xy 443.656746 -251.925288) (xy 443.620789 -251.967721) (xy 443.600078 -251.986288)
			(xy 443.600078 -258.247134) (xy 443.620817 -258.265671) (xy 443.656776 -258.308109) (xy 443.685694 -258.355624)
			(xy 443.706867 -258.40706) (xy 443.71978 -258.461164) (xy 443.724117 -258.516618) (xy 443.719774 -258.572072)
			(xy 443.706856 -258.626175) (xy 443.685677 -258.677608) (xy 443.656754 -258.725121) (xy 443.620791 -258.767555)
			(xy 443.600078 -258.786122) (xy 443.600078 -259.947156) (xy 443.620839 -259.96567) (xy 443.656798 -260.008111)
			(xy 443.685715 -260.055629) (xy 443.706888 -260.107069) (xy 443.719799 -260.161176) (xy 443.724134 -260.216633)
			(xy 443.719788 -260.272089) (xy 443.706867 -260.326193) (xy 443.685686 -260.377629) (xy 443.656759 -260.425142)
			(xy 443.620793 -260.467577) (xy 443.600078 -260.486144) (xy 443.600078 -261.647178) (xy 443.620761 -261.665775)
			(xy 443.65672 -261.708204) (xy 443.68564 -261.755711) (xy 443.706816 -261.807138) (xy 443.719732 -261.861235)
			(xy 443.724075 -261.916682) (xy 443.719738 -261.972129) (xy 443.706827 -262.026227) (xy 443.685656 -262.077657)
			(xy 443.656741 -262.125166) (xy 443.620787 -262.167599) (xy 443.600078 -262.186166) (xy 443.600078 -263.3472)
			(xy 443.620783 -263.365774) (xy 443.656742 -263.408206) (xy 443.685661 -263.455716) (xy 443.706836 -263.507147)
			(xy 443.719751 -263.561246) (xy 443.724092 -263.616696) (xy 443.719752 -263.672146) (xy 443.706838 -263.726246)
			(xy 443.685665 -263.777677) (xy 443.656746 -263.825188) (xy 443.620789 -263.867621) (xy 443.600078 -263.886188)
			(xy 443.600078 -265.047222) (xy 443.620805 -265.065772) (xy 443.656764 -265.108208) (xy 443.685682 -265.155721)
			(xy 443.706856 -265.207156) (xy 443.71977 -265.261258) (xy 443.724108 -265.31671) (xy 443.719766 -265.372163)
			(xy 443.70685 -265.426264) (xy 443.685673 -265.477697) (xy 443.656752 -265.525209) (xy 443.62079 -265.567643)
			(xy 443.600078 -265.58621) (xy 443.600078 -266.747244) (xy 443.620827 -266.765771) (xy 443.656786 -266.80821)
			(xy 443.685704 -266.855727) (xy 443.706876 -266.907164) (xy 443.719788 -266.961269) (xy 443.724125 -267.016725)
			(xy 443.719781 -267.07218) (xy 443.706861 -267.126283) (xy 443.685681 -267.177718) (xy 443.656757 -267.225231)
			(xy 443.620792 -267.267665) (xy 443.600078 -267.286232) (xy 443.600078 -267.635228) (xy 443.617866 -267.653779)
			(xy 443.64798 -267.695425) (xy 443.671234 -267.741257) (xy 443.687059 -267.790153) (xy 443.695068 -267.840919)
			(xy 443.695065 -267.892312) (xy 443.687051 -267.943077) (xy 443.671222 -267.991972) (xy 443.647964 -268.037801)
			(xy 443.617845 -268.079445) (xy 443.600078 -268.098016) (xy 443.600078 -268.447266) (xy 443.620749 -268.465876)
			(xy 443.656708 -268.508303) (xy 443.685628 -268.555808) (xy 443.706805 -268.607234) (xy 443.719722 -268.661328)
			(xy 443.724066 -268.716774) (xy 443.71973 -268.77222) (xy 443.706821 -268.826316) (xy 443.685652 -268.877746)
			(xy 443.656739 -268.925255) (xy 443.620786 -268.967687) (xy 443.600078 -268.986254) (xy 443.600078 -270.147288)
			(xy 443.620771 -270.165874) (xy 443.65673 -270.208305) (xy 443.685649 -270.255813) (xy 443.706825 -270.307242)
			(xy 443.719741 -270.36134) (xy 443.724083 -270.416788) (xy 443.719744 -270.472237) (xy 443.706832 -270.526335)
			(xy 443.68566 -270.577766) (xy 443.656744 -270.625276) (xy 443.620788 -270.667709) (xy 443.600078 -270.686276)
			(xy 443.600078 -271.84731) (xy 443.620793 -271.865873) (xy 443.656752 -271.908307) (xy 443.685671 -271.955818)
			(xy 443.706845 -272.007251) (xy 443.71976 -272.061352) (xy 443.724099 -272.116803) (xy 443.719759 -272.172254)
			(xy 443.706844 -272.226354) (xy 443.685668 -272.277786) (xy 443.656749 -272.325298) (xy 443.620789 -272.367731)
			(xy 443.600078 -272.386298) (xy 443.600078 -273.547078) (xy 443.620761 -273.565675) (xy 443.65672 -273.608104)
			(xy 443.68564 -273.655611) (xy 443.706816 -273.707038) (xy 443.719732 -273.761135) (xy 443.724075 -273.816582)
			(xy 443.719738 -273.872029) (xy 443.706827 -273.926127) (xy 443.685656 -273.977557) (xy 443.656741 -274.025066)
			(xy 443.620787 -274.067499) (xy 443.600078 -274.086066) (xy 443.600078 -276.097238) (xy 443.620821 -276.115771)
			(xy 443.65678 -276.158209) (xy 443.685698 -276.205725) (xy 443.706871 -276.257162) (xy 443.719783 -276.311266)
			(xy 443.72412 -276.366721) (xy 443.719777 -276.422175) (xy 443.706858 -276.476278) (xy 443.685679 -276.527712)
			(xy 443.656755 -276.575225) (xy 443.620791 -276.617659) (xy 443.600078 -276.636226) (xy 443.600078 -277.79726)
			(xy 443.620743 -277.815876) (xy 443.656702 -277.858302) (xy 443.685622 -277.905806) (xy 443.706799 -277.957231)
			(xy 443.719717 -278.011325) (xy 443.724061 -278.06677) (xy 443.719726 -278.122215) (xy 443.706818 -278.176311)
			(xy 443.685649 -278.22774) (xy 443.656737 -278.275249) (xy 443.620785 -278.317681) (xy 443.600078 -278.336248)
			(xy 443.600078 -279.497282) (xy 443.620765 -279.515875) (xy 443.656724 -279.558304) (xy 443.685644 -279.605812)
			(xy 443.706819 -279.65724) (xy 443.719736 -279.711337) (xy 443.724078 -279.766784) (xy 443.719741 -279.822232)
			(xy 443.706829 -279.87633) (xy 443.685658 -279.92776) (xy 443.656742 -279.97527) (xy 443.620787 -280.017703)
			(xy 443.600078 -280.03627) (xy 443.600078 -281.197304) (xy 443.620787 -281.215873) (xy 443.656746 -281.258306)
			(xy 443.685665 -281.305817) (xy 443.70684 -281.357249) (xy 443.719754 -281.411348) (xy 443.724095 -281.466799)
			(xy 443.719755 -281.522249) (xy 443.70684 -281.576349) (xy 443.685666 -281.627781) (xy 443.656747 -281.675292)
			(xy 443.620789 -281.717725) (xy 443.600078 -281.736292) (xy 443.600078 -282.897072) (xy 443.620755 -282.915676)
			(xy 443.656714 -282.958103) (xy 443.685634 -283.005609) (xy 443.70681 -283.057036) (xy 443.719727 -283.111131)
			(xy 443.72407 -283.166578) (xy 443.719734 -283.222025) (xy 443.706824 -283.276122) (xy 443.685654 -283.327551)
			(xy 443.65674 -283.375061) (xy 443.620786 -283.417493) (xy 443.600078 -283.43606) (xy 443.600078 -285.447232)
			(xy 443.620815 -285.465771) (xy 443.656774 -285.508209) (xy 443.685692 -285.555724) (xy 443.706865 -285.607159)
			(xy 443.719778 -285.661263) (xy 443.724116 -285.716717) (xy 443.719773 -285.77217) (xy 443.706855 -285.826273)
			(xy 443.685677 -285.877707) (xy 443.656754 -285.925219) (xy 443.620791 -285.967653) (xy 443.600078 -285.98622)
			(xy 443.600078 -287.147254) (xy 443.620837 -287.16577) (xy 443.656796 -287.208211) (xy 443.685713 -287.255729)
			(xy 443.706886 -287.307168) (xy 443.719797 -287.361275) (xy 443.724133 -287.416731) (xy 443.719787 -287.472187)
			(xy 443.706866 -287.526292) (xy 443.685685 -287.577727) (xy 443.656759 -287.62524) (xy 443.620793 -287.667675)
			(xy 443.600078 -287.686242) (xy 443.600078 -288.847276) (xy 443.620759 -288.865875) (xy 443.656718 -288.908304)
			(xy 443.685638 -288.95581) (xy 443.706814 -289.007238) (xy 443.719731 -289.061334) (xy 443.724074 -289.11678)
			(xy 443.719737 -289.172228) (xy 443.706826 -289.226325) (xy 443.685655 -289.277755) (xy 443.656741 -289.325264)
			(xy 443.620787 -289.367697) (xy 443.600078 -289.386264) (xy 443.600078 -290.547298) (xy 443.620781 -290.565874)
			(xy 443.65674 -290.608306) (xy 443.685659 -290.655815) (xy 443.706834 -290.707246) (xy 443.719749 -290.761345)
			(xy 443.72409 -290.816795) (xy 443.719751 -290.872244) (xy 443.706837 -290.926344) (xy 443.685664 -290.977775)
			(xy 443.656746 -291.025286) (xy 443.620788 -291.067719) (xy 443.600078 -291.086286) (xy 443.600078 -292.24732)
			(xy 443.620803 -292.265872) (xy 443.656762 -292.308308) (xy 443.68568 -292.355821) (xy 443.706854 -292.407255)
			(xy 443.719768 -292.461357) (xy 443.724107 -292.516809) (xy 443.719765 -292.572261) (xy 443.706849 -292.626363)
			(xy 443.685672 -292.677796) (xy 443.656751 -292.725307) (xy 443.62079 -292.767741) (xy 443.600078 -292.786308)
			(xy 443.600078 -294.797226) (xy 443.620809 -294.815772) (xy 443.656768 -294.858208) (xy 443.685686 -294.905722)
			(xy 443.70686 -294.957157) (xy 443.719773 -295.01126) (xy 443.724111 -295.066713) (xy 443.719769 -295.122166)
			(xy 443.706852 -295.176268) (xy 443.685674 -295.227701) (xy 443.656753 -295.275213) (xy 443.620791 -295.317647)
			(xy 443.600078 -295.336214) (xy 443.600078 -296.497248) (xy 443.620831 -296.51577) (xy 443.65679 -296.55821)
			(xy 443.685708 -296.605728) (xy 443.70688 -296.657166) (xy 443.719792 -296.711272) (xy 443.724128 -296.766727)
			(xy 443.719783 -296.822183) (xy 443.706863 -296.876287) (xy 443.685683 -296.927721) (xy 443.656758 -296.975235)
			(xy 443.620792 -297.017669) (xy 443.600078 -297.036236) (xy 443.600078 -298.19727) (xy 443.620753 -298.215876)
			(xy 443.656712 -298.258303) (xy 443.685632 -298.305809) (xy 443.706808 -298.357235) (xy 443.719726 -298.41133)
			(xy 443.724069 -298.466776) (xy 443.719733 -298.522223) (xy 443.706823 -298.57632) (xy 443.685653 -298.627749)
			(xy 443.65674 -298.675259) (xy 443.620786 -298.717691) (xy 443.600078 -298.736258) (xy 443.600078 -299.897292)
			(xy 443.620775 -299.915874) (xy 443.656734 -299.958305) (xy 443.685653 -300.005814) (xy 443.706829 -300.057244)
			(xy 443.719744 -300.111342) (xy 443.724086 -300.166791) (xy 443.719747 -300.22224) (xy 443.706834 -300.276339)
			(xy 443.685661 -300.32777) (xy 443.656745 -300.37528) (xy 443.620788 -300.417713) (xy 443.600078 -300.43628)
			(xy 443.600078 -301.597314) (xy 443.620797 -301.615873) (xy 443.656756 -301.658307) (xy 443.685675 -301.705819)
			(xy 443.706849 -301.757252) (xy 443.719763 -301.811354) (xy 443.724102 -301.866805) (xy 443.719761 -301.922257)
			(xy 443.706846 -301.976358) (xy 443.68567 -302.02779) (xy 443.65675 -302.075301) (xy 443.62079 -302.117735)
			(xy 443.600078 -302.136302) (xy 443.600078 -304.14722) (xy 443.620803 -304.165772) (xy 443.656762 -304.208208)
			(xy 443.68568 -304.255721) (xy 443.706854 -304.307155) (xy 443.719768 -304.361257) (xy 443.724107 -304.416709)
			(xy 443.719765 -304.472161) (xy 443.706849 -304.526263) (xy 443.685672 -304.577696) (xy 443.656751 -304.625207)
			(xy 443.62079 -304.667641) (xy 443.600078 -304.686208) (xy 443.600078 -305.847242) (xy 443.620825 -305.865771)
			(xy 443.656784 -305.908209) (xy 443.685702 -305.955726) (xy 443.706875 -306.007163) (xy 443.719787 -306.061268)
			(xy 443.724124 -306.116724) (xy 443.719779 -306.172178) (xy 443.70686 -306.226281) (xy 443.68568 -306.277716)
			(xy 443.656756 -306.325229) (xy 443.620792 -306.367663) (xy 443.600078 -306.38623) (xy 443.600078 -307.547264)
			(xy 443.620747 -307.565876) (xy 443.656706 -307.608303) (xy 443.685626 -307.655807) (xy 443.706803 -307.707233)
			(xy 443.71972 -307.761327) (xy 443.724064 -307.816773) (xy 443.719729 -307.872219) (xy 443.70682 -307.926315)
			(xy 443.685651 -307.977744) (xy 443.656738 -308.025253) (xy 443.620786 -308.067685) (xy 443.600078 -308.086252)
			(xy 443.600078 -309.247286) (xy 443.620769 -309.265875) (xy 443.656728 -309.308305) (xy 443.685647 -309.355813)
			(xy 443.706823 -309.407242) (xy 443.719739 -309.461339) (xy 443.724081 -309.516787) (xy 443.719743 -309.572235)
			(xy 443.706831 -309.626334) (xy 443.685659 -309.677764) (xy 443.656743 -309.725274) (xy 443.620787 -309.767707)
			(xy 443.600078 -309.786274) (xy 443.600078 -310.947308) (xy 443.620791 -310.965873) (xy 443.65675 -311.008307)
			(xy 443.685669 -311.055818) (xy 443.706843 -311.10725) (xy 443.719758 -311.16135) (xy 443.724098 -311.216801)
			(xy 443.719757 -311.272252) (xy 443.706843 -311.326352) (xy 443.685668 -311.377784) (xy 443.656748 -311.425296)
			(xy 443.620789 -311.467729) (xy 443.600078 -311.486296) (xy 443.600078 -312.07837) (xy 443.59951 -312.103331)
			(xy 443.58978 -312.152294) (xy 443.570669 -312.198412) (xy 443.542914 -312.239906) (xy 443.525656 -312.257948)
			(xy 442.761116 -313.022488) (xy 442.743049 -313.039713) (xy 442.701553 -313.067446) (xy 442.655443 -313.086551)
			(xy 442.606493 -313.096295) (xy 442.581538 -313.09691) (xy 442.440568 -313.09691) (xy 442.42675 -313.119484)
			(xy 442.39349 -313.160652) (xy 442.354504 -313.196444) (xy 442.31065 -313.226073) (xy 442.262893 -313.248885)
			(xy 442.212287 -313.264378) (xy 442.159944 -313.27221) (xy 442.10702 -313.27221) (xy 442.054677 -313.264378)
			(xy 442.004071 -313.248885) (xy 441.956314 -313.226073) (xy 441.91246 -313.196444) (xy 441.873474 -313.160652)
			(xy 441.840214 -313.119484) (xy 441.826396 -313.09691) (xy 440.230768 -313.09691) (xy 440.21695 -313.119484)
			(xy 440.18369 -313.160652) (xy 440.144704 -313.196444) (xy 440.10085 -313.226073) (xy 440.053093 -313.248885)
			(xy 440.002487 -313.264378) (xy 439.950144 -313.27221) (xy 439.89722 -313.27221) (xy 439.844877 -313.264378)
			(xy 439.794271 -313.248885) (xy 439.746514 -313.226073) (xy 439.70266 -313.196444) (xy 439.663674 -313.160652)
			(xy 439.630414 -313.119484) (xy 439.616596 -313.09691) (xy 436.09768 -313.09691) (xy 436.083575 -313.117523)
			(xy 436.050136 -313.154622) (xy 436.011458 -313.186221) (xy 435.968435 -313.21159) (xy 435.922063 -313.230141)
			(xy 435.873414 -313.241447) (xy 435.823614 -313.245245) (xy 435.773814 -313.241447) (xy 435.725165 -313.230141)
			(xy 435.678793 -313.21159) (xy 435.63577 -313.186221) (xy 435.597092 -313.154622) (xy 435.563653 -313.117523)
			(xy 435.549548 -313.09691) (xy 434.896768 -313.09691) (xy 434.88295 -313.119484) (xy 434.84969 -313.160652)
			(xy 434.810704 -313.196444) (xy 434.76685 -313.226073) (xy 434.719093 -313.248885) (xy 434.668487 -313.264378)
			(xy 434.616144 -313.27221) (xy 434.56322 -313.27221) (xy 434.510877 -313.264378) (xy 434.460271 -313.248885)
			(xy 434.412514 -313.226073) (xy 434.36866 -313.196444) (xy 434.329674 -313.160652) (xy 434.296414 -313.119484)
			(xy 434.282596 -313.09691) (xy 432.686968 -313.09691) (xy 432.67315 -313.119484) (xy 432.63989 -313.160652)
			(xy 432.600904 -313.196444) (xy 432.55705 -313.226073) (xy 432.509293 -313.248885) (xy 432.458687 -313.264378)
			(xy 432.406344 -313.27221) (xy 432.35342 -313.27221) (xy 432.301077 -313.264378) (xy 432.250471 -313.248885)
			(xy 432.202714 -313.226073) (xy 432.15886 -313.196444) (xy 432.119874 -313.160652) (xy 432.086614 -313.119484)
			(xy 432.072796 -313.09691) (xy 429.743616 -313.09691) (xy 429.429672 -313.410854) (xy 429.420119 -313.420177)
			(xy 429.399376 -313.436978) (xy 429.38827 -313.444382) (xy 429.365156 -313.459622) (xy 429.365156 -321.272408)
			(xy 429.381412 -321.287394) (xy 429.694848 -321.60083) (xy 452.871078 -321.60083) (xy 452.896039 -321.601391)
			(xy 452.945003 -321.611123) (xy 452.991121 -321.630236) (xy 453.032615 -321.657993) (xy 453.050656 -321.675252)
			(xy 453.383396 -322.007992) (xy 453.400626 -322.026054) (xy 453.428358 -322.067552) (xy 453.447462 -322.113663)
			(xy 453.457204 -322.162614) (xy 453.457818 -322.18757) (xy 453.457818 -327.949814) (xy 454.394316 -328.886312)
			(xy 454.411559 -328.904363) (xy 454.439288 -328.945865) (xy 454.458388 -328.991979) (xy 454.468126 -329.040933)
			(xy 454.468738 -329.06589) (xy 454.468738 -334.6069) (xy 454.4682 -334.631862) (xy 454.458462 -334.680828)
			(xy 454.439343 -334.726946) (xy 454.411579 -334.768438) (xy 454.394316 -334.786478) (xy 453.787002 -335.393792)
			(xy 453.768942 -335.411025) (xy 453.727443 -335.438756) (xy 453.681332 -335.457859) (xy 453.63238 -335.4676)
			(xy 453.607424 -335.468214) (xy 453.593529 -335.468021) (xy 453.565907 -335.464966) (xy 453.552306 -335.462118)
			(xy 453.54042 -335.464258) (xy 453.516376 -335.466547) (xy 453.5043 -335.46669) (xy 446.087754 -335.46669)
			(xy 445.639698 -335.914746) (xy 445.639698 -357.95585) (xy 445.63914 -357.980812) (xy 445.629411 -358.029777)
			(xy 445.610297 -358.075895) (xy 445.582537 -358.117388) (xy 445.565276 -358.135428) (xy 440.927236 -362.773468)
			(xy 440.909158 -362.790681) (xy 440.867666 -362.818417) (xy 440.82156 -362.837526) (xy 440.772612 -362.847273)
			(xy 440.747658 -362.84789) (xy 432.078384 -362.84789) (xy 432.070002 -362.888276) (xy 432.063889 -362.914976)
			(xy 432.04504 -362.966403) (xy 432.019032 -363.014608) (xy 431.986399 -363.058598) (xy 431.947811 -363.097471)
			(xy 431.904062 -363.130427) (xy 431.856051 -363.156789) (xy 431.804764 -363.176016) (xy 431.751254 -363.187713)
			(xy 431.696622 -363.191639) (xy 431.64199 -363.187713) (xy 431.58848 -363.176016) (xy 431.537193 -363.156789)
			(xy 431.489182 -363.130427) (xy 431.445433 -363.097471) (xy 431.406845 -363.058598) (xy 431.374212 -363.014608)
			(xy 431.348204 -362.966403) (xy 431.329355 -362.914976) (xy 431.323242 -362.888276) (xy 431.31486 -362.84789)
			(xy 425.9072 -362.84789) (xy 425.892484 -362.870357) (xy 425.857634 -362.911223) (xy 425.817277 -362.946659)
			(xy 425.772248 -362.975932) (xy 425.723482 -362.998434) (xy 425.67199 -363.0137) (xy 425.61884 -363.021411)
			(xy 425.591986 -363.02188) (xy 425.565565 -363.021411) (xy 425.513251 -363.013961) (xy 425.462513 -362.999198)
			(xy 425.414368 -362.977417) (xy 425.369782 -362.949055) (xy 425.349416 -362.932218) (xy 425.338146 -362.923235)
			(xy 425.311895 -362.911369) (xy 425.283376 -362.907306) (xy 425.254857 -362.911369) (xy 425.228606 -362.923235)
			(xy 425.217336 -362.932218) (xy 425.196947 -362.949027) (xy 425.152365 -362.977389) (xy 425.104226 -362.999175)
			(xy 425.053495 -363.01395) (xy 425.001186 -363.021416) (xy 424.974766 -363.02188) (xy 424.947827 -363.02143)
			(xy 424.894512 -363.013657) (xy 424.842874 -362.998277) (xy 424.793994 -362.975614) (xy 424.748892 -362.946139)
			(xy 424.728386 -362.928662) (xy 424.717008 -362.919272) (xy 424.690256 -362.906869) (xy 424.661076 -362.902617)
			(xy 424.631896 -362.906869) (xy 424.605144 -362.919272) (xy 424.593766 -362.928662) (xy 424.573226 -362.946093)
			(xy 424.528118 -362.975538) (xy 424.479244 -362.998189) (xy 424.42762 -363.013576) (xy 424.37432 -363.021379)
			(xy 424.347386 -363.02188) (xy 424.320535 -363.021382) (xy 424.26739 -363.013659) (xy 424.215904 -362.99839)
			(xy 424.167142 -362.975891) (xy 424.122113 -362.946626) (xy 424.08175 -362.911203) (xy 424.046888 -362.870354)
			(xy 424.032172 -362.84789) (xy 416.218878 -362.84789) (xy 416.204176 -362.870367) (xy 416.169324 -362.911233)
			(xy 416.128964 -362.946668) (xy 416.083934 -362.97594) (xy 416.035165 -362.998441) (xy 415.983671 -363.013704)
			(xy 415.930518 -363.021413) (xy 415.903664 -363.02188) (xy 415.877242 -363.021424) (xy 415.824928 -363.013971)
			(xy 415.77419 -362.999204) (xy 415.726045 -362.977421) (xy 415.68146 -362.949056) (xy 415.661094 -362.932218)
			(xy 415.649824 -362.923235) (xy 415.623573 -362.911369) (xy 415.595054 -362.907306) (xy 415.566535 -362.911369)
			(xy 415.540284 -362.923235) (xy 415.529014 -362.932218) (xy 415.508633 -362.949037) (xy 415.464049 -362.977398)
			(xy 415.415908 -362.999182) (xy 415.365175 -363.013954) (xy 415.312864 -363.021418) (xy 415.286444 -363.02188)
			(xy 415.259506 -363.021383) (xy 415.206193 -363.013621) (xy 415.154557 -362.998253) (xy 415.105676 -362.975599)
			(xy 415.060572 -362.946135) (xy 415.040064 -362.928662) (xy 415.028686 -362.919272) (xy 415.001934 -362.906869)
			(xy 414.972754 -362.902617) (xy 414.943574 -362.906869) (xy 414.916822 -362.919272) (xy 414.905444 -362.928662)
			(xy 414.884913 -362.946103) (xy 414.839802 -362.975547) (xy 414.790926 -362.998196) (xy 414.7393 -363.013581)
			(xy 414.685998 -363.02138) (xy 414.659064 -363.02188) (xy 414.632212 -363.021399) (xy 414.579067 -363.013673)
			(xy 414.52758 -362.998401) (xy 414.478818 -362.975899) (xy 414.43379 -362.946632) (xy 414.393427 -362.911206)
			(xy 414.358566 -362.870355) (xy 414.34385 -362.84789) (xy 384.424936 -362.84789) (xy 384.411304 -362.871037)
			(xy 384.37854 -362.913609) (xy 384.340129 -362.951163) (xy 384.29683 -362.982957) (xy 384.249498 -363.008363)
			(xy 384.19907 -363.026877) (xy 384.146544 -363.038135) (xy 384.092958 -363.041912) (xy 384.039372 -363.038135)
			(xy 383.986846 -363.026877) (xy 383.936418 -363.008363) (xy 383.889086 -362.982957) (xy 383.845787 -362.951163)
			(xy 383.807376 -362.913609) (xy 383.774612 -362.871037) (xy 383.76098 -362.84789) (xy 363.960918 -362.84789)
			(xy 363.944194 -362.869314) (xy 363.905683 -362.907663) (xy 363.862118 -362.940158) (xy 363.814383 -362.96614)
			(xy 363.763442 -362.985084) (xy 363.710329 -362.996606) (xy 363.656118 -363.000473) (xy 363.601907 -362.996606)
			(xy 363.548794 -362.985084) (xy 363.497853 -362.96614) (xy 363.450118 -362.940158) (xy 363.406553 -362.907663)
			(xy 363.368042 -362.869314) (xy 363.351318 -362.84789) (xy 354.349812 -362.84789) (xy 354.324851 -362.847329)
			(xy 354.275887 -362.837596) (xy 354.22977 -362.818483) (xy 354.188276 -362.790727) (xy 354.170234 -362.773468)
			(xy 354.105718 -362.708952) (xy 354.077524 -362.716064) (xy 354.054059 -362.721755) (xy 354.006162 -362.727868)
			(xy 353.98202 -362.728256) (xy 353.954771 -362.727703) (xy 353.900829 -362.719951) (xy 353.848538 -362.704601)
			(xy 353.798964 -362.681965) (xy 353.753116 -362.652506) (xy 353.711927 -362.616821) (xy 353.676235 -362.575638)
			(xy 353.646767 -362.529795) (xy 353.624123 -362.480226) (xy 353.608764 -362.427938) (xy 353.601002 -362.373996)
			(xy 353.600512 -362.346748) (xy 353.600881 -362.322605) (xy 353.607 -362.274707) (xy 353.612704 -362.251244)
			(xy 353.619816 -362.22305) (xy 353.340416 -361.94365) (xy 353.320832 -361.960695) (xy 353.277631 -361.989491)
			(xy 353.230684 -362.011659) (xy 353.181 -362.026722) (xy 353.129646 -362.034357) (xy 353.103688 -362.034836)
			(xy 353.10318 -362.034836) (xy 353.075392 -362.03437) (xy 353.020501 -362.025672) (xy 352.967646 -362.008495)
			(xy 352.91813 -361.983261) (xy 352.87317 -361.950591) (xy 352.833875 -361.91129) (xy 352.801212 -361.866326)
			(xy 352.775985 -361.816805) (xy 352.758815 -361.763948) (xy 352.750126 -361.709056) (xy 352.749612 -361.681268)
			(xy 352.749612 -361.68076) (xy 352.750109 -361.654802) (xy 352.757737 -361.603447) (xy 352.772792 -361.553761)
			(xy 352.794952 -361.50681) (xy 352.823739 -361.463604) (xy 352.840798 -361.444032) (xy 347.442536 -356.04577)
			(xy 337.985354 -356.04577) (xy 331.4065 -362.624624) (xy 331.388456 -362.641878) (xy 331.346955 -362.669618)
			(xy 331.300839 -362.688728) (xy 331.251881 -362.698472) (xy 331.226922 -362.699046) (xy 300.905926 -362.699046)
			(xy 300.885271 -362.717071) (xy 300.839665 -362.747489) (xy 300.790093 -362.770895) (xy 300.737628 -362.786786)
			(xy 300.6834 -362.794818) (xy 300.62858 -362.794818) (xy 300.574352 -362.786786) (xy 300.521887 -362.770895)
			(xy 300.472315 -362.747489) (xy 300.426709 -362.717071) (xy 300.406054 -362.699046) (xy 298.734226 -362.699046)
			(xy 298.713968 -362.715609) (xy 298.669686 -362.743487) (xy 298.621937 -362.76489) (xy 298.571662 -362.779398)
			(xy 298.519851 -362.786724) (xy 298.467525 -362.786724) (xy 298.415714 -362.779398) (xy 298.365439 -362.76489)
			(xy 298.31769 -362.743487) (xy 298.273408 -362.715609) (xy 298.25315 -362.699046) (xy 298.073826 -362.699046)
			(xy 298.053568 -362.715609) (xy 298.009286 -362.743487) (xy 297.961537 -362.76489) (xy 297.911262 -362.779398)
			(xy 297.859451 -362.786724) (xy 297.807125 -362.786724) (xy 297.755314 -362.779398) (xy 297.705039 -362.76489)
			(xy 297.65729 -362.743487) (xy 297.613008 -362.715609) (xy 297.59275 -362.699046) (xy 291.217604 -362.699046)
			(xy 291.196949 -362.717071) (xy 291.151343 -362.747489) (xy 291.101771 -362.770895) (xy 291.049306 -362.786786)
			(xy 290.995078 -362.794818) (xy 290.940258 -362.794818) (xy 290.88603 -362.786786) (xy 290.833565 -362.770895)
			(xy 290.783993 -362.747489) (xy 290.738387 -362.717071) (xy 290.717732 -362.699046) (xy 289.045904 -362.699046)
			(xy 289.025646 -362.715609) (xy 288.981364 -362.743487) (xy 288.933615 -362.76489) (xy 288.88334 -362.779398)
			(xy 288.831529 -362.786724) (xy 288.779203 -362.786724) (xy 288.727392 -362.779398) (xy 288.677117 -362.76489)
			(xy 288.629368 -362.743487) (xy 288.585086 -362.715609) (xy 288.564828 -362.699046) (xy 288.385504 -362.699046)
			(xy 288.365246 -362.715609) (xy 288.320964 -362.743487) (xy 288.273215 -362.76489) (xy 288.22294 -362.779398)
			(xy 288.171129 -362.786724) (xy 288.118803 -362.786724) (xy 288.066992 -362.779398) (xy 288.016717 -362.76489)
			(xy 287.968968 -362.743487) (xy 287.924686 -362.715609) (xy 287.904428 -362.699046) (xy 263.027922 -362.699046)
			(xy 262.990134 -362.793343) (xy 262.908311 -362.97931) (xy 262.819383 -363.161986) (xy 262.723482 -363.3411)
			(xy 262.620751 -363.516385) (xy 262.511341 -363.687582) (xy 262.395416 -363.854435) (xy 262.273148 -364.016698)
			(xy 262.144717 -364.174128) (xy 262.010316 -364.326493) (xy 261.870144 -364.473565) (xy 261.724408 -364.615127)
			(xy 261.573326 -364.750969) (xy 261.417121 -364.880887) (xy 261.256026 -365.00469) (xy 261.090281 -365.122194)
			(xy 260.92013 -365.233223) (xy 260.745828 -365.337614) (xy 260.567633 -365.43521) (xy 260.385809 -365.525868)
			(xy 260.200627 -365.609452) (xy 260.012361 -365.685838) (xy 259.821292 -365.754913) (xy 259.627704 -365.816574)
			(xy 259.431883 -365.870729) (xy 259.23412 -365.917299) (xy 259.03471 -365.956213) (xy 258.833949 -365.987415)
			(xy 258.632134 -366.010858) (xy 258.429566 -366.026506) (xy 258.226546 -366.034337) (xy 258.12496 -366.034828)
			(xy 258.021461 -366.034339) (xy 257.814622 -366.026211) (xy 257.608261 -366.009968) (xy 257.402697 -365.985637)
			(xy 257.198247 -365.953254) (xy 256.995226 -365.912869) (xy 256.793947 -365.864545) (xy 256.594721 -365.808356)
			(xy 256.397853 -365.744389) (xy 256.203649 -365.672742) (xy 256.012408 -365.593526) (xy 255.824424 -365.506864)
			(xy 255.639987 -365.412887) (xy 255.459382 -365.311743) (xy 255.282887 -365.203585) (xy 255.110774 -365.088583)
			(xy 254.943309 -364.966911) (xy 254.78075 -364.838759) (xy 254.623347 -364.704324) (xy 254.471343 -364.563813)
			(xy 254.324973 -364.417442) (xy 254.184463 -364.265438) (xy 254.050028 -364.108035) (xy 253.921877 -363.945475)
			(xy 253.800206 -363.77801) (xy 253.685204 -363.605896) (xy 253.577047 -363.429401) (xy 253.475903 -363.248795)
			(xy 253.381928 -363.064358) (xy 253.295266 -362.876374) (xy 253.21605 -362.685132) (xy 253.144404 -362.490928)
			(xy 253.080438 -362.29406) (xy 253.02425 -362.094833) (xy 252.975926 -361.893554) (xy 252.935543 -361.690533)
			(xy 252.90316 -361.486083) (xy 252.87883 -361.280519) (xy 252.862588 -361.074158) (xy 252.854461 -360.867319)
			(xy 252.853952 -360.76382) (xy 218.945968 -360.76382) (xy 218.945526 -360.86732) (xy 218.937398 -361.074161)
			(xy 218.921156 -361.280523) (xy 218.896825 -361.486088) (xy 218.864443 -361.690539) (xy 218.824058 -361.893562)
			(xy 218.775734 -362.094843) (xy 218.719545 -362.294071) (xy 218.655577 -362.490939) (xy 218.58393 -362.685145)
			(xy 218.504714 -362.876388) (xy 218.41805 -363.064373) (xy 218.324073 -363.248811) (xy 218.222927 -363.429417)
			(xy 218.114769 -363.605914) (xy 217.999765 -363.778027) (xy 217.878093 -363.945493) (xy 217.749939 -364.108053)
			(xy 217.615502 -364.265457) (xy 217.47499 -364.417461) (xy 217.328618 -364.563831) (xy 217.176612 -364.704342)
			(xy 217.019207 -364.838777) (xy 216.856645 -364.966929) (xy 216.689178 -365.0886) (xy 216.517063 -365.203602)
			(xy 216.340566 -365.311758) (xy 216.159958 -365.412901) (xy 215.975519 -365.506876) (xy 215.787533 -365.593538)
			(xy 215.596289 -365.672752) (xy 215.402083 -365.744397) (xy 215.205213 -365.808362) (xy 215.005985 -365.864549)
			(xy 214.804703 -365.912871) (xy 214.60168 -365.953253) (xy 214.397228 -365.985634) (xy 214.191663 -366.009962)
			(xy 213.985301 -366.026202) (xy 213.77846 -366.034327) (xy 213.67496 -366.034828) (xy 213.572213 -366.034308)
			(xy 213.366875 -366.026305) (xy 213.162006 -366.010305) (xy 212.957915 -365.986333) (xy 212.754914 -365.954424)
			(xy 212.553311 -365.914627) (xy 212.353412 -365.867003) (xy 212.155521 -365.811624) (xy 211.959939 -365.748574)
			(xy 211.766963 -365.67795) (xy 211.576886 -365.599857) (xy 211.389997 -365.514416) (xy 211.20658 -365.421755)
			(xy 211.026915 -365.322017) (xy 210.851273 -365.215351) (xy 210.679921 -365.101921) (xy 210.513121 -364.981899)
			(xy 210.351126 -364.855467) (xy 210.194181 -364.722816) (xy 210.042526 -364.58415) (xy 209.896391 -364.439679)
			(xy 209.755997 -364.289621) (xy 209.621559 -364.134206) (xy 209.49328 -363.973669) (xy 209.371355 -363.808254)
			(xy 209.255971 -363.638213) (xy 209.147301 -363.463803) (xy 209.045512 -363.285291) (xy 208.950757 -363.102948)
			(xy 208.863181 -362.91705) (xy 208.782918 -362.727879) (xy 208.710088 -362.535725) (xy 208.644803 -362.340877)
			(xy 208.587162 -362.143633) (xy 208.537252 -361.944293) (xy 208.515712 -361.843828) (xy 176.508918 -361.843828)
			(xy 176.486234 -361.857232) (xy 176.43799 -361.878409) (xy 176.387295 -361.892762) (xy 176.33511 -361.900018)
			(xy 176.308766 -361.90047) (xy 176.282418 -361.900047) (xy 176.23022 -361.892829) (xy 176.179516 -361.878481)
			(xy 176.131276 -361.857276) (xy 176.108614 -361.843828) (xy 175.746918 -361.843828) (xy 175.724234 -361.857232)
			(xy 175.67599 -361.878409) (xy 175.625295 -361.892762) (xy 175.57311 -361.900018) (xy 175.546766 -361.90047)
			(xy 175.520418 -361.900047) (xy 175.46822 -361.892829) (xy 175.417516 -361.878481) (xy 175.369276 -361.857276)
			(xy 175.346614 -361.843828) (xy 166.595298 -361.843828) (xy 166.582598 -361.87634) (xy 166.572535 -361.900878)
			(xy 166.546125 -361.946871) (xy 166.513142 -361.988402) (xy 166.474326 -362.024541) (xy 166.430546 -362.054476)
			(xy 166.382786 -362.077536) (xy 166.332118 -362.093202) (xy 166.279678 -362.101124) (xy 166.226642 -362.101124)
			(xy 166.174202 -362.093202) (xy 166.123534 -362.077536) (xy 166.075774 -362.054476) (xy 166.031994 -362.024541)
			(xy 165.993178 -361.988402) (xy 165.960195 -361.946871) (xy 165.933785 -361.900878) (xy 165.923722 -361.87634)
			(xy 165.911022 -361.843828) (xy 146.694652 -361.843828) (xy 146.681165 -361.867504) (xy 146.648505 -361.911118)
			(xy 146.609971 -361.949641) (xy 146.566348 -361.982289) (xy 146.518524 -362.008397) (xy 146.467471 -362.027435)
			(xy 146.414228 -362.039016) (xy 146.35988 -362.042902) (xy 146.305532 -362.039016) (xy 146.252289 -362.027435)
			(xy 146.201236 -362.008397) (xy 146.153412 -361.982289) (xy 146.109789 -361.949641) (xy 146.071255 -361.911118)
			(xy 146.038595 -361.867504) (xy 146.025108 -361.843828) (xy 145.574766 -361.843828) (xy 145.5674 -361.885992)
			(xy 145.562114 -361.91361) (xy 145.544501 -361.96701) (xy 145.519241 -362.017247) (xy 145.48688 -362.063231)
			(xy 145.448119 -362.103968) (xy 145.403799 -362.138573) (xy 145.35488 -362.166298) (xy 145.30242 -362.186543)
			(xy 145.247557 -362.198867) (xy 145.19148 -362.203005) (xy 145.135403 -362.198867) (xy 145.08054 -362.186543)
			(xy 145.02808 -362.166298) (xy 144.979161 -362.138573) (xy 144.934841 -362.103968) (xy 144.89608 -362.063231)
			(xy 144.863719 -362.017247) (xy 144.838459 -361.96701) (xy 144.820846 -361.91361) (xy 144.81556 -361.885992)
			(xy 144.808194 -361.843828) (xy 132.81914 -361.843828) (xy 132.794179 -361.843268) (xy 132.745214 -361.833537)
			(xy 132.699096 -361.814424) (xy 132.657603 -361.786666) (xy 132.639562 -361.769406) (xy 129.346198 -358.476042)
			(xy 129.318512 -358.482646) (xy 129.296496 -358.487623) (xy 129.251674 -358.492968) (xy 129.229104 -358.493314)
			(xy 129.22885 -358.493314) (xy 129.201599 -358.492798) (xy 129.14765 -358.485048) (xy 129.095353 -358.469699)
			(xy 129.045774 -358.447063) (xy 128.999921 -358.4176) (xy 128.958728 -358.381912) (xy 128.923033 -358.340724)
			(xy 128.893564 -358.294875) (xy 128.870921 -358.245299) (xy 128.855564 -358.193005) (xy 128.847806 -358.139057)
			(xy 128.847342 -358.111806) (xy 128.847342 -358.109012) (xy 128.847038 -358.095624) (xy 128.840262 -358.069723)
			(xy 128.826988 -358.046474) (xy 128.808127 -358.027473) (xy 128.784977 -358.014027) (xy 128.759128 -358.007059)
			(xy 128.745742 -358.00665) (xy 116.089176 -358.00665) (xy 116.077238 -358.04094) (xy 116.067789 -358.067177)
			(xy 116.042312 -358.116783) (xy 116.009881 -358.162149) (xy 115.971189 -358.202307) (xy 115.927059 -358.236401)
			(xy 115.878434 -358.263704) (xy 115.826351 -358.283632) (xy 115.771921 -358.295762) (xy 115.716304 -358.299834)
			(xy 115.660687 -358.295762) (xy 115.606257 -358.283632) (xy 115.554174 -358.263704) (xy 115.505549 -358.236401)
			(xy 115.461419 -358.202307) (xy 115.422727 -358.162149) (xy 115.390296 -358.116783) (xy 115.364819 -358.067177)
			(xy 115.35537 -358.04094) (xy 115.343432 -358.00665) (xy 104.641142 -358.00665) (xy 104.619552 -358.005634)
			(xy 104.598024 -358.017349) (xy 104.552613 -358.035785) (xy 104.505213 -358.048248) (xy 104.456606 -358.054531)
			(xy 104.4321 -358.05491) (xy 104.404849 -358.054422) (xy 104.350901 -358.046666) (xy 104.298607 -358.031311)
			(xy 104.24903 -358.00867) (xy 104.203179 -357.979204) (xy 104.161989 -357.943512) (xy 104.126298 -357.902322)
			(xy 104.096831 -357.856472) (xy 104.07419 -357.806895) (xy 104.058835 -357.754601) (xy 104.051078 -357.700653)
			(xy 104.050592 -357.673402) (xy 104.051047 -357.647611) (xy 104.058053 -357.596508) (xy 104.064562 -357.571548)
			(xy 104.072436 -357.5431) (xy 101.584506 -355.05517) (xy 100.192586 -355.05517) (xy 100.18649 -355.099112)
			(xy 100.182367 -355.126221) (xy 100.167354 -355.178959) (xy 100.144943 -355.229004) (xy 100.115595 -355.275322)
			(xy 100.079916 -355.31696) (xy 100.038641 -355.353058) (xy 99.992622 -355.382873) (xy 99.942806 -355.405789)
			(xy 99.890223 -355.421334) (xy 99.835955 -355.429187) (xy 99.781121 -355.429187) (xy 99.726853 -355.421334)
			(xy 99.67427 -355.405789) (xy 99.624454 -355.382873) (xy 99.578435 -355.353058) (xy 99.53716 -355.31696)
			(xy 99.501481 -355.275322) (xy 99.472133 -355.229004) (xy 99.449722 -355.178959) (xy 99.434709 -355.126221)
			(xy 99.430586 -355.099112) (xy 99.42449 -355.05517) (xy 88.326214 -355.05517) (xy 87.588598 -355.792786)
			(xy 87.588598 -358.41559) (xy 87.588065 -358.440553) (xy 87.578327 -358.489519) (xy 87.559207 -358.535638)
			(xy 87.53144 -358.577129) (xy 87.514176 -358.595168) (xy 86.096856 -360.012488) (xy 86.078772 -360.029694)
			(xy 86.037282 -360.057431) (xy 85.991178 -360.076541) (xy 85.942232 -360.086291) (xy 85.917278 -360.08691)
			(xy 57.254394 -360.08691) (xy 57.241164 -360.111389) (xy 57.208692 -360.156574) (xy 57.170001 -360.196561)
			(xy 57.12591 -360.230504) (xy 57.077356 -360.25768) (xy 57.025369 -360.277515) (xy 56.971052 -360.289587)
			(xy 56.915558 -360.293639) (xy 56.860064 -360.289587) (xy 56.805747 -360.277515) (xy 56.75376 -360.25768)
			(xy 56.705206 -360.230504) (xy 56.661115 -360.196561) (xy 56.622424 -360.156574) (xy 56.589952 -360.111389)
			(xy 56.576722 -360.08691) (xy 36.981892 -360.08691) (xy 36.956929 -360.086385) (xy 36.907962 -360.076644)
			(xy 36.861844 -360.057521) (xy 36.820353 -360.029753) (xy 36.802314 -360.012488) (xy 24.88946 -348.099634)
			(xy 24.87222 -348.081578) (xy 24.844477 -348.040081) (xy 24.825364 -347.993969) (xy 24.815615 -347.945014)
			(xy 24.815038 -347.920056) (xy 24.815038 -340.275926) (xy 22.223222 -337.68411) (xy 8.797798 -337.68411)
			(xy 8.772835 -337.683581) (xy 8.723869 -337.673842) (xy 8.67775 -337.65472) (xy 8.636259 -337.626953)
			(xy 8.61822 -337.609688) (xy 6.181852 -335.17332) (xy 6.164604 -335.155271) (xy 6.136863 -335.113771)
			(xy 6.117752 -335.067657) (xy 6.108005 -335.018701) (xy 6.10743 -334.993742) (xy 6.10743 -327.654158)
			(xy 6.107938 -327.63968) (xy 6.107938 -194.806062) (xy 6.082484 -194.793169) (xy 6.035383 -194.760969)
			(xy 5.993599 -194.722117) (xy 5.958064 -194.677478) (xy 5.92957 -194.628047) (xy 5.908751 -194.574926)
			(xy 5.896071 -194.519297) (xy 5.891813 -194.4624) (xy 5.896071 -194.405503) (xy 5.908751 -194.349874)
			(xy 5.92957 -194.296753) (xy 5.958064 -194.247322) (xy 5.993599 -194.202683) (xy 6.035383 -194.163831)
			(xy 6.082484 -194.131631) (xy 6.107938 -194.118738) (xy 6.107938 -189.54623) (xy 6.106922 -189.54115)
			(xy 6.104544 -189.528649) (xy 6.101998 -189.503328) (xy 6.101842 -189.490604) (xy 6.102199 -189.471247)
			(xy 6.108069 -189.43298) (xy 6.113526 -189.414404) (xy 6.11797 -189.395396) (xy 6.13188 -189.358926)
			(xy 6.151198 -189.325008) (xy 6.163056 -189.309502) (xy 6.16585 -189.305692) (xy 6.309106 -189.033658)
			(xy 6.90626 -187.860178) (xy 6.90626 -187.859924) (xy 6.906514 -187.85967) (xy 12.681458 -176.589436)
			(xy 12.681458 -165.383464) (xy 12.680904 -165.368923) (xy 12.672672 -165.341028) (xy 12.656912 -165.316583)
			(xy 12.634903 -165.29757) (xy 12.608429 -165.285529) (xy 12.579634 -165.281436) (xy 12.550852 -165.285623)
			(xy 12.53744 -165.291262) (xy 12.443605 -165.333751) (xy 12.253132 -165.412238) (xy 12.059739 -165.483225)
			(xy 11.86372 -165.546603) (xy 11.665374 -165.602274) (xy 11.465006 -165.650155) (xy 11.262919 -165.690171)
			(xy 11.059424 -165.722263) (xy 10.854831 -165.746381) (xy 10.649451 -165.762487) (xy 10.443599 -165.770558)
			(xy 10.340594 -165.771068) (xy 10.339832 -165.771068) (xy 10.237188 -165.770573) (xy 10.032056 -165.76258)
			(xy 9.82739 -165.746606) (xy 9.623502 -165.722675) (xy 9.4207 -165.690825) (xy 9.219291 -165.651102)
			(xy 9.019583 -165.603567) (xy 8.821876 -165.548293) (xy 8.626471 -165.485363) (xy 8.433665 -165.414872)
			(xy 8.24375 -165.336927) (xy 8.057013 -165.251648) (xy 7.873739 -165.159162) (xy 7.694204 -165.059611)
			(xy 7.518682 -164.953144) (xy 7.347438 -164.839925) (xy 7.180732 -164.720124) (xy 7.018817 -164.593923)
			(xy 6.861939 -164.461513) (xy 6.710335 -164.323096) (xy 6.564235 -164.17888) (xy 6.423861 -164.029086)
			(xy 6.289426 -163.87394) (xy 6.161133 -163.713677) (xy 6.039178 -163.54854) (xy 5.923745 -163.378781)
			(xy 5.815009 -163.204655) (xy 5.713135 -163.026428) (xy 5.618278 -162.84437) (xy 5.530582 -162.658756)
			(xy 5.450178 -162.469868) (xy 5.377191 -162.277994) (xy 5.311729 -162.083423) (xy 5.253892 -161.88645)
			(xy 5.203769 -161.687375) (xy 5.161435 -161.4865) (xy 5.126954 -161.284128) (xy 5.100379 -161.080568)
			(xy 5.081749 -160.876127) (xy 5.071094 -160.671115) (xy 5.068429 -160.465845) (xy 3.523996 -160.465845)
			(xy 3.523996 -347.699838) (xy 5.068068 -347.699838) (xy 5.072082 -347.494154) (xy 5.084118 -347.288784)
			(xy 5.104157 -347.08404) (xy 5.13217 -346.880233) (xy 5.168113 -346.677674) (xy 5.211932 -346.476672)
			(xy 5.263559 -346.277533) (xy 5.322917 -346.08056) (xy 5.389915 -345.886052) (xy 5.464451 -345.694307)
			(xy 5.546411 -345.505616) (xy 5.635671 -345.320266) (xy 5.732094 -345.13854) (xy 5.835535 -344.960714)
			(xy 5.945834 -344.78706) (xy 6.062825 -344.617841) (xy 6.186329 -344.453315) (xy 6.316158 -344.293734)
			(xy 6.452115 -344.139339) (xy 6.593992 -343.990367) (xy 6.741573 -343.847043) (xy 6.894634 -343.709587)
			(xy 7.052941 -343.578207) (xy 7.216254 -343.453104) (xy 7.384323 -343.334467) (xy 7.556893 -343.222479)
			(xy 7.733701 -343.117308) (xy 7.914478 -343.019117) (xy 8.098948 -342.928053) (xy 8.28683 -342.844256)
			(xy 8.47784 -342.767853) (xy 8.671684 -342.69896) (xy 8.868069 -342.637683) (xy 9.066695 -342.584115)
			(xy 9.26726 -342.538338) (xy 9.469458 -342.50042) (xy 9.672982 -342.470421) (xy 9.877521 -342.448384)
			(xy 10.082764 -342.434345) (xy 10.288399 -342.428325) (xy 10.494112 -342.430332) (xy 10.69959 -342.440364)
			(xy 10.90452 -342.458405) (xy 11.10859 -342.484428) (xy 11.31149 -342.518393) (xy 11.51291 -342.560248)
			(xy 11.712543 -342.60993) (xy 11.910086 -342.667364) (xy 12.105238 -342.732461) (xy 12.297702 -342.805122)
			(xy 12.487184 -342.885238) (xy 12.673395 -342.972685) (xy 12.856054 -343.067331) (xy 13.03488 -343.169031)
			(xy 13.209602 -343.277631) (xy 13.379955 -343.392966) (xy 13.545677 -343.514859) (xy 13.706518 -343.643125)
			(xy 13.862231 -343.777568) (xy 14.012581 -343.917985) (xy 14.157338 -344.064161) (xy 14.296281 -344.215873)
			(xy 14.429199 -344.372891) (xy 14.55589 -344.534976) (xy 14.67616 -344.701879) (xy 14.789827 -344.873349)
			(xy 14.896717 -345.049122) (xy 14.996668 -345.228932) (xy 15.089527 -345.412505) (xy 15.175154 -345.599561)
			(xy 15.253416 -345.789816) (xy 15.324197 -345.982979) (xy 15.387387 -346.178757) (xy 15.44289 -346.376851)
			(xy 15.490622 -346.57696) (xy 15.530511 -346.778778) (xy 15.562495 -346.982) (xy 15.586525 -347.186314)
			(xy 15.602566 -347.39141) (xy 15.610592 -347.596977) (xy 15.611094 -347.699838) (xy 15.610592 -347.802699)
			(xy 15.602566 -348.008266) (xy 15.586525 -348.213362) (xy 15.562495 -348.417676) (xy 15.530511 -348.620898)
			(xy 15.490622 -348.822716) (xy 15.44289 -349.022825) (xy 15.387387 -349.220919) (xy 15.324197 -349.416697)
			(xy 15.253416 -349.60986) (xy 15.175154 -349.800115) (xy 15.089527 -349.987171) (xy 14.996668 -350.170744)
			(xy 14.896717 -350.350554) (xy 14.789827 -350.526327) (xy 14.67616 -350.697797) (xy 14.55589 -350.8647)
			(xy 14.429199 -351.026785) (xy 14.296281 -351.183803) (xy 14.157338 -351.335515) (xy 14.012581 -351.481691)
			(xy 13.862231 -351.622108) (xy 13.706518 -351.756551) (xy 13.545677 -351.884817) (xy 13.379955 -352.00671)
			(xy 13.209602 -352.122045) (xy 13.03488 -352.230645) (xy 12.856054 -352.332345) (xy 12.673395 -352.426991)
			(xy 12.487184 -352.514438) (xy 12.297702 -352.594554) (xy 12.105238 -352.667215) (xy 11.910086 -352.732312)
			(xy 11.712543 -352.789746) (xy 11.51291 -352.839428) (xy 11.31149 -352.881283) (xy 11.10859 -352.915248)
			(xy 10.90452 -352.941271) (xy 10.69959 -352.959312) (xy 10.494112 -352.969344) (xy 10.288399 -352.971351)
			(xy 10.082764 -352.965331) (xy 9.877521 -352.951292) (xy 9.672982 -352.929255) (xy 9.469458 -352.899256)
			(xy 9.26726 -352.861338) (xy 9.066695 -352.815561) (xy 8.868069 -352.761993) (xy 8.671684 -352.700716)
			(xy 8.47784 -352.631823) (xy 8.28683 -352.55542) (xy 8.098948 -352.471623) (xy 7.914478 -352.380559)
			(xy 7.733701 -352.282368) (xy 7.556893 -352.177197) (xy 7.384323 -352.065209) (xy 7.216254 -351.946572)
			(xy 7.052941 -351.821469) (xy 6.894634 -351.690089) (xy 6.741573 -351.552633) (xy 6.593992 -351.409309)
			(xy 6.452115 -351.260337) (xy 6.316158 -351.105942) (xy 6.186329 -350.946361) (xy 6.062825 -350.781835)
			(xy 5.945834 -350.612616) (xy 5.835535 -350.438962) (xy 5.732094 -350.261136) (xy 5.635671 -350.07941)
			(xy 5.546411 -349.89406) (xy 5.464451 -349.705369) (xy 5.389915 -349.513624) (xy 5.322917 -349.319116)
			(xy 5.263559 -349.122143) (xy 5.211932 -348.923004) (xy 5.168113 -348.722002) (xy 5.13217 -348.519443)
			(xy 5.104157 -348.315636) (xy 5.084118 -348.110892) (xy 5.072082 -347.905522) (xy 5.068068 -347.699838)
			(xy 3.523996 -347.699838) (xy 3.523996 -360.76382) (xy 4.226823 -360.76382) (xy 4.230819 -360.553934)
			(xy 4.242804 -360.344352) (xy 4.262758 -360.135378) (xy 4.290654 -359.927316) (xy 4.326451 -359.720466)
			(xy 4.370096 -359.515129) (xy 4.421528 -359.311603) (xy 4.48067 -359.110182) (xy 4.547438 -358.911159)
			(xy 4.621734 -358.714822) (xy 4.703452 -358.521456) (xy 4.792471 -358.331341) (xy 4.888664 -358.144753)
			(xy 4.991891 -357.961962) (xy 5.102002 -357.783234) (xy 5.218837 -357.608827) (xy 5.342227 -357.438995)
			(xy 5.471994 -357.273983) (xy 5.607948 -357.114032) (xy 5.749894 -356.959372) (xy 5.897624 -356.810228)
			(xy 6.050926 -356.666817) (xy 6.209576 -356.529346) (xy 6.373345 -356.398014) (xy 6.541995 -356.273013)
			(xy 6.715281 -356.154522) (xy 6.892953 -356.042715) (xy 7.074753 -355.937753) (xy 7.260417 -355.839788)
			(xy 7.449675 -355.748963) (xy 7.642255 -355.665409) (xy 7.837876 -355.589246) (xy 8.036254 -355.520587)
			(xy 8.237103 -355.45953) (xy 8.44013 -355.406163) (xy 8.645043 -355.360565) (xy 8.851542 -355.3228)
			(xy 9.059329 -355.292925) (xy 9.268104 -355.270982) (xy 9.477562 -355.257003) (xy 9.687401 -355.251008)
			(xy 9.897315 -355.253007) (xy 10.107002 -355.262995) (xy 10.316156 -355.28096) (xy 10.524474 -355.306874)
			(xy 10.731655 -355.340699) (xy 10.937399 -355.382388) (xy 11.141405 -355.43188) (xy 11.34338 -355.489102)
			(xy 11.54303 -355.553972) (xy 11.740065 -355.626396) (xy 11.934201 -355.706269) (xy 12.125154 -355.793475)
			(xy 12.31265 -355.887887) (xy 12.496415 -355.989369) (xy 12.676183 -356.097773) (xy 12.851694 -356.212943)
			(xy 13.022693 -356.334711) (xy 13.188933 -356.4629) (xy 13.350172 -356.597326) (xy 13.506176 -356.737793)
			(xy 13.656719 -356.884097) (xy 13.801583 -357.036026) (xy 13.940558 -357.19336) (xy 14.073443 -357.355871)
			(xy 14.200044 -357.523324) (xy 14.320179 -357.695474) (xy 14.433673 -357.872074) (xy 14.540361 -358.052866)
			(xy 14.640088 -358.237589) (xy 14.732711 -358.425975) (xy 14.818095 -358.61775) (xy 14.896116 -358.812637)
			(xy 14.966661 -359.010353) (xy 15.029628 -359.210611) (xy 15.084925 -359.413121) (xy 15.132472 -359.61759)
			(xy 15.1722 -359.823721) (xy 15.204052 -360.031214) (xy 15.227982 -360.23977) (xy 15.243954 -360.449086)
			(xy 15.251946 -360.658858) (xy 15.252446 -360.76382) (xy 15.251946 -360.868782) (xy 15.243954 -361.078554)
			(xy 15.239789 -361.133136) (xy 121.446286 -361.133136) (xy 121.450375 -361.077254) (xy 121.462558 -361.022564)
			(xy 121.482574 -360.97023) (xy 121.509997 -360.921368) (xy 121.544242 -360.87702) (xy 121.584578 -360.83813)
			(xy 121.630148 -360.805528) (xy 121.679979 -360.779909) (xy 121.733009 -360.761817) (xy 121.788107 -360.75164)
			(xy 121.844101 -360.749594) (xy 121.899796 -360.755722) (xy 121.954005 -360.769894) (xy 122.005573 -360.791808)
			(xy 122.053401 -360.820997) (xy 122.096469 -360.856838) (xy 122.133859 -360.898568) (xy 122.164775 -360.945298)
			(xy 122.188558 -360.996031) (xy 122.2047 -361.049687) (xy 122.212859 -361.105121) (xy 122.21337 -361.133136)
			(xy 122.212859 -361.161151) (xy 122.2047 -361.216585) (xy 122.188558 -361.270241) (xy 122.164775 -361.320974)
			(xy 122.133859 -361.367704) (xy 122.096469 -361.409434) (xy 122.053401 -361.445275) (xy 122.005573 -361.474464)
			(xy 121.954005 -361.496378) (xy 121.899796 -361.51055) (xy 121.844101 -361.516678) (xy 121.788107 -361.514632)
			(xy 121.733009 -361.504455) (xy 121.679979 -361.486363) (xy 121.630148 -361.460744) (xy 121.584578 -361.428142)
			(xy 121.544242 -361.389252) (xy 121.509997 -361.344904) (xy 121.482574 -361.296042) (xy 121.462558 -361.243708)
			(xy 121.450375 -361.189018) (xy 121.446286 -361.133136) (xy 15.239789 -361.133136) (xy 15.227982 -361.28787)
			(xy 15.204052 -361.496426) (xy 15.1722 -361.703919) (xy 15.132472 -361.91005) (xy 15.084925 -362.114519)
			(xy 15.029628 -362.317029) (xy 14.966661 -362.517287) (xy 14.896116 -362.715003) (xy 14.818095 -362.90989)
			(xy 14.732711 -363.101665) (xy 14.640088 -363.290051) (xy 14.540361 -363.474774) (xy 14.433673 -363.655566)
			(xy 14.320179 -363.832166) (xy 14.200044 -364.004316) (xy 14.073443 -364.171769) (xy 13.940558 -364.33428)
			(xy 13.801583 -364.491614) (xy 13.656719 -364.643543) (xy 13.506176 -364.789847) (xy 13.350172 -364.930314)
			(xy 13.188933 -365.06474) (xy 13.022693 -365.192929) (xy 12.851694 -365.314697) (xy 12.676183 -365.429867)
			(xy 12.496415 -365.538271) (xy 12.31265 -365.639753) (xy 12.125154 -365.734165) (xy 11.934201 -365.821371)
			(xy 11.740065 -365.901244) (xy 11.54303 -365.973668) (xy 11.34338 -366.038538) (xy 11.141405 -366.09576)
			(xy 10.937399 -366.145252) (xy 10.731655 -366.186941) (xy 10.524474 -366.220766) (xy 10.316156 -366.24668)
			(xy 10.107002 -366.264645) (xy 9.897315 -366.274633) (xy 9.687401 -366.276632) (xy 9.477562 -366.270637)
			(xy 9.268104 -366.256658) (xy 9.059329 -366.234715) (xy 8.851542 -366.20484) (xy 8.645043 -366.167075)
			(xy 8.44013 -366.121477) (xy 8.237103 -366.06811) (xy 8.036254 -366.007053) (xy 7.837876 -365.938394)
			(xy 7.642255 -365.862231) (xy 7.449675 -365.778677) (xy 7.260417 -365.687852) (xy 7.074753 -365.589887)
			(xy 6.892953 -365.484925) (xy 6.715281 -365.373118) (xy 6.541995 -365.254627) (xy 6.373345 -365.129626)
			(xy 6.209576 -364.998294) (xy 6.050926 -364.860823) (xy 5.897624 -364.717412) (xy 5.749894 -364.568268)
			(xy 5.607948 -364.413608) (xy 5.471994 -364.253657) (xy 5.342227 -364.088645) (xy 5.218837 -363.918813)
			(xy 5.102002 -363.744406) (xy 4.991891 -363.565678) (xy 4.888664 -363.382887) (xy 4.792471 -363.196299)
			(xy 4.703452 -363.006184) (xy 4.621734 -362.812818) (xy 4.547438 -362.616481) (xy 4.48067 -362.417458)
			(xy 4.421528 -362.216037) (xy 4.370096 -362.012511) (xy 4.326451 -361.807174) (xy 4.290654 -361.600324)
			(xy 4.262758 -361.392262) (xy 4.242804 -361.183288) (xy 4.230819 -360.973706) (xy 4.226823 -360.76382)
			(xy 3.523996 -360.76382) (xy 3.523996 -383.932484) (xy 8.539215 -383.932484) (xy 8.539215 -383.803344)
			(xy 8.547165 -383.674449) (xy 8.563035 -383.546289) (xy 8.586764 -383.419348) (xy 8.618263 -383.294109)
			(xy 8.657412 -383.171046) (xy 8.704063 -383.050627) (xy 8.758038 -382.933308) (xy 8.819133 -382.819534)
			(xy 8.887116 -382.709737) (xy 8.96173 -382.604334) (xy 9.042691 -382.503724) (xy 9.129691 -382.408289)
			(xy 9.222402 -382.31839) (xy 9.320472 -382.234369) (xy 9.423527 -382.156545) (xy 9.531178 -382.085213)
			(xy 9.643017 -382.020643) (xy 9.758618 -381.963081) (xy 9.877543 -381.912744) (xy 9.999342 -381.869824)
			(xy 10.123552 -381.834483) (xy 10.249701 -381.806856) (xy 10.377313 -381.787047) (xy 10.505902 -381.775131)
			(xy 10.63498 -381.771155) (xy 10.764058 -381.775131) (xy 10.892647 -381.787047) (xy 11.020259 -381.806856)
			(xy 11.146408 -381.834483) (xy 11.270618 -381.869824) (xy 11.392417 -381.912744) (xy 11.511342 -381.963081)
			(xy 11.626943 -382.020643) (xy 11.738782 -382.085213) (xy 11.846433 -382.156545) (xy 11.949488 -382.234369)
			(xy 12.047558 -382.31839) (xy 12.140269 -382.408289) (xy 12.227269 -382.503724) (xy 12.30823 -382.604334)
			(xy 12.382844 -382.709737) (xy 12.450827 -382.819534) (xy 12.505341 -382.921052) (xy 19.016679 -382.921052)
			(xy 19.016679 -382.866548) (xy 19.024437 -382.812598) (xy 19.039793 -382.760301) (xy 19.062436 -382.710722)
			(xy 19.091904 -382.664871) (xy 19.127599 -382.62368) (xy 19.168792 -382.587989) (xy 19.214645 -382.558523)
			(xy 19.264226 -382.535884) (xy 19.316523 -382.520531) (xy 19.370474 -382.512778) (xy 19.397726 -382.512316)
			(xy 20.261326 -382.512316) (xy 20.288578 -382.512756) (xy 20.342526 -382.520516) (xy 20.394821 -382.535874)
			(xy 20.444398 -382.558518) (xy 20.490248 -382.587987) (xy 20.531438 -382.623681) (xy 20.567129 -382.664873)
			(xy 20.596594 -382.710725) (xy 20.619235 -382.760303) (xy 20.63459 -382.812599) (xy 20.642346 -382.866548)
			(xy 20.642346 -382.921052) (xy 20.636681 -382.960459) (xy 22.291788 -382.960459) (xy 22.291788 -382.905921)
			(xy 22.29955 -382.851938) (xy 22.314915 -382.79961) (xy 22.337571 -382.75) (xy 22.367056 -382.70412)
			(xy 22.40277 -382.662903) (xy 22.443987 -382.627188) (xy 22.489867 -382.597702) (xy 22.539476 -382.575046)
			(xy 22.591804 -382.559681) (xy 22.645787 -382.551919) (xy 22.673056 -382.551432) (xy 23.536656 -382.551432)
			(xy 23.563927 -382.551887) (xy 23.617915 -382.559649) (xy 23.670249 -382.575015) (xy 23.719863 -382.597673)
			(xy 23.765748 -382.62716) (xy 23.806969 -382.662878) (xy 23.842687 -382.704099) (xy 23.872175 -382.749983)
			(xy 23.894834 -382.799597) (xy 23.9102 -382.851931) (xy 23.917962 -382.905919) (xy 23.917962 -382.960461)
			(xy 23.9102 -383.014449) (xy 23.894834 -383.066783) (xy 23.872175 -383.116397) (xy 23.842687 -383.162281)
			(xy 23.806969 -383.203502) (xy 23.765748 -383.23922) (xy 23.719863 -383.268707) (xy 23.670249 -383.291365)
			(xy 23.617915 -383.306731) (xy 23.563927 -383.314493) (xy 23.536656 -383.314956) (xy 22.673056 -383.314956)
			(xy 22.645787 -383.314461) (xy 22.591804 -383.306699) (xy 22.539476 -383.291334) (xy 22.489867 -383.268678)
			(xy 22.443987 -383.239192) (xy 22.40277 -383.203477) (xy 22.367056 -383.16226) (xy 22.337571 -383.11638)
			(xy 22.314915 -383.06677) (xy 22.29955 -383.014442) (xy 22.291788 -382.960459) (xy 20.636681 -382.960459)
			(xy 20.63459 -382.975001) (xy 20.619235 -383.027297) (xy 20.596594 -383.076875) (xy 20.567129 -383.122727)
			(xy 20.531438 -383.163919) (xy 20.490248 -383.199613) (xy 20.444398 -383.229082) (xy 20.394821 -383.251726)
			(xy 20.342526 -383.267084) (xy 20.288578 -383.274844) (xy 20.261326 -383.275332) (xy 19.397726 -383.275332)
			(xy 19.370474 -383.274822) (xy 19.316523 -383.267069) (xy 19.264226 -383.251716) (xy 19.214645 -383.229077)
			(xy 19.168792 -383.199611) (xy 19.127599 -383.16392) (xy 19.091904 -383.122729) (xy 19.062436 -383.076878)
			(xy 19.039793 -383.027299) (xy 19.024437 -382.975002) (xy 19.016679 -382.921052) (xy 12.505341 -382.921052)
			(xy 12.511922 -382.933308) (xy 12.565897 -383.050627) (xy 12.612548 -383.171046) (xy 12.651697 -383.294109)
			(xy 12.683196 -383.419348) (xy 12.706925 -383.546289) (xy 12.722795 -383.674449) (xy 12.727298 -383.747461)
			(xy 271.909282 -383.747461) (xy 271.909282 -383.662739) (xy 271.917335 -383.578402) (xy 271.933369 -383.495212)
			(xy 271.957237 -383.413922) (xy 271.988725 -383.33527) (xy 272.027547 -383.259967) (xy 272.07335 -383.188695)
			(xy 272.125721 -383.122099) (xy 272.184186 -383.060784) (xy 272.248214 -383.005303) (xy 272.317226 -382.95616)
			(xy 272.390596 -382.9138) (xy 272.467661 -382.878605) (xy 272.547723 -382.850896) (xy 272.630056 -382.830922)
			(xy 272.713915 -382.818865) (xy 272.79854 -382.814834) (xy 272.883165 -382.818865) (xy 272.967024 -382.830922)
			(xy 273.049357 -382.850896) (xy 273.129419 -382.878605) (xy 273.206484 -382.9138) (xy 273.279854 -382.95616)
			(xy 273.348866 -383.005303) (xy 273.412894 -383.060784) (xy 273.471359 -383.122099) (xy 273.52373 -383.188695)
			(xy 273.569533 -383.259967) (xy 273.608355 -383.33527) (xy 273.639843 -383.413922) (xy 273.663711 -383.495212)
			(xy 273.679745 -383.578402) (xy 273.687798 -383.662739) (xy 273.688302 -383.7051) (xy 273.687798 -383.747461)
			(xy 273.679745 -383.831798) (xy 273.663711 -383.914988) (xy 273.639843 -383.996278) (xy 273.608355 -384.07493)
			(xy 273.569533 -384.150233) (xy 273.52373 -384.221505) (xy 273.471359 -384.288101) (xy 273.412894 -384.349416)
			(xy 273.348866 -384.404897) (xy 273.279854 -384.45404) (xy 273.206484 -384.4964) (xy 273.129419 -384.531595)
			(xy 273.049357 -384.559304) (xy 272.967024 -384.579278) (xy 272.883165 -384.591335) (xy 272.79854 -384.595367)
			(xy 272.713915 -384.591335) (xy 272.630056 -384.579278) (xy 272.547723 -384.559304) (xy 272.467661 -384.531595)
			(xy 272.390596 -384.4964) (xy 272.317226 -384.45404) (xy 272.248214 -384.404897) (xy 272.184186 -384.349416)
			(xy 272.125721 -384.288101) (xy 272.07335 -384.221505) (xy 272.027547 -384.150233) (xy 271.988725 -384.07493)
			(xy 271.957237 -383.996278) (xy 271.933369 -383.914988) (xy 271.917335 -383.831798) (xy 271.909282 -383.747461)
			(xy 12.727298 -383.747461) (xy 12.730745 -383.803344) (xy 12.731242 -383.867914) (xy 12.730745 -383.932484)
			(xy 12.722795 -384.061379) (xy 12.706925 -384.189539) (xy 12.683196 -384.31648) (xy 12.651697 -384.441719)
			(xy 12.612548 -384.564782) (xy 12.565897 -384.685201) (xy 12.511922 -384.80252) (xy 12.450827 -384.916294)
			(xy 12.382844 -385.026091) (xy 12.30823 -385.131494) (xy 12.227269 -385.232104) (xy 12.140269 -385.327539)
			(xy 12.047558 -385.417438) (xy 11.949488 -385.501459) (xy 11.846433 -385.579283) (xy 11.738782 -385.650615)
			(xy 11.626943 -385.715185) (xy 11.511342 -385.772747) (xy 11.483943 -385.784344) (xy 19.460972 -385.784344)
			(xy 19.460972 -384.920744) (xy 19.461458 -384.893493) (xy 19.469214 -384.839545) (xy 19.484569 -384.78725)
			(xy 19.507211 -384.737673) (xy 19.536677 -384.691823) (xy 19.572368 -384.650632) (xy 19.613559 -384.614941)
			(xy 19.659409 -384.585475) (xy 19.708986 -384.562833) (xy 19.761281 -384.547478) (xy 19.815229 -384.539722)
			(xy 19.869731 -384.539722) (xy 19.923679 -384.547478) (xy 19.975974 -384.562833) (xy 20.025551 -384.585475)
			(xy 20.071401 -384.614941) (xy 20.112592 -384.650632) (xy 20.148283 -384.691823) (xy 20.177749 -384.737673)
			(xy 20.200391 -384.78725) (xy 20.215746 -384.839545) (xy 20.223502 -384.893493) (xy 20.223988 -384.920744)
			(xy 20.223988 -385.784344) (xy 20.22353 -385.809998) (xy 22.731984 -385.809998) (xy 22.731984 -384.946398)
			(xy 22.73247 -384.919147) (xy 22.740226 -384.865199) (xy 22.755581 -384.812904) (xy 22.778223 -384.763327)
			(xy 22.807689 -384.717477) (xy 22.84338 -384.676286) (xy 22.884571 -384.640595) (xy 22.930421 -384.611129)
			(xy 22.979998 -384.588487) (xy 23.032293 -384.573132) (xy 23.086241 -384.565376) (xy 23.140743 -384.565376)
			(xy 23.194691 -384.573132) (xy 23.246986 -384.588487) (xy 23.296563 -384.611129) (xy 23.342413 -384.640595)
			(xy 23.383604 -384.676286) (xy 23.419295 -384.717477) (xy 23.448761 -384.763327) (xy 23.471403 -384.812904)
			(xy 23.486758 -384.865199) (xy 23.494514 -384.919147) (xy 23.495 -384.946398) (xy 23.495 -385.440249)
			(xy 36.585674 -385.440249) (xy 36.585674 -385.385751) (xy 36.593429 -385.331807) (xy 36.608782 -385.279515)
			(xy 36.63142 -385.229941) (xy 36.660882 -385.184092) (xy 36.696569 -385.142903) (xy 36.737753 -385.107211)
			(xy 36.783598 -385.077743) (xy 36.83317 -385.055099) (xy 36.88546 -385.039739) (xy 36.939403 -385.031977)
			(xy 36.966652 -385.031488) (xy 37.830252 -385.031488) (xy 37.857507 -385.031956) (xy 37.911462 -385.039707)
			(xy 37.963765 -385.055059) (xy 38.013351 -385.077699) (xy 38.05921 -385.107165) (xy 38.100408 -385.142858)
			(xy 38.136106 -385.184052) (xy 38.165578 -385.229907) (xy 38.188224 -385.27949) (xy 38.203582 -385.331791)
			(xy 38.211341 -385.385745) (xy 38.211341 -385.440255) (xy 38.203582 -385.494209) (xy 38.188224 -385.54651)
			(xy 38.165578 -385.596093) (xy 38.16123 -385.602858) (xy 41.455211 -385.602858) (xy 41.455211 -385.548342)
			(xy 41.46297 -385.494381) (xy 41.47833 -385.442074) (xy 41.500978 -385.392486) (xy 41.530453 -385.346625)
			(xy 41.566155 -385.305427) (xy 41.607357 -385.269729) (xy 41.653221 -385.240259) (xy 41.702812 -385.217616)
			(xy 41.755121 -385.202261) (xy 41.809082 -385.194508) (xy 41.83634 -385.194048) (xy 42.69994 -385.194048)
			(xy 42.727186 -385.194625) (xy 42.781123 -385.202385) (xy 42.833407 -385.217742) (xy 42.882974 -385.240383)
			(xy 42.928814 -385.269847) (xy 42.969994 -385.305534) (xy 43.005677 -385.346718) (xy 43.035136 -385.392562)
			(xy 43.057772 -385.44213) (xy 43.073123 -385.494416) (xy 43.080878 -385.548354) (xy 43.080878 -385.602846)
			(xy 43.073123 -385.656784) (xy 43.057772 -385.70907) (xy 43.035136 -385.758638) (xy 43.005677 -385.804482)
			(xy 42.969994 -385.845666) (xy 42.928814 -385.881353) (xy 42.882974 -385.910817) (xy 42.833407 -385.933458)
			(xy 42.781123 -385.948815) (xy 42.727186 -385.956575) (xy 42.69994 -385.957064) (xy 41.83634 -385.957064)
			(xy 41.809082 -385.956692) (xy 41.755121 -385.948939) (xy 41.702812 -385.933584) (xy 41.653221 -385.910941)
			(xy 41.607357 -385.881471) (xy 41.566155 -385.845773) (xy 41.530453 -385.804575) (xy 41.500978 -385.758714)
			(xy 41.47833 -385.709126) (xy 41.46297 -385.656819) (xy 41.455211 -385.602858) (xy 38.16123 -385.602858)
			(xy 38.136106 -385.641948) (xy 38.100408 -385.683142) (xy 38.05921 -385.718835) (xy 38.013351 -385.748301)
			(xy 37.963765 -385.770941) (xy 37.911462 -385.786293) (xy 37.857507 -385.794044) (xy 37.830252 -385.794504)
			(xy 36.966652 -385.794504) (xy 36.939403 -385.794023) (xy 36.88546 -385.786261) (xy 36.83317 -385.770901)
			(xy 36.783598 -385.748257) (xy 36.737753 -385.718789) (xy 36.696569 -385.683097) (xy 36.660882 -385.641908)
			(xy 36.63142 -385.596059) (xy 36.608782 -385.546485) (xy 36.593429 -385.494193) (xy 36.585674 -385.440249)
			(xy 23.495 -385.440249) (xy 23.495 -385.809998) (xy 23.494514 -385.837249) (xy 23.486758 -385.891197)
			(xy 23.471403 -385.943492) (xy 23.448761 -385.993069) (xy 23.419295 -386.038919) (xy 23.383604 -386.08011)
			(xy 23.342413 -386.115801) (xy 23.297425 -386.144713) (xy 269.99209 -386.144713) (xy 269.99209 -386.059991)
			(xy 270.000143 -385.975654) (xy 270.016177 -385.892464) (xy 270.040045 -385.811174) (xy 270.071533 -385.732522)
			(xy 270.110355 -385.657219) (xy 270.156158 -385.585947) (xy 270.208529 -385.519351) (xy 270.266994 -385.458036)
			(xy 270.331022 -385.402555) (xy 270.400034 -385.353412) (xy 270.473404 -385.311052) (xy 270.550469 -385.275857)
			(xy 270.630531 -385.248148) (xy 270.712864 -385.228174) (xy 270.796723 -385.216117) (xy 270.881348 -385.212086)
			(xy 270.965973 -385.216117) (xy 271.049832 -385.228174) (xy 271.132165 -385.248148) (xy 271.212227 -385.275857)
			(xy 271.289292 -385.311052) (xy 271.362662 -385.353412) (xy 271.431674 -385.402555) (xy 271.495702 -385.458036)
			(xy 271.554167 -385.519351) (xy 271.606538 -385.585947) (xy 271.652341 -385.657219) (xy 271.691163 -385.732522)
			(xy 271.722651 -385.811174) (xy 271.746519 -385.892464) (xy 271.762553 -385.975654) (xy 271.770606 -386.059991)
			(xy 271.77111 -386.102352) (xy 271.770606 -386.144713) (xy 271.762553 -386.22905) (xy 271.746519 -386.31224)
			(xy 271.722651 -386.39353) (xy 271.691163 -386.472182) (xy 271.652341 -386.547485) (xy 271.606538 -386.618757)
			(xy 271.554167 -386.685353) (xy 271.495702 -386.746668) (xy 271.431674 -386.802149) (xy 271.362662 -386.851292)
			(xy 271.289292 -386.893652) (xy 271.212227 -386.928847) (xy 271.132165 -386.956556) (xy 271.049832 -386.97653)
			(xy 270.965973 -386.988587) (xy 270.881348 -386.992619) (xy 270.796723 -386.988587) (xy 270.712864 -386.97653)
			(xy 270.630531 -386.956556) (xy 270.550469 -386.928847) (xy 270.473404 -386.893652) (xy 270.400034 -386.851292)
			(xy 270.331022 -386.802149) (xy 270.266994 -386.746668) (xy 270.208529 -386.685353) (xy 270.156158 -386.618757)
			(xy 270.110355 -386.547485) (xy 270.071533 -386.472182) (xy 270.040045 -386.39353) (xy 270.016177 -386.31224)
			(xy 270.000143 -386.22905) (xy 269.99209 -386.144713) (xy 23.297425 -386.144713) (xy 23.296563 -386.145267)
			(xy 23.246986 -386.167909) (xy 23.194691 -386.183264) (xy 23.140743 -386.19102) (xy 23.086241 -386.19102)
			(xy 23.032293 -386.183264) (xy 22.979998 -386.167909) (xy 22.930421 -386.145267) (xy 22.884571 -386.115801)
			(xy 22.84338 -386.08011) (xy 22.807689 -386.038919) (xy 22.778223 -385.993069) (xy 22.755581 -385.943492)
			(xy 22.740226 -385.891197) (xy 22.73247 -385.837249) (xy 22.731984 -385.809998) (xy 20.22353 -385.809998)
			(xy 20.223502 -385.811595) (xy 20.215746 -385.865543) (xy 20.200391 -385.917838) (xy 20.177749 -385.967415)
			(xy 20.148283 -386.013265) (xy 20.112592 -386.054456) (xy 20.071401 -386.090147) (xy 20.025551 -386.119613)
			(xy 19.975974 -386.142255) (xy 19.923679 -386.15761) (xy 19.869731 -386.165366) (xy 19.815229 -386.165366)
			(xy 19.761281 -386.15761) (xy 19.708986 -386.142255) (xy 19.659409 -386.119613) (xy 19.613559 -386.090147)
			(xy 19.572368 -386.054456) (xy 19.536677 -386.013265) (xy 19.507211 -385.967415) (xy 19.484569 -385.917838)
			(xy 19.469214 -385.865543) (xy 19.461458 -385.811595) (xy 19.460972 -385.784344) (xy 11.483943 -385.784344)
			(xy 11.392417 -385.823084) (xy 11.270618 -385.866004) (xy 11.146408 -385.901345) (xy 11.020259 -385.928972)
			(xy 10.892647 -385.948781) (xy 10.764058 -385.960697) (xy 10.63498 -385.964674) (xy 10.505902 -385.960697)
			(xy 10.377313 -385.948781) (xy 10.249701 -385.928972) (xy 10.123552 -385.901345) (xy 9.999342 -385.866004)
			(xy 9.877543 -385.823084) (xy 9.758618 -385.772747) (xy 9.643017 -385.715185) (xy 9.531178 -385.650615)
			(xy 9.423527 -385.579283) (xy 9.320472 -385.501459) (xy 9.222402 -385.417438) (xy 9.129691 -385.327539)
			(xy 9.042691 -385.232104) (xy 8.96173 -385.131494) (xy 8.887116 -385.026091) (xy 8.819133 -384.916294)
			(xy 8.758038 -384.80252) (xy 8.704063 -384.685201) (xy 8.657412 -384.564782) (xy 8.618263 -384.441719)
			(xy 8.586764 -384.31648) (xy 8.563035 -384.189539) (xy 8.547165 -384.061379) (xy 8.539215 -383.932484)
			(xy 3.523996 -383.932484) (xy 3.523996 -389.402275) (xy 286.566098 -389.402275) (xy 286.566098 -389.317529)
			(xy 286.574154 -389.233168) (xy 286.590192 -389.149954) (xy 286.614067 -389.068641) (xy 286.645564 -388.989966)
			(xy 286.684397 -388.914642) (xy 286.730213 -388.843349) (xy 286.7826 -388.776735) (xy 286.84108 -388.715402)
			(xy 286.905127 -388.659906) (xy 286.974158 -388.610748) (xy 287.04755 -388.568376) (xy 287.124637 -388.533171)
			(xy 287.204721 -388.505454) (xy 287.287078 -388.485474) (xy 287.370961 -388.473414) (xy 287.45561 -388.469382)
			(xy 287.540259 -388.473414) (xy 287.624142 -388.485474) (xy 287.706499 -388.505454) (xy 287.786583 -388.533171)
			(xy 287.86367 -388.568376) (xy 287.937062 -388.610748) (xy 288.006093 -388.659906) (xy 288.07014 -388.715402)
			(xy 288.12862 -388.776735) (xy 288.181007 -388.843349) (xy 288.226823 -388.914642) (xy 288.265656 -388.989966)
			(xy 288.297153 -389.068641) (xy 288.321028 -389.149954) (xy 288.337066 -389.233168) (xy 288.345122 -389.317529)
			(xy 288.345626 -389.359902) (xy 288.345122 -389.402275) (xy 297.615098 -389.402275) (xy 297.615098 -389.317529)
			(xy 297.623154 -389.233168) (xy 297.639192 -389.149954) (xy 297.663067 -389.068641) (xy 297.694564 -388.989966)
			(xy 297.733397 -388.914642) (xy 297.779213 -388.843349) (xy 297.8316 -388.776735) (xy 297.89008 -388.715402)
			(xy 297.954127 -388.659906) (xy 298.023158 -388.610748) (xy 298.09655 -388.568376) (xy 298.173637 -388.533171)
			(xy 298.253721 -388.505454) (xy 298.336078 -388.485474) (xy 298.419961 -388.473414) (xy 298.50461 -388.469382)
			(xy 298.589259 -388.473414) (xy 298.673142 -388.485474) (xy 298.755499 -388.505454) (xy 298.835583 -388.533171)
			(xy 298.91267 -388.568376) (xy 298.986062 -388.610748) (xy 299.055093 -388.659906) (xy 299.11914 -388.715402)
			(xy 299.17762 -388.776735) (xy 299.230007 -388.843349) (xy 299.275823 -388.914642) (xy 299.314656 -388.989966)
			(xy 299.346153 -389.068641) (xy 299.370028 -389.149954) (xy 299.386066 -389.233168) (xy 299.394122 -389.317529)
			(xy 299.394626 -389.359902) (xy 299.394122 -389.402275) (xy 299.386066 -389.486636) (xy 299.370028 -389.56985)
			(xy 299.346153 -389.651163) (xy 299.314656 -389.729838) (xy 299.275823 -389.805162) (xy 299.230007 -389.876455)
			(xy 299.17762 -389.943069) (xy 299.11914 -390.004402) (xy 299.055093 -390.059898) (xy 298.986062 -390.109056)
			(xy 298.91267 -390.151428) (xy 298.835583 -390.186633) (xy 298.755499 -390.21435) (xy 298.673142 -390.23433)
			(xy 298.589259 -390.24639) (xy 298.50461 -390.250423) (xy 298.419961 -390.24639) (xy 298.336078 -390.23433)
			(xy 298.253721 -390.21435) (xy 298.173637 -390.186633) (xy 298.09655 -390.151428) (xy 298.023158 -390.109056)
			(xy 297.954127 -390.059898) (xy 297.89008 -390.004402) (xy 297.8316 -389.943069) (xy 297.779213 -389.876455)
			(xy 297.733397 -389.805162) (xy 297.694564 -389.729838) (xy 297.663067 -389.651163) (xy 297.639192 -389.56985)
			(xy 297.623154 -389.486636) (xy 297.615098 -389.402275) (xy 288.345122 -389.402275) (xy 288.337066 -389.486636)
			(xy 288.321028 -389.56985) (xy 288.297153 -389.651163) (xy 288.265656 -389.729838) (xy 288.226823 -389.805162)
			(xy 288.181007 -389.876455) (xy 288.12862 -389.943069) (xy 288.07014 -390.004402) (xy 288.006093 -390.059898)
			(xy 287.937062 -390.109056) (xy 287.86367 -390.151428) (xy 287.786583 -390.186633) (xy 287.706499 -390.21435)
			(xy 287.624142 -390.23433) (xy 287.540259 -390.24639) (xy 287.45561 -390.250423) (xy 287.370961 -390.24639)
			(xy 287.287078 -390.23433) (xy 287.204721 -390.21435) (xy 287.124637 -390.186633) (xy 287.04755 -390.151428)
			(xy 286.974158 -390.109056) (xy 286.905127 -390.059898) (xy 286.84108 -390.004402) (xy 286.7826 -389.943069)
			(xy 286.730213 -389.876455) (xy 286.684397 -389.805162) (xy 286.645564 -389.729838) (xy 286.614067 -389.651163)
			(xy 286.590192 -389.56985) (xy 286.574154 -389.486636) (xy 286.566098 -389.402275) (xy 3.523996 -389.402275)
			(xy 3.523996 -390.74852) (xy 289.828732 -390.74852) (xy 289.829157 -390.717787) (xy 289.836564 -390.656768)
			(xy 289.851272 -390.597088) (xy 289.873068 -390.539615) (xy 289.901633 -390.485189) (xy 289.93655 -390.434604)
			(xy 289.97731 -390.388596) (xy 290.023319 -390.347837) (xy 290.073907 -390.312922) (xy 290.128334 -390.28436)
			(xy 290.185807 -390.262566) (xy 290.245488 -390.24786) (xy 290.306507 -390.240455) (xy 290.33724 -390.240012)
			(xy 290.369283 -390.240508) (xy 290.432859 -390.248584) (xy 290.494917 -390.264579) (xy 290.554476 -390.288239)
			(xy 290.610594 -390.31919) (xy 290.662381 -390.356941) (xy 290.709019 -390.400896) (xy 290.749768 -390.450359)
			(xy 290.783985 -390.504546) (xy 290.811128 -390.562601) (xy 290.830767 -390.623604) (xy 290.842591 -390.686591)
			(xy 290.844986 -390.718548) (xy 290.846452 -390.733661) (xy 290.857061 -390.762093) (xy 290.875562 -390.786147)
			(xy 290.900318 -390.803698) (xy 290.929141 -390.813192) (xy 290.9443 -390.814052) (xy 290.977155 -390.815239)
			(xy 291.042167 -390.825028) (xy 291.105376 -390.843112) (xy 291.165728 -390.86919) (xy 291.222216 -390.902827)
			(xy 291.2739 -390.943462) (xy 291.319917 -390.990417) (xy 291.359501 -391.04291) (xy 291.391992 -391.100065)
			(xy 291.416847 -391.160931) (xy 291.433653 -391.224491) (xy 291.442129 -391.289688) (xy 291.442648 -391.32256)
			(xy 291.442106 -391.353289) (xy 291.434703 -391.414298) (xy 291.42 -391.473971) (xy 291.398212 -391.531436)
			(xy 291.369656 -391.585856) (xy 291.334748 -391.636437) (xy 291.293998 -391.682441) (xy 291.248 -391.723199)
			(xy 291.197424 -391.758114) (xy 291.143009 -391.786679) (xy 291.085547 -391.808477) (xy 291.025877 -391.823189)
			(xy 290.964869 -391.830602) (xy 290.93414 -391.831068) (xy 290.902098 -391.830516) (xy 290.838523 -391.822449)
			(xy 290.776465 -391.806463) (xy 290.716905 -391.78281) (xy 290.660787 -391.751866) (xy 290.608999 -391.71412)
			(xy 290.56236 -391.670169) (xy 290.521609 -391.620711) (xy 290.487392 -391.566526) (xy 290.460249 -391.508474)
			(xy 290.440611 -391.447473) (xy 290.428788 -391.384488) (xy 290.426394 -391.352532) (xy 290.424962 -391.337414)
			(xy 290.414346 -391.308979) (xy 290.395837 -391.284924) (xy 290.371072 -391.267376) (xy 290.342242 -391.257886)
			(xy 290.32708 -391.257028) (xy 290.294229 -391.25578) (xy 290.229223 -391.24599) (xy 290.166019 -391.227907)
			(xy 290.105673 -391.201832) (xy 290.049188 -391.1682) (xy 289.997507 -391.127571) (xy 289.95149 -391.080623)
			(xy 289.911906 -391.028137) (xy 289.879413 -390.97099) (xy 289.854553 -390.910132) (xy 289.837741 -390.846579)
			(xy 289.829256 -390.78139) (xy 289.828732 -390.74852) (xy 3.523996 -390.74852) (xy 3.523996 -394.8085)
			(xy 243.179528 -394.8085) (xy 243.183558 -394.723892) (xy 243.195613 -394.640051) (xy 243.215583 -394.557735)
			(xy 243.243287 -394.47769) (xy 243.278475 -394.400641) (xy 243.320827 -394.327286) (xy 243.36996 -394.258289)
			(xy 243.42543 -394.194274) (xy 243.486733 -394.135823) (xy 243.553315 -394.083463) (xy 243.624573 -394.03767)
			(xy 243.699861 -393.998857) (xy 243.778498 -393.967377) (xy 243.859771 -393.943515) (xy 243.942944 -393.927486)
			(xy 244.027264 -393.919435) (xy 244.069616 -393.918948) (xy 244.11084 -393.919417) (xy 244.192933 -393.927053)
			(xy 244.273968 -393.94225) (xy 244.35325 -393.964876) (xy 244.430099 -393.994739) (xy 244.503857 -394.031582)
			(xy 244.573891 -394.075088) (xy 244.639601 -394.124886) (xy 244.670326 -394.152374) (xy 244.677558 -394.158461)
			(xy 244.695171 -394.165287) (xy 244.714061 -394.165287) (xy 244.731674 -394.158461) (xy 244.738906 -394.152374)
			(xy 244.769639 -394.124894) (xy 244.835341 -394.075085) (xy 244.905371 -394.03157) (xy 244.979128 -393.994723)
			(xy 245.055977 -393.964858) (xy 245.13526 -393.942233) (xy 245.216297 -393.927041) (xy 245.298392 -393.919413)
			(xy 245.339616 -393.918948) (xy 245.381408 -393.919476) (xy 245.464624 -393.927312) (xy 245.546738 -393.942923)
			(xy 245.627024 -393.96617) (xy 245.704775 -393.996849) (xy 245.779303 -394.034689) (xy 245.849951 -394.079356)
			(xy 245.916096 -394.130456) (xy 245.977154 -394.187537) (xy 246.032585 -394.250097) (xy 246.081902 -394.317582)
			(xy 246.124667 -394.389397) (xy 246.143018 -394.426948) (xy 246.170089 -394.428781) (xy 246.223268 -394.43954)
			(xy 246.274197 -394.458246) (xy 246.321697 -394.484466) (xy 246.364667 -394.51759) (xy 246.402111 -394.556853)
			(xy 246.433163 -394.601345) (xy 246.457102 -394.650034) (xy 246.473374 -394.701792) (xy 246.481601 -394.75542)
			(xy 246.482108 -394.782548) (xy 246.481601 -394.8085) (xy 249.114543 -394.8085) (xy 249.118574 -394.723896)
			(xy 249.130628 -394.640058) (xy 249.150596 -394.557746) (xy 249.178298 -394.477704) (xy 249.213483 -394.400658)
			(xy 249.255833 -394.327305) (xy 249.304963 -394.25831) (xy 249.360429 -394.194298) (xy 249.421729 -394.135847)
			(xy 249.488307 -394.083488) (xy 249.55956 -394.037695) (xy 249.634844 -393.998882) (xy 249.713476 -393.967401)
			(xy 249.794745 -393.943537) (xy 249.877914 -393.927506) (xy 249.96223 -393.919453) (xy 250.00458 -393.918948)
			(xy 250.045803 -393.919439) (xy 250.127896 -393.927072) (xy 250.20893 -393.942266) (xy 250.288212 -393.964889)
			(xy 250.365061 -393.994749) (xy 250.438819 -394.031588) (xy 250.508854 -394.075092) (xy 250.574564 -394.124887)
			(xy 250.60529 -394.152374) (xy 250.612522 -394.158461) (xy 250.630135 -394.165287) (xy 250.649025 -394.165287)
			(xy 250.666638 -394.158461) (xy 250.67387 -394.152374) (xy 250.704576 -394.124863) (xy 250.770283 -394.075057)
			(xy 250.840317 -394.031545) (xy 250.914078 -393.994701) (xy 250.990931 -393.96484) (xy 251.070218 -393.942219)
			(xy 251.151257 -393.927032) (xy 251.233355 -393.91941) (xy 251.27458 -393.918948) (xy 251.316356 -393.919458)
			(xy 251.399539 -393.927298) (xy 251.481621 -393.942901) (xy 251.561879 -393.966129) (xy 251.639606 -393.996779)
			(xy 251.714118 -394.03458) (xy 251.784758 -394.079199) (xy 251.850904 -394.130243) (xy 251.911974 -394.187264)
			(xy 251.96743 -394.249758) (xy 252.016784 -394.317175) (xy 252.059601 -394.388922) (xy 252.077982 -394.42644)
			(xy 252.086364 -394.42644) (xy 252.114351 -394.426946) (xy 252.169636 -394.435698) (xy 252.222871 -394.452992)
			(xy 252.272744 -394.478402) (xy 252.318028 -394.511302) (xy 252.357606 -394.550881) (xy 252.390505 -394.596166)
			(xy 252.415913 -394.646041) (xy 252.433205 -394.699276) (xy 252.441955 -394.754561) (xy 252.442472 -394.782548)
			(xy 252.441992 -394.8085) (xy 255.049428 -394.8085) (xy 255.053459 -394.723891) (xy 255.065514 -394.640048)
			(xy 255.085484 -394.55773) (xy 255.11319 -394.477684) (xy 255.148379 -394.400634) (xy 255.190732 -394.327277)
			(xy 255.239868 -394.258279) (xy 255.295339 -394.194265) (xy 255.356645 -394.135813) (xy 255.423229 -394.083453)
			(xy 255.494489 -394.03766) (xy 255.56978 -393.998849) (xy 255.648419 -393.96737) (xy 255.729694 -393.943509)
			(xy 255.812869 -393.927482) (xy 255.897191 -393.919434) (xy 255.939544 -393.918948) (xy 255.980768 -393.919399)
			(xy 256.062862 -393.927038) (xy 256.143897 -393.942237) (xy 256.223179 -393.964866) (xy 256.300029 -393.994731)
			(xy 256.373786 -394.031576) (xy 256.44382 -394.075085) (xy 256.509529 -394.124885) (xy 256.540254 -394.152374)
			(xy 256.547486 -394.158461) (xy 256.565099 -394.165287) (xy 256.583989 -394.165287) (xy 256.601602 -394.158461)
			(xy 256.608834 -394.152374) (xy 256.639555 -394.12488) (xy 256.70526 -394.075073) (xy 256.775292 -394.031559)
			(xy 256.849049 -393.994713) (xy 256.925901 -393.96485) (xy 257.005185 -393.942227) (xy 257.086223 -393.927037)
			(xy 257.168319 -393.919412) (xy 257.209544 -393.918948) (xy 257.251493 -393.919491) (xy 257.335018 -393.927401)
			(xy 257.417428 -393.943137) (xy 257.497991 -393.96656) (xy 257.575991 -393.997462) (xy 257.650737 -394.035568)
			(xy 257.721565 -394.08054) (xy 257.787845 -394.131979) (xy 257.848989 -394.189427) (xy 257.904455 -394.252376)
			(xy 257.95375 -394.320266) (xy 257.996436 -394.392494) (xy 258.014724 -394.43025) (xy 258.027542 -394.428485)
			(xy 258.053348 -394.426578) (xy 258.066286 -394.42644) (xy 258.067048 -394.42644) (xy 258.093699 -394.426845)
			(xy 258.146403 -394.434796) (xy 258.197335 -394.450512) (xy 258.245356 -394.473643) (xy 258.289393 -394.503673)
			(xy 258.328463 -394.539929) (xy 258.361693 -394.581604) (xy 258.388341 -394.627765) (xy 258.407813 -394.677383)
			(xy 258.419673 -394.729348) (xy 258.423656 -394.7825) (xy 258.421708 -394.8085) (xy 260.984428 -394.8085)
			(xy 260.988458 -394.723893) (xy 261.000513 -394.640052) (xy 261.020483 -394.557736) (xy 261.048186 -394.477692)
			(xy 261.083374 -394.400643) (xy 261.125725 -394.327288) (xy 261.174858 -394.258291) (xy 261.230327 -394.194277)
			(xy 261.29163 -394.135826) (xy 261.358212 -394.083466) (xy 261.429469 -394.037672) (xy 261.504756 -393.99886)
			(xy 261.583392 -393.967379) (xy 261.664664 -393.943516) (xy 261.747837 -393.927487) (xy 261.832156 -393.919436)
			(xy 261.874508 -393.918948) (xy 261.915732 -393.919422) (xy 261.997825 -393.927057) (xy 262.078859 -393.942253)
			(xy 262.158141 -393.964879) (xy 262.234991 -393.994741) (xy 262.308749 -394.031583) (xy 262.378783 -394.075089)
			(xy 262.444493 -394.124886) (xy 262.475218 -394.152374) (xy 262.48245 -394.158461) (xy 262.500063 -394.165287)
			(xy 262.518953 -394.165287) (xy 262.536566 -394.158461) (xy 262.543798 -394.152374) (xy 262.574534 -394.124897)
			(xy 262.640236 -394.075089) (xy 262.710266 -394.031574) (xy 262.784021 -393.994725) (xy 262.86087 -393.96486)
			(xy 262.940153 -393.942234) (xy 263.021189 -393.927042) (xy 263.103284 -393.919413) (xy 263.144508 -393.918948)
			(xy 263.18635 -393.919404) (xy 263.269665 -393.927258) (xy 263.351874 -393.942906) (xy 263.432248 -393.966208)
			(xy 263.510078 -393.996959) (xy 263.584674 -394.034887) (xy 263.655376 -394.079656) (xy 263.721559 -394.130869)
			(xy 263.782638 -394.188075) (xy 263.838071 -394.250766) (xy 263.887369 -394.318389) (xy 263.930095 -394.390344)
			(xy 263.948418 -394.427964) (xy 263.981692 -394.42644) (xy 264.008347 -394.426817) (xy 264.061062 -394.434761)
			(xy 264.112004 -394.450474) (xy 264.160035 -394.473603) (xy 264.204083 -394.503633) (xy 264.243162 -394.539893)
			(xy 264.276401 -394.581572) (xy 264.303057 -394.62774) (xy 264.322533 -394.677365) (xy 264.334396 -394.729339)
			(xy 264.33838 -394.7825) (xy 264.336432 -394.8085) (xy 266.919443 -394.8085) (xy 266.923474 -394.723896)
			(xy 266.935527 -394.640059) (xy 266.955496 -394.557747) (xy 266.983198 -394.477706) (xy 267.018382 -394.40066)
			(xy 267.060731 -394.327308) (xy 267.109861 -394.258313) (xy 267.165326 -394.194301) (xy 267.226625 -394.13585)
			(xy 267.293203 -394.083491) (xy 267.364456 -394.037698) (xy 267.439739 -393.998885) (xy 267.51837 -393.967403)
			(xy 267.599638 -393.943538) (xy 267.682807 -393.927507) (xy 267.767122 -393.919453) (xy 267.809472 -393.918948)
			(xy 267.850695 -393.919444) (xy 267.932787 -393.927077) (xy 268.013822 -393.942269) (xy 268.093103 -393.964892)
			(xy 268.169953 -393.994751) (xy 268.243711 -394.03159) (xy 268.313746 -394.075093) (xy 268.379456 -394.124888)
			(xy 268.410182 -394.152374) (xy 268.417414 -394.158461) (xy 268.435027 -394.165287) (xy 268.453917 -394.165287)
			(xy 268.47153 -394.158461) (xy 268.478762 -394.152374) (xy 268.509471 -394.124866) (xy 268.575178 -394.07506)
			(xy 268.645212 -394.031548) (xy 268.718971 -393.994703) (xy 268.795824 -393.964842) (xy 268.87511 -393.942221)
			(xy 268.95615 -393.927033) (xy 269.038247 -393.91941) (xy 269.079472 -393.918948) (xy 269.121265 -393.919428)
			(xy 269.204483 -393.927269) (xy 269.286598 -393.942885) (xy 269.366885 -393.966137) (xy 269.444636 -393.996821)
			(xy 269.519164 -394.034666) (xy 269.589812 -394.079337) (xy 269.655956 -394.130441) (xy 269.717013 -394.187526)
			(xy 269.772444 -394.250089) (xy 269.821759 -394.317577) (xy 269.864524 -394.389396) (xy 269.882874 -394.426948)
			(xy 269.909949 -394.428731) (xy 269.963129 -394.439499) (xy 270.014058 -394.458212) (xy 270.061558 -394.484438)
			(xy 270.104527 -394.517569) (xy 270.141971 -394.556837) (xy 270.173021 -394.601333) (xy 270.19696 -394.650026)
			(xy 270.213231 -394.701787) (xy 270.221458 -394.755419) (xy 270.221964 -394.782548) (xy 270.221496 -394.8085)
			(xy 272.854328 -394.8085) (xy 272.858359 -394.723891) (xy 272.870414 -394.640048) (xy 272.890384 -394.557731)
			(xy 272.918089 -394.477686) (xy 272.953277 -394.400636) (xy 272.995631 -394.32728) (xy 273.044766 -394.258282)
			(xy 273.100237 -394.194267) (xy 273.161542 -394.135816) (xy 273.228125 -394.083456) (xy 273.299385 -394.037663)
			(xy 273.374675 -393.998851) (xy 273.453313 -393.967372) (xy 273.534587 -393.943511) (xy 273.617762 -393.927483)
			(xy 273.702084 -393.919434) (xy 273.744436 -393.918948) (xy 273.78566 -393.919404) (xy 273.867754 -393.927042)
			(xy 273.948789 -393.942241) (xy 274.028071 -393.964869) (xy 274.10492 -393.994734) (xy 274.178678 -394.031578)
			(xy 274.248712 -394.075086) (xy 274.314421 -394.124886) (xy 274.345146 -394.152374) (xy 274.352378 -394.158461)
			(xy 274.369991 -394.165287) (xy 274.388881 -394.165287) (xy 274.406494 -394.158461) (xy 274.413726 -394.152374)
			(xy 274.44445 -394.124884) (xy 274.510154 -394.075076) (xy 274.580186 -394.031562) (xy 274.653943 -393.994716)
			(xy 274.730794 -393.964852) (xy 274.810078 -393.942228) (xy 274.891116 -393.927038) (xy 274.973211 -393.919412)
			(xy 275.014436 -393.918948) (xy 275.056229 -393.919459) (xy 275.139445 -393.927297) (xy 275.221559 -393.942909)
			(xy 275.301846 -393.966158) (xy 275.379596 -393.996839) (xy 275.454125 -394.034681) (xy 275.524773 -394.079349)
			(xy 275.590918 -394.130451) (xy 275.651975 -394.187533) (xy 275.707406 -394.250094) (xy 275.756722 -394.31758)
			(xy 275.799488 -394.389397) (xy 275.817838 -394.426948) (xy 275.844911 -394.428763) (xy 275.898089 -394.439526)
			(xy 275.949019 -394.458234) (xy 275.996518 -394.484456) (xy 276.039488 -394.517583) (xy 276.076932 -394.556848)
			(xy 276.107984 -394.601341) (xy 276.131922 -394.650031) (xy 276.148194 -394.70179) (xy 276.156421 -394.75542)
			(xy 276.156928 -394.782548) (xy 276.156405 -394.808456) (xy 278.916892 -394.808456) (xy 278.917356 -394.766262)
			(xy 278.925335 -394.682252) (xy 278.941234 -394.599376) (xy 278.964912 -394.518378) (xy 278.996156 -394.439987)
			(xy 279.034684 -394.364908) (xy 279.08015 -394.293815) (xy 279.132146 -394.227349) (xy 279.190203 -394.166106)
			(xy 279.2538 -394.110638) (xy 279.322365 -394.061443) (xy 279.395282 -394.018964) (xy 279.471894 -393.983582)
			(xy 279.551513 -393.955615) (xy 279.633423 -393.935316) (xy 279.675082 -393.9286) (xy 279.689459 -393.925944)
			(xy 279.715949 -393.913606) (xy 279.737852 -393.894262) (xy 279.753368 -393.869499) (xy 279.761223 -393.841352)
			(xy 279.760772 -393.812133) (xy 279.75687 -393.798044) (xy 279.744165 -393.755179) (xy 279.726399 -393.667554)
			(xy 279.717507 -393.578589) (xy 279.716992 -393.533884) (xy 279.717496 -393.491536) (xy 279.725547 -393.407222)
			(xy 279.741576 -393.324056) (xy 279.765437 -393.242789) (xy 279.796916 -393.164159) (xy 279.835727 -393.088878)
			(xy 279.881517 -393.017626) (xy 279.933873 -392.95105) (xy 279.992321 -392.889752) (xy 280.056331 -392.834287)
			(xy 280.125323 -392.785158) (xy 280.198673 -392.742809) (xy 280.275716 -392.707625) (xy 280.355755 -392.679923)
			(xy 280.438064 -392.659955) (xy 280.521899 -392.647902) (xy 280.6065 -392.643872) (xy 280.691101 -392.647902)
			(xy 280.774936 -392.659955) (xy 280.857245 -392.679923) (xy 280.937284 -392.707625) (xy 281.014327 -392.742809)
			(xy 281.087677 -392.785158) (xy 281.156669 -392.834287) (xy 281.220679 -392.889752) (xy 281.279127 -392.95105)
			(xy 281.331483 -393.017626) (xy 281.377273 -393.088878) (xy 281.416084 -393.164159) (xy 281.447563 -393.242789)
			(xy 281.471424 -393.324056) (xy 281.487453 -393.407222) (xy 281.495504 -393.491536) (xy 281.496008 -393.533884)
			(xy 281.495487 -393.576077) (xy 281.487514 -393.660085) (xy 281.47162 -393.74296) (xy 281.461756 -393.776708)
			(xy 289.471608 -393.776708) (xy 289.471608 -393.776454) (xy 289.47211 -393.744493) (xy 289.480121 -393.681075)
			(xy 289.496018 -393.619161) (xy 289.51955 -393.559728) (xy 289.550344 -393.503713) (xy 289.587917 -393.451998)
			(xy 289.631674 -393.405401) (xy 289.680927 -393.364656) (xy 289.734898 -393.330405) (xy 289.792737 -393.303188)
			(xy 289.85353 -393.283435) (xy 289.91632 -393.271457) (xy 289.980116 -393.267444) (xy 290.043912 -393.271457)
			(xy 290.106702 -393.283435) (xy 290.167495 -393.303188) (xy 290.225334 -393.330405) (xy 290.279305 -393.364656)
			(xy 290.328558 -393.405401) (xy 290.372315 -393.451998) (xy 290.409888 -393.503713) (xy 290.440682 -393.559728)
			(xy 290.464214 -393.619161) (xy 290.480111 -393.681075) (xy 290.488122 -393.744493) (xy 290.488624 -393.776454)
			(xy 290.488624 -393.7765) (xy 291.470768 -393.7765) (xy 291.474784 -393.712663) (xy 291.48677 -393.649832)
			(xy 291.506536 -393.589) (xy 291.533771 -393.531124) (xy 291.568045 -393.477118) (xy 291.608817 -393.427834)
			(xy 291.655445 -393.384049) (xy 291.707193 -393.346453) (xy 291.763245 -393.315639) (xy 291.822717 -393.292094)
			(xy 291.884671 -393.276188) (xy 291.94813 -393.268172) (xy 291.980112 -393.267692) (xy 292.010658 -393.268138)
			(xy 292.071311 -393.275449) (xy 292.13065 -393.289975) (xy 292.187822 -393.311508) (xy 292.242001 -393.339737)
			(xy 292.292406 -393.374254) (xy 292.338312 -393.414564) (xy 292.379057 -393.460084) (xy 292.396926 -393.484862)
			(xy 292.405296 -393.496027) (xy 292.426903 -393.51367) (xy 292.452477 -393.52481) (xy 292.480111 -393.528618)
			(xy 292.507745 -393.52481) (xy 292.533319 -393.51367) (xy 292.554926 -393.496027) (xy 292.563296 -393.484862)
			(xy 292.582389 -393.458454) (xy 292.626241 -393.410247) (xy 292.675892 -393.368039) (xy 292.730528 -393.332518)
			(xy 292.789254 -393.304269) (xy 292.851108 -393.283754) (xy 292.915076 -393.271309) (xy 292.98011 -393.267138)
			(xy 293.045144 -393.271309) (xy 293.109112 -393.283754) (xy 293.170966 -393.304269) (xy 293.229692 -393.332518)
			(xy 293.284328 -393.368039) (xy 293.333979 -393.410247) (xy 293.377831 -393.458454) (xy 293.396924 -393.484862)
			(xy 293.405294 -393.496027) (xy 293.426901 -393.51367) (xy 293.452475 -393.52481) (xy 293.480109 -393.528618)
			(xy 293.507743 -393.52481) (xy 293.533317 -393.51367) (xy 293.554924 -393.496027) (xy 293.563294 -393.484862)
			(xy 293.582387 -393.458454) (xy 293.626239 -393.410247) (xy 293.67589 -393.368039) (xy 293.730526 -393.332518)
			(xy 293.789252 -393.304269) (xy 293.851106 -393.283754) (xy 293.915074 -393.271309) (xy 293.980108 -393.267138)
			(xy 294.045142 -393.271309) (xy 294.10911 -393.283754) (xy 294.170964 -393.304269) (xy 294.22969 -393.332518)
			(xy 294.284326 -393.368039) (xy 294.333977 -393.410247) (xy 294.377829 -393.458454) (xy 294.396922 -393.484862)
			(xy 294.405292 -393.496027) (xy 294.426899 -393.51367) (xy 294.452473 -393.52481) (xy 294.480107 -393.528618)
			(xy 294.507741 -393.52481) (xy 294.533315 -393.51367) (xy 294.554922 -393.496027) (xy 294.563292 -393.484862)
			(xy 294.582385 -393.458454) (xy 294.626237 -393.410247) (xy 294.675888 -393.368039) (xy 294.730524 -393.332518)
			(xy 294.78925 -393.304269) (xy 294.851104 -393.283754) (xy 294.915072 -393.271309) (xy 294.980106 -393.267138)
			(xy 295.04514 -393.271309) (xy 295.109108 -393.283754) (xy 295.170962 -393.304269) (xy 295.229688 -393.332518)
			(xy 295.284324 -393.368039) (xy 295.333975 -393.410247) (xy 295.377827 -393.458454) (xy 295.39692 -393.484862)
			(xy 295.40529 -393.496027) (xy 295.426897 -393.51367) (xy 295.452471 -393.52481) (xy 295.480105 -393.528618)
			(xy 295.507739 -393.52481) (xy 295.533313 -393.51367) (xy 295.55492 -393.496027) (xy 295.56329 -393.484862)
			(xy 295.582383 -393.458454) (xy 295.626235 -393.410247) (xy 295.675886 -393.368039) (xy 295.730522 -393.332518)
			(xy 295.789248 -393.304269) (xy 295.851102 -393.283754) (xy 295.91507 -393.271309) (xy 295.980104 -393.267138)
			(xy 296.045138 -393.271309) (xy 296.109106 -393.283754) (xy 296.17096 -393.304269) (xy 296.229686 -393.332518)
			(xy 296.284322 -393.368039) (xy 296.333973 -393.410247) (xy 296.377825 -393.458454) (xy 296.396918 -393.484862)
			(xy 296.405288 -393.496027) (xy 296.426895 -393.51367) (xy 296.452469 -393.52481) (xy 296.480103 -393.528618)
			(xy 296.507737 -393.52481) (xy 296.533311 -393.51367) (xy 296.554918 -393.496027) (xy 296.563288 -393.484862)
			(xy 296.581151 -393.46008) (xy 296.621903 -393.414568) (xy 296.667813 -393.374265) (xy 296.71822 -393.339752)
			(xy 296.772399 -393.311525) (xy 296.829568 -393.289992) (xy 296.888906 -393.275462) (xy 296.949557 -393.268144)
			(xy 296.980102 -393.267692) (xy 297.012076 -393.268286) (xy 297.07552 -393.276301) (xy 297.137459 -393.292204)
			(xy 297.196916 -393.315745) (xy 297.252954 -393.346553) (xy 297.304689 -393.384141) (xy 297.351305 -393.427916)
			(xy 297.392067 -393.477189) (xy 297.426332 -393.531182) (xy 297.45356 -393.589044) (xy 297.473321 -393.649863)
			(xy 297.485304 -393.712678) (xy 297.489319 -393.7765) (xy 297.485304 -393.840322) (xy 297.473321 -393.903137)
			(xy 297.45356 -393.963956) (xy 297.426332 -394.021818) (xy 297.392067 -394.075811) (xy 297.351305 -394.125084)
			(xy 297.304689 -394.168859) (xy 297.252954 -394.206447) (xy 297.196916 -394.237255) (xy 297.137459 -394.260796)
			(xy 297.07552 -394.276699) (xy 297.012076 -394.284714) (xy 296.980102 -394.285216) (xy 296.949556 -394.284756)
			(xy 296.888904 -394.277447) (xy 296.829565 -394.262922) (xy 296.772394 -394.241392) (xy 296.718215 -394.213165)
			(xy 296.667809 -394.178649) (xy 296.621903 -394.138341) (xy 296.581158 -394.092823) (xy 296.563288 -394.068046)
			(xy 296.554946 -394.056837) (xy 296.53336 -394.03911) (xy 296.507771 -394.027912) (xy 296.480103 -394.024083)
			(xy 296.452435 -394.027912) (xy 296.426846 -394.03911) (xy 296.40526 -394.056837) (xy 296.396918 -394.068046)
			(xy 296.377825 -394.094454) (xy 296.333973 -394.142661) (xy 296.284322 -394.184869) (xy 296.229686 -394.22039)
			(xy 296.17096 -394.248639) (xy 296.109106 -394.269154) (xy 296.045138 -394.281599) (xy 295.980104 -394.28577)
			(xy 295.91507 -394.281599) (xy 295.851102 -394.269154) (xy 295.789248 -394.248639) (xy 295.730522 -394.22039)
			(xy 295.675886 -394.184869) (xy 295.626235 -394.142661) (xy 295.582383 -394.094454) (xy 295.56329 -394.068046)
			(xy 295.554948 -394.056837) (xy 295.533362 -394.03911) (xy 295.507773 -394.027912) (xy 295.480105 -394.024083)
			(xy 295.452437 -394.027912) (xy 295.426848 -394.03911) (xy 295.405262 -394.056837) (xy 295.39692 -394.068046)
			(xy 295.377827 -394.094454) (xy 295.333975 -394.142661) (xy 295.284324 -394.184869) (xy 295.229688 -394.22039)
			(xy 295.170962 -394.248639) (xy 295.109108 -394.269154) (xy 295.04514 -394.281599) (xy 294.980106 -394.28577)
			(xy 294.915072 -394.281599) (xy 294.851104 -394.269154) (xy 294.78925 -394.248639) (xy 294.730524 -394.22039)
			(xy 294.675888 -394.184869) (xy 294.626237 -394.142661) (xy 294.582385 -394.094454) (xy 294.563292 -394.068046)
			(xy 294.55495 -394.056837) (xy 294.533364 -394.03911) (xy 294.507775 -394.027912) (xy 294.480107 -394.024083)
			(xy 294.452439 -394.027912) (xy 294.42685 -394.03911) (xy 294.405264 -394.056837) (xy 294.396922 -394.068046)
			(xy 294.377829 -394.094454) (xy 294.333977 -394.142661) (xy 294.284326 -394.184869) (xy 294.22969 -394.22039)
			(xy 294.170964 -394.248639) (xy 294.10911 -394.269154) (xy 294.045142 -394.281599) (xy 293.980108 -394.28577)
			(xy 293.915074 -394.281599) (xy 293.851106 -394.269154) (xy 293.789252 -394.248639) (xy 293.730526 -394.22039)
			(xy 293.67589 -394.184869) (xy 293.626239 -394.142661) (xy 293.582387 -394.094454) (xy 293.563294 -394.068046)
			(xy 293.554952 -394.056837) (xy 293.533366 -394.03911) (xy 293.507777 -394.027912) (xy 293.480109 -394.024083)
			(xy 293.452441 -394.027912) (xy 293.426852 -394.03911) (xy 293.405266 -394.056837) (xy 293.396924 -394.068046)
			(xy 293.377831 -394.094454) (xy 293.333979 -394.142661) (xy 293.284328 -394.184869) (xy 293.229692 -394.22039)
			(xy 293.170966 -394.248639) (xy 293.109112 -394.269154) (xy 293.045144 -394.281599) (xy 292.98011 -394.28577)
			(xy 292.915076 -394.281599) (xy 292.851108 -394.269154) (xy 292.789254 -394.248639) (xy 292.730528 -394.22039)
			(xy 292.675892 -394.184869) (xy 292.626241 -394.142661) (xy 292.582389 -394.094454) (xy 292.563296 -394.068046)
			(xy 292.554954 -394.056837) (xy 292.533368 -394.03911) (xy 292.507779 -394.027912) (xy 292.480111 -394.024083)
			(xy 292.452443 -394.027912) (xy 292.426854 -394.03911) (xy 292.405268 -394.056837) (xy 292.396926 -394.068046)
			(xy 292.379057 -394.092823) (xy 292.338306 -394.138335) (xy 292.292396 -394.178638) (xy 292.24199 -394.213151)
			(xy 292.187812 -394.241378) (xy 292.130644 -394.262913) (xy 292.071307 -394.277444) (xy 292.010657 -394.284763)
			(xy 291.980112 -394.285216) (xy 291.94813 -394.284828) (xy 291.884671 -394.276812) (xy 291.822717 -394.260906)
			(xy 291.763245 -394.237361) (xy 291.707193 -394.206547) (xy 291.655445 -394.168951) (xy 291.608817 -394.125166)
			(xy 291.568045 -394.075882) (xy 291.533771 -394.021876) (xy 291.506536 -393.964) (xy 291.48677 -393.903168)
			(xy 291.474784 -393.840337) (xy 291.470768 -393.7765) (xy 290.488624 -393.7765) (xy 290.488624 -393.776962)
			(xy 290.488202 -393.806564) (xy 290.481324 -393.865367) (xy 290.467658 -393.922971) (xy 290.447389 -393.978597)
			(xy 290.420792 -394.03149) (xy 290.388226 -394.080932) (xy 290.369498 -394.10386) (xy 290.389588 -394.127178)
			(xy 290.424612 -394.17779) (xy 290.453267 -394.232263) (xy 290.475133 -394.289797) (xy 290.48989 -394.349552)
			(xy 290.497321 -394.410651) (xy 290.497768 -394.441426) (xy 290.497768 -394.44168) (xy 290.497266 -394.473641)
			(xy 290.489255 -394.537059) (xy 290.473358 -394.598973) (xy 290.449826 -394.658406) (xy 290.419032 -394.714421)
			(xy 290.381459 -394.766136) (xy 290.337702 -394.812733) (xy 290.288449 -394.853478) (xy 290.234478 -394.887729)
			(xy 290.176639 -394.914946) (xy 290.115846 -394.934699) (xy 290.053056 -394.946677) (xy 289.98926 -394.950691)
			(xy 289.925464 -394.946677) (xy 289.862674 -394.934699) (xy 289.801881 -394.914946) (xy 289.744042 -394.887729)
			(xy 289.690071 -394.853478) (xy 289.640818 -394.812733) (xy 289.597061 -394.766136) (xy 289.559488 -394.714421)
			(xy 289.528694 -394.658406) (xy 289.505162 -394.598973) (xy 289.489265 -394.537059) (xy 289.481254 -394.473641)
			(xy 289.480752 -394.44168) (xy 289.480752 -394.441172) (xy 289.481141 -394.411569) (xy 289.488026 -394.352765)
			(xy 289.501699 -394.29516) (xy 289.521974 -394.239535) (xy 289.548577 -394.186643) (xy 289.581148 -394.137202)
			(xy 289.599878 -394.114274) (xy 289.579769 -394.090972) (xy 289.544745 -394.040357) (xy 289.516091 -393.985882)
			(xy 289.494228 -393.928344) (xy 289.479476 -393.868586) (xy 289.472051 -393.807484) (xy 289.471608 -393.776708)
			(xy 281.461756 -393.776708) (xy 281.447947 -393.823957) (xy 281.416708 -393.902348) (xy 281.378185 -393.977427)
			(xy 281.332723 -394.04852) (xy 281.280732 -394.114986) (xy 281.222678 -394.176229) (xy 281.159084 -394.231698)
			(xy 281.090523 -394.280894) (xy 281.017609 -394.323374) (xy 280.941 -394.358757) (xy 280.861383 -394.386724)
			(xy 280.779476 -394.407024) (xy 280.737818 -394.41374) (xy 280.72343 -394.416347) (xy 280.696933 -394.428691)
			(xy 280.675026 -394.448046) (xy 280.659511 -394.472819) (xy 280.651661 -394.500977) (xy 280.652122 -394.530204)
			(xy 280.65603 -394.544296) (xy 280.668744 -394.587158) (xy 280.686507 -394.674785) (xy 280.695395 -394.763751)
			(xy 280.695908 -394.808456) (xy 280.695404 -394.850804) (xy 280.687353 -394.935118) (xy 280.671324 -395.018284)
			(xy 280.647463 -395.099551) (xy 280.615984 -395.178181) (xy 280.577173 -395.253462) (xy 280.531383 -395.324714)
			(xy 280.479027 -395.39129) (xy 280.420579 -395.452588) (xy 280.356569 -395.508053) (xy 280.287577 -395.557182)
			(xy 280.214227 -395.599531) (xy 280.137184 -395.634715) (xy 280.057145 -395.662417) (xy 279.974836 -395.682385)
			(xy 279.891001 -395.694438) (xy 279.8064 -395.698469) (xy 279.721799 -395.694438) (xy 279.637964 -395.682385)
			(xy 279.555655 -395.662417) (xy 279.475616 -395.634715) (xy 279.398573 -395.599531) (xy 279.325223 -395.557182)
			(xy 279.256231 -395.508053) (xy 279.192221 -395.452588) (xy 279.133773 -395.39129) (xy 279.081417 -395.324714)
			(xy 279.035627 -395.253462) (xy 278.996816 -395.178181) (xy 278.965337 -395.099551) (xy 278.941476 -395.018284)
			(xy 278.925447 -394.935118) (xy 278.917396 -394.850804) (xy 278.916892 -394.808456) (xy 276.156405 -394.808456)
			(xy 276.156404 -394.808503) (xy 276.148874 -394.859865) (xy 276.133965 -394.909589) (xy 276.111994 -394.956621)
			(xy 276.083427 -394.999964) (xy 276.048869 -395.038699) (xy 276.009052 -395.072006) (xy 275.964821 -395.099179)
			(xy 275.917114 -395.11964) (xy 275.86694 -395.132958) (xy 275.841206 -395.13637) (xy 275.825747 -395.174161)
			(xy 275.788816 -395.246988) (xy 275.745365 -395.316123) (xy 275.695761 -395.380985) (xy 275.64042 -395.441027)
			(xy 275.579808 -395.495744) (xy 275.514437 -395.544676) (xy 275.444856 -395.587409) (xy 275.371651 -395.623585)
			(xy 275.295438 -395.652899) (xy 275.216859 -395.675104) (xy 275.136576 -395.690013) (xy 275.055264 -395.6975)
			(xy 275.014436 -395.697964) (xy 274.973213 -395.69746) (xy 274.891121 -395.689828) (xy 274.810087 -395.674636)
			(xy 274.730806 -395.652015) (xy 274.653956 -395.622157) (xy 274.580198 -395.585319) (xy 274.510163 -395.541817)
			(xy 274.444452 -395.492024) (xy 274.413726 -395.464538) (xy 274.406494 -395.458451) (xy 274.388881 -395.451625)
			(xy 274.369991 -395.451625) (xy 274.352378 -395.458451) (xy 274.345146 -395.464538) (xy 274.314435 -395.492044)
			(xy 274.248729 -395.54185) (xy 274.178695 -395.585362) (xy 274.104936 -395.622207) (xy 274.028083 -395.652068)
			(xy 273.948797 -395.67469) (xy 273.867758 -395.689878) (xy 273.785661 -395.697501) (xy 273.744436 -395.697964)
			(xy 273.702084 -395.697566) (xy 273.617762 -395.689517) (xy 273.534587 -395.673489) (xy 273.453313 -395.649628)
			(xy 273.374675 -395.618149) (xy 273.299385 -395.579337) (xy 273.228125 -395.533544) (xy 273.161542 -395.481184)
			(xy 273.100237 -395.422733) (xy 273.044766 -395.358718) (xy 272.995631 -395.28972) (xy 272.953277 -395.216364)
			(xy 272.918089 -395.139314) (xy 272.890384 -395.059269) (xy 272.870414 -394.976952) (xy 272.858359 -394.893109)
			(xy 272.854328 -394.8085) (xy 270.221496 -394.8085) (xy 270.221496 -394.808506) (xy 270.213964 -394.859873)
			(xy 270.199053 -394.909601) (xy 270.177077 -394.956636) (xy 270.148504 -394.999982) (xy 270.113939 -395.038718)
			(xy 270.074115 -395.072025) (xy 270.029876 -395.099194) (xy 269.98216 -395.119651) (xy 269.93198 -395.132962)
			(xy 269.906242 -395.13637) (xy 269.890753 -395.174148) (xy 269.853824 -395.246974) (xy 269.810375 -395.316109)
			(xy 269.760773 -395.38097) (xy 269.705435 -395.441012) (xy 269.644826 -395.49573) (xy 269.579457 -395.544662)
			(xy 269.509879 -395.587396) (xy 269.436676 -395.623574) (xy 269.360466 -395.652889) (xy 269.28189 -395.675096)
			(xy 269.201609 -395.690008) (xy 269.120299 -395.697499) (xy 269.079472 -395.697964) (xy 269.038248 -395.6975)
			(xy 268.956155 -395.689862) (xy 268.87512 -395.674665) (xy 268.795838 -395.652037) (xy 268.718989 -395.622174)
			(xy 268.645231 -395.585331) (xy 268.575197 -395.541824) (xy 268.509487 -395.492026) (xy 268.478762 -395.464538)
			(xy 268.47153 -395.458451) (xy 268.453917 -395.451625) (xy 268.435027 -395.451625) (xy 268.417414 -395.458451)
			(xy 268.410182 -395.464538) (xy 268.379456 -395.492026) (xy 268.313752 -395.541834) (xy 268.243721 -395.585348)
			(xy 268.169964 -395.622194) (xy 268.093113 -395.652058) (xy 268.013829 -395.674682) (xy 267.932792 -395.689873)
			(xy 267.850696 -395.6975) (xy 267.809472 -395.697964) (xy 267.767122 -395.697547) (xy 267.682807 -395.689493)
			(xy 267.599638 -395.673462) (xy 267.51837 -395.649597) (xy 267.439739 -395.618115) (xy 267.364456 -395.579302)
			(xy 267.293203 -395.533509) (xy 267.226625 -395.48115) (xy 267.165326 -395.422699) (xy 267.109861 -395.358687)
			(xy 267.060731 -395.289692) (xy 267.018382 -395.21634) (xy 266.983198 -395.139294) (xy 266.955496 -395.059253)
			(xy 266.935527 -394.976941) (xy 266.923474 -394.893104) (xy 266.919443 -394.8085) (xy 264.336432 -394.8085)
			(xy 264.334396 -394.835661) (xy 264.322533 -394.887635) (xy 264.303057 -394.93726) (xy 264.276401 -394.983428)
			(xy 264.243162 -395.025107) (xy 264.204083 -395.061367) (xy 264.160035 -395.091397) (xy 264.112004 -395.114526)
			(xy 264.061062 -395.130239) (xy 264.008347 -395.138183) (xy 263.981692 -395.138656) (xy 263.970516 -395.138402)
			(xy 263.954928 -395.17605) (xy 263.917915 -395.248648) (xy 263.874417 -395.317555) (xy 263.824797 -395.382194)
			(xy 263.769471 -395.442023) (xy 263.708905 -395.496539) (xy 263.643605 -395.545287) (xy 263.57412 -395.587856)
			(xy 263.501032 -395.623891) (xy 263.424953 -395.653088) (xy 263.346523 -395.675203) (xy 263.266399 -395.69005)
			(xy 263.185252 -395.697505) (xy 263.144508 -395.697964) (xy 263.103285 -395.697477) (xy 263.021192 -395.689843)
			(xy 262.940158 -395.674649) (xy 262.860876 -395.652025) (xy 262.784027 -395.622164) (xy 262.710269 -395.585324)
			(xy 262.640234 -395.54182) (xy 262.574524 -395.492025) (xy 262.543798 -395.464538) (xy 262.536566 -395.458451)
			(xy 262.518953 -395.451625) (xy 262.500063 -395.451625) (xy 262.48245 -395.458451) (xy 262.475218 -395.464538)
			(xy 262.444477 -395.492009) (xy 262.378775 -395.541818) (xy 262.308747 -395.585333) (xy 262.234992 -395.622182)
			(xy 262.158144 -395.652048) (xy 262.078861 -395.674675) (xy 261.997826 -395.689868) (xy 261.915732 -395.697498)
			(xy 261.874508 -395.697964) (xy 261.832156 -395.697564) (xy 261.747837 -395.689513) (xy 261.664664 -395.673484)
			(xy 261.583392 -395.649621) (xy 261.504756 -395.61814) (xy 261.429469 -395.579328) (xy 261.358212 -395.533534)
			(xy 261.29163 -395.481174) (xy 261.230327 -395.422723) (xy 261.174858 -395.358709) (xy 261.125725 -395.289712)
			(xy 261.083374 -395.216357) (xy 261.048186 -395.139308) (xy 261.020483 -395.059264) (xy 261.000513 -394.976948)
			(xy 260.988458 -394.893107) (xy 260.984428 -394.8085) (xy 258.421708 -394.8085) (xy 258.419673 -394.835652)
			(xy 258.407813 -394.887617) (xy 258.388341 -394.937235) (xy 258.361693 -394.983396) (xy 258.328463 -395.025071)
			(xy 258.289393 -395.061327) (xy 258.245356 -395.091357) (xy 258.197335 -395.114488) (xy 258.146403 -395.130204)
			(xy 258.093699 -395.138155) (xy 258.067048 -395.138656) (xy 258.03606 -395.137386) (xy 258.020546 -395.175113)
			(xy 257.983557 -395.247826) (xy 257.940067 -395.316846) (xy 257.89044 -395.381595) (xy 257.835094 -395.441529)
			(xy 257.774494 -395.496144) (xy 257.709147 -395.544982) (xy 257.639604 -395.587632) (xy 257.566448 -395.623736)
			(xy 257.490294 -395.65299) (xy 257.411782 -395.67515) (xy 257.331571 -395.690029) (xy 257.250334 -395.697502)
			(xy 257.209544 -395.697964) (xy 257.168321 -395.697455) (xy 257.08623 -395.689824) (xy 257.005196 -395.674633)
			(xy 256.925914 -395.652012) (xy 256.849065 -395.622155) (xy 256.775306 -395.585317) (xy 256.705271 -395.541816)
			(xy 256.63956 -395.492023) (xy 256.608834 -395.464538) (xy 256.601602 -395.458451) (xy 256.583989 -395.451625)
			(xy 256.565099 -395.451625) (xy 256.547486 -395.458451) (xy 256.540254 -395.464538) (xy 256.50954 -395.49204)
			(xy 256.443834 -395.541846) (xy 256.373801 -395.585359) (xy 256.300042 -395.622204) (xy 256.22319 -395.652066)
			(xy 256.143904 -395.674688) (xy 256.062865 -395.689877) (xy 255.980769 -395.697501) (xy 255.939544 -395.697964)
			(xy 255.897191 -395.697566) (xy 255.812869 -395.689518) (xy 255.729694 -395.673491) (xy 255.648419 -395.64963)
			(xy 255.56978 -395.618151) (xy 255.494489 -395.57934) (xy 255.423229 -395.533547) (xy 255.356645 -395.481187)
			(xy 255.295339 -395.422735) (xy 255.239868 -395.358721) (xy 255.190732 -395.289723) (xy 255.148379 -395.216366)
			(xy 255.11319 -395.139316) (xy 255.085484 -395.05927) (xy 255.065514 -394.976952) (xy 255.053459 -394.893109)
			(xy 255.049428 -394.8085) (xy 252.441992 -394.8085) (xy 252.441968 -394.809821) (xy 252.433657 -394.863731)
			(xy 252.417221 -394.915743) (xy 252.393046 -394.964639) (xy 252.361695 -395.009276) (xy 252.323904 -395.04861)
			(xy 252.280556 -395.081721) (xy 252.232666 -395.107832) (xy 252.181353 -395.126335) (xy 252.127819 -395.136795)
			(xy 252.100588 -395.138402) (xy 252.085024 -395.17606) (xy 252.048009 -395.248659) (xy 252.004509 -395.317566)
			(xy 251.954887 -395.382206) (xy 251.89956 -395.442034) (xy 251.838991 -395.496551) (xy 251.773689 -395.545298)
			(xy 251.704202 -395.587866) (xy 251.631111 -395.623899) (xy 251.555031 -395.653095) (xy 251.476599 -395.675208)
			(xy 251.396473 -395.690054) (xy 251.315325 -395.697507) (xy 251.27458 -395.697964) (xy 251.233356 -395.697495)
			(xy 251.151263 -395.689858) (xy 251.070228 -395.674661) (xy 250.990947 -395.652035) (xy 250.914097 -395.622172)
			(xy 250.840339 -395.58533) (xy 250.770305 -395.541823) (xy 250.704595 -395.492026) (xy 250.67387 -395.464538)
			(xy 250.666638 -395.458451) (xy 250.649025 -395.451625) (xy 250.630135 -395.451625) (xy 250.612522 -395.458451)
			(xy 250.60529 -395.464538) (xy 250.574561 -395.492023) (xy 250.508857 -395.54183) (xy 250.438827 -395.585344)
			(xy 250.36507 -395.622192) (xy 250.28822 -395.652056) (xy 250.208936 -395.67468) (xy 250.127899 -395.689872)
			(xy 250.045804 -395.697499) (xy 250.00458 -395.697964) (xy 249.96223 -395.697547) (xy 249.877914 -395.689494)
			(xy 249.794745 -395.673463) (xy 249.713476 -395.649599) (xy 249.634844 -395.618118) (xy 249.55956 -395.579305)
			(xy 249.488307 -395.533512) (xy 249.421729 -395.481153) (xy 249.360429 -395.422702) (xy 249.304963 -395.35869)
			(xy 249.255833 -395.289695) (xy 249.213483 -395.216342) (xy 249.178298 -395.139296) (xy 249.150596 -395.059254)
			(xy 249.130628 -394.976942) (xy 249.118574 -394.893104) (xy 249.114543 -394.8085) (xy 246.481601 -394.8085)
			(xy 246.481601 -394.808504) (xy 246.474071 -394.859867) (xy 246.459161 -394.909593) (xy 246.437189 -394.956626)
			(xy 246.40862 -394.999969) (xy 246.374059 -395.038705) (xy 246.334241 -395.072012) (xy 246.290007 -395.099183)
			(xy 246.242297 -395.119644) (xy 246.192121 -395.132959) (xy 246.166386 -395.13637) (xy 246.15086 -395.174132)
			(xy 246.113933 -395.246957) (xy 246.070488 -395.316091) (xy 246.020888 -395.380952) (xy 245.965553 -395.440994)
			(xy 245.904948 -395.495712) (xy 245.839582 -395.544645) (xy 245.770007 -395.587381) (xy 245.696808 -395.62356)
			(xy 245.620601 -395.652878) (xy 245.542028 -395.675088) (xy 245.461749 -395.690002) (xy 245.380442 -395.697497)
			(xy 245.339616 -395.697964) (xy 245.298393 -395.697472) (xy 245.216301 -395.689839) (xy 245.135266 -395.674645)
			(xy 245.055985 -395.652022) (xy 244.979135 -395.622162) (xy 244.905377 -395.585323) (xy 244.835342 -395.541819)
			(xy 244.769632 -395.492024) (xy 244.738906 -395.464538) (xy 244.731674 -395.458451) (xy 244.714061 -395.451625)
			(xy 244.695171 -395.451625) (xy 244.677558 -395.458451) (xy 244.670326 -395.464538) (xy 244.639624 -395.492053)
			(xy 244.573916 -395.541859) (xy 244.503881 -395.58537) (xy 244.43012 -395.622214) (xy 244.353266 -395.652074)
			(xy 244.273979 -395.674694) (xy 244.192939 -395.68988) (xy 244.110841 -395.697502) (xy 244.069616 -395.697964)
			(xy 244.027264 -395.697565) (xy 243.942944 -395.689514) (xy 243.859771 -395.673485) (xy 243.778498 -395.649623)
			(xy 243.699861 -395.618143) (xy 243.624573 -395.57933) (xy 243.553315 -395.533537) (xy 243.486733 -395.481177)
			(xy 243.42543 -395.422726) (xy 243.36996 -395.358711) (xy 243.320827 -395.289714) (xy 243.278475 -395.216359)
			(xy 243.243287 -395.13931) (xy 243.215583 -395.059265) (xy 243.195613 -394.976949) (xy 243.183558 -394.893108)
			(xy 243.179528 -394.8085) (xy 3.523996 -394.8085) (xy 3.523996 -396.842996) (xy 18.90268 -396.842996)
			(xy 18.90268 -395.979396) (xy 18.903166 -395.952145) (xy 18.910922 -395.898197) (xy 18.926277 -395.845902)
			(xy 18.948919 -395.796325) (xy 18.978385 -395.750475) (xy 19.014076 -395.709284) (xy 19.055267 -395.673593)
			(xy 19.101117 -395.644127) (xy 19.150694 -395.621485) (xy 19.202989 -395.60613) (xy 19.256937 -395.598374)
			(xy 19.311439 -395.598374) (xy 19.365387 -395.60613) (xy 19.417682 -395.621485) (xy 19.467259 -395.644127)
			(xy 19.513109 -395.673593) (xy 19.5543 -395.709284) (xy 19.589991 -395.750475) (xy 19.601933 -395.769057)
			(xy 288.471858 -395.769057) (xy 288.471858 -395.705103) (xy 288.479873 -395.641653) (xy 288.495778 -395.579708)
			(xy 288.519321 -395.520246) (xy 288.550131 -395.464202) (xy 288.587723 -395.412462) (xy 288.631502 -395.365842)
			(xy 288.68078 -395.325076) (xy 288.734778 -395.290808) (xy 288.792645 -395.263577) (xy 288.853469 -395.243814)
			(xy 288.91629 -395.231831) (xy 288.980118 -395.227815) (xy 289.043946 -395.231831) (xy 289.106767 -395.243814)
			(xy 289.167591 -395.263577) (xy 289.225458 -395.290808) (xy 289.279456 -395.325076) (xy 289.328734 -395.365842)
			(xy 289.372513 -395.412462) (xy 289.410105 -395.464202) (xy 289.440915 -395.520246) (xy 289.464458 -395.579708)
			(xy 289.480363 -395.641653) (xy 289.488378 -395.705103) (xy 289.48888 -395.73708) (xy 289.488378 -395.769057)
			(xy 289.480363 -395.832507) (xy 289.464458 -395.894452) (xy 289.440915 -395.953914) (xy 289.410105 -396.009958)
			(xy 289.372513 -396.061698) (xy 289.328734 -396.108318) (xy 289.279456 -396.149084) (xy 289.225458 -396.183352)
			(xy 289.167591 -396.210583) (xy 289.106767 -396.230346) (xy 289.043946 -396.242329) (xy 288.980118 -396.246345)
			(xy 288.91629 -396.242329) (xy 288.853469 -396.230346) (xy 288.792645 -396.210583) (xy 288.734778 -396.183352)
			(xy 288.68078 -396.149084) (xy 288.631502 -396.108318) (xy 288.587723 -396.061698) (xy 288.550131 -396.009958)
			(xy 288.519321 -395.953914) (xy 288.495778 -395.894452) (xy 288.479873 -395.832507) (xy 288.471858 -395.769057)
			(xy 19.601933 -395.769057) (xy 19.619457 -395.796325) (xy 19.642099 -395.845902) (xy 19.657454 -395.898197)
			(xy 19.66521 -395.952145) (xy 19.665696 -395.979396) (xy 19.665696 -396.842996) (xy 19.66521 -396.870247)
			(xy 19.657454 -396.924195) (xy 19.642099 -396.97649) (xy 19.619457 -397.026067) (xy 19.589991 -397.071917)
			(xy 19.5543 -397.113108) (xy 19.513109 -397.148799) (xy 19.467259 -397.178265) (xy 19.417682 -397.200907)
			(xy 19.365387 -397.216262) (xy 19.311439 -397.224018) (xy 19.256937 -397.224018) (xy 19.202989 -397.216262)
			(xy 19.150694 -397.200907) (xy 19.101117 -397.178265) (xy 19.055267 -397.148799) (xy 19.014076 -397.113108)
			(xy 18.978385 -397.071917) (xy 18.948919 -397.026067) (xy 18.926277 -396.97649) (xy 18.910922 -396.924195)
			(xy 18.903166 -396.870247) (xy 18.90268 -396.842996) (xy 3.523996 -396.842996) (xy 3.523996 -397.606012)
			(xy 24.954992 -397.606012) (xy 24.954992 -396.742412) (xy 24.955478 -396.715161) (xy 24.963234 -396.661213)
			(xy 24.978589 -396.608918) (xy 25.001231 -396.559341) (xy 25.030697 -396.513491) (xy 25.066388 -396.4723)
			(xy 25.107579 -396.436609) (xy 25.153429 -396.407143) (xy 25.203006 -396.384501) (xy 25.255301 -396.369146)
			(xy 25.309249 -396.36139) (xy 25.363751 -396.36139) (xy 25.417699 -396.369146) (xy 25.469994 -396.384501)
			(xy 25.519571 -396.407143) (xy 25.565421 -396.436609) (xy 25.606612 -396.4723) (xy 25.642303 -396.513491)
			(xy 25.671769 -396.559341) (xy 25.694411 -396.608918) (xy 25.709766 -396.661213) (xy 25.717522 -396.715161)
			(xy 25.718008 -396.742412) (xy 25.718008 -397.606012) (xy 25.717522 -397.633263) (xy 25.709766 -397.687211)
			(xy 25.694411 -397.739506) (xy 25.671769 -397.789083) (xy 25.642303 -397.834933) (xy 25.606612 -397.876124)
			(xy 25.565421 -397.911815) (xy 25.519571 -397.941281) (xy 25.469994 -397.963923) (xy 25.417699 -397.979278)
			(xy 25.363751 -397.987034) (xy 25.309249 -397.987034) (xy 25.255301 -397.979278) (xy 25.203006 -397.963923)
			(xy 25.153429 -397.941281) (xy 25.107579 -397.911815) (xy 25.066388 -397.876124) (xy 25.030697 -397.834933)
			(xy 25.001231 -397.789083) (xy 24.978589 -397.739506) (xy 24.963234 -397.687211) (xy 24.955478 -397.633263)
			(xy 24.954992 -397.606012) (xy 3.523996 -397.606012) (xy 3.523996 -398.68657) (xy 36.781952 -398.68657)
			(xy 36.781952 -398.63203) (xy 36.789714 -398.578046) (xy 36.805081 -398.525717) (xy 36.827739 -398.476107)
			(xy 36.857227 -398.430227) (xy 36.892945 -398.389011) (xy 36.934165 -398.353298) (xy 36.980049 -398.323816)
			(xy 37.029662 -398.301164) (xy 37.081993 -398.285804) (xy 37.135978 -398.278048) (xy 37.163248 -398.277588)
			(xy 38.026848 -398.277588) (xy 38.054119 -398.277978) (xy 38.108104 -398.285746) (xy 38.160435 -398.301118)
			(xy 38.210045 -398.323779) (xy 38.255926 -398.353271) (xy 38.297144 -398.38899) (xy 38.332858 -398.430212)
			(xy 38.362344 -398.476097) (xy 38.384999 -398.52571) (xy 38.400364 -398.578043) (xy 38.408126 -398.632029)
			(xy 38.408126 -398.686571) (xy 38.400364 -398.740557) (xy 38.384999 -398.79289) (xy 38.38214 -398.799152)
			(xy 42.10455 -398.799152) (xy 42.10455 -398.744648) (xy 42.112306 -398.6907) (xy 42.12766 -398.638404)
			(xy 42.150301 -398.588826) (xy 42.179766 -398.542974) (xy 42.215456 -398.501781) (xy 42.256645 -398.466087)
			(xy 42.302494 -398.436618) (xy 42.35207 -398.413973) (xy 42.404365 -398.398614) (xy 42.458312 -398.390852)
			(xy 42.485564 -398.390364) (xy 43.349164 -398.390364) (xy 43.376417 -398.390881) (xy 43.430367 -398.398633)
			(xy 43.482666 -398.413985) (xy 43.532247 -398.436624) (xy 43.578101 -398.466088) (xy 43.619295 -398.50178)
			(xy 43.65499 -398.54297) (xy 43.684459 -398.588822) (xy 43.707103 -398.638401) (xy 43.722459 -398.690697)
			(xy 43.730217 -398.744648) (xy 43.730217 -398.799152) (xy 43.722459 -398.853103) (xy 43.707103 -398.9054)
			(xy 43.684459 -398.954978) (xy 43.65499 -399.00083) (xy 43.619295 -399.04202) (xy 43.578101 -399.077712)
			(xy 43.532247 -399.107176) (xy 43.482666 -399.129815) (xy 43.430367 -399.145167) (xy 43.376417 -399.152919)
			(xy 43.349164 -399.15338) (xy 42.485564 -399.15338) (xy 42.458312 -399.152948) (xy 42.404365 -399.145186)
			(xy 42.35207 -399.129827) (xy 42.302494 -399.107182) (xy 42.256645 -399.077713) (xy 42.215456 -399.042019)
			(xy 42.179766 -399.000826) (xy 42.150301 -398.954974) (xy 42.12766 -398.905396) (xy 42.112306 -398.8531)
			(xy 42.10455 -398.799152) (xy 38.38214 -398.799152) (xy 38.362344 -398.842503) (xy 38.332858 -398.888388)
			(xy 38.297144 -398.92961) (xy 38.255926 -398.965329) (xy 38.210045 -398.994821) (xy 38.160435 -399.017482)
			(xy 38.108104 -399.032854) (xy 38.054119 -399.040622) (xy 38.026848 -399.041112) (xy 37.163248 -399.041112)
			(xy 37.135978 -399.040552) (xy 37.081993 -399.032796) (xy 37.029662 -399.017436) (xy 36.980049 -398.994784)
			(xy 36.934165 -398.965302) (xy 36.892945 -398.929589) (xy 36.857227 -398.888373) (xy 36.827739 -398.842493)
			(xy 36.805081 -398.792883) (xy 36.789714 -398.740554) (xy 36.781952 -398.68657) (xy 3.523996 -398.68657)
			(xy 3.523996 -399.443249) (xy 18.470394 -399.443249) (xy 18.470394 -399.388751) (xy 18.47815 -399.334808)
			(xy 18.493503 -399.282518) (xy 18.516141 -399.232945) (xy 18.545603 -399.187098) (xy 18.58129 -399.14591)
			(xy 18.622475 -399.11022) (xy 18.66832 -399.080754) (xy 18.717892 -399.058112) (xy 18.770181 -399.042756)
			(xy 18.824123 -399.034996) (xy 18.851372 -399.034508) (xy 19.714972 -399.034508) (xy 19.742227 -399.034937)
			(xy 19.796184 -399.042691) (xy 19.848487 -399.058045) (xy 19.898073 -399.080687) (xy 19.943931 -399.110156)
			(xy 19.985129 -399.145851) (xy 20.020827 -399.187046) (xy 20.050299 -399.232903) (xy 20.072945 -399.282487)
			(xy 20.088303 -399.334789) (xy 20.096061 -399.388745) (xy 20.096061 -399.443255) (xy 20.088303 -399.497211)
			(xy 20.072945 -399.549513) (xy 20.050299 -399.599097) (xy 20.020828 -399.644954) (xy 19.985129 -399.686149)
			(xy 19.943931 -399.721844) (xy 19.898073 -399.751313) (xy 19.848487 -399.773955) (xy 19.796184 -399.789309)
			(xy 19.742227 -399.797063) (xy 19.714972 -399.797524) (xy 18.851372 -399.797524) (xy 18.824123 -399.797004)
			(xy 18.770181 -399.789244) (xy 18.717892 -399.773888) (xy 18.66832 -399.751246) (xy 18.622475 -399.72178)
			(xy 18.58129 -399.68609) (xy 18.545603 -399.644902) (xy 18.516141 -399.599055) (xy 18.493503 -399.549482)
			(xy 18.47815 -399.497192) (xy 18.470394 -399.443249) (xy 3.523996 -399.443249) (xy 3.523996 -400.459248)
			(xy 25.590794 -400.459248) (xy 25.590794 -400.404752) (xy 25.598549 -400.350811) (xy 25.613901 -400.298522)
			(xy 25.636538 -400.24895) (xy 25.665999 -400.203104) (xy 25.701684 -400.161916) (xy 25.742867 -400.126226)
			(xy 25.788709 -400.09676) (xy 25.838279 -400.074117) (xy 25.890566 -400.058759) (xy 25.944506 -400.050997)
			(xy 25.971754 -400.050508) (xy 26.835354 -400.050508) (xy 26.86261 -400.050936) (xy 26.916568 -400.058688)
			(xy 26.968874 -400.07404) (xy 27.018462 -400.096681) (xy 27.064323 -400.126149) (xy 27.105523 -400.161845)
			(xy 27.141223 -400.20304) (xy 27.170697 -400.248897) (xy 27.193343 -400.298483) (xy 27.208702 -400.350787)
			(xy 27.216461 -400.404744) (xy 27.216461 -400.459256) (xy 27.208702 -400.513213) (xy 27.193343 -400.565517)
			(xy 27.170697 -400.615103) (xy 27.141223 -400.66096) (xy 27.105523 -400.702155) (xy 27.064323 -400.737851)
			(xy 27.018462 -400.767319) (xy 26.968874 -400.78996) (xy 26.916568 -400.805312) (xy 26.86261 -400.813064)
			(xy 26.835354 -400.813524) (xy 25.971754 -400.813524) (xy 25.944506 -400.813003) (xy 25.890566 -400.805241)
			(xy 25.838279 -400.789883) (xy 25.788709 -400.76724) (xy 25.742867 -400.737774) (xy 25.701684 -400.702084)
			(xy 25.665999 -400.660896) (xy 25.636538 -400.61505) (xy 25.613901 -400.565478) (xy 25.598549 -400.513189)
			(xy 25.590794 -400.459248) (xy 3.523996 -400.459248) (xy 3.523996 -400.885453) (xy 47.598783 -400.885453)
			(xy 47.598783 -400.830947) (xy 47.606541 -400.776997) (xy 47.621898 -400.7247) (xy 47.644541 -400.675121)
			(xy 47.674011 -400.629269) (xy 47.709706 -400.588079) (xy 47.7509 -400.552388) (xy 47.796754 -400.522923)
			(xy 47.846336 -400.500284) (xy 47.898634 -400.484933) (xy 47.952585 -400.477181) (xy 47.979838 -400.47672)
			(xy 48.843438 -400.47672) (xy 48.870689 -400.477152) (xy 48.924637 -400.484914) (xy 48.976931 -400.500273)
			(xy 49.026507 -400.522918) (xy 49.072356 -400.552388) (xy 49.113545 -400.588082) (xy 49.149235 -400.629274)
			(xy 49.1787 -400.675126) (xy 49.20134 -400.724705) (xy 49.216694 -400.777) (xy 49.22445 -400.830948)
			(xy 49.22445 -400.885448) (xy 50.662106 -400.885448) (xy 50.662106 -400.830952) (xy 50.669862 -400.77701)
			(xy 50.685214 -400.724721) (xy 50.707852 -400.675149) (xy 50.737314 -400.629303) (xy 50.773001 -400.588116)
			(xy 50.814185 -400.552427) (xy 50.86003 -400.522963) (xy 50.9096 -400.500322) (xy 50.961888 -400.484966)
			(xy 51.01583 -400.477208) (xy 51.043078 -400.47672) (xy 51.906678 -400.47672) (xy 51.933934 -400.477125)
			(xy 51.987891 -400.48488) (xy 52.040196 -400.500236) (xy 52.089782 -400.522879) (xy 52.135642 -400.552348)
			(xy 52.17684 -400.588045) (xy 52.212539 -400.629241) (xy 52.242011 -400.675098) (xy 52.264657 -400.724684)
			(xy 52.280015 -400.776987) (xy 52.287773 -400.830944) (xy 52.287773 -400.885452) (xy 53.725283 -400.885452)
			(xy 53.725283 -400.830948) (xy 53.73304 -400.777) (xy 53.748396 -400.724704) (xy 53.771038 -400.675127)
			(xy 53.800506 -400.629276) (xy 53.836199 -400.588086) (xy 53.87739 -400.552395) (xy 53.923242 -400.52293)
			(xy 53.972821 -400.50029) (xy 54.025117 -400.484936) (xy 54.079066 -400.477182) (xy 54.106318 -400.47672)
			(xy 54.969918 -400.47672) (xy 54.99717 -400.477151) (xy 55.05112 -400.48491) (xy 55.103417 -400.500268)
			(xy 55.152995 -400.522912) (xy 55.198847 -400.552381) (xy 55.240038 -400.588075) (xy 55.27573 -400.629268)
			(xy 55.305197 -400.675121) (xy 55.327838 -400.7247) (xy 55.343194 -400.776997) (xy 55.35095 -400.830948)
			(xy 55.35095 -400.885447) (xy 56.788606 -400.885447) (xy 56.788606 -400.830953) (xy 56.796361 -400.777013)
			(xy 56.811713 -400.724725) (xy 56.834349 -400.675154) (xy 56.863809 -400.629309) (xy 56.899494 -400.588123)
			(xy 56.940676 -400.552435) (xy 56.986518 -400.522969) (xy 57.036086 -400.500327) (xy 57.088372 -400.48497)
			(xy 57.142311 -400.477209) (xy 57.169558 -400.47672) (xy 58.033158 -400.47672) (xy 58.060415 -400.477124)
			(xy 58.114374 -400.484877) (xy 58.166681 -400.50023) (xy 58.21627 -400.522872) (xy 58.262132 -400.552341)
			(xy 58.303333 -400.588037) (xy 58.339034 -400.629234) (xy 58.368508 -400.675093) (xy 58.391155 -400.724679)
			(xy 58.406514 -400.776985) (xy 58.414273 -400.830943) (xy 58.414273 -400.885449) (xy 59.851806 -400.885449)
			(xy 59.851806 -400.830951) (xy 59.859562 -400.777007) (xy 59.874916 -400.724717) (xy 59.897555 -400.675143)
			(xy 59.927019 -400.629296) (xy 59.962708 -400.588109) (xy 60.003895 -400.55242) (xy 60.049742 -400.522956)
			(xy 60.099315 -400.500317) (xy 60.151605 -400.484963) (xy 60.205549 -400.477206) (xy 60.232798 -400.47672)
			(xy 61.096398 -400.47672) (xy 61.123653 -400.477127) (xy 61.177608 -400.484884) (xy 61.22991 -400.500241)
			(xy 61.279494 -400.522885) (xy 61.325351 -400.552355) (xy 61.366547 -400.588052) (xy 61.402243 -400.629247)
			(xy 61.431714 -400.675104) (xy 61.454358 -400.724688) (xy 61.469715 -400.77699) (xy 61.477473 -400.830945)
			(xy 61.477473 -400.885453) (xy 62.914983 -400.885453) (xy 62.914983 -400.830947) (xy 62.922741 -400.776997)
			(xy 62.938098 -400.7247) (xy 62.960741 -400.675121) (xy 62.990211 -400.629269) (xy 63.025906 -400.588079)
			(xy 63.0671 -400.552388) (xy 63.112954 -400.522923) (xy 63.162536 -400.500284) (xy 63.214834 -400.484933)
			(xy 63.268785 -400.477181) (xy 63.296038 -400.47672) (xy 64.159638 -400.47672) (xy 64.186889 -400.477152)
			(xy 64.240837 -400.484914) (xy 64.293131 -400.500273) (xy 64.342707 -400.522918) (xy 64.388556 -400.552388)
			(xy 64.429745 -400.588082) (xy 64.465435 -400.629274) (xy 64.4949 -400.675126) (xy 64.51754 -400.724705)
			(xy 64.532894 -400.777) (xy 64.54065 -400.830948) (xy 64.54065 -400.885448) (xy 65.978306 -400.885448)
			(xy 65.978306 -400.830952) (xy 65.986062 -400.77701) (xy 66.001414 -400.724721) (xy 66.024052 -400.675149)
			(xy 66.053514 -400.629303) (xy 66.089201 -400.588116) (xy 66.130385 -400.552427) (xy 66.17623 -400.522963)
			(xy 66.2258 -400.500322) (xy 66.278088 -400.484966) (xy 66.33203 -400.477208) (xy 66.359278 -400.47672)
			(xy 67.222878 -400.47672) (xy 67.250134 -400.477125) (xy 67.304091 -400.48488) (xy 67.356396 -400.500236)
			(xy 67.405982 -400.522879) (xy 67.451842 -400.552348) (xy 67.49304 -400.588045) (xy 67.528739 -400.629241)
			(xy 67.558211 -400.675098) (xy 67.580857 -400.724684) (xy 67.596215 -400.776987) (xy 67.603973 -400.830944)
			(xy 67.603973 -400.885452) (xy 69.041483 -400.885452) (xy 69.041483 -400.830948) (xy 69.04924 -400.777)
			(xy 69.064596 -400.724704) (xy 69.087238 -400.675127) (xy 69.116706 -400.629276) (xy 69.152399 -400.588086)
			(xy 69.19359 -400.552395) (xy 69.239442 -400.52293) (xy 69.289021 -400.50029) (xy 69.341317 -400.484936)
			(xy 69.395266 -400.477182) (xy 69.422518 -400.47672) (xy 70.286118 -400.47672) (xy 70.31337 -400.477151)
			(xy 70.36732 -400.48491) (xy 70.419617 -400.500268) (xy 70.469195 -400.522912) (xy 70.515047 -400.552381)
			(xy 70.556238 -400.588075) (xy 70.59193 -400.629268) (xy 70.621397 -400.675121) (xy 70.644038 -400.7247)
			(xy 70.659394 -400.776997) (xy 70.66715 -400.830948) (xy 70.66715 -400.885447) (xy 72.104806 -400.885447)
			(xy 72.104806 -400.830953) (xy 72.112561 -400.777013) (xy 72.127913 -400.724725) (xy 72.150549 -400.675154)
			(xy 72.180009 -400.629309) (xy 72.215694 -400.588123) (xy 72.256876 -400.552435) (xy 72.302718 -400.522969)
			(xy 72.352286 -400.500327) (xy 72.404572 -400.48497) (xy 72.458511 -400.477209) (xy 72.485758 -400.47672)
			(xy 73.349358 -400.47672) (xy 73.376615 -400.477124) (xy 73.430574 -400.484877) (xy 73.482881 -400.50023)
			(xy 73.53247 -400.522872) (xy 73.578332 -400.552341) (xy 73.619533 -400.588037) (xy 73.655234 -400.629234)
			(xy 73.684708 -400.675093) (xy 73.707355 -400.724679) (xy 73.722714 -400.776985) (xy 73.730473 -400.830943)
			(xy 73.730473 -400.885449) (xy 75.168006 -400.885449) (xy 75.168006 -400.830951) (xy 75.175762 -400.777007)
			(xy 75.191116 -400.724717) (xy 75.213755 -400.675143) (xy 75.243219 -400.629296) (xy 75.278908 -400.588109)
			(xy 75.320095 -400.55242) (xy 75.365942 -400.522956) (xy 75.415515 -400.500317) (xy 75.467805 -400.484963)
			(xy 75.521749 -400.477206) (xy 75.548998 -400.47672) (xy 76.412598 -400.47672) (xy 76.439853 -400.477127)
			(xy 76.493808 -400.484884) (xy 76.54611 -400.500241) (xy 76.595694 -400.522885) (xy 76.641551 -400.552355)
			(xy 76.682747 -400.588052) (xy 76.718443 -400.629247) (xy 76.747914 -400.675104) (xy 76.770558 -400.724688)
			(xy 76.785915 -400.77699) (xy 76.793673 -400.830945) (xy 76.793673 -400.885453) (xy 78.231183 -400.885453)
			(xy 78.231183 -400.830947) (xy 78.238941 -400.776997) (xy 78.254298 -400.7247) (xy 78.276941 -400.675121)
			(xy 78.306411 -400.629269) (xy 78.342106 -400.588079) (xy 78.3833 -400.552388) (xy 78.429154 -400.522923)
			(xy 78.478736 -400.500284) (xy 78.531034 -400.484933) (xy 78.584985 -400.477181) (xy 78.612238 -400.47672)
			(xy 79.475838 -400.47672) (xy 79.503089 -400.477152) (xy 79.557037 -400.484914) (xy 79.609331 -400.500273)
			(xy 79.658907 -400.522918) (xy 79.704756 -400.552388) (xy 79.745945 -400.588082) (xy 79.781635 -400.629274)
			(xy 79.8111 -400.675126) (xy 79.83374 -400.724705) (xy 79.849094 -400.777) (xy 79.85685 -400.830948)
			(xy 79.85685 -400.885448) (xy 81.294506 -400.885448) (xy 81.294506 -400.830952) (xy 81.302262 -400.77701)
			(xy 81.317614 -400.724721) (xy 81.340252 -400.675149) (xy 81.369714 -400.629303) (xy 81.405401 -400.588116)
			(xy 81.446585 -400.552427) (xy 81.49243 -400.522963) (xy 81.542 -400.500322) (xy 81.594288 -400.484966)
			(xy 81.64823 -400.477208) (xy 81.675478 -400.47672) (xy 82.539078 -400.47672) (xy 82.566334 -400.477125)
			(xy 82.620291 -400.48488) (xy 82.672596 -400.500236) (xy 82.722182 -400.522879) (xy 82.768042 -400.552348)
			(xy 82.80924 -400.588045) (xy 82.844939 -400.629241) (xy 82.874411 -400.675098) (xy 82.897057 -400.724684)
			(xy 82.912415 -400.776987) (xy 82.920173 -400.830944) (xy 82.920173 -400.885452) (xy 84.357683 -400.885452)
			(xy 84.357683 -400.830948) (xy 84.36544 -400.777) (xy 84.380796 -400.724704) (xy 84.403438 -400.675127)
			(xy 84.432906 -400.629276) (xy 84.468599 -400.588086) (xy 84.50979 -400.552395) (xy 84.555642 -400.52293)
			(xy 84.605221 -400.50029) (xy 84.657517 -400.484936) (xy 84.711466 -400.477182) (xy 84.738718 -400.47672)
			(xy 85.602318 -400.47672) (xy 85.62957 -400.477151) (xy 85.68352 -400.48491) (xy 85.735817 -400.500268)
			(xy 85.785395 -400.522912) (xy 85.831247 -400.552381) (xy 85.872438 -400.588075) (xy 85.90813 -400.629268)
			(xy 85.937597 -400.675121) (xy 85.960238 -400.7247) (xy 85.975594 -400.776997) (xy 85.98335 -400.830948)
			(xy 85.98335 -400.885447) (xy 87.421006 -400.885447) (xy 87.421006 -400.830953) (xy 87.428761 -400.777013)
			(xy 87.444113 -400.724725) (xy 87.466749 -400.675154) (xy 87.496209 -400.629309) (xy 87.531894 -400.588123)
			(xy 87.573076 -400.552435) (xy 87.618918 -400.522969) (xy 87.668486 -400.500327) (xy 87.720772 -400.48497)
			(xy 87.774711 -400.477209) (xy 87.801958 -400.47672) (xy 88.665558 -400.47672) (xy 88.692815 -400.477124)
			(xy 88.746774 -400.484877) (xy 88.799081 -400.50023) (xy 88.84867 -400.522872) (xy 88.894532 -400.552341)
			(xy 88.935733 -400.588037) (xy 88.971434 -400.629234) (xy 89.000908 -400.675093) (xy 89.023555 -400.724679)
			(xy 89.038914 -400.776985) (xy 89.046673 -400.830943) (xy 89.046673 -400.885449) (xy 90.484206 -400.885449)
			(xy 90.484206 -400.830951) (xy 90.491962 -400.777007) (xy 90.507316 -400.724717) (xy 90.529955 -400.675143)
			(xy 90.559419 -400.629296) (xy 90.595108 -400.588109) (xy 90.636295 -400.55242) (xy 90.682142 -400.522956)
			(xy 90.731715 -400.500317) (xy 90.784005 -400.484963) (xy 90.837949 -400.477206) (xy 90.865198 -400.47672)
			(xy 91.728798 -400.47672) (xy 91.756053 -400.477127) (xy 91.810008 -400.484884) (xy 91.86231 -400.500241)
			(xy 91.911894 -400.522885) (xy 91.957751 -400.552355) (xy 91.998947 -400.588052) (xy 92.034643 -400.629247)
			(xy 92.064114 -400.675104) (xy 92.086758 -400.724688) (xy 92.102115 -400.77699) (xy 92.109873 -400.830945)
			(xy 92.109873 -400.885453) (xy 93.547383 -400.885453) (xy 93.547383 -400.830947) (xy 93.555141 -400.776997)
			(xy 93.570498 -400.7247) (xy 93.593141 -400.675121) (xy 93.622611 -400.629269) (xy 93.658306 -400.588079)
			(xy 93.6995 -400.552388) (xy 93.745354 -400.522923) (xy 93.794936 -400.500284) (xy 93.847234 -400.484933)
			(xy 93.901185 -400.477181) (xy 93.928438 -400.47672) (xy 94.792038 -400.47672) (xy 94.819289 -400.477152)
			(xy 94.873237 -400.484914) (xy 94.925531 -400.500273) (xy 94.975107 -400.522918) (xy 95.020956 -400.552388)
			(xy 95.062145 -400.588082) (xy 95.097835 -400.629274) (xy 95.1273 -400.675126) (xy 95.14994 -400.724705)
			(xy 95.165294 -400.777) (xy 95.17305 -400.830948) (xy 95.17305 -400.885447) (xy 119.774006 -400.885447)
			(xy 119.774006 -400.830953) (xy 119.781761 -400.777013) (xy 119.797112 -400.724726) (xy 119.819749 -400.675156)
			(xy 119.849208 -400.629311) (xy 119.884892 -400.588125) (xy 119.926074 -400.552436) (xy 119.971915 -400.522971)
			(xy 120.021483 -400.500329) (xy 120.073768 -400.484971) (xy 120.127707 -400.477209) (xy 120.154954 -400.47672)
			(xy 121.018554 -400.47672) (xy 121.045811 -400.477124) (xy 121.099771 -400.484876) (xy 121.152078 -400.500229)
			(xy 121.201668 -400.522871) (xy 121.24753 -400.55234) (xy 121.288731 -400.588036) (xy 121.324433 -400.629233)
			(xy 121.353907 -400.675092) (xy 121.376555 -400.724679) (xy 121.391914 -400.776984) (xy 121.399673 -400.830943)
			(xy 121.399673 -400.885449) (xy 122.837206 -400.885449) (xy 122.837206 -400.830951) (xy 122.844962 -400.777008)
			(xy 122.860316 -400.724717) (xy 122.882955 -400.675144) (xy 122.912418 -400.629298) (xy 122.948106 -400.588111)
			(xy 122.989293 -400.552422) (xy 123.035139 -400.522958) (xy 123.084712 -400.500318) (xy 123.137002 -400.484963)
			(xy 123.190945 -400.477207) (xy 123.218194 -400.47672) (xy 124.081794 -400.47672) (xy 124.109049 -400.477127)
			(xy 124.163005 -400.484883) (xy 124.215307 -400.50024) (xy 124.264892 -400.522884) (xy 124.310749 -400.552354)
			(xy 124.351946 -400.58805) (xy 124.387643 -400.629246) (xy 124.417113 -400.675103) (xy 124.439758 -400.724687)
			(xy 124.455115 -400.776989) (xy 124.462873 -400.830945) (xy 124.462873 -400.885452) (xy 125.900383 -400.885452)
			(xy 125.900383 -400.830948) (xy 125.908141 -400.776998) (xy 125.923497 -400.724701) (xy 125.946141 -400.675122)
			(xy 125.97561 -400.629271) (xy 126.011304 -400.58808) (xy 126.052498 -400.552389) (xy 126.098352 -400.522924)
			(xy 126.147933 -400.500285) (xy 126.200231 -400.484933) (xy 126.254182 -400.477181) (xy 126.281434 -400.47672)
			(xy 127.145034 -400.47672) (xy 127.172286 -400.477152) (xy 127.226234 -400.484913) (xy 127.278528 -400.500272)
			(xy 127.328105 -400.522917) (xy 127.373954 -400.552386) (xy 127.415143 -400.588081) (xy 127.450834 -400.629273)
			(xy 127.480299 -400.675125) (xy 127.50294 -400.724704) (xy 127.518294 -400.777) (xy 127.52605 -400.830948)
			(xy 127.52605 -400.885448) (xy 128.963706 -400.885448) (xy 128.963706 -400.830952) (xy 128.971461 -400.777011)
			(xy 128.986814 -400.724722) (xy 129.009452 -400.67515) (xy 129.038913 -400.629304) (xy 129.074599 -400.588118)
			(xy 129.115783 -400.552429) (xy 129.161627 -400.522964) (xy 129.211197 -400.500323) (xy 129.263485 -400.484967)
			(xy 129.317426 -400.477208) (xy 129.344674 -400.47672) (xy 130.208274 -400.47672) (xy 130.23553 -400.477125)
			(xy 130.289488 -400.48488) (xy 130.341793 -400.500235) (xy 130.39138 -400.522877) (xy 130.43724 -400.552347)
			(xy 130.478438 -400.588043) (xy 130.514138 -400.62924) (xy 130.54361 -400.675097) (xy 130.566256 -400.724683)
			(xy 130.581615 -400.776987) (xy 130.589373 -400.830944) (xy 130.589373 -400.885451) (xy 132.026883 -400.885451)
			(xy 132.026883 -400.830949) (xy 132.03464 -400.777) (xy 132.049996 -400.724705) (xy 132.072638 -400.675128)
			(xy 132.102105 -400.629277) (xy 132.137797 -400.588087) (xy 132.178989 -400.552396) (xy 132.22484 -400.522931)
			(xy 132.274418 -400.500291) (xy 132.326714 -400.484937) (xy 132.380662 -400.477182) (xy 132.407914 -400.47672)
			(xy 133.271514 -400.47672) (xy 133.298767 -400.477151) (xy 133.352717 -400.48491) (xy 133.405014 -400.500267)
			(xy 133.454593 -400.522911) (xy 133.500445 -400.552379) (xy 133.541636 -400.588074) (xy 133.577329 -400.629266)
			(xy 133.606796 -400.67512) (xy 133.629438 -400.724699) (xy 133.644793 -400.776997) (xy 133.65255 -400.830947)
			(xy 133.65255 -400.885447) (xy 135.090206 -400.885447) (xy 135.090206 -400.830953) (xy 135.097961 -400.777013)
			(xy 135.113312 -400.724726) (xy 135.135949 -400.675156) (xy 135.165408 -400.629311) (xy 135.201092 -400.588125)
			(xy 135.242274 -400.552436) (xy 135.288115 -400.522971) (xy 135.337683 -400.500329) (xy 135.389968 -400.484971)
			(xy 135.443907 -400.477209) (xy 135.471154 -400.47672) (xy 136.334754 -400.47672) (xy 136.362011 -400.477124)
			(xy 136.415971 -400.484876) (xy 136.468278 -400.500229) (xy 136.517868 -400.522871) (xy 136.56373 -400.55234)
			(xy 136.604931 -400.588036) (xy 136.640633 -400.629233) (xy 136.670107 -400.675092) (xy 136.692755 -400.724679)
			(xy 136.708114 -400.776984) (xy 136.715873 -400.830943) (xy 136.715873 -400.885449) (xy 138.153406 -400.885449)
			(xy 138.153406 -400.830951) (xy 138.161162 -400.777008) (xy 138.176516 -400.724717) (xy 138.199155 -400.675144)
			(xy 138.228618 -400.629298) (xy 138.264306 -400.588111) (xy 138.305493 -400.552422) (xy 138.351339 -400.522958)
			(xy 138.400912 -400.500318) (xy 138.453202 -400.484963) (xy 138.507145 -400.477207) (xy 138.534394 -400.47672)
			(xy 139.397994 -400.47672) (xy 139.425249 -400.477127) (xy 139.479205 -400.484883) (xy 139.531507 -400.50024)
			(xy 139.581092 -400.522884) (xy 139.626949 -400.552354) (xy 139.668146 -400.58805) (xy 139.703843 -400.629246)
			(xy 139.733313 -400.675103) (xy 139.755958 -400.724687) (xy 139.771315 -400.776989) (xy 139.779073 -400.830945)
			(xy 139.779073 -400.885452) (xy 141.216583 -400.885452) (xy 141.216583 -400.830948) (xy 141.224341 -400.776998)
			(xy 141.239697 -400.724701) (xy 141.262341 -400.675122) (xy 141.29181 -400.629271) (xy 141.327504 -400.58808)
			(xy 141.368698 -400.552389) (xy 141.414552 -400.522924) (xy 141.464133 -400.500285) (xy 141.516431 -400.484933)
			(xy 141.570382 -400.477181) (xy 141.597634 -400.47672) (xy 142.461234 -400.47672) (xy 142.488486 -400.477152)
			(xy 142.542434 -400.484913) (xy 142.594728 -400.500272) (xy 142.644305 -400.522917) (xy 142.690154 -400.552386)
			(xy 142.731343 -400.588081) (xy 142.767034 -400.629273) (xy 142.796499 -400.675125) (xy 142.81914 -400.724704)
			(xy 142.834494 -400.777) (xy 142.84225 -400.830948) (xy 142.84225 -400.885448) (xy 144.279906 -400.885448)
			(xy 144.279906 -400.830952) (xy 144.287661 -400.777011) (xy 144.303014 -400.724722) (xy 144.325652 -400.67515)
			(xy 144.355113 -400.629304) (xy 144.390799 -400.588118) (xy 144.431983 -400.552429) (xy 144.477827 -400.522964)
			(xy 144.527397 -400.500323) (xy 144.579685 -400.484967) (xy 144.633626 -400.477208) (xy 144.660874 -400.47672)
			(xy 145.524474 -400.47672) (xy 145.55173 -400.477125) (xy 145.605688 -400.48488) (xy 145.657993 -400.500235)
			(xy 145.70758 -400.522877) (xy 145.75344 -400.552347) (xy 145.794638 -400.588043) (xy 145.830338 -400.62924)
			(xy 145.85981 -400.675097) (xy 145.882456 -400.724683) (xy 145.897815 -400.776987) (xy 145.905573 -400.830944)
			(xy 145.905573 -400.885451) (xy 147.343083 -400.885451) (xy 147.343083 -400.830949) (xy 147.35084 -400.777)
			(xy 147.366196 -400.724705) (xy 147.388838 -400.675128) (xy 147.418305 -400.629277) (xy 147.453997 -400.588087)
			(xy 147.495189 -400.552396) (xy 147.54104 -400.522931) (xy 147.590618 -400.500291) (xy 147.642914 -400.484937)
			(xy 147.696862 -400.477182) (xy 147.724114 -400.47672) (xy 148.587714 -400.47672) (xy 148.614967 -400.477151)
			(xy 148.668917 -400.48491) (xy 148.721214 -400.500267) (xy 148.770793 -400.522911) (xy 148.816645 -400.552379)
			(xy 148.857836 -400.588074) (xy 148.893529 -400.629266) (xy 148.922996 -400.67512) (xy 148.945638 -400.724699)
			(xy 148.960993 -400.776997) (xy 148.96875 -400.830947) (xy 148.96875 -400.885447) (xy 150.406406 -400.885447)
			(xy 150.406406 -400.830953) (xy 150.414161 -400.777013) (xy 150.429512 -400.724726) (xy 150.452149 -400.675156)
			(xy 150.481608 -400.629311) (xy 150.517292 -400.588125) (xy 150.558474 -400.552436) (xy 150.604315 -400.522971)
			(xy 150.653883 -400.500329) (xy 150.706168 -400.484971) (xy 150.760107 -400.477209) (xy 150.787354 -400.47672)
			(xy 151.650954 -400.47672) (xy 151.678211 -400.477124) (xy 151.732171 -400.484876) (xy 151.784478 -400.500229)
			(xy 151.834068 -400.522871) (xy 151.87993 -400.55234) (xy 151.921131 -400.588036) (xy 151.956833 -400.629233)
			(xy 151.986307 -400.675092) (xy 152.008955 -400.724679) (xy 152.024314 -400.776984) (xy 152.032073 -400.830943)
			(xy 152.032073 -400.885449) (xy 153.469606 -400.885449) (xy 153.469606 -400.830951) (xy 153.477362 -400.777008)
			(xy 153.492716 -400.724717) (xy 153.515355 -400.675144) (xy 153.544818 -400.629298) (xy 153.580506 -400.588111)
			(xy 153.621693 -400.552422) (xy 153.667539 -400.522958) (xy 153.717112 -400.500318) (xy 153.769402 -400.484963)
			(xy 153.823345 -400.477207) (xy 153.850594 -400.47672) (xy 154.714194 -400.47672) (xy 154.741449 -400.477127)
			(xy 154.795405 -400.484883) (xy 154.847707 -400.50024) (xy 154.897292 -400.522884) (xy 154.943149 -400.552354)
			(xy 154.984346 -400.58805) (xy 155.020043 -400.629246) (xy 155.049513 -400.675103) (xy 155.072158 -400.724687)
			(xy 155.087515 -400.776989) (xy 155.095273 -400.830945) (xy 155.095273 -400.885452) (xy 156.532783 -400.885452)
			(xy 156.532783 -400.830948) (xy 156.540541 -400.776998) (xy 156.555897 -400.724701) (xy 156.578541 -400.675122)
			(xy 156.60801 -400.629271) (xy 156.643704 -400.58808) (xy 156.684898 -400.552389) (xy 156.730752 -400.522924)
			(xy 156.780333 -400.500285) (xy 156.832631 -400.484933) (xy 156.886582 -400.477181) (xy 156.913834 -400.47672)
			(xy 157.777434 -400.47672) (xy 157.804686 -400.477152) (xy 157.858634 -400.484913) (xy 157.910928 -400.500272)
			(xy 157.960505 -400.522917) (xy 158.006354 -400.552386) (xy 158.047543 -400.588081) (xy 158.083234 -400.629273)
			(xy 158.112699 -400.675125) (xy 158.13534 -400.724704) (xy 158.150694 -400.777) (xy 158.15845 -400.830948)
			(xy 158.15845 -400.885448) (xy 159.596106 -400.885448) (xy 159.596106 -400.830952) (xy 159.603861 -400.777011)
			(xy 159.619214 -400.724722) (xy 159.641852 -400.67515) (xy 159.671313 -400.629304) (xy 159.706999 -400.588118)
			(xy 159.748183 -400.552429) (xy 159.794027 -400.522964) (xy 159.843597 -400.500323) (xy 159.895885 -400.484967)
			(xy 159.949826 -400.477208) (xy 159.977074 -400.47672) (xy 160.840674 -400.47672) (xy 160.86793 -400.477125)
			(xy 160.921888 -400.48488) (xy 160.974193 -400.500235) (xy 161.02378 -400.522877) (xy 161.06964 -400.552347)
			(xy 161.110838 -400.588043) (xy 161.146538 -400.62924) (xy 161.17601 -400.675097) (xy 161.198656 -400.724683)
			(xy 161.214015 -400.776987) (xy 161.221773 -400.830944) (xy 161.221773 -400.885451) (xy 162.659283 -400.885451)
			(xy 162.659283 -400.830949) (xy 162.66704 -400.777) (xy 162.682396 -400.724705) (xy 162.705038 -400.675128)
			(xy 162.734505 -400.629277) (xy 162.770197 -400.588087) (xy 162.811389 -400.552396) (xy 162.85724 -400.522931)
			(xy 162.906818 -400.500291) (xy 162.959114 -400.484937) (xy 163.013062 -400.477182) (xy 163.040314 -400.47672)
			(xy 163.903914 -400.47672) (xy 163.931167 -400.477151) (xy 163.985117 -400.48491) (xy 164.037414 -400.500267)
			(xy 164.086993 -400.522911) (xy 164.132845 -400.552379) (xy 164.174036 -400.588074) (xy 164.209729 -400.629266)
			(xy 164.239196 -400.67512) (xy 164.261838 -400.724699) (xy 164.277193 -400.776997) (xy 164.28495 -400.830947)
			(xy 164.28495 -400.885447) (xy 165.722606 -400.885447) (xy 165.722606 -400.830953) (xy 165.730361 -400.777013)
			(xy 165.745712 -400.724726) (xy 165.768349 -400.675156) (xy 165.797808 -400.629311) (xy 165.833492 -400.588125)
			(xy 165.874674 -400.552436) (xy 165.920515 -400.522971) (xy 165.970083 -400.500329) (xy 166.022368 -400.484971)
			(xy 166.076307 -400.477209) (xy 166.103554 -400.47672) (xy 166.967154 -400.47672) (xy 166.994411 -400.477124)
			(xy 167.048371 -400.484876) (xy 167.100678 -400.500229) (xy 167.150268 -400.522871) (xy 167.19613 -400.55234)
			(xy 167.237331 -400.588036) (xy 167.273033 -400.629233) (xy 167.302507 -400.675092) (xy 167.325155 -400.724679)
			(xy 167.340514 -400.776984) (xy 167.348273 -400.830943) (xy 167.348273 -400.885457) (xy 167.340514 -400.939416)
			(xy 167.325155 -400.991721) (xy 167.302507 -401.041308) (xy 167.273033 -401.087167) (xy 167.237331 -401.128364)
			(xy 167.19613 -401.16406) (xy 167.150268 -401.193529) (xy 167.100678 -401.216171) (xy 167.048371 -401.231524)
			(xy 166.994411 -401.239276) (xy 166.967154 -401.239736) (xy 166.103554 -401.239736) (xy 166.076307 -401.239191)
			(xy 166.022368 -401.231429) (xy 165.970083 -401.216071) (xy 165.920515 -401.193429) (xy 165.874674 -401.163964)
			(xy 165.833492 -401.128275) (xy 165.797808 -401.087089) (xy 165.768349 -401.041244) (xy 165.745712 -400.991674)
			(xy 165.730361 -400.939387) (xy 165.722606 -400.885447) (xy 164.28495 -400.885447) (xy 164.28495 -400.885453)
			(xy 164.277193 -400.939403) (xy 164.261838 -400.991701) (xy 164.239196 -401.04128) (xy 164.209729 -401.087134)
			(xy 164.174036 -401.128326) (xy 164.132845 -401.164021) (xy 164.086993 -401.193489) (xy 164.037414 -401.216133)
			(xy 163.985117 -401.23149) (xy 163.931167 -401.239249) (xy 163.903914 -401.239736) (xy 163.040314 -401.239736)
			(xy 163.013062 -401.239218) (xy 162.959114 -401.231463) (xy 162.906818 -401.216109) (xy 162.85724 -401.193469)
			(xy 162.811389 -401.164004) (xy 162.770197 -401.128313) (xy 162.734505 -401.087123) (xy 162.705038 -401.041272)
			(xy 162.682396 -400.991695) (xy 162.66704 -400.9394) (xy 162.659283 -400.885451) (xy 161.221773 -400.885451)
			(xy 161.221773 -400.885456) (xy 161.214015 -400.939413) (xy 161.198656 -400.991717) (xy 161.17601 -401.041303)
			(xy 161.146538 -401.08716) (xy 161.110838 -401.128357) (xy 161.06964 -401.164053) (xy 161.02378 -401.193523)
			(xy 160.974193 -401.216165) (xy 160.921888 -401.23152) (xy 160.86793 -401.239275) (xy 160.840674 -401.239736)
			(xy 159.977074 -401.239736) (xy 159.949826 -401.239192) (xy 159.895885 -401.231433) (xy 159.843597 -401.216077)
			(xy 159.794027 -401.193436) (xy 159.748183 -401.163971) (xy 159.706999 -401.128282) (xy 159.671313 -401.087096)
			(xy 159.641852 -401.04125) (xy 159.619214 -400.991678) (xy 159.603861 -400.939389) (xy 159.596106 -400.885448)
			(xy 158.15845 -400.885448) (xy 158.15845 -400.885452) (xy 158.150694 -400.9394) (xy 158.13534 -400.991696)
			(xy 158.112699 -401.041275) (xy 158.083234 -401.087127) (xy 158.047543 -401.128319) (xy 158.006354 -401.164014)
			(xy 157.960505 -401.193483) (xy 157.910928 -401.216128) (xy 157.858634 -401.231487) (xy 157.804686 -401.239248)
			(xy 157.777434 -401.239736) (xy 156.913834 -401.239736) (xy 156.886582 -401.239219) (xy 156.832631 -401.231467)
			(xy 156.780333 -401.216115) (xy 156.730752 -401.193476) (xy 156.684898 -401.164011) (xy 156.643704 -401.12832)
			(xy 156.60801 -401.087129) (xy 156.578541 -401.041278) (xy 156.555897 -400.991699) (xy 156.540541 -400.939402)
			(xy 156.532783 -400.885452) (xy 155.095273 -400.885452) (xy 155.095273 -400.885455) (xy 155.087515 -400.939411)
			(xy 155.072158 -400.991713) (xy 155.049513 -401.041297) (xy 155.020043 -401.087154) (xy 154.984346 -401.12835)
			(xy 154.943149 -401.164046) (xy 154.897292 -401.193516) (xy 154.847707 -401.21616) (xy 154.795405 -401.231517)
			(xy 154.741449 -401.239273) (xy 154.714194 -401.239736) (xy 153.850594 -401.239736) (xy 153.823345 -401.239193)
			(xy 153.769402 -401.231437) (xy 153.717112 -401.216082) (xy 153.667539 -401.193442) (xy 153.621693 -401.163978)
			(xy 153.580506 -401.128289) (xy 153.544818 -401.087102) (xy 153.515355 -401.041256) (xy 153.492716 -400.991683)
			(xy 153.477362 -400.939392) (xy 153.469606 -400.885449) (xy 152.032073 -400.885449) (xy 152.032073 -400.885457)
			(xy 152.024314 -400.939416) (xy 152.008955 -400.991721) (xy 151.986307 -401.041308) (xy 151.956833 -401.087167)
			(xy 151.921131 -401.128364) (xy 151.87993 -401.16406) (xy 151.834068 -401.193529) (xy 151.784478 -401.216171)
			(xy 151.732171 -401.231524) (xy 151.678211 -401.239276) (xy 151.650954 -401.239736) (xy 150.787354 -401.239736)
			(xy 150.760107 -401.239191) (xy 150.706168 -401.231429) (xy 150.653883 -401.216071) (xy 150.604315 -401.193429)
			(xy 150.558474 -401.163964) (xy 150.517292 -401.128275) (xy 150.481608 -401.087089) (xy 150.452149 -401.041244)
			(xy 150.429512 -400.991674) (xy 150.414161 -400.939387) (xy 150.406406 -400.885447) (xy 148.96875 -400.885447)
			(xy 148.96875 -400.885453) (xy 148.960993 -400.939403) (xy 148.945638 -400.991701) (xy 148.922996 -401.04128)
			(xy 148.893529 -401.087134) (xy 148.857836 -401.128326) (xy 148.816645 -401.164021) (xy 148.770793 -401.193489)
			(xy 148.721214 -401.216133) (xy 148.668917 -401.23149) (xy 148.614967 -401.239249) (xy 148.587714 -401.239736)
			(xy 147.724114 -401.239736) (xy 147.696862 -401.239218) (xy 147.642914 -401.231463) (xy 147.590618 -401.216109)
			(xy 147.54104 -401.193469) (xy 147.495189 -401.164004) (xy 147.453997 -401.128313) (xy 147.418305 -401.087123)
			(xy 147.388838 -401.041272) (xy 147.366196 -400.991695) (xy 147.35084 -400.9394) (xy 147.343083 -400.885451)
			(xy 145.905573 -400.885451) (xy 145.905573 -400.885456) (xy 145.897815 -400.939413) (xy 145.882456 -400.991717)
			(xy 145.85981 -401.041303) (xy 145.830338 -401.08716) (xy 145.794638 -401.128357) (xy 145.75344 -401.164053)
			(xy 145.70758 -401.193523) (xy 145.657993 -401.216165) (xy 145.605688 -401.23152) (xy 145.55173 -401.239275)
			(xy 145.524474 -401.239736) (xy 144.660874 -401.239736) (xy 144.633626 -401.239192) (xy 144.579685 -401.231433)
			(xy 144.527397 -401.216077) (xy 144.477827 -401.193436) (xy 144.431983 -401.163971) (xy 144.390799 -401.128282)
			(xy 144.355113 -401.087096) (xy 144.325652 -401.04125) (xy 144.303014 -400.991678) (xy 144.287661 -400.939389)
			(xy 144.279906 -400.885448) (xy 142.84225 -400.885448) (xy 142.84225 -400.885452) (xy 142.834494 -400.9394)
			(xy 142.81914 -400.991696) (xy 142.796499 -401.041275) (xy 142.767034 -401.087127) (xy 142.731343 -401.128319)
			(xy 142.690154 -401.164014) (xy 142.644305 -401.193483) (xy 142.594728 -401.216128) (xy 142.542434 -401.231487)
			(xy 142.488486 -401.239248) (xy 142.461234 -401.239736) (xy 141.597634 -401.239736) (xy 141.570382 -401.239219)
			(xy 141.516431 -401.231467) (xy 141.464133 -401.216115) (xy 141.414552 -401.193476) (xy 141.368698 -401.164011)
			(xy 141.327504 -401.12832) (xy 141.29181 -401.087129) (xy 141.262341 -401.041278) (xy 141.239697 -400.991699)
			(xy 141.224341 -400.939402) (xy 141.216583 -400.885452) (xy 139.779073 -400.885452) (xy 139.779073 -400.885455)
			(xy 139.771315 -400.939411) (xy 139.755958 -400.991713) (xy 139.733313 -401.041297) (xy 139.703843 -401.087154)
			(xy 139.668146 -401.12835) (xy 139.626949 -401.164046) (xy 139.581092 -401.193516) (xy 139.531507 -401.21616)
			(xy 139.479205 -401.231517) (xy 139.425249 -401.239273) (xy 139.397994 -401.239736) (xy 138.534394 -401.239736)
			(xy 138.507145 -401.239193) (xy 138.453202 -401.231437) (xy 138.400912 -401.216082) (xy 138.351339 -401.193442)
			(xy 138.305493 -401.163978) (xy 138.264306 -401.128289) (xy 138.228618 -401.087102) (xy 138.199155 -401.041256)
			(xy 138.176516 -400.991683) (xy 138.161162 -400.939392) (xy 138.153406 -400.885449) (xy 136.715873 -400.885449)
			(xy 136.715873 -400.885457) (xy 136.708114 -400.939416) (xy 136.692755 -400.991721) (xy 136.670107 -401.041308)
			(xy 136.640633 -401.087167) (xy 136.604931 -401.128364) (xy 136.56373 -401.16406) (xy 136.517868 -401.193529)
			(xy 136.468278 -401.216171) (xy 136.415971 -401.231524) (xy 136.362011 -401.239276) (xy 136.334754 -401.239736)
			(xy 135.471154 -401.239736) (xy 135.443907 -401.239191) (xy 135.389968 -401.231429) (xy 135.337683 -401.216071)
			(xy 135.288115 -401.193429) (xy 135.242274 -401.163964) (xy 135.201092 -401.128275) (xy 135.165408 -401.087089)
			(xy 135.135949 -401.041244) (xy 135.113312 -400.991674) (xy 135.097961 -400.939387) (xy 135.090206 -400.885447)
			(xy 133.65255 -400.885447) (xy 133.65255 -400.885453) (xy 133.644793 -400.939403) (xy 133.629438 -400.991701)
			(xy 133.606796 -401.04128) (xy 133.577329 -401.087134) (xy 133.541636 -401.128326) (xy 133.500445 -401.164021)
			(xy 133.454593 -401.193489) (xy 133.405014 -401.216133) (xy 133.352717 -401.23149) (xy 133.298767 -401.239249)
			(xy 133.271514 -401.239736) (xy 132.407914 -401.239736) (xy 132.380662 -401.239218) (xy 132.326714 -401.231463)
			(xy 132.274418 -401.216109) (xy 132.22484 -401.193469) (xy 132.178989 -401.164004) (xy 132.137797 -401.128313)
			(xy 132.102105 -401.087123) (xy 132.072638 -401.041272) (xy 132.049996 -400.991695) (xy 132.03464 -400.9394)
			(xy 132.026883 -400.885451) (xy 130.589373 -400.885451) (xy 130.589373 -400.885456) (xy 130.581615 -400.939413)
			(xy 130.566256 -400.991717) (xy 130.54361 -401.041303) (xy 130.514138 -401.08716) (xy 130.478438 -401.128357)
			(xy 130.43724 -401.164053) (xy 130.39138 -401.193523) (xy 130.341793 -401.216165) (xy 130.289488 -401.23152)
			(xy 130.23553 -401.239275) (xy 130.208274 -401.239736) (xy 129.344674 -401.239736) (xy 129.317426 -401.239192)
			(xy 129.263485 -401.231433) (xy 129.211197 -401.216077) (xy 129.161627 -401.193436) (xy 129.115783 -401.163971)
			(xy 129.074599 -401.128282) (xy 129.038913 -401.087096) (xy 129.009452 -401.04125) (xy 128.986814 -400.991678)
			(xy 128.971461 -400.939389) (xy 128.963706 -400.885448) (xy 127.52605 -400.885448) (xy 127.52605 -400.885452)
			(xy 127.518294 -400.9394) (xy 127.50294 -400.991696) (xy 127.480299 -401.041275) (xy 127.450834 -401.087127)
			(xy 127.415143 -401.128319) (xy 127.373954 -401.164014) (xy 127.328105 -401.193483) (xy 127.278528 -401.216128)
			(xy 127.226234 -401.231487) (xy 127.172286 -401.239248) (xy 127.145034 -401.239736) (xy 126.281434 -401.239736)
			(xy 126.254182 -401.239219) (xy 126.200231 -401.231467) (xy 126.147933 -401.216115) (xy 126.098352 -401.193476)
			(xy 126.052498 -401.164011) (xy 126.011304 -401.12832) (xy 125.97561 -401.087129) (xy 125.946141 -401.041278)
			(xy 125.923497 -400.991699) (xy 125.908141 -400.939402) (xy 125.900383 -400.885452) (xy 124.462873 -400.885452)
			(xy 124.462873 -400.885455) (xy 124.455115 -400.939411) (xy 124.439758 -400.991713) (xy 124.417113 -401.041297)
			(xy 124.387643 -401.087154) (xy 124.351946 -401.12835) (xy 124.310749 -401.164046) (xy 124.264892 -401.193516)
			(xy 124.215307 -401.21616) (xy 124.163005 -401.231517) (xy 124.109049 -401.239273) (xy 124.081794 -401.239736)
			(xy 123.218194 -401.239736) (xy 123.190945 -401.239193) (xy 123.137002 -401.231437) (xy 123.084712 -401.216082)
			(xy 123.035139 -401.193442) (xy 122.989293 -401.163978) (xy 122.948106 -401.128289) (xy 122.912418 -401.087102)
			(xy 122.882955 -401.041256) (xy 122.860316 -400.991683) (xy 122.844962 -400.939392) (xy 122.837206 -400.885449)
			(xy 121.399673 -400.885449) (xy 121.399673 -400.885457) (xy 121.391914 -400.939416) (xy 121.376555 -400.991721)
			(xy 121.353907 -401.041308) (xy 121.324433 -401.087167) (xy 121.288731 -401.128364) (xy 121.24753 -401.16406)
			(xy 121.201668 -401.193529) (xy 121.152078 -401.216171) (xy 121.099771 -401.231524) (xy 121.045811 -401.239276)
			(xy 121.018554 -401.239736) (xy 120.154954 -401.239736) (xy 120.127707 -401.239191) (xy 120.073768 -401.231429)
			(xy 120.021483 -401.216071) (xy 119.971915 -401.193429) (xy 119.926074 -401.163964) (xy 119.884892 -401.128275)
			(xy 119.849208 -401.087089) (xy 119.819749 -401.041244) (xy 119.797112 -400.991674) (xy 119.781761 -400.939387)
			(xy 119.774006 -400.885447) (xy 95.17305 -400.885447) (xy 95.17305 -400.885452) (xy 95.165294 -400.9394)
			(xy 95.14994 -400.991695) (xy 95.1273 -401.041274) (xy 95.097835 -401.087126) (xy 95.062145 -401.128318)
			(xy 95.020956 -401.164012) (xy 94.975107 -401.193482) (xy 94.925531 -401.216127) (xy 94.873237 -401.231486)
			(xy 94.819289 -401.239248) (xy 94.792038 -401.239736) (xy 93.928438 -401.239736) (xy 93.901185 -401.239219)
			(xy 93.847234 -401.231467) (xy 93.794936 -401.216116) (xy 93.745354 -401.193477) (xy 93.6995 -401.164012)
			(xy 93.658306 -401.128321) (xy 93.622611 -401.087131) (xy 93.593141 -401.041279) (xy 93.570498 -400.9917)
			(xy 93.555141 -400.939403) (xy 93.547383 -400.885453) (xy 92.109873 -400.885453) (xy 92.109873 -400.885455)
			(xy 92.102115 -400.93941) (xy 92.086758 -400.991712) (xy 92.064114 -401.041296) (xy 92.034643 -401.087153)
			(xy 91.998947 -401.128348) (xy 91.957751 -401.164045) (xy 91.911894 -401.193515) (xy 91.86231 -401.216159)
			(xy 91.810008 -401.231516) (xy 91.756053 -401.239273) (xy 91.728798 -401.239736) (xy 90.865198 -401.239736)
			(xy 90.837949 -401.239194) (xy 90.784005 -401.231437) (xy 90.731715 -401.216083) (xy 90.682142 -401.193444)
			(xy 90.636295 -401.16398) (xy 90.595108 -401.128291) (xy 90.559419 -401.087104) (xy 90.529955 -401.041257)
			(xy 90.507316 -400.991683) (xy 90.491962 -400.939393) (xy 90.484206 -400.885449) (xy 89.046673 -400.885449)
			(xy 89.046673 -400.885457) (xy 89.038914 -400.939415) (xy 89.023555 -400.991721) (xy 89.000908 -401.041307)
			(xy 88.971434 -401.087166) (xy 88.935733 -401.128363) (xy 88.894532 -401.164059) (xy 88.84867 -401.193528)
			(xy 88.799081 -401.21617) (xy 88.746774 -401.231523) (xy 88.692815 -401.239276) (xy 88.665558 -401.239736)
			(xy 87.801958 -401.239736) (xy 87.774711 -401.239191) (xy 87.720772 -401.23143) (xy 87.668486 -401.216073)
			(xy 87.618918 -401.193431) (xy 87.573076 -401.163965) (xy 87.531894 -401.128277) (xy 87.496209 -401.087091)
			(xy 87.466749 -401.041246) (xy 87.444113 -400.991675) (xy 87.428761 -400.939387) (xy 87.421006 -400.885447)
			(xy 85.98335 -400.885447) (xy 85.98335 -400.885452) (xy 85.975594 -400.939403) (xy 85.960238 -400.9917)
			(xy 85.937597 -401.041279) (xy 85.90813 -401.087132) (xy 85.872438 -401.128325) (xy 85.831247 -401.164019)
			(xy 85.785395 -401.193488) (xy 85.735817 -401.216132) (xy 85.68352 -401.23149) (xy 85.62957 -401.239249)
			(xy 85.602318 -401.239736) (xy 84.738718 -401.239736) (xy 84.711466 -401.239218) (xy 84.657517 -401.231464)
			(xy 84.605221 -401.21611) (xy 84.555642 -401.19347) (xy 84.50979 -401.164005) (xy 84.468599 -401.128314)
			(xy 84.432906 -401.087124) (xy 84.403438 -401.041273) (xy 84.380796 -400.991696) (xy 84.36544 -400.9394)
			(xy 84.357683 -400.885452) (xy 82.920173 -400.885452) (xy 82.920173 -400.885456) (xy 82.912415 -400.939413)
			(xy 82.897057 -400.991716) (xy 82.874411 -401.041302) (xy 82.844939 -401.087159) (xy 82.80924 -401.128355)
			(xy 82.768042 -401.164052) (xy 82.722182 -401.193521) (xy 82.672596 -401.216164) (xy 82.620291 -401.23152)
			(xy 82.566334 -401.239275) (xy 82.539078 -401.239736) (xy 81.675478 -401.239736) (xy 81.64823 -401.239192)
			(xy 81.594288 -401.231434) (xy 81.542 -401.216078) (xy 81.49243 -401.193437) (xy 81.446585 -401.163973)
			(xy 81.405401 -401.128284) (xy 81.369714 -401.087097) (xy 81.340252 -401.041251) (xy 81.317614 -400.991679)
			(xy 81.302262 -400.93939) (xy 81.294506 -400.885448) (xy 79.85685 -400.885448) (xy 79.85685 -400.885452)
			(xy 79.849094 -400.9394) (xy 79.83374 -400.991695) (xy 79.8111 -401.041274) (xy 79.781635 -401.087126)
			(xy 79.745945 -401.128318) (xy 79.704756 -401.164012) (xy 79.658907 -401.193482) (xy 79.609331 -401.216127)
			(xy 79.557037 -401.231486) (xy 79.503089 -401.239248) (xy 79.475838 -401.239736) (xy 78.612238 -401.239736)
			(xy 78.584985 -401.239219) (xy 78.531034 -401.231467) (xy 78.478736 -401.216116) (xy 78.429154 -401.193477)
			(xy 78.3833 -401.164012) (xy 78.342106 -401.128321) (xy 78.306411 -401.087131) (xy 78.276941 -401.041279)
			(xy 78.254298 -400.9917) (xy 78.238941 -400.939403) (xy 78.231183 -400.885453) (xy 76.793673 -400.885453)
			(xy 76.793673 -400.885455) (xy 76.785915 -400.93941) (xy 76.770558 -400.991712) (xy 76.747914 -401.041296)
			(xy 76.718443 -401.087153) (xy 76.682747 -401.128348) (xy 76.641551 -401.164045) (xy 76.595694 -401.193515)
			(xy 76.54611 -401.216159) (xy 76.493808 -401.231516) (xy 76.439853 -401.239273) (xy 76.412598 -401.239736)
			(xy 75.548998 -401.239736) (xy 75.521749 -401.239194) (xy 75.467805 -401.231437) (xy 75.415515 -401.216083)
			(xy 75.365942 -401.193444) (xy 75.320095 -401.16398) (xy 75.278908 -401.128291) (xy 75.243219 -401.087104)
			(xy 75.213755 -401.041257) (xy 75.191116 -400.991683) (xy 75.175762 -400.939393) (xy 75.168006 -400.885449)
			(xy 73.730473 -400.885449) (xy 73.730473 -400.885457) (xy 73.722714 -400.939415) (xy 73.707355 -400.991721)
			(xy 73.684708 -401.041307) (xy 73.655234 -401.087166) (xy 73.619533 -401.128363) (xy 73.578332 -401.164059)
			(xy 73.53247 -401.193528) (xy 73.482881 -401.21617) (xy 73.430574 -401.231523) (xy 73.376615 -401.239276)
			(xy 73.349358 -401.239736) (xy 72.485758 -401.239736) (xy 72.458511 -401.239191) (xy 72.404572 -401.23143)
			(xy 72.352286 -401.216073) (xy 72.302718 -401.193431) (xy 72.256876 -401.163965) (xy 72.215694 -401.128277)
			(xy 72.180009 -401.087091) (xy 72.150549 -401.041246) (xy 72.127913 -400.991675) (xy 72.112561 -400.939387)
			(xy 72.104806 -400.885447) (xy 70.66715 -400.885447) (xy 70.66715 -400.885452) (xy 70.659394 -400.939403)
			(xy 70.644038 -400.9917) (xy 70.621397 -401.041279) (xy 70.59193 -401.087132) (xy 70.556238 -401.128325)
			(xy 70.515047 -401.164019) (xy 70.469195 -401.193488) (xy 70.419617 -401.216132) (xy 70.36732 -401.23149)
			(xy 70.31337 -401.239249) (xy 70.286118 -401.239736) (xy 69.422518 -401.239736) (xy 69.395266 -401.239218)
			(xy 69.341317 -401.231464) (xy 69.289021 -401.21611) (xy 69.239442 -401.19347) (xy 69.19359 -401.164005)
			(xy 69.152399 -401.128314) (xy 69.116706 -401.087124) (xy 69.087238 -401.041273) (xy 69.064596 -400.991696)
			(xy 69.04924 -400.9394) (xy 69.041483 -400.885452) (xy 67.603973 -400.885452) (xy 67.603973 -400.885456)
			(xy 67.596215 -400.939413) (xy 67.580857 -400.991716) (xy 67.558211 -401.041302) (xy 67.528739 -401.087159)
			(xy 67.49304 -401.128355) (xy 67.451842 -401.164052) (xy 67.405982 -401.193521) (xy 67.356396 -401.216164)
			(xy 67.304091 -401.23152) (xy 67.250134 -401.239275) (xy 67.222878 -401.239736) (xy 66.359278 -401.239736)
			(xy 66.33203 -401.239192) (xy 66.278088 -401.231434) (xy 66.2258 -401.216078) (xy 66.17623 -401.193437)
			(xy 66.130385 -401.163973) (xy 66.089201 -401.128284) (xy 66.053514 -401.087097) (xy 66.024052 -401.041251)
			(xy 66.001414 -400.991679) (xy 65.986062 -400.93939) (xy 65.978306 -400.885448) (xy 64.54065 -400.885448)
			(xy 64.54065 -400.885452) (xy 64.532894 -400.9394) (xy 64.51754 -400.991695) (xy 64.4949 -401.041274)
			(xy 64.465435 -401.087126) (xy 64.429745 -401.128318) (xy 64.388556 -401.164012) (xy 64.342707 -401.193482)
			(xy 64.293131 -401.216127) (xy 64.240837 -401.231486) (xy 64.186889 -401.239248) (xy 64.159638 -401.239736)
			(xy 63.296038 -401.239736) (xy 63.268785 -401.239219) (xy 63.214834 -401.231467) (xy 63.162536 -401.216116)
			(xy 63.112954 -401.193477) (xy 63.0671 -401.164012) (xy 63.025906 -401.128321) (xy 62.990211 -401.087131)
			(xy 62.960741 -401.041279) (xy 62.938098 -400.9917) (xy 62.922741 -400.939403) (xy 62.914983 -400.885453)
			(xy 61.477473 -400.885453) (xy 61.477473 -400.885455) (xy 61.469715 -400.93941) (xy 61.454358 -400.991712)
			(xy 61.431714 -401.041296) (xy 61.402243 -401.087153) (xy 61.366547 -401.128348) (xy 61.325351 -401.164045)
			(xy 61.279494 -401.193515) (xy 61.22991 -401.216159) (xy 61.177608 -401.231516) (xy 61.123653 -401.239273)
			(xy 61.096398 -401.239736) (xy 60.232798 -401.239736) (xy 60.205549 -401.239194) (xy 60.151605 -401.231437)
			(xy 60.099315 -401.216083) (xy 60.049742 -401.193444) (xy 60.003895 -401.16398) (xy 59.962708 -401.128291)
			(xy 59.927019 -401.087104) (xy 59.897555 -401.041257) (xy 59.874916 -400.991683) (xy 59.859562 -400.939393)
			(xy 59.851806 -400.885449) (xy 58.414273 -400.885449) (xy 58.414273 -400.885457) (xy 58.406514 -400.939415)
			(xy 58.391155 -400.991721) (xy 58.368508 -401.041307) (xy 58.339034 -401.087166) (xy 58.303333 -401.128363)
			(xy 58.262132 -401.164059) (xy 58.21627 -401.193528) (xy 58.166681 -401.21617) (xy 58.114374 -401.231523)
			(xy 58.060415 -401.239276) (xy 58.033158 -401.239736) (xy 57.169558 -401.239736) (xy 57.142311 -401.239191)
			(xy 57.088372 -401.23143) (xy 57.036086 -401.216073) (xy 56.986518 -401.193431) (xy 56.940676 -401.163965)
			(xy 56.899494 -401.128277) (xy 56.863809 -401.087091) (xy 56.834349 -401.041246) (xy 56.811713 -400.991675)
			(xy 56.796361 -400.939387) (xy 56.788606 -400.885447) (xy 55.35095 -400.885447) (xy 55.35095 -400.885452)
			(xy 55.343194 -400.939403) (xy 55.327838 -400.9917) (xy 55.305197 -401.041279) (xy 55.27573 -401.087132)
			(xy 55.240038 -401.128325) (xy 55.198847 -401.164019) (xy 55.152995 -401.193488) (xy 55.103417 -401.216132)
			(xy 55.05112 -401.23149) (xy 54.99717 -401.239249) (xy 54.969918 -401.239736) (xy 54.106318 -401.239736)
			(xy 54.079066 -401.239218) (xy 54.025117 -401.231464) (xy 53.972821 -401.21611) (xy 53.923242 -401.19347)
			(xy 53.87739 -401.164005) (xy 53.836199 -401.128314) (xy 53.800506 -401.087124) (xy 53.771038 -401.041273)
			(xy 53.748396 -400.991696) (xy 53.73304 -400.9394) (xy 53.725283 -400.885452) (xy 52.287773 -400.885452)
			(xy 52.287773 -400.885456) (xy 52.280015 -400.939413) (xy 52.264657 -400.991716) (xy 52.242011 -401.041302)
			(xy 52.212539 -401.087159) (xy 52.17684 -401.128355) (xy 52.135642 -401.164052) (xy 52.089782 -401.193521)
			(xy 52.040196 -401.216164) (xy 51.987891 -401.23152) (xy 51.933934 -401.239275) (xy 51.906678 -401.239736)
			(xy 51.043078 -401.239736) (xy 51.01583 -401.239192) (xy 50.961888 -401.231434) (xy 50.9096 -401.216078)
			(xy 50.86003 -401.193437) (xy 50.814185 -401.163973) (xy 50.773001 -401.128284) (xy 50.737314 -401.087097)
			(xy 50.707852 -401.041251) (xy 50.685214 -400.991679) (xy 50.669862 -400.93939) (xy 50.662106 -400.885448)
			(xy 49.22445 -400.885448) (xy 49.22445 -400.885452) (xy 49.216694 -400.9394) (xy 49.20134 -400.991695)
			(xy 49.1787 -401.041274) (xy 49.149235 -401.087126) (xy 49.113545 -401.128318) (xy 49.072356 -401.164012)
			(xy 49.026507 -401.193482) (xy 48.976931 -401.216127) (xy 48.924637 -401.231486) (xy 48.870689 -401.239248)
			(xy 48.843438 -401.239736) (xy 47.979838 -401.239736) (xy 47.952585 -401.239219) (xy 47.898634 -401.231467)
			(xy 47.846336 -401.216116) (xy 47.796754 -401.193477) (xy 47.7509 -401.164012) (xy 47.709706 -401.128321)
			(xy 47.674011 -401.087131) (xy 47.644541 -401.041279) (xy 47.621898 -400.9917) (xy 47.606541 -400.939403)
			(xy 47.598783 -400.885453) (xy 3.523996 -400.885453) (xy 3.523996 -402.656674) (xy 98.152872 -402.656674)
			(xy 98.152872 -402.602126) (xy 98.160635 -402.548133) (xy 98.176003 -402.495795) (xy 98.198664 -402.446176)
			(xy 98.228156 -402.400288) (xy 98.263878 -402.359064) (xy 98.305104 -402.323344) (xy 98.350994 -402.293855)
			(xy 98.400613 -402.271196) (xy 98.452953 -402.255831) (xy 98.506946 -402.24807) (xy 98.53422 -402.247608)
			(xy 99.39782 -402.247608) (xy 99.425086 -402.248156) (xy 99.479063 -402.255919) (xy 99.531387 -402.271285)
			(xy 99.58099 -402.293941) (xy 99.626865 -402.323425) (xy 99.668077 -402.359137) (xy 99.703787 -402.400351)
			(xy 99.733269 -402.446227) (xy 99.755922 -402.495832) (xy 99.771285 -402.548156) (xy 99.779046 -402.602134)
			(xy 99.779046 -402.656666) (xy 99.771285 -402.710644) (xy 99.755922 -402.762968) (xy 99.733269 -402.812573)
			(xy 99.703787 -402.858449) (xy 99.668077 -402.899663) (xy 99.626865 -402.935375) (xy 99.58099 -402.964859)
			(xy 99.531387 -402.987515) (xy 99.479063 -403.002881) (xy 99.425086 -403.010644) (xy 99.39782 -403.011132)
			(xy 98.53422 -403.011132) (xy 98.506946 -403.01073) (xy 98.452953 -403.002969) (xy 98.400613 -402.987604)
			(xy 98.350994 -402.964945) (xy 98.305104 -402.935456) (xy 98.263878 -402.899736) (xy 98.228156 -402.858512)
			(xy 98.198664 -402.812624) (xy 98.176003 -402.763005) (xy 98.160635 -402.710667) (xy 98.152872 -402.656674)
			(xy 3.523996 -402.656674) (xy 3.523996 -403.371812) (xy 3.524525 -403.402954) (xy 3.532689 -403.464702)
			(xy 3.548837 -403.524857) (xy 3.572694 -403.582392) (xy 3.603851 -403.636324) (xy 3.641776 -403.685732)
			(xy 3.663442 -403.708108) (xy 3.86649 -403.911156) (xy 47.598731 -403.911156) (xy 47.598731 -403.856644)
			(xy 47.606489 -403.802686) (xy 47.621848 -403.750382) (xy 47.644495 -403.700796) (xy 47.673969 -403.654938)
			(xy 47.709669 -403.613742) (xy 47.750868 -403.578046) (xy 47.796729 -403.548577) (xy 47.846317 -403.525935)
			(xy 47.898623 -403.510581) (xy 47.952582 -403.502828) (xy 47.979838 -403.502368) (xy 48.843438 -403.502368)
			(xy 48.870686 -403.502905) (xy 48.924626 -403.510665) (xy 48.976913 -403.526023) (xy 49.026482 -403.548665)
			(xy 49.072325 -403.57813) (xy 49.113508 -403.613819) (xy 49.149193 -403.655006) (xy 49.178654 -403.700851)
			(xy 49.201291 -403.750423) (xy 49.216643 -403.802711) (xy 49.224398 -403.856652) (xy 49.224398 -403.911148)
			(xy 49.224397 -403.911152) (xy 50.662054 -403.911152) (xy 50.662054 -403.856648) (xy 50.66981 -403.802699)
			(xy 50.685165 -403.750403) (xy 50.707806 -403.700824) (xy 50.737272 -403.654971) (xy 50.772964 -403.613779)
			(xy 50.814154 -403.578085) (xy 50.860004 -403.548617) (xy 50.909582 -403.525973) (xy 50.961877 -403.510615)
			(xy 51.015826 -403.502855) (xy 51.043078 -403.502368) (xy 51.906678 -403.502368) (xy 51.93393 -403.502878)
			(xy 51.98788 -403.510632) (xy 52.040177 -403.525985) (xy 52.089757 -403.548625) (xy 52.13561 -403.57809)
			(xy 52.176803 -403.613782) (xy 52.212497 -403.654972) (xy 52.241965 -403.700824) (xy 52.264607 -403.750402)
			(xy 52.279964 -403.802698) (xy 52.287721 -403.856648) (xy 52.287721 -403.911152) (xy 52.287721 -403.911155)
			(xy 53.725231 -403.911155) (xy 53.725231 -403.856645) (xy 53.732989 -403.802689) (xy 53.748347 -403.750386)
			(xy 53.770992 -403.700801) (xy 53.800464 -403.654945) (xy 53.836162 -403.613749) (xy 53.877359 -403.578053)
			(xy 53.923217 -403.548583) (xy 53.972803 -403.525941) (xy 54.025106 -403.510585) (xy 54.079063 -403.50283)
			(xy 54.106318 -403.502368) (xy 54.969918 -403.502368) (xy 54.997167 -403.502903) (xy 55.051109 -403.510662)
			(xy 55.103398 -403.526017) (xy 55.15297 -403.548658) (xy 55.198815 -403.578123) (xy 55.240001 -403.613812)
			(xy 55.275688 -403.654999) (xy 55.305151 -403.700846) (xy 55.327789 -403.750419) (xy 55.343142 -403.802709)
			(xy 55.350898 -403.856651) (xy 55.350898 -403.911149) (xy 55.350898 -403.911151) (xy 56.788554 -403.911151)
			(xy 56.788554 -403.856649) (xy 56.79631 -403.802702) (xy 56.811664 -403.750407) (xy 56.834303 -403.700829)
			(xy 56.863767 -403.654978) (xy 56.899457 -403.613786) (xy 56.940644 -403.578093) (xy 56.986492 -403.548623)
			(xy 57.036067 -403.525978) (xy 57.08836 -403.510619) (xy 57.142307 -403.502857) (xy 57.169558 -403.502368)
			(xy 58.033158 -403.502368) (xy 58.060411 -403.502876) (xy 58.114363 -403.510628) (xy 58.166663 -403.525979)
			(xy 58.216245 -403.548618) (xy 58.262101 -403.578083) (xy 58.303296 -403.613775) (xy 58.338992 -403.654966)
			(xy 58.368462 -403.700818) (xy 58.391106 -403.750398) (xy 58.406463 -403.802696) (xy 58.414221 -403.856647)
			(xy 58.414221 -403.911153) (xy 59.851754 -403.911153) (xy 59.851754 -403.856647) (xy 59.859511 -403.802696)
			(xy 59.874867 -403.750398) (xy 59.897509 -403.700818) (xy 59.926977 -403.654965) (xy 59.962671 -403.613772)
			(xy 60.003863 -403.578078) (xy 60.049716 -403.54861) (xy 60.099296 -403.525967) (xy 60.151594 -403.510611)
			(xy 60.205545 -403.502854) (xy 60.232798 -403.502368) (xy 61.096398 -403.502368) (xy 61.123649 -403.502879)
			(xy 61.177597 -403.510635) (xy 61.229892 -403.52599) (xy 61.279469 -403.548631) (xy 61.32532 -403.578097)
			(xy 61.36651 -403.613789) (xy 61.402201 -403.654979) (xy 61.431668 -403.700829) (xy 61.454309 -403.750406)
			(xy 61.469664 -403.802701) (xy 61.477421 -403.856649) (xy 61.477421 -403.911151) (xy 61.47742 -403.911156)
			(xy 62.914931 -403.911156) (xy 62.914931 -403.856644) (xy 62.922689 -403.802686) (xy 62.938048 -403.750382)
			(xy 62.960695 -403.700796) (xy 62.990169 -403.654938) (xy 63.025869 -403.613742) (xy 63.067068 -403.578046)
			(xy 63.112929 -403.548577) (xy 63.162517 -403.525935) (xy 63.214823 -403.510581) (xy 63.268782 -403.502828)
			(xy 63.296038 -403.502368) (xy 64.159638 -403.502368) (xy 64.186886 -403.502905) (xy 64.240826 -403.510665)
			(xy 64.293113 -403.526023) (xy 64.342682 -403.548665) (xy 64.388525 -403.57813) (xy 64.429708 -403.613819)
			(xy 64.465393 -403.655006) (xy 64.494854 -403.700851) (xy 64.517491 -403.750423) (xy 64.532843 -403.802711)
			(xy 64.540598 -403.856652) (xy 64.540598 -403.911148) (xy 64.540597 -403.911152) (xy 65.978254 -403.911152)
			(xy 65.978254 -403.856648) (xy 65.98601 -403.802699) (xy 66.001365 -403.750403) (xy 66.024006 -403.700824)
			(xy 66.053472 -403.654971) (xy 66.089164 -403.613779) (xy 66.130354 -403.578085) (xy 66.176204 -403.548617)
			(xy 66.225782 -403.525973) (xy 66.278077 -403.510615) (xy 66.332026 -403.502855) (xy 66.359278 -403.502368)
			(xy 67.222878 -403.502368) (xy 67.25013 -403.502878) (xy 67.30408 -403.510632) (xy 67.356377 -403.525985)
			(xy 67.405957 -403.548625) (xy 67.45181 -403.57809) (xy 67.493003 -403.613782) (xy 67.528697 -403.654972)
			(xy 67.558165 -403.700824) (xy 67.580807 -403.750402) (xy 67.596164 -403.802698) (xy 67.603921 -403.856648)
			(xy 67.603921 -403.911152) (xy 67.603921 -403.911155) (xy 69.041431 -403.911155) (xy 69.041431 -403.856645)
			(xy 69.049189 -403.802689) (xy 69.064547 -403.750386) (xy 69.087192 -403.700801) (xy 69.116664 -403.654945)
			(xy 69.152362 -403.613749) (xy 69.193559 -403.578053) (xy 69.239417 -403.548583) (xy 69.289003 -403.525941)
			(xy 69.341306 -403.510585) (xy 69.395263 -403.50283) (xy 69.422518 -403.502368) (xy 70.286118 -403.502368)
			(xy 70.313367 -403.502903) (xy 70.367309 -403.510662) (xy 70.419598 -403.526017) (xy 70.46917 -403.548658)
			(xy 70.515015 -403.578123) (xy 70.556201 -403.613812) (xy 70.591888 -403.654999) (xy 70.621351 -403.700846)
			(xy 70.643989 -403.750419) (xy 70.659342 -403.802709) (xy 70.667098 -403.856651) (xy 70.667098 -403.911149)
			(xy 70.667098 -403.911151) (xy 72.104754 -403.911151) (xy 72.104754 -403.856649) (xy 72.11251 -403.802702)
			(xy 72.127864 -403.750407) (xy 72.150503 -403.700829) (xy 72.179967 -403.654978) (xy 72.215657 -403.613786)
			(xy 72.256844 -403.578093) (xy 72.302692 -403.548623) (xy 72.352267 -403.525978) (xy 72.40456 -403.510619)
			(xy 72.458507 -403.502857) (xy 72.485758 -403.502368) (xy 73.349358 -403.502368) (xy 73.376611 -403.502876)
			(xy 73.430563 -403.510628) (xy 73.482863 -403.525979) (xy 73.532445 -403.548618) (xy 73.578301 -403.578083)
			(xy 73.619496 -403.613775) (xy 73.655192 -403.654966) (xy 73.684662 -403.700818) (xy 73.707306 -403.750398)
			(xy 73.722663 -403.802696) (xy 73.730421 -403.856647) (xy 73.730421 -403.911153) (xy 75.167954 -403.911153)
			(xy 75.167954 -403.856647) (xy 75.175711 -403.802696) (xy 75.191067 -403.750398) (xy 75.213709 -403.700818)
			(xy 75.243177 -403.654965) (xy 75.278871 -403.613772) (xy 75.320063 -403.578078) (xy 75.365916 -403.54861)
			(xy 75.415496 -403.525967) (xy 75.467794 -403.510611) (xy 75.521745 -403.502854) (xy 75.548998 -403.502368)
			(xy 76.412598 -403.502368) (xy 76.439849 -403.502879) (xy 76.493797 -403.510635) (xy 76.546092 -403.52599)
			(xy 76.595669 -403.548631) (xy 76.64152 -403.578097) (xy 76.68271 -403.613789) (xy 76.718401 -403.654979)
			(xy 76.747868 -403.700829) (xy 76.770509 -403.750406) (xy 76.785864 -403.802701) (xy 76.793621 -403.856649)
			(xy 76.793621 -403.911151) (xy 76.79362 -403.911156) (xy 78.231131 -403.911156) (xy 78.231131 -403.856644)
			(xy 78.238889 -403.802686) (xy 78.254248 -403.750382) (xy 78.276895 -403.700796) (xy 78.306369 -403.654938)
			(xy 78.342069 -403.613742) (xy 78.383268 -403.578046) (xy 78.429129 -403.548577) (xy 78.478717 -403.525935)
			(xy 78.531023 -403.510581) (xy 78.584982 -403.502828) (xy 78.612238 -403.502368) (xy 79.475838 -403.502368)
			(xy 79.503086 -403.502905) (xy 79.557026 -403.510665) (xy 79.609313 -403.526023) (xy 79.658882 -403.548665)
			(xy 79.704725 -403.57813) (xy 79.745908 -403.613819) (xy 79.781593 -403.655006) (xy 79.811054 -403.700851)
			(xy 79.833691 -403.750423) (xy 79.849043 -403.802711) (xy 79.856798 -403.856652) (xy 79.856798 -403.911148)
			(xy 79.856797 -403.911152) (xy 81.294454 -403.911152) (xy 81.294454 -403.856648) (xy 81.30221 -403.802699)
			(xy 81.317565 -403.750403) (xy 81.340206 -403.700824) (xy 81.369672 -403.654971) (xy 81.405364 -403.613779)
			(xy 81.446554 -403.578085) (xy 81.492404 -403.548617) (xy 81.541982 -403.525973) (xy 81.594277 -403.510615)
			(xy 81.648226 -403.502855) (xy 81.675478 -403.502368) (xy 82.539078 -403.502368) (xy 82.56633 -403.502878)
			(xy 82.62028 -403.510632) (xy 82.672577 -403.525985) (xy 82.722157 -403.548625) (xy 82.76801 -403.57809)
			(xy 82.809203 -403.613782) (xy 82.844897 -403.654972) (xy 82.874365 -403.700824) (xy 82.897007 -403.750402)
			(xy 82.912364 -403.802698) (xy 82.920121 -403.856648) (xy 82.920121 -403.911152) (xy 82.920121 -403.911155)
			(xy 84.357631 -403.911155) (xy 84.357631 -403.856645) (xy 84.365389 -403.802689) (xy 84.380747 -403.750386)
			(xy 84.403392 -403.700801) (xy 84.432864 -403.654945) (xy 84.468562 -403.613749) (xy 84.509759 -403.578053)
			(xy 84.555617 -403.548583) (xy 84.605203 -403.525941) (xy 84.657506 -403.510585) (xy 84.711463 -403.50283)
			(xy 84.738718 -403.502368) (xy 85.602318 -403.502368) (xy 85.629567 -403.502903) (xy 85.683509 -403.510662)
			(xy 85.735798 -403.526017) (xy 85.78537 -403.548658) (xy 85.831215 -403.578123) (xy 85.872401 -403.613812)
			(xy 85.908088 -403.654999) (xy 85.937551 -403.700846) (xy 85.960189 -403.750419) (xy 85.975542 -403.802709)
			(xy 85.983298 -403.856651) (xy 85.983298 -403.911149) (xy 85.983298 -403.911151) (xy 87.420954 -403.911151)
			(xy 87.420954 -403.856649) (xy 87.42871 -403.802702) (xy 87.444064 -403.750407) (xy 87.466703 -403.700829)
			(xy 87.496167 -403.654978) (xy 87.531857 -403.613786) (xy 87.573044 -403.578093) (xy 87.618892 -403.548623)
			(xy 87.668467 -403.525978) (xy 87.72076 -403.510619) (xy 87.774707 -403.502857) (xy 87.801958 -403.502368)
			(xy 88.665558 -403.502368) (xy 88.692811 -403.502876) (xy 88.746763 -403.510628) (xy 88.799063 -403.525979)
			(xy 88.848645 -403.548618) (xy 88.894501 -403.578083) (xy 88.935696 -403.613775) (xy 88.971392 -403.654966)
			(xy 89.000862 -403.700818) (xy 89.023506 -403.750398) (xy 89.038863 -403.802696) (xy 89.046621 -403.856647)
			(xy 89.046621 -403.911153) (xy 90.484154 -403.911153) (xy 90.484154 -403.856647) (xy 90.491911 -403.802696)
			(xy 90.507267 -403.750398) (xy 90.529909 -403.700818) (xy 90.559377 -403.654965) (xy 90.595071 -403.613772)
			(xy 90.636263 -403.578078) (xy 90.682116 -403.54861) (xy 90.731696 -403.525967) (xy 90.783994 -403.510611)
			(xy 90.837945 -403.502854) (xy 90.865198 -403.502368) (xy 91.728798 -403.502368) (xy 91.756049 -403.502879)
			(xy 91.809997 -403.510635) (xy 91.862292 -403.52599) (xy 91.911869 -403.548631) (xy 91.95772 -403.578097)
			(xy 91.99891 -403.613789) (xy 92.034601 -403.654979) (xy 92.064068 -403.700829) (xy 92.086709 -403.750406)
			(xy 92.102064 -403.802701) (xy 92.109821 -403.856649) (xy 92.109821 -403.911151) (xy 92.10982 -403.911156)
			(xy 93.547331 -403.911156) (xy 93.547331 -403.856644) (xy 93.555089 -403.802686) (xy 93.570448 -403.750382)
			(xy 93.593095 -403.700796) (xy 93.622569 -403.654938) (xy 93.658269 -403.613742) (xy 93.699468 -403.578046)
			(xy 93.745329 -403.548577) (xy 93.794917 -403.525935) (xy 93.847223 -403.510581) (xy 93.901182 -403.502828)
			(xy 93.928438 -403.502368) (xy 94.792038 -403.502368) (xy 94.819286 -403.502905) (xy 94.873226 -403.510665)
			(xy 94.925513 -403.526023) (xy 94.975082 -403.548665) (xy 95.020925 -403.57813) (xy 95.062108 -403.613819)
			(xy 95.097793 -403.655006) (xy 95.127254 -403.700851) (xy 95.149891 -403.750423) (xy 95.165243 -403.802711)
			(xy 95.172998 -403.856652) (xy 95.172998 -403.911148) (xy 95.172998 -403.911151) (xy 119.773954 -403.911151)
			(xy 119.773954 -403.856649) (xy 119.78171 -403.802702) (xy 119.797063 -403.750408) (xy 119.819702 -403.70083)
			(xy 119.849166 -403.654979) (xy 119.884855 -403.613788) (xy 119.926042 -403.578094) (xy 119.97189 -403.548625)
			(xy 120.021465 -403.525979) (xy 120.073757 -403.510619) (xy 120.127703 -403.502857) (xy 120.154954 -403.502368)
			(xy 121.018554 -403.502368) (xy 121.045807 -403.502876) (xy 121.09976 -403.510627) (xy 121.15206 -403.525978)
			(xy 121.201643 -403.548617) (xy 121.247499 -403.578082) (xy 121.288694 -403.613773) (xy 121.324391 -403.654964)
			(xy 121.353861 -403.700817) (xy 121.376506 -403.750397) (xy 121.391863 -403.802695) (xy 121.399621 -403.856647)
			(xy 121.399621 -403.911153) (xy 122.837154 -403.911153) (xy 122.837154 -403.856647) (xy 122.844911 -403.802697)
			(xy 122.860266 -403.750399) (xy 122.882909 -403.700819) (xy 122.912376 -403.654966) (xy 122.948069 -403.613774)
			(xy 122.989261 -403.57808) (xy 123.035114 -403.548611) (xy 123.084694 -403.525969) (xy 123.136991 -403.510612)
			(xy 123.190941 -403.502854) (xy 123.218194 -403.502368) (xy 124.081794 -403.502368) (xy 124.109045 -403.502879)
			(xy 124.162994 -403.510635) (xy 124.215289 -403.525989) (xy 124.264867 -403.54863) (xy 124.310718 -403.578096)
			(xy 124.351908 -403.613787) (xy 124.3876 -403.654978) (xy 124.417067 -403.700828) (xy 124.439709 -403.750406)
			(xy 124.455064 -403.802701) (xy 124.462821 -403.856649) (xy 124.462821 -403.911151) (xy 124.46282 -403.911156)
			(xy 125.900331 -403.911156) (xy 125.900331 -403.856644) (xy 125.908089 -403.802686) (xy 125.923448 -403.750383)
			(xy 125.946095 -403.700797) (xy 125.975568 -403.654939) (xy 126.011267 -403.613743) (xy 126.052467 -403.578047)
			(xy 126.098327 -403.548578) (xy 126.147914 -403.525936) (xy 126.20022 -403.510582) (xy 126.254178 -403.502829)
			(xy 126.281434 -403.502368) (xy 127.145034 -403.502368) (xy 127.172282 -403.502905) (xy 127.226223 -403.510664)
			(xy 127.27851 -403.526022) (xy 127.32808 -403.548663) (xy 127.373923 -403.578129) (xy 127.415106 -403.613818)
			(xy 127.450792 -403.655004) (xy 127.480253 -403.70085) (xy 127.50289 -403.750422) (xy 127.518243 -403.802711)
			(xy 127.525998 -403.856652) (xy 127.525998 -403.911148) (xy 127.525997 -403.911152) (xy 128.963654 -403.911152)
			(xy 128.963654 -403.856648) (xy 128.97141 -403.802699) (xy 128.986765 -403.750403) (xy 129.009406 -403.700825)
			(xy 129.038871 -403.654973) (xy 129.074562 -403.613781) (xy 129.115752 -403.578087) (xy 129.161602 -403.548618)
			(xy 129.211179 -403.525974) (xy 129.263474 -403.510616) (xy 129.317422 -403.502856) (xy 129.344674 -403.502368)
			(xy 130.208274 -403.502368) (xy 130.235526 -403.502878) (xy 130.289477 -403.510631) (xy 130.341774 -403.525984)
			(xy 130.391355 -403.548623) (xy 130.437208 -403.578089) (xy 130.478401 -403.61378) (xy 130.514096 -403.654971)
			(xy 130.543564 -403.700822) (xy 130.566207 -403.750401) (xy 130.581563 -403.802698) (xy 130.589321 -403.856648)
			(xy 130.589321 -403.911152) (xy 130.589321 -403.911155) (xy 132.026831 -403.911155) (xy 132.026831 -403.856645)
			(xy 132.034589 -403.802689) (xy 132.049946 -403.750387) (xy 132.072591 -403.700803) (xy 132.102063 -403.654946)
			(xy 132.13776 -403.61375) (xy 132.178957 -403.578054) (xy 132.224815 -403.548585) (xy 132.2744 -403.525942)
			(xy 132.326703 -403.510586) (xy 132.380659 -403.50283) (xy 132.407914 -403.502368) (xy 133.271514 -403.502368)
			(xy 133.298763 -403.502903) (xy 133.352706 -403.510661) (xy 133.404995 -403.526016) (xy 133.454568 -403.548657)
			(xy 133.500413 -403.578121) (xy 133.541599 -403.613811) (xy 133.577287 -403.654998) (xy 133.60675 -403.700845)
			(xy 133.629389 -403.750418) (xy 133.644742 -403.802708) (xy 133.652498 -403.856651) (xy 133.652498 -403.911149)
			(xy 133.652498 -403.911151) (xy 135.090154 -403.911151) (xy 135.090154 -403.856649) (xy 135.09791 -403.802702)
			(xy 135.113263 -403.750408) (xy 135.135902 -403.70083) (xy 135.165366 -403.654979) (xy 135.201055 -403.613788)
			(xy 135.242242 -403.578094) (xy 135.28809 -403.548625) (xy 135.337665 -403.525979) (xy 135.389957 -403.510619)
			(xy 135.443903 -403.502857) (xy 135.471154 -403.502368) (xy 136.334754 -403.502368) (xy 136.362007 -403.502876)
			(xy 136.41596 -403.510627) (xy 136.46826 -403.525978) (xy 136.517843 -403.548617) (xy 136.563699 -403.578082)
			(xy 136.604894 -403.613773) (xy 136.640591 -403.654964) (xy 136.670061 -403.700817) (xy 136.692706 -403.750397)
			(xy 136.708063 -403.802695) (xy 136.715821 -403.856647) (xy 136.715821 -403.911153) (xy 138.153354 -403.911153)
			(xy 138.153354 -403.856647) (xy 138.161111 -403.802697) (xy 138.176466 -403.750399) (xy 138.199109 -403.700819)
			(xy 138.228576 -403.654966) (xy 138.264269 -403.613774) (xy 138.305461 -403.57808) (xy 138.351314 -403.548611)
			(xy 138.400894 -403.525969) (xy 138.453191 -403.510612) (xy 138.507141 -403.502854) (xy 138.534394 -403.502368)
			(xy 139.397994 -403.502368) (xy 139.425245 -403.502879) (xy 139.479194 -403.510635) (xy 139.531489 -403.525989)
			(xy 139.581067 -403.54863) (xy 139.626918 -403.578096) (xy 139.668108 -403.613787) (xy 139.7038 -403.654978)
			(xy 139.733267 -403.700828) (xy 139.755909 -403.750406) (xy 139.771264 -403.802701) (xy 139.779021 -403.856649)
			(xy 139.779021 -403.911151) (xy 139.77902 -403.911156) (xy 141.216531 -403.911156) (xy 141.216531 -403.856644)
			(xy 141.224289 -403.802686) (xy 141.239648 -403.750383) (xy 141.262295 -403.700797) (xy 141.291768 -403.654939)
			(xy 141.327467 -403.613743) (xy 141.368667 -403.578047) (xy 141.414527 -403.548578) (xy 141.464114 -403.525936)
			(xy 141.51642 -403.510582) (xy 141.570378 -403.502829) (xy 141.597634 -403.502368) (xy 142.461234 -403.502368)
			(xy 142.488482 -403.502905) (xy 142.542423 -403.510664) (xy 142.59471 -403.526022) (xy 142.64428 -403.548663)
			(xy 142.690123 -403.578129) (xy 142.731306 -403.613818) (xy 142.766992 -403.655004) (xy 142.796453 -403.70085)
			(xy 142.81909 -403.750422) (xy 142.834443 -403.802711) (xy 142.842198 -403.856652) (xy 142.842198 -403.911148)
			(xy 142.842197 -403.911152) (xy 144.279854 -403.911152) (xy 144.279854 -403.856648) (xy 144.28761 -403.802699)
			(xy 144.302965 -403.750403) (xy 144.325606 -403.700825) (xy 144.355071 -403.654973) (xy 144.390762 -403.613781)
			(xy 144.431952 -403.578087) (xy 144.477802 -403.548618) (xy 144.527379 -403.525974) (xy 144.579674 -403.510616)
			(xy 144.633622 -403.502856) (xy 144.660874 -403.502368) (xy 145.524474 -403.502368) (xy 145.551726 -403.502878)
			(xy 145.605677 -403.510631) (xy 145.657974 -403.525984) (xy 145.707555 -403.548623) (xy 145.753408 -403.578089)
			(xy 145.794601 -403.61378) (xy 145.830296 -403.654971) (xy 145.859764 -403.700822) (xy 145.882407 -403.750401)
			(xy 145.897763 -403.802698) (xy 145.905521 -403.856648) (xy 145.905521 -403.911152) (xy 145.905521 -403.911155)
			(xy 147.343031 -403.911155) (xy 147.343031 -403.856645) (xy 147.350789 -403.802689) (xy 147.366146 -403.750387)
			(xy 147.388791 -403.700803) (xy 147.418263 -403.654946) (xy 147.45396 -403.61375) (xy 147.495157 -403.578054)
			(xy 147.541015 -403.548585) (xy 147.5906 -403.525942) (xy 147.642903 -403.510586) (xy 147.696859 -403.50283)
			(xy 147.724114 -403.502368) (xy 148.587714 -403.502368) (xy 148.614963 -403.502903) (xy 148.668906 -403.510661)
			(xy 148.721195 -403.526016) (xy 148.770768 -403.548657) (xy 148.816613 -403.578121) (xy 148.857799 -403.613811)
			(xy 148.893487 -403.654998) (xy 148.92295 -403.700845) (xy 148.945589 -403.750418) (xy 148.960942 -403.802708)
			(xy 148.968698 -403.856651) (xy 148.968698 -403.911149) (xy 148.968698 -403.911151) (xy 150.406354 -403.911151)
			(xy 150.406354 -403.856649) (xy 150.41411 -403.802702) (xy 150.429463 -403.750408) (xy 150.452102 -403.70083)
			(xy 150.481566 -403.654979) (xy 150.517255 -403.613788) (xy 150.558442 -403.578094) (xy 150.60429 -403.548625)
			(xy 150.653865 -403.525979) (xy 150.706157 -403.510619) (xy 150.760103 -403.502857) (xy 150.787354 -403.502368)
			(xy 151.650954 -403.502368) (xy 151.678207 -403.502876) (xy 151.73216 -403.510627) (xy 151.78446 -403.525978)
			(xy 151.834043 -403.548617) (xy 151.879899 -403.578082) (xy 151.921094 -403.613773) (xy 151.956791 -403.654964)
			(xy 151.986261 -403.700817) (xy 152.008906 -403.750397) (xy 152.024263 -403.802695) (xy 152.032021 -403.856647)
			(xy 152.032021 -403.911153) (xy 153.469554 -403.911153) (xy 153.469554 -403.856647) (xy 153.477311 -403.802697)
			(xy 153.492666 -403.750399) (xy 153.515309 -403.700819) (xy 153.544776 -403.654966) (xy 153.580469 -403.613774)
			(xy 153.621661 -403.57808) (xy 153.667514 -403.548611) (xy 153.717094 -403.525969) (xy 153.769391 -403.510612)
			(xy 153.823341 -403.502854) (xy 153.850594 -403.502368) (xy 154.714194 -403.502368) (xy 154.741445 -403.502879)
			(xy 154.795394 -403.510635) (xy 154.847689 -403.525989) (xy 154.897267 -403.54863) (xy 154.943118 -403.578096)
			(xy 154.984308 -403.613787) (xy 155.02 -403.654978) (xy 155.049467 -403.700828) (xy 155.072109 -403.750406)
			(xy 155.087464 -403.802701) (xy 155.095221 -403.856649) (xy 155.095221 -403.911151) (xy 155.09522 -403.911156)
			(xy 156.532731 -403.911156) (xy 156.532731 -403.856644) (xy 156.540489 -403.802686) (xy 156.555848 -403.750383)
			(xy 156.578495 -403.700797) (xy 156.607968 -403.654939) (xy 156.643667 -403.613743) (xy 156.684867 -403.578047)
			(xy 156.730727 -403.548578) (xy 156.780314 -403.525936) (xy 156.83262 -403.510582) (xy 156.886578 -403.502829)
			(xy 156.913834 -403.502368) (xy 157.777434 -403.502368) (xy 157.804682 -403.502905) (xy 157.858623 -403.510664)
			(xy 157.91091 -403.526022) (xy 157.96048 -403.548663) (xy 158.006323 -403.578129) (xy 158.047506 -403.613818)
			(xy 158.083192 -403.655004) (xy 158.112653 -403.70085) (xy 158.13529 -403.750422) (xy 158.150643 -403.802711)
			(xy 158.158398 -403.856652) (xy 158.158398 -403.911148) (xy 158.158397 -403.911152) (xy 159.596054 -403.911152)
			(xy 159.596054 -403.856648) (xy 159.60381 -403.802699) (xy 159.619165 -403.750403) (xy 159.641806 -403.700825)
			(xy 159.671271 -403.654973) (xy 159.706962 -403.613781) (xy 159.748152 -403.578087) (xy 159.794002 -403.548618)
			(xy 159.843579 -403.525974) (xy 159.895874 -403.510616) (xy 159.949822 -403.502856) (xy 159.977074 -403.502368)
			(xy 160.840674 -403.502368) (xy 160.867926 -403.502878) (xy 160.921877 -403.510631) (xy 160.974174 -403.525984)
			(xy 161.023755 -403.548623) (xy 161.069608 -403.578089) (xy 161.110801 -403.61378) (xy 161.146496 -403.654971)
			(xy 161.175964 -403.700822) (xy 161.198607 -403.750401) (xy 161.213963 -403.802698) (xy 161.221721 -403.856648)
			(xy 161.221721 -403.911152) (xy 161.221721 -403.911155) (xy 162.659231 -403.911155) (xy 162.659231 -403.856645)
			(xy 162.666989 -403.802689) (xy 162.682346 -403.750387) (xy 162.704991 -403.700803) (xy 162.734463 -403.654946)
			(xy 162.77016 -403.61375) (xy 162.811357 -403.578054) (xy 162.857215 -403.548585) (xy 162.9068 -403.525942)
			(xy 162.959103 -403.510586) (xy 163.013059 -403.50283) (xy 163.040314 -403.502368) (xy 163.903914 -403.502368)
			(xy 163.931163 -403.502903) (xy 163.985106 -403.510661) (xy 164.037395 -403.526016) (xy 164.086968 -403.548657)
			(xy 164.132813 -403.578121) (xy 164.173999 -403.613811) (xy 164.209687 -403.654998) (xy 164.23915 -403.700845)
			(xy 164.261789 -403.750418) (xy 164.277142 -403.802708) (xy 164.284898 -403.856651) (xy 164.284898 -403.911149)
			(xy 164.284898 -403.911151) (xy 165.722554 -403.911151) (xy 165.722554 -403.856649) (xy 165.73031 -403.802702)
			(xy 165.745663 -403.750408) (xy 165.768302 -403.70083) (xy 165.797766 -403.654979) (xy 165.833455 -403.613788)
			(xy 165.874642 -403.578094) (xy 165.92049 -403.548625) (xy 165.970065 -403.525979) (xy 166.022357 -403.510619)
			(xy 166.076303 -403.502857) (xy 166.103554 -403.502368) (xy 166.967154 -403.502368) (xy 166.994407 -403.502876)
			(xy 167.04836 -403.510627) (xy 167.10066 -403.525978) (xy 167.150243 -403.548617) (xy 167.196099 -403.578082)
			(xy 167.237294 -403.613773) (xy 167.272991 -403.654964) (xy 167.302461 -403.700817) (xy 167.325106 -403.750397)
			(xy 167.340463 -403.802695) (xy 167.348221 -403.856647) (xy 167.348221 -403.911153) (xy 167.340463 -403.965105)
			(xy 167.325106 -404.017403) (xy 167.302461 -404.066983) (xy 167.272991 -404.112836) (xy 167.237294 -404.154027)
			(xy 167.196099 -404.189718) (xy 167.150243 -404.219183) (xy 167.10066 -404.241822) (xy 167.04836 -404.257173)
			(xy 166.994407 -404.264924) (xy 166.967154 -404.265384) (xy 166.103554 -404.265384) (xy 166.076303 -404.264943)
			(xy 166.022357 -404.257181) (xy 165.970065 -404.241821) (xy 165.92049 -404.219175) (xy 165.874642 -404.189706)
			(xy 165.833455 -404.154012) (xy 165.797766 -404.112821) (xy 165.768302 -404.06697) (xy 165.745663 -404.017392)
			(xy 165.73031 -403.965098) (xy 165.722554 -403.911151) (xy 164.284898 -403.911151) (xy 164.277142 -403.965092)
			(xy 164.261789 -404.017382) (xy 164.23915 -404.066955) (xy 164.209687 -404.112802) (xy 164.173999 -404.153989)
			(xy 164.132813 -404.189679) (xy 164.086968 -404.219143) (xy 164.037395 -404.241784) (xy 163.985106 -404.257139)
			(xy 163.931163 -404.264897) (xy 163.903914 -404.265384) (xy 163.040314 -404.265384) (xy 163.013059 -404.26497)
			(xy 162.959103 -404.257214) (xy 162.9068 -404.241858) (xy 162.857215 -404.219215) (xy 162.811357 -404.189746)
			(xy 162.77016 -404.15405) (xy 162.734463 -404.112854) (xy 162.704991 -404.066997) (xy 162.682346 -404.017413)
			(xy 162.666989 -403.965111) (xy 162.659231 -403.911155) (xy 161.221721 -403.911155) (xy 161.213963 -403.965102)
			(xy 161.198607 -404.017399) (xy 161.175964 -404.066978) (xy 161.146496 -404.112829) (xy 161.110801 -404.15402)
			(xy 161.069608 -404.189711) (xy 161.023755 -404.219177) (xy 160.974174 -404.241816) (xy 160.921877 -404.257169)
			(xy 160.867926 -404.264922) (xy 160.840674 -404.265384) (xy 159.977074 -404.265384) (xy 159.949822 -404.264944)
			(xy 159.895874 -404.257184) (xy 159.843579 -404.241826) (xy 159.794002 -404.219182) (xy 159.748152 -404.189713)
			(xy 159.706962 -404.154019) (xy 159.671271 -404.112827) (xy 159.641806 -404.066975) (xy 159.619165 -404.017397)
			(xy 159.60381 -403.965101) (xy 159.596054 -403.911152) (xy 158.158397 -403.911152) (xy 158.150643 -403.965089)
			(xy 158.13529 -404.017378) (xy 158.112653 -404.06695) (xy 158.083192 -404.112796) (xy 158.047506 -404.153982)
			(xy 158.006323 -404.189671) (xy 157.96048 -404.219137) (xy 157.91091 -404.241778) (xy 157.858623 -404.257136)
			(xy 157.804682 -404.264895) (xy 157.777434 -404.265384) (xy 156.913834 -404.265384) (xy 156.886578 -404.264971)
			(xy 156.83262 -404.257218) (xy 156.780314 -404.241864) (xy 156.730727 -404.219222) (xy 156.684867 -404.189753)
			(xy 156.643667 -404.154057) (xy 156.607968 -404.112861) (xy 156.578495 -404.067003) (xy 156.555848 -404.017417)
			(xy 156.540489 -403.965114) (xy 156.532731 -403.911156) (xy 155.09522 -403.911156) (xy 155.087464 -403.965099)
			(xy 155.072109 -404.017394) (xy 155.049467 -404.066972) (xy 155.02 -404.112822) (xy 154.984308 -404.154013)
			(xy 154.943118 -404.189704) (xy 154.897267 -404.21917) (xy 154.847689 -404.241811) (xy 154.795394 -404.257165)
			(xy 154.741445 -404.264921) (xy 154.714194 -404.265384) (xy 153.850594 -404.265384) (xy 153.823341 -404.264946)
			(xy 153.769391 -404.257188) (xy 153.717094 -404.241831) (xy 153.667514 -404.219189) (xy 153.621661 -404.18972)
			(xy 153.580469 -404.154026) (xy 153.544776 -404.112834) (xy 153.515309 -404.066981) (xy 153.492666 -404.017401)
			(xy 153.477311 -403.965103) (xy 153.469554 -403.911153) (xy 152.032021 -403.911153) (xy 152.024263 -403.965105)
			(xy 152.008906 -404.017403) (xy 151.986261 -404.066983) (xy 151.956791 -404.112836) (xy 151.921094 -404.154027)
			(xy 151.879899 -404.189718) (xy 151.834043 -404.219183) (xy 151.78446 -404.241822) (xy 151.73216 -404.257173)
			(xy 151.678207 -404.264924) (xy 151.650954 -404.265384) (xy 150.787354 -404.265384) (xy 150.760103 -404.264943)
			(xy 150.706157 -404.257181) (xy 150.653865 -404.241821) (xy 150.60429 -404.219175) (xy 150.558442 -404.189706)
			(xy 150.517255 -404.154012) (xy 150.481566 -404.112821) (xy 150.452102 -404.06697) (xy 150.429463 -404.017392)
			(xy 150.41411 -403.965098) (xy 150.406354 -403.911151) (xy 148.968698 -403.911151) (xy 148.960942 -403.965092)
			(xy 148.945589 -404.017382) (xy 148.92295 -404.066955) (xy 148.893487 -404.112802) (xy 148.857799 -404.153989)
			(xy 148.816613 -404.189679) (xy 148.770768 -404.219143) (xy 148.721195 -404.241784) (xy 148.668906 -404.257139)
			(xy 148.614963 -404.264897) (xy 148.587714 -404.265384) (xy 147.724114 -404.265384) (xy 147.696859 -404.26497)
			(xy 147.642903 -404.257214) (xy 147.5906 -404.241858) (xy 147.541015 -404.219215) (xy 147.495157 -404.189746)
			(xy 147.45396 -404.15405) (xy 147.418263 -404.112854) (xy 147.388791 -404.066997) (xy 147.366146 -404.017413)
			(xy 147.350789 -403.965111) (xy 147.343031 -403.911155) (xy 145.905521 -403.911155) (xy 145.897763 -403.965102)
			(xy 145.882407 -404.017399) (xy 145.859764 -404.066978) (xy 145.830296 -404.112829) (xy 145.794601 -404.15402)
			(xy 145.753408 -404.189711) (xy 145.707555 -404.219177) (xy 145.657974 -404.241816) (xy 145.605677 -404.257169)
			(xy 145.551726 -404.264922) (xy 145.524474 -404.265384) (xy 144.660874 -404.265384) (xy 144.633622 -404.264944)
			(xy 144.579674 -404.257184) (xy 144.527379 -404.241826) (xy 144.477802 -404.219182) (xy 144.431952 -404.189713)
			(xy 144.390762 -404.154019) (xy 144.355071 -404.112827) (xy 144.325606 -404.066975) (xy 144.302965 -404.017397)
			(xy 144.28761 -403.965101) (xy 144.279854 -403.911152) (xy 142.842197 -403.911152) (xy 142.834443 -403.965089)
			(xy 142.81909 -404.017378) (xy 142.796453 -404.06695) (xy 142.766992 -404.112796) (xy 142.731306 -404.153982)
			(xy 142.690123 -404.189671) (xy 142.64428 -404.219137) (xy 142.59471 -404.241778) (xy 142.542423 -404.257136)
			(xy 142.488482 -404.264895) (xy 142.461234 -404.265384) (xy 141.597634 -404.265384) (xy 141.570378 -404.264971)
			(xy 141.51642 -404.257218) (xy 141.464114 -404.241864) (xy 141.414527 -404.219222) (xy 141.368667 -404.189753)
			(xy 141.327467 -404.154057) (xy 141.291768 -404.112861) (xy 141.262295 -404.067003) (xy 141.239648 -404.017417)
			(xy 141.224289 -403.965114) (xy 141.216531 -403.911156) (xy 139.77902 -403.911156) (xy 139.771264 -403.965099)
			(xy 139.755909 -404.017394) (xy 139.733267 -404.066972) (xy 139.7038 -404.112822) (xy 139.668108 -404.154013)
			(xy 139.626918 -404.189704) (xy 139.581067 -404.21917) (xy 139.531489 -404.241811) (xy 139.479194 -404.257165)
			(xy 139.425245 -404.264921) (xy 139.397994 -404.265384) (xy 138.534394 -404.265384) (xy 138.507141 -404.264946)
			(xy 138.453191 -404.257188) (xy 138.400894 -404.241831) (xy 138.351314 -404.219189) (xy 138.305461 -404.18972)
			(xy 138.264269 -404.154026) (xy 138.228576 -404.112834) (xy 138.199109 -404.066981) (xy 138.176466 -404.017401)
			(xy 138.161111 -403.965103) (xy 138.153354 -403.911153) (xy 136.715821 -403.911153) (xy 136.708063 -403.965105)
			(xy 136.692706 -404.017403) (xy 136.670061 -404.066983) (xy 136.640591 -404.112836) (xy 136.604894 -404.154027)
			(xy 136.563699 -404.189718) (xy 136.517843 -404.219183) (xy 136.46826 -404.241822) (xy 136.41596 -404.257173)
			(xy 136.362007 -404.264924) (xy 136.334754 -404.265384) (xy 135.471154 -404.265384) (xy 135.443903 -404.264943)
			(xy 135.389957 -404.257181) (xy 135.337665 -404.241821) (xy 135.28809 -404.219175) (xy 135.242242 -404.189706)
			(xy 135.201055 -404.154012) (xy 135.165366 -404.112821) (xy 135.135902 -404.06697) (xy 135.113263 -404.017392)
			(xy 135.09791 -403.965098) (xy 135.090154 -403.911151) (xy 133.652498 -403.911151) (xy 133.644742 -403.965092)
			(xy 133.629389 -404.017382) (xy 133.60675 -404.066955) (xy 133.577287 -404.112802) (xy 133.541599 -404.153989)
			(xy 133.500413 -404.189679) (xy 133.454568 -404.219143) (xy 133.404995 -404.241784) (xy 133.352706 -404.257139)
			(xy 133.298763 -404.264897) (xy 133.271514 -404.265384) (xy 132.407914 -404.265384) (xy 132.380659 -404.26497)
			(xy 132.326703 -404.257214) (xy 132.2744 -404.241858) (xy 132.224815 -404.219215) (xy 132.178957 -404.189746)
			(xy 132.13776 -404.15405) (xy 132.102063 -404.112854) (xy 132.072591 -404.066997) (xy 132.049946 -404.017413)
			(xy 132.034589 -403.965111) (xy 132.026831 -403.911155) (xy 130.589321 -403.911155) (xy 130.581563 -403.965102)
			(xy 130.566207 -404.017399) (xy 130.543564 -404.066978) (xy 130.514096 -404.112829) (xy 130.478401 -404.15402)
			(xy 130.437208 -404.189711) (xy 130.391355 -404.219177) (xy 130.341774 -404.241816) (xy 130.289477 -404.257169)
			(xy 130.235526 -404.264922) (xy 130.208274 -404.265384) (xy 129.344674 -404.265384) (xy 129.317422 -404.264944)
			(xy 129.263474 -404.257184) (xy 129.211179 -404.241826) (xy 129.161602 -404.219182) (xy 129.115752 -404.189713)
			(xy 129.074562 -404.154019) (xy 129.038871 -404.112827) (xy 129.009406 -404.066975) (xy 128.986765 -404.017397)
			(xy 128.97141 -403.965101) (xy 128.963654 -403.911152) (xy 127.525997 -403.911152) (xy 127.518243 -403.965089)
			(xy 127.50289 -404.017378) (xy 127.480253 -404.06695) (xy 127.450792 -404.112796) (xy 127.415106 -404.153982)
			(xy 127.373923 -404.189671) (xy 127.32808 -404.219137) (xy 127.27851 -404.241778) (xy 127.226223 -404.257136)
			(xy 127.172282 -404.264895) (xy 127.145034 -404.265384) (xy 126.281434 -404.265384) (xy 126.254178 -404.264971)
			(xy 126.20022 -404.257218) (xy 126.147914 -404.241864) (xy 126.098327 -404.219222) (xy 126.052467 -404.189753)
			(xy 126.011267 -404.154057) (xy 125.975568 -404.112861) (xy 125.946095 -404.067003) (xy 125.923448 -404.017417)
			(xy 125.908089 -403.965114) (xy 125.900331 -403.911156) (xy 124.46282 -403.911156) (xy 124.455064 -403.965099)
			(xy 124.439709 -404.017394) (xy 124.417067 -404.066972) (xy 124.3876 -404.112822) (xy 124.351908 -404.154013)
			(xy 124.310718 -404.189704) (xy 124.264867 -404.21917) (xy 124.215289 -404.241811) (xy 124.162994 -404.257165)
			(xy 124.109045 -404.264921) (xy 124.081794 -404.265384) (xy 123.218194 -404.265384) (xy 123.190941 -404.264946)
			(xy 123.136991 -404.257188) (xy 123.084694 -404.241831) (xy 123.035114 -404.219189) (xy 122.989261 -404.18972)
			(xy 122.948069 -404.154026) (xy 122.912376 -404.112834) (xy 122.882909 -404.066981) (xy 122.860266 -404.017401)
			(xy 122.844911 -403.965103) (xy 122.837154 -403.911153) (xy 121.399621 -403.911153) (xy 121.391863 -403.965105)
			(xy 121.376506 -404.017403) (xy 121.353861 -404.066983) (xy 121.324391 -404.112836) (xy 121.288694 -404.154027)
			(xy 121.247499 -404.189718) (xy 121.201643 -404.219183) (xy 121.15206 -404.241822) (xy 121.09976 -404.257173)
			(xy 121.045807 -404.264924) (xy 121.018554 -404.265384) (xy 120.154954 -404.265384) (xy 120.127703 -404.264943)
			(xy 120.073757 -404.257181) (xy 120.021465 -404.241821) (xy 119.97189 -404.219175) (xy 119.926042 -404.189706)
			(xy 119.884855 -404.154012) (xy 119.849166 -404.112821) (xy 119.819702 -404.06697) (xy 119.797063 -404.017392)
			(xy 119.78171 -403.965098) (xy 119.773954 -403.911151) (xy 95.172998 -403.911151) (xy 95.165243 -403.965089)
			(xy 95.149891 -404.017377) (xy 95.127254 -404.066949) (xy 95.097793 -404.112794) (xy 95.062108 -404.153981)
			(xy 95.020925 -404.18967) (xy 94.975082 -404.219135) (xy 94.925513 -404.241777) (xy 94.873226 -404.257135)
			(xy 94.819286 -404.264895) (xy 94.792038 -404.265384) (xy 93.928438 -404.265384) (xy 93.901182 -404.264972)
			(xy 93.847223 -404.257219) (xy 93.794917 -404.241865) (xy 93.745329 -404.219223) (xy 93.699468 -404.189754)
			(xy 93.658269 -404.154058) (xy 93.622569 -404.112862) (xy 93.593095 -404.067004) (xy 93.570448 -404.017418)
			(xy 93.555089 -403.965114) (xy 93.547331 -403.911156) (xy 92.10982 -403.911156) (xy 92.102064 -403.965099)
			(xy 92.086709 -404.017394) (xy 92.064068 -404.066971) (xy 92.034601 -404.112821) (xy 91.99891 -404.154011)
			(xy 91.95772 -404.189703) (xy 91.911869 -404.219169) (xy 91.862292 -404.24181) (xy 91.809997 -404.257165)
			(xy 91.756049 -404.264921) (xy 91.728798 -404.265384) (xy 90.865198 -404.265384) (xy 90.837945 -404.264946)
			(xy 90.783994 -404.257189) (xy 90.731696 -404.241833) (xy 90.682116 -404.21919) (xy 90.636263 -404.189722)
			(xy 90.595071 -404.154028) (xy 90.559377 -404.112835) (xy 90.529909 -404.066982) (xy 90.507267 -404.017402)
			(xy 90.491911 -403.965104) (xy 90.484154 -403.911153) (xy 89.046621 -403.911153) (xy 89.038863 -403.965104)
			(xy 89.023506 -404.017402) (xy 89.000862 -404.066982) (xy 88.971392 -404.112834) (xy 88.935696 -404.154025)
			(xy 88.894501 -404.189717) (xy 88.848645 -404.219182) (xy 88.799063 -404.241821) (xy 88.746763 -404.257172)
			(xy 88.692811 -404.264924) (xy 88.665558 -404.265384) (xy 87.801958 -404.265384) (xy 87.774707 -404.264943)
			(xy 87.72076 -404.257181) (xy 87.668467 -404.241822) (xy 87.618892 -404.219177) (xy 87.573044 -404.189707)
			(xy 87.531857 -404.154014) (xy 87.496167 -404.112822) (xy 87.466703 -404.066971) (xy 87.444064 -404.017393)
			(xy 87.42871 -403.965098) (xy 87.420954 -403.911151) (xy 85.983298 -403.911151) (xy 85.975542 -403.965091)
			(xy 85.960189 -404.017381) (xy 85.937551 -404.066954) (xy 85.908088 -404.112801) (xy 85.872401 -404.153988)
			(xy 85.831215 -404.189677) (xy 85.78537 -404.219142) (xy 85.735798 -404.241783) (xy 85.683509 -404.257138)
			(xy 85.629567 -404.264897) (xy 85.602318 -404.265384) (xy 84.738718 -404.265384) (xy 84.711463 -404.26497)
			(xy 84.657506 -404.257215) (xy 84.605203 -404.241859) (xy 84.555617 -404.219217) (xy 84.509759 -404.189747)
			(xy 84.468562 -404.154051) (xy 84.432864 -404.112855) (xy 84.403392 -404.066999) (xy 84.380747 -404.017414)
			(xy 84.365389 -403.965111) (xy 84.357631 -403.911155) (xy 82.920121 -403.911155) (xy 82.912364 -403.965102)
			(xy 82.897007 -404.017398) (xy 82.874365 -404.066976) (xy 82.844897 -404.112828) (xy 82.809203 -404.154018)
			(xy 82.76801 -404.18971) (xy 82.722157 -404.219175) (xy 82.672577 -404.241815) (xy 82.62028 -404.257168)
			(xy 82.56633 -404.264922) (xy 82.539078 -404.265384) (xy 81.675478 -404.265384) (xy 81.648226 -404.264945)
			(xy 81.594277 -404.257185) (xy 81.541982 -404.241827) (xy 81.492404 -404.219183) (xy 81.446554 -404.189715)
			(xy 81.405364 -404.154021) (xy 81.369672 -404.112829) (xy 81.340206 -404.066976) (xy 81.317565 -404.017397)
			(xy 81.30221 -403.965101) (xy 81.294454 -403.911152) (xy 79.856797 -403.911152) (xy 79.849043 -403.965089)
			(xy 79.833691 -404.017377) (xy 79.811054 -404.066949) (xy 79.781593 -404.112794) (xy 79.745908 -404.153981)
			(xy 79.704725 -404.18967) (xy 79.658882 -404.219135) (xy 79.609313 -404.241777) (xy 79.557026 -404.257135)
			(xy 79.503086 -404.264895) (xy 79.475838 -404.265384) (xy 78.612238 -404.265384) (xy 78.584982 -404.264972)
			(xy 78.531023 -404.257219) (xy 78.478717 -404.241865) (xy 78.429129 -404.219223) (xy 78.383268 -404.189754)
			(xy 78.342069 -404.154058) (xy 78.306369 -404.112862) (xy 78.276895 -404.067004) (xy 78.254248 -404.017418)
			(xy 78.238889 -403.965114) (xy 78.231131 -403.911156) (xy 76.79362 -403.911156) (xy 76.785864 -403.965099)
			(xy 76.770509 -404.017394) (xy 76.747868 -404.066971) (xy 76.718401 -404.112821) (xy 76.68271 -404.154011)
			(xy 76.64152 -404.189703) (xy 76.595669 -404.219169) (xy 76.546092 -404.24181) (xy 76.493797 -404.257165)
			(xy 76.439849 -404.264921) (xy 76.412598 -404.265384) (xy 75.548998 -404.265384) (xy 75.521745 -404.264946)
			(xy 75.467794 -404.257189) (xy 75.415496 -404.241833) (xy 75.365916 -404.21919) (xy 75.320063 -404.189722)
			(xy 75.278871 -404.154028) (xy 75.243177 -404.112835) (xy 75.213709 -404.066982) (xy 75.191067 -404.017402)
			(xy 75.175711 -403.965104) (xy 75.167954 -403.911153) (xy 73.730421 -403.911153) (xy 73.722663 -403.965104)
			(xy 73.707306 -404.017402) (xy 73.684662 -404.066982) (xy 73.655192 -404.112834) (xy 73.619496 -404.154025)
			(xy 73.578301 -404.189717) (xy 73.532445 -404.219182) (xy 73.482863 -404.241821) (xy 73.430563 -404.257172)
			(xy 73.376611 -404.264924) (xy 73.349358 -404.265384) (xy 72.485758 -404.265384) (xy 72.458507 -404.264943)
			(xy 72.40456 -404.257181) (xy 72.352267 -404.241822) (xy 72.302692 -404.219177) (xy 72.256844 -404.189707)
			(xy 72.215657 -404.154014) (xy 72.179967 -404.112822) (xy 72.150503 -404.066971) (xy 72.127864 -404.017393)
			(xy 72.11251 -403.965098) (xy 72.104754 -403.911151) (xy 70.667098 -403.911151) (xy 70.659342 -403.965091)
			(xy 70.643989 -404.017381) (xy 70.621351 -404.066954) (xy 70.591888 -404.112801) (xy 70.556201 -404.153988)
			(xy 70.515015 -404.189677) (xy 70.46917 -404.219142) (xy 70.419598 -404.241783) (xy 70.367309 -404.257138)
			(xy 70.313367 -404.264897) (xy 70.286118 -404.265384) (xy 69.422518 -404.265384) (xy 69.395263 -404.26497)
			(xy 69.341306 -404.257215) (xy 69.289003 -404.241859) (xy 69.239417 -404.219217) (xy 69.193559 -404.189747)
			(xy 69.152362 -404.154051) (xy 69.116664 -404.112855) (xy 69.087192 -404.066999) (xy 69.064547 -404.017414)
			(xy 69.049189 -403.965111) (xy 69.041431 -403.911155) (xy 67.603921 -403.911155) (xy 67.596164 -403.965102)
			(xy 67.580807 -404.017398) (xy 67.558165 -404.066976) (xy 67.528697 -404.112828) (xy 67.493003 -404.154018)
			(xy 67.45181 -404.18971) (xy 67.405957 -404.219175) (xy 67.356377 -404.241815) (xy 67.30408 -404.257168)
			(xy 67.25013 -404.264922) (xy 67.222878 -404.265384) (xy 66.359278 -404.265384) (xy 66.332026 -404.264945)
			(xy 66.278077 -404.257185) (xy 66.225782 -404.241827) (xy 66.176204 -404.219183) (xy 66.130354 -404.189715)
			(xy 66.089164 -404.154021) (xy 66.053472 -404.112829) (xy 66.024006 -404.066976) (xy 66.001365 -404.017397)
			(xy 65.98601 -403.965101) (xy 65.978254 -403.911152) (xy 64.540597 -403.911152) (xy 64.532843 -403.965089)
			(xy 64.517491 -404.017377) (xy 64.494854 -404.066949) (xy 64.465393 -404.112794) (xy 64.429708 -404.153981)
			(xy 64.388525 -404.18967) (xy 64.342682 -404.219135) (xy 64.293113 -404.241777) (xy 64.240826 -404.257135)
			(xy 64.186886 -404.264895) (xy 64.159638 -404.265384) (xy 63.296038 -404.265384) (xy 63.268782 -404.264972)
			(xy 63.214823 -404.257219) (xy 63.162517 -404.241865) (xy 63.112929 -404.219223) (xy 63.067068 -404.189754)
			(xy 63.025869 -404.154058) (xy 62.990169 -404.112862) (xy 62.960695 -404.067004) (xy 62.938048 -404.017418)
			(xy 62.922689 -403.965114) (xy 62.914931 -403.911156) (xy 61.47742 -403.911156) (xy 61.469664 -403.965099)
			(xy 61.454309 -404.017394) (xy 61.431668 -404.066971) (xy 61.402201 -404.112821) (xy 61.36651 -404.154011)
			(xy 61.32532 -404.189703) (xy 61.279469 -404.219169) (xy 61.229892 -404.24181) (xy 61.177597 -404.257165)
			(xy 61.123649 -404.264921) (xy 61.096398 -404.265384) (xy 60.232798 -404.265384) (xy 60.205545 -404.264946)
			(xy 60.151594 -404.257189) (xy 60.099296 -404.241833) (xy 60.049716 -404.21919) (xy 60.003863 -404.189722)
			(xy 59.962671 -404.154028) (xy 59.926977 -404.112835) (xy 59.897509 -404.066982) (xy 59.874867 -404.017402)
			(xy 59.859511 -403.965104) (xy 59.851754 -403.911153) (xy 58.414221 -403.911153) (xy 58.406463 -403.965104)
			(xy 58.391106 -404.017402) (xy 58.368462 -404.066982) (xy 58.338992 -404.112834) (xy 58.303296 -404.154025)
			(xy 58.262101 -404.189717) (xy 58.216245 -404.219182) (xy 58.166663 -404.241821) (xy 58.114363 -404.257172)
			(xy 58.060411 -404.264924) (xy 58.033158 -404.265384) (xy 57.169558 -404.265384) (xy 57.142307 -404.264943)
			(xy 57.08836 -404.257181) (xy 57.036067 -404.241822) (xy 56.986492 -404.219177) (xy 56.940644 -404.189707)
			(xy 56.899457 -404.154014) (xy 56.863767 -404.112822) (xy 56.834303 -404.066971) (xy 56.811664 -404.017393)
			(xy 56.79631 -403.965098) (xy 56.788554 -403.911151) (xy 55.350898 -403.911151) (xy 55.343142 -403.965091)
			(xy 55.327789 -404.017381) (xy 55.305151 -404.066954) (xy 55.275688 -404.112801) (xy 55.240001 -404.153988)
			(xy 55.198815 -404.189677) (xy 55.15297 -404.219142) (xy 55.103398 -404.241783) (xy 55.051109 -404.257138)
			(xy 54.997167 -404.264897) (xy 54.969918 -404.265384) (xy 54.106318 -404.265384) (xy 54.079063 -404.26497)
			(xy 54.025106 -404.257215) (xy 53.972803 -404.241859) (xy 53.923217 -404.219217) (xy 53.877359 -404.189747)
			(xy 53.836162 -404.154051) (xy 53.800464 -404.112855) (xy 53.770992 -404.066999) (xy 53.748347 -404.017414)
			(xy 53.732989 -403.965111) (xy 53.725231 -403.911155) (xy 52.287721 -403.911155) (xy 52.279964 -403.965102)
			(xy 52.264607 -404.017398) (xy 52.241965 -404.066976) (xy 52.212497 -404.112828) (xy 52.176803 -404.154018)
			(xy 52.13561 -404.18971) (xy 52.089757 -404.219175) (xy 52.040177 -404.241815) (xy 51.98788 -404.257168)
			(xy 51.93393 -404.264922) (xy 51.906678 -404.265384) (xy 51.043078 -404.265384) (xy 51.015826 -404.264945)
			(xy 50.961877 -404.257185) (xy 50.909582 -404.241827) (xy 50.860004 -404.219183) (xy 50.814154 -404.189715)
			(xy 50.772964 -404.154021) (xy 50.737272 -404.112829) (xy 50.707806 -404.066976) (xy 50.685165 -404.017397)
			(xy 50.66981 -403.965101) (xy 50.662054 -403.911152) (xy 49.224397 -403.911152) (xy 49.216643 -403.965089)
			(xy 49.201291 -404.017377) (xy 49.178654 -404.066949) (xy 49.149193 -404.112794) (xy 49.113508 -404.153981)
			(xy 49.072325 -404.18967) (xy 49.026482 -404.219135) (xy 48.976913 -404.241777) (xy 48.924626 -404.257135)
			(xy 48.870686 -404.264895) (xy 48.843438 -404.265384) (xy 47.979838 -404.265384) (xy 47.952582 -404.264972)
			(xy 47.898623 -404.257219) (xy 47.846317 -404.241865) (xy 47.796729 -404.219223) (xy 47.750868 -404.189754)
			(xy 47.709669 -404.154058) (xy 47.673969 -404.112862) (xy 47.644495 -404.067004) (xy 47.621848 -404.017418)
			(xy 47.606489 -403.965114) (xy 47.598731 -403.911156) (xy 3.86649 -403.911156) (xy 5.184394 -405.22906)
			(xy 102.242112 -405.22906) (xy 102.242112 -404.36546) (xy 102.242598 -404.338209) (xy 102.250354 -404.284261)
			(xy 102.265709 -404.231966) (xy 102.288351 -404.182389) (xy 102.317817 -404.136539) (xy 102.353508 -404.095348)
			(xy 102.394699 -404.059657) (xy 102.440549 -404.030191) (xy 102.490126 -404.007549) (xy 102.542421 -403.992194)
			(xy 102.596369 -403.984438) (xy 102.650871 -403.984438) (xy 102.704819 -403.992194) (xy 102.757114 -404.007549)
			(xy 102.806691 -404.030191) (xy 102.852541 -404.059657) (xy 102.893732 -404.095348) (xy 102.929423 -404.136539)
			(xy 102.958889 -404.182389) (xy 102.981531 -404.231966) (xy 102.996886 -404.284261) (xy 103.004642 -404.338209)
			(xy 103.005128 -404.36546) (xy 103.005128 -405.22906) (xy 103.004642 -405.256311) (xy 102.996886 -405.310259)
			(xy 102.981531 -405.362554) (xy 102.958889 -405.412131) (xy 102.929423 -405.457981) (xy 102.893732 -405.499172)
			(xy 102.852541 -405.534863) (xy 102.806691 -405.564329) (xy 102.757114 -405.586971) (xy 102.704819 -405.602326)
			(xy 102.650871 -405.610082) (xy 102.596369 -405.610082) (xy 102.542421 -405.602326) (xy 102.490126 -405.586971)
			(xy 102.440549 -405.564329) (xy 102.394699 -405.534863) (xy 102.353508 -405.499172) (xy 102.317817 -405.457981)
			(xy 102.288351 -405.412131) (xy 102.265709 -405.362554) (xy 102.250354 -405.310259) (xy 102.242598 -405.256311)
			(xy 102.242112 -405.22906) (xy 5.184394 -405.22906) (xy 6.990842 -407.035508) (xy 15.978632 -407.035508)
			(xy 15.978632 -406.171908) (xy 15.979118 -406.144657) (xy 15.986874 -406.090709) (xy 16.002229 -406.038414)
			(xy 16.024871 -405.988837) (xy 16.054337 -405.942987) (xy 16.090028 -405.901796) (xy 16.131219 -405.866105)
			(xy 16.177069 -405.836639) (xy 16.226646 -405.813997) (xy 16.278941 -405.798642) (xy 16.332889 -405.790886)
			(xy 16.387391 -405.790886) (xy 16.441339 -405.798642) (xy 16.493634 -405.813997) (xy 16.543211 -405.836639)
			(xy 16.589061 -405.866105) (xy 16.630252 -405.901796) (xy 16.665943 -405.942987) (xy 16.695409 -405.988837)
			(xy 16.718051 -406.038414) (xy 16.733406 -406.090709) (xy 16.741162 -406.144657) (xy 16.741648 -406.171908)
			(xy 16.741648 -407.031753) (xy 48.944975 -407.031753) (xy 48.944975 -406.977247) (xy 48.952733 -406.923295)
			(xy 48.96809 -406.870997) (xy 48.990734 -406.821417) (xy 49.020204 -406.775565) (xy 49.0559 -406.734373)
			(xy 49.097095 -406.698681) (xy 49.142951 -406.669216) (xy 49.192533 -406.646577) (xy 49.244833 -406.631225)
			(xy 49.298785 -406.623473) (xy 49.326038 -406.623012) (xy 50.189638 -406.623012) (xy 50.216889 -406.62346)
			(xy 50.270835 -406.631222) (xy 50.323128 -406.646581) (xy 50.372703 -406.669225) (xy 50.418551 -406.698694)
			(xy 50.459739 -406.734388) (xy 50.495428 -406.775579) (xy 50.524893 -406.82143) (xy 50.547532 -406.871007)
			(xy 50.562886 -406.923302) (xy 50.570642 -406.977249) (xy 50.570642 -407.031749) (xy 52.008298 -407.031749)
			(xy 52.008298 -406.977251) (xy 52.016054 -406.923308) (xy 52.031407 -406.871018) (xy 52.054045 -406.821445)
			(xy 52.083508 -406.775598) (xy 52.119195 -406.734411) (xy 52.16038 -406.698721) (xy 52.206226 -406.669256)
			(xy 52.255797 -406.646615) (xy 52.308087 -406.631258) (xy 52.362029 -406.6235) (xy 52.389278 -406.623012)
			(xy 53.252878 -406.623012) (xy 53.280133 -406.623433) (xy 53.33409 -406.631188) (xy 53.386393 -406.646543)
			(xy 53.435978 -406.669186) (xy 53.481837 -406.698655) (xy 53.523034 -406.73435) (xy 53.558732 -406.775546)
			(xy 53.588204 -406.821402) (xy 53.610849 -406.870987) (xy 53.626207 -406.923289) (xy 53.633965 -406.977245)
			(xy 53.633965 -407.031752) (xy 55.071475 -407.031752) (xy 55.071475 -406.977248) (xy 55.079232 -406.923298)
			(xy 55.094589 -406.871002) (xy 55.117231 -406.821423) (xy 55.146699 -406.775571) (xy 55.182393 -406.73438)
			(xy 55.223586 -406.698688) (xy 55.269439 -406.669222) (xy 55.319018 -406.646582) (xy 55.371316 -406.631229)
			(xy 55.425266 -406.623474) (xy 55.452518 -406.623012) (xy 56.316118 -406.623012) (xy 56.34337 -406.623459)
			(xy 56.397318 -406.631218) (xy 56.449614 -406.646576) (xy 56.499191 -406.669219) (xy 56.545042 -406.698687)
			(xy 56.586232 -406.734381) (xy 56.621924 -406.775573) (xy 56.65139 -406.821424) (xy 56.674031 -406.871003)
			(xy 56.689386 -406.923299) (xy 56.697142 -406.977248) (xy 56.697142 -407.031748) (xy 58.134798 -407.031748)
			(xy 58.134798 -406.977252) (xy 58.142553 -406.923311) (xy 58.157905 -406.871022) (xy 58.180542 -406.821451)
			(xy 58.210003 -406.775605) (xy 58.245688 -406.734418) (xy 58.286871 -406.698728) (xy 58.332714 -406.669262)
			(xy 58.382283 -406.64662) (xy 58.43457 -406.631262) (xy 58.48851 -406.623501) (xy 58.515758 -406.623012)
			(xy 59.379358 -406.623012) (xy 59.406614 -406.623432) (xy 59.460573 -406.631185) (xy 59.512878 -406.646538)
			(xy 59.562466 -406.669179) (xy 59.608327 -406.698648) (xy 59.649527 -406.734343) (xy 59.685227 -406.775539)
			(xy 59.714701 -406.821397) (xy 59.737348 -406.870982) (xy 59.752707 -406.923286) (xy 59.760465 -406.977244)
			(xy 59.760465 -407.03175) (xy 61.197998 -407.03175) (xy 61.197998 -406.97725) (xy 61.205754 -406.923306)
			(xy 61.221108 -406.871014) (xy 61.243748 -406.821439) (xy 61.273213 -406.775592) (xy 61.308902 -406.734404)
			(xy 61.35009 -406.698714) (xy 61.395938 -406.669249) (xy 61.445512 -406.646609) (xy 61.497804 -406.631255)
			(xy 61.551748 -406.623498) (xy 61.578998 -406.623012) (xy 62.442598 -406.623012) (xy 62.469852 -406.623435)
			(xy 62.523806 -406.631192) (xy 62.576107 -406.646549) (xy 62.62569 -406.669192) (xy 62.671546 -406.698662)
			(xy 62.712741 -406.734357) (xy 62.748437 -406.775552) (xy 62.777907 -406.821408) (xy 62.800551 -406.870991)
			(xy 62.815908 -406.923292) (xy 62.823665 -406.977246) (xy 62.823665 -407.031753) (xy 64.261175 -407.031753)
			(xy 64.261175 -406.977247) (xy 64.268933 -406.923295) (xy 64.28429 -406.870997) (xy 64.306934 -406.821417)
			(xy 64.336404 -406.775565) (xy 64.3721 -406.734373) (xy 64.413295 -406.698681) (xy 64.459151 -406.669216)
			(xy 64.508733 -406.646577) (xy 64.561033 -406.631225) (xy 64.614985 -406.623473) (xy 64.642238 -406.623012)
			(xy 65.505838 -406.623012) (xy 65.533089 -406.62346) (xy 65.587035 -406.631222) (xy 65.639328 -406.646581)
			(xy 65.688903 -406.669225) (xy 65.734751 -406.698694) (xy 65.775939 -406.734388) (xy 65.811628 -406.775579)
			(xy 65.841093 -406.82143) (xy 65.863732 -406.871007) (xy 65.879086 -406.923302) (xy 65.886842 -406.977249)
			(xy 65.886842 -407.031749) (xy 67.324498 -407.031749) (xy 67.324498 -406.977251) (xy 67.332254 -406.923308)
			(xy 67.347607 -406.871018) (xy 67.370245 -406.821445) (xy 67.399708 -406.775598) (xy 67.435395 -406.734411)
			(xy 67.47658 -406.698721) (xy 67.522426 -406.669256) (xy 67.571997 -406.646615) (xy 67.624287 -406.631258)
			(xy 67.678229 -406.6235) (xy 67.705478 -406.623012) (xy 68.569078 -406.623012) (xy 68.596333 -406.623433)
			(xy 68.65029 -406.631188) (xy 68.702593 -406.646543) (xy 68.752178 -406.669186) (xy 68.798037 -406.698655)
			(xy 68.839234 -406.73435) (xy 68.874932 -406.775546) (xy 68.904404 -406.821402) (xy 68.927049 -406.870987)
			(xy 68.942407 -406.923289) (xy 68.950165 -406.977245) (xy 68.950165 -407.031752) (xy 70.387675 -407.031752)
			(xy 70.387675 -406.977248) (xy 70.395432 -406.923298) (xy 70.410789 -406.871002) (xy 70.433431 -406.821423)
			(xy 70.462899 -406.775571) (xy 70.498593 -406.73438) (xy 70.539786 -406.698688) (xy 70.585639 -406.669222)
			(xy 70.635218 -406.646582) (xy 70.687516 -406.631229) (xy 70.741466 -406.623474) (xy 70.768718 -406.623012)
			(xy 71.632318 -406.623012) (xy 71.65957 -406.623459) (xy 71.713518 -406.631218) (xy 71.765814 -406.646576)
			(xy 71.815391 -406.669219) (xy 71.861242 -406.698687) (xy 71.902432 -406.734381) (xy 71.938124 -406.775573)
			(xy 71.96759 -406.821424) (xy 71.990231 -406.871003) (xy 72.005586 -406.923299) (xy 72.013342 -406.977248)
			(xy 72.013342 -407.031748) (xy 73.450998 -407.031748) (xy 73.450998 -406.977252) (xy 73.458753 -406.923311)
			(xy 73.474105 -406.871022) (xy 73.496742 -406.821451) (xy 73.526203 -406.775605) (xy 73.561888 -406.734418)
			(xy 73.603071 -406.698728) (xy 73.648914 -406.669262) (xy 73.698483 -406.64662) (xy 73.75077 -406.631262)
			(xy 73.80471 -406.623501) (xy 73.831958 -406.623012) (xy 74.695558 -406.623012) (xy 74.722814 -406.623432)
			(xy 74.776773 -406.631185) (xy 74.829078 -406.646538) (xy 74.878666 -406.669179) (xy 74.924527 -406.698648)
			(xy 74.965727 -406.734343) (xy 75.001427 -406.775539) (xy 75.030901 -406.821397) (xy 75.053548 -406.870982)
			(xy 75.068907 -406.923286) (xy 75.076665 -406.977244) (xy 75.076665 -407.03175) (xy 76.514198 -407.03175)
			(xy 76.514198 -406.97725) (xy 76.521954 -406.923306) (xy 76.537308 -406.871014) (xy 76.559948 -406.821439)
			(xy 76.589413 -406.775592) (xy 76.625102 -406.734404) (xy 76.66629 -406.698714) (xy 76.712138 -406.669249)
			(xy 76.761712 -406.646609) (xy 76.814004 -406.631255) (xy 76.867948 -406.623498) (xy 76.895198 -406.623012)
			(xy 77.758798 -406.623012) (xy 77.786052 -406.623435) (xy 77.840006 -406.631192) (xy 77.892307 -406.646549)
			(xy 77.94189 -406.669192) (xy 77.987746 -406.698662) (xy 78.028941 -406.734357) (xy 78.064637 -406.775552)
			(xy 78.094107 -406.821408) (xy 78.116751 -406.870991) (xy 78.132108 -406.923292) (xy 78.139865 -406.977246)
			(xy 78.139865 -407.031753) (xy 79.577375 -407.031753) (xy 79.577375 -406.977247) (xy 79.585133 -406.923295)
			(xy 79.60049 -406.870997) (xy 79.623134 -406.821417) (xy 79.652604 -406.775565) (xy 79.6883 -406.734373)
			(xy 79.729495 -406.698681) (xy 79.775351 -406.669216) (xy 79.824933 -406.646577) (xy 79.877233 -406.631225)
			(xy 79.931185 -406.623473) (xy 79.958438 -406.623012) (xy 80.822038 -406.623012) (xy 80.849289 -406.62346)
			(xy 80.903235 -406.631222) (xy 80.955528 -406.646581) (xy 81.005103 -406.669225) (xy 81.050951 -406.698694)
			(xy 81.092139 -406.734388) (xy 81.127828 -406.775579) (xy 81.157293 -406.82143) (xy 81.179932 -406.871007)
			(xy 81.195286 -406.923302) (xy 81.203042 -406.977249) (xy 81.203042 -407.031749) (xy 82.640698 -407.031749)
			(xy 82.640698 -406.977251) (xy 82.648454 -406.923308) (xy 82.663807 -406.871018) (xy 82.686445 -406.821445)
			(xy 82.715908 -406.775598) (xy 82.751595 -406.734411) (xy 82.79278 -406.698721) (xy 82.838626 -406.669256)
			(xy 82.888197 -406.646615) (xy 82.940487 -406.631258) (xy 82.994429 -406.6235) (xy 83.021678 -406.623012)
			(xy 83.885278 -406.623012) (xy 83.912533 -406.623433) (xy 83.96649 -406.631188) (xy 84.018793 -406.646543)
			(xy 84.068378 -406.669186) (xy 84.114237 -406.698655) (xy 84.155434 -406.73435) (xy 84.191132 -406.775546)
			(xy 84.220604 -406.821402) (xy 84.243249 -406.870987) (xy 84.258607 -406.923289) (xy 84.266365 -406.977245)
			(xy 84.266365 -407.031752) (xy 85.703875 -407.031752) (xy 85.703875 -406.977248) (xy 85.711632 -406.923298)
			(xy 85.726989 -406.871002) (xy 85.749631 -406.821423) (xy 85.779099 -406.775571) (xy 85.814793 -406.73438)
			(xy 85.855986 -406.698688) (xy 85.901839 -406.669222) (xy 85.951418 -406.646582) (xy 86.003716 -406.631229)
			(xy 86.057666 -406.623474) (xy 86.084918 -406.623012) (xy 86.948518 -406.623012) (xy 86.97577 -406.623459)
			(xy 87.029718 -406.631218) (xy 87.082014 -406.646576) (xy 87.131591 -406.669219) (xy 87.177442 -406.698687)
			(xy 87.218632 -406.734381) (xy 87.254324 -406.775573) (xy 87.28379 -406.821424) (xy 87.306431 -406.871003)
			(xy 87.321786 -406.923299) (xy 87.329542 -406.977248) (xy 87.329542 -407.031748) (xy 88.767198 -407.031748)
			(xy 88.767198 -406.977252) (xy 88.774953 -406.923311) (xy 88.790305 -406.871022) (xy 88.812942 -406.821451)
			(xy 88.842403 -406.775605) (xy 88.878088 -406.734418) (xy 88.919271 -406.698728) (xy 88.965114 -406.669262)
			(xy 89.014683 -406.64662) (xy 89.06697 -406.631262) (xy 89.12091 -406.623501) (xy 89.148158 -406.623012)
			(xy 90.011758 -406.623012) (xy 90.039014 -406.623432) (xy 90.092973 -406.631185) (xy 90.145278 -406.646538)
			(xy 90.194866 -406.669179) (xy 90.240727 -406.698648) (xy 90.281927 -406.734343) (xy 90.317627 -406.775539)
			(xy 90.347101 -406.821397) (xy 90.369748 -406.870982) (xy 90.385107 -406.923286) (xy 90.392865 -406.977244)
			(xy 90.392865 -407.03175) (xy 91.830398 -407.03175) (xy 91.830398 -406.97725) (xy 91.838154 -406.923306)
			(xy 91.853508 -406.871014) (xy 91.876148 -406.821439) (xy 91.905613 -406.775592) (xy 91.941302 -406.734404)
			(xy 91.98249 -406.698714) (xy 92.028338 -406.669249) (xy 92.077912 -406.646609) (xy 92.130204 -406.631255)
			(xy 92.184148 -406.623498) (xy 92.211398 -406.623012) (xy 93.074998 -406.623012) (xy 93.102252 -406.623435)
			(xy 93.156206 -406.631192) (xy 93.208507 -406.646549) (xy 93.25809 -406.669192) (xy 93.303946 -406.698662)
			(xy 93.345141 -406.734357) (xy 93.380837 -406.775552) (xy 93.410307 -406.821408) (xy 93.432951 -406.870991)
			(xy 93.448308 -406.923292) (xy 93.456065 -406.977246) (xy 93.456065 -407.031753) (xy 94.893575 -407.031753)
			(xy 94.893575 -406.977247) (xy 94.901333 -406.923295) (xy 94.91669 -406.870997) (xy 94.939334 -406.821417)
			(xy 94.968804 -406.775565) (xy 95.0045 -406.734373) (xy 95.045695 -406.698681) (xy 95.091551 -406.669216)
			(xy 95.141133 -406.646577) (xy 95.193433 -406.631225) (xy 95.247385 -406.623473) (xy 95.274638 -406.623012)
			(xy 96.138238 -406.623012) (xy 96.165489 -406.62346) (xy 96.219435 -406.631222) (xy 96.271728 -406.646581)
			(xy 96.321303 -406.669225) (xy 96.367151 -406.698694) (xy 96.408339 -406.734388) (xy 96.444028 -406.775579)
			(xy 96.473493 -406.82143) (xy 96.496132 -406.871007) (xy 96.511486 -406.923302) (xy 96.519242 -406.977249)
			(xy 96.519242 -407.031751) (xy 96.511486 -407.085698) (xy 96.496132 -407.137993) (xy 96.495694 -407.138953)
			(xy 106.243063 -407.138953) (xy 106.243063 -407.084447) (xy 106.250821 -407.030495) (xy 106.266177 -406.978197)
			(xy 106.288821 -406.928617) (xy 106.31829 -406.882763) (xy 106.353985 -406.841571) (xy 106.395179 -406.805878)
			(xy 106.441034 -406.776411) (xy 106.490616 -406.75377) (xy 106.542915 -406.738416) (xy 106.596867 -406.730662)
			(xy 106.62412 -406.7302) (xy 107.48772 -406.7302) (xy 107.514971 -406.730671) (xy 107.568918 -406.73843)
			(xy 107.621211 -406.753787) (xy 107.670787 -406.77643) (xy 107.716636 -406.805898) (xy 107.757824 -406.84159)
			(xy 107.793514 -406.88278) (xy 107.82298 -406.928631) (xy 107.84562 -406.978208) (xy 107.860974 -407.030502)
			(xy 107.861153 -407.031748) (xy 121.120198 -407.031748) (xy 121.120198 -406.977252) (xy 121.127953 -406.923312)
			(xy 121.143305 -406.871023) (xy 121.165942 -406.821452) (xy 121.195402 -406.775606) (xy 121.231087 -406.734419)
			(xy 121.272269 -406.69873) (xy 121.318111 -406.669264) (xy 121.36768 -406.646621) (xy 121.419967 -406.631263)
			(xy 121.473906 -406.623501) (xy 121.501154 -406.623012) (xy 122.364754 -406.623012) (xy 122.39201 -406.623432)
			(xy 122.445969 -406.631184) (xy 122.498275 -406.646537) (xy 122.547864 -406.669178) (xy 122.593725 -406.698646)
			(xy 122.634926 -406.734342) (xy 122.670626 -406.775538) (xy 122.7001 -406.821396) (xy 122.722747 -406.870981)
			(xy 122.738106 -406.923286) (xy 122.745865 -406.977244) (xy 122.745865 -407.03175) (xy 124.183398 -407.03175)
			(xy 124.183398 -406.97725) (xy 124.191154 -406.923306) (xy 124.206508 -406.871015) (xy 124.229148 -406.821441)
			(xy 124.258612 -406.775593) (xy 124.294301 -406.734405) (xy 124.335488 -406.698715) (xy 124.381335 -406.669251)
			(xy 124.430909 -406.64661) (xy 124.4832 -406.631255) (xy 124.537144 -406.623499) (xy 124.564394 -406.623012)
			(xy 125.427994 -406.623012) (xy 125.455249 -406.623434) (xy 125.509203 -406.631191) (xy 125.561504 -406.646548)
			(xy 125.611088 -406.669191) (xy 125.656944 -406.69866) (xy 125.69814 -406.734356) (xy 125.733836 -406.775551)
			(xy 125.763306 -406.821407) (xy 125.78595 -406.87099) (xy 125.801308 -406.923291) (xy 125.809065 -406.977245)
			(xy 125.809065 -407.031753) (xy 127.246575 -407.031753) (xy 127.246575 -406.977247) (xy 127.254333 -406.923296)
			(xy 127.26969 -406.870998) (xy 127.292334 -406.821418) (xy 127.321803 -406.775566) (xy 127.357499 -406.734375)
			(xy 127.398693 -406.698683) (xy 127.444548 -406.669217) (xy 127.49413 -406.646578) (xy 127.546429 -406.631226)
			(xy 127.600381 -406.623473) (xy 127.627634 -406.623012) (xy 128.491234 -406.623012) (xy 128.518485 -406.62346)
			(xy 128.572432 -406.631221) (xy 128.624725 -406.64658) (xy 128.674301 -406.669224) (xy 128.720149 -406.698693)
			(xy 128.761338 -406.734386) (xy 128.797028 -406.775578) (xy 128.826492 -406.821429) (xy 128.849132 -406.871007)
			(xy 128.864486 -406.923301) (xy 128.872242 -406.977249) (xy 128.872242 -407.031749) (xy 130.309898 -407.031749)
			(xy 130.309898 -406.977251) (xy 130.317654 -406.923309) (xy 130.333007 -406.871019) (xy 130.355645 -406.821446)
			(xy 130.385107 -406.775599) (xy 130.420794 -406.734412) (xy 130.461979 -406.698722) (xy 130.507823 -406.669257)
			(xy 130.557395 -406.646616) (xy 130.609683 -406.631259) (xy 130.663625 -406.6235) (xy 130.690874 -406.623012)
			(xy 131.554474 -406.623012) (xy 131.58173 -406.623433) (xy 131.635686 -406.631187) (xy 131.68799 -406.646542)
			(xy 131.737576 -406.669184) (xy 131.783435 -406.698653) (xy 131.824633 -406.734349) (xy 131.860331 -406.775544)
			(xy 131.889803 -406.821401) (xy 131.912449 -406.870986) (xy 131.927807 -406.923288) (xy 131.935565 -406.977245)
			(xy 131.935565 -407.031752) (xy 133.373075 -407.031752) (xy 133.373075 -406.977248) (xy 133.380832 -406.923299)
			(xy 133.396188 -406.871002) (xy 133.418831 -406.821424) (xy 133.448298 -406.775573) (xy 133.483992 -406.734382)
			(xy 133.525184 -406.69869) (xy 133.571036 -406.669224) (xy 133.620616 -406.646583) (xy 133.672912 -406.631229)
			(xy 133.726862 -406.623474) (xy 133.754114 -406.623012) (xy 134.617714 -406.623012) (xy 134.644966 -406.623459)
			(xy 134.698915 -406.631217) (xy 134.751211 -406.646574) (xy 134.800789 -406.669218) (xy 134.84664 -406.698686)
			(xy 134.887831 -406.734379) (xy 134.923523 -406.775571) (xy 134.952989 -406.821423) (xy 134.97563 -406.871002)
			(xy 134.990986 -406.923299) (xy 134.998742 -406.977248) (xy 134.998742 -407.031748) (xy 136.436398 -407.031748)
			(xy 136.436398 -406.977252) (xy 136.444153 -406.923312) (xy 136.459505 -406.871023) (xy 136.482142 -406.821452)
			(xy 136.511602 -406.775606) (xy 136.547287 -406.734419) (xy 136.588469 -406.69873) (xy 136.634311 -406.669264)
			(xy 136.68388 -406.646621) (xy 136.736167 -406.631263) (xy 136.790106 -406.623501) (xy 136.817354 -406.623012)
			(xy 137.680954 -406.623012) (xy 137.70821 -406.623432) (xy 137.762169 -406.631184) (xy 137.814475 -406.646537)
			(xy 137.864064 -406.669178) (xy 137.909925 -406.698646) (xy 137.951126 -406.734342) (xy 137.986826 -406.775538)
			(xy 138.0163 -406.821396) (xy 138.038947 -406.870981) (xy 138.054306 -406.923286) (xy 138.062065 -406.977244)
			(xy 138.062065 -407.03175) (xy 139.499598 -407.03175) (xy 139.499598 -406.97725) (xy 139.507354 -406.923306)
			(xy 139.522708 -406.871015) (xy 139.545348 -406.821441) (xy 139.574812 -406.775593) (xy 139.610501 -406.734405)
			(xy 139.651688 -406.698715) (xy 139.697535 -406.669251) (xy 139.747109 -406.64661) (xy 139.7994 -406.631255)
			(xy 139.853344 -406.623499) (xy 139.880594 -406.623012) (xy 140.744194 -406.623012) (xy 140.771449 -406.623434)
			(xy 140.825403 -406.631191) (xy 140.877704 -406.646548) (xy 140.927288 -406.669191) (xy 140.973144 -406.69866)
			(xy 141.01434 -406.734356) (xy 141.050036 -406.775551) (xy 141.079506 -406.821407) (xy 141.10215 -406.87099)
			(xy 141.117508 -406.923291) (xy 141.125265 -406.977245) (xy 141.125265 -407.031753) (xy 142.562775 -407.031753)
			(xy 142.562775 -406.977247) (xy 142.570533 -406.923296) (xy 142.58589 -406.870998) (xy 142.608534 -406.821418)
			(xy 142.638003 -406.775566) (xy 142.673699 -406.734375) (xy 142.714893 -406.698683) (xy 142.760748 -406.669217)
			(xy 142.81033 -406.646578) (xy 142.862629 -406.631226) (xy 142.916581 -406.623473) (xy 142.943834 -406.623012)
			(xy 143.807434 -406.623012) (xy 143.834685 -406.62346) (xy 143.888632 -406.631221) (xy 143.940925 -406.64658)
			(xy 143.990501 -406.669224) (xy 144.036349 -406.698693) (xy 144.077538 -406.734386) (xy 144.113228 -406.775578)
			(xy 144.142692 -406.821429) (xy 144.165332 -406.871007) (xy 144.180686 -406.923301) (xy 144.188442 -406.977249)
			(xy 144.188442 -407.031749) (xy 145.626098 -407.031749) (xy 145.626098 -406.977251) (xy 145.633854 -406.923309)
			(xy 145.649207 -406.871019) (xy 145.671845 -406.821446) (xy 145.701307 -406.775599) (xy 145.736994 -406.734412)
			(xy 145.778179 -406.698722) (xy 145.824023 -406.669257) (xy 145.873595 -406.646616) (xy 145.925883 -406.631259)
			(xy 145.979825 -406.6235) (xy 146.007074 -406.623012) (xy 146.870674 -406.623012) (xy 146.89793 -406.623433)
			(xy 146.951886 -406.631187) (xy 147.00419 -406.646542) (xy 147.053776 -406.669184) (xy 147.099635 -406.698653)
			(xy 147.140833 -406.734349) (xy 147.176531 -406.775544) (xy 147.206003 -406.821401) (xy 147.228649 -406.870986)
			(xy 147.244007 -406.923288) (xy 147.251765 -406.977245) (xy 147.251765 -407.031752) (xy 148.689275 -407.031752)
			(xy 148.689275 -406.977248) (xy 148.697032 -406.923299) (xy 148.712388 -406.871002) (xy 148.735031 -406.821424)
			(xy 148.764498 -406.775573) (xy 148.800192 -406.734382) (xy 148.841384 -406.69869) (xy 148.887236 -406.669224)
			(xy 148.936816 -406.646583) (xy 148.989112 -406.631229) (xy 149.043062 -406.623474) (xy 149.070314 -406.623012)
			(xy 149.933914 -406.623012) (xy 149.961166 -406.623459) (xy 150.015115 -406.631217) (xy 150.067411 -406.646574)
			(xy 150.116989 -406.669218) (xy 150.16284 -406.698686) (xy 150.204031 -406.734379) (xy 150.239723 -406.775571)
			(xy 150.269189 -406.821423) (xy 150.29183 -406.871002) (xy 150.307186 -406.923299) (xy 150.314942 -406.977248)
			(xy 150.314942 -407.031748) (xy 151.752598 -407.031748) (xy 151.752598 -406.977252) (xy 151.760353 -406.923312)
			(xy 151.775705 -406.871023) (xy 151.798342 -406.821452) (xy 151.827802 -406.775606) (xy 151.863487 -406.734419)
			(xy 151.904669 -406.69873) (xy 151.950511 -406.669264) (xy 152.00008 -406.646621) (xy 152.052367 -406.631263)
			(xy 152.106306 -406.623501) (xy 152.133554 -406.623012) (xy 152.997154 -406.623012) (xy 153.02441 -406.623432)
			(xy 153.078369 -406.631184) (xy 153.130675 -406.646537) (xy 153.180264 -406.669178) (xy 153.226125 -406.698646)
			(xy 153.267326 -406.734342) (xy 153.303026 -406.775538) (xy 153.3325 -406.821396) (xy 153.355147 -406.870981)
			(xy 153.370506 -406.923286) (xy 153.378265 -406.977244) (xy 153.378265 -407.03175) (xy 154.815798 -407.03175)
			(xy 154.815798 -406.97725) (xy 154.823554 -406.923306) (xy 154.838908 -406.871015) (xy 154.861548 -406.821441)
			(xy 154.891012 -406.775593) (xy 154.926701 -406.734405) (xy 154.967888 -406.698715) (xy 155.013735 -406.669251)
			(xy 155.063309 -406.64661) (xy 155.1156 -406.631255) (xy 155.169544 -406.623499) (xy 155.196794 -406.623012)
			(xy 156.060394 -406.623012) (xy 156.087649 -406.623434) (xy 156.141603 -406.631191) (xy 156.193904 -406.646548)
			(xy 156.243488 -406.669191) (xy 156.289344 -406.69866) (xy 156.33054 -406.734356) (xy 156.366236 -406.775551)
			(xy 156.395706 -406.821407) (xy 156.41835 -406.87099) (xy 156.433708 -406.923291) (xy 156.441465 -406.977245)
			(xy 156.441465 -407.031753) (xy 157.878975 -407.031753) (xy 157.878975 -406.977247) (xy 157.886733 -406.923296)
			(xy 157.90209 -406.870998) (xy 157.924734 -406.821418) (xy 157.954203 -406.775566) (xy 157.989899 -406.734375)
			(xy 158.031093 -406.698683) (xy 158.076948 -406.669217) (xy 158.12653 -406.646578) (xy 158.178829 -406.631226)
			(xy 158.232781 -406.623473) (xy 158.260034 -406.623012) (xy 159.123634 -406.623012) (xy 159.150885 -406.62346)
			(xy 159.204832 -406.631221) (xy 159.257125 -406.64658) (xy 159.306701 -406.669224) (xy 159.352549 -406.698693)
			(xy 159.393738 -406.734386) (xy 159.429428 -406.775578) (xy 159.458892 -406.821429) (xy 159.481532 -406.871007)
			(xy 159.496886 -406.923301) (xy 159.504642 -406.977249) (xy 159.504642 -407.031749) (xy 160.942298 -407.031749)
			(xy 160.942298 -406.977251) (xy 160.950054 -406.923309) (xy 160.965407 -406.871019) (xy 160.988045 -406.821446)
			(xy 161.017507 -406.775599) (xy 161.053194 -406.734412) (xy 161.094379 -406.698722) (xy 161.140223 -406.669257)
			(xy 161.189795 -406.646616) (xy 161.242083 -406.631259) (xy 161.296025 -406.6235) (xy 161.323274 -406.623012)
			(xy 162.186874 -406.623012) (xy 162.21413 -406.623433) (xy 162.268086 -406.631187) (xy 162.32039 -406.646542)
			(xy 162.369976 -406.669184) (xy 162.415835 -406.698653) (xy 162.457033 -406.734349) (xy 162.492731 -406.775544)
			(xy 162.522203 -406.821401) (xy 162.544849 -406.870986) (xy 162.560207 -406.923288) (xy 162.567965 -406.977245)
			(xy 162.567965 -407.031752) (xy 164.005475 -407.031752) (xy 164.005475 -406.977248) (xy 164.013232 -406.923299)
			(xy 164.028588 -406.871002) (xy 164.051231 -406.821424) (xy 164.080698 -406.775573) (xy 164.116392 -406.734382)
			(xy 164.157584 -406.69869) (xy 164.203436 -406.669224) (xy 164.253016 -406.646583) (xy 164.305312 -406.631229)
			(xy 164.359262 -406.623474) (xy 164.386514 -406.623012) (xy 165.250114 -406.623012) (xy 165.277366 -406.623459)
			(xy 165.331315 -406.631217) (xy 165.383611 -406.646574) (xy 165.433189 -406.669218) (xy 165.47904 -406.698686)
			(xy 165.520231 -406.734379) (xy 165.555923 -406.775571) (xy 165.585389 -406.821423) (xy 165.60803 -406.871002)
			(xy 165.623386 -406.923299) (xy 165.631142 -406.977248) (xy 165.631142 -407.031748) (xy 167.068798 -407.031748)
			(xy 167.068798 -406.977252) (xy 167.076553 -406.923312) (xy 167.091905 -406.871023) (xy 167.114542 -406.821452)
			(xy 167.144002 -406.775606) (xy 167.179687 -406.734419) (xy 167.220869 -406.69873) (xy 167.266711 -406.669264)
			(xy 167.31628 -406.646621) (xy 167.368567 -406.631263) (xy 167.422506 -406.623501) (xy 167.449754 -406.623012)
			(xy 168.313354 -406.623012) (xy 168.34061 -406.623432) (xy 168.394569 -406.631184) (xy 168.446875 -406.646537)
			(xy 168.496464 -406.669178) (xy 168.542325 -406.698646) (xy 168.583526 -406.734342) (xy 168.619226 -406.775538)
			(xy 168.6487 -406.821396) (xy 168.671347 -406.870981) (xy 168.686706 -406.923286) (xy 168.694465 -406.977244)
			(xy 168.694465 -407.031756) (xy 168.686706 -407.085714) (xy 168.671347 -407.138019) (xy 168.6487 -407.187604)
			(xy 168.619226 -407.233462) (xy 168.583526 -407.274658) (xy 168.542325 -407.310354) (xy 168.496464 -407.339822)
			(xy 168.446875 -407.362463) (xy 168.394569 -407.377816) (xy 168.34061 -407.385568) (xy 168.313354 -407.386028)
			(xy 167.449754 -407.386028) (xy 167.422506 -407.385499) (xy 167.368567 -407.377737) (xy 167.31628 -407.362379)
			(xy 167.266711 -407.339736) (xy 167.220869 -407.31027) (xy 167.179687 -407.274581) (xy 167.144002 -407.233394)
			(xy 167.114542 -407.187548) (xy 167.091905 -407.137977) (xy 167.076553 -407.085688) (xy 167.068798 -407.031748)
			(xy 165.631142 -407.031748) (xy 165.631142 -407.031752) (xy 165.623386 -407.085701) (xy 165.60803 -407.137998)
			(xy 165.585389 -407.187577) (xy 165.555923 -407.233429) (xy 165.520231 -407.274621) (xy 165.47904 -407.310314)
			(xy 165.433189 -407.339782) (xy 165.383611 -407.362426) (xy 165.331315 -407.377783) (xy 165.277366 -407.385541)
			(xy 165.250114 -407.386028) (xy 164.386514 -407.386028) (xy 164.359262 -407.385526) (xy 164.305312 -407.377771)
			(xy 164.253016 -407.362417) (xy 164.203436 -407.339776) (xy 164.157584 -407.31031) (xy 164.116392 -407.274618)
			(xy 164.080698 -407.233427) (xy 164.051231 -407.187576) (xy 164.028588 -407.137998) (xy 164.013232 -407.085701)
			(xy 164.005475 -407.031752) (xy 162.567965 -407.031752) (xy 162.567965 -407.031755) (xy 162.560207 -407.085712)
			(xy 162.544849 -407.138014) (xy 162.522203 -407.187599) (xy 162.492731 -407.233456) (xy 162.457033 -407.274651)
			(xy 162.415835 -407.310347) (xy 162.369976 -407.339816) (xy 162.32039 -407.362458) (xy 162.268086 -407.377813)
			(xy 162.21413 -407.385567) (xy 162.186874 -407.386028) (xy 161.323274 -407.386028) (xy 161.296025 -407.3855)
			(xy 161.242083 -407.377741) (xy 161.189795 -407.362384) (xy 161.140223 -407.339743) (xy 161.094379 -407.310278)
			(xy 161.053194 -407.274588) (xy 161.017507 -407.233401) (xy 160.988045 -407.187554) (xy 160.965407 -407.137981)
			(xy 160.950054 -407.085691) (xy 160.942298 -407.031749) (xy 159.504642 -407.031749) (xy 159.504642 -407.031751)
			(xy 159.496886 -407.085699) (xy 159.481532 -407.137993) (xy 159.458892 -407.187571) (xy 159.429428 -407.233422)
			(xy 159.393738 -407.274614) (xy 159.352549 -407.310307) (xy 159.306701 -407.339776) (xy 159.257125 -407.36242)
			(xy 159.204832 -407.377779) (xy 159.150885 -407.38554) (xy 159.123634 -407.386028) (xy 158.260034 -407.386028)
			(xy 158.232781 -407.385527) (xy 158.178829 -407.377774) (xy 158.12653 -407.362422) (xy 158.076948 -407.339783)
			(xy 158.031093 -407.310317) (xy 157.989899 -407.274625) (xy 157.954203 -407.233434) (xy 157.924734 -407.187582)
			(xy 157.90209 -407.138002) (xy 157.886733 -407.085704) (xy 157.878975 -407.031753) (xy 156.441465 -407.031753)
			(xy 156.441465 -407.031755) (xy 156.433708 -407.085709) (xy 156.41835 -407.13801) (xy 156.395706 -407.187593)
			(xy 156.366236 -407.233449) (xy 156.33054 -407.274644) (xy 156.289344 -407.31034) (xy 156.243488 -407.339809)
			(xy 156.193904 -407.362452) (xy 156.141603 -407.377809) (xy 156.087649 -407.385566) (xy 156.060394 -407.386028)
			(xy 155.196794 -407.386028) (xy 155.169544 -407.385501) (xy 155.1156 -407.377745) (xy 155.063309 -407.36239)
			(xy 155.013735 -407.339749) (xy 154.967888 -407.310285) (xy 154.926701 -407.274595) (xy 154.891012 -407.233407)
			(xy 154.861548 -407.187559) (xy 154.838908 -407.137985) (xy 154.823554 -407.085694) (xy 154.815798 -407.03175)
			(xy 153.378265 -407.03175) (xy 153.378265 -407.031756) (xy 153.370506 -407.085714) (xy 153.355147 -407.138019)
			(xy 153.3325 -407.187604) (xy 153.303026 -407.233462) (xy 153.267326 -407.274658) (xy 153.226125 -407.310354)
			(xy 153.180264 -407.339822) (xy 153.130675 -407.362463) (xy 153.078369 -407.377816) (xy 153.02441 -407.385568)
			(xy 152.997154 -407.386028) (xy 152.133554 -407.386028) (xy 152.106306 -407.385499) (xy 152.052367 -407.377737)
			(xy 152.00008 -407.362379) (xy 151.950511 -407.339736) (xy 151.904669 -407.31027) (xy 151.863487 -407.274581)
			(xy 151.827802 -407.233394) (xy 151.798342 -407.187548) (xy 151.775705 -407.137977) (xy 151.760353 -407.085688)
			(xy 151.752598 -407.031748) (xy 150.314942 -407.031748) (xy 150.314942 -407.031752) (xy 150.307186 -407.085701)
			(xy 150.29183 -407.137998) (xy 150.269189 -407.187577) (xy 150.239723 -407.233429) (xy 150.204031 -407.274621)
			(xy 150.16284 -407.310314) (xy 150.116989 -407.339782) (xy 150.067411 -407.362426) (xy 150.015115 -407.377783)
			(xy 149.961166 -407.385541) (xy 149.933914 -407.386028) (xy 149.070314 -407.386028) (xy 149.043062 -407.385526)
			(xy 148.989112 -407.377771) (xy 148.936816 -407.362417) (xy 148.887236 -407.339776) (xy 148.841384 -407.31031)
			(xy 148.800192 -407.274618) (xy 148.764498 -407.233427) (xy 148.735031 -407.187576) (xy 148.712388 -407.137998)
			(xy 148.697032 -407.085701) (xy 148.689275 -407.031752) (xy 147.251765 -407.031752) (xy 147.251765 -407.031755)
			(xy 147.244007 -407.085712) (xy 147.228649 -407.138014) (xy 147.206003 -407.187599) (xy 147.176531 -407.233456)
			(xy 147.140833 -407.274651) (xy 147.099635 -407.310347) (xy 147.053776 -407.339816) (xy 147.00419 -407.362458)
			(xy 146.951886 -407.377813) (xy 146.89793 -407.385567) (xy 146.870674 -407.386028) (xy 146.007074 -407.386028)
			(xy 145.979825 -407.3855) (xy 145.925883 -407.377741) (xy 145.873595 -407.362384) (xy 145.824023 -407.339743)
			(xy 145.778179 -407.310278) (xy 145.736994 -407.274588) (xy 145.701307 -407.233401) (xy 145.671845 -407.187554)
			(xy 145.649207 -407.137981) (xy 145.633854 -407.085691) (xy 145.626098 -407.031749) (xy 144.188442 -407.031749)
			(xy 144.188442 -407.031751) (xy 144.180686 -407.085699) (xy 144.165332 -407.137993) (xy 144.142692 -407.187571)
			(xy 144.113228 -407.233422) (xy 144.077538 -407.274614) (xy 144.036349 -407.310307) (xy 143.990501 -407.339776)
			(xy 143.940925 -407.36242) (xy 143.888632 -407.377779) (xy 143.834685 -407.38554) (xy 143.807434 -407.386028)
			(xy 142.943834 -407.386028) (xy 142.916581 -407.385527) (xy 142.862629 -407.377774) (xy 142.81033 -407.362422)
			(xy 142.760748 -407.339783) (xy 142.714893 -407.310317) (xy 142.673699 -407.274625) (xy 142.638003 -407.233434)
			(xy 142.608534 -407.187582) (xy 142.58589 -407.138002) (xy 142.570533 -407.085704) (xy 142.562775 -407.031753)
			(xy 141.125265 -407.031753) (xy 141.125265 -407.031755) (xy 141.117508 -407.085709) (xy 141.10215 -407.13801)
			(xy 141.079506 -407.187593) (xy 141.050036 -407.233449) (xy 141.01434 -407.274644) (xy 140.973144 -407.31034)
			(xy 140.927288 -407.339809) (xy 140.877704 -407.362452) (xy 140.825403 -407.377809) (xy 140.771449 -407.385566)
			(xy 140.744194 -407.386028) (xy 139.880594 -407.386028) (xy 139.853344 -407.385501) (xy 139.7994 -407.377745)
			(xy 139.747109 -407.36239) (xy 139.697535 -407.339749) (xy 139.651688 -407.310285) (xy 139.610501 -407.274595)
			(xy 139.574812 -407.233407) (xy 139.545348 -407.187559) (xy 139.522708 -407.137985) (xy 139.507354 -407.085694)
			(xy 139.499598 -407.03175) (xy 138.062065 -407.03175) (xy 138.062065 -407.031756) (xy 138.054306 -407.085714)
			(xy 138.038947 -407.138019) (xy 138.0163 -407.187604) (xy 137.986826 -407.233462) (xy 137.951126 -407.274658)
			(xy 137.909925 -407.310354) (xy 137.864064 -407.339822) (xy 137.814475 -407.362463) (xy 137.762169 -407.377816)
			(xy 137.70821 -407.385568) (xy 137.680954 -407.386028) (xy 136.817354 -407.386028) (xy 136.790106 -407.385499)
			(xy 136.736167 -407.377737) (xy 136.68388 -407.362379) (xy 136.634311 -407.339736) (xy 136.588469 -407.31027)
			(xy 136.547287 -407.274581) (xy 136.511602 -407.233394) (xy 136.482142 -407.187548) (xy 136.459505 -407.137977)
			(xy 136.444153 -407.085688) (xy 136.436398 -407.031748) (xy 134.998742 -407.031748) (xy 134.998742 -407.031752)
			(xy 134.990986 -407.085701) (xy 134.97563 -407.137998) (xy 134.952989 -407.187577) (xy 134.923523 -407.233429)
			(xy 134.887831 -407.274621) (xy 134.84664 -407.310314) (xy 134.800789 -407.339782) (xy 134.751211 -407.362426)
			(xy 134.698915 -407.377783) (xy 134.644966 -407.385541) (xy 134.617714 -407.386028) (xy 133.754114 -407.386028)
			(xy 133.726862 -407.385526) (xy 133.672912 -407.377771) (xy 133.620616 -407.362417) (xy 133.571036 -407.339776)
			(xy 133.525184 -407.31031) (xy 133.483992 -407.274618) (xy 133.448298 -407.233427) (xy 133.418831 -407.187576)
			(xy 133.396188 -407.137998) (xy 133.380832 -407.085701) (xy 133.373075 -407.031752) (xy 131.935565 -407.031752)
			(xy 131.935565 -407.031755) (xy 131.927807 -407.085712) (xy 131.912449 -407.138014) (xy 131.889803 -407.187599)
			(xy 131.860331 -407.233456) (xy 131.824633 -407.274651) (xy 131.783435 -407.310347) (xy 131.737576 -407.339816)
			(xy 131.68799 -407.362458) (xy 131.635686 -407.377813) (xy 131.58173 -407.385567) (xy 131.554474 -407.386028)
			(xy 130.690874 -407.386028) (xy 130.663625 -407.3855) (xy 130.609683 -407.377741) (xy 130.557395 -407.362384)
			(xy 130.507823 -407.339743) (xy 130.461979 -407.310278) (xy 130.420794 -407.274588) (xy 130.385107 -407.233401)
			(xy 130.355645 -407.187554) (xy 130.333007 -407.137981) (xy 130.317654 -407.085691) (xy 130.309898 -407.031749)
			(xy 128.872242 -407.031749) (xy 128.872242 -407.031751) (xy 128.864486 -407.085699) (xy 128.849132 -407.137993)
			(xy 128.826492 -407.187571) (xy 128.797028 -407.233422) (xy 128.761338 -407.274614) (xy 128.720149 -407.310307)
			(xy 128.674301 -407.339776) (xy 128.624725 -407.36242) (xy 128.572432 -407.377779) (xy 128.518485 -407.38554)
			(xy 128.491234 -407.386028) (xy 127.627634 -407.386028) (xy 127.600381 -407.385527) (xy 127.546429 -407.377774)
			(xy 127.49413 -407.362422) (xy 127.444548 -407.339783) (xy 127.398693 -407.310317) (xy 127.357499 -407.274625)
			(xy 127.321803 -407.233434) (xy 127.292334 -407.187582) (xy 127.26969 -407.138002) (xy 127.254333 -407.085704)
			(xy 127.246575 -407.031753) (xy 125.809065 -407.031753) (xy 125.809065 -407.031755) (xy 125.801308 -407.085709)
			(xy 125.78595 -407.13801) (xy 125.763306 -407.187593) (xy 125.733836 -407.233449) (xy 125.69814 -407.274644)
			(xy 125.656944 -407.31034) (xy 125.611088 -407.339809) (xy 125.561504 -407.362452) (xy 125.509203 -407.377809)
			(xy 125.455249 -407.385566) (xy 125.427994 -407.386028) (xy 124.564394 -407.386028) (xy 124.537144 -407.385501)
			(xy 124.4832 -407.377745) (xy 124.430909 -407.36239) (xy 124.381335 -407.339749) (xy 124.335488 -407.310285)
			(xy 124.294301 -407.274595) (xy 124.258612 -407.233407) (xy 124.229148 -407.187559) (xy 124.206508 -407.137985)
			(xy 124.191154 -407.085694) (xy 124.183398 -407.03175) (xy 122.745865 -407.03175) (xy 122.745865 -407.031756)
			(xy 122.738106 -407.085714) (xy 122.722747 -407.138019) (xy 122.7001 -407.187604) (xy 122.670626 -407.233462)
			(xy 122.634926 -407.274658) (xy 122.593725 -407.310354) (xy 122.547864 -407.339822) (xy 122.498275 -407.362463)
			(xy 122.445969 -407.377816) (xy 122.39201 -407.385568) (xy 122.364754 -407.386028) (xy 121.501154 -407.386028)
			(xy 121.473906 -407.385499) (xy 121.419967 -407.377737) (xy 121.36768 -407.362379) (xy 121.318111 -407.339736)
			(xy 121.272269 -407.31027) (xy 121.231087 -407.274581) (xy 121.195402 -407.233394) (xy 121.165942 -407.187548)
			(xy 121.143305 -407.137977) (xy 121.127953 -407.085688) (xy 121.120198 -407.031748) (xy 107.861153 -407.031748)
			(xy 107.86873 -407.084449) (xy 107.86873 -407.138951) (xy 107.860974 -407.192898) (xy 107.84562 -407.245192)
			(xy 107.822979 -407.294769) (xy 107.793514 -407.34062) (xy 107.757824 -407.38181) (xy 107.716636 -407.417502)
			(xy 107.670787 -407.44697) (xy 107.621211 -407.469613) (xy 107.568918 -407.48497) (xy 107.514971 -407.492729)
			(xy 107.48772 -407.493216) (xy 106.62412 -407.493216) (xy 106.596867 -407.492738) (xy 106.542915 -407.484984)
			(xy 106.490616 -407.46963) (xy 106.441034 -407.446989) (xy 106.395179 -407.417522) (xy 106.353985 -407.381829)
			(xy 106.31829 -407.340637) (xy 106.288821 -407.294783) (xy 106.266177 -407.245203) (xy 106.250821 -407.192905)
			(xy 106.243063 -407.138953) (xy 96.495694 -407.138953) (xy 96.473493 -407.18757) (xy 96.444028 -407.233421)
			(xy 96.408339 -407.274612) (xy 96.367151 -407.310306) (xy 96.321303 -407.339775) (xy 96.271728 -407.362419)
			(xy 96.219435 -407.377778) (xy 96.165489 -407.38554) (xy 96.138238 -407.386028) (xy 95.274638 -407.386028)
			(xy 95.247385 -407.385527) (xy 95.193433 -407.377775) (xy 95.141133 -407.362423) (xy 95.091551 -407.339784)
			(xy 95.045695 -407.310319) (xy 95.0045 -407.274627) (xy 94.968804 -407.233435) (xy 94.939334 -407.187583)
			(xy 94.91669 -407.138003) (xy 94.901333 -407.085705) (xy 94.893575 -407.031753) (xy 93.456065 -407.031753)
			(xy 93.456065 -407.031754) (xy 93.448308 -407.085708) (xy 93.432951 -407.138009) (xy 93.410307 -407.187592)
			(xy 93.380837 -407.233448) (xy 93.345141 -407.274643) (xy 93.303946 -407.310338) (xy 93.25809 -407.339808)
			(xy 93.208507 -407.362451) (xy 93.156206 -407.377808) (xy 93.102252 -407.385565) (xy 93.074998 -407.386028)
			(xy 92.211398 -407.386028) (xy 92.184148 -407.385502) (xy 92.130204 -407.377745) (xy 92.077912 -407.362391)
			(xy 92.028338 -407.339751) (xy 91.98249 -407.310286) (xy 91.941302 -407.274596) (xy 91.905613 -407.233408)
			(xy 91.876148 -407.187561) (xy 91.853508 -407.137986) (xy 91.838154 -407.085694) (xy 91.830398 -407.03175)
			(xy 90.392865 -407.03175) (xy 90.392865 -407.031756) (xy 90.385107 -407.085714) (xy 90.369748 -407.138018)
			(xy 90.347101 -407.187603) (xy 90.317627 -407.233461) (xy 90.281927 -407.274657) (xy 90.240727 -407.310352)
			(xy 90.194866 -407.339821) (xy 90.145278 -407.362462) (xy 90.092973 -407.377815) (xy 90.039014 -407.385568)
			(xy 90.011758 -407.386028) (xy 89.148158 -407.386028) (xy 89.12091 -407.385499) (xy 89.06697 -407.377738)
			(xy 89.014683 -407.36238) (xy 88.965114 -407.339738) (xy 88.919271 -407.310272) (xy 88.878088 -407.274582)
			(xy 88.842403 -407.233395) (xy 88.812942 -407.187549) (xy 88.790305 -407.137978) (xy 88.774953 -407.085689)
			(xy 88.767198 -407.031748) (xy 87.329542 -407.031748) (xy 87.329542 -407.031752) (xy 87.321786 -407.085701)
			(xy 87.306431 -407.137997) (xy 87.28379 -407.187576) (xy 87.254324 -407.233427) (xy 87.218632 -407.274619)
			(xy 87.177442 -407.310313) (xy 87.131591 -407.339781) (xy 87.082014 -407.362424) (xy 87.029718 -407.377782)
			(xy 86.97577 -407.385541) (xy 86.948518 -407.386028) (xy 86.084918 -407.386028) (xy 86.057666 -407.385526)
			(xy 86.003716 -407.377771) (xy 85.951418 -407.362418) (xy 85.901839 -407.339778) (xy 85.855986 -407.310312)
			(xy 85.814793 -407.27462) (xy 85.779099 -407.233429) (xy 85.749631 -407.187577) (xy 85.726989 -407.137998)
			(xy 85.711632 -407.085702) (xy 85.703875 -407.031752) (xy 84.266365 -407.031752) (xy 84.266365 -407.031755)
			(xy 84.258607 -407.085711) (xy 84.243249 -407.138013) (xy 84.220604 -407.187598) (xy 84.191132 -407.233454)
			(xy 84.155434 -407.27465) (xy 84.114237 -407.310345) (xy 84.068378 -407.339814) (xy 84.018793 -407.362457)
			(xy 83.96649 -407.377812) (xy 83.912533 -407.385567) (xy 83.885278 -407.386028) (xy 83.021678 -407.386028)
			(xy 82.994429 -407.3855) (xy 82.940487 -407.377742) (xy 82.888197 -407.362385) (xy 82.838626 -407.339744)
			(xy 82.79278 -407.310279) (xy 82.751595 -407.274589) (xy 82.715908 -407.233402) (xy 82.686445 -407.187555)
			(xy 82.663807 -407.137982) (xy 82.648454 -407.085692) (xy 82.640698 -407.031749) (xy 81.203042 -407.031749)
			(xy 81.203042 -407.031751) (xy 81.195286 -407.085698) (xy 81.179932 -407.137993) (xy 81.157293 -407.18757)
			(xy 81.127828 -407.233421) (xy 81.092139 -407.274612) (xy 81.050951 -407.310306) (xy 81.005103 -407.339775)
			(xy 80.955528 -407.362419) (xy 80.903235 -407.377778) (xy 80.849289 -407.38554) (xy 80.822038 -407.386028)
			(xy 79.958438 -407.386028) (xy 79.931185 -407.385527) (xy 79.877233 -407.377775) (xy 79.824933 -407.362423)
			(xy 79.775351 -407.339784) (xy 79.729495 -407.310319) (xy 79.6883 -407.274627) (xy 79.652604 -407.233435)
			(xy 79.623134 -407.187583) (xy 79.60049 -407.138003) (xy 79.585133 -407.085705) (xy 79.577375 -407.031753)
			(xy 78.139865 -407.031753) (xy 78.139865 -407.031754) (xy 78.132108 -407.085708) (xy 78.116751 -407.138009)
			(xy 78.094107 -407.187592) (xy 78.064637 -407.233448) (xy 78.028941 -407.274643) (xy 77.987746 -407.310338)
			(xy 77.94189 -407.339808) (xy 77.892307 -407.362451) (xy 77.840006 -407.377808) (xy 77.786052 -407.385565)
			(xy 77.758798 -407.386028) (xy 76.895198 -407.386028) (xy 76.867948 -407.385502) (xy 76.814004 -407.377745)
			(xy 76.761712 -407.362391) (xy 76.712138 -407.339751) (xy 76.66629 -407.310286) (xy 76.625102 -407.274596)
			(xy 76.589413 -407.233408) (xy 76.559948 -407.187561) (xy 76.537308 -407.137986) (xy 76.521954 -407.085694)
			(xy 76.514198 -407.03175) (xy 75.076665 -407.03175) (xy 75.076665 -407.031756) (xy 75.068907 -407.085714)
			(xy 75.053548 -407.138018) (xy 75.030901 -407.187603) (xy 75.001427 -407.233461) (xy 74.965727 -407.274657)
			(xy 74.924527 -407.310352) (xy 74.878666 -407.339821) (xy 74.829078 -407.362462) (xy 74.776773 -407.377815)
			(xy 74.722814 -407.385568) (xy 74.695558 -407.386028) (xy 73.831958 -407.386028) (xy 73.80471 -407.385499)
			(xy 73.75077 -407.377738) (xy 73.698483 -407.36238) (xy 73.648914 -407.339738) (xy 73.603071 -407.310272)
			(xy 73.561888 -407.274582) (xy 73.526203 -407.233395) (xy 73.496742 -407.187549) (xy 73.474105 -407.137978)
			(xy 73.458753 -407.085689) (xy 73.450998 -407.031748) (xy 72.013342 -407.031748) (xy 72.013342 -407.031752)
			(xy 72.005586 -407.085701) (xy 71.990231 -407.137997) (xy 71.96759 -407.187576) (xy 71.938124 -407.233427)
			(xy 71.902432 -407.274619) (xy 71.861242 -407.310313) (xy 71.815391 -407.339781) (xy 71.765814 -407.362424)
			(xy 71.713518 -407.377782) (xy 71.65957 -407.385541) (xy 71.632318 -407.386028) (xy 70.768718 -407.386028)
			(xy 70.741466 -407.385526) (xy 70.687516 -407.377771) (xy 70.635218 -407.362418) (xy 70.585639 -407.339778)
			(xy 70.539786 -407.310312) (xy 70.498593 -407.27462) (xy 70.462899 -407.233429) (xy 70.433431 -407.187577)
			(xy 70.410789 -407.137998) (xy 70.395432 -407.085702) (xy 70.387675 -407.031752) (xy 68.950165 -407.031752)
			(xy 68.950165 -407.031755) (xy 68.942407 -407.085711) (xy 68.927049 -407.138013) (xy 68.904404 -407.187598)
			(xy 68.874932 -407.233454) (xy 68.839234 -407.27465) (xy 68.798037 -407.310345) (xy 68.752178 -407.339814)
			(xy 68.702593 -407.362457) (xy 68.65029 -407.377812) (xy 68.596333 -407.385567) (xy 68.569078 -407.386028)
			(xy 67.705478 -407.386028) (xy 67.678229 -407.3855) (xy 67.624287 -407.377742) (xy 67.571997 -407.362385)
			(xy 67.522426 -407.339744) (xy 67.47658 -407.310279) (xy 67.435395 -407.274589) (xy 67.399708 -407.233402)
			(xy 67.370245 -407.187555) (xy 67.347607 -407.137982) (xy 67.332254 -407.085692) (xy 67.324498 -407.031749)
			(xy 65.886842 -407.031749) (xy 65.886842 -407.031751) (xy 65.879086 -407.085698) (xy 65.863732 -407.137993)
			(xy 65.841093 -407.18757) (xy 65.811628 -407.233421) (xy 65.775939 -407.274612) (xy 65.734751 -407.310306)
			(xy 65.688903 -407.339775) (xy 65.639328 -407.362419) (xy 65.587035 -407.377778) (xy 65.533089 -407.38554)
			(xy 65.505838 -407.386028) (xy 64.642238 -407.386028) (xy 64.614985 -407.385527) (xy 64.561033 -407.377775)
			(xy 64.508733 -407.362423) (xy 64.459151 -407.339784) (xy 64.413295 -407.310319) (xy 64.3721 -407.274627)
			(xy 64.336404 -407.233435) (xy 64.306934 -407.187583) (xy 64.28429 -407.138003) (xy 64.268933 -407.085705)
			(xy 64.261175 -407.031753) (xy 62.823665 -407.031753) (xy 62.823665 -407.031754) (xy 62.815908 -407.085708)
			(xy 62.800551 -407.138009) (xy 62.777907 -407.187592) (xy 62.748437 -407.233448) (xy 62.712741 -407.274643)
			(xy 62.671546 -407.310338) (xy 62.62569 -407.339808) (xy 62.576107 -407.362451) (xy 62.523806 -407.377808)
			(xy 62.469852 -407.385565) (xy 62.442598 -407.386028) (xy 61.578998 -407.386028) (xy 61.551748 -407.385502)
			(xy 61.497804 -407.377745) (xy 61.445512 -407.362391) (xy 61.395938 -407.339751) (xy 61.35009 -407.310286)
			(xy 61.308902 -407.274596) (xy 61.273213 -407.233408) (xy 61.243748 -407.187561) (xy 61.221108 -407.137986)
			(xy 61.205754 -407.085694) (xy 61.197998 -407.03175) (xy 59.760465 -407.03175) (xy 59.760465 -407.031756)
			(xy 59.752707 -407.085714) (xy 59.737348 -407.138018) (xy 59.714701 -407.187603) (xy 59.685227 -407.233461)
			(xy 59.649527 -407.274657) (xy 59.608327 -407.310352) (xy 59.562466 -407.339821) (xy 59.512878 -407.362462)
			(xy 59.460573 -407.377815) (xy 59.406614 -407.385568) (xy 59.379358 -407.386028) (xy 58.515758 -407.386028)
			(xy 58.48851 -407.385499) (xy 58.43457 -407.377738) (xy 58.382283 -407.36238) (xy 58.332714 -407.339738)
			(xy 58.286871 -407.310272) (xy 58.245688 -407.274582) (xy 58.210003 -407.233395) (xy 58.180542 -407.187549)
			(xy 58.157905 -407.137978) (xy 58.142553 -407.085689) (xy 58.134798 -407.031748) (xy 56.697142 -407.031748)
			(xy 56.697142 -407.031752) (xy 56.689386 -407.085701) (xy 56.674031 -407.137997) (xy 56.65139 -407.187576)
			(xy 56.621924 -407.233427) (xy 56.586232 -407.274619) (xy 56.545042 -407.310313) (xy 56.499191 -407.339781)
			(xy 56.449614 -407.362424) (xy 56.397318 -407.377782) (xy 56.34337 -407.385541) (xy 56.316118 -407.386028)
			(xy 55.452518 -407.386028) (xy 55.425266 -407.385526) (xy 55.371316 -407.377771) (xy 55.319018 -407.362418)
			(xy 55.269439 -407.339778) (xy 55.223586 -407.310312) (xy 55.182393 -407.27462) (xy 55.146699 -407.233429)
			(xy 55.117231 -407.187577) (xy 55.094589 -407.137998) (xy 55.079232 -407.085702) (xy 55.071475 -407.031752)
			(xy 53.633965 -407.031752) (xy 53.633965 -407.031755) (xy 53.626207 -407.085711) (xy 53.610849 -407.138013)
			(xy 53.588204 -407.187598) (xy 53.558732 -407.233454) (xy 53.523034 -407.27465) (xy 53.481837 -407.310345)
			(xy 53.435978 -407.339814) (xy 53.386393 -407.362457) (xy 53.33409 -407.377812) (xy 53.280133 -407.385567)
			(xy 53.252878 -407.386028) (xy 52.389278 -407.386028) (xy 52.362029 -407.3855) (xy 52.308087 -407.377742)
			(xy 52.255797 -407.362385) (xy 52.206226 -407.339744) (xy 52.16038 -407.310279) (xy 52.119195 -407.274589)
			(xy 52.083508 -407.233402) (xy 52.054045 -407.187555) (xy 52.031407 -407.137982) (xy 52.016054 -407.085692)
			(xy 52.008298 -407.031749) (xy 50.570642 -407.031749) (xy 50.570642 -407.031751) (xy 50.562886 -407.085698)
			(xy 50.547532 -407.137993) (xy 50.524893 -407.18757) (xy 50.495428 -407.233421) (xy 50.459739 -407.274612)
			(xy 50.418551 -407.310306) (xy 50.372703 -407.339775) (xy 50.323128 -407.362419) (xy 50.270835 -407.377778)
			(xy 50.216889 -407.38554) (xy 50.189638 -407.386028) (xy 49.326038 -407.386028) (xy 49.298785 -407.385527)
			(xy 49.244833 -407.377775) (xy 49.192533 -407.362423) (xy 49.142951 -407.339784) (xy 49.097095 -407.310319)
			(xy 49.0559 -407.274627) (xy 49.020204 -407.233435) (xy 48.990734 -407.187583) (xy 48.96809 -407.138003)
			(xy 48.952733 -407.085705) (xy 48.944975 -407.031753) (xy 16.741648 -407.031753) (xy 16.741648 -407.035508)
			(xy 16.741162 -407.062759) (xy 16.733406 -407.116707) (xy 16.718051 -407.169002) (xy 16.695409 -407.218579)
			(xy 16.665943 -407.264429) (xy 16.630252 -407.30562) (xy 16.589061 -407.341311) (xy 16.543211 -407.370777)
			(xy 16.493634 -407.393419) (xy 16.441339 -407.408774) (xy 16.387391 -407.41653) (xy 16.332889 -407.41653)
			(xy 16.278941 -407.408774) (xy 16.226646 -407.393419) (xy 16.177069 -407.370777) (xy 16.131219 -407.341311)
			(xy 16.090028 -407.30562) (xy 16.054337 -407.264429) (xy 16.024871 -407.218579) (xy 16.002229 -407.169002)
			(xy 15.986874 -407.116707) (xy 15.979118 -407.062759) (xy 15.978632 -407.035508) (xy 6.990842 -407.035508)
			(xy 6.992366 -407.037032) (xy 7.053122 -407.098555) (xy 7.169238 -407.226701) (xy 7.278928 -407.360388)
			(xy 7.381928 -407.499295) (xy 7.477991 -407.643088) (xy 7.566884 -407.791419) (xy 7.648395 -407.943932)
			(xy 7.722326 -408.10026) (xy 7.7885 -408.260026) (xy 7.846758 -408.422846) (xy 7.896958 -408.588328)
			(xy 7.938981 -408.756072) (xy 7.972725 -408.925677) (xy 7.998109 -409.096732) (xy 8.015072 -409.268826)
			(xy 8.023573 -409.441546) (xy 8.024114 -409.52801) (xy 8.024114 -410.057457) (xy 48.944923 -410.057457)
			(xy 48.944923 -410.002943) (xy 48.952682 -409.948984) (xy 48.968041 -409.896679) (xy 48.990688 -409.847092)
			(xy 49.020162 -409.801233) (xy 49.055863 -409.760036) (xy 49.097064 -409.724339) (xy 49.142925 -409.69487)
			(xy 49.192515 -409.672228) (xy 49.244821 -409.656874) (xy 49.298781 -409.64912) (xy 49.326038 -409.64866)
			(xy 50.189638 -409.64866) (xy 50.216885 -409.649213) (xy 50.270824 -409.656973) (xy 50.32311 -409.67233)
			(xy 50.372678 -409.694972) (xy 50.41852 -409.724436) (xy 50.459702 -409.760125) (xy 50.495386 -409.801311)
			(xy 50.524847 -409.847155) (xy 50.547483 -409.896726) (xy 50.562835 -409.949013) (xy 50.57059 -410.002953)
			(xy 50.57059 -410.057447) (xy 50.570589 -410.057453) (xy 52.008246 -410.057453) (xy 52.008246 -410.002947)
			(xy 52.016002 -409.948997) (xy 52.031358 -409.8967) (xy 52.053999 -409.84712) (xy 52.083466 -409.801267)
			(xy 52.119158 -409.760074) (xy 52.160349 -409.724379) (xy 52.206201 -409.69491) (xy 52.255779 -409.672265)
			(xy 52.308076 -409.656907) (xy 52.362025 -409.649147) (xy 52.389278 -409.64866) (xy 53.252878 -409.64866)
			(xy 53.28013 -409.649186) (xy 53.334078 -409.65694) (xy 53.386374 -409.672292) (xy 53.435953 -409.694932)
			(xy 53.481805 -409.724397) (xy 53.522997 -409.760087) (xy 53.55869 -409.801277) (xy 53.588158 -409.847127)
			(xy 53.6108 -409.896705) (xy 53.626156 -409.949) (xy 53.633913 -410.002948) (xy 53.633913 -410.057452)
			(xy 53.633912 -410.057456) (xy 55.071423 -410.057456) (xy 55.071423 -410.002944) (xy 55.079181 -409.948987)
			(xy 55.094539 -409.896683) (xy 55.117185 -409.847098) (xy 55.146657 -409.80124) (xy 55.182356 -409.760043)
			(xy 55.223554 -409.724346) (xy 55.269413 -409.694876) (xy 55.319 -409.672233) (xy 55.371305 -409.656877)
			(xy 55.425262 -409.649122) (xy 55.452518 -409.64866) (xy 56.316118 -409.64866) (xy 56.343366 -409.649211)
			(xy 56.397307 -409.656969) (xy 56.449595 -409.672325) (xy 56.499166 -409.694965) (xy 56.54501 -409.724429)
			(xy 56.586195 -409.760118) (xy 56.621882 -409.801304) (xy 56.651344 -409.84715) (xy 56.673982 -409.896721)
			(xy 56.689334 -409.94901) (xy 56.69709 -410.002952) (xy 56.69709 -410.057448) (xy 56.697089 -410.057452)
			(xy 58.134746 -410.057452) (xy 58.134746 -410.002948) (xy 58.142502 -409.949) (xy 58.157856 -409.896704)
			(xy 58.180496 -409.847125) (xy 58.209961 -409.801273) (xy 58.245651 -409.760081) (xy 58.28684 -409.724386)
			(xy 58.332689 -409.694916) (xy 58.382265 -409.672271) (xy 58.434559 -409.656911) (xy 58.488506 -409.649149)
			(xy 58.515758 -409.64866) (xy 59.379358 -409.64866) (xy 59.406611 -409.649184) (xy 59.460561 -409.656936)
			(xy 59.51286 -409.672287) (xy 59.562441 -409.694925) (xy 59.608296 -409.72439) (xy 59.64949 -409.76008)
			(xy 59.685185 -409.801271) (xy 59.714655 -409.847122) (xy 59.737298 -409.896701) (xy 59.752655 -409.948997)
			(xy 59.760413 -410.002948) (xy 59.760413 -410.057452) (xy 59.760413 -410.057453) (xy 61.197946 -410.057453)
			(xy 61.197946 -410.002947) (xy 61.205703 -409.948994) (xy 61.221059 -409.896695) (xy 61.243702 -409.847114)
			(xy 61.273171 -409.80126) (xy 61.308865 -409.760066) (xy 61.350059 -409.724372) (xy 61.395913 -409.694903)
			(xy 61.445494 -409.67226) (xy 61.497793 -409.656903) (xy 61.551745 -409.649146) (xy 61.578998 -409.64866)
			(xy 62.442598 -409.64866) (xy 62.469849 -409.649187) (xy 62.523795 -409.656943) (xy 62.576089 -409.672298)
			(xy 62.625665 -409.694938) (xy 62.671515 -409.724404) (xy 62.712704 -409.760094) (xy 62.748395 -409.801284)
			(xy 62.777861 -409.847133) (xy 62.800502 -409.896709) (xy 62.815856 -409.949003) (xy 62.823613 -410.002949)
			(xy 62.823613 -410.057451) (xy 62.823612 -410.057457) (xy 64.261123 -410.057457) (xy 64.261123 -410.002943)
			(xy 64.268882 -409.948984) (xy 64.284241 -409.896679) (xy 64.306888 -409.847092) (xy 64.336362 -409.801233)
			(xy 64.372063 -409.760036) (xy 64.413264 -409.724339) (xy 64.459125 -409.69487) (xy 64.508715 -409.672228)
			(xy 64.561021 -409.656874) (xy 64.614981 -409.64912) (xy 64.642238 -409.64866) (xy 65.505838 -409.64866)
			(xy 65.533085 -409.649213) (xy 65.587024 -409.656973) (xy 65.63931 -409.67233) (xy 65.688878 -409.694972)
			(xy 65.73472 -409.724436) (xy 65.775902 -409.760125) (xy 65.811586 -409.801311) (xy 65.841047 -409.847155)
			(xy 65.863683 -409.896726) (xy 65.879035 -409.949013) (xy 65.88679 -410.002953) (xy 65.88679 -410.057447)
			(xy 65.886789 -410.057453) (xy 67.324446 -410.057453) (xy 67.324446 -410.002947) (xy 67.332202 -409.948997)
			(xy 67.347558 -409.8967) (xy 67.370199 -409.84712) (xy 67.399666 -409.801267) (xy 67.435358 -409.760074)
			(xy 67.476549 -409.724379) (xy 67.522401 -409.69491) (xy 67.571979 -409.672265) (xy 67.624276 -409.656907)
			(xy 67.678225 -409.649147) (xy 67.705478 -409.64866) (xy 68.569078 -409.64866) (xy 68.59633 -409.649186)
			(xy 68.650278 -409.65694) (xy 68.702574 -409.672292) (xy 68.752153 -409.694932) (xy 68.798005 -409.724397)
			(xy 68.839197 -409.760087) (xy 68.87489 -409.801277) (xy 68.904358 -409.847127) (xy 68.927 -409.896705)
			(xy 68.942356 -409.949) (xy 68.950113 -410.002948) (xy 68.950113 -410.057452) (xy 68.950112 -410.057456)
			(xy 70.387623 -410.057456) (xy 70.387623 -410.002944) (xy 70.395381 -409.948987) (xy 70.410739 -409.896683)
			(xy 70.433385 -409.847098) (xy 70.462857 -409.80124) (xy 70.498556 -409.760043) (xy 70.539754 -409.724346)
			(xy 70.585613 -409.694876) (xy 70.6352 -409.672233) (xy 70.687505 -409.656877) (xy 70.741462 -409.649122)
			(xy 70.768718 -409.64866) (xy 71.632318 -409.64866) (xy 71.659566 -409.649211) (xy 71.713507 -409.656969)
			(xy 71.765795 -409.672325) (xy 71.815366 -409.694965) (xy 71.86121 -409.724429) (xy 71.902395 -409.760118)
			(xy 71.938082 -409.801304) (xy 71.967544 -409.84715) (xy 71.990182 -409.896721) (xy 72.005534 -409.94901)
			(xy 72.01329 -410.002952) (xy 72.01329 -410.057448) (xy 72.013289 -410.057452) (xy 73.450946 -410.057452)
			(xy 73.450946 -410.002948) (xy 73.458702 -409.949) (xy 73.474056 -409.896704) (xy 73.496696 -409.847125)
			(xy 73.526161 -409.801273) (xy 73.561851 -409.760081) (xy 73.60304 -409.724386) (xy 73.648889 -409.694916)
			(xy 73.698465 -409.672271) (xy 73.750759 -409.656911) (xy 73.804706 -409.649149) (xy 73.831958 -409.64866)
			(xy 74.695558 -409.64866) (xy 74.722811 -409.649184) (xy 74.776761 -409.656936) (xy 74.82906 -409.672287)
			(xy 74.878641 -409.694925) (xy 74.924496 -409.72439) (xy 74.96569 -409.76008) (xy 75.001385 -409.801271)
			(xy 75.030855 -409.847122) (xy 75.053498 -409.896701) (xy 75.068855 -409.948997) (xy 75.076613 -410.002948)
			(xy 75.076613 -410.057452) (xy 75.076613 -410.057453) (xy 76.514146 -410.057453) (xy 76.514146 -410.002947)
			(xy 76.521903 -409.948994) (xy 76.537259 -409.896695) (xy 76.559902 -409.847114) (xy 76.589371 -409.80126)
			(xy 76.625065 -409.760066) (xy 76.666259 -409.724372) (xy 76.712113 -409.694903) (xy 76.761694 -409.67226)
			(xy 76.813993 -409.656903) (xy 76.867945 -409.649146) (xy 76.895198 -409.64866) (xy 77.758798 -409.64866)
			(xy 77.786049 -409.649187) (xy 77.839995 -409.656943) (xy 77.892289 -409.672298) (xy 77.941865 -409.694938)
			(xy 77.987715 -409.724404) (xy 78.028904 -409.760094) (xy 78.064595 -409.801284) (xy 78.094061 -409.847133)
			(xy 78.116702 -409.896709) (xy 78.132056 -409.949003) (xy 78.139813 -410.002949) (xy 78.139813 -410.057451)
			(xy 78.139812 -410.057457) (xy 79.577323 -410.057457) (xy 79.577323 -410.002943) (xy 79.585082 -409.948984)
			(xy 79.600441 -409.896679) (xy 79.623088 -409.847092) (xy 79.652562 -409.801233) (xy 79.688263 -409.760036)
			(xy 79.729464 -409.724339) (xy 79.775325 -409.69487) (xy 79.824915 -409.672228) (xy 79.877221 -409.656874)
			(xy 79.931181 -409.64912) (xy 79.958438 -409.64866) (xy 80.822038 -409.64866) (xy 80.849285 -409.649213)
			(xy 80.903224 -409.656973) (xy 80.95551 -409.67233) (xy 81.005078 -409.694972) (xy 81.05092 -409.724436)
			(xy 81.092102 -409.760125) (xy 81.127786 -409.801311) (xy 81.157247 -409.847155) (xy 81.179883 -409.896726)
			(xy 81.195235 -409.949013) (xy 81.20299 -410.002953) (xy 81.20299 -410.057447) (xy 81.202989 -410.057453)
			(xy 82.640646 -410.057453) (xy 82.640646 -410.002947) (xy 82.648402 -409.948997) (xy 82.663758 -409.8967)
			(xy 82.686399 -409.84712) (xy 82.715866 -409.801267) (xy 82.751558 -409.760074) (xy 82.792749 -409.724379)
			(xy 82.838601 -409.69491) (xy 82.888179 -409.672265) (xy 82.940476 -409.656907) (xy 82.994425 -409.649147)
			(xy 83.021678 -409.64866) (xy 83.885278 -409.64866) (xy 83.91253 -409.649186) (xy 83.966478 -409.65694)
			(xy 84.018774 -409.672292) (xy 84.068353 -409.694932) (xy 84.114205 -409.724397) (xy 84.155397 -409.760087)
			(xy 84.19109 -409.801277) (xy 84.220558 -409.847127) (xy 84.2432 -409.896705) (xy 84.258556 -409.949)
			(xy 84.266313 -410.002948) (xy 84.266313 -410.057452) (xy 84.266312 -410.057456) (xy 85.703823 -410.057456)
			(xy 85.703823 -410.002944) (xy 85.711581 -409.948987) (xy 85.726939 -409.896683) (xy 85.749585 -409.847098)
			(xy 85.779057 -409.80124) (xy 85.814756 -409.760043) (xy 85.855954 -409.724346) (xy 85.901813 -409.694876)
			(xy 85.9514 -409.672233) (xy 86.003705 -409.656877) (xy 86.057662 -409.649122) (xy 86.084918 -409.64866)
			(xy 86.948518 -409.64866) (xy 86.975766 -409.649211) (xy 87.029707 -409.656969) (xy 87.081995 -409.672325)
			(xy 87.131566 -409.694965) (xy 87.17741 -409.724429) (xy 87.218595 -409.760118) (xy 87.254282 -409.801304)
			(xy 87.283744 -409.84715) (xy 87.306382 -409.896721) (xy 87.321734 -409.94901) (xy 87.32949 -410.002952)
			(xy 87.32949 -410.057448) (xy 87.329489 -410.057452) (xy 88.767146 -410.057452) (xy 88.767146 -410.002948)
			(xy 88.774902 -409.949) (xy 88.790256 -409.896704) (xy 88.812896 -409.847125) (xy 88.842361 -409.801273)
			(xy 88.878051 -409.760081) (xy 88.91924 -409.724386) (xy 88.965089 -409.694916) (xy 89.014665 -409.672271)
			(xy 89.066959 -409.656911) (xy 89.120906 -409.649149) (xy 89.148158 -409.64866) (xy 90.011758 -409.64866)
			(xy 90.039011 -409.649184) (xy 90.092961 -409.656936) (xy 90.14526 -409.672287) (xy 90.194841 -409.694925)
			(xy 90.240696 -409.72439) (xy 90.28189 -409.76008) (xy 90.317585 -409.801271) (xy 90.347055 -409.847122)
			(xy 90.369698 -409.896701) (xy 90.385055 -409.948997) (xy 90.392813 -410.002948) (xy 90.392813 -410.057452)
			(xy 90.392813 -410.057453) (xy 91.830346 -410.057453) (xy 91.830346 -410.002947) (xy 91.838103 -409.948994)
			(xy 91.853459 -409.896695) (xy 91.876102 -409.847114) (xy 91.905571 -409.80126) (xy 91.941265 -409.760066)
			(xy 91.982459 -409.724372) (xy 92.028313 -409.694903) (xy 92.077894 -409.67226) (xy 92.130193 -409.656903)
			(xy 92.184145 -409.649146) (xy 92.211398 -409.64866) (xy 93.074998 -409.64866) (xy 93.102249 -409.649187)
			(xy 93.156195 -409.656943) (xy 93.208489 -409.672298) (xy 93.258065 -409.694938) (xy 93.303915 -409.724404)
			(xy 93.345104 -409.760094) (xy 93.380795 -409.801284) (xy 93.410261 -409.847133) (xy 93.432902 -409.896709)
			(xy 93.448256 -409.949003) (xy 93.456013 -410.002949) (xy 93.456013 -410.057451) (xy 93.456012 -410.057457)
			(xy 94.893523 -410.057457) (xy 94.893523 -410.002943) (xy 94.901282 -409.948984) (xy 94.916641 -409.896679)
			(xy 94.939288 -409.847092) (xy 94.968762 -409.801233) (xy 95.004463 -409.760036) (xy 95.045664 -409.724339)
			(xy 95.091525 -409.69487) (xy 95.141115 -409.672228) (xy 95.193421 -409.656874) (xy 95.247381 -409.64912)
			(xy 95.274638 -409.64866) (xy 96.138238 -409.64866) (xy 96.165485 -409.649213) (xy 96.219424 -409.656973)
			(xy 96.27171 -409.67233) (xy 96.321278 -409.694972) (xy 96.36712 -409.724436) (xy 96.408302 -409.760125)
			(xy 96.443986 -409.801311) (xy 96.473447 -409.847155) (xy 96.496083 -409.896726) (xy 96.511435 -409.949013)
			(xy 96.51919 -410.002953) (xy 96.51919 -410.057447) (xy 96.519189 -410.057451) (xy 121.120146 -410.057451)
			(xy 121.120146 -410.002949) (xy 121.127902 -409.949) (xy 121.143256 -409.896705) (xy 121.165895 -409.847127)
			(xy 121.19536 -409.801275) (xy 121.231049 -409.760082) (xy 121.272238 -409.724388) (xy 121.318086 -409.694918)
			(xy 121.367662 -409.672272) (xy 121.419955 -409.656911) (xy 121.473903 -409.649149) (xy 121.501154 -409.64866)
			(xy 122.364754 -409.64866) (xy 122.392007 -409.649184) (xy 122.445958 -409.656935) (xy 122.498257 -409.672286)
			(xy 122.547839 -409.694924) (xy 122.593694 -409.724388) (xy 122.634889 -409.760079) (xy 122.670584 -409.801269)
			(xy 122.700054 -409.847121) (xy 122.722698 -409.8967) (xy 122.738055 -409.948997) (xy 122.745813 -410.002947)
			(xy 122.745813 -410.057453) (xy 124.183346 -410.057453) (xy 124.183346 -410.002947) (xy 124.191103 -409.948995)
			(xy 124.206459 -409.896696) (xy 124.229102 -409.847115) (xy 124.25857 -409.801261) (xy 124.294264 -409.760068)
			(xy 124.335457 -409.724373) (xy 124.38131 -409.694904) (xy 124.430891 -409.672261) (xy 124.483189 -409.656904)
			(xy 124.537141 -409.649146) (xy 124.564394 -409.64866) (xy 125.427994 -409.64866) (xy 125.455245 -409.649187)
			(xy 125.509192 -409.656942) (xy 125.561486 -409.672297) (xy 125.611063 -409.694937) (xy 125.656913 -409.724402)
			(xy 125.698103 -409.760093) (xy 125.733794 -409.801282) (xy 125.76326 -409.847132) (xy 125.785901 -409.896708)
			(xy 125.801256 -409.949002) (xy 125.809013 -410.002949) (xy 125.809013 -410.057451) (xy 125.809012 -410.057457)
			(xy 127.246523 -410.057457) (xy 127.246523 -410.002943) (xy 127.254282 -409.948985) (xy 127.269641 -409.89668)
			(xy 127.292287 -409.847093) (xy 127.321761 -409.801235) (xy 127.357462 -409.760037) (xy 127.398662 -409.724341)
			(xy 127.444523 -409.694871) (xy 127.494112 -409.672229) (xy 127.546418 -409.656874) (xy 127.600377 -409.649121)
			(xy 127.627634 -409.64866) (xy 128.491234 -409.64866) (xy 128.518481 -409.649213) (xy 128.572421 -409.656972)
			(xy 128.624707 -409.672329) (xy 128.674276 -409.69497) (xy 128.720118 -409.724435) (xy 128.761301 -409.760123)
			(xy 128.796985 -409.801309) (xy 128.826446 -409.847154) (xy 128.849083 -409.896725) (xy 128.864435 -409.949012)
			(xy 128.87219 -410.002953) (xy 128.87219 -410.057447) (xy 128.872189 -410.057452) (xy 130.309846 -410.057452)
			(xy 130.309846 -410.002948) (xy 130.317602 -409.948998) (xy 130.332957 -409.896701) (xy 130.355599 -409.847121)
			(xy 130.385065 -409.801268) (xy 130.420757 -409.760075) (xy 130.461947 -409.72438) (xy 130.507798 -409.694911)
			(xy 130.557376 -409.672266) (xy 130.609672 -409.656908) (xy 130.663622 -409.649148) (xy 130.690874 -409.64866)
			(xy 131.554474 -409.64866) (xy 131.581726 -409.649185) (xy 131.635675 -409.656939) (xy 131.687972 -409.672291)
			(xy 131.737551 -409.69493) (xy 131.783403 -409.724395) (xy 131.824596 -409.760086) (xy 131.860289 -409.801276)
			(xy 131.889757 -409.847126) (xy 131.9124 -409.896704) (xy 131.927756 -409.949) (xy 131.935513 -410.002948)
			(xy 131.935513 -410.057452) (xy 131.935512 -410.057456) (xy 133.373023 -410.057456) (xy 133.373023 -410.002944)
			(xy 133.380781 -409.948987) (xy 133.396139 -409.896684) (xy 133.418784 -409.847099) (xy 133.448256 -409.801241)
			(xy 133.483954 -409.760045) (xy 133.525152 -409.724348) (xy 133.571011 -409.694878) (xy 133.620597 -409.672234)
			(xy 133.672901 -409.656878) (xy 133.726858 -409.649122) (xy 133.754114 -409.64866) (xy 134.617714 -409.64866)
			(xy 134.644962 -409.649211) (xy 134.698904 -409.656969) (xy 134.751193 -409.672324) (xy 134.800764 -409.694964)
			(xy 134.846609 -409.724428) (xy 134.887794 -409.760116) (xy 134.923481 -409.801303) (xy 134.952943 -409.847149)
			(xy 134.975581 -409.896721) (xy 134.990934 -409.94901) (xy 134.99869 -410.002952) (xy 134.99869 -410.057448)
			(xy 134.99869 -410.057451) (xy 136.436346 -410.057451) (xy 136.436346 -410.002949) (xy 136.444102 -409.949)
			(xy 136.459456 -409.896705) (xy 136.482095 -409.847127) (xy 136.51156 -409.801275) (xy 136.547249 -409.760082)
			(xy 136.588438 -409.724388) (xy 136.634286 -409.694918) (xy 136.683862 -409.672272) (xy 136.736155 -409.656911)
			(xy 136.790103 -409.649149) (xy 136.817354 -409.64866) (xy 137.680954 -409.64866) (xy 137.708207 -409.649184)
			(xy 137.762158 -409.656935) (xy 137.814457 -409.672286) (xy 137.864039 -409.694924) (xy 137.909894 -409.724388)
			(xy 137.951089 -409.760079) (xy 137.986784 -409.801269) (xy 138.016254 -409.847121) (xy 138.038898 -409.8967)
			(xy 138.054255 -409.948997) (xy 138.062013 -410.002947) (xy 138.062013 -410.057453) (xy 139.499546 -410.057453)
			(xy 139.499546 -410.002947) (xy 139.507303 -409.948995) (xy 139.522659 -409.896696) (xy 139.545302 -409.847115)
			(xy 139.57477 -409.801261) (xy 139.610464 -409.760068) (xy 139.651657 -409.724373) (xy 139.69751 -409.694904)
			(xy 139.747091 -409.672261) (xy 139.799389 -409.656904) (xy 139.853341 -409.649146) (xy 139.880594 -409.64866)
			(xy 140.744194 -409.64866) (xy 140.771445 -409.649187) (xy 140.825392 -409.656942) (xy 140.877686 -409.672297)
			(xy 140.927263 -409.694937) (xy 140.973113 -409.724402) (xy 141.014303 -409.760093) (xy 141.049994 -409.801282)
			(xy 141.07946 -409.847132) (xy 141.102101 -409.896708) (xy 141.117456 -409.949002) (xy 141.125213 -410.002949)
			(xy 141.125213 -410.057451) (xy 141.125212 -410.057457) (xy 142.562723 -410.057457) (xy 142.562723 -410.002943)
			(xy 142.570482 -409.948985) (xy 142.585841 -409.89668) (xy 142.608487 -409.847093) (xy 142.637961 -409.801235)
			(xy 142.673662 -409.760037) (xy 142.714862 -409.724341) (xy 142.760723 -409.694871) (xy 142.810312 -409.672229)
			(xy 142.862618 -409.656874) (xy 142.916577 -409.649121) (xy 142.943834 -409.64866) (xy 143.807434 -409.64866)
			(xy 143.834681 -409.649213) (xy 143.888621 -409.656972) (xy 143.940907 -409.672329) (xy 143.990476 -409.69497)
			(xy 144.036318 -409.724435) (xy 144.077501 -409.760123) (xy 144.113185 -409.801309) (xy 144.142646 -409.847154)
			(xy 144.165283 -409.896725) (xy 144.180635 -409.949012) (xy 144.18839 -410.002953) (xy 144.18839 -410.057447)
			(xy 144.188389 -410.057452) (xy 145.626046 -410.057452) (xy 145.626046 -410.002948) (xy 145.633802 -409.948998)
			(xy 145.649157 -409.896701) (xy 145.671799 -409.847121) (xy 145.701265 -409.801268) (xy 145.736957 -409.760075)
			(xy 145.778147 -409.72438) (xy 145.823998 -409.694911) (xy 145.873576 -409.672266) (xy 145.925872 -409.656908)
			(xy 145.979822 -409.649148) (xy 146.007074 -409.64866) (xy 146.870674 -409.64866) (xy 146.897926 -409.649185)
			(xy 146.951875 -409.656939) (xy 147.004172 -409.672291) (xy 147.053751 -409.69493) (xy 147.099603 -409.724395)
			(xy 147.140796 -409.760086) (xy 147.176489 -409.801276) (xy 147.205957 -409.847126) (xy 147.2286 -409.896704)
			(xy 147.243956 -409.949) (xy 147.251713 -410.002948) (xy 147.251713 -410.057452) (xy 147.251712 -410.057456)
			(xy 148.689223 -410.057456) (xy 148.689223 -410.002944) (xy 148.696981 -409.948987) (xy 148.712339 -409.896684)
			(xy 148.734984 -409.847099) (xy 148.764456 -409.801241) (xy 148.800154 -409.760045) (xy 148.841352 -409.724348)
			(xy 148.887211 -409.694878) (xy 148.936797 -409.672234) (xy 148.989101 -409.656878) (xy 149.043058 -409.649122)
			(xy 149.070314 -409.64866) (xy 149.933914 -409.64866) (xy 149.961162 -409.649211) (xy 150.015104 -409.656969)
			(xy 150.067393 -409.672324) (xy 150.116964 -409.694964) (xy 150.162809 -409.724428) (xy 150.203994 -409.760116)
			(xy 150.239681 -409.801303) (xy 150.269143 -409.847149) (xy 150.291781 -409.896721) (xy 150.307134 -409.94901)
			(xy 150.31489 -410.002952) (xy 150.31489 -410.057448) (xy 150.31489 -410.057451) (xy 151.752546 -410.057451)
			(xy 151.752546 -410.002949) (xy 151.760302 -409.949) (xy 151.775656 -409.896705) (xy 151.798295 -409.847127)
			(xy 151.82776 -409.801275) (xy 151.863449 -409.760082) (xy 151.904638 -409.724388) (xy 151.950486 -409.694918)
			(xy 152.000062 -409.672272) (xy 152.052355 -409.656911) (xy 152.106303 -409.649149) (xy 152.133554 -409.64866)
			(xy 152.997154 -409.64866) (xy 153.024407 -409.649184) (xy 153.078358 -409.656935) (xy 153.130657 -409.672286)
			(xy 153.180239 -409.694924) (xy 153.226094 -409.724388) (xy 153.267289 -409.760079) (xy 153.302984 -409.801269)
			(xy 153.332454 -409.847121) (xy 153.355098 -409.8967) (xy 153.370455 -409.948997) (xy 153.378213 -410.002947)
			(xy 153.378213 -410.057453) (xy 154.815746 -410.057453) (xy 154.815746 -410.002947) (xy 154.823503 -409.948995)
			(xy 154.838859 -409.896696) (xy 154.861502 -409.847115) (xy 154.89097 -409.801261) (xy 154.926664 -409.760068)
			(xy 154.967857 -409.724373) (xy 155.01371 -409.694904) (xy 155.063291 -409.672261) (xy 155.115589 -409.656904)
			(xy 155.169541 -409.649146) (xy 155.196794 -409.64866) (xy 156.060394 -409.64866) (xy 156.087645 -409.649187)
			(xy 156.141592 -409.656942) (xy 156.193886 -409.672297) (xy 156.243463 -409.694937) (xy 156.289313 -409.724402)
			(xy 156.330503 -409.760093) (xy 156.366194 -409.801282) (xy 156.39566 -409.847132) (xy 156.418301 -409.896708)
			(xy 156.433656 -409.949002) (xy 156.441413 -410.002949) (xy 156.441413 -410.057451) (xy 156.441412 -410.057457)
			(xy 157.878923 -410.057457) (xy 157.878923 -410.002943) (xy 157.886682 -409.948985) (xy 157.902041 -409.89668)
			(xy 157.924687 -409.847093) (xy 157.954161 -409.801235) (xy 157.989862 -409.760037) (xy 158.031062 -409.724341)
			(xy 158.076923 -409.694871) (xy 158.126512 -409.672229) (xy 158.178818 -409.656874) (xy 158.232777 -409.649121)
			(xy 158.260034 -409.64866) (xy 159.123634 -409.64866) (xy 159.150881 -409.649213) (xy 159.204821 -409.656972)
			(xy 159.257107 -409.672329) (xy 159.306676 -409.69497) (xy 159.352518 -409.724435) (xy 159.393701 -409.760123)
			(xy 159.429385 -409.801309) (xy 159.458846 -409.847154) (xy 159.481483 -409.896725) (xy 159.496835 -409.949012)
			(xy 159.50459 -410.002953) (xy 159.50459 -410.057447) (xy 159.504589 -410.057452) (xy 160.942246 -410.057452)
			(xy 160.942246 -410.002948) (xy 160.950002 -409.948998) (xy 160.965357 -409.896701) (xy 160.987999 -409.847121)
			(xy 161.017465 -409.801268) (xy 161.053157 -409.760075) (xy 161.094347 -409.72438) (xy 161.140198 -409.694911)
			(xy 161.189776 -409.672266) (xy 161.242072 -409.656908) (xy 161.296022 -409.649148) (xy 161.323274 -409.64866)
			(xy 162.186874 -409.64866) (xy 162.214126 -409.649185) (xy 162.268075 -409.656939) (xy 162.320372 -409.672291)
			(xy 162.369951 -409.69493) (xy 162.415803 -409.724395) (xy 162.456996 -409.760086) (xy 162.492689 -409.801276)
			(xy 162.522157 -409.847126) (xy 162.5448 -409.896704) (xy 162.560156 -409.949) (xy 162.567913 -410.002948)
			(xy 162.567913 -410.057452) (xy 162.567912 -410.057456) (xy 164.005423 -410.057456) (xy 164.005423 -410.002944)
			(xy 164.013181 -409.948987) (xy 164.028539 -409.896684) (xy 164.051184 -409.847099) (xy 164.080656 -409.801241)
			(xy 164.116354 -409.760045) (xy 164.157552 -409.724348) (xy 164.203411 -409.694878) (xy 164.252997 -409.672234)
			(xy 164.305301 -409.656878) (xy 164.359258 -409.649122) (xy 164.386514 -409.64866) (xy 165.250114 -409.64866)
			(xy 165.277362 -409.649211) (xy 165.331304 -409.656969) (xy 165.383593 -409.672324) (xy 165.433164 -409.694964)
			(xy 165.479009 -409.724428) (xy 165.520194 -409.760116) (xy 165.555881 -409.801303) (xy 165.585343 -409.847149)
			(xy 165.607981 -409.896721) (xy 165.623334 -409.94901) (xy 165.63109 -410.002952) (xy 165.63109 -410.057448)
			(xy 165.63109 -410.057451) (xy 167.068746 -410.057451) (xy 167.068746 -410.002949) (xy 167.076502 -409.949)
			(xy 167.091856 -409.896705) (xy 167.114495 -409.847127) (xy 167.14396 -409.801275) (xy 167.179649 -409.760082)
			(xy 167.220838 -409.724388) (xy 167.266686 -409.694918) (xy 167.316262 -409.672272) (xy 167.368555 -409.656911)
			(xy 167.422503 -409.649149) (xy 167.449754 -409.64866) (xy 168.313354 -409.64866) (xy 168.340607 -409.649184)
			(xy 168.394558 -409.656935) (xy 168.446857 -409.672286) (xy 168.496439 -409.694924) (xy 168.542294 -409.724388)
			(xy 168.583489 -409.760079) (xy 168.619184 -409.801269) (xy 168.648654 -409.847121) (xy 168.671298 -409.8967)
			(xy 168.686655 -409.948997) (xy 168.694413 -410.002947) (xy 168.694413 -410.057453) (xy 168.686655 -410.111403)
			(xy 168.671298 -410.1637) (xy 168.648654 -410.213279) (xy 168.619184 -410.259131) (xy 168.583489 -410.300321)
			(xy 168.542294 -410.336012) (xy 168.496439 -410.365476) (xy 168.446857 -410.388114) (xy 168.394558 -410.403465)
			(xy 168.340607 -410.411216) (xy 168.313354 -410.411676) (xy 167.449754 -410.411676) (xy 167.422503 -410.411251)
			(xy 167.368555 -410.403489) (xy 167.316262 -410.388128) (xy 167.266686 -410.365482) (xy 167.220838 -410.336012)
			(xy 167.179649 -410.300318) (xy 167.14396 -410.259125) (xy 167.114495 -410.213273) (xy 167.091856 -410.163695)
			(xy 167.076502 -410.1114) (xy 167.068746 -410.057451) (xy 165.63109 -410.057451) (xy 165.623334 -410.11139)
			(xy 165.607981 -410.163679) (xy 165.585343 -410.213251) (xy 165.555881 -410.259097) (xy 165.520194 -410.300284)
			(xy 165.479009 -410.335972) (xy 165.433164 -410.365436) (xy 165.383593 -410.388076) (xy 165.331304 -410.403431)
			(xy 165.277362 -410.411189) (xy 165.250114 -410.411676) (xy 164.386514 -410.411676) (xy 164.359258 -410.411278)
			(xy 164.305301 -410.403522) (xy 164.252997 -410.388166) (xy 164.203411 -410.365522) (xy 164.157552 -410.336052)
			(xy 164.116354 -410.300355) (xy 164.080656 -410.259159) (xy 164.051184 -410.213301) (xy 164.028539 -410.163716)
			(xy 164.013181 -410.111413) (xy 164.005423 -410.057456) (xy 162.567912 -410.057456) (xy 162.560156 -410.1114)
			(xy 162.5448 -410.163696) (xy 162.522157 -410.213274) (xy 162.492689 -410.259124) (xy 162.456996 -410.300314)
			(xy 162.415803 -410.336005) (xy 162.369951 -410.36547) (xy 162.320372 -410.388109) (xy 162.268075 -410.403461)
			(xy 162.214126 -410.411215) (xy 162.186874 -410.411676) (xy 161.323274 -410.411676) (xy 161.296022 -410.411252)
			(xy 161.242072 -410.403492) (xy 161.189776 -410.388134) (xy 161.140198 -410.365489) (xy 161.094347 -410.33602)
			(xy 161.053157 -410.300325) (xy 161.017465 -410.259132) (xy 160.987999 -410.213279) (xy 160.965357 -410.163699)
			(xy 160.950002 -410.111402) (xy 160.942246 -410.057452) (xy 159.504589 -410.057452) (xy 159.496835 -410.111388)
			(xy 159.481483 -410.163675) (xy 159.458846 -410.213246) (xy 159.429385 -410.259091) (xy 159.393701 -410.300277)
			(xy 159.352518 -410.335965) (xy 159.306676 -410.36543) (xy 159.257107 -410.388071) (xy 159.204821 -410.403428)
			(xy 159.150881 -410.411187) (xy 159.123634 -410.411676) (xy 158.260034 -410.411676) (xy 158.232777 -410.411279)
			(xy 158.178818 -410.403526) (xy 158.126512 -410.388171) (xy 158.076923 -410.365529) (xy 158.031062 -410.336059)
			(xy 157.989862 -410.300363) (xy 157.954161 -410.259165) (xy 157.924687 -410.213307) (xy 157.902041 -410.16372)
			(xy 157.886682 -410.111415) (xy 157.878923 -410.057457) (xy 156.441412 -410.057457) (xy 156.433656 -410.111398)
			(xy 156.418301 -410.163692) (xy 156.39566 -410.213268) (xy 156.366194 -410.259118) (xy 156.330503 -410.300307)
			(xy 156.289313 -410.335998) (xy 156.243463 -410.365463) (xy 156.193886 -410.388103) (xy 156.141592 -410.403458)
			(xy 156.087645 -410.411213) (xy 156.060394 -410.411676) (xy 155.196794 -410.411676) (xy 155.169541 -410.411254)
			(xy 155.115589 -410.403496) (xy 155.063291 -410.388139) (xy 155.01371 -410.365496) (xy 154.967857 -410.336027)
			(xy 154.926664 -410.300332) (xy 154.89097 -410.259139) (xy 154.861502 -410.213285) (xy 154.838859 -410.163704)
			(xy 154.823503 -410.111405) (xy 154.815746 -410.057453) (xy 153.378213 -410.057453) (xy 153.370455 -410.111403)
			(xy 153.355098 -410.1637) (xy 153.332454 -410.213279) (xy 153.302984 -410.259131) (xy 153.267289 -410.300321)
			(xy 153.226094 -410.336012) (xy 153.180239 -410.365476) (xy 153.130657 -410.388114) (xy 153.078358 -410.403465)
			(xy 153.024407 -410.411216) (xy 152.997154 -410.411676) (xy 152.133554 -410.411676) (xy 152.106303 -410.411251)
			(xy 152.052355 -410.403489) (xy 152.000062 -410.388128) (xy 151.950486 -410.365482) (xy 151.904638 -410.336012)
			(xy 151.863449 -410.300318) (xy 151.82776 -410.259125) (xy 151.798295 -410.213273) (xy 151.775656 -410.163695)
			(xy 151.760302 -410.1114) (xy 151.752546 -410.057451) (xy 150.31489 -410.057451) (xy 150.307134 -410.11139)
			(xy 150.291781 -410.163679) (xy 150.269143 -410.213251) (xy 150.239681 -410.259097) (xy 150.203994 -410.300284)
			(xy 150.162809 -410.335972) (xy 150.116964 -410.365436) (xy 150.067393 -410.388076) (xy 150.015104 -410.403431)
			(xy 149.961162 -410.411189) (xy 149.933914 -410.411676) (xy 149.070314 -410.411676) (xy 149.043058 -410.411278)
			(xy 148.989101 -410.403522) (xy 148.936797 -410.388166) (xy 148.887211 -410.365522) (xy 148.841352 -410.336052)
			(xy 148.800154 -410.300355) (xy 148.764456 -410.259159) (xy 148.734984 -410.213301) (xy 148.712339 -410.163716)
			(xy 148.696981 -410.111413) (xy 148.689223 -410.057456) (xy 147.251712 -410.057456) (xy 147.243956 -410.1114)
			(xy 147.2286 -410.163696) (xy 147.205957 -410.213274) (xy 147.176489 -410.259124) (xy 147.140796 -410.300314)
			(xy 147.099603 -410.336005) (xy 147.053751 -410.36547) (xy 147.004172 -410.388109) (xy 146.951875 -410.403461)
			(xy 146.897926 -410.411215) (xy 146.870674 -410.411676) (xy 146.007074 -410.411676) (xy 145.979822 -410.411252)
			(xy 145.925872 -410.403492) (xy 145.873576 -410.388134) (xy 145.823998 -410.365489) (xy 145.778147 -410.33602)
			(xy 145.736957 -410.300325) (xy 145.701265 -410.259132) (xy 145.671799 -410.213279) (xy 145.649157 -410.163699)
			(xy 145.633802 -410.111402) (xy 145.626046 -410.057452) (xy 144.188389 -410.057452) (xy 144.180635 -410.111388)
			(xy 144.165283 -410.163675) (xy 144.142646 -410.213246) (xy 144.113185 -410.259091) (xy 144.077501 -410.300277)
			(xy 144.036318 -410.335965) (xy 143.990476 -410.36543) (xy 143.940907 -410.388071) (xy 143.888621 -410.403428)
			(xy 143.834681 -410.411187) (xy 143.807434 -410.411676) (xy 142.943834 -410.411676) (xy 142.916577 -410.411279)
			(xy 142.862618 -410.403526) (xy 142.810312 -410.388171) (xy 142.760723 -410.365529) (xy 142.714862 -410.336059)
			(xy 142.673662 -410.300363) (xy 142.637961 -410.259165) (xy 142.608487 -410.213307) (xy 142.585841 -410.16372)
			(xy 142.570482 -410.111415) (xy 142.562723 -410.057457) (xy 141.125212 -410.057457) (xy 141.117456 -410.111398)
			(xy 141.102101 -410.163692) (xy 141.07946 -410.213268) (xy 141.049994 -410.259118) (xy 141.014303 -410.300307)
			(xy 140.973113 -410.335998) (xy 140.927263 -410.365463) (xy 140.877686 -410.388103) (xy 140.825392 -410.403458)
			(xy 140.771445 -410.411213) (xy 140.744194 -410.411676) (xy 139.880594 -410.411676) (xy 139.853341 -410.411254)
			(xy 139.799389 -410.403496) (xy 139.747091 -410.388139) (xy 139.69751 -410.365496) (xy 139.651657 -410.336027)
			(xy 139.610464 -410.300332) (xy 139.57477 -410.259139) (xy 139.545302 -410.213285) (xy 139.522659 -410.163704)
			(xy 139.507303 -410.111405) (xy 139.499546 -410.057453) (xy 138.062013 -410.057453) (xy 138.054255 -410.111403)
			(xy 138.038898 -410.1637) (xy 138.016254 -410.213279) (xy 137.986784 -410.259131) (xy 137.951089 -410.300321)
			(xy 137.909894 -410.336012) (xy 137.864039 -410.365476) (xy 137.814457 -410.388114) (xy 137.762158 -410.403465)
			(xy 137.708207 -410.411216) (xy 137.680954 -410.411676) (xy 136.817354 -410.411676) (xy 136.790103 -410.411251)
			(xy 136.736155 -410.403489) (xy 136.683862 -410.388128) (xy 136.634286 -410.365482) (xy 136.588438 -410.336012)
			(xy 136.547249 -410.300318) (xy 136.51156 -410.259125) (xy 136.482095 -410.213273) (xy 136.459456 -410.163695)
			(xy 136.444102 -410.1114) (xy 136.436346 -410.057451) (xy 134.99869 -410.057451) (xy 134.990934 -410.11139)
			(xy 134.975581 -410.163679) (xy 134.952943 -410.213251) (xy 134.923481 -410.259097) (xy 134.887794 -410.300284)
			(xy 134.846609 -410.335972) (xy 134.800764 -410.365436) (xy 134.751193 -410.388076) (xy 134.698904 -410.403431)
			(xy 134.644962 -410.411189) (xy 134.617714 -410.411676) (xy 133.754114 -410.411676) (xy 133.726858 -410.411278)
			(xy 133.672901 -410.403522) (xy 133.620597 -410.388166) (xy 133.571011 -410.365522) (xy 133.525152 -410.336052)
			(xy 133.483954 -410.300355) (xy 133.448256 -410.259159) (xy 133.418784 -410.213301) (xy 133.396139 -410.163716)
			(xy 133.380781 -410.111413) (xy 133.373023 -410.057456) (xy 131.935512 -410.057456) (xy 131.927756 -410.1114)
			(xy 131.9124 -410.163696) (xy 131.889757 -410.213274) (xy 131.860289 -410.259124) (xy 131.824596 -410.300314)
			(xy 131.783403 -410.336005) (xy 131.737551 -410.36547) (xy 131.687972 -410.388109) (xy 131.635675 -410.403461)
			(xy 131.581726 -410.411215) (xy 131.554474 -410.411676) (xy 130.690874 -410.411676) (xy 130.663622 -410.411252)
			(xy 130.609672 -410.403492) (xy 130.557376 -410.388134) (xy 130.507798 -410.365489) (xy 130.461947 -410.33602)
			(xy 130.420757 -410.300325) (xy 130.385065 -410.259132) (xy 130.355599 -410.213279) (xy 130.332957 -410.163699)
			(xy 130.317602 -410.111402) (xy 130.309846 -410.057452) (xy 128.872189 -410.057452) (xy 128.864435 -410.111388)
			(xy 128.849083 -410.163675) (xy 128.826446 -410.213246) (xy 128.796985 -410.259091) (xy 128.761301 -410.300277)
			(xy 128.720118 -410.335965) (xy 128.674276 -410.36543) (xy 128.624707 -410.388071) (xy 128.572421 -410.403428)
			(xy 128.518481 -410.411187) (xy 128.491234 -410.411676) (xy 127.627634 -410.411676) (xy 127.600377 -410.411279)
			(xy 127.546418 -410.403526) (xy 127.494112 -410.388171) (xy 127.444523 -410.365529) (xy 127.398662 -410.336059)
			(xy 127.357462 -410.300363) (xy 127.321761 -410.259165) (xy 127.292287 -410.213307) (xy 127.269641 -410.16372)
			(xy 127.254282 -410.111415) (xy 127.246523 -410.057457) (xy 125.809012 -410.057457) (xy 125.801256 -410.111398)
			(xy 125.785901 -410.163692) (xy 125.76326 -410.213268) (xy 125.733794 -410.259118) (xy 125.698103 -410.300307)
			(xy 125.656913 -410.335998) (xy 125.611063 -410.365463) (xy 125.561486 -410.388103) (xy 125.509192 -410.403458)
			(xy 125.455245 -410.411213) (xy 125.427994 -410.411676) (xy 124.564394 -410.411676) (xy 124.537141 -410.411254)
			(xy 124.483189 -410.403496) (xy 124.430891 -410.388139) (xy 124.38131 -410.365496) (xy 124.335457 -410.336027)
			(xy 124.294264 -410.300332) (xy 124.25857 -410.259139) (xy 124.229102 -410.213285) (xy 124.206459 -410.163704)
			(xy 124.191103 -410.111405) (xy 124.183346 -410.057453) (xy 122.745813 -410.057453) (xy 122.738055 -410.111403)
			(xy 122.722698 -410.1637) (xy 122.700054 -410.213279) (xy 122.670584 -410.259131) (xy 122.634889 -410.300321)
			(xy 122.593694 -410.336012) (xy 122.547839 -410.365476) (xy 122.498257 -410.388114) (xy 122.445958 -410.403465)
			(xy 122.392007 -410.411216) (xy 122.364754 -410.411676) (xy 121.501154 -410.411676) (xy 121.473903 -410.411251)
			(xy 121.419955 -410.403489) (xy 121.367662 -410.388128) (xy 121.318086 -410.365482) (xy 121.272238 -410.336012)
			(xy 121.231049 -410.300318) (xy 121.19536 -410.259125) (xy 121.165895 -410.213273) (xy 121.143256 -410.163695)
			(xy 121.127902 -410.1114) (xy 121.120146 -410.057451) (xy 96.519189 -410.057451) (xy 96.511435 -410.111387)
			(xy 96.496083 -410.163674) (xy 96.473447 -410.213245) (xy 96.443986 -410.259089) (xy 96.408302 -410.300275)
			(xy 96.36712 -410.335964) (xy 96.321278 -410.365428) (xy 96.27171 -410.38807) (xy 96.219424 -410.403427)
			(xy 96.165485 -410.411187) (xy 96.138238 -410.411676) (xy 95.274638 -410.411676) (xy 95.247381 -410.41128)
			(xy 95.193421 -410.403526) (xy 95.141115 -410.388172) (xy 95.091525 -410.36553) (xy 95.045664 -410.336061)
			(xy 95.004463 -410.300364) (xy 94.968762 -410.259167) (xy 94.939288 -410.213308) (xy 94.916641 -410.163721)
			(xy 94.901282 -410.111416) (xy 94.893523 -410.057457) (xy 93.456012 -410.057457) (xy 93.448256 -410.111397)
			(xy 93.432902 -410.163691) (xy 93.410261 -410.213267) (xy 93.380795 -410.259116) (xy 93.345104 -410.300306)
			(xy 93.303915 -410.335996) (xy 93.258065 -410.365462) (xy 93.208489 -410.388102) (xy 93.156195 -410.403457)
			(xy 93.102249 -410.411213) (xy 93.074998 -410.411676) (xy 92.211398 -410.411676) (xy 92.184145 -410.411254)
			(xy 92.130193 -410.403497) (xy 92.077894 -410.38814) (xy 92.028313 -410.365497) (xy 91.982459 -410.336028)
			(xy 91.941265 -410.300334) (xy 91.905571 -410.25914) (xy 91.876102 -410.213286) (xy 91.853459 -410.163705)
			(xy 91.838103 -410.111406) (xy 91.830346 -410.057453) (xy 90.392813 -410.057453) (xy 90.385055 -410.111403)
			(xy 90.369698 -410.163699) (xy 90.347055 -410.213278) (xy 90.317585 -410.259129) (xy 90.28189 -410.30032)
			(xy 90.240696 -410.33601) (xy 90.194841 -410.365475) (xy 90.14526 -410.388113) (xy 90.092961 -410.403464)
			(xy 90.039011 -410.411216) (xy 90.011758 -410.411676) (xy 89.148158 -410.411676) (xy 89.120906 -410.411251)
			(xy 89.066959 -410.403489) (xy 89.014665 -410.388129) (xy 88.965089 -410.365484) (xy 88.91924 -410.336014)
			(xy 88.878051 -410.300319) (xy 88.842361 -410.259127) (xy 88.812896 -410.213275) (xy 88.790256 -410.163696)
			(xy 88.774902 -410.1114) (xy 88.767146 -410.057452) (xy 87.329489 -410.057452) (xy 87.321734 -410.11139)
			(xy 87.306382 -410.163679) (xy 87.283744 -410.21325) (xy 87.254282 -410.259096) (xy 87.218595 -410.300282)
			(xy 87.17741 -410.335971) (xy 87.131566 -410.365435) (xy 87.081995 -410.388075) (xy 87.029707 -410.403431)
			(xy 86.975766 -410.411189) (xy 86.948518 -410.411676) (xy 86.084918 -410.411676) (xy 86.057662 -410.411278)
			(xy 86.003705 -410.403523) (xy 85.9514 -410.388167) (xy 85.901813 -410.365524) (xy 85.855954 -410.336054)
			(xy 85.814756 -410.300357) (xy 85.779057 -410.25916) (xy 85.749585 -410.213302) (xy 85.726939 -410.163717)
			(xy 85.711581 -410.111413) (xy 85.703823 -410.057456) (xy 84.266312 -410.057456) (xy 84.258556 -410.1114)
			(xy 84.2432 -410.163695) (xy 84.220558 -410.213273) (xy 84.19109 -410.259123) (xy 84.155397 -410.300313)
			(xy 84.114205 -410.336003) (xy 84.068353 -410.365468) (xy 84.018774 -410.388108) (xy 83.966478 -410.40346)
			(xy 83.91253 -410.411214) (xy 83.885278 -410.411676) (xy 83.021678 -410.411676) (xy 82.994425 -410.411253)
			(xy 82.940476 -410.403493) (xy 82.888179 -410.388135) (xy 82.838601 -410.36549) (xy 82.792749 -410.336021)
			(xy 82.751558 -410.300326) (xy 82.715866 -410.259133) (xy 82.686399 -410.21328) (xy 82.663758 -410.1637)
			(xy 82.648402 -410.111403) (xy 82.640646 -410.057453) (xy 81.202989 -410.057453) (xy 81.195235 -410.111387)
			(xy 81.179883 -410.163674) (xy 81.157247 -410.213245) (xy 81.127786 -410.259089) (xy 81.092102 -410.300275)
			(xy 81.05092 -410.335964) (xy 81.005078 -410.365428) (xy 80.95551 -410.38807) (xy 80.903224 -410.403427)
			(xy 80.849285 -410.411187) (xy 80.822038 -410.411676) (xy 79.958438 -410.411676) (xy 79.931181 -410.41128)
			(xy 79.877221 -410.403526) (xy 79.824915 -410.388172) (xy 79.775325 -410.36553) (xy 79.729464 -410.336061)
			(xy 79.688263 -410.300364) (xy 79.652562 -410.259167) (xy 79.623088 -410.213308) (xy 79.600441 -410.163721)
			(xy 79.585082 -410.111416) (xy 79.577323 -410.057457) (xy 78.139812 -410.057457) (xy 78.132056 -410.111397)
			(xy 78.116702 -410.163691) (xy 78.094061 -410.213267) (xy 78.064595 -410.259116) (xy 78.028904 -410.300306)
			(xy 77.987715 -410.335996) (xy 77.941865 -410.365462) (xy 77.892289 -410.388102) (xy 77.839995 -410.403457)
			(xy 77.786049 -410.411213) (xy 77.758798 -410.411676) (xy 76.895198 -410.411676) (xy 76.867945 -410.411254)
			(xy 76.813993 -410.403497) (xy 76.761694 -410.38814) (xy 76.712113 -410.365497) (xy 76.666259 -410.336028)
			(xy 76.625065 -410.300334) (xy 76.589371 -410.25914) (xy 76.559902 -410.213286) (xy 76.537259 -410.163705)
			(xy 76.521903 -410.111406) (xy 76.514146 -410.057453) (xy 75.076613 -410.057453) (xy 75.068855 -410.111403)
			(xy 75.053498 -410.163699) (xy 75.030855 -410.213278) (xy 75.001385 -410.259129) (xy 74.96569 -410.30032)
			(xy 74.924496 -410.33601) (xy 74.878641 -410.365475) (xy 74.82906 -410.388113) (xy 74.776761 -410.403464)
			(xy 74.722811 -410.411216) (xy 74.695558 -410.411676) (xy 73.831958 -410.411676) (xy 73.804706 -410.411251)
			(xy 73.750759 -410.403489) (xy 73.698465 -410.388129) (xy 73.648889 -410.365484) (xy 73.60304 -410.336014)
			(xy 73.561851 -410.300319) (xy 73.526161 -410.259127) (xy 73.496696 -410.213275) (xy 73.474056 -410.163696)
			(xy 73.458702 -410.1114) (xy 73.450946 -410.057452) (xy 72.013289 -410.057452) (xy 72.005534 -410.11139)
			(xy 71.990182 -410.163679) (xy 71.967544 -410.21325) (xy 71.938082 -410.259096) (xy 71.902395 -410.300282)
			(xy 71.86121 -410.335971) (xy 71.815366 -410.365435) (xy 71.765795 -410.388075) (xy 71.713507 -410.403431)
			(xy 71.659566 -410.411189) (xy 71.632318 -410.411676) (xy 70.768718 -410.411676) (xy 70.741462 -410.411278)
			(xy 70.687505 -410.403523) (xy 70.6352 -410.388167) (xy 70.585613 -410.365524) (xy 70.539754 -410.336054)
			(xy 70.498556 -410.300357) (xy 70.462857 -410.25916) (xy 70.433385 -410.213302) (xy 70.410739 -410.163717)
			(xy 70.395381 -410.111413) (xy 70.387623 -410.057456) (xy 68.950112 -410.057456) (xy 68.942356 -410.1114)
			(xy 68.927 -410.163695) (xy 68.904358 -410.213273) (xy 68.87489 -410.259123) (xy 68.839197 -410.300313)
			(xy 68.798005 -410.336003) (xy 68.752153 -410.365468) (xy 68.702574 -410.388108) (xy 68.650278 -410.40346)
			(xy 68.59633 -410.411214) (xy 68.569078 -410.411676) (xy 67.705478 -410.411676) (xy 67.678225 -410.411253)
			(xy 67.624276 -410.403493) (xy 67.571979 -410.388135) (xy 67.522401 -410.36549) (xy 67.476549 -410.336021)
			(xy 67.435358 -410.300326) (xy 67.399666 -410.259133) (xy 67.370199 -410.21328) (xy 67.347558 -410.1637)
			(xy 67.332202 -410.111403) (xy 67.324446 -410.057453) (xy 65.886789 -410.057453) (xy 65.879035 -410.111387)
			(xy 65.863683 -410.163674) (xy 65.841047 -410.213245) (xy 65.811586 -410.259089) (xy 65.775902 -410.300275)
			(xy 65.73472 -410.335964) (xy 65.688878 -410.365428) (xy 65.63931 -410.38807) (xy 65.587024 -410.403427)
			(xy 65.533085 -410.411187) (xy 65.505838 -410.411676) (xy 64.642238 -410.411676) (xy 64.614981 -410.41128)
			(xy 64.561021 -410.403526) (xy 64.508715 -410.388172) (xy 64.459125 -410.36553) (xy 64.413264 -410.336061)
			(xy 64.372063 -410.300364) (xy 64.336362 -410.259167) (xy 64.306888 -410.213308) (xy 64.284241 -410.163721)
			(xy 64.268882 -410.111416) (xy 64.261123 -410.057457) (xy 62.823612 -410.057457) (xy 62.815856 -410.111397)
			(xy 62.800502 -410.163691) (xy 62.777861 -410.213267) (xy 62.748395 -410.259116) (xy 62.712704 -410.300306)
			(xy 62.671515 -410.335996) (xy 62.625665 -410.365462) (xy 62.576089 -410.388102) (xy 62.523795 -410.403457)
			(xy 62.469849 -410.411213) (xy 62.442598 -410.411676) (xy 61.578998 -410.411676) (xy 61.551745 -410.411254)
			(xy 61.497793 -410.403497) (xy 61.445494 -410.38814) (xy 61.395913 -410.365497) (xy 61.350059 -410.336028)
			(xy 61.308865 -410.300334) (xy 61.273171 -410.25914) (xy 61.243702 -410.213286) (xy 61.221059 -410.163705)
			(xy 61.205703 -410.111406) (xy 61.197946 -410.057453) (xy 59.760413 -410.057453) (xy 59.752655 -410.111403)
			(xy 59.737298 -410.163699) (xy 59.714655 -410.213278) (xy 59.685185 -410.259129) (xy 59.64949 -410.30032)
			(xy 59.608296 -410.33601) (xy 59.562441 -410.365475) (xy 59.51286 -410.388113) (xy 59.460561 -410.403464)
			(xy 59.406611 -410.411216) (xy 59.379358 -410.411676) (xy 58.515758 -410.411676) (xy 58.488506 -410.411251)
			(xy 58.434559 -410.403489) (xy 58.382265 -410.388129) (xy 58.332689 -410.365484) (xy 58.28684 -410.336014)
			(xy 58.245651 -410.300319) (xy 58.209961 -410.259127) (xy 58.180496 -410.213275) (xy 58.157856 -410.163696)
			(xy 58.142502 -410.1114) (xy 58.134746 -410.057452) (xy 56.697089 -410.057452) (xy 56.689334 -410.11139)
			(xy 56.673982 -410.163679) (xy 56.651344 -410.21325) (xy 56.621882 -410.259096) (xy 56.586195 -410.300282)
			(xy 56.54501 -410.335971) (xy 56.499166 -410.365435) (xy 56.449595 -410.388075) (xy 56.397307 -410.403431)
			(xy 56.343366 -410.411189) (xy 56.316118 -410.411676) (xy 55.452518 -410.411676) (xy 55.425262 -410.411278)
			(xy 55.371305 -410.403523) (xy 55.319 -410.388167) (xy 55.269413 -410.365524) (xy 55.223554 -410.336054)
			(xy 55.182356 -410.300357) (xy 55.146657 -410.25916) (xy 55.117185 -410.213302) (xy 55.094539 -410.163717)
			(xy 55.079181 -410.111413) (xy 55.071423 -410.057456) (xy 53.633912 -410.057456) (xy 53.626156 -410.1114)
			(xy 53.6108 -410.163695) (xy 53.588158 -410.213273) (xy 53.55869 -410.259123) (xy 53.522997 -410.300313)
			(xy 53.481805 -410.336003) (xy 53.435953 -410.365468) (xy 53.386374 -410.388108) (xy 53.334078 -410.40346)
			(xy 53.28013 -410.411214) (xy 53.252878 -410.411676) (xy 52.389278 -410.411676) (xy 52.362025 -410.411253)
			(xy 52.308076 -410.403493) (xy 52.255779 -410.388135) (xy 52.206201 -410.36549) (xy 52.160349 -410.336021)
			(xy 52.119158 -410.300326) (xy 52.083466 -410.259133) (xy 52.053999 -410.21328) (xy 52.031358 -410.1637)
			(xy 52.016002 -410.111403) (xy 52.008246 -410.057453) (xy 50.570589 -410.057453) (xy 50.562835 -410.111387)
			(xy 50.547483 -410.163674) (xy 50.524847 -410.213245) (xy 50.495386 -410.259089) (xy 50.459702 -410.300275)
			(xy 50.41852 -410.335964) (xy 50.372678 -410.365428) (xy 50.32311 -410.38807) (xy 50.270824 -410.403427)
			(xy 50.216885 -410.411187) (xy 50.189638 -410.411676) (xy 49.326038 -410.411676) (xy 49.298781 -410.41128)
			(xy 49.244821 -410.403526) (xy 49.192515 -410.388172) (xy 49.142925 -410.36553) (xy 49.097064 -410.336061)
			(xy 49.055863 -410.300364) (xy 49.020162 -410.259167) (xy 48.990688 -410.213308) (xy 48.968041 -410.163721)
			(xy 48.952682 -410.111416) (xy 48.944923 -410.057457) (xy 8.024114 -410.057457) (xy 8.024114 -411.241049)
			(xy 101.876886 -411.241049) (xy 101.876886 -411.186551) (xy 101.884641 -411.132608) (xy 101.899994 -411.080318)
			(xy 101.922631 -411.030744) (xy 101.952093 -410.984897) (xy 101.98778 -410.943708) (xy 102.028964 -410.908017)
			(xy 102.074809 -410.878551) (xy 102.12438 -410.855908) (xy 102.176669 -410.840549) (xy 102.230611 -410.832788)
			(xy 102.25786 -410.8323) (xy 103.12146 -410.8323) (xy 103.148715 -410.832745) (xy 103.202672 -410.840497)
			(xy 103.254975 -410.85585) (xy 103.304562 -410.878491) (xy 103.350421 -410.907958) (xy 103.391619 -410.943653)
			(xy 103.427318 -410.984847) (xy 103.45679 -411.030703) (xy 103.479436 -411.080287) (xy 103.494794 -411.132589)
			(xy 103.502553 -411.186545) (xy 103.502553 -411.241055) (xy 103.494794 -411.295011) (xy 103.479436 -411.347313)
			(xy 103.45679 -411.396897) (xy 103.427318 -411.442753) (xy 103.391619 -411.483947) (xy 103.350421 -411.519642)
			(xy 103.304562 -411.549109) (xy 103.254975 -411.57175) (xy 103.202672 -411.587103) (xy 103.148715 -411.594855)
			(xy 103.12146 -411.595316) (xy 102.25786 -411.595316) (xy 102.230611 -411.594812) (xy 102.176669 -411.587051)
			(xy 102.12438 -411.571692) (xy 102.074809 -411.549049) (xy 102.028964 -411.519583) (xy 101.98778 -411.483892)
			(xy 101.952093 -411.442703) (xy 101.922631 -411.396856) (xy 101.899994 -411.347282) (xy 101.884641 -411.294992)
			(xy 101.876886 -411.241049) (xy 8.024114 -411.241049) (xy 8.024114 -424.470068) (xy 39.528496 -424.470068)
			(xy 39.528496 -417.770056) (xy 39.529001 -417.664532) (xy 39.537085 -417.453638) (xy 39.553241 -417.243209)
			(xy 39.577444 -417.033552) (xy 39.609661 -416.824977) (xy 39.649843 -416.617789) (xy 39.697931 -416.412292)
			(xy 39.753855 -416.208788) (xy 39.817532 -416.007575) (xy 39.88887 -415.808948) (xy 39.967764 -415.6132)
			(xy 40.054097 -415.420618) (xy 40.147744 -415.231483) (xy 40.248566 -415.046074) (xy 40.356416 -414.864663)
			(xy 40.471135 -414.687516) (xy 40.592555 -414.514894) (xy 40.720498 -414.347048) (xy 40.854776 -414.184226)
			(xy 40.995192 -414.026667) (xy 41.14154 -413.874602) (xy 41.293605 -413.728254) (xy 41.451164 -413.587838)
			(xy 41.613986 -413.45356) (xy 41.781832 -413.325617) (xy 41.954454 -413.204197) (xy 42.131601 -413.089478)
			(xy 42.313012 -412.981628) (xy 42.498421 -412.880806) (xy 42.687556 -412.787159) (xy 42.880138 -412.700826)
			(xy 43.075886 -412.621932) (xy 43.274513 -412.550594) (xy 43.475726 -412.486917) (xy 43.67923 -412.430993)
			(xy 43.884727 -412.382905) (xy 44.091915 -412.342723) (xy 44.30049 -412.310506) (xy 44.510147 -412.286303)
			(xy 44.720576 -412.270147) (xy 44.93147 -412.262063) (xy 45.142518 -412.262063) (xy 45.353412 -412.270147)
			(xy 45.563841 -412.286303) (xy 45.773498 -412.310506) (xy 45.982073 -412.342723) (xy 46.189261 -412.382905)
			(xy 46.394758 -412.430993) (xy 46.598262 -412.486917) (xy 46.799475 -412.550594) (xy 46.998102 -412.621932)
			(xy 47.19385 -412.700826) (xy 47.386432 -412.787159) (xy 47.575567 -412.880806) (xy 47.760976 -412.981628)
			(xy 47.942387 -413.089478) (xy 48.119534 -413.204197) (xy 48.292156 -413.325617) (xy 48.460002 -413.45356)
			(xy 48.622824 -413.587838) (xy 48.649451 -413.611568) (xy 104.877616 -413.611568) (xy 104.877616 -412.747968)
			(xy 104.878102 -412.720717) (xy 104.885858 -412.666769) (xy 104.901213 -412.614474) (xy 104.923855 -412.564897)
			(xy 104.953321 -412.519047) (xy 104.989012 -412.477856) (xy 105.030203 -412.442165) (xy 105.076053 -412.412699)
			(xy 105.12563 -412.390057) (xy 105.177925 -412.374702) (xy 105.231873 -412.366946) (xy 105.286375 -412.366946)
			(xy 105.340323 -412.374702) (xy 105.392618 -412.390057) (xy 105.442195 -412.412699) (xy 105.488045 -412.442165)
			(xy 105.529236 -412.477856) (xy 105.564927 -412.519047) (xy 105.594393 -412.564897) (xy 105.617035 -412.614474)
			(xy 105.63239 -412.666769) (xy 105.640146 -412.720717) (xy 105.640632 -412.747968) (xy 105.640632 -413.611568)
			(xy 105.640146 -413.638819) (xy 105.63239 -413.692767) (xy 105.617035 -413.745062) (xy 105.594393 -413.794639)
			(xy 105.584722 -413.809688) (xy 116.689632 -413.809688) (xy 116.689632 -412.946088) (xy 116.690118 -412.918837)
			(xy 116.697874 -412.864889) (xy 116.713229 -412.812594) (xy 116.735871 -412.763017) (xy 116.765337 -412.717167)
			(xy 116.801028 -412.675976) (xy 116.842219 -412.640285) (xy 116.888069 -412.610819) (xy 116.937646 -412.588177)
			(xy 116.989941 -412.572822) (xy 117.043889 -412.565066) (xy 117.098391 -412.565066) (xy 117.152339 -412.572822)
			(xy 117.204634 -412.588177) (xy 117.254211 -412.610819) (xy 117.300061 -412.640285) (xy 117.341252 -412.675976)
			(xy 117.376943 -412.717167) (xy 117.406409 -412.763017) (xy 117.429051 -412.812594) (xy 117.444406 -412.864889)
			(xy 117.452162 -412.918837) (xy 117.452648 -412.946088) (xy 117.452648 -413.809688) (xy 117.452162 -413.836939)
			(xy 117.444406 -413.890887) (xy 117.429051 -413.943182) (xy 117.406409 -413.992759) (xy 117.376943 -414.038609)
			(xy 117.341252 -414.0798) (xy 117.300061 -414.115491) (xy 117.254211 -414.144957) (xy 117.204634 -414.167599)
			(xy 117.152339 -414.182954) (xy 117.098391 -414.19071) (xy 117.043889 -414.19071) (xy 116.989941 -414.182954)
			(xy 116.937646 -414.167599) (xy 116.888069 -414.144957) (xy 116.842219 -414.115491) (xy 116.801028 -414.0798)
			(xy 116.765337 -414.038609) (xy 116.735871 -413.992759) (xy 116.713229 -413.943182) (xy 116.697874 -413.890887)
			(xy 116.690118 -413.836939) (xy 116.689632 -413.809688) (xy 105.584722 -413.809688) (xy 105.564927 -413.840489)
			(xy 105.529236 -413.88168) (xy 105.488045 -413.917371) (xy 105.442195 -413.946837) (xy 105.392618 -413.969479)
			(xy 105.340323 -413.984834) (xy 105.286375 -413.99259) (xy 105.231873 -413.99259) (xy 105.177925 -413.984834)
			(xy 105.12563 -413.969479) (xy 105.076053 -413.946837) (xy 105.030203 -413.917371) (xy 104.989012 -413.88168)
			(xy 104.953321 -413.840489) (xy 104.923855 -413.794639) (xy 104.901213 -413.745062) (xy 104.885858 -413.692767)
			(xy 104.878102 -413.638819) (xy 104.877616 -413.611568) (xy 48.649451 -413.611568) (xy 48.780383 -413.728254)
			(xy 48.932448 -413.874602) (xy 49.078796 -414.026667) (xy 49.219212 -414.184226) (xy 49.35349 -414.347048)
			(xy 49.481433 -414.514894) (xy 49.602853 -414.687516) (xy 49.717572 -414.864663) (xy 49.825422 -415.046074)
			(xy 49.926244 -415.231483) (xy 50.019891 -415.420618) (xy 50.106224 -415.6132) (xy 50.133819 -415.681668)
			(xy 100.559616 -415.681668) (xy 100.559616 -414.818068) (xy 100.560102 -414.790817) (xy 100.567858 -414.736869)
			(xy 100.583213 -414.684574) (xy 100.605855 -414.634997) (xy 100.635321 -414.589147) (xy 100.671012 -414.547956)
			(xy 100.712203 -414.512265) (xy 100.758053 -414.482799) (xy 100.80763 -414.460157) (xy 100.859925 -414.444802)
			(xy 100.913873 -414.437046) (xy 100.968375 -414.437046) (xy 101.022323 -414.444802) (xy 101.074618 -414.460157)
			(xy 101.124195 -414.482799) (xy 101.170045 -414.512265) (xy 101.211236 -414.547956) (xy 101.246927 -414.589147)
			(xy 101.276393 -414.634997) (xy 101.299035 -414.684574) (xy 101.31439 -414.736869) (xy 101.322146 -414.790817)
			(xy 101.322632 -414.818068) (xy 101.322632 -415.681668) (xy 101.322146 -415.708919) (xy 101.31439 -415.762867)
			(xy 101.299035 -415.815162) (xy 101.276393 -415.864739) (xy 101.246927 -415.910589) (xy 101.211236 -415.95178)
			(xy 101.170045 -415.987471) (xy 101.124195 -416.016937) (xy 101.074618 -416.039579) (xy 101.022323 -416.054934)
			(xy 100.968375 -416.06269) (xy 100.913873 -416.06269) (xy 100.859925 -416.054934) (xy 100.80763 -416.039579)
			(xy 100.758053 -416.016937) (xy 100.712203 -415.987471) (xy 100.671012 -415.95178) (xy 100.635321 -415.910589)
			(xy 100.605855 -415.864739) (xy 100.583213 -415.815162) (xy 100.567858 -415.762867) (xy 100.560102 -415.708919)
			(xy 100.559616 -415.681668) (xy 50.133819 -415.681668) (xy 50.185118 -415.808948) (xy 50.256456 -416.007575)
			(xy 50.320133 -416.208788) (xy 50.376057 -416.412292) (xy 50.424145 -416.617789) (xy 50.464327 -416.824977)
			(xy 50.496544 -417.033552) (xy 50.520747 -417.243209) (xy 50.536903 -417.453638) (xy 50.544987 -417.664532)
			(xy 50.545492 -417.770056) (xy 50.545492 -420.089838) (xy 58.13806 -420.089838) (xy 58.138171 -420.074752)
			(xy 58.139951 -420.044634) (xy 58.141616 -420.02964) (xy 58.141616 -418.95014) (xy 58.139949 -418.935146)
			(xy 58.138169 -418.905028) (xy 58.13806 -418.889942) (xy 58.138171 -418.874856) (xy 58.139951 -418.844738)
			(xy 58.141616 -418.829744) (xy 58.141616 -418.218874) (xy 58.142085 -418.206785) (xy 58.149546 -418.183788)
			(xy 58.163733 -418.164211) (xy 58.183264 -418.14996) (xy 58.206237 -418.142424) (xy 58.218324 -418.141912)
			(xy 59.158124 -418.141912) (xy 59.170235 -418.142296) (xy 59.193265 -418.149803) (xy 59.212839 -418.164073)
			(xy 59.227033 -418.183702) (xy 59.234451 -418.206761) (xy 59.234832 -418.218874) (xy 59.234832 -420.760398)
			(xy 59.23439 -420.77249) (xy 59.226931 -420.795495) (xy 59.212739 -420.815078) (xy 59.193198 -420.829327)
			(xy 59.170215 -420.836854) (xy 59.158124 -420.83736) (xy 58.218324 -420.83736) (xy 58.206212 -420.836963)
			(xy 58.183179 -420.829465) (xy 58.163602 -420.8152) (xy 58.149408 -420.795571) (xy 58.141994 -420.772511)
			(xy 58.141616 -420.760398) (xy 58.141616 -420.150036) (xy 58.139948 -420.135042) (xy 58.138169 -420.104924)
			(xy 58.13806 -420.089838) (xy 50.545492 -420.089838) (xy 50.545492 -421.089836) (xy 60.138056 -421.089836)
			(xy 60.138167 -421.07475) (xy 60.139947 -421.044632) (xy 60.141612 -421.029638) (xy 60.141612 -419.950138)
			(xy 60.139945 -419.935144) (xy 60.138165 -419.905026) (xy 60.138056 -419.88994) (xy 60.138167 -419.874854)
			(xy 60.139947 -419.844736) (xy 60.141612 -419.829742) (xy 60.141612 -419.218872) (xy 60.14204 -419.206794)
			(xy 60.149513 -419.183822) (xy 60.163718 -419.164284) (xy 60.183265 -419.150091) (xy 60.206242 -419.142633)
			(xy 60.21832 -419.142164) (xy 61.15812 -419.142164) (xy 61.170193 -419.142647) (xy 61.193156 -419.150112)
			(xy 61.21269 -419.164304) (xy 61.226885 -419.183837) (xy 61.234352 -419.206799) (xy 61.234828 -419.218872)
			(xy 61.234828 -421.089836) (xy 68.13804 -421.089836) (xy 68.138151 -421.07475) (xy 68.139931 -421.044632)
			(xy 68.141596 -421.029638) (xy 68.141596 -419.950138) (xy 68.139929 -419.935144) (xy 68.138149 -419.905026)
			(xy 68.13804 -419.88994) (xy 68.138151 -419.874854) (xy 68.139931 -419.844736) (xy 68.141596 -419.829742)
			(xy 68.141596 -419.218872) (xy 68.14204 -419.206796) (xy 68.149511 -419.183827) (xy 68.163712 -419.16429)
			(xy 68.183255 -419.150096) (xy 68.206227 -419.142635) (xy 68.218304 -419.142164) (xy 69.158104 -419.142164)
			(xy 69.170176 -419.14266) (xy 69.193139 -419.150121) (xy 69.212673 -419.16431) (xy 69.226868 -419.18384)
			(xy 69.234336 -419.2068) (xy 69.234812 -419.218872) (xy 69.234812 -420.089838) (xy 70.138036 -420.089838)
			(xy 70.138149 -420.074753) (xy 70.139929 -420.044634) (xy 70.141592 -420.02964) (xy 70.141592 -418.95014)
			(xy 70.139925 -418.935146) (xy 70.138145 -418.905028) (xy 70.138036 -418.889942) (xy 70.13815 -418.874857)
			(xy 70.139929 -418.844738) (xy 70.141592 -418.829744) (xy 70.141592 -418.218874) (xy 70.142084 -418.206788)
			(xy 70.149542 -418.183794) (xy 70.163724 -418.164219) (xy 70.183249 -418.149968) (xy 70.206216 -418.142428)
			(xy 70.2183 -418.141912) (xy 71.1581 -418.141912) (xy 71.17021 -418.142316) (xy 71.193239 -418.149817)
			(xy 71.212814 -418.164081) (xy 71.227008 -418.183706) (xy 71.234426 -418.206762) (xy 71.234808 -418.218874)
			(xy 71.234808 -420.760398) (xy 71.234292 -420.772483) (xy 71.226841 -420.795475) (xy 71.212666 -420.815051)
			(xy 71.193146 -420.829303) (xy 71.170183 -420.836844) (xy 71.1581 -420.83736) (xy 70.2183 -420.83736)
			(xy 70.206187 -420.836983) (xy 70.183153 -420.829479) (xy 70.163576 -420.815209) (xy 70.149383 -420.795576)
			(xy 70.14197 -420.772512) (xy 70.141592 -420.760398) (xy 70.141592 -420.150036) (xy 70.139924 -420.135042)
			(xy 70.138145 -420.104924) (xy 70.138036 -420.089838) (xy 69.234812 -420.089838) (xy 69.234812 -421.089836)
			(xy 72.138032 -421.089836) (xy 72.138145 -421.074751) (xy 72.139925 -421.044632) (xy 72.141588 -421.029638)
			(xy 72.141588 -419.950138) (xy 72.13992 -419.935144) (xy 72.138141 -419.905026) (xy 72.138032 -419.88994)
			(xy 72.138145 -419.874855) (xy 72.139925 -419.844736) (xy 72.141588 -419.829742) (xy 72.141588 -419.218872)
			(xy 72.14204 -419.206796) (xy 72.14951 -419.183829) (xy 72.16371 -419.164293) (xy 72.18325 -419.150099)
			(xy 72.20622 -419.142636) (xy 72.218296 -419.142164) (xy 73.158096 -419.142164) (xy 73.170168 -419.142667)
			(xy 73.19313 -419.150125) (xy 73.212665 -419.164313) (xy 73.22686 -419.183841) (xy 73.234328 -419.206801)
			(xy 73.234804 -419.218872) (xy 73.234804 -419.702852) (xy 110.957342 -419.702852) (xy 110.957342 -419.648348)
			(xy 110.965098 -419.594399) (xy 110.980453 -419.542102) (xy 111.003093 -419.492523) (xy 111.032558 -419.44667)
			(xy 111.068249 -419.405477) (xy 111.109438 -419.369782) (xy 111.155288 -419.340312) (xy 111.204865 -419.317667)
			(xy 111.25716 -419.302306) (xy 111.311108 -419.294545) (xy 111.33836 -419.294056) (xy 112.20196 -419.294056)
			(xy 112.229212 -419.294589) (xy 112.283162 -419.30234) (xy 112.33546 -419.317691) (xy 112.385041 -419.340329)
			(xy 112.430894 -419.369793) (xy 112.472088 -419.405484) (xy 112.507783 -419.446674) (xy 112.537251 -419.492524)
			(xy 112.559895 -419.542102) (xy 112.575251 -419.594399) (xy 112.583009 -419.648348) (xy 112.583009 -419.702852)
			(xy 112.575251 -419.756801) (xy 112.559895 -419.809098) (xy 112.537251 -419.858676) (xy 112.507783 -419.904526)
			(xy 112.472088 -419.945716) (xy 112.430894 -419.981407) (xy 112.385041 -420.010871) (xy 112.33546 -420.033509)
			(xy 112.283162 -420.04886) (xy 112.229212 -420.056611) (xy 112.20196 -420.057072) (xy 111.33836 -420.057072)
			(xy 111.311108 -420.056655) (xy 111.25716 -420.048894) (xy 111.204865 -420.033533) (xy 111.155288 -420.010888)
			(xy 111.109438 -419.981418) (xy 111.068249 -419.945723) (xy 111.032558 -419.90453) (xy 111.003093 -419.858677)
			(xy 110.980453 -419.809098) (xy 110.965098 -419.756801) (xy 110.957342 -419.702852) (xy 73.234804 -419.702852)
			(xy 73.234804 -421.760396) (xy 73.234384 -421.772479) (xy 73.226917 -421.795462) (xy 73.212713 -421.815013)
			(xy 73.193162 -421.829217) (xy 73.170179 -421.836684) (xy 73.158096 -421.837104) (xy 72.218296 -421.837104)
			(xy 72.206221 -421.836639) (xy 72.183253 -421.829175) (xy 72.163716 -421.814979) (xy 72.149521 -421.79544)
			(xy 72.14206 -421.772471) (xy 72.141588 -421.760396) (xy 72.141588 -421.150034) (xy 72.13992 -421.13504)
			(xy 72.138141 -421.104922) (xy 72.138032 -421.089836) (xy 69.234812 -421.089836) (xy 69.234812 -421.760396)
			(xy 69.234332 -421.77247) (xy 69.226871 -421.795436) (xy 69.212679 -421.814973) (xy 69.193143 -421.829168)
			(xy 69.170178 -421.836631) (xy 69.158104 -421.837104) (xy 68.218304 -421.837104) (xy 68.206221 -421.836684)
			(xy 68.183238 -421.829217) (xy 68.163687 -421.815013) (xy 68.149483 -421.795462) (xy 68.142016 -421.772479)
			(xy 68.141596 -421.760396) (xy 68.141596 -421.150034) (xy 68.139928 -421.13504) (xy 68.138149 -421.104922)
			(xy 68.13804 -421.089836) (xy 61.234828 -421.089836) (xy 61.234828 -421.760396) (xy 61.234333 -421.772468)
			(xy 61.226874 -421.795432) (xy 61.212684 -421.814967) (xy 61.193154 -421.829163) (xy 61.170192 -421.836629)
			(xy 61.15812 -421.837104) (xy 60.21832 -421.837104) (xy 60.206238 -421.83667) (xy 60.183255 -421.829208)
			(xy 60.163704 -421.815007) (xy 60.1495 -421.795459) (xy 60.142032 -421.772478) (xy 60.141612 -421.760396)
			(xy 60.141612 -421.150034) (xy 60.139944 -421.13504) (xy 60.138165 -421.104922) (xy 60.138056 -421.089836)
			(xy 50.545492 -421.089836) (xy 50.545492 -423.68978) (xy 58.13806 -423.68978) (xy 58.138175 -423.674695)
			(xy 58.139953 -423.644576) (xy 58.141616 -423.629582) (xy 58.141616 -422.550082) (xy 58.139952 -422.535088)
			(xy 58.138171 -422.50497) (xy 58.13806 -422.489884) (xy 58.138175 -422.474799) (xy 58.139953 -422.44468)
			(xy 58.141616 -422.429686) (xy 58.141616 -421.81907) (xy 58.142081 -421.806981) (xy 58.149543 -421.783984)
			(xy 58.163731 -421.764406) (xy 58.183263 -421.750156) (xy 58.206237 -421.74262) (xy 58.218324 -421.742108)
			(xy 59.158124 -421.742108) (xy 59.170235 -421.742496) (xy 59.193264 -421.750003) (xy 59.212838 -421.764272)
			(xy 59.227031 -421.783899) (xy 59.23445 -421.806958) (xy 59.234832 -421.81907) (xy 59.234832 -423.68978)
			(xy 62.138052 -423.68978) (xy 62.138167 -423.674695) (xy 62.139945 -423.644576) (xy 62.141608 -423.629582)
			(xy 62.141608 -422.550082) (xy 62.139944 -422.535088) (xy 62.138163 -422.50497) (xy 62.138052 -422.489884)
			(xy 62.138167 -422.474799) (xy 62.139945 -422.44468) (xy 62.141608 -422.429686) (xy 62.141608 -421.81907)
			(xy 62.142081 -421.806982) (xy 62.149542 -421.783986) (xy 62.163728 -421.764409) (xy 62.183258 -421.750158)
			(xy 62.20623 -421.742621) (xy 62.218316 -421.742108) (xy 63.158116 -421.742108) (xy 63.170227 -421.742503)
			(xy 63.193256 -421.750008) (xy 63.212829 -421.764274) (xy 63.227023 -421.783901) (xy 63.234442 -421.806958)
			(xy 63.234824 -421.81907) (xy 63.234824 -424.360594) (xy 63.234387 -424.372687) (xy 63.226927 -424.395693)
			(xy 63.212734 -424.415276) (xy 63.193192 -424.429526) (xy 63.170207 -424.437051) (xy 63.158116 -424.437556)
			(xy 62.218316 -424.437556) (xy 62.206214 -424.437071) (xy 62.183196 -424.429582) (xy 62.163628 -424.415337)
			(xy 62.149431 -424.395733) (xy 62.142 -424.372697) (xy 62.141608 -424.360594) (xy 62.141608 -423.749978)
			(xy 62.139944 -423.734984) (xy 62.138162 -423.704866) (xy 62.138052 -423.68978) (xy 59.234832 -423.68978)
			(xy 59.234832 -424.360594) (xy 59.234387 -424.372686) (xy 59.226928 -424.395691) (xy 59.212737 -424.415274)
			(xy 59.193197 -424.429523) (xy 59.170215 -424.43705) (xy 59.158124 -424.437556) (xy 58.218324 -424.437556)
			(xy 58.206222 -424.437064) (xy 58.183205 -424.429578) (xy 58.163637 -424.415334) (xy 58.149439 -424.395732)
			(xy 58.142008 -424.372697) (xy 58.141616 -424.360594) (xy 58.141616 -423.749978) (xy 58.139952 -423.734984)
			(xy 58.13817 -423.704866) (xy 58.13806 -423.68978) (xy 50.545492 -423.68978) (xy 50.545492 -424.470068)
			(xy 50.544987 -424.575592) (xy 50.54061 -424.689778) (xy 64.138048 -424.689778) (xy 64.138163 -424.674693)
			(xy 64.139941 -424.644574) (xy 64.141604 -424.62958) (xy 64.141604 -423.55008) (xy 64.13994 -423.535086)
			(xy 64.138158 -423.504968) (xy 64.138048 -423.489882) (xy 64.138163 -423.474797) (xy 64.139941 -423.444678)
			(xy 64.141604 -423.429684) (xy 64.141604 -422.819068) (xy 64.142037 -422.806991) (xy 64.14951 -422.78402)
			(xy 64.163714 -422.764483) (xy 64.18326 -422.75029) (xy 64.206234 -422.74283) (xy 64.218312 -422.74236)
			(xy 65.158112 -422.74236) (xy 65.170184 -422.742854) (xy 65.193146 -422.750316) (xy 65.21268 -422.764506)
			(xy 65.226875 -422.784036) (xy 65.234343 -422.806996) (xy 65.23482 -422.819068) (xy 65.23482 -424.689778)
			(xy 68.13804 -424.689778) (xy 68.138155 -424.674693) (xy 68.139933 -424.644574) (xy 68.141596 -424.62958)
			(xy 68.141596 -423.55008) (xy 68.139932 -423.535086) (xy 68.13815 -423.504968) (xy 68.13804 -423.489882)
			(xy 68.138155 -423.474797) (xy 68.139933 -423.444678) (xy 68.141596 -423.429684) (xy 68.141596 -422.819068)
			(xy 68.142037 -422.806991) (xy 68.149509 -422.784022) (xy 68.163711 -422.764485) (xy 68.183255 -422.750292)
			(xy 68.206227 -422.742831) (xy 68.218304 -422.74236) (xy 69.158104 -422.74236) (xy 69.170176 -422.74286)
			(xy 69.193137 -422.75032) (xy 69.212672 -422.764508) (xy 69.226867 -422.784037) (xy 69.234335 -422.806997)
			(xy 69.234812 -422.819068) (xy 69.234812 -423.68978) (xy 70.138036 -423.68978) (xy 70.138153 -423.674695)
			(xy 70.139931 -423.644576) (xy 70.141592 -423.629582) (xy 70.141592 -422.550082) (xy 70.139928 -422.535088)
			(xy 70.138147 -422.50497) (xy 70.138036 -422.489884) (xy 70.138153 -422.474799) (xy 70.139931 -422.44468)
			(xy 70.141592 -422.429686) (xy 70.141592 -421.81907) (xy 70.142081 -421.806984) (xy 70.14954 -421.78399)
			(xy 70.163723 -421.764415) (xy 70.183248 -421.750163) (xy 70.206215 -421.742624) (xy 70.2183 -421.742108)
			(xy 71.1581 -421.742108) (xy 71.17021 -421.742516) (xy 71.193238 -421.750017) (xy 71.212812 -421.76428)
			(xy 71.227007 -421.783904) (xy 71.234426 -421.806959) (xy 71.234808 -421.81907) (xy 71.234808 -424.360594)
			(xy 71.234288 -424.372678) (xy 71.226839 -424.395671) (xy 71.212664 -424.415247) (xy 71.193145 -424.429499)
			(xy 71.170183 -424.43704) (xy 71.1581 -424.437556) (xy 70.2183 -424.437556) (xy 70.206197 -424.437085)
			(xy 70.183179 -424.429592) (xy 70.163611 -424.415343) (xy 70.149414 -424.395736) (xy 70.141983 -424.372698)
			(xy 70.141592 -424.360594) (xy 70.141592 -423.749978) (xy 70.139928 -423.734984) (xy 70.138146 -423.704866)
			(xy 70.138036 -423.68978) (xy 69.234812 -423.68978) (xy 69.234812 -424.689778) (xy 72.138032 -424.689778)
			(xy 72.138149 -424.674693) (xy 72.139927 -424.644574) (xy 72.141588 -424.62958) (xy 72.141588 -423.55008)
			(xy 72.139924 -423.535086) (xy 72.138142 -423.504968) (xy 72.138032 -423.489882) (xy 72.138149 -423.474797)
			(xy 72.139927 -423.444678) (xy 72.141588 -423.429684) (xy 72.141588 -422.819068) (xy 72.142037 -422.806992)
			(xy 72.149508 -422.784025) (xy 72.163708 -422.764488) (xy 72.18325 -422.750295) (xy 72.20622 -422.742832)
			(xy 72.218296 -422.74236) (xy 73.158096 -422.74236) (xy 73.170167 -422.742867) (xy 73.193129 -422.750325)
			(xy 73.212663 -422.764511) (xy 73.226859 -422.784039) (xy 73.234327 -422.806997) (xy 73.234804 -422.819068)
			(xy 73.234804 -425.360592) (xy 73.234381 -425.372675) (xy 73.226915 -425.395658) (xy 73.212712 -425.415209)
			(xy 73.193162 -425.429413) (xy 73.170179 -425.43688) (xy 73.158096 -425.4373) (xy 72.218296 -425.4373)
			(xy 72.206212 -425.436891) (xy 72.183228 -425.429421) (xy 72.163677 -425.415214) (xy 72.149473 -425.395661)
			(xy 72.142007 -425.372676) (xy 72.141588 -425.360592) (xy 72.141588 -424.749976) (xy 72.139924 -424.734982)
			(xy 72.138142 -424.704864) (xy 72.138032 -424.689778) (xy 69.234812 -424.689778) (xy 69.234812 -425.360592)
			(xy 69.234381 -425.372674) (xy 69.226916 -425.395656) (xy 69.212714 -425.415206) (xy 69.193167 -425.429411)
			(xy 69.170186 -425.436879) (xy 69.158104 -425.4373) (xy 68.218304 -425.4373) (xy 68.206221 -425.436884)
			(xy 68.183237 -425.429417) (xy 68.163686 -425.415212) (xy 68.149482 -425.39566) (xy 68.142015 -425.372675)
			(xy 68.141596 -425.360592) (xy 68.141596 -424.749976) (xy 68.139932 -424.734982) (xy 68.13815 -424.704864)
			(xy 68.13804 -424.689778) (xy 65.23482 -424.689778) (xy 65.23482 -425.360592) (xy 65.234329 -425.372665)
			(xy 65.22687 -425.39563) (xy 65.21268 -425.415166) (xy 65.193148 -425.429361) (xy 65.170185 -425.436826)
			(xy 65.158112 -425.4373) (xy 64.218312 -425.4373) (xy 64.206229 -425.436877) (xy 64.183246 -425.429412)
			(xy 64.163694 -425.415208) (xy 64.14949 -425.395658) (xy 64.142024 -425.372675) (xy 64.141604 -425.360592)
			(xy 64.141604 -424.749976) (xy 64.13994 -424.734982) (xy 64.138158 -424.704864) (xy 64.138048 -424.689778)
			(xy 50.54061 -424.689778) (xy 50.536903 -424.786486) (xy 50.520747 -424.996915) (xy 50.496544 -425.206572)
			(xy 50.464327 -425.415147) (xy 50.424145 -425.622335) (xy 50.376057 -425.827832) (xy 50.320133 -426.031336)
			(xy 50.256456 -426.232549) (xy 50.185118 -426.431176) (xy 50.106224 -426.626924) (xy 50.019891 -426.819506)
			(xy 49.926244 -427.008641) (xy 49.825422 -427.19405) (xy 49.768393 -427.289976) (xy 58.13806 -427.289976)
			(xy 58.138174 -427.274891) (xy 58.139952 -427.244772) (xy 58.141616 -427.229778) (xy 58.141616 -426.150024)
			(xy 58.139947 -426.135031) (xy 58.138169 -426.104912) (xy 58.13806 -426.089826) (xy 58.13817 -426.07474)
			(xy 58.139951 -426.044622) (xy 58.141616 -426.029628) (xy 58.141616 -425.419012) (xy 58.142023 -425.406928)
			(xy 58.149491 -425.383941) (xy 58.163697 -425.364389) (xy 58.183252 -425.350185) (xy 58.206239 -425.342722)
			(xy 58.218324 -425.342304) (xy 59.158124 -425.342304) (xy 59.170201 -425.342744) (xy 59.193171 -425.350215)
			(xy 59.212709 -425.364417) (xy 59.226902 -425.383961) (xy 59.234361 -425.406935) (xy 59.234832 -425.419012)
			(xy 59.234832 -427.960536) (xy 59.234367 -427.97261) (xy 59.226898 -427.995574) (xy 59.2127 -428.015109)
			(xy 59.193164 -428.029303) (xy 59.170198 -428.036769) (xy 59.158124 -428.037244) (xy 58.218324 -428.037244)
			(xy 58.206254 -428.036716) (xy 58.183294 -428.029264) (xy 58.16376 -428.015083) (xy 58.149563 -427.99556)
			(xy 58.142093 -427.972605) (xy 58.141616 -427.960536) (xy 58.141616 -427.350174) (xy 58.139952 -427.33518)
			(xy 58.13817 -427.305062) (xy 58.13806 -427.289976) (xy 49.768393 -427.289976) (xy 49.717572 -427.375461)
			(xy 49.602853 -427.552608) (xy 49.481433 -427.72523) (xy 49.35349 -427.893076) (xy 49.219212 -428.055898)
			(xy 49.078796 -428.213457) (xy 49.0054 -428.28972) (xy 60.138056 -428.28972) (xy 60.138166 -428.274634)
			(xy 60.139947 -428.244516) (xy 60.141612 -428.229522) (xy 60.141612 -427.150022) (xy 60.139943 -427.135029)
			(xy 60.138165 -427.10491) (xy 60.138056 -427.089824) (xy 60.138166 -427.074738) (xy 60.139947 -427.04462)
			(xy 60.141612 -427.029626) (xy 60.141612 -426.41901) (xy 60.142115 -426.406924) (xy 60.149566 -426.383928)
			(xy 60.163744 -426.364351) (xy 60.183268 -426.350099) (xy 60.206236 -426.342562) (xy 60.21832 -426.342048)
			(xy 61.15812 -426.342048) (xy 61.170225 -426.342499) (xy 61.193244 -426.349997) (xy 61.212812 -426.364252)
			(xy 61.227008 -426.383863) (xy 61.234437 -426.406904) (xy 61.234828 -426.41901) (xy 61.234828 -427.289976)
			(xy 62.138052 -427.289976) (xy 62.138166 -427.274891) (xy 62.139944 -427.244772) (xy 62.141608 -427.229778)
			(xy 62.141608 -426.150024) (xy 62.139939 -426.135031) (xy 62.138161 -426.104912) (xy 62.138052 -426.089826)
			(xy 62.138162 -426.07474) (xy 62.139943 -426.044622) (xy 62.141608 -426.029628) (xy 62.141608 -425.419012)
			(xy 62.142023 -425.406928) (xy 62.149489 -425.383943) (xy 62.163694 -425.364392) (xy 62.183247 -425.350188)
			(xy 62.206232 -425.342723) (xy 62.218316 -425.342304) (xy 63.158116 -425.342304) (xy 63.170193 -425.342751)
			(xy 63.193162 -425.350219) (xy 63.2127 -425.36442) (xy 63.226894 -425.383963) (xy 63.234353 -425.406935)
			(xy 63.234824 -425.419012) (xy 63.234824 -427.960536) (xy 63.234367 -427.972611) (xy 63.226896 -427.995577)
			(xy 63.212697 -428.015112) (xy 63.193159 -428.029306) (xy 63.170191 -428.03677) (xy 63.158116 -428.037244)
			(xy 62.218316 -428.037244) (xy 62.206246 -428.036723) (xy 62.183285 -428.029269) (xy 62.163751 -428.015086)
			(xy 62.149555 -427.995561) (xy 62.142085 -427.972606) (xy 62.141608 -427.960536) (xy 62.141608 -427.350174)
			(xy 62.139944 -427.33518) (xy 62.138162 -427.305062) (xy 62.138052 -427.289976) (xy 61.234828 -427.289976)
			(xy 61.234828 -428.28972) (xy 64.138048 -428.28972) (xy 64.138158 -428.274634) (xy 64.139939 -428.244516)
			(xy 64.141604 -428.229522) (xy 64.141604 -427.150022) (xy 64.139935 -427.135029) (xy 64.138157 -427.10491)
			(xy 64.138048 -427.089824) (xy 64.138158 -427.074738) (xy 64.139939 -427.04462) (xy 64.141604 -427.029626)
			(xy 64.141604 -426.41901) (xy 64.142115 -426.406925) (xy 64.149565 -426.38393) (xy 64.163741 -426.364353)
			(xy 64.183263 -426.350101) (xy 64.206228 -426.342563) (xy 64.218312 -426.342048) (xy 65.158112 -426.342048)
			(xy 65.170216 -426.342505) (xy 65.193235 -426.350002) (xy 65.212804 -426.364255) (xy 65.227 -426.383864)
			(xy 65.234429 -426.406905) (xy 65.23482 -426.41901) (xy 65.23482 -427.289976) (xy 66.138044 -427.289976)
			(xy 66.138159 -427.274891) (xy 66.139936 -427.244772) (xy 66.1416 -427.229778) (xy 66.1416 -426.150024)
			(xy 66.139931 -426.135031) (xy 66.138153 -426.104912) (xy 66.138044 -426.089826) (xy 66.138154 -426.07474)
			(xy 66.139935 -426.044622) (xy 66.1416 -426.029628) (xy 66.1416 -425.419012) (xy 66.142023 -425.406929)
			(xy 66.149488 -425.383946) (xy 66.163692 -425.364394) (xy 66.183242 -425.35019) (xy 66.206225 -425.342724)
			(xy 66.218308 -425.342304) (xy 67.158108 -425.342304) (xy 67.170192 -425.342706) (xy 67.193177 -425.350177)
			(xy 67.212729 -425.364386) (xy 67.226932 -425.383941) (xy 67.234397 -425.406928) (xy 67.234816 -425.419012)
			(xy 67.234816 -427.960536) (xy 67.234367 -427.972612) (xy 67.226895 -427.995579) (xy 67.212695 -428.015115)
			(xy 67.193154 -428.029308) (xy 67.170184 -428.036771) (xy 67.158108 -428.037244) (xy 66.218308 -428.037244)
			(xy 66.206237 -428.03673) (xy 66.183277 -428.029274) (xy 66.163743 -428.015089) (xy 66.149547 -427.995563)
			(xy 66.142077 -427.972606) (xy 66.1416 -427.960536) (xy 66.1416 -427.350174) (xy 66.139936 -427.33518)
			(xy 66.138154 -427.305062) (xy 66.138044 -427.289976) (xy 65.23482 -427.289976) (xy 65.23482 -428.28972)
			(xy 68.13804 -428.28972) (xy 68.138152 -428.274634) (xy 68.139933 -428.244516) (xy 68.141596 -428.229522)
			(xy 68.141596 -427.150022) (xy 68.139927 -427.135029) (xy 68.138149 -427.10491) (xy 68.13804 -427.089824)
			(xy 68.13815 -427.074738) (xy 68.139931 -427.04462) (xy 68.141596 -427.029626) (xy 68.141596 -426.41901)
			(xy 68.142115 -426.406925) (xy 68.149564 -426.383932) (xy 68.163739 -426.364356) (xy 68.183258 -426.350104)
			(xy 68.206221 -426.342564) (xy 68.218304 -426.342048) (xy 69.158104 -426.342048) (xy 69.170208 -426.342512)
			(xy 69.193227 -426.350006) (xy 69.212795 -426.364257) (xy 69.226991 -426.383866) (xy 69.234421 -426.406905)
			(xy 69.234812 -426.41901) (xy 69.234812 -427.289976) (xy 70.138036 -427.289976) (xy 70.138153 -427.274891)
			(xy 70.13993 -427.244772) (xy 70.141592 -427.229778) (xy 70.141592 -426.150024) (xy 70.139923 -426.135031)
			(xy 70.138145 -426.104912) (xy 70.138036 -426.089826) (xy 70.138148 -426.07474) (xy 70.139929 -426.044622)
			(xy 70.141592 -426.029628) (xy 70.141592 -425.419012) (xy 70.142023 -425.40693) (xy 70.149487 -425.383948)
			(xy 70.163689 -425.364397) (xy 70.183237 -425.350193) (xy 70.206218 -425.342725) (xy 70.2183 -425.342304)
			(xy 71.1581 -425.342304) (xy 71.170184 -425.342713) (xy 71.193169 -425.350182) (xy 71.21272 -425.364388)
			(xy 71.226924 -425.383942) (xy 71.234389 -425.406928) (xy 71.234808 -425.419012) (xy 71.234808 -427.960536)
			(xy 71.234367 -427.972612) (xy 71.226894 -427.995581) (xy 71.212692 -428.015117) (xy 71.193149 -428.029311)
			(xy 71.170177 -428.036772) (xy 71.1581 -428.037244) (xy 70.2183 -428.037244) (xy 70.206229 -428.036736)
			(xy 70.183268 -428.029278) (xy 70.163734 -428.015092) (xy 70.149538 -427.995564) (xy 70.142069 -427.972607)
			(xy 70.141592 -427.960536) (xy 70.141592 -427.350174) (xy 70.139928 -427.33518) (xy 70.138146 -427.305062)
			(xy 70.138036 -427.289976) (xy 69.234812 -427.289976) (xy 69.234812 -428.28972) (xy 72.138032 -428.28972)
			(xy 72.138144 -428.274634) (xy 72.139925 -428.244516) (xy 72.141588 -428.229522) (xy 72.141588 -427.150022)
			(xy 72.139919 -427.135029) (xy 72.138141 -427.10491) (xy 72.138032 -427.089824) (xy 72.138144 -427.074738)
			(xy 72.139925 -427.04462) (xy 72.141588 -427.029626) (xy 72.141588 -426.41901) (xy 72.142017 -426.406916)
			(xy 72.149477 -426.383908) (xy 72.163671 -426.364324) (xy 72.183216 -426.350075) (xy 72.206204 -426.342551)
			(xy 72.218296 -426.342048) (xy 73.158096 -426.342048) (xy 73.170199 -426.342519) (xy 73.193218 -426.350011)
			(xy 73.212787 -426.36426) (xy 73.226983 -426.383867) (xy 73.234413 -426.406905) (xy 73.234804 -426.41901)
			(xy 73.234804 -427.289976) (xy 75.138026 -427.289976) (xy 75.138117 -427.275402) (xy 75.139771 -427.246301)
			(xy 75.141328 -427.23181) (xy 75.141328 -426.147992) (xy 75.139785 -426.1335) (xy 75.138132 -426.1044)
			(xy 75.138026 -426.089826) (xy 75.138121 -426.075252) (xy 75.139773 -426.046151) (xy 75.141328 -426.03166)
			(xy 75.141328 -425.419012) (xy 75.141727 -425.406901) (xy 75.149227 -425.383869) (xy 75.163492 -425.364294)
			(xy 75.183119 -425.3501) (xy 75.206178 -425.342684) (xy 75.21829 -425.342304) (xy 76.15809 -425.342304)
			(xy 76.170175 -425.342815) (xy 76.19317 -425.350265) (xy 76.212747 -425.364441) (xy 76.226999 -425.383963)
			(xy 76.234537 -425.406928) (xy 76.235052 -425.419012) (xy 76.235052 -427.960536) (xy 76.234615 -427.972642)
			(xy 76.227112 -427.995661) (xy 76.212854 -428.015229) (xy 76.19324 -428.029424) (xy 76.170197 -428.036854)
			(xy 76.15809 -428.037244) (xy 75.21829 -428.037244) (xy 75.206198 -428.036801) (xy 75.183195 -428.029339)
			(xy 75.163614 -428.015147) (xy 75.149364 -427.995608) (xy 75.141835 -427.972626) (xy 75.141328 -427.960536)
			(xy 75.141328 -427.348142) (xy 75.139781 -427.33365) (xy 75.138131 -427.30455) (xy 75.138026 -427.289976)
			(xy 73.234804 -427.289976) (xy 73.234804 -428.28972) (xy 77.138022 -428.28972) (xy 77.138117 -428.275146)
			(xy 77.139768 -428.246045) (xy 77.141324 -428.231554) (xy 77.141324 -427.14799) (xy 77.139781 -427.133498)
			(xy 77.138128 -427.104398) (xy 77.138022 -427.089824) (xy 77.138117 -427.07525) (xy 77.139769 -427.046149)
			(xy 77.141324 -427.031658) (xy 77.141324 -426.41901) (xy 77.14182 -426.406897) (xy 77.149303 -426.383857)
			(xy 77.163539 -426.364256) (xy 77.183135 -426.350014) (xy 77.206174 -426.342524) (xy 77.218286 -426.342048)
			(xy 78.158086 -426.342048) (xy 78.170209 -426.342472) (xy 78.193269 -426.349962) (xy 78.212885 -426.364212)
			(xy 78.227136 -426.383827) (xy 78.234627 -426.406887) (xy 78.235048 -426.41901) (xy 78.235048 -427.289976)
			(xy 79.138018 -427.289976) (xy 79.138109 -427.275402) (xy 79.139763 -427.246301) (xy 79.14132 -427.23181)
			(xy 79.14132 -426.147992) (xy 79.139777 -426.1335) (xy 79.138124 -426.1044) (xy 79.138018 -426.089826)
			(xy 79.138113 -426.075252) (xy 79.139765 -426.046151) (xy 79.14132 -426.03166) (xy 79.14132 -425.419012)
			(xy 79.141727 -425.406902) (xy 79.149226 -425.383872) (xy 79.163489 -425.364297) (xy 79.183114 -425.350102)
			(xy 79.20617 -425.342685) (xy 79.218282 -425.342304) (xy 80.158082 -425.342304) (xy 80.170167 -425.342822)
			(xy 80.193161 -425.35027) (xy 80.212738 -425.364444) (xy 80.226991 -425.383965) (xy 80.234529 -425.406929)
			(xy 80.235044 -425.419012) (xy 80.235044 -427.960536) (xy 80.234615 -427.972642) (xy 80.227111 -427.995663)
			(xy 80.212851 -428.015232) (xy 80.193235 -428.029427) (xy 80.17019 -428.036855) (xy 80.158082 -428.037244)
			(xy 79.218282 -428.037244) (xy 79.20619 -428.036808) (xy 79.183186 -428.029344) (xy 79.163605 -428.01515)
			(xy 79.149355 -427.995609) (xy 79.141827 -427.972627) (xy 79.14132 -427.960536) (xy 79.14132 -427.348142)
			(xy 79.139773 -427.33365) (xy 79.138123 -427.30455) (xy 79.138018 -427.289976) (xy 78.235048 -427.289976)
			(xy 78.235048 -428.28972) (xy 81.138014 -428.28972) (xy 81.138108 -428.275146) (xy 81.13976 -428.246045)
			(xy 81.141316 -428.231554) (xy 81.141316 -427.14799) (xy 81.139773 -427.133498) (xy 81.13812 -427.104398)
			(xy 81.138014 -427.089824) (xy 81.138108 -427.07525) (xy 81.13976 -427.046149) (xy 81.141316 -427.031658)
			(xy 81.141316 -426.41901) (xy 81.14182 -426.406898) (xy 81.149302 -426.383859) (xy 81.163536 -426.364259)
			(xy 81.18313 -426.350016) (xy 81.206166 -426.342525) (xy 81.218278 -426.342048) (xy 82.158078 -426.342048)
			(xy 82.170201 -426.342479) (xy 82.19326 -426.349966) (xy 82.212877 -426.364215) (xy 82.227128 -426.383829)
			(xy 82.234619 -426.406887) (xy 82.23504 -426.41901) (xy 82.23504 -427.289976) (xy 83.13801 -427.289976)
			(xy 83.1381 -427.275402) (xy 83.139755 -427.246301) (xy 83.141312 -427.23181) (xy 83.141312 -426.147992)
			(xy 83.139769 -426.1335) (xy 83.138116 -426.1044) (xy 83.13801 -426.089826) (xy 83.138105 -426.075252)
			(xy 83.139756 -426.046151) (xy 83.141312 -426.03166) (xy 83.141312 -425.419012) (xy 83.141727 -425.406903)
			(xy 83.149224 -425.383874) (xy 83.163486 -425.364299) (xy 83.183109 -425.350105) (xy 83.206163 -425.342686)
			(xy 83.218274 -425.342304) (xy 84.158074 -425.342304) (xy 84.170159 -425.342829) (xy 84.193152 -425.350274)
			(xy 84.21273 -425.364447) (xy 84.226982 -425.383966) (xy 84.234521 -425.406929) (xy 84.235036 -425.419012)
			(xy 84.235036 -427.960536) (xy 84.234615 -427.972643) (xy 84.22711 -427.995665) (xy 84.212848 -428.015235)
			(xy 84.19323 -428.029429) (xy 84.170183 -428.036856) (xy 84.158074 -428.037244) (xy 83.218274 -428.037244)
			(xy 83.206181 -428.036815) (xy 83.183177 -428.029349) (xy 83.163596 -428.015153) (xy 83.149347 -427.995611)
			(xy 83.141819 -427.972627) (xy 83.141312 -427.960536) (xy 83.141312 -427.348142) (xy 83.139765 -427.33365)
			(xy 83.138115 -427.30455) (xy 83.13801 -427.289976) (xy 82.23504 -427.289976) (xy 82.23504 -428.28972)
			(xy 85.138006 -428.28972) (xy 85.1381 -428.275146) (xy 85.139752 -428.246045) (xy 85.141308 -428.231554)
			(xy 85.141308 -427.14799) (xy 85.139765 -427.133498) (xy 85.138112 -427.104398) (xy 85.138006 -427.089824)
			(xy 85.1381 -427.07525) (xy 85.139752 -427.046149) (xy 85.141308 -427.031658) (xy 85.141308 -426.41901)
			(xy 85.14182 -426.406899) (xy 85.149301 -426.383861) (xy 85.163533 -426.364262) (xy 85.183125 -426.350019)
			(xy 85.206159 -426.342526) (xy 85.21827 -426.342048) (xy 86.15807 -426.342048) (xy 86.170192 -426.342486)
			(xy 86.193252 -426.349971) (xy 86.212868 -426.364218) (xy 86.22712 -426.38383) (xy 86.234611 -426.406888)
			(xy 86.235032 -426.41901) (xy 86.235032 -427.289976) (xy 87.138002 -427.289976) (xy 87.138092 -427.275402)
			(xy 87.139747 -427.246301) (xy 87.141304 -427.23181) (xy 87.141304 -426.147992) (xy 87.139761 -426.1335)
			(xy 87.138108 -426.1044) (xy 87.138002 -426.089826) (xy 87.138097 -426.075252) (xy 87.139748 -426.046151)
			(xy 87.141304 -426.03166) (xy 87.141304 -425.419012) (xy 87.141727 -425.406903) (xy 87.149223 -425.383876)
			(xy 87.163483 -425.364302) (xy 87.183104 -425.350107) (xy 87.206156 -425.342687) (xy 87.218266 -425.342304)
			(xy 88.158066 -425.342304) (xy 88.17015 -425.342836) (xy 88.193144 -425.350279) (xy 88.212721 -425.36445)
			(xy 88.226974 -425.383968) (xy 88.234513 -425.40693) (xy 88.235028 -425.419012) (xy 88.235028 -427.960536)
			(xy 88.234615 -427.972644) (xy 88.227109 -427.995668) (xy 88.212845 -428.015238) (xy 88.193225 -428.029432)
			(xy 88.170175 -428.036857) (xy 88.158066 -428.037244) (xy 87.218266 -428.037244) (xy 87.206173 -428.036821)
			(xy 87.183169 -428.029353) (xy 87.163588 -428.015156) (xy 87.149339 -427.995612) (xy 87.141811 -427.972628)
			(xy 87.141304 -427.960536) (xy 87.141304 -427.348142) (xy 87.139757 -427.33365) (xy 87.138107 -427.30455)
			(xy 87.138002 -427.289976) (xy 86.235032 -427.289976) (xy 86.235032 -428.28972) (xy 89.137998 -428.28972)
			(xy 89.138092 -428.275146) (xy 89.139744 -428.246045) (xy 89.1413 -428.231554) (xy 89.1413 -427.14799)
			(xy 89.139757 -427.133498) (xy 89.138104 -427.104398) (xy 89.137998 -427.089824) (xy 89.138092 -427.07525)
			(xy 89.139744 -427.046149) (xy 89.1413 -427.031658) (xy 89.1413 -426.41901) (xy 89.14182 -426.4069)
			(xy 89.1493 -426.383863) (xy 89.163531 -426.364265) (xy 89.18312 -426.350022) (xy 89.206152 -426.342527)
			(xy 89.218262 -426.342048) (xy 90.158062 -426.342048) (xy 90.170184 -426.342492) (xy 90.193243 -426.349975)
			(xy 90.21286 -426.36422) (xy 90.227112 -426.383832) (xy 90.234603 -426.406888) (xy 90.235024 -426.41901)
			(xy 90.235024 -428.960534) (xy 90.234669 -428.972662) (xy 90.227162 -428.995729) (xy 90.212895 -429.015347)
			(xy 90.193264 -429.029595) (xy 90.170191 -429.03708) (xy 90.158062 -429.037496) (xy 89.218262 -429.037496)
			(xy 89.206149 -429.037021) (xy 89.18311 -429.029528) (xy 89.163512 -429.015285) (xy 89.14927 -428.995686)
			(xy 89.141778 -428.972647) (xy 89.1413 -428.960534) (xy 89.1413 -428.347886) (xy 89.139757 -428.333394)
			(xy 89.138104 -428.304294) (xy 89.137998 -428.28972) (xy 86.235032 -428.28972) (xy 86.235032 -428.960534)
			(xy 86.234617 -428.972653) (xy 86.227117 -428.995703) (xy 86.212861 -429.015307) (xy 86.193245 -429.029546)
			(xy 86.17019 -429.037027) (xy 86.15807 -429.037496) (xy 85.21827 -429.037496) (xy 85.206157 -429.037014)
			(xy 85.183119 -429.029523) (xy 85.16352 -429.015282) (xy 85.149279 -428.995685) (xy 85.141786 -428.972647)
			(xy 85.141308 -428.960534) (xy 85.141308 -428.347886) (xy 85.139765 -428.333394) (xy 85.138112 -428.304294)
			(xy 85.138006 -428.28972) (xy 82.23504 -428.28972) (xy 82.23504 -428.960534) (xy 82.234617 -428.972653)
			(xy 82.227118 -428.995701) (xy 82.212864 -429.015304) (xy 82.19325 -429.029543) (xy 82.170197 -429.037026)
			(xy 82.158078 -429.037496) (xy 81.218278 -429.037496) (xy 81.206166 -429.037008) (xy 81.183127 -429.029519)
			(xy 81.163529 -429.01528) (xy 81.149287 -428.995683) (xy 81.141794 -428.972646) (xy 81.141316 -428.960534)
			(xy 81.141316 -428.347886) (xy 81.139773 -428.333394) (xy 81.13812 -428.304294) (xy 81.138014 -428.28972)
			(xy 78.235048 -428.28972) (xy 78.235048 -428.960534) (xy 78.234617 -428.972652) (xy 78.227119 -428.995698)
			(xy 78.212867 -429.015301) (xy 78.193255 -429.029541) (xy 78.170204 -429.037025) (xy 78.158086 -429.037496)
			(xy 77.218286 -429.037496) (xy 77.206174 -429.037001) (xy 77.183136 -429.029514) (xy 77.163537 -429.015277)
			(xy 77.149295 -428.995682) (xy 77.141802 -428.972646) (xy 77.141324 -428.960534) (xy 77.141324 -428.347886)
			(xy 77.139781 -428.333394) (xy 77.138128 -428.304294) (xy 77.138022 -428.28972) (xy 73.234804 -428.28972)
			(xy 73.234804 -428.960534) (xy 73.234323 -428.972621) (xy 73.226862 -428.995615) (xy 73.212677 -429.015191)
			(xy 73.19315 -429.029442) (xy 73.170181 -429.036981) (xy 73.158096 -429.037496) (xy 72.218296 -429.037496)
			(xy 72.206187 -429.037087) (xy 72.183158 -429.029586) (xy 72.163585 -429.015323) (xy 72.149391 -428.995699)
			(xy 72.141971 -428.972645) (xy 72.141588 -428.960534) (xy 72.141588 -428.349918) (xy 72.139919 -428.334925)
			(xy 72.138141 -428.304806) (xy 72.138032 -428.28972) (xy 69.234812 -428.28972) (xy 69.234812 -428.960534)
			(xy 69.234421 -428.97263) (xy 69.226949 -428.99564) (xy 69.212744 -429.015223) (xy 69.193192 -429.029471)
			(xy 69.170199 -429.036994) (xy 69.158104 -429.037496) (xy 68.218304 -429.037496) (xy 68.206195 -429.03708)
			(xy 68.183167 -429.029582) (xy 68.163593 -429.01532) (xy 68.149399 -428.995698) (xy 68.141979 -428.972644)
			(xy 68.141596 -428.960534) (xy 68.141596 -428.349918) (xy 68.139927 -428.334925) (xy 68.138149 -428.304806)
			(xy 68.13804 -428.28972) (xy 65.23482 -428.28972) (xy 65.23482 -428.960534) (xy 65.234421 -428.972629)
			(xy 65.22695 -428.995638) (xy 65.212747 -429.015221) (xy 65.193197 -429.029469) (xy 65.170206 -429.036993)
			(xy 65.158112 -429.037496) (xy 64.218312 -429.037496) (xy 64.206203 -429.037073) (xy 64.183176 -429.029577)
			(xy 64.163602 -429.015317) (xy 64.149407 -428.995696) (xy 64.141987 -428.972644) (xy 64.141604 -428.960534)
			(xy 64.141604 -428.349918) (xy 64.139935 -428.334925) (xy 64.138157 -428.304806) (xy 64.138048 -428.28972)
			(xy 61.234828 -428.28972) (xy 61.234828 -428.960534) (xy 61.234421 -428.972629) (xy 61.226951 -428.995636)
			(xy 61.21275 -429.015218) (xy 61.193202 -429.029466) (xy 61.170213 -429.036992) (xy 61.15812 -429.037496)
			(xy 60.21832 -429.037496) (xy 60.206212 -429.037066) (xy 60.183185 -429.029572) (xy 60.163611 -429.015314)
			(xy 60.149416 -428.995695) (xy 60.141995 -428.972643) (xy 60.141612 -428.960534) (xy 60.141612 -428.349918)
			(xy 60.139943 -428.334925) (xy 60.138165 -428.304806) (xy 60.138056 -428.28972) (xy 49.0054 -428.28972)
			(xy 48.932448 -428.365522) (xy 48.780383 -428.51187) (xy 48.622824 -428.652286) (xy 48.460002 -428.786564)
			(xy 48.292156 -428.914507) (xy 48.119534 -429.035927) (xy 47.942387 -429.150646) (xy 47.760976 -429.258496)
			(xy 47.575567 -429.359318) (xy 47.386432 -429.452965) (xy 47.19385 -429.539298) (xy 46.998102 -429.618192)
			(xy 46.799475 -429.68953) (xy 46.598262 -429.753207) (xy 46.394758 -429.809131) (xy 46.189261 -429.857219)
			(xy 45.982073 -429.897401) (xy 45.773498 -429.929618) (xy 45.563841 -429.953821) (xy 45.353412 -429.969977)
			(xy 45.142518 -429.978061) (xy 44.93147 -429.978061) (xy 44.720576 -429.969977) (xy 44.510147 -429.953821)
			(xy 44.30049 -429.929618) (xy 44.091915 -429.897401) (xy 43.884727 -429.857219) (xy 43.67923 -429.809131)
			(xy 43.475726 -429.753207) (xy 43.274513 -429.68953) (xy 43.075886 -429.618192) (xy 42.880138 -429.539298)
			(xy 42.687556 -429.452965) (xy 42.498421 -429.359318) (xy 42.313012 -429.258496) (xy 42.131601 -429.150646)
			(xy 41.954454 -429.035927) (xy 41.781832 -428.914507) (xy 41.613986 -428.786564) (xy 41.451164 -428.652286)
			(xy 41.293605 -428.51187) (xy 41.14154 -428.365522) (xy 40.995192 -428.213457) (xy 40.854776 -428.055898)
			(xy 40.720498 -427.893076) (xy 40.592555 -427.72523) (xy 40.471135 -427.552608) (xy 40.356416 -427.375461)
			(xy 40.248566 -427.19405) (xy 40.147744 -427.008641) (xy 40.054097 -426.819506) (xy 39.967764 -426.626924)
			(xy 39.88887 -426.431176) (xy 39.817532 -426.232549) (xy 39.753855 -426.031336) (xy 39.697931 -425.827832)
			(xy 39.649843 -425.622335) (xy 39.609661 -425.415147) (xy 39.577444 -425.206572) (xy 39.553241 -424.996915)
			(xy 39.537085 -424.786486) (xy 39.529001 -424.575592) (xy 39.528496 -424.470068) (xy 8.024114 -424.470068)
			(xy 8.024114 -433.340256) (xy 8.024565 -433.354039) (xy 8.03193 -433.380601) (xy 8.046135 -433.404224)
			(xy 8.066143 -433.423185) (xy 8.090495 -433.4361) (xy 8.117415 -433.442027) (xy 8.144939 -433.440534)
			(xy 8.17106 -433.43173) (xy 8.193872 -433.416257) (xy 8.211712 -433.395244) (xy 8.217916 -433.382928)
			(xy 8.261825 -433.289418) (xy 8.356005 -433.105523) (xy 8.457319 -432.925459) (xy 8.56561 -432.749504)
			(xy 8.680713 -432.577927) (xy 8.802451 -432.410992) (xy 8.930637 -432.248956) (xy 9.065073 -432.092066)
			(xy 9.205554 -431.940565) (xy 9.351863 -431.794686) (xy 9.503776 -431.654651) (xy 9.66106 -431.520676)
			(xy 9.823472 -431.392967) (xy 9.990764 -431.27172) (xy 10.162678 -431.157122) (xy 10.338951 -431.049348)
			(xy 10.519312 -430.948564) (xy 10.703483 -430.854925) (xy 10.891182 -430.768574) (xy 11.08212 -430.689644)
			(xy 11.276005 -430.618257) (xy 11.472537 -430.554521) (xy 11.671417 -430.498536) (xy 11.872337 -430.450387)
			(xy 12.07499 -430.410147) (xy 12.279064 -430.377879) (xy 12.484245 -430.353633) (xy 12.690219 -430.337445)
			(xy 12.896669 -430.32934) (xy 12.999974 -430.328832) (xy 13.103478 -430.32934) (xy 13.310327 -430.337468)
			(xy 13.516697 -430.353709) (xy 13.722271 -430.378041) (xy 13.926731 -430.410424) (xy 14.129762 -430.45081)
			(xy 14.33105 -430.499135) (xy 14.530287 -430.555326) (xy 14.727163 -430.619295) (xy 14.921377 -430.690944)
			(xy 15.112628 -430.770163) (xy 15.300621 -430.856829) (xy 15.365562 -430.889918) (xy 58.13806 -430.889918)
			(xy 58.138169 -430.874832) (xy 58.139951 -430.844714) (xy 58.141616 -430.82972) (xy 58.141616 -429.749966)
			(xy 58.139951 -429.734972) (xy 58.13817 -429.704854) (xy 58.13806 -429.689768) (xy 58.138174 -429.674682)
			(xy 58.139952 -429.644564) (xy 58.141616 -429.62957) (xy 58.141616 -429.018954) (xy 58.142068 -429.006864)
			(xy 58.149534 -428.983866) (xy 58.163726 -428.964289) (xy 58.18326 -428.950039) (xy 58.206236 -428.942504)
			(xy 58.218324 -428.941992) (xy 59.158124 -428.941992) (xy 59.170233 -428.942396) (xy 59.19326 -428.949901)
			(xy 59.212832 -428.964166) (xy 59.227026 -428.983789) (xy 59.234448 -429.006843) (xy 59.234832 -429.018954)
			(xy 59.234832 -431.560478) (xy 59.234373 -431.572569) (xy 59.226919 -431.595574) (xy 59.212732 -431.615156)
			(xy 59.193194 -431.629407) (xy 59.170214 -431.636934) (xy 59.158124 -431.63744) (xy 58.218324 -431.63744)
			(xy 58.20622 -431.636964) (xy 58.183201 -431.629476) (xy 58.163631 -431.615228) (xy 58.149434 -431.595622)
			(xy 58.142005 -431.572583) (xy 58.141616 -431.560478) (xy 58.141616 -430.950116) (xy 58.139947 -430.935123)
			(xy 58.138169 -430.905004) (xy 58.13806 -430.889918) (xy 15.365562 -430.889918) (xy 15.485067 -430.950809)
			(xy 15.665681 -431.051958) (xy 15.842184 -431.16012) (xy 16.014306 -431.275128) (xy 16.181779 -431.396805)
			(xy 16.344346 -431.524962) (xy 16.501756 -431.659404) (xy 16.653767 -431.799921) (xy 16.743762 -431.889916)
			(xy 60.138056 -431.889916) (xy 60.138165 -431.87483) (xy 60.139947 -431.844712) (xy 60.141612 -431.829718)
			(xy 60.141612 -430.749964) (xy 60.139947 -430.73497) (xy 60.138166 -430.704852) (xy 60.138056 -430.689766)
			(xy 60.13817 -430.67468) (xy 60.139948 -430.644562) (xy 60.141612 -430.629568) (xy 60.141612 -430.018952)
			(xy 60.142024 -430.006873) (xy 60.149502 -429.983901) (xy 60.163711 -429.964363) (xy 60.183262 -429.950171)
			(xy 60.206241 -429.942713) (xy 60.21832 -429.942244) (xy 61.15812 -429.942244) (xy 61.170191 -429.942747)
			(xy 61.19315 -429.950209) (xy 61.212683 -429.964397) (xy 61.226878 -429.983924) (xy 61.234349 -430.006881)
			(xy 61.234828 -430.018952) (xy 61.234828 -430.889918) (xy 62.138052 -430.889918) (xy 62.138161 -430.874832)
			(xy 62.139943 -430.844714) (xy 62.141608 -430.82972) (xy 62.141608 -429.749966) (xy 62.139943 -429.734972)
			(xy 62.138162 -429.704854) (xy 62.138052 -429.689768) (xy 62.138166 -429.674682) (xy 62.139944 -429.644564)
			(xy 62.141608 -429.62957) (xy 62.141608 -429.018954) (xy 62.142068 -429.006865) (xy 62.149533 -428.983868)
			(xy 62.163723 -428.964292) (xy 62.183255 -428.950042) (xy 62.206229 -428.942505) (xy 62.218316 -428.941992)
			(xy 63.158116 -428.941992) (xy 63.170225 -428.942402) (xy 63.193251 -428.949905) (xy 63.212824 -428.964169)
			(xy 63.227018 -428.983791) (xy 63.23444 -429.006844) (xy 63.234824 -429.018954) (xy 63.234824 -431.560478)
			(xy 63.234373 -431.57257) (xy 63.226918 -431.595576) (xy 63.212729 -431.615159) (xy 63.193189 -431.629409)
			(xy 63.170206 -431.636935) (xy 63.158116 -431.63744) (xy 62.218316 -431.63744) (xy 62.206212 -431.63697)
			(xy 62.183192 -431.62948) (xy 62.163622 -431.615231) (xy 62.149426 -431.595623) (xy 62.141997 -431.572583)
			(xy 62.141608 -431.560478) (xy 62.141608 -430.950116) (xy 62.139939 -430.935123) (xy 62.138161 -430.905004)
			(xy 62.138052 -430.889918) (xy 61.234828 -430.889918) (xy 61.234828 -431.889916) (xy 64.138048 -431.889916)
			(xy 64.138157 -431.87483) (xy 64.139939 -431.844712) (xy 64.141604 -431.829718) (xy 64.141604 -430.749964)
			(xy 64.139939 -430.73497) (xy 64.138158 -430.704852) (xy 64.138048 -430.689766) (xy 64.138162 -430.67468)
			(xy 64.13994 -430.644562) (xy 64.141604 -430.629568) (xy 64.141604 -430.018952) (xy 64.142023 -430.006874)
			(xy 64.149501 -429.983903) (xy 64.163708 -429.964366) (xy 64.183257 -429.950173) (xy 64.206233 -429.942714)
			(xy 64.218312 -429.942244) (xy 65.158112 -429.942244) (xy 65.170182 -429.942753) (xy 65.193142 -429.950213)
			(xy 65.212674 -429.9644) (xy 65.22687 -429.983926) (xy 65.234341 -430.006882) (xy 65.23482 -430.018952)
			(xy 65.23482 -430.889918) (xy 66.138044 -430.889918) (xy 66.138153 -430.874832) (xy 66.139935 -430.844714)
			(xy 66.1416 -430.82972) (xy 66.1416 -429.749966) (xy 66.139935 -429.734972) (xy 66.138154 -429.704854)
			(xy 66.138044 -429.689768) (xy 66.138158 -429.674682) (xy 66.139936 -429.644564) (xy 66.1416 -429.62957)
			(xy 66.1416 -429.018954) (xy 66.142067 -429.006866) (xy 66.149532 -428.983871) (xy 66.16372 -428.964295)
			(xy 66.18325 -428.950044) (xy 66.206222 -428.942507) (xy 66.218308 -428.941992) (xy 67.158108 -428.941992)
			(xy 67.170217 -428.942409) (xy 67.193243 -428.94991) (xy 67.212815 -428.964172) (xy 67.22701 -428.983792)
			(xy 67.234432 -429.006844) (xy 67.234816 -429.018954) (xy 67.234816 -431.560478) (xy 67.234373 -431.572571)
			(xy 67.226917 -431.595578) (xy 67.212726 -431.615162) (xy 67.193184 -431.629412) (xy 67.170199 -431.636937)
			(xy 67.158108 -431.63744) (xy 66.218308 -431.63744) (xy 66.206204 -431.636978) (xy 66.183183 -431.629485)
			(xy 66.163613 -431.615234) (xy 66.149417 -431.595625) (xy 66.141989 -431.572584) (xy 66.1416 -431.560478)
			(xy 66.1416 -430.950116) (xy 66.139931 -430.935123) (xy 66.138153 -430.905004) (xy 66.138044 -430.889918)
			(xy 65.23482 -430.889918) (xy 65.23482 -431.889916) (xy 68.13804 -431.889916) (xy 68.138151 -431.87483)
			(xy 68.139933 -431.844712) (xy 68.141596 -431.829718) (xy 68.141596 -430.749964) (xy 68.139931 -430.73497)
			(xy 68.13815 -430.704852) (xy 68.13804 -430.689766) (xy 68.138154 -430.67468) (xy 68.139932 -430.644562)
			(xy 68.141596 -430.629568) (xy 68.141596 -430.018952) (xy 68.142023 -430.006875) (xy 68.149499 -429.983905)
			(xy 68.163705 -429.964368) (xy 68.183252 -429.950176) (xy 68.206226 -429.942715) (xy 68.218304 -429.942244)
			(xy 69.158104 -429.942244) (xy 69.170174 -429.94276) (xy 69.193133 -429.950218) (xy 69.212666 -429.964403)
			(xy 69.226862 -429.983927) (xy 69.234333 -430.006882) (xy 69.234812 -430.018952) (xy 69.234812 -430.889918)
			(xy 70.138036 -430.889918) (xy 70.138147 -430.874832) (xy 70.139929 -430.844714) (xy 70.141592 -430.82972)
			(xy 70.141592 -429.749966) (xy 70.139927 -429.734972) (xy 70.138146 -429.704854) (xy 70.138036 -429.689768)
			(xy 70.138152 -429.674683) (xy 70.13993 -429.644564) (xy 70.141592 -429.62957) (xy 70.141592 -429.018954)
			(xy 70.142067 -429.006867) (xy 70.149531 -428.983873) (xy 70.163717 -428.964298) (xy 70.183245 -428.950047)
			(xy 70.206214 -428.942508) (xy 70.2183 -428.941992) (xy 71.1581 -428.941992) (xy 71.170208 -428.942416)
			(xy 71.193234 -428.949914) (xy 71.212807 -428.964174) (xy 71.227001 -428.983794) (xy 71.234424 -429.006845)
			(xy 71.234808 -429.018954) (xy 71.234808 -431.560478) (xy 71.234275 -431.572562) (xy 71.22683 -431.595553)
			(xy 71.212659 -431.61513) (xy 71.193142 -431.629383) (xy 71.170182 -431.636924) (xy 71.1581 -431.63744)
			(xy 70.2183 -431.63744) (xy 70.206195 -431.636984) (xy 70.183175 -431.62949) (xy 70.163605 -431.615237)
			(xy 70.149409 -431.595626) (xy 70.141981 -431.572584) (xy 70.141592 -431.560478) (xy 70.141592 -430.950116)
			(xy 70.139923 -430.935123) (xy 70.138145 -430.905004) (xy 70.138036 -430.889918) (xy 69.234812 -430.889918)
			(xy 69.234812 -431.889916) (xy 72.138032 -431.889916) (xy 72.138143 -431.87483) (xy 72.139925 -431.844712)
			(xy 72.141588 -431.829718) (xy 72.141588 -430.749964) (xy 72.139923 -430.73497) (xy 72.138142 -430.704852)
			(xy 72.138032 -430.689766) (xy 72.138148 -430.674681) (xy 72.139926 -430.644562) (xy 72.141588 -430.629568)
			(xy 72.141588 -430.018952) (xy 72.142023 -430.006875) (xy 72.149498 -429.983907) (xy 72.163703 -429.964371)
			(xy 72.183247 -429.950178) (xy 72.206219 -429.942716) (xy 72.218296 -429.942244) (xy 73.158096 -429.942244)
			(xy 73.170166 -429.942767) (xy 73.193124 -429.950222) (xy 73.212657 -429.964406) (xy 73.226854 -429.983929)
			(xy 73.234325 -430.006883) (xy 73.234804 -430.018952) (xy 73.234804 -430.889918) (xy 75.138026 -430.889918)
			(xy 75.13812 -430.875344) (xy 75.139772 -430.846243) (xy 75.141328 -430.831752) (xy 75.141328 -429.747934)
			(xy 75.13978 -429.733442) (xy 75.13813 -429.704342) (xy 75.138026 -429.689768) (xy 75.138125 -429.675194)
			(xy 75.139774 -429.646093) (xy 75.141328 -429.631602) (xy 75.141328 -429.018954) (xy 75.141772 -429.006838)
			(xy 75.149271 -428.983795) (xy 75.163521 -428.964195) (xy 75.183127 -428.949955) (xy 75.206174 -428.942467)
			(xy 75.21829 -428.941992) (xy 76.15809 -428.941992) (xy 76.170199 -428.94252) (xy 76.193235 -428.949999)
			(xy 76.212832 -428.964228) (xy 76.227076 -428.983815) (xy 76.234572 -429.006845) (xy 76.235052 -429.018954)
			(xy 76.235052 -431.560478) (xy 76.234621 -431.572601) (xy 76.227134 -431.59566) (xy 76.212885 -431.615277)
			(xy 76.193271 -431.629528) (xy 76.170213 -431.637019) (xy 76.15809 -431.63744) (xy 75.21829 -431.63744)
			(xy 75.206165 -431.637048) (xy 75.183102 -431.62955) (xy 75.163485 -431.615292) (xy 75.149235 -431.59567)
			(xy 75.141747 -431.572604) (xy 75.141328 -431.560478) (xy 75.141328 -430.948084) (xy 75.139785 -430.933592)
			(xy 75.138132 -430.904492) (xy 75.138026 -430.889918) (xy 73.234804 -430.889918) (xy 73.234804 -431.889916)
			(xy 77.138022 -431.889916) (xy 77.138116 -431.875342) (xy 77.139768 -431.846241) (xy 77.141324 -431.83175)
			(xy 77.141324 -430.747932) (xy 77.139776 -430.73344) (xy 77.138126 -430.70434) (xy 77.138022 -430.689766)
			(xy 77.138121 -430.675192) (xy 77.13977 -430.646091) (xy 77.141324 -430.6316) (xy 77.141324 -430.018952)
			(xy 77.141676 -430.006838) (xy 77.149191 -429.983805) (xy 77.163469 -429.964231) (xy 77.183105 -429.950039)
			(xy 77.20617 -429.942624) (xy 77.218286 -429.942244) (xy 78.158086 -429.942244) (xy 78.170175 -429.942719)
			(xy 78.193176 -429.950173) (xy 78.212757 -429.964357) (xy 78.227007 -429.983889) (xy 78.234539 -430.006864)
			(xy 78.235048 -430.018952) (xy 78.235048 -430.889918) (xy 79.138018 -430.889918) (xy 79.138112 -430.875344)
			(xy 79.139764 -430.846243) (xy 79.14132 -430.831752) (xy 79.14132 -429.747934) (xy 79.139772 -429.733442)
			(xy 79.138122 -429.704342) (xy 79.138018 -429.689768) (xy 79.138117 -429.675194) (xy 79.139766 -429.646093)
			(xy 79.14132 -429.631602) (xy 79.14132 -429.018954) (xy 79.141772 -429.006839) (xy 79.14927 -428.983797)
			(xy 79.163518 -428.964198) (xy 79.183122 -428.949957) (xy 79.206167 -428.942468) (xy 79.218282 -428.941992)
			(xy 80.158082 -428.941992) (xy 80.170191 -428.942526) (xy 80.193226 -428.950003) (xy 80.212824 -428.964231)
			(xy 80.227068 -428.983817) (xy 80.234563 -429.006845) (xy 80.235044 -429.018954) (xy 80.235044 -431.560478)
			(xy 80.234621 -431.572601) (xy 80.227133 -431.595663) (xy 80.212882 -431.61528) (xy 80.193266 -431.629531)
			(xy 80.170205 -431.63702) (xy 80.158082 -431.63744) (xy 79.218282 -431.63744) (xy 79.206156 -431.637055)
			(xy 79.183093 -431.629555) (xy 79.163476 -431.615295) (xy 79.149227 -431.595671) (xy 79.141739 -431.572604)
			(xy 79.14132 -431.560478) (xy 79.14132 -430.948084) (xy 79.139777 -430.933592) (xy 79.138124 -430.904492)
			(xy 79.138018 -430.889918) (xy 78.235048 -430.889918) (xy 78.235048 -431.889916) (xy 81.138014 -431.889916)
			(xy 81.138108 -431.875342) (xy 81.13976 -431.846241) (xy 81.141316 -431.83175) (xy 81.141316 -430.747932)
			(xy 81.139768 -430.73344) (xy 81.138118 -430.70434) (xy 81.138014 -430.689766) (xy 81.138112 -430.675192)
			(xy 81.139761 -430.646091) (xy 81.141316 -430.6316) (xy 81.141316 -430.018952) (xy 81.141676 -430.006839)
			(xy 81.14919 -429.983807) (xy 81.163466 -429.964234) (xy 81.1831 -429.950041) (xy 81.206163 -429.942625)
			(xy 81.218278 -429.942244) (xy 82.158078 -429.942244) (xy 82.170167 -429.942726) (xy 82.193167 -429.950177)
			(xy 82.212748 -429.96436) (xy 82.226999 -429.983891) (xy 82.234531 -430.006865) (xy 82.23504 -430.018952)
			(xy 82.23504 -430.889918) (xy 83.13801 -430.889918) (xy 83.138104 -430.875344) (xy 83.139756 -430.846243)
			(xy 83.141312 -430.831752) (xy 83.141312 -429.747934) (xy 83.139764 -429.733442) (xy 83.138114 -429.704342)
			(xy 83.13801 -429.689768) (xy 83.138108 -429.675194) (xy 83.139758 -429.646093) (xy 83.141312 -429.631602)
			(xy 83.141312 -429.018954) (xy 83.141772 -429.00684) (xy 83.149269 -428.983799) (xy 83.163515 -428.964201)
			(xy 83.183117 -428.94996) (xy 83.20616 -428.942469) (xy 83.218274 -428.941992) (xy 84.158074 -428.941992)
			(xy 84.170183 -428.942533) (xy 84.193217 -428.950008) (xy 84.212815 -428.964233) (xy 84.227059 -428.983818)
			(xy 84.234555 -429.006846) (xy 84.235036 -429.018954) (xy 84.235036 -431.560478) (xy 84.234621 -431.572602)
			(xy 84.227132 -431.595665) (xy 84.21288 -431.615282) (xy 84.193261 -431.629533) (xy 84.170198 -431.637022)
			(xy 84.158074 -431.63744) (xy 83.218274 -431.63744) (xy 83.206156 -431.63701) (xy 83.183108 -431.629513)
			(xy 83.163505 -431.615261) (xy 83.149265 -431.595649) (xy 83.141782 -431.572596) (xy 83.141312 -431.560478)
			(xy 83.141312 -430.948084) (xy 83.139769 -430.933592) (xy 83.138116 -430.904492) (xy 83.13801 -430.889918)
			(xy 82.23504 -430.889918) (xy 82.23504 -431.889916) (xy 85.138006 -431.889916) (xy 85.1381 -431.875342)
			(xy 85.139752 -431.846241) (xy 85.141308 -431.83175) (xy 85.141308 -430.747932) (xy 85.13976 -430.73344)
			(xy 85.13811 -430.70434) (xy 85.138006 -430.689766) (xy 85.138104 -430.675192) (xy 85.139753 -430.646091)
			(xy 85.141308 -430.6316) (xy 85.141308 -430.018952) (xy 85.141676 -430.00684) (xy 85.149189 -429.98381)
			(xy 85.163463 -429.964237) (xy 85.183095 -429.950044) (xy 85.206156 -429.942626) (xy 85.21827 -429.942244)
			(xy 86.15807 -429.942244) (xy 86.170158 -429.942733) (xy 86.193159 -429.950182) (xy 86.212739 -429.964363)
			(xy 86.226991 -429.983892) (xy 86.234523 -430.006865) (xy 86.235032 -430.018952) (xy 86.235032 -430.889918)
			(xy 87.138002 -430.889918) (xy 87.138096 -430.875344) (xy 87.139748 -430.846243) (xy 87.141304 -430.831752)
			(xy 87.141304 -429.747934) (xy 87.139756 -429.733442) (xy 87.138106 -429.704342) (xy 87.138002 -429.689768)
			(xy 87.1381 -429.675194) (xy 87.13975 -429.646093) (xy 87.141304 -429.631602) (xy 87.141304 -429.018954)
			(xy 87.141772 -429.00684) (xy 87.149268 -428.983801) (xy 87.163512 -428.964203) (xy 87.183112 -428.949962)
			(xy 87.206152 -428.94247) (xy 87.218266 -428.941992) (xy 88.158066 -428.941992) (xy 88.170174 -428.94254)
			(xy 88.193209 -428.950012) (xy 88.212807 -428.964236) (xy 88.227051 -428.98382) (xy 88.234547 -429.006846)
			(xy 88.235028 -429.018954) (xy 88.235028 -431.560478) (xy 88.234621 -431.572603) (xy 88.22713 -431.595667)
			(xy 88.212877 -431.615285) (xy 88.193256 -431.629536) (xy 88.170191 -431.637023) (xy 88.158066 -431.63744)
			(xy 87.218266 -431.63744) (xy 87.206147 -431.637017) (xy 87.183099 -431.629518) (xy 87.163496 -431.615264)
			(xy 87.149257 -431.59565) (xy 87.141774 -431.572597) (xy 87.141304 -431.560478) (xy 87.141304 -430.948084)
			(xy 87.13976 -430.933592) (xy 87.138108 -430.904492) (xy 87.138002 -430.889918) (xy 86.235032 -430.889918)
			(xy 86.235032 -431.889916) (xy 89.137998 -431.889916) (xy 89.138092 -431.875342) (xy 89.139744 -431.846241)
			(xy 89.1413 -431.83175) (xy 89.1413 -430.747932) (xy 89.139752 -430.73344) (xy 89.138102 -430.70434)
			(xy 89.137998 -430.689766) (xy 89.138096 -430.675192) (xy 89.139746 -430.646091) (xy 89.1413 -430.6316)
			(xy 89.1413 -430.018952) (xy 89.141676 -430.006841) (xy 89.149188 -429.983812) (xy 89.16346 -429.96424)
			(xy 89.18309 -429.950047) (xy 89.206149 -429.942627) (xy 89.218262 -429.942244) (xy 90.158062 -429.942244)
			(xy 90.17015 -429.94274) (xy 90.19315 -429.950187) (xy 90.212731 -429.964366) (xy 90.226983 -429.983894)
			(xy 90.234515 -430.006866) (xy 90.235024 -430.018952) (xy 90.235024 -432.560476) (xy 90.234563 -432.572581)
			(xy 90.227074 -432.595604) (xy 90.212823 -432.615175) (xy 90.193212 -432.629371) (xy 90.170168 -432.636797)
			(xy 90.158062 -432.637184) (xy 89.218262 -432.637184) (xy 89.206173 -432.636726) (xy 89.183175 -432.629261)
			(xy 89.163598 -432.615072) (xy 89.149348 -432.595538) (xy 89.141812 -432.572564) (xy 89.1413 -432.560476)
			(xy 89.1413 -431.948082) (xy 89.139756 -431.93359) (xy 89.138104 -431.90449) (xy 89.137998 -431.889916)
			(xy 86.235032 -431.889916) (xy 86.235032 -432.560476) (xy 86.234563 -432.57258) (xy 86.227075 -432.595601)
			(xy 86.212825 -432.615172) (xy 86.193217 -432.629369) (xy 86.170175 -432.636796) (xy 86.15807 -432.637184)
			(xy 85.21827 -432.637184) (xy 85.206181 -432.636719) (xy 85.183184 -432.629257) (xy 85.163606 -432.615069)
			(xy 85.149356 -432.595537) (xy 85.14182 -432.572563) (xy 85.141308 -432.560476) (xy 85.141308 -431.948082)
			(xy 85.139764 -431.93359) (xy 85.138112 -431.90449) (xy 85.138006 -431.889916) (xy 82.23504 -431.889916)
			(xy 82.23504 -432.560476) (xy 82.234564 -432.57258) (xy 82.227076 -432.595599) (xy 82.212828 -432.615169)
			(xy 82.193222 -432.629366) (xy 82.170183 -432.636795) (xy 82.158078 -432.637184) (xy 81.218278 -432.637184)
			(xy 81.20619 -432.636712) (xy 81.183192 -432.629252) (xy 81.163615 -432.615066) (xy 81.149364 -432.595535)
			(xy 81.141828 -432.572563) (xy 81.141316 -432.560476) (xy 81.141316 -431.948082) (xy 81.139772 -431.93359)
			(xy 81.13812 -431.90449) (xy 81.138014 -431.889916) (xy 78.235048 -431.889916) (xy 78.235048 -432.560476)
			(xy 78.234564 -432.572579) (xy 78.227077 -432.595597) (xy 78.212831 -432.615166) (xy 78.193227 -432.629364)
			(xy 78.17019 -432.636793) (xy 78.158086 -432.637184) (xy 77.218286 -432.637184) (xy 77.206198 -432.636705)
			(xy 77.183201 -432.629248) (xy 77.163623 -432.615063) (xy 77.149372 -432.595534) (xy 77.141836 -432.572562)
			(xy 77.141324 -432.560476) (xy 77.141324 -431.948082) (xy 77.13978 -431.93359) (xy 77.138128 -431.90449)
			(xy 77.138022 -431.889916) (xy 73.234804 -431.889916) (xy 73.234804 -432.560476) (xy 73.234367 -432.572558)
			(xy 73.226905 -432.59554) (xy 73.212706 -432.615091) (xy 73.193158 -432.629296) (xy 73.170178 -432.636764)
			(xy 73.158096 -432.637184) (xy 72.218296 -432.637184) (xy 72.206211 -432.636791) (xy 72.183224 -432.629319)
			(xy 72.163671 -432.615109) (xy 72.149468 -432.595551) (xy 72.142005 -432.572562) (xy 72.141588 -432.560476)
			(xy 72.141588 -431.950114) (xy 72.139918 -431.935121) (xy 72.138141 -431.905002) (xy 72.138032 -431.889916)
			(xy 69.234812 -431.889916) (xy 69.234812 -432.560476) (xy 69.234367 -432.572557) (xy 69.226906 -432.595538)
			(xy 69.212709 -432.615089) (xy 69.193163 -432.629294) (xy 69.170185 -432.636762) (xy 69.158104 -432.637184)
			(xy 68.218304 -432.637184) (xy 68.206219 -432.636784) (xy 68.183232 -432.629314) (xy 68.16368 -432.615106)
			(xy 68.149476 -432.59555) (xy 68.142013 -432.572561) (xy 68.141596 -432.560476) (xy 68.141596 -431.950114)
			(xy 68.139926 -431.935121) (xy 68.138149 -431.905002) (xy 68.13804 -431.889916) (xy 65.23482 -431.889916)
			(xy 65.23482 -432.560476) (xy 65.234367 -432.572556) (xy 65.226907 -432.595536) (xy 65.212711 -432.615086)
			(xy 65.193168 -432.629291) (xy 65.170192 -432.636761) (xy 65.158112 -432.637184) (xy 64.218312 -432.637184)
			(xy 64.206228 -432.636777) (xy 64.183241 -432.629309) (xy 64.163689 -432.615103) (xy 64.149485 -432.595548)
			(xy 64.142022 -432.572561) (xy 64.141604 -432.560476) (xy 64.141604 -431.950114) (xy 64.139934 -431.935121)
			(xy 64.138157 -431.905002) (xy 64.138048 -431.889916) (xy 61.234828 -431.889916) (xy 61.234828 -432.560476)
			(xy 61.234367 -432.572555) (xy 61.226909 -432.595534) (xy 61.212714 -432.615083) (xy 61.193173 -432.629288)
			(xy 61.170199 -432.63676) (xy 61.15812 -432.637184) (xy 60.21832 -432.637184) (xy 60.206236 -432.63677)
			(xy 60.18325 -432.629305) (xy 60.163697 -432.6151) (xy 60.149493 -432.595547) (xy 60.14203 -432.57256)
			(xy 60.141612 -432.560476) (xy 60.141612 -431.950114) (xy 60.139942 -431.935121) (xy 60.138165 -431.905002)
			(xy 60.138056 -431.889916) (xy 16.743762 -431.889916) (xy 16.800144 -431.946298) (xy 16.940662 -432.09831)
			(xy 17.075103 -432.25572) (xy 17.20326 -432.418287) (xy 17.324937 -432.585761) (xy 17.439944 -432.757882)
			(xy 17.548106 -432.934386) (xy 17.649254 -433.115) (xy 17.743234 -433.299446) (xy 17.8299 -433.48744)
			(xy 17.909119 -433.678691) (xy 17.980768 -433.872904) (xy 18.044737 -434.069781) (xy 18.100927 -434.269017)
			(xy 18.149252 -434.470306) (xy 18.153141 -434.48986) (xy 58.13806 -434.48986) (xy 58.138173 -434.474774)
			(xy 58.139952 -434.444656) (xy 58.141616 -434.429662) (xy 58.141616 -433.350162) (xy 58.139951 -433.335168)
			(xy 58.13817 -433.30505) (xy 58.13806 -433.289964) (xy 58.138173 -433.274878) (xy 58.139952 -433.24476)
			(xy 58.141616 -433.229766) (xy 58.141616 -432.618896) (xy 58.142009 -432.606811) (xy 58.149481 -432.583824)
			(xy 58.163691 -432.564271) (xy 58.183249 -432.550068) (xy 58.206238 -432.542605) (xy 58.218324 -432.542188)
			(xy 59.158124 -432.542188) (xy 59.170199 -432.542644) (xy 59.193167 -432.550113) (xy 59.212703 -432.564311)
			(xy 59.226897 -432.583851) (xy 59.234359 -432.606821) (xy 59.234832 -432.618896) (xy 59.234832 -435.16042)
			(xy 59.234353 -435.172493) (xy 59.226888 -435.195457) (xy 59.212694 -435.214991) (xy 59.19316 -435.229186)
			(xy 59.170197 -435.236652) (xy 59.158124 -435.237128) (xy 58.218324 -435.237128) (xy 58.206245 -435.236667)
			(xy 58.183266 -435.229209) (xy 58.163717 -435.215014) (xy 58.149512 -435.195473) (xy 58.14204 -435.172499)
			(xy 58.141616 -435.16042) (xy 58.141616 -434.550058) (xy 58.13995 -434.535064) (xy 58.13817 -434.504946)
			(xy 58.13806 -434.48986) (xy 18.153141 -434.48986) (xy 18.189637 -434.673337) (xy 18.22202 -434.877797)
			(xy 18.246351 -435.083371) (xy 18.262593 -435.289741) (xy 18.270456 -435.489858) (xy 60.138056 -435.489858)
			(xy 60.138169 -435.474772) (xy 60.139948 -435.444654) (xy 60.141612 -435.42966) (xy 60.141612 -434.35016)
			(xy 60.139947 -434.335166) (xy 60.138166 -434.305048) (xy 60.138056 -434.289962) (xy 60.138169 -434.274876)
			(xy 60.139948 -434.244758) (xy 60.141612 -434.229764) (xy 60.141612 -433.618894) (xy 60.142102 -433.606807)
			(xy 60.149557 -433.583811) (xy 60.163739 -433.564234) (xy 60.183265 -433.549982) (xy 60.206235 -433.542445)
			(xy 60.21832 -433.541932) (xy 61.15812 -433.541932) (xy 61.170233 -433.5423) (xy 61.193267 -433.549808)
			(xy 61.212842 -433.564081) (xy 61.227035 -433.583715) (xy 61.234449 -433.606779) (xy 61.234828 -433.618894)
			(xy 61.234828 -434.48986) (xy 62.138052 -434.48986) (xy 62.138165 -434.474774) (xy 62.139944 -434.444656)
			(xy 62.141608 -434.429662) (xy 62.141608 -433.350162) (xy 62.139943 -433.335168) (xy 62.138162 -433.30505)
			(xy 62.138052 -433.289964) (xy 62.138165 -433.274878) (xy 62.139944 -433.24476) (xy 62.141608 -433.229766)
			(xy 62.141608 -432.618896) (xy 62.142009 -432.606811) (xy 62.14948 -432.583826) (xy 62.163688 -432.564274)
			(xy 62.183244 -432.550071) (xy 62.206231 -432.542606) (xy 62.218316 -432.542188) (xy 63.158116 -432.542188)
			(xy 63.170191 -432.542651) (xy 63.193158 -432.550117) (xy 63.212694 -432.564314) (xy 63.226888 -432.583853)
			(xy 63.234351 -432.606821) (xy 63.234824 -432.618896) (xy 63.234824 -435.16042) (xy 63.234353 -435.172494)
			(xy 63.226887 -435.195459) (xy 63.212691 -435.214994) (xy 63.193155 -435.229189) (xy 63.17019 -435.236654)
			(xy 63.158116 -435.237128) (xy 62.218316 -435.237128) (xy 62.206244 -435.236622) (xy 62.183281 -435.229167)
			(xy 62.163745 -435.21498) (xy 62.14955 -435.195451) (xy 62.142083 -435.172492) (xy 62.141608 -435.16042)
			(xy 62.141608 -434.550058) (xy 62.139942 -434.535064) (xy 62.138162 -434.504946) (xy 62.138052 -434.48986)
			(xy 61.234828 -434.48986) (xy 61.234828 -435.489858) (xy 64.138048 -435.489858) (xy 64.138161 -435.474772)
			(xy 64.13994 -435.444654) (xy 64.141604 -435.42966) (xy 64.141604 -434.35016) (xy 64.139938 -434.335166)
			(xy 64.138158 -434.305048) (xy 64.138048 -434.289962) (xy 64.138161 -434.274876) (xy 64.13994 -434.244758)
			(xy 64.141604 -434.229764) (xy 64.141604 -433.618894) (xy 64.142102 -433.606808) (xy 64.149556 -433.583813)
			(xy 64.163736 -433.564236) (xy 64.18326 -433.549985) (xy 64.206228 -433.542447) (xy 64.218312 -433.541932)
			(xy 65.158112 -433.541932) (xy 65.170225 -433.542306) (xy 65.193258 -433.549813) (xy 65.212834 -433.564084)
			(xy 65.227027 -433.583717) (xy 65.234441 -433.60678) (xy 65.23482 -433.618894) (xy 65.23482 -434.48986)
			(xy 66.138044 -434.48986) (xy 66.138157 -434.474774) (xy 66.139936 -434.444656) (xy 66.1416 -434.429662)
			(xy 66.1416 -433.350162) (xy 66.139935 -433.335168) (xy 66.138154 -433.30505) (xy 66.138044 -433.289964)
			(xy 66.138157 -433.274878) (xy 66.139936 -433.24476) (xy 66.1416 -433.229766) (xy 66.1416 -432.618896)
			(xy 66.142009 -432.606812) (xy 66.149479 -432.583828) (xy 66.163686 -432.564277) (xy 66.183239 -432.550073)
			(xy 66.206224 -432.542607) (xy 66.218308 -432.542188) (xy 67.158108 -432.542188) (xy 67.170183 -432.542657)
			(xy 67.193149 -432.550122) (xy 67.212686 -432.564317) (xy 67.22688 -432.583854) (xy 67.234343 -432.606821)
			(xy 67.234816 -432.618896) (xy 67.234816 -435.16042) (xy 67.234353 -435.172495) (xy 67.226886 -435.195461)
			(xy 67.212689 -435.214997) (xy 67.19315 -435.229191) (xy 67.170183 -435.236655) (xy 67.158108 -435.237128)
			(xy 66.218308 -435.237128) (xy 66.206236 -435.236629) (xy 66.183272 -435.229171) (xy 66.163737 -435.214983)
			(xy 66.149541 -435.195453) (xy 66.142075 -435.172492) (xy 66.1416 -435.16042) (xy 66.1416 -434.550058)
			(xy 66.139934 -434.535064) (xy 66.138154 -434.504946) (xy 66.138044 -434.48986) (xy 65.23482 -434.48986)
			(xy 65.23482 -435.489858) (xy 68.13804 -435.489858) (xy 68.138153 -435.474772) (xy 68.139932 -435.444654)
			(xy 68.141596 -435.42966) (xy 68.141596 -434.35016) (xy 68.13993 -434.335166) (xy 68.13815 -434.305048)
			(xy 68.13804 -434.289962) (xy 68.138153 -434.274876) (xy 68.139932 -434.244758) (xy 68.141596 -434.229764)
			(xy 68.141596 -433.618894) (xy 68.142102 -433.606809) (xy 68.149555 -433.583815) (xy 68.163733 -433.564239)
			(xy 68.183255 -433.549987) (xy 68.20622 -433.542448) (xy 68.218304 -433.541932) (xy 69.158104 -433.541932)
			(xy 69.170216 -433.542313) (xy 69.193249 -433.549818) (xy 69.212825 -433.564087) (xy 69.227018 -433.583718)
			(xy 69.234433 -433.60678) (xy 69.234812 -433.618894) (xy 69.234812 -434.48986) (xy 70.138036 -434.48986)
			(xy 70.138151 -434.474775) (xy 70.13993 -434.444656) (xy 70.141592 -434.429662) (xy 70.141592 -433.350162)
			(xy 70.139927 -433.335168) (xy 70.138146 -433.30505) (xy 70.138036 -433.289964) (xy 70.138152 -433.274879)
			(xy 70.13993 -433.24476) (xy 70.141592 -433.229766) (xy 70.141592 -432.618896) (xy 70.142061 -432.606821)
			(xy 70.149524 -432.583854) (xy 70.16372 -432.564317) (xy 70.183258 -432.550123) (xy 70.206225 -432.54266)
			(xy 70.2183 -432.542188) (xy 71.1581 -432.542188) (xy 71.170174 -432.542664) (xy 71.193141 -432.550126)
			(xy 71.212677 -432.56432) (xy 71.226872 -432.583856) (xy 71.234335 -432.606822) (xy 71.234808 -432.618896)
			(xy 71.234808 -435.16042) (xy 71.234353 -435.172496) (xy 71.226885 -435.195463) (xy 71.212686 -435.215)
			(xy 71.193145 -435.229194) (xy 71.170176 -435.236656) (xy 71.1581 -435.237128) (xy 70.2183 -435.237128)
			(xy 70.206227 -435.236636) (xy 70.183264 -435.229176) (xy 70.163728 -435.214986) (xy 70.149533 -435.195454)
			(xy 70.142067 -435.172492) (xy 70.141592 -435.16042) (xy 70.141592 -434.550058) (xy 70.139926 -434.535064)
			(xy 70.138146 -434.504946) (xy 70.138036 -434.48986) (xy 69.234812 -434.48986) (xy 69.234812 -435.489858)
			(xy 72.138032 -435.489858) (xy 72.138147 -435.474773) (xy 72.139926 -435.444654) (xy 72.141588 -435.42966)
			(xy 72.141588 -434.35016) (xy 72.139922 -434.335166) (xy 72.138142 -434.305048) (xy 72.138032 -434.289962)
			(xy 72.138147 -434.274877) (xy 72.139926 -434.244758) (xy 72.141588 -434.229764) (xy 72.141588 -433.618894)
			(xy 72.142003 -433.606799) (xy 72.149468 -433.583791) (xy 72.163666 -433.564207) (xy 72.183213 -433.549958)
			(xy 72.206203 -433.542435) (xy 72.218296 -433.541932) (xy 73.158096 -433.541932) (xy 73.170208 -433.54232)
			(xy 73.193241 -433.549822) (xy 73.212817 -433.56409) (xy 73.22701 -433.58372) (xy 73.234425 -433.606781)
			(xy 73.234804 -433.618894) (xy 73.234804 -434.48986) (xy 75.138026 -434.48986) (xy 75.138124 -434.475286)
			(xy 75.139774 -434.446185) (xy 75.141328 -434.431694) (xy 75.141328 -433.34813) (xy 75.13978 -433.333638)
			(xy 75.13813 -433.304538) (xy 75.138026 -433.289964) (xy 75.138124 -433.27539) (xy 75.139774 -433.246289)
			(xy 75.141328 -433.231798) (xy 75.141328 -432.618896) (xy 75.141713 -432.606784) (xy 75.149217 -432.583752)
			(xy 75.163486 -432.564176) (xy 75.183116 -432.549983) (xy 75.206177 -432.542567) (xy 75.21829 -432.542188)
			(xy 76.15809 -432.542188) (xy 76.170184 -432.542617) (xy 76.193192 -432.550077) (xy 76.212776 -432.564271)
			(xy 76.227025 -432.583816) (xy 76.234549 -432.606804) (xy 76.235052 -432.618896) (xy 76.235052 -435.16042)
			(xy 76.234601 -435.172525) (xy 76.227103 -435.195544) (xy 76.212848 -435.215112) (xy 76.193237 -435.229308)
			(xy 76.170196 -435.236737) (xy 76.15809 -435.237128) (xy 75.21829 -435.237128) (xy 75.206197 -435.2367)
			(xy 75.183191 -435.229237) (xy 75.163608 -435.215041) (xy 75.149359 -435.195498) (xy 75.141833 -435.172512)
			(xy 75.141328 -435.16042) (xy 75.141328 -434.548026) (xy 75.13978 -434.533534) (xy 75.13813 -434.504434)
			(xy 75.138026 -434.48986) (xy 73.234804 -434.48986) (xy 73.234804 -435.489858) (xy 77.138022 -435.489858)
			(xy 77.13812 -435.475284) (xy 77.13977 -435.446183) (xy 77.141324 -435.431692) (xy 77.141324 -434.348128)
			(xy 77.139776 -434.333636) (xy 77.138126 -434.304536) (xy 77.138022 -434.289962) (xy 77.13812 -434.275388)
			(xy 77.13977 -434.246287) (xy 77.141324 -434.231796) (xy 77.141324 -433.618894) (xy 77.141807 -433.606781)
			(xy 77.149294 -433.58374) (xy 77.163534 -433.564139) (xy 77.183132 -433.549897) (xy 77.206173 -433.542408)
			(xy 77.218286 -433.541932) (xy 78.158086 -433.541932) (xy 78.170207 -433.542372) (xy 78.193265 -433.54986)
			(xy 78.21288 -433.564106) (xy 78.227131 -433.583717) (xy 78.234625 -433.606773) (xy 78.235048 -433.618894)
			(xy 78.235048 -434.48986) (xy 79.138018 -434.48986) (xy 79.138116 -434.475286) (xy 79.139766 -434.446185)
			(xy 79.14132 -434.431694) (xy 79.14132 -433.34813) (xy 79.139772 -433.333638) (xy 79.138122 -433.304538)
			(xy 79.138018 -433.289964) (xy 79.138116 -433.27539) (xy 79.139766 -433.246289) (xy 79.14132 -433.231798)
			(xy 79.14132 -432.618896) (xy 79.141713 -432.606785) (xy 79.149216 -432.583754) (xy 79.163483 -432.564179)
			(xy 79.183111 -432.549985) (xy 79.206169 -432.542568) (xy 79.218282 -432.542188) (xy 80.158082 -432.542188)
			(xy 80.170175 -432.542624) (xy 80.193183 -432.550081) (xy 80.212768 -432.564274) (xy 80.227017 -432.583818)
			(xy 80.234541 -432.606804) (xy 80.235044 -432.618896) (xy 80.235044 -435.16042) (xy 80.234601 -435.172526)
			(xy 80.227102 -435.195546) (xy 80.212845 -435.215115) (xy 80.193232 -435.22931) (xy 80.170189 -435.236739)
			(xy 80.158082 -435.237128) (xy 79.218282 -435.237128) (xy 79.206188 -435.236708) (xy 79.183182 -435.229242)
			(xy 79.163599 -435.215045) (xy 79.14935 -435.195499) (xy 79.141824 -435.172512) (xy 79.14132 -435.16042)
			(xy 79.14132 -434.548026) (xy 79.139772 -434.533534) (xy 79.138122 -434.504434) (xy 79.138018 -434.48986)
			(xy 78.235048 -434.48986) (xy 78.235048 -435.489858) (xy 81.138014 -435.489858) (xy 81.138111 -435.475284)
			(xy 81.139761 -435.446183) (xy 81.141316 -435.431692) (xy 81.141316 -434.348128) (xy 81.139768 -434.333636)
			(xy 81.138118 -434.304536) (xy 81.138014 -434.289962) (xy 81.138112 -434.275388) (xy 81.139761 -434.246287)
			(xy 81.141316 -434.231796) (xy 81.141316 -433.618894) (xy 81.141807 -433.606781) (xy 81.149293 -433.583742)
			(xy 81.163531 -433.564142) (xy 81.183127 -433.5499) (xy 81.206165 -433.542409) (xy 81.218278 -433.541932)
			(xy 82.158078 -433.541932) (xy 82.170199 -433.542379) (xy 82.193256 -433.549864) (xy 82.212871 -433.564109)
			(xy 82.227123 -433.583719) (xy 82.234617 -433.606773) (xy 82.23504 -433.618894) (xy 82.23504 -434.48986)
			(xy 83.13801 -434.48986) (xy 83.138107 -434.475286) (xy 83.139757 -434.446185) (xy 83.141312 -434.431694)
			(xy 83.141312 -433.34813) (xy 83.139764 -433.333638) (xy 83.138114 -433.304538) (xy 83.13801 -433.289964)
			(xy 83.138108 -433.27539) (xy 83.139757 -433.246289) (xy 83.141312 -433.231798) (xy 83.141312 -432.618896)
			(xy 83.141713 -432.606786) (xy 83.149215 -432.583756) (xy 83.16348 -432.564182) (xy 83.183106 -432.549988)
			(xy 83.206162 -432.542569) (xy 83.218274 -432.542188) (xy 84.158074 -432.542188) (xy 84.170167 -432.54263)
			(xy 84.193175 -432.550086) (xy 84.212759 -432.564277) (xy 84.227009 -432.583819) (xy 84.234533 -432.606804)
			(xy 84.235036 -432.618896) (xy 84.235036 -435.16042) (xy 84.234601 -435.172526) (xy 84.227101 -435.195548)
			(xy 84.212843 -435.215118) (xy 84.193227 -435.229313) (xy 84.170182 -435.23674) (xy 84.158074 -435.237128)
			(xy 83.218274 -435.237128) (xy 83.20618 -435.236714) (xy 83.183173 -435.229247) (xy 83.163591 -435.215047)
			(xy 83.149342 -435.195501) (xy 83.141816 -435.172513) (xy 83.141312 -435.16042) (xy 83.141312 -434.548026)
			(xy 83.139764 -434.533534) (xy 83.138114 -434.504434) (xy 83.13801 -434.48986) (xy 82.23504 -434.48986)
			(xy 82.23504 -435.489858) (xy 85.138006 -435.489858) (xy 85.138103 -435.475284) (xy 85.139753 -435.446183)
			(xy 85.141308 -435.431692) (xy 85.141308 -434.348128) (xy 85.13976 -434.333636) (xy 85.13811 -434.304536)
			(xy 85.138006 -434.289962) (xy 85.138104 -434.275388) (xy 85.139753 -434.246287) (xy 85.141308 -434.231796)
			(xy 85.141308 -433.618894) (xy 85.141806 -433.606782) (xy 85.149292 -433.583744) (xy 85.163528 -433.564145)
			(xy 85.183122 -433.549903) (xy 85.206158 -433.54241) (xy 85.21827 -433.541932) (xy 86.15807 -433.541932)
			(xy 86.170191 -433.542385) (xy 86.193247 -433.549869) (xy 86.212863 -433.564112) (xy 86.227115 -433.58372)
			(xy 86.234609 -433.606774) (xy 86.235032 -433.618894) (xy 86.235032 -434.48986) (xy 87.138002 -434.48986)
			(xy 87.1381 -434.475286) (xy 87.139749 -434.446185) (xy 87.141304 -434.431694) (xy 87.141304 -433.34813)
			(xy 87.139756 -433.333638) (xy 87.138106 -433.304538) (xy 87.138002 -433.289964) (xy 87.1381 -433.27539)
			(xy 87.139749 -433.246289) (xy 87.141304 -433.231798) (xy 87.141304 -432.618896) (xy 87.141713 -432.606787)
			(xy 87.149214 -432.583758) (xy 87.163477 -432.564185) (xy 87.183101 -432.549991) (xy 87.206155 -432.542571)
			(xy 87.218266 -432.542188) (xy 88.158066 -432.542188) (xy 88.170159 -432.542637) (xy 88.193166 -432.55009)
			(xy 88.212751 -432.56428) (xy 88.227001 -432.583821) (xy 88.234525 -432.606805) (xy 88.235028 -432.618896)
			(xy 88.235028 -435.16042) (xy 88.234601 -435.172527) (xy 88.2271 -435.19555) (xy 88.21284 -435.215121)
			(xy 88.193222 -435.229316) (xy 88.170174 -435.236741) (xy 88.158066 -435.237128) (xy 87.218266 -435.237128)
			(xy 87.206171 -435.236721) (xy 87.183164 -435.229251) (xy 87.163582 -435.21505) (xy 87.149334 -435.195502)
			(xy 87.141808 -435.172513) (xy 87.141304 -435.16042) (xy 87.141304 -434.548026) (xy 87.139756 -434.533534)
			(xy 87.138106 -434.504434) (xy 87.138002 -434.48986) (xy 86.235032 -434.48986) (xy 86.235032 -435.489858)
			(xy 89.137998 -435.489858) (xy 89.138095 -435.475284) (xy 89.139745 -435.446183) (xy 89.1413 -435.431692)
			(xy 89.1413 -434.348128) (xy 89.139752 -434.333636) (xy 89.138102 -434.304536) (xy 89.137998 -434.289962)
			(xy 89.138096 -434.275388) (xy 89.139745 -434.246287) (xy 89.1413 -434.231796) (xy 89.1413 -433.618894)
			(xy 89.141806 -433.606783) (xy 89.14929 -433.583746) (xy 89.163525 -433.564148) (xy 89.183117 -433.549905)
			(xy 89.206151 -433.542411) (xy 89.218262 -433.541932) (xy 90.158062 -433.541932) (xy 90.170182 -433.542392)
			(xy 90.193239 -433.549873) (xy 90.212854 -433.564115) (xy 90.227107 -433.583722) (xy 90.234601 -433.606774)
			(xy 90.235024 -433.618894) (xy 90.235024 -436.160418) (xy 90.234655 -436.172545) (xy 90.227153 -436.195611)
			(xy 90.212889 -436.215229) (xy 90.193261 -436.229478) (xy 90.17019 -436.236963) (xy 90.158062 -436.23738)
			(xy 89.218262 -436.23738) (xy 89.206147 -436.236921) (xy 89.183106 -436.229425) (xy 89.163506 -436.21518)
			(xy 89.149265 -436.195576) (xy 89.141776 -436.172533) (xy 89.1413 -436.160418) (xy 89.1413 -435.548024)
			(xy 89.139751 -435.533532) (xy 89.138102 -435.504432) (xy 89.137998 -435.489858) (xy 86.235032 -435.489858)
			(xy 86.235032 -436.160418) (xy 86.234655 -436.172545) (xy 86.227154 -436.195609) (xy 86.212892 -436.215226)
			(xy 86.193266 -436.229476) (xy 86.170197 -436.236962) (xy 86.15807 -436.23738) (xy 85.21827 -436.23738)
			(xy 85.206156 -436.236914) (xy 85.183114 -436.229421) (xy 85.163515 -436.215177) (xy 85.149274 -436.195575)
			(xy 85.141784 -436.172532) (xy 85.141308 -436.160418) (xy 85.141308 -435.548024) (xy 85.139759 -435.533532)
			(xy 85.13811 -435.504432) (xy 85.138006 -435.489858) (xy 82.23504 -435.489858) (xy 82.23504 -436.160418)
			(xy 82.234655 -436.172544) (xy 82.227155 -436.195607) (xy 82.212895 -436.215224) (xy 82.193271 -436.229473)
			(xy 82.170204 -436.236961) (xy 82.158078 -436.23738) (xy 81.218278 -436.23738) (xy 81.206164 -436.236907)
			(xy 81.183123 -436.229416) (xy 81.163523 -436.215174) (xy 81.149282 -436.195573) (xy 81.141792 -436.172532)
			(xy 81.141316 -436.160418) (xy 81.141316 -435.548024) (xy 81.139767 -435.533532) (xy 81.138118 -435.504432)
			(xy 81.138014 -435.489858) (xy 78.235048 -435.489858) (xy 78.235048 -436.160418) (xy 78.234604 -436.172535)
			(xy 78.22711 -436.195581) (xy 78.212861 -436.215184) (xy 78.193252 -436.229424) (xy 78.170203 -436.236909)
			(xy 78.158086 -436.23738) (xy 77.218286 -436.23738) (xy 77.206172 -436.236901) (xy 77.183132 -436.229412)
			(xy 77.163532 -436.215171) (xy 77.14929 -436.195572) (xy 77.1418 -436.172531) (xy 77.141324 -436.160418)
			(xy 77.141324 -435.548024) (xy 77.139775 -435.533532) (xy 77.138126 -435.504432) (xy 77.138022 -435.489858)
			(xy 73.234804 -435.489858) (xy 73.234804 -436.160418) (xy 73.234309 -436.172504) (xy 73.226853 -436.195498)
			(xy 73.212672 -436.215074) (xy 73.193147 -436.229325) (xy 73.17018 -436.236865) (xy 73.158096 -436.23738)
			(xy 72.218296 -436.23738) (xy 72.206185 -436.236987) (xy 72.183154 -436.229484) (xy 72.163579 -436.215217)
			(xy 72.149385 -436.195589) (xy 72.141968 -436.172531) (xy 72.141588 -436.160418) (xy 72.141588 -435.550056)
			(xy 72.139922 -435.535062) (xy 72.138142 -435.504944) (xy 72.138032 -435.489858) (xy 69.234812 -435.489858)
			(xy 69.234812 -436.160418) (xy 69.234407 -436.172513) (xy 69.22694 -436.195523) (xy 69.212739 -436.215106)
			(xy 69.193189 -436.229355) (xy 69.170198 -436.236878) (xy 69.158104 -436.23738) (xy 68.218304 -436.23738)
			(xy 68.206193 -436.23698) (xy 68.183163 -436.229479) (xy 68.163588 -436.215214) (xy 68.149394 -436.195588)
			(xy 68.141976 -436.17253) (xy 68.141596 -436.160418) (xy 68.141596 -435.550056) (xy 68.13993 -435.535062)
			(xy 68.13815 -435.504944) (xy 68.13804 -435.489858) (xy 65.23482 -435.489858) (xy 65.23482 -436.160418)
			(xy 65.234407 -436.172513) (xy 65.226941 -436.195521) (xy 65.212742 -436.215104) (xy 65.193194 -436.229352)
			(xy 65.170205 -436.236877) (xy 65.158112 -436.23738) (xy 64.218312 -436.23738) (xy 64.206202 -436.236973)
			(xy 64.183172 -436.229474) (xy 64.163597 -436.215211) (xy 64.149402 -436.195586) (xy 64.141985 -436.17253)
			(xy 64.141604 -436.160418) (xy 64.141604 -435.550056) (xy 64.139938 -435.535062) (xy 64.138158 -435.504944)
			(xy 64.138048 -435.489858) (xy 61.234828 -435.489858) (xy 61.234828 -436.160418) (xy 61.234408 -436.172512)
			(xy 61.226942 -436.195518) (xy 61.212745 -436.215101) (xy 61.193199 -436.22935) (xy 61.170212 -436.236876)
			(xy 61.15812 -436.23738) (xy 60.21832 -436.23738) (xy 60.20621 -436.236966) (xy 60.18318 -436.22947)
			(xy 60.163605 -436.215208) (xy 60.149411 -436.195585) (xy 60.141993 -436.172529) (xy 60.141612 -436.160418)
			(xy 60.141612 -435.550056) (xy 60.139946 -435.535062) (xy 60.138166 -435.504944) (xy 60.138056 -435.489858)
			(xy 18.270456 -435.489858) (xy 18.27072 -435.49659) (xy 18.271236 -435.600094) (xy 18.27074 -435.702721)
			(xy 18.26275 -435.907821) (xy 18.246783 -436.112454) (xy 18.222861 -436.31631) (xy 18.191021 -436.51908)
			(xy 18.151311 -436.720457) (xy 18.103792 -436.920135) (xy 18.048535 -437.117813) (xy 17.985625 -437.313189)
			(xy 17.915156 -437.505968) (xy 17.837236 -437.695857) (xy 17.751983 -437.882569) (xy 17.659525 -438.065821)
			(xy 17.64623 -438.089802) (xy 58.13806 -438.089802) (xy 58.138177 -438.074717) (xy 58.139953 -438.044598)
			(xy 58.141616 -438.029604) (xy 58.141616 -436.950104) (xy 58.139946 -436.935111) (xy 58.138168 -436.904992)
			(xy 58.13806 -436.889906) (xy 58.138168 -436.87482) (xy 58.13995 -436.844702) (xy 58.141616 -436.829708)
			(xy 58.141616 -436.219092) (xy 58.142006 -436.207006) (xy 58.149479 -436.184019) (xy 58.16369 -436.164467)
			(xy 58.183248 -436.150264) (xy 58.206238 -436.142801) (xy 58.218324 -436.142384) (xy 59.158124 -436.142384)
			(xy 59.170199 -436.142844) (xy 59.193166 -436.150312) (xy 59.212701 -436.16451) (xy 59.226895 -436.184049)
			(xy 59.234359 -436.207017) (xy 59.234832 -436.219092) (xy 59.234832 -438.760616) (xy 59.23435 -438.772689)
			(xy 59.226886 -438.795653) (xy 59.212693 -438.815187) (xy 59.19316 -438.829382) (xy 59.170197 -438.836848)
			(xy 59.158124 -438.837324) (xy 58.218324 -438.837324) (xy 58.206244 -438.836867) (xy 58.183265 -438.829408)
			(xy 58.163716 -438.815213) (xy 58.14951 -438.795671) (xy 58.142039 -438.772696) (xy 58.141616 -438.760616)
			(xy 58.141616 -438.15) (xy 58.139945 -438.135007) (xy 58.138168 -438.104888) (xy 58.13806 -438.089802)
			(xy 17.64623 -438.089802) (xy 17.560003 -438.245334) (xy 17.453569 -438.420837) (xy 17.340383 -438.592063)
			(xy 17.220616 -438.758754) (xy 17.094452 -438.920655) (xy 16.96208 -439.077522) (xy 16.950872 -439.0898)
			(xy 60.138056 -439.0898) (xy 60.138173 -439.074715) (xy 60.139949 -439.044596) (xy 60.141612 -439.029602)
			(xy 60.141612 -437.950102) (xy 60.139941 -437.935109) (xy 60.138164 -437.90499) (xy 60.138056 -437.889904)
			(xy 60.138173 -437.874819) (xy 60.139949 -437.8447) (xy 60.141612 -437.829706) (xy 60.141612 -437.21909)
			(xy 60.142099 -437.207003) (xy 60.149555 -437.184007) (xy 60.163737 -437.164429) (xy 60.183265 -437.150178)
			(xy 60.206234 -437.142641) (xy 60.21832 -437.142128) (xy 61.15812 -437.142128) (xy 61.170233 -437.1425)
			(xy 61.193265 -437.150008) (xy 61.212841 -437.16428) (xy 61.227034 -437.183913) (xy 61.234449 -437.206976)
			(xy 61.234828 -437.21909) (xy 61.234828 -438.089802) (xy 62.138052 -438.089802) (xy 62.138169 -438.074717)
			(xy 62.139945 -438.044598) (xy 62.141608 -438.029604) (xy 62.141608 -436.950104) (xy 62.139938 -436.935111)
			(xy 62.13816 -436.904992) (xy 62.138052 -436.889906) (xy 62.13816 -436.87482) (xy 62.139942 -436.844702)
			(xy 62.141608 -436.829708) (xy 62.141608 -436.219092) (xy 62.142006 -436.207007) (xy 62.149478 -436.184021)
			(xy 62.163687 -436.16447) (xy 62.183243 -436.150267) (xy 62.206231 -436.142802) (xy 62.218316 -436.142384)
			(xy 63.158116 -436.142384) (xy 63.170191 -436.142851) (xy 63.193157 -436.150317) (xy 63.212693 -436.164513)
			(xy 63.226887 -436.18405) (xy 63.234351 -436.207017) (xy 63.234824 -436.219092) (xy 63.234824 -438.760616)
			(xy 63.23435 -438.77269) (xy 63.226885 -438.795655) (xy 63.21269 -438.81519) (xy 63.193155 -438.829385)
			(xy 63.17019 -438.83685) (xy 63.158116 -438.837324) (xy 62.218316 -438.837324) (xy 62.206244 -438.836822)
			(xy 62.18328 -438.829366) (xy 62.163744 -438.815179) (xy 62.149548 -438.795649) (xy 62.142083 -438.772688)
			(xy 62.141608 -438.760616) (xy 62.141608 -438.15) (xy 62.139937 -438.135007) (xy 62.13816 -438.104888)
			(xy 62.138052 -438.089802) (xy 61.234828 -438.089802) (xy 61.234828 -439.0898) (xy 64.138048 -439.0898)
			(xy 64.138165 -439.074715) (xy 64.139941 -439.044596) (xy 64.141604 -439.029602) (xy 64.141604 -437.950102)
			(xy 64.139933 -437.935109) (xy 64.138156 -437.90499) (xy 64.138048 -437.889904) (xy 64.138165 -437.874819)
			(xy 64.139941 -437.8447) (xy 64.141604 -437.829706) (xy 64.141604 -437.21909) (xy 64.142098 -437.207004)
			(xy 64.149553 -437.184009) (xy 64.163734 -437.164432) (xy 64.18326 -437.150181) (xy 64.206227 -437.142643)
			(xy 64.218312 -437.142128) (xy 65.158112 -437.142128) (xy 65.170224 -437.142506) (xy 65.193257 -437.150012)
			(xy 65.212832 -437.164283) (xy 65.227025 -437.183914) (xy 65.234441 -437.206976) (xy 65.23482 -437.21909)
			(xy 65.23482 -438.089802) (xy 66.138044 -438.089802) (xy 66.138161 -438.074717) (xy 66.139937 -438.044598)
			(xy 66.1416 -438.029604) (xy 66.1416 -436.950104) (xy 66.13993 -436.935111) (xy 66.138152 -436.904992)
			(xy 66.138044 -436.889906) (xy 66.138152 -436.87482) (xy 66.139934 -436.844702) (xy 66.1416 -436.829708)
			(xy 66.1416 -436.219092) (xy 66.142058 -436.207016) (xy 66.149523 -436.184047) (xy 66.163721 -436.16451)
			(xy 66.183262 -436.150316) (xy 66.206232 -436.142855) (xy 66.218308 -436.142384) (xy 67.158108 -436.142384)
			(xy 67.170182 -436.142857) (xy 67.193148 -436.150321) (xy 67.212684 -436.164516) (xy 67.226879 -436.184052)
			(xy 67.234343 -436.207018) (xy 67.234816 -436.219092) (xy 67.234816 -438.760616) (xy 67.234349 -438.772691)
			(xy 67.226883 -438.795657) (xy 67.212687 -438.815193) (xy 67.19315 -438.829387) (xy 67.170183 -438.836851)
			(xy 67.158108 -438.837324) (xy 66.218308 -438.837324) (xy 66.206235 -438.836829) (xy 66.183271 -438.829371)
			(xy 66.163735 -438.815182) (xy 66.14954 -438.79565) (xy 66.142075 -438.772688) (xy 66.1416 -438.760616)
			(xy 66.1416 -438.15) (xy 66.139929 -438.135007) (xy 66.138152 -438.104888) (xy 66.138044 -438.089802)
			(xy 65.23482 -438.089802) (xy 65.23482 -439.0898) (xy 68.13804 -439.0898) (xy 68.138157 -439.074715)
			(xy 68.139933 -439.044596) (xy 68.141596 -439.029602) (xy 68.141596 -437.950102) (xy 68.139925 -437.935109)
			(xy 68.138148 -437.90499) (xy 68.13804 -437.889904) (xy 68.138157 -437.874819) (xy 68.139933 -437.8447)
			(xy 68.141596 -437.829706) (xy 68.141596 -437.21909) (xy 68.142098 -437.207004) (xy 68.149552 -437.184011)
			(xy 68.163731 -437.164435) (xy 68.183255 -437.150183) (xy 68.20622 -437.142644) (xy 68.218304 -437.142128)
			(xy 69.158104 -437.142128) (xy 69.170216 -437.142513) (xy 69.193248 -437.150017) (xy 69.212824 -437.164286)
			(xy 69.227017 -437.183916) (xy 69.234433 -437.206977) (xy 69.234812 -437.21909) (xy 69.234812 -438.089802)
			(xy 70.138036 -438.089802) (xy 70.138153 -438.074717) (xy 70.139929 -438.044598) (xy 70.141592 -438.029604)
			(xy 70.141592 -436.950104) (xy 70.139922 -436.935111) (xy 70.138144 -436.904992) (xy 70.138036 -436.889906)
			(xy 70.138146 -436.87482) (xy 70.139928 -436.844702) (xy 70.141592 -436.829708) (xy 70.141592 -436.219092)
			(xy 70.142058 -436.207017) (xy 70.149522 -436.18405) (xy 70.163718 -436.164513) (xy 70.183257 -436.150319)
			(xy 70.206225 -436.142856) (xy 70.2183 -436.142384) (xy 71.1581 -436.142384) (xy 71.170174 -436.142864)
			(xy 71.19314 -436.150326) (xy 71.212676 -436.164518) (xy 71.226871 -436.184053) (xy 71.234335 -436.207018)
			(xy 71.234808 -436.219092) (xy 71.234808 -438.760616) (xy 71.234349 -438.772691) (xy 71.226882 -438.795659)
			(xy 71.212684 -438.815196) (xy 71.193145 -438.82939) (xy 71.170175 -438.836852) (xy 71.1581 -438.837324)
			(xy 70.2183 -438.837324) (xy 70.206227 -438.836836) (xy 70.183263 -438.829375) (xy 70.163727 -438.815184)
			(xy 70.149532 -438.795652) (xy 70.142067 -438.772689) (xy 70.141592 -438.760616) (xy 70.141592 -438.15)
			(xy 70.139921 -438.135007) (xy 70.138144 -438.104888) (xy 70.138036 -438.089802) (xy 69.234812 -438.089802)
			(xy 69.234812 -439.0898) (xy 72.138032 -439.0898) (xy 72.138151 -439.074715) (xy 72.139927 -439.044596)
			(xy 72.141588 -439.029602) (xy 72.141588 -437.950102) (xy 72.139917 -437.935109) (xy 72.13814 -437.90499)
			(xy 72.138032 -437.889904) (xy 72.138151 -437.874819) (xy 72.139927 -437.8447) (xy 72.141588 -437.829706)
			(xy 72.141588 -437.21909) (xy 72.142 -437.206995) (xy 72.149465 -437.183986) (xy 72.163664 -437.164402)
			(xy 72.183212 -437.150154) (xy 72.206202 -437.142631) (xy 72.218296 -437.142128) (xy 73.158096 -437.142128)
			(xy 73.170207 -437.14252) (xy 73.193239 -437.150022) (xy 73.212815 -437.164288) (xy 73.227009 -437.183917)
			(xy 73.234425 -437.206977) (xy 73.234804 -437.21909) (xy 73.234804 -438.089802) (xy 75.138026 -438.089802)
			(xy 75.138119 -438.075228) (xy 75.139772 -438.046127) (xy 75.141328 -438.031636) (xy 75.141328 -436.948072)
			(xy 75.139784 -436.93358) (xy 75.138131 -436.90448) (xy 75.138026 -436.889906) (xy 75.138119 -436.875332)
			(xy 75.139772 -436.846231) (xy 75.141328 -436.83174) (xy 75.141328 -436.219092) (xy 75.14171 -436.20698)
			(xy 75.149215 -436.183948) (xy 75.163484 -436.164372) (xy 75.183115 -436.150179) (xy 75.206176 -436.142763)
			(xy 75.21829 -436.142384) (xy 76.15809 -436.142384) (xy 76.170183 -436.142817) (xy 76.193191 -436.150276)
			(xy 76.212775 -436.16447) (xy 76.227024 -436.184014) (xy 76.234549 -436.207) (xy 76.235052 -436.219092)
			(xy 76.235052 -438.760616) (xy 76.234598 -438.772721) (xy 76.227101 -438.795739) (xy 76.212847 -438.815308)
			(xy 76.193237 -438.829504) (xy 76.170196 -438.836933) (xy 76.15809 -438.837324) (xy 75.21829 -438.837324)
			(xy 75.206196 -438.8369) (xy 75.183189 -438.829436) (xy 75.163607 -438.81524) (xy 75.149358 -438.795695)
			(xy 75.141832 -438.772708) (xy 75.141328 -438.760616) (xy 75.141328 -438.147968) (xy 75.139783 -438.133476)
			(xy 75.138131 -438.104376) (xy 75.138026 -438.089802) (xy 73.234804 -438.089802) (xy 73.234804 -439.0898)
			(xy 77.138022 -439.0898) (xy 77.138115 -439.075226) (xy 77.139768 -439.046125) (xy 77.141324 -439.031634)
			(xy 77.141324 -437.94807) (xy 77.139779 -437.933578) (xy 77.138127 -437.904478) (xy 77.138022 -437.889904)
			(xy 77.138115 -437.87533) (xy 77.139768 -437.846229) (xy 77.141324 -437.831738) (xy 77.141324 -437.21909)
			(xy 77.141803 -437.206976) (xy 77.149291 -437.183935) (xy 77.163532 -437.164335) (xy 77.183132 -437.150093)
			(xy 77.206172 -437.142604) (xy 77.218286 -437.142128) (xy 78.158086 -437.142128) (xy 78.170207 -437.142572)
			(xy 78.193264 -437.150059) (xy 78.212878 -437.164305) (xy 78.22713 -437.183915) (xy 78.234624 -437.206969)
			(xy 78.235048 -437.21909) (xy 78.235048 -438.089802) (xy 79.138018 -438.089802) (xy 79.138111 -438.075228)
			(xy 79.139764 -438.046127) (xy 79.14132 -438.031636) (xy 79.14132 -436.948072) (xy 79.139776 -436.93358)
			(xy 79.138123 -436.90448) (xy 79.138018 -436.889906) (xy 79.138111 -436.875332) (xy 79.139764 -436.846231)
			(xy 79.14132 -436.83174) (xy 79.14132 -436.219092) (xy 79.14171 -436.206981) (xy 79.149214 -436.18395)
			(xy 79.163481 -436.164375) (xy 79.18311 -436.150181) (xy 79.206169 -436.142764) (xy 79.218282 -436.142384)
			(xy 80.158082 -436.142384) (xy 80.170175 -436.142824) (xy 80.193182 -436.150281) (xy 80.212766 -436.164473)
			(xy 80.227016 -436.184015) (xy 80.234541 -436.207) (xy 80.235044 -436.219092) (xy 80.235044 -438.760616)
			(xy 80.234598 -438.772721) (xy 80.227099 -438.795742) (xy 80.212844 -438.815311) (xy 80.193232 -438.829506)
			(xy 80.170189 -438.836935) (xy 80.158082 -438.837324) (xy 79.218282 -438.837324) (xy 79.206188 -438.836907)
			(xy 79.183181 -438.829441) (xy 79.163598 -438.815243) (xy 79.149349 -438.795697) (xy 79.141824 -438.772709)
			(xy 79.14132 -438.760616) (xy 79.14132 -438.147968) (xy 79.139775 -438.133476) (xy 79.138123 -438.104376)
			(xy 79.138018 -438.089802) (xy 78.235048 -438.089802) (xy 78.235048 -439.0898) (xy 81.138014 -439.0898)
			(xy 81.138106 -439.075226) (xy 81.13976 -439.046125) (xy 81.141316 -439.031634) (xy 81.141316 -437.94807)
			(xy 81.139771 -437.933578) (xy 81.138119 -437.904478) (xy 81.138014 -437.889904) (xy 81.138107 -437.87533)
			(xy 81.13976 -437.846229) (xy 81.141316 -437.831738) (xy 81.141316 -437.21909) (xy 81.141803 -437.206977)
			(xy 81.14929 -437.183937) (xy 81.163529 -437.164338) (xy 81.183127 -437.150096) (xy 81.206165 -437.142605)
			(xy 81.218278 -437.142128) (xy 82.158078 -437.142128) (xy 82.170199 -437.142579) (xy 82.193255 -437.150064)
			(xy 82.21287 -437.164308) (xy 82.227122 -437.183916) (xy 82.234616 -437.20697) (xy 82.23504 -437.21909)
			(xy 82.23504 -438.089802) (xy 83.13801 -438.089802) (xy 83.138103 -438.075228) (xy 83.139756 -438.046127)
			(xy 83.141312 -438.031636) (xy 83.141312 -436.948072) (xy 83.139767 -436.93358) (xy 83.138115 -436.90448)
			(xy 83.13801 -436.889906) (xy 83.138103 -436.875332) (xy 83.139756 -436.846231) (xy 83.141312 -436.83174)
			(xy 83.141312 -436.219092) (xy 83.14171 -436.206981) (xy 83.149213 -436.183952) (xy 83.163479 -436.164378)
			(xy 83.183105 -436.150184) (xy 83.206162 -436.142765) (xy 83.218274 -436.142384) (xy 84.158074 -436.142384)
			(xy 84.170167 -436.14283) (xy 84.193174 -436.150285) (xy 84.212758 -436.164476) (xy 84.227008 -436.184017)
			(xy 84.234533 -436.207001) (xy 84.235036 -436.219092) (xy 84.235036 -438.760616) (xy 84.234598 -438.772722)
			(xy 84.227098 -438.795744) (xy 84.212841 -438.815313) (xy 84.193227 -438.829509) (xy 84.170181 -438.836936)
			(xy 84.158074 -438.837324) (xy 83.218274 -438.837324) (xy 83.206179 -438.836914) (xy 83.183172 -438.829446)
			(xy 83.163589 -438.815246) (xy 83.149341 -438.795698) (xy 83.141816 -438.772709) (xy 83.141312 -438.760616)
			(xy 83.141312 -438.147968) (xy 83.139767 -438.133476) (xy 83.138115 -438.104376) (xy 83.13801 -438.089802)
			(xy 82.23504 -438.089802) (xy 82.23504 -439.0898) (xy 85.138006 -439.0898) (xy 85.138098 -439.075226)
			(xy 85.139752 -439.046125) (xy 85.141308 -439.031634) (xy 85.141308 -437.94807) (xy 85.139763 -437.933578)
			(xy 85.138111 -437.904478) (xy 85.138006 -437.889904) (xy 85.138099 -437.87533) (xy 85.139752 -437.846229)
			(xy 85.141308 -437.831738) (xy 85.141308 -437.21909) (xy 85.141803 -437.206978) (xy 85.149289 -437.18394)
			(xy 85.163526 -437.164341) (xy 85.183122 -437.150098) (xy 85.206158 -437.142606) (xy 85.21827 -437.142128)
			(xy 86.15807 -437.142128) (xy 86.17019 -437.142585) (xy 86.193246 -437.150068) (xy 86.212861 -437.16431)
			(xy 86.227114 -437.183918) (xy 86.234608 -437.20697) (xy 86.235032 -437.21909) (xy 86.235032 -438.089802)
			(xy 87.138002 -438.089802) (xy 87.138095 -438.075228) (xy 87.139748 -438.046127) (xy 87.141304 -438.031636)
			(xy 87.141304 -436.948072) (xy 87.139759 -436.93358) (xy 87.138107 -436.90448) (xy 87.138002 -436.889906)
			(xy 87.138095 -436.875332) (xy 87.139748 -436.846231) (xy 87.141304 -436.83174) (xy 87.141304 -436.219092)
			(xy 87.141709 -436.206982) (xy 87.149212 -436.183954) (xy 87.163476 -436.164381) (xy 87.1831 -436.150186)
			(xy 87.206155 -436.142767) (xy 87.218266 -436.142384) (xy 88.158066 -436.142384) (xy 88.170158 -436.142837)
			(xy 88.193165 -436.15029) (xy 88.212749 -436.164478) (xy 88.227 -436.184018) (xy 88.234525 -436.207001)
			(xy 88.235028 -436.219092) (xy 88.235028 -438.760616) (xy 88.234598 -438.772723) (xy 88.227097 -438.795746)
			(xy 88.212838 -438.815316) (xy 88.193222 -438.829511) (xy 88.170174 -438.836937) (xy 88.158066 -438.837324)
			(xy 87.218266 -438.837324) (xy 87.206171 -438.836921) (xy 87.183163 -438.829451) (xy 87.163581 -438.815249)
			(xy 87.149333 -438.7957) (xy 87.141808 -438.77271) (xy 87.141304 -438.760616) (xy 87.141304 -438.147968)
			(xy 87.139759 -438.133476) (xy 87.138107 -438.104376) (xy 87.138002 -438.089802) (xy 86.235032 -438.089802)
			(xy 86.235032 -439.0898) (xy 89.137998 -439.0898) (xy 89.13809 -439.075226) (xy 89.139744 -439.046125)
			(xy 89.1413 -439.031634) (xy 89.1413 -437.94807) (xy 89.139755 -437.933578) (xy 89.138103 -437.904478)
			(xy 89.137998 -437.889904) (xy 89.138091 -437.87533) (xy 89.139744 -437.846229) (xy 89.1413 -437.831738)
			(xy 89.1413 -437.21909) (xy 89.141803 -437.206979) (xy 89.149288 -437.183942) (xy 89.163524 -437.164343)
			(xy 89.183117 -437.150101) (xy 89.206151 -437.142607) (xy 89.218262 -437.142128) (xy 90.158062 -437.142128)
			(xy 90.170182 -437.142592) (xy 90.193238 -437.150073) (xy 90.212853 -437.164313) (xy 90.227105 -437.183919)
			(xy 90.2346 -437.20697) (xy 90.235024 -437.21909) (xy 90.235024 -439.760614) (xy 90.234651 -439.772741)
			(xy 90.22715 -439.795807) (xy 90.212888 -439.815425) (xy 90.19326 -439.829674) (xy 90.17019 -439.837159)
			(xy 90.158062 -439.837576) (xy 89.218262 -439.837576) (xy 89.206147 -439.837121) (xy 89.183105 -439.829625)
			(xy 89.163505 -439.815378) (xy 89.149264 -439.795774) (xy 89.141775 -439.772729) (xy 89.1413 -439.760614)
			(xy 89.1413 -439.147966) (xy 89.139755 -439.133474) (xy 89.138103 -439.104374) (xy 89.137998 -439.0898)
			(xy 86.235032 -439.0898) (xy 86.235032 -439.760614) (xy 86.234651 -439.77274) (xy 86.227152 -439.795805)
			(xy 86.212891 -439.815422) (xy 86.193265 -439.829672) (xy 86.170197 -439.837158) (xy 86.15807 -439.837576)
			(xy 85.21827 -439.837576) (xy 85.206155 -439.837114) (xy 85.183113 -439.82962) (xy 85.163513 -439.815375)
			(xy 85.149272 -439.795772) (xy 85.141783 -439.772729) (xy 85.141308 -439.760614) (xy 85.141308 -439.147966)
			(xy 85.139763 -439.133474) (xy 85.138111 -439.104374) (xy 85.138006 -439.0898) (xy 82.23504 -439.0898)
			(xy 82.23504 -439.760614) (xy 82.234651 -439.77274) (xy 82.227153 -439.795803) (xy 82.212894 -439.815419)
			(xy 82.19327 -439.829669) (xy 82.170204 -439.837157) (xy 82.158078 -439.837576) (xy 81.218278 -439.837576)
			(xy 81.206164 -439.837107) (xy 81.183122 -439.829616) (xy 81.163522 -439.815372) (xy 81.149281 -439.795771)
			(xy 81.141791 -439.772728) (xy 81.141316 -439.760614) (xy 81.141316 -439.147966) (xy 81.139771 -439.133474)
			(xy 81.138119 -439.104374) (xy 81.138014 -439.0898) (xy 78.235048 -439.0898) (xy 78.235048 -439.760614)
			(xy 78.2346 -439.772731) (xy 78.227107 -439.795777) (xy 78.21286 -439.81538) (xy 78.193252 -439.82962)
			(xy 78.170203 -439.837105) (xy 78.158086 -439.837576) (xy 77.218286 -439.837576) (xy 77.206172 -439.837101)
			(xy 77.183131 -439.829611) (xy 77.16353 -439.81537) (xy 77.149289 -439.795769) (xy 77.141799 -439.772728)
			(xy 77.141324 -439.760614) (xy 77.141324 -439.147966) (xy 77.139779 -439.133474) (xy 77.138127 -439.104374)
			(xy 77.138022 -439.0898) (xy 73.234804 -439.0898) (xy 73.234804 -439.760614) (xy 73.234306 -439.7727)
			(xy 73.22685 -439.795694) (xy 73.21267 -439.81527) (xy 73.193146 -439.829521) (xy 73.17018 -439.837061)
			(xy 73.158096 -439.837576) (xy 72.218296 -439.837576) (xy 72.206185 -439.837187) (xy 72.183153 -439.829683)
			(xy 72.163578 -439.815416) (xy 72.149384 -439.795787) (xy 72.141968 -439.772727) (xy 72.141588 -439.760614)
			(xy 72.141588 -439.149998) (xy 72.139917 -439.135005) (xy 72.13814 -439.104886) (xy 72.138032 -439.0898)
			(xy 69.234812 -439.0898) (xy 69.234812 -439.760614) (xy 69.234404 -439.772709) (xy 69.226938 -439.795718)
			(xy 69.212737 -439.815302) (xy 69.193189 -439.829551) (xy 69.170198 -439.837074) (xy 69.158104 -439.837576)
			(xy 68.218304 -439.837576) (xy 68.206193 -439.83718) (xy 68.183162 -439.829679) (xy 68.163586 -439.815413)
			(xy 68.149392 -439.795785) (xy 68.141976 -439.772727) (xy 68.141596 -439.760614) (xy 68.141596 -439.149998)
			(xy 68.139925 -439.135005) (xy 68.138148 -439.104886) (xy 68.13804 -439.0898) (xy 65.23482 -439.0898)
			(xy 65.23482 -439.760614) (xy 65.234404 -439.772708) (xy 65.226939 -439.795716) (xy 65.21274 -439.815299)
			(xy 65.193194 -439.829548) (xy 65.170205 -439.837073) (xy 65.158112 -439.837576) (xy 64.218312 -439.837576)
			(xy 64.206201 -439.837173) (xy 64.18317 -439.829674) (xy 64.163595 -439.81541) (xy 64.149401 -439.795784)
			(xy 64.141984 -439.772726) (xy 64.141604 -439.760614) (xy 64.141604 -439.149998) (xy 64.139933 -439.135005)
			(xy 64.138156 -439.104886) (xy 64.138048 -439.0898) (xy 61.234828 -439.0898) (xy 61.234828 -439.760614)
			(xy 61.234404 -439.772708) (xy 61.22694 -439.795714) (xy 61.212743 -439.815297) (xy 61.193199 -439.829546)
			(xy 61.170212 -439.837072) (xy 61.15812 -439.837576) (xy 60.21832 -439.837576) (xy 60.20621 -439.837166)
			(xy 60.183179 -439.829669) (xy 60.163604 -439.815407) (xy 60.149409 -439.795782) (xy 60.141992 -439.772726)
			(xy 60.141612 -439.760614) (xy 60.141612 -439.149998) (xy 60.139941 -439.135005) (xy 60.138164 -439.104886)
			(xy 60.138056 -439.0898) (xy 16.950872 -439.0898) (xy 16.823701 -439.229117) (xy 16.679526 -439.375209)
			(xy 16.529773 -439.515579) (xy 16.374669 -439.650012) (xy 16.214449 -439.778305) (xy 16.049355 -439.900263)
			(xy 15.87964 -440.015701) (xy 15.705558 -440.124446) (xy 15.527376 -440.22633) (xy 15.436596 -440.274202)
			(xy 15.423478 -440.281619) (xy 15.401949 -440.302682) (xy 15.387495 -440.329107) (xy 15.381373 -440.358597)
			(xy 15.384112 -440.388591) (xy 15.395477 -440.416484) (xy 15.414479 -440.439853) (xy 15.439468 -440.456667)
			(xy 15.468273 -440.465467) (xy 15.483332 -440.465972) (xy 58.138314 -440.465972)
		)
		(stroke
			(width 0)
			(type solid)
		)
		(fill yes)
		(layer "In8.Cu")
		(net "P12V_AUX")
	)
	(gr_line
		(start 0.585724 -79.085694)
		(end 1.414272 -79.914242)
		(stroke
			(width 3.048)
			(type default)
		)
		(layer "In8.Cu")
	)
	(gr_arc
		(start 1.999996 -403.371812)
		(mid 2.152217 -404.13708)
		(end 2.58572 -404.78583)
		(stroke
			(width 3.048)
			(type default)
		)
		(layer "In8.Cu")
	)
	(gr_arc
		(start 1.999996 -81.32826)
		(mid 1.847757 -80.563001)
		(end 1.414272 -79.914242)
		(stroke
			(width 3.048)
			(type default)
		)
		(layer "In8.Cu")
	)
	(gr_line
		(start 1.999996 -81.32826)
		(end 1.999996 -403.371812)
		(stroke
			(width 3.048)
			(type default)
		)
		(layer "In8.Cu")
	)
	(gr_arc
		(start 1.999996 -11.780012)
		(mid 0.585785 -12.365797)
		(end 0 -13.780008)
		(stroke
			(width 3.048)
			(type default)
		)
		(layer "In8.Cu")
	)
	(gr_line
		(start 2.58572 -404.78583)
		(end 5.914644 -408.114754)
		(stroke
			(width 3.048)
			(type default)
		)
		(layer "In8.Cu")
	)
	(gr_line
		(start 6.355842 -189.490604)
		(end 6.534658 -189.150244)
		(stroke
			(width 0.508)
			(type default)
		)
		(layer "In8.Cu")
	)
	(gr_line
		(start 6.36143 -334.993742)
		(end 8.797798 -337.43011)
		(stroke
			(width 0.508)
			(type default)
		)
		(layer "In8.Cu")
	)
	(gr_line
		(start 6.36143 -327.654158)
		(end 6.36143 -334.993742)
		(stroke
			(width 0.508)
			(type default)
		)
		(layer "In8.Cu")
	)
	(gr_line
		(start 6.361938 -327.65365)
		(end 6.36143 -327.654158)
		(stroke
			(width 0.508)
			(type default)
		)
		(layer "In8.Cu")
	)
	(gr_line
		(start 6.361938 -189.46749)
		(end 6.361938 -327.65365)
		(stroke
			(width 0.508)
			(type default)
		)
		(layer "In8.Cu")
	)
	(gr_line
		(start 6.39445 -319.186306)
		(end 7.05612 -318.524636)
		(stroke
			(width 0.508)
			(type default)
		)
		(layer "In8.Cu")
	)
	(gr_line
		(start 6.436106 -318.533272)
		(end 6.448552 -318.520826)
		(stroke
			(width 0.508)
			(type default)
		)
		(layer "In8.Cu")
	)
	(gr_arc
		(start 6.500114 -439.989976)
		(mid 7.085899 -441.404187)
		(end 8.50011 -441.989972)
		(stroke
			(width 3.048)
			(type default)
		)
		(layer "In8.Cu")
	)
	(gr_arc
		(start 6.500114 -409.528264)
		(mid 6.347973 -408.763275)
		(end 5.914644 -408.114754)
		(stroke
			(width 3.048)
			(type default)
		)
		(layer "In8.Cu")
	)
	(gr_line
		(start 6.500114 -409.528264)
		(end 6.500114 -439.989976)
		(stroke
			(width 3.048)
			(type default)
		)
		(layer "In8.Cu")
	)
	(gr_line
		(start 7.05612 -318.524636)
		(end 6.401816 -317.870332)
		(stroke
			(width 0.508)
			(type default)
		)
		(layer "In8.Cu")
	)
	(gr_line
		(start 7.132574 -187.975494)
		(end 6.534658 -189.150244)
		(stroke
			(width 0.508)
			(type default)
		)
		(layer "In8.Cu")
	)
	(gr_line
		(start 8.50011 -441.989972)
		(end 194.505072 -441.989972)
		(stroke
			(width 3.048)
			(type default)
		)
		(layer "In8.Cu")
	)
	(gr_line
		(start 8.797798 -337.43011)
		(end 9.115298 -337.43011)
		(stroke
			(width 0.508)
			(type default)
		)
		(layer "In8.Cu")
	)
	(gr_line
		(start 9.115298 -337.43011)
		(end 22.328378 -337.43011)
		(stroke
			(width 0.508)
			(type default)
		)
		(layer "In8.Cu")
	)
	(gr_line
		(start 11.102086 -11.780012)
		(end 1.999996 -11.780012)
		(stroke
			(width 3.048)
			(type default)
		)
		(layer "In8.Cu")
	)
	(gr_arc
		(start 11.102086 -11.780012)
		(mid 12.516298 -11.194228)
		(end 13.102082 -9.780016)
		(stroke
			(width 3.048)
			(type default)
		)
		(layer "In8.Cu")
	)
	(gr_line
		(start 11.492738 -318.520826)
		(end 6.448552 -318.520826)
		(stroke
			(width 0.508)
			(type default)
		)
		(layer "In8.Cu")
	)
	(gr_line
		(start 12.935458 -176.65065)
		(end 7.132574 -187.975494)
		(stroke
			(width 0.508)
			(type default)
		)
		(layer "In8.Cu")
	)
	(gr_line
		(start 12.935458 -176.65065)
		(end 12.935458 -163.93033)
		(stroke
			(width 0.508)
			(type default)
		)
		(layer "In8.Cu")
	)
	(gr_line
		(start 13.102082 -0.999998)
		(end 13.102082 -9.780016)
		(stroke
			(width 3.048)
			(type default)
		)
		(layer "In8.Cu")
	)
	(gr_arc
		(start 14.10208 0)
		(mid 13.394975 -0.292893)
		(end 13.102082 -0.999998)
		(stroke
			(width 3.048)
			(type default)
		)
		(layer "In8.Cu")
	)
	(gr_line
		(start 17.78 -159.085788)
		(end 12.935458 -163.93033)
		(stroke
			(width 0.508)
			(type default)
		)
		(layer "In8.Cu")
	)
	(gr_line
		(start 22.328378 -337.43011)
		(end 25.069038 -340.17077)
		(stroke
			(width 0.508)
			(type default)
		)
		(layer "In8.Cu")
	)
	(gr_line
		(start 25.069038 -347.920056)
		(end 25.069038 -340.17077)
		(stroke
			(width 0.508)
			(type default)
		)
		(layer "In8.Cu")
	)
	(gr_line
		(start 25.069038 -347.920056)
		(end 36.981892 -359.83291)
		(stroke
			(width 0.508)
			(type default)
		)
		(layer "In8.Cu")
	)
	(gr_line
		(start 25.20696 -126.774448)
		(end 25.20696 -122.568208)
		(stroke
			(width 0.508)
			(type default)
		)
		(layer "In8.Cu")
	)
	(gr_line
		(start 25.20696 -44.882308)
		(end 25.20696 -122.568208)
		(stroke
			(width 0.508)
			(type default)
		)
		(layer "In8.Cu")
	)
	(gr_line
		(start 30.14218 -131.709668)
		(end 25.20696 -126.774448)
		(stroke
			(width 0.508)
			(type default)
		)
		(layer "In8.Cu")
	)
	(gr_line
		(start 31.41218 -317.861188)
		(end 30.826964 -318.446404)
		(stroke
			(width 0.508)
			(type default)
		)
		(layer "In8.Cu")
	)
	(gr_line
		(start 31.416498 -317.861188)
		(end 31.41218 -317.861188)
		(stroke
			(width 0.508)
			(type default)
		)
		(layer "In8.Cu")
	)
	(gr_line
		(start 31.489142 -318.520826)
		(end 11.492738 -318.520826)
		(stroke
			(width 0.508)
			(type default)
		)
		(layer "In8.Cu")
	)
	(gr_line
		(start 31.489142 -318.51219)
		(end 31.489142 -219.006166)
		(stroke
			(width 0.508)
			(type default)
		)
		(layer "In8.Cu")
	)
	(gr_line
		(start 31.489142 -219.006166)
		(end 32.171386 -218.323922)
		(stroke
			(width 0.508)
			(type default)
		)
		(layer "In8.Cu")
	)
	(gr_line
		(start 32.171386 -218.323922)
		(end 74.415142 -218.323922)
		(stroke
			(width 0.508)
			(type default)
		)
		(layer "In8.Cu")
	)
	(gr_line
		(start 32.60344 -37.485828)
		(end 25.20696 -44.882308)
		(stroke
			(width 0.508)
			(type default)
		)
		(layer "In8.Cu")
	)
	(gr_line
		(start 36.30041 -341.547958)
		(end 36.30041 -323.332094)
		(stroke
			(width 0.508)
			(type default)
		)
		(layer "In8.Cu")
	)
	(gr_line
		(start 36.30041 -323.332094)
		(end 31.489142 -318.520826)
		(stroke
			(width 0.508)
			(type default)
		)
		(layer "In8.Cu")
	)
	(gr_line
		(start 36.981892 -359.83291)
		(end 85.917278 -359.83291)
		(stroke
			(width 0.508)
			(type default)
		)
		(layer "In8.Cu")
	)
	(gr_line
		(start 38.225476 -343.473024)
		(end 36.30041 -341.547958)
		(stroke
			(width 0.508)
			(type default)
		)
		(layer "In8.Cu")
	)
	(gr_line
		(start 38.847776 -131.709668)
		(end 30.14218 -131.709668)
		(stroke
			(width 0.508)
			(type default)
		)
		(layer "In8.Cu")
	)
	(gr_line
		(start 40.442642 -130.114802)
		(end 38.847776 -131.709668)
		(stroke
			(width 0.508)
			(type default)
		)
		(layer "In8.Cu")
	)
	(gr_line
		(start 47.939452 -159.085788)
		(end 17.78 -159.085788)
		(stroke
			(width 0.508)
			(type default)
		)
		(layer "In8.Cu")
	)
	(gr_line
		(start 49.138078 -157.887162)
		(end 47.939452 -159.085788)
		(stroke
			(width 0.508)
			(type default)
		)
		(layer "In8.Cu")
	)
	(gr_line
		(start 49.138078 -139.17295)
		(end 49.138078 -157.887162)
		(stroke
			(width 0.508)
			(type default)
		)
		(layer "In8.Cu")
	)
	(gr_line
		(start 49.811178 -138.49985)
		(end 49.138078 -139.17295)
		(stroke
			(width 0.508)
			(type default)
		)
		(layer "In8.Cu")
	)
	(gr_line
		(start 58.922158 -343.473024)
		(end 38.225476 -343.473024)
		(stroke
			(width 0.508)
			(type default)
		)
		(layer "In8.Cu")
	)
	(gr_line
		(start 60.475114 -138.524234)
		(end 61.136784 -139.185904)
		(stroke
			(width 0.508)
			(type default)
		)
		(layer "In8.Cu")
	)
	(gr_line
		(start 61.106304 -217.656664)
		(end 60.452 -218.310968)
		(stroke
			(width 0.508)
			(type default)
		)
		(layer "In8.Cu")
	)
	(gr_line
		(start 61.136784 -139.185904)
		(end 61.791088 -138.5316)
		(stroke
			(width 0.508)
			(type default)
		)
		(layer "In8.Cu")
	)
	(gr_line
		(start 61.14034 -218.20378)
		(end 61.14034 -138.605768)
		(stroke
			(width 0.508)
			(type default)
		)
		(layer "In8.Cu")
	)
	(gr_line
		(start 61.142372 -168.862248)
		(end 61.142372 -168.8338)
		(stroke
			(width 0.508)
			(type default)
		)
		(layer "In8.Cu")
	)
	(gr_line
		(start 61.149738 -167.517826)
		(end 61.14669 -167.517826)
		(stroke
			(width 0.508)
			(type default)
		)
		(layer "In8.Cu")
	)
	(gr_line
		(start 61.151262 -170.551348)
		(end 61.14034 -170.56227)
		(stroke
			(width 0.508)
			(type default)
		)
		(layer "In8.Cu")
	)
	(gr_line
		(start 61.1632 -171.160948)
		(end 61.7728 -170.551348)
		(stroke
			(width 0.508)
			(type default)
		)
		(layer "In8.Cu")
	)
	(gr_line
		(start 61.20765 -162.098482)
		(end 61.86932 -161.436812)
		(stroke
			(width 0.508)
			(type default)
		)
		(layer "In8.Cu")
	)
	(gr_line
		(start 61.7474 -170.551348)
		(end 61.1378 -169.941748)
		(stroke
			(width 0.508)
			(type default)
		)
		(layer "In8.Cu")
	)
	(gr_line
		(start 61.7474 -170.551348)
		(end 61.151262 -170.551348)
		(stroke
			(width 0.508)
			(type default)
		)
		(layer "In8.Cu")
	)
	(gr_line
		(start 61.767974 -218.318334)
		(end 61.106304 -217.656664)
		(stroke
			(width 0.508)
			(type default)
		)
		(layer "In8.Cu")
	)
	(gr_line
		(start 61.7728 -170.551348)
		(end 61.7474 -170.551348)
		(stroke
			(width 0.508)
			(type default)
		)
		(layer "In8.Cu")
	)
	(gr_line
		(start 61.7728 -170.551348)
		(end 65.6844 -170.551348)
		(stroke
			(width 0.508)
			(type default)
		)
		(layer "In8.Cu")
	)
	(gr_line
		(start 61.86932 -161.436812)
		(end 61.215016 -160.782508)
		(stroke
			(width 0.508)
			(type default)
		)
		(layer "In8.Cu")
	)
	(gr_line
		(start 64.485774 -138.605514)
		(end 64.497458 -138.59383)
		(stroke
			(width 0.508)
			(type default)
		)
		(layer "In8.Cu")
	)
	(gr_line
		(start 65.6844 -170.551348)
		(end 68.072 -172.938948)
		(stroke
			(width 0.508)
			(type default)
		)
		(layer "In8.Cu")
	)
	(gr_line
		(start 67.93103 -334.464152)
		(end 58.922158 -343.473024)
		(stroke
			(width 0.508)
			(type default)
		)
		(layer "In8.Cu")
	)
	(gr_line
		(start 68.072 -172.938948)
		(end 74.980038 -172.938948)
		(stroke
			(width 0.508)
			(type default)
		)
		(layer "In8.Cu")
	)
	(gr_line
		(start 71.738998 -161.468308)
		(end 61.260228 -161.468308)
		(stroke
			(width 0.508)
			(type default)
		)
		(layer "In8.Cu")
	)
	(gr_line
		(start 72.711818 -333.98587)
		(end 72.291448 -334.40624)
		(stroke
			(width 0.508)
			(type default)
		)
		(layer "In8.Cu")
	)
	(gr_line
		(start 72.714358 -334.44815)
		(end 72.714358 -296.49039)
		(stroke
			(width 0.508)
			(type default)
		)
		(layer "In8.Cu")
	)
	(gr_line
		(start 72.714358 -296.49039)
		(end 80.158336 -289.046412)
		(stroke
			(width 0.508)
			(type default)
		)
		(layer "In8.Cu")
	)
	(gr_line
		(start 72.968358 -160.238948)
		(end 71.738998 -161.468308)
		(stroke
			(width 0.508)
			(type default)
		)
		(layer "In8.Cu")
	)
	(gr_line
		(start 73.176638 -334.45069)
		(end 72.711818 -333.98587)
		(stroke
			(width 0.508)
			(type default)
		)
		(layer "In8.Cu")
	)
	(gr_line
		(start 74.424794 -218.31427)
		(end 74.415142 -218.323922)
		(stroke
			(width 0.508)
			(type default)
		)
		(layer "In8.Cu")
	)
	(gr_line
		(start 74.980038 -172.938948)
		(end 77.069442 -175.028352)
		(stroke
			(width 0.508)
			(type default)
		)
		(layer "In8.Cu")
	)
	(gr_line
		(start 76.061316 -334.464152)
		(end 67.93103 -334.464152)
		(stroke
			(width 0.508)
			(type default)
		)
		(layer "In8.Cu")
	)
	(gr_line
		(start 76.26604 -347.58757)
		(end 77.935328 -349.256858)
		(stroke
			(width 0.508)
			(type default)
		)
		(layer "In8.Cu")
	)
	(gr_line
		(start 76.26604 -341.25154)
		(end 76.26604 -347.58757)
		(stroke
			(width 0.508)
			(type default)
		)
		(layer "In8.Cu")
	)
	(gr_line
		(start 77.069442 -175.028352)
		(end 85.940646 -194.906392)
		(stroke
			(width 0.508)
			(type default)
		)
		(layer "In8.Cu")
	)
	(gr_line
		(start 77.213968 -340.303612)
		(end 76.26604 -341.25154)
		(stroke
			(width 0.508)
			(type default)
		)
		(layer "In8.Cu")
	)
	(gr_line
		(start 77.935328 -349.256858)
		(end 85.83295 -349.256858)
		(stroke
			(width 0.508)
			(type default)
		)
		(layer "In8.Cu")
	)
	(gr_line
		(start 79.973678 -330.55179)
		(end 76.061316 -334.464152)
		(stroke
			(width 0.508)
			(type default)
		)
		(layer "In8.Cu")
	)
	(gr_line
		(start 80.00365 -160.238948)
		(end 72.968358 -160.238948)
		(stroke
			(width 0.508)
			(type default)
		)
		(layer "In8.Cu")
	)
	(gr_line
		(start 80.158336 -289.046412)
		(end 103.48849 -289.046412)
		(stroke
			(width 0.508)
			(type default)
		)
		(layer "In8.Cu")
	)
	(gr_line
		(start 80.701896 0)
		(end 14.10208 0)
		(stroke
			(width 3.048)
			(type default)
		)
		(layer "In8.Cu")
	)
	(gr_line
		(start 80.841088 -345.232482)
		(end 83.009486 -347.40088)
		(stroke
			(width 0.254)
			(type default)
		)
		(layer "In8.Cu")
	)
	(gr_line
		(start 80.841088 -343.195148)
		(end 80.841088 -345.232482)
		(stroke
			(width 0.254)
			(type default)
		)
		(layer "In8.Cu")
	)
	(gr_line
		(start 81.011776 -343.02446)
		(end 80.841088 -343.195148)
		(stroke
			(width 0.254)
			(type default)
		)
		(layer "In8.Cu")
	)
	(gr_line
		(start 81.701894 -9.780016)
		(end 81.701894 -0.999998)
		(stroke
			(width 3.048)
			(type default)
		)
		(layer "In8.Cu")
	)
	(gr_arc
		(start 81.701894 -9.780016)
		(mid 82.287684 -11.19422)
		(end 83.70189 -11.780012)
		(stroke
			(width 3.048)
			(type default)
		)
		(layer "In8.Cu")
	)
	(gr_arc
		(start 81.701894 -0.999998)
		(mid 81.409001 -0.292893)
		(end 80.701896 0)
		(stroke
			(width 3.048)
			(type default)
		)
		(layer "In8.Cu")
	)
	(gr_line
		(start 82.996024 -348.857316)
		(end 82.750406 -349.102934)
		(stroke
			(width 0.254)
			(type default)
		)
		(layer "In8.Cu")
	)
	(gr_line
		(start 82.996024 -348.83598)
		(end 83.250024 -349.08998)
		(stroke
			(width 0.254)
			(type default)
		)
		(layer "In8.Cu")
	)
	(gr_line
		(start 83.009486 -347.40088)
		(end 83.009486 -348.96298)
		(stroke
			(width 0.254)
			(type default)
		)
		(layer "In8.Cu")
	)
	(gr_line
		(start 83.123532 -340.303612)
		(end 77.213968 -340.303612)
		(stroke
			(width 0.508)
			(type default)
		)
		(layer "In8.Cu")
	)
	(gr_line
		(start 83.503008 -339.924136)
		(end 83.123532 -340.303612)
		(stroke
			(width 0.508)
			(type default)
		)
		(layer "In8.Cu")
	)
	(gr_line
		(start 83.503008 -336.813144)
		(end 83.503008 -339.924136)
		(stroke
			(width 0.508)
			(type default)
		)
		(layer "In8.Cu")
	)
	(gr_line
		(start 83.593178 -330.55179)
		(end 79.973678 -330.55179)
		(stroke
			(width 0.508)
			(type default)
		)
		(layer "In8.Cu")
	)
	(gr_line
		(start 84.66836 -343.02446)
		(end 81.011776 -343.02446)
		(stroke
			(width 0.254)
			(type default)
		)
		(layer "In8.Cu")
	)
	(gr_line
		(start 84.854542 -329.290426)
		(end 83.593178 -330.55179)
		(stroke
			(width 0.508)
			(type default)
		)
		(layer "In8.Cu")
	)
	(gr_line
		(start 84.854542 -327.37171)
		(end 84.854542 -329.290426)
		(stroke
			(width 0.508)
			(type default)
		)
		(layer "In8.Cu")
	)
	(gr_line
		(start 85.143848 -343.499948)
		(end 84.66836 -343.02446)
		(stroke
			(width 0.254)
			(type default)
		)
		(layer "In8.Cu")
	)
	(gr_line
		(start 85.751162 -334.56499)
		(end 83.503008 -336.813144)
		(stroke
			(width 0.508)
			(type default)
		)
		(layer "In8.Cu")
	)
	(gr_line
		(start 85.768942 -326.45731)
		(end 84.854542 -327.37171)
		(stroke
			(width 0.508)
			(type default)
		)
		(layer "In8.Cu")
	)
	(gr_line
		(start 85.83295 -349.256858)
		(end 87.483442 -350.90735)
		(stroke
			(width 0.508)
			(type default)
		)
		(layer "In8.Cu")
	)
	(gr_line
		(start 85.917278 -359.83291)
		(end 87.334598 -358.41559)
		(stroke
			(width 0.508)
			(type default)
		)
		(layer "In8.Cu")
	)
	(gr_line
		(start 87.334598 -358.41559)
		(end 87.334598 -355.68763)
		(stroke
			(width 0.508)
			(type default)
		)
		(layer "In8.Cu")
	)
	(gr_line
		(start 87.334598 -355.68763)
		(end 88.221058 -354.80117)
		(stroke
			(width 0.508)
			(type default)
		)
		(layer "In8.Cu")
	)
	(gr_line
		(start 87.483442 -350.90735)
		(end 88.251792 -351.6757)
		(stroke
			(width 0.508)
			(type default)
		)
		(layer "In8.Cu")
	)
	(gr_line
		(start 88.221058 -354.80117)
		(end 101.689662 -354.80117)
		(stroke
			(width 0.508)
			(type default)
		)
		(layer "In8.Cu")
	)
	(gr_line
		(start 88.251792 -351.6757)
		(end 95.84817 -351.6757)
		(stroke
			(width 0.508)
			(type default)
		)
		(layer "In8.Cu")
	)
	(gr_line
		(start 88.595962 -343.499948)
		(end 85.143848 -343.499948)
		(stroke
			(width 0.254)
			(type default)
		)
		(layer "In8.Cu")
	)
	(gr_line
		(start 88.925146 -206.024734)
		(end 85.940646 -194.906392)
		(stroke
			(width 0.508)
			(type default)
		)
		(layer "In8.Cu")
	)
	(gr_line
		(start 89.051638 -339.654134)
		(end 89.715086 -340.317582)
		(stroke
			(width 0.254)
			(type default)
		)
		(layer "In8.Cu")
	)
	(gr_line
		(start 89.051638 -337.30692)
		(end 89.051638 -339.654134)
		(stroke
			(width 0.254)
			(type default)
		)
		(layer "In8.Cu")
	)
	(gr_line
		(start 89.104978 -218.31427)
		(end 74.424794 -218.31427)
		(stroke
			(width 0.508)
			(type default)
		)
		(layer "In8.Cu")
	)
	(gr_line
		(start 89.12733 -337.231228)
		(end 89.051638 -337.30692)
		(stroke
			(width 0.254)
			(type default)
		)
		(layer "In8.Cu")
	)
	(gr_line
		(start 89.528142 -260.92531)
		(end 89.528142 -233.665522)
		(stroke
			(width 0.508)
			(type default)
		)
		(layer "In8.Cu")
	)
	(gr_line
		(start 89.528142 -233.665522)
		(end 97.108518 -226.085146)
		(stroke
			(width 0.508)
			(type default)
		)
		(layer "In8.Cu")
	)
	(gr_line
		(start 89.564718 -217.85453)
		(end 89.104978 -218.31427)
		(stroke
			(width 0.508)
			(type default)
		)
		(layer "In8.Cu")
	)
	(gr_line
		(start 89.715086 -342.380824)
		(end 88.595962 -343.499948)
		(stroke
			(width 0.254)
			(type default)
		)
		(layer "In8.Cu")
	)
	(gr_line
		(start 89.715086 -340.317582)
		(end 89.715086 -342.380824)
		(stroke
			(width 0.254)
			(type default)
		)
		(layer "In8.Cu")
	)
	(gr_line
		(start 91.116658 -334.56499)
		(end 85.751162 -334.56499)
		(stroke
			(width 0.508)
			(type default)
		)
		(layer "In8.Cu")
	)
	(gr_line
		(start 91.458542 -326.45731)
		(end 85.768942 -326.45731)
		(stroke
			(width 0.508)
			(type default)
		)
		(layer "In8.Cu")
	)
	(gr_line
		(start 91.463368 -334.21828)
		(end 91.116658 -334.56499)
		(stroke
			(width 0.508)
			(type default)
		)
		(layer "In8.Cu")
	)
	(gr_line
		(start 91.463368 -332.966314)
		(end 91.463368 -334.21828)
		(stroke
			(width 0.508)
			(type default)
		)
		(layer "In8.Cu")
	)
	(gr_line
		(start 91.51366 -37.485828)
		(end 32.60344 -37.485828)
		(stroke
			(width 0.508)
			(type default)
		)
		(layer "In8.Cu")
	)
	(gr_line
		(start 92.674694 -337.231228)
		(end 89.12733 -337.231228)
		(stroke
			(width 0.254)
			(type default)
		)
		(layer "In8.Cu")
	)
	(gr_line
		(start 92.674694 -337.231228)
		(end 92.801694 -337.231228)
		(stroke
			(width 0.254)
			(type default)
		)
		(layer "In8.Cu")
	)
	(gr_line
		(start 92.779342 -325.13651)
		(end 91.458542 -326.45731)
		(stroke
			(width 0.508)
			(type default)
		)
		(layer "In8.Cu")
	)
	(gr_line
		(start 92.779342 -323.46011)
		(end 92.779342 -325.13651)
		(stroke
			(width 0.508)
			(type default)
		)
		(layer "In8.Cu")
	)
	(gr_line
		(start 92.801694 -337.231228)
		(end 92.920058 -337.349592)
		(stroke
			(width 0.254)
			(type default)
		)
		(layer "In8.Cu")
	)
	(gr_line
		(start 92.920058 -337.349592)
		(end 92.920058 -339.383624)
		(stroke
			(width 0.254)
			(type default)
		)
		(layer "In8.Cu")
	)
	(gr_line
		(start 93.171518 -339.635084)
		(end 92.920058 -339.383624)
		(stroke
			(width 0.254)
			(type default)
		)
		(layer "In8.Cu")
	)
	(gr_line
		(start 93.247464 -331.182218)
		(end 91.463368 -332.966314)
		(stroke
			(width 0.508)
			(type default)
		)
		(layer "In8.Cu")
	)
	(gr_line
		(start 93.261942 -322.97751)
		(end 92.779342 -323.46011)
		(stroke
			(width 0.508)
			(type default)
		)
		(layer "In8.Cu")
	)
	(gr_line
		(start 94.812358 -217.85453)
		(end 89.564718 -217.85453)
		(stroke
			(width 0.508)
			(type default)
		)
		(layer "In8.Cu")
	)
	(gr_line
		(start 95.167958 -219.61729)
		(end 95.167958 -218.76639)
		(stroke
			(width 0.508)
			(type default)
		)
		(layer "In8.Cu")
	)
	(gr_line
		(start 95.167958 -218.76639)
		(end 95.180658 -218.75369)
		(stroke
			(width 0.508)
			(type default)
		)
		(layer "In8.Cu")
	)
	(gr_line
		(start 95.180658 -218.75369)
		(end 95.180658 -218.22283)
		(stroke
			(width 0.508)
			(type default)
		)
		(layer "In8.Cu")
	)
	(gr_line
		(start 95.180658 -218.22283)
		(end 94.812358 -217.85453)
		(stroke
			(width 0.508)
			(type default)
		)
		(layer "In8.Cu")
	)
	(gr_line
		(start 95.84817 -351.6757)
		(end 97.721928 -349.801942)
		(stroke
			(width 0.508)
			(type default)
		)
		(layer "In8.Cu")
	)
	(gr_line
		(start 96.640142 -268.03731)
		(end 89.528142 -260.92531)
		(stroke
			(width 0.508)
			(type default)
		)
		(layer "In8.Cu")
	)
	(gr_line
		(start 96.732598 -260.52399)
		(end 97.286318 -261.07771)
		(stroke
			(width 0.508)
			(type default)
		)
		(layer "In8.Cu")
	)
	(gr_line
		(start 96.732598 -234.93857)
		(end 96.732598 -260.52399)
		(stroke
			(width 0.508)
			(type default)
		)
		(layer "In8.Cu")
	)
	(gr_line
		(start 97.108518 -226.085146)
		(end 97.108518 -221.55785)
		(stroke
			(width 0.508)
			(type default)
		)
		(layer "In8.Cu")
	)
	(gr_line
		(start 97.108518 -221.55785)
		(end 95.167958 -219.61729)
		(stroke
			(width 0.508)
			(type default)
		)
		(layer "In8.Cu")
	)
	(gr_line
		(start 97.189544 -335.993486)
		(end 98.115374 -336.919316)
		(stroke
			(width 0.254)
			(type default)
		)
		(layer "In8.Cu")
	)
	(gr_line
		(start 97.189544 -333.929736)
		(end 97.189544 -335.993486)
		(stroke
			(width 0.254)
			(type default)
		)
		(layer "In8.Cu")
	)
	(gr_line
		(start 97.286318 -261.07771)
		(end 102.532942 -261.07771)
		(stroke
			(width 0.508)
			(type default)
		)
		(layer "In8.Cu")
	)
	(gr_line
		(start 97.316798 -333.802482)
		(end 97.189544 -333.929736)
		(stroke
			(width 0.254)
			(type default)
		)
		(layer "In8.Cu")
	)
	(gr_line
		(start 97.429574 -339.635084)
		(end 93.171518 -339.635084)
		(stroke
			(width 0.254)
			(type default)
		)
		(layer "In8.Cu")
	)
	(gr_line
		(start 97.61474 -31.384748)
		(end 91.51366 -37.485828)
		(stroke
			(width 0.508)
			(type default)
		)
		(layer "In8.Cu")
	)
	(gr_line
		(start 97.721928 -349.801942)
		(end 113.672874 -349.801942)
		(stroke
			(width 0.508)
			(type default)
		)
		(layer "In8.Cu")
	)
	(gr_line
		(start 98.115374 -338.949284)
		(end 97.429574 -339.635084)
		(stroke
			(width 0.254)
			(type default)
		)
		(layer "In8.Cu")
	)
	(gr_line
		(start 98.115374 -336.919316)
		(end 98.115374 -338.949284)
		(stroke
			(width 0.254)
			(type default)
		)
		(layer "In8.Cu")
	)
	(gr_line
		(start 98.148902 -138.49985)
		(end 49.811178 -138.49985)
		(stroke
			(width 0.508)
			(type default)
		)
		(layer "In8.Cu")
	)
	(gr_line
		(start 98.570542 -233.100626)
		(end 96.732598 -234.93857)
		(stroke
			(width 0.508)
			(type default)
		)
		(layer "In8.Cu")
	)
	(gr_line
		(start 98.570542 -233.100626)
		(end 100.894134 -230.777034)
		(stroke
			(width 0.508)
			(type default)
		)
		(layer "In8.Cu")
	)
	(gr_line
		(start 100.864162 -333.802482)
		(end 97.316798 -333.802482)
		(stroke
			(width 0.254)
			(type default)
		)
		(layer "In8.Cu")
	)
	(gr_line
		(start 100.894134 -219.286836)
		(end 100.894134 -213.23935)
		(stroke
			(width 0.508)
			(type default)
		)
		(layer "In8.Cu")
	)
	(gr_line
		(start 100.894134 -219.286836)
		(end 102.683818 -221.07652)
		(stroke
			(width 0.508)
			(type default)
		)
		(layer "In8.Cu")
	)
	(gr_line
		(start 100.894134 -213.23935)
		(end 88.925146 -206.024734)
		(stroke
			(width 0.508)
			(type default)
		)
		(layer "In8.Cu")
	)
	(gr_line
		(start 100.99294 -338.73694)
		(end 100.99294 -333.93126)
		(stroke
			(width 0.254)
			(type default)
		)
		(layer "In8.Cu")
	)
	(gr_line
		(start 100.99294 -333.93126)
		(end 100.864162 -333.802482)
		(stroke
			(width 0.254)
			(type default)
		)
		(layer "In8.Cu")
	)
	(gr_line
		(start 101.689662 -354.80117)
		(end 104.641142 -357.75265)
		(stroke
			(width 0.508)
			(type default)
		)
		(layer "In8.Cu")
	)
	(gr_line
		(start 101.923596 -339.667596)
		(end 100.99294 -338.73694)
		(stroke
			(width 0.254)
			(type default)
		)
		(layer "In8.Cu")
	)
	(gr_line
		(start 102.683818 -228.98735)
		(end 100.894134 -230.777034)
		(stroke
			(width 0.508)
			(type default)
		)
		(layer "In8.Cu")
	)
	(gr_line
		(start 102.683818 -221.07652)
		(end 102.683818 -228.98735)
		(stroke
			(width 0.508)
			(type default)
		)
		(layer "In8.Cu")
	)
	(gr_line
		(start 102.710742 -268.03731)
		(end 96.640142 -268.03731)
		(stroke
			(width 0.508)
			(type default)
		)
		(layer "In8.Cu")
	)
	(gr_line
		(start 102.79888 -258.166108)
		(end 102.79888 -257.42773)
		(stroke
			(width 0.508)
			(type default)
		)
		(layer "In8.Cu")
	)
	(gr_line
		(start 102.79888 -257.42773)
		(end 103.091742 -257.134868)
		(stroke
			(width 0.508)
			(type default)
		)
		(layer "In8.Cu")
	)
	(gr_line
		(start 103.040942 -245.32971)
		(end 103.574342 -245.86311)
		(stroke
			(width 0.508)
			(type default)
		)
		(layer "In8.Cu")
	)
	(gr_line
		(start 103.040942 -239.43691)
		(end 103.040942 -245.32971)
		(stroke
			(width 0.508)
			(type default)
		)
		(layer "In8.Cu")
	)
	(gr_line
		(start 103.091742 -260.51891)
		(end 102.532942 -261.07771)
		(stroke
			(width 0.508)
			(type default)
		)
		(layer "In8.Cu")
	)
	(gr_line
		(start 103.091742 -260.51891)
		(end 103.091742 -258.45897)
		(stroke
			(width 0.508)
			(type default)
		)
		(layer "In8.Cu")
	)
	(gr_line
		(start 103.091742 -258.45897)
		(end 102.79888 -258.166108)
		(stroke
			(width 0.508)
			(type default)
		)
		(layer "In8.Cu")
	)
	(gr_line
		(start 103.091742 -257.134868)
		(end 103.091742 -256.27711)
		(stroke
			(width 0.508)
			(type default)
		)
		(layer "In8.Cu")
	)
	(gr_line
		(start 103.091742 -248.50471)
		(end 103.091742 -256.27711)
		(stroke
			(width 0.508)
			(type default)
		)
		(layer "In8.Cu")
	)
	(gr_line
		(start 103.156766 -256.890774)
		(end 103.485696 -256.561844)
		(stroke
			(width 0.508)
			(type default)
		)
		(layer "In8.Cu")
	)
	(gr_line
		(start 103.480362 -256.402332)
		(end 103.151432 -256.073402)
		(stroke
			(width 0.508)
			(type default)
		)
		(layer "In8.Cu")
	)
	(gr_line
		(start 103.548942 -256.48031)
		(end 103.294942 -256.48031)
		(stroke
			(width 0.508)
			(type default)
		)
		(layer "In8.Cu")
	)
	(gr_line
		(start 103.548942 -256.48031)
		(end 104.742742 -256.48031)
		(stroke
			(width 0.508)
			(type default)
		)
		(layer "In8.Cu")
	)
	(gr_line
		(start 103.574342 -248.02211)
		(end 103.091742 -248.50471)
		(stroke
			(width 0.508)
			(type default)
		)
		(layer "In8.Cu")
	)
	(gr_line
		(start 103.574342 -245.86311)
		(end 104.793542 -245.86311)
		(stroke
			(width 0.508)
			(type default)
		)
		(layer "In8.Cu")
	)
	(gr_line
		(start 104.20096 -261.592568)
		(end 104.20096 -261.163308)
		(stroke
			(width 0.254)
			(type default)
		)
		(layer "In8.Cu")
	)
	(gr_line
		(start 104.20096 -261.163308)
		(end 104.591358 -260.77291)
		(stroke
			(width 0.254)
			(type default)
		)
		(layer "In8.Cu")
	)
	(gr_line
		(start 104.366314 -288.168588)
		(end 103.48849 -289.046412)
		(stroke
			(width 0.508)
			(type default)
		)
		(layer "In8.Cu")
	)
	(gr_line
		(start 104.366314 -283.765752)
		(end 104.366314 -288.168588)
		(stroke
			(width 0.508)
			(type default)
		)
		(layer "In8.Cu")
	)
	(gr_line
		(start 104.387142 -238.09071)
		(end 103.040942 -239.43691)
		(stroke
			(width 0.508)
			(type default)
		)
		(layer "In8.Cu")
	)
	(gr_line
		(start 104.412542 -266.33551)
		(end 102.710742 -268.03731)
		(stroke
			(width 0.508)
			(type default)
		)
		(layer "In8.Cu")
	)
	(gr_line
		(start 104.412542 -266.33551)
		(end 104.412542 -262.01751)
		(stroke
			(width 0.508)
			(type default)
		)
		(layer "In8.Cu")
	)
	(gr_line
		(start 104.412542 -262.01751)
		(end 104.412542 -261.80415)
		(stroke
			(width 0.254)
			(type default)
		)
		(layer "In8.Cu")
	)
	(gr_line
		(start 104.412542 -261.80415)
		(end 104.20096 -261.592568)
		(stroke
			(width 0.254)
			(type default)
		)
		(layer "In8.Cu")
	)
	(gr_line
		(start 104.488742 -248.02211)
		(end 103.574342 -248.02211)
		(stroke
			(width 0.508)
			(type default)
		)
		(layer "In8.Cu")
	)
	(gr_line
		(start 104.591358 -260.77291)
		(end 105.530142 -260.77291)
		(stroke
			(width 0.254)
			(type default)
		)
		(layer "In8.Cu")
	)
	(gr_line
		(start 104.641142 -357.75265)
		(end 128.981962 -357.75265)
		(stroke
			(width 0.508)
			(type default)
		)
		(layer "In8.Cu")
	)
	(gr_line
		(start 104.742742 -256.48031)
		(end 105.250742 -256.98831)
		(stroke
			(width 0.508)
			(type default)
		)
		(layer "In8.Cu")
	)
	(gr_line
		(start 104.793542 -245.86311)
		(end 105.123742 -246.19331)
		(stroke
			(width 0.508)
			(type default)
		)
		(layer "In8.Cu")
	)
	(gr_line
		(start 105.123742 -247.38711)
		(end 104.488742 -248.02211)
		(stroke
			(width 0.508)
			(type default)
		)
		(layer "In8.Cu")
	)
	(gr_line
		(start 105.123742 -246.19331)
		(end 105.123742 -247.38711)
		(stroke
			(width 0.508)
			(type default)
		)
		(layer "In8.Cu")
	)
	(gr_line
		(start 105.250742 -260.49351)
		(end 105.571544 -260.814312)
		(stroke
			(width 0.508)
			(type default)
		)
		(layer "In8.Cu")
	)
	(gr_line
		(start 105.250742 -256.98831)
		(end 105.250742 -260.49351)
		(stroke
			(width 0.508)
			(type default)
		)
		(layer "In8.Cu")
	)
	(gr_line
		(start 105.348786 -336.030824)
		(end 106.154474 -336.836512)
		(stroke
			(width 0.254)
			(type default)
		)
		(layer "In8.Cu")
	)
	(gr_line
		(start 105.348786 -333.936594)
		(end 105.348786 -336.030824)
		(stroke
			(width 0.254)
			(type default)
		)
		(layer "In8.Cu")
	)
	(gr_line
		(start 105.484676 -333.800704)
		(end 105.348786 -333.936594)
		(stroke
			(width 0.254)
			(type default)
		)
		(layer "In8.Cu")
	)
	(gr_line
		(start 105.571544 -260.814312)
		(end 107.629198 -260.814312)
		(stroke
			(width 0.508)
			(type default)
		)
		(layer "In8.Cu")
	)
	(gr_line
		(start 105.722928 -339.667596)
		(end 101.923596 -339.667596)
		(stroke
			(width 0.254)
			(type default)
		)
		(layer "In8.Cu")
	)
	(gr_line
		(start 106.154474 -339.23605)
		(end 105.722928 -339.667596)
		(stroke
			(width 0.254)
			(type default)
		)
		(layer "In8.Cu")
	)
	(gr_line
		(start 106.154474 -336.836512)
		(end 106.154474 -339.23605)
		(stroke
			(width 0.254)
			(type default)
		)
		(layer "In8.Cu")
	)
	(gr_line
		(start 106.91495 -263.604756)
		(end 108.127038 -264.816844)
		(stroke
			(width 0.508)
			(type default)
		)
		(layer "In8.Cu")
	)
	(gr_line
		(start 106.91495 -262.118094)
		(end 106.91495 -263.604756)
		(stroke
			(width 0.508)
			(type default)
		)
		(layer "In8.Cu")
	)
	(gr_line
		(start 107.249214 -261.78383)
		(end 106.91495 -262.118094)
		(stroke
			(width 0.508)
			(type default)
		)
		(layer "In8.Cu")
	)
	(gr_line
		(start 107.557316 -261.78383)
		(end 107.249214 -261.78383)
		(stroke
			(width 0.508)
			(type default)
		)
		(layer "In8.Cu")
	)
	(gr_line
		(start 107.629198 -260.814312)
		(end 107.89793 -261.083044)
		(stroke
			(width 0.508)
			(type default)
		)
		(layer "In8.Cu")
	)
	(gr_line
		(start 107.89793 -261.443216)
		(end 107.557316 -261.78383)
		(stroke
			(width 0.508)
			(type default)
		)
		(layer "In8.Cu")
	)
	(gr_line
		(start 107.89793 -261.083044)
		(end 107.89793 -261.443216)
		(stroke
			(width 0.508)
			(type default)
		)
		(layer "In8.Cu")
	)
	(gr_line
		(start 108.127038 -280.005028)
		(end 104.366314 -283.765752)
		(stroke
			(width 0.508)
			(type default)
		)
		(layer "In8.Cu")
	)
	(gr_line
		(start 108.127038 -264.816844)
		(end 108.127038 -280.005028)
		(stroke
			(width 0.508)
			(type default)
		)
		(layer "In8.Cu")
	)
	(gr_line
		(start 109.00537 -338.589366)
		(end 109.00537 -337.58124)
		(stroke
			(width 0.254)
			(type default)
		)
		(layer "In8.Cu")
	)
	(gr_line
		(start 109.00537 -337.58124)
		(end 109.2581 -337.32851)
		(stroke
			(width 0.254)
			(type default)
		)
		(layer "In8.Cu")
	)
	(gr_line
		(start 109.073442 -333.800704)
		(end 105.484676 -333.800704)
		(stroke
			(width 0.254)
			(type default)
		)
		(layer "In8.Cu")
	)
	(gr_line
		(start 109.2581 -337.32851)
		(end 109.2581 -333.985362)
		(stroke
			(width 0.254)
			(type default)
		)
		(layer "In8.Cu")
	)
	(gr_line
		(start 109.2581 -333.985362)
		(end 109.073442 -333.800704)
		(stroke
			(width 0.254)
			(type default)
		)
		(layer "In8.Cu")
	)
	(gr_line
		(start 109.360716 -130.114802)
		(end 40.442642 -130.114802)
		(stroke
			(width 0.508)
			(type default)
		)
		(layer "In8.Cu")
	)
	(gr_line
		(start 109.360716 -130.114802)
		(end 211.767166 -130.114802)
		(stroke
			(width 0.508)
			(type default)
		)
		(layer "In8.Cu")
	)
	(gr_line
		(start 110.059978 -339.643974)
		(end 109.00537 -338.589366)
		(stroke
			(width 0.254)
			(type default)
		)
		(layer "In8.Cu")
	)
	(gr_line
		(start 113.530634 -336.00898)
		(end 114.17554 -336.653886)
		(stroke
			(width 0.254)
			(type default)
		)
		(layer "In8.Cu")
	)
	(gr_line
		(start 113.530634 -333.912972)
		(end 113.530634 -336.00898)
		(stroke
			(width 0.254)
			(type default)
		)
		(layer "In8.Cu")
	)
	(gr_line
		(start 113.64214 -333.801466)
		(end 113.530634 -333.912972)
		(stroke
			(width 0.254)
			(type default)
		)
		(layer "In8.Cu")
	)
	(gr_line
		(start 113.672874 -349.801942)
		(end 115.75542 -351.884488)
		(stroke
			(width 0.508)
			(type default)
		)
		(layer "In8.Cu")
	)
	(gr_line
		(start 113.720118 -339.643974)
		(end 110.059978 -339.643974)
		(stroke
			(width 0.254)
			(type default)
		)
		(layer "In8.Cu")
	)
	(gr_line
		(start 114.17554 -339.188552)
		(end 113.720118 -339.643974)
		(stroke
			(width 0.254)
			(type default)
		)
		(layer "In8.Cu")
	)
	(gr_line
		(start 114.17554 -336.653886)
		(end 114.17554 -339.188552)
		(stroke
			(width 0.254)
			(type default)
		)
		(layer "In8.Cu")
	)
	(gr_line
		(start 115.334542 -238.09071)
		(end 104.387142 -238.09071)
		(stroke
			(width 0.508)
			(type default)
		)
		(layer "In8.Cu")
	)
	(gr_line
		(start 115.359942 -227.72751)
		(end 115.359942 -218.46413)
		(stroke
			(width 0.508)
			(type default)
		)
		(layer "In8.Cu")
	)
	(gr_line
		(start 115.359942 -227.72751)
		(end 127.243078 -239.610646)
		(stroke
			(width 0.508)
			(type default)
		)
		(layer "In8.Cu")
	)
	(gr_line
		(start 115.359942 -211.048854)
		(end 115.359942 -218.46413)
		(stroke
			(width 0.508)
			(type default)
		)
		(layer "In8.Cu")
	)
	(gr_line
		(start 115.359942 -195.59524)
		(end 80.00365 -160.238948)
		(stroke
			(width 0.508)
			(type default)
		)
		(layer "In8.Cu")
	)
	(gr_line
		(start 115.359942 -195.59524)
		(end 115.359942 -211.048854)
		(stroke
			(width 0.508)
			(type default)
		)
		(layer "In8.Cu")
	)
	(gr_line
		(start 115.75542 -351.884488)
		(end 120.08358 -351.884488)
		(stroke
			(width 0.508)
			(type default)
		)
		(layer "In8.Cu")
	)
	(gr_line
		(start 115.842542 -240.02111)
		(end 115.842542 -238.59871)
		(stroke
			(width 0.508)
			(type default)
		)
		(layer "In8.Cu")
	)
	(gr_line
		(start 115.842542 -238.59871)
		(end 115.334542 -238.09071)
		(stroke
			(width 0.508)
			(type default)
		)
		(layer "In8.Cu")
	)
	(gr_line
		(start 116.020342 -279.08631)
		(end 116.020342 -261.17931)
		(stroke
			(width 0.508)
			(type default)
		)
		(layer "In8.Cu")
	)
	(gr_line
		(start 116.020342 -261.17931)
		(end 116.680742 -260.51891)
		(stroke
			(width 0.508)
			(type default)
		)
		(layer "In8.Cu")
	)
	(gr_line
		(start 116.680742 -260.51891)
		(end 120.668542 -260.51891)
		(stroke
			(width 0.508)
			(type default)
		)
		(layer "In8.Cu")
	)
	(gr_line
		(start 117.22608 -333.801466)
		(end 113.64214 -333.801466)
		(stroke
			(width 0.254)
			(type default)
		)
		(layer "In8.Cu")
	)
	(gr_line
		(start 117.375686 -338.88045)
		(end 117.375686 -333.951072)
		(stroke
			(width 0.254)
			(type default)
		)
		(layer "In8.Cu")
	)
	(gr_line
		(start 117.375686 -333.951072)
		(end 117.22608 -333.801466)
		(stroke
			(width 0.254)
			(type default)
		)
		(layer "In8.Cu")
	)
	(gr_line
		(start 117.747542 -241.92611)
		(end 115.842542 -240.02111)
		(stroke
			(width 0.508)
			(type default)
		)
		(layer "In8.Cu")
	)
	(gr_line
		(start 118.3005 -339.805264)
		(end 117.375686 -338.88045)
		(stroke
			(width 0.254)
			(type default)
		)
		(layer "In8.Cu")
	)
	(gr_line
		(start 118.618 -246.835168)
		(end 118.618 -245.068852)
		(stroke
			(width 0.508)
			(type default)
		)
		(layer "In8.Cu")
	)
	(gr_line
		(start 118.618 -245.068852)
		(end 120.084342 -243.60251)
		(stroke
			(width 0.508)
			(type default)
		)
		(layer "In8.Cu")
	)
	(gr_line
		(start 118.661942 -270.06931)
		(end 118.661942 -260.84911)
		(stroke
			(width 0.254)
			(type default)
		)
		(layer "In8.Cu")
	)
	(gr_line
		(start 118.661942 -260.84911)
		(end 118.407942 -260.59511)
		(stroke
			(width 0.254)
			(type default)
		)
		(layer "In8.Cu")
	)
	(gr_line
		(start 118.92788 -260.632448)
		(end 118.67388 -260.886448)
		(stroke
			(width 0.254)
			(type default)
		)
		(layer "In8.Cu")
	)
	(gr_line
		(start 119.423942 -270.83131)
		(end 118.661942 -270.06931)
		(stroke
			(width 0.254)
			(type default)
		)
		(layer "In8.Cu")
	)
	(gr_line
		(start 120.08358 -351.884488)
		(end 121.783348 -350.18472)
		(stroke
			(width 0.508)
			(type default)
		)
		(layer "In8.Cu")
	)
	(gr_line
		(start 120.084342 -243.60251)
		(end 120.744742 -243.60251)
		(stroke
			(width 0.508)
			(type default)
		)
		(layer "In8.Cu")
	)
	(gr_line
		(start 120.338342 -270.83131)
		(end 119.423942 -270.83131)
		(stroke
			(width 0.254)
			(type default)
		)
		(layer "In8.Cu")
	)
	(gr_line
		(start 120.465342 -241.92611)
		(end 117.747542 -241.92611)
		(stroke
			(width 0.508)
			(type default)
		)
		(layer "In8.Cu")
	)
	(gr_line
		(start 120.668542 -260.51891)
		(end 121.100342 -260.08711)
		(stroke
			(width 0.508)
			(type default)
		)
		(layer "In8.Cu")
	)
	(gr_line
		(start 120.744742 -243.60251)
		(end 121.024142 -243.32311)
		(stroke
			(width 0.508)
			(type default)
		)
		(layer "In8.Cu")
	)
	(gr_line
		(start 121.024142 -243.32311)
		(end 121.024142 -242.48491)
		(stroke
			(width 0.508)
			(type default)
		)
		(layer "In8.Cu")
	)
	(gr_line
		(start 121.024142 -242.48491)
		(end 120.465342 -241.92611)
		(stroke
			(width 0.508)
			(type default)
		)
		(layer "In8.Cu")
	)
	(gr_line
		(start 121.100342 -260.08711)
		(end 121.100342 -249.31751)
		(stroke
			(width 0.508)
			(type default)
		)
		(layer "In8.Cu")
	)
	(gr_line
		(start 121.100342 -260.08711)
		(end 121.481342 -260.46811)
		(stroke
			(width 0.254)
			(type default)
		)
		(layer "In8.Cu")
	)
	(gr_line
		(start 121.100342 -249.31751)
		(end 118.618 -246.835168)
		(stroke
			(width 0.508)
			(type default)
		)
		(layer "In8.Cu")
	)
	(gr_line
		(start 121.481342 -261.73811)
		(end 121.786142 -262.04291)
		(stroke
			(width 0.254)
			(type default)
		)
		(layer "In8.Cu")
	)
	(gr_line
		(start 121.481342 -260.46811)
		(end 121.481342 -261.73811)
		(stroke
			(width 0.254)
			(type default)
		)
		(layer "In8.Cu")
	)
	(gr_line
		(start 121.672604 -336.047334)
		(end 122.38101 -336.75574)
		(stroke
			(width 0.254)
			(type default)
		)
		(layer "In8.Cu")
	)
	(gr_line
		(start 121.672604 -333.912972)
		(end 121.672604 -336.047334)
		(stroke
			(width 0.254)
			(type default)
		)
		(layer "In8.Cu")
	)
	(gr_line
		(start 121.722896 -289.031172)
		(end 116.020342 -279.08631)
		(stroke
			(width 0.508)
			(type default)
		)
		(layer "In8.Cu")
	)
	(gr_line
		(start 121.76252 -289.070796)
		(end 121.722896 -289.031172)
		(stroke
			(width 0.508)
			(type default)
		)
		(layer "In8.Cu")
	)
	(gr_line
		(start 121.783348 -350.18472)
		(end 139.706096 -350.18472)
		(stroke
			(width 0.508)
			(type default)
		)
		(layer "In8.Cu")
	)
	(gr_line
		(start 121.785126 -333.80045)
		(end 121.672604 -333.912972)
		(stroke
			(width 0.254)
			(type default)
		)
		(layer "In8.Cu")
	)
	(gr_line
		(start 121.786142 -262.04291)
		(end 122.040142 -262.04291)
		(stroke
			(width 0.254)
			(type default)
		)
		(layer "In8.Cu")
	)
	(gr_line
		(start 121.859802 -339.805264)
		(end 118.3005 -339.805264)
		(stroke
			(width 0.254)
			(type default)
		)
		(layer "In8.Cu")
	)
	(gr_line
		(start 122.38101 -339.284056)
		(end 121.859802 -339.805264)
		(stroke
			(width 0.254)
			(type default)
		)
		(layer "In8.Cu")
	)
	(gr_line
		(start 122.38101 -336.75574)
		(end 122.38101 -339.284056)
		(stroke
			(width 0.254)
			(type default)
		)
		(layer "In8.Cu")
	)
	(gr_line
		(start 124.102114 -11.780012)
		(end 83.70189 -11.780012)
		(stroke
			(width 3.048)
			(type default)
		)
		(layer "In8.Cu")
	)
	(gr_arc
		(start 124.102114 -11.780012)
		(mid 125.516321 -11.194223)
		(end 126.10211 -9.780016)
		(stroke
			(width 3.048)
			(type default)
		)
		(layer "In8.Cu")
	)
	(gr_line
		(start 125.062742 -322.97751)
		(end 93.261942 -322.97751)
		(stroke
			(width 0.508)
			(type default)
		)
		(layer "In8.Cu")
	)
	(gr_line
		(start 125.392688 -333.80045)
		(end 121.785126 -333.80045)
		(stroke
			(width 0.254)
			(type default)
		)
		(layer "In8.Cu")
	)
	(gr_line
		(start 125.551692 -342.469724)
		(end 125.551692 -333.959454)
		(stroke
			(width 0.254)
			(type default)
		)
		(layer "In8.Cu")
	)
	(gr_line
		(start 125.551692 -333.959454)
		(end 125.392688 -333.80045)
		(stroke
			(width 0.254)
			(type default)
		)
		(layer "In8.Cu")
	)
	(gr_line
		(start 125.723142 -324.98411)
		(end 125.723142 -323.63791)
		(stroke
			(width 0.508)
			(type default)
		)
		(layer "In8.Cu")
	)
	(gr_line
		(start 125.723142 -323.63791)
		(end 125.062742 -322.97751)
		(stroke
			(width 0.508)
			(type default)
		)
		(layer "In8.Cu")
	)
	(gr_line
		(start 126.10211 -6.279896)
		(end 126.10211 -9.780016)
		(stroke
			(width 3.048)
			(type default)
		)
		(layer "In8.Cu")
	)
	(gr_line
		(start 126.209298 -262.04291)
		(end 122.040142 -262.04291)
		(stroke
			(width 0.508)
			(type default)
		)
		(layer "In8.Cu")
	)
	(gr_line
		(start 126.297182 -343.215214)
		(end 125.551692 -342.469724)
		(stroke
			(width 0.254)
			(type default)
		)
		(layer "In8.Cu")
	)
	(gr_line
		(start 126.794768 -331.182218)
		(end 93.247464 -331.182218)
		(stroke
			(width 0.508)
			(type default)
		)
		(layer "In8.Cu")
	)
	(gr_arc
		(start 127.102108 -5.279898)
		(mid 126.395003 -5.572791)
		(end 126.10211 -6.279896)
		(stroke
			(width 3.048)
			(type default)
		)
		(layer "In8.Cu")
	)
	(gr_line
		(start 127.243078 -261.00913)
		(end 126.209298 -262.04291)
		(stroke
			(width 0.508)
			(type default)
		)
		(layer "In8.Cu")
	)
	(gr_line
		(start 127.243078 -239.610646)
		(end 127.243078 -261.00913)
		(stroke
			(width 0.508)
			(type default)
		)
		(layer "In8.Cu")
	)
	(gr_line
		(start 127.247142 -326.50811)
		(end 125.723142 -324.98411)
		(stroke
			(width 0.508)
			(type default)
		)
		(layer "In8.Cu")
	)
	(gr_line
		(start 127.260858 -333.971646)
		(end 127.260858 -331.648308)
		(stroke
			(width 0.508)
			(type default)
		)
		(layer "In8.Cu")
	)
	(gr_line
		(start 127.260858 -331.648308)
		(end 126.794768 -331.182218)
		(stroke
			(width 0.508)
			(type default)
		)
		(layer "In8.Cu")
	)
	(gr_line
		(start 127.628142 -225.44151)
		(end 129.228342 -227.04171)
		(stroke
			(width 0.508)
			(type default)
		)
		(layer "In8.Cu")
	)
	(gr_line
		(start 127.628142 -215.28151)
		(end 127.628142 -225.44151)
		(stroke
			(width 0.508)
			(type default)
		)
		(layer "In8.Cu")
	)
	(gr_line
		(start 127.83947 -334.550258)
		(end 127.260858 -333.971646)
		(stroke
			(width 0.508)
			(type default)
		)
		(layer "In8.Cu")
	)
	(gr_line
		(start 128.110742 -214.79891)
		(end 127.628142 -215.28151)
		(stroke
			(width 0.508)
			(type default)
		)
		(layer "In8.Cu")
	)
	(gr_line
		(start 128.981962 -357.75265)
		(end 132.81914 -361.589828)
		(stroke
			(width 0.508)
			(type default)
		)
		(layer "In8.Cu")
	)
	(gr_line
		(start 129.228342 -227.04171)
		(end 132.606542 -227.04171)
		(stroke
			(width 0.508)
			(type default)
		)
		(layer "In8.Cu")
	)
	(gr_line
		(start 129.803398 -343.215214)
		(end 126.297182 -343.215214)
		(stroke
			(width 0.254)
			(type default)
		)
		(layer "In8.Cu")
	)
	(gr_line
		(start 129.843784 -340.065868)
		(end 130.572256 -340.79434)
		(stroke
			(width 0.254)
			(type default)
		)
		(layer "In8.Cu")
	)
	(gr_line
		(start 129.843784 -337.277202)
		(end 129.843784 -340.065868)
		(stroke
			(width 0.254)
			(type default)
		)
		(layer "In8.Cu")
	)
	(gr_line
		(start 129.912872 -337.208114)
		(end 129.843784 -337.277202)
		(stroke
			(width 0.254)
			(type default)
		)
		(layer "In8.Cu")
	)
	(gr_line
		(start 130.572256 -342.446356)
		(end 129.803398 -343.215214)
		(stroke
			(width 0.254)
			(type default)
		)
		(layer "In8.Cu")
	)
	(gr_line
		(start 130.572256 -340.79434)
		(end 130.572256 -342.446356)
		(stroke
			(width 0.254)
			(type default)
		)
		(layer "In8.Cu")
	)
	(gr_line
		(start 131.438142 -326.50811)
		(end 127.247142 -326.50811)
		(stroke
			(width 0.508)
			(type default)
		)
		(layer "In8.Cu")
	)
	(gr_line
		(start 132.047742 -270.83131)
		(end 120.338342 -270.83131)
		(stroke
			(width 0.508)
			(type default)
		)
		(layer "In8.Cu")
	)
	(gr_line
		(start 132.606542 -227.04171)
		(end 135.88238 -230.317548)
		(stroke
			(width 0.508)
			(type default)
		)
		(layer "In8.Cu")
	)
	(gr_line
		(start 132.81914 -361.589828)
		(end 212.53196 -361.589828)
		(stroke
			(width 0.508)
			(type default)
		)
		(layer "In8.Cu")
	)
	(gr_line
		(start 133.551676 -337.208114)
		(end 129.912872 -337.208114)
		(stroke
			(width 0.254)
			(type default)
		)
		(layer "In8.Cu")
	)
	(gr_line
		(start 133.825742 -331.23251)
		(end 133.825742 -328.89571)
		(stroke
			(width 0.508)
			(type default)
		)
		(layer "In8.Cu")
	)
	(gr_line
		(start 133.825742 -328.89571)
		(end 131.438142 -326.50811)
		(stroke
			(width 0.508)
			(type default)
		)
		(layer "In8.Cu")
	)
	(gr_line
		(start 133.826758 -348.063058)
		(end 133.826758 -337.483196)
		(stroke
			(width 0.254)
			(type default)
		)
		(layer "In8.Cu")
	)
	(gr_line
		(start 133.826758 -337.483196)
		(end 133.551676 -337.208114)
		(stroke
			(width 0.254)
			(type default)
		)
		(layer "In8.Cu")
	)
	(gr_line
		(start 134.257542 -331.66431)
		(end 133.825742 -331.23251)
		(stroke
			(width 0.508)
			(type default)
		)
		(layer "In8.Cu")
	)
	(gr_line
		(start 134.257542 -331.66431)
		(end 148.007578 -331.66431)
		(stroke
			(width 0.508)
			(type default)
		)
		(layer "In8.Cu")
	)
	(gr_line
		(start 134.325106 -348.561406)
		(end 133.826758 -348.063058)
		(stroke
			(width 0.254)
			(type default)
		)
		(layer "In8.Cu")
	)
	(gr_line
		(start 134.34568 -334.550258)
		(end 127.83947 -334.550258)
		(stroke
			(width 0.508)
			(type default)
		)
		(layer "In8.Cu")
	)
	(gr_line
		(start 135.711438 -341.987378)
		(end 135.711438 -335.916016)
		(stroke
			(width 0.508)
			(type default)
		)
		(layer "In8.Cu")
	)
	(gr_line
		(start 135.711438 -335.916016)
		(end 134.34568 -334.550258)
		(stroke
			(width 0.508)
			(type default)
		)
		(layer "In8.Cu")
	)
	(gr_line
		(start 135.773922 -267.10513)
		(end 132.047742 -270.83131)
		(stroke
			(width 0.508)
			(type default)
		)
		(layer "In8.Cu")
	)
	(gr_line
		(start 135.88238 -230.317548)
		(end 138.733276 -230.317548)
		(stroke
			(width 0.508)
			(type default)
		)
		(layer "In8.Cu")
	)
	(gr_line
		(start 136.400794 -342.676734)
		(end 135.711438 -341.987378)
		(stroke
			(width 0.508)
			(type default)
		)
		(layer "In8.Cu")
	)
	(gr_line
		(start 137.448544 -289.070796)
		(end 121.76252 -289.070796)
		(stroke
			(width 0.508)
			(type default)
		)
		(layer "In8.Cu")
	)
	(gr_line
		(start 138.00455 -345.41714)
		(end 138.573764 -345.986354)
		(stroke
			(width 0.254)
			(type default)
		)
		(layer "In8.Cu")
	)
	(gr_line
		(start 138.00455 -342.86571)
		(end 138.00455 -345.41714)
		(stroke
			(width 0.254)
			(type default)
		)
		(layer "In8.Cu")
	)
	(gr_line
		(start 138.00963 -342.997536)
		(end 137.75563 -342.743536)
		(stroke
			(width 0.254)
			(type default)
		)
		(layer "In8.Cu")
	)
	(gr_line
		(start 138.00963 -342.9762)
		(end 138.255248 -342.730582)
		(stroke
			(width 0.254)
			(type default)
		)
		(layer "In8.Cu")
	)
	(gr_line
		(start 138.298682 -348.561406)
		(end 134.325106 -348.561406)
		(stroke
			(width 0.254)
			(type default)
		)
		(layer "In8.Cu")
	)
	(gr_line
		(start 138.380978 -267.10513)
		(end 135.773922 -267.10513)
		(stroke
			(width 0.508)
			(type default)
		)
		(layer "In8.Cu")
	)
	(gr_line
		(start 138.573764 -348.286324)
		(end 138.298682 -348.561406)
		(stroke
			(width 0.254)
			(type default)
		)
		(layer "In8.Cu")
	)
	(gr_line
		(start 138.573764 -345.986354)
		(end 138.573764 -348.286324)
		(stroke
			(width 0.254)
			(type default)
		)
		(layer "In8.Cu")
	)
	(gr_line
		(start 138.733276 -230.317548)
		(end 140.813536 -230.317548)
		(stroke
			(width 0.508)
			(type default)
		)
		(layer "In8.Cu")
	)
	(gr_line
		(start 139.706096 -350.18472)
		(end 143.200374 -346.690442)
		(stroke
			(width 0.508)
			(type default)
		)
		(layer "In8.Cu")
	)
	(gr_line
		(start 140.504418 -267.10513)
		(end 138.380978 -267.10513)
		(stroke
			(width 0.508)
			(type default)
		)
		(layer "In8.Cu")
	)
	(gr_line
		(start 140.813536 -230.317548)
		(end 141.637258 -231.14127)
		(stroke
			(width 0.508)
			(type default)
		)
		(layer "In8.Cu")
	)
	(gr_line
		(start 141.637258 -265.97229)
		(end 140.504418 -267.10513)
		(stroke
			(width 0.508)
			(type default)
		)
		(layer "In8.Cu")
	)
	(gr_line
		(start 141.637258 -231.14127)
		(end 141.637258 -265.97229)
		(stroke
			(width 0.508)
			(type default)
		)
		(layer "In8.Cu")
	)
	(gr_line
		(start 142.897352 -342.676734)
		(end 136.400794 -342.676734)
		(stroke
			(width 0.508)
			(type default)
		)
		(layer "In8.Cu")
	)
	(gr_line
		(start 143.200374 -346.690442)
		(end 143.200374 -342.979756)
		(stroke
			(width 0.508)
			(type default)
		)
		(layer "In8.Cu")
	)
	(gr_line
		(start 143.200374 -342.979756)
		(end 142.897352 -342.676734)
		(stroke
			(width 0.508)
			(type default)
		)
		(layer "In8.Cu")
	)
	(gr_line
		(start 144.875758 -331.14361)
		(end 144.455388 -331.56398)
		(stroke
			(width 0.508)
			(type default)
		)
		(layer "In8.Cu")
	)
	(gr_line
		(start 144.880838 -331.64145)
		(end 144.880838 -296.50309)
		(stroke
			(width 0.508)
			(type default)
		)
		(layer "In8.Cu")
	)
	(gr_line
		(start 144.880838 -296.50309)
		(end 137.448544 -289.070796)
		(stroke
			(width 0.508)
			(type default)
		)
		(layer "In8.Cu")
	)
	(gr_line
		(start 145.340578 -331.60843)
		(end 144.875758 -331.14361)
		(stroke
			(width 0.508)
			(type default)
		)
		(layer "In8.Cu")
	)
	(gr_line
		(start 148.007578 -331.66431)
		(end 148.624798 -332.28153)
		(stroke
			(width 0.508)
			(type default)
		)
		(layer "In8.Cu")
	)
	(gr_line
		(start 148.624798 -340.809326)
		(end 148.624798 -332.28153)
		(stroke
			(width 0.508)
			(type default)
		)
		(layer "In8.Cu")
	)
	(gr_line
		(start 149.83714 -342.021668)
		(end 148.624798 -340.809326)
		(stroke
			(width 0.508)
			(type default)
		)
		(layer "In8.Cu")
	)
	(gr_line
		(start 151.246078 -214.79383)
		(end 150.992078 -214.79383)
		(stroke
			(width 0.508)
			(type default)
		)
		(layer "In8.Cu")
	)
	(gr_line
		(start 152.596342 -192.94729)
		(end 98.148902 -138.49985)
		(stroke
			(width 0.508)
			(type default)
		)
		(layer "In8.Cu")
	)
	(gr_line
		(start 152.617678 -214.79891)
		(end 128.110742 -214.79891)
		(stroke
			(width 0.508)
			(type default)
		)
		(layer "In8.Cu")
	)
	(gr_line
		(start 152.6794 -194.528948)
		(end 152.6794 -192.94729)
		(stroke
			(width 0.508)
			(type default)
		)
		(layer "In8.Cu")
	)
	(gr_line
		(start 152.6794 -192.94729)
		(end 152.596342 -192.94729)
		(stroke
			(width 0.508)
			(type default)
		)
		(layer "In8.Cu")
	)
	(gr_line
		(start 152.6794 -192.94729)
		(end 216.315798 -192.94729)
		(stroke
			(width 0.508)
			(type default)
		)
		(layer "In8.Cu")
	)
	(gr_line
		(start 153.847038 -214.79383)
		(end 151.500078 -214.79383)
		(stroke
			(width 0.508)
			(type default)
		)
		(layer "In8.Cu")
	)
	(gr_line
		(start 154.29738 -31.384748)
		(end 97.61474 -31.384748)
		(stroke
			(width 0.508)
			(type default)
		)
		(layer "In8.Cu")
	)
	(gr_line
		(start 154.398218 -214.24265)
		(end 153.847038 -214.79383)
		(stroke
			(width 0.508)
			(type default)
		)
		(layer "In8.Cu")
	)
	(gr_line
		(start 154.398218 -214.24265)
		(end 154.398218 -196.247766)
		(stroke
			(width 0.508)
			(type default)
		)
		(layer "In8.Cu")
	)
	(gr_line
		(start 154.398218 -214.24265)
		(end 154.906218 -214.75065)
		(stroke
			(width 0.508)
			(type default)
		)
		(layer "In8.Cu")
	)
	(gr_line
		(start 154.398218 -196.247766)
		(end 152.6794 -194.528948)
		(stroke
			(width 0.508)
			(type default)
		)
		(layer "In8.Cu")
	)
	(gr_line
		(start 160.5788 -31.384748)
		(end 154.29738 -31.384748)
		(stroke
			(width 0.508)
			(type default)
		)
		(layer "In8.Cu")
	)
	(gr_line
		(start 161.671 -57.064148)
		(end 161.671 -32.476948)
		(stroke
			(width 0.508)
			(type default)
		)
		(layer "In8.Cu")
	)
	(gr_line
		(start 161.671 -32.476948)
		(end 160.5788 -31.384748)
		(stroke
			(width 0.508)
			(type default)
		)
		(layer "In8.Cu")
	)
	(gr_line
		(start 164.7444 -60.137548)
		(end 161.671 -57.064148)
		(stroke
			(width 0.508)
			(type default)
		)
		(layer "In8.Cu")
	)
	(gr_line
		(start 166.78148 -440.8678)
		(end 166.64686 -440.8678)
		(stroke
			(width 0.635)
			(type default)
		)
		(layer "In8.Cu")
	)
	(gr_line
		(start 167.59174 -440.05754)
		(end 166.78148 -440.8678)
		(stroke
			(width 0.635)
			(type default)
		)
		(layer "In8.Cu")
	)
	(gr_line
		(start 167.59174 -440.05754)
		(end 168.43248 -440.89828)
		(stroke
			(width 0.635)
			(type default)
		)
		(layer "In8.Cu")
	)
	(gr_line
		(start 167.59174 -416.88258)
		(end 167.59174 -440.05754)
		(stroke
			(width 0.635)
			(type default)
		)
		(layer "In8.Cu")
	)
	(gr_line
		(start 170.464988 -414.009332)
		(end 167.59174 -416.88258)
		(stroke
			(width 0.635)
			(type default)
		)
		(layer "In8.Cu")
	)
	(gr_line
		(start 180.581808 -214.79383)
		(end 153.847038 -214.79383)
		(stroke
			(width 0.508)
			(type default)
		)
		(layer "In8.Cu")
	)
	(gr_line
		(start 180.581808 -214.79383)
		(end 181.171342 -215.383364)
		(stroke
			(width 0.508)
			(type default)
		)
		(layer "In8.Cu")
	)
	(gr_line
		(start 180.847746 -215.059768)
		(end 180.581808 -214.79383)
		(stroke
			(width 0.508)
			(type default)
		)
		(layer "In8.Cu")
	)
	(gr_line
		(start 181.171342 -327.49871)
		(end 182.02148 -328.348848)
		(stroke
			(width 0.508)
			(type default)
		)
		(layer "In8.Cu")
	)
	(gr_line
		(start 181.171342 -326.500236)
		(end 181.171342 -327.49871)
		(stroke
			(width 0.508)
			(type default)
		)
		(layer "In8.Cu")
	)
	(gr_line
		(start 181.171342 -267.58011)
		(end 181.171342 -326.911208)
		(stroke
			(width 0.508)
			(type default)
		)
		(layer "In8.Cu")
	)
	(gr_line
		(start 181.171342 -215.383364)
		(end 181.171342 -267.58011)
		(stroke
			(width 0.508)
			(type default)
		)
		(layer "In8.Cu")
	)
	(gr_line
		(start 181.26202 -320.21145)
		(end 181.664356 -319.809114)
		(stroke
			(width 0.508)
			(type default)
		)
		(layer "In8.Cu")
	)
	(gr_line
		(start 181.635908 -319.809114)
		(end 181.26202 -319.435226)
		(stroke
			(width 0.508)
			(type default)
		)
		(layer "In8.Cu")
	)
	(gr_line
		(start 181.664356 -319.809114)
		(end 181.635908 -319.809114)
		(stroke
			(width 0.508)
			(type default)
		)
		(layer "In8.Cu")
	)
	(gr_line
		(start 181.664356 -319.809114)
		(end 197.5866 -319.809114)
		(stroke
			(width 0.508)
			(type default)
		)
		(layer "In8.Cu")
	)
	(gr_line
		(start 182.02148 -328.348848)
		(end 185.60034 -328.348848)
		(stroke
			(width 0.508)
			(type default)
		)
		(layer "In8.Cu")
	)
	(gr_line
		(start 184.879488 -406.620726)
		(end 185.209688 -406.950926)
		(stroke
			(width 0.635)
			(type default)
		)
		(layer "In8.Cu")
	)
	(gr_line
		(start 184.879488 -400.685254)
		(end 184.879488 -406.620726)
		(stroke
			(width 0.635)
			(type default)
		)
		(layer "In8.Cu")
	)
	(gr_line
		(start 185.006488 -414.009332)
		(end 170.464988 -414.009332)
		(stroke
			(width 0.635)
			(type default)
		)
		(layer "In8.Cu")
	)
	(gr_line
		(start 185.006488 -414.009332)
		(end 185.836052 -414.009332)
		(stroke
			(width 0.635)
			(type default)
		)
		(layer "In8.Cu")
	)
	(gr_line
		(start 185.006488 -413.179768)
		(end 185.006488 -412.921704)
		(stroke
			(width 0.635)
			(type default)
		)
		(layer "In8.Cu")
	)
	(gr_line
		(start 185.006488 -408.491182)
		(end 185.006488 -414.009332)
		(stroke
			(width 0.635)
			(type default)
		)
		(layer "In8.Cu")
	)
	(gr_line
		(start 185.166 -342.021668)
		(end 149.83714 -342.021668)
		(stroke
			(width 0.508)
			(type default)
		)
		(layer "In8.Cu")
	)
	(gr_line
		(start 185.209688 -408.287982)
		(end 185.006488 -408.491182)
		(stroke
			(width 0.635)
			(type default)
		)
		(layer "In8.Cu")
	)
	(gr_line
		(start 185.209688 -406.950926)
		(end 185.209688 -408.287982)
		(stroke
			(width 0.635)
			(type default)
		)
		(layer "In8.Cu")
	)
	(gr_line
		(start 185.60034 -328.348848)
		(end 186.3344 -329.082908)
		(stroke
			(width 0.508)
			(type default)
		)
		(layer "In8.Cu")
	)
	(gr_line
		(start 185.836052 -414.009332)
		(end 186.03722 -414.2105)
		(stroke
			(width 0.635)
			(type default)
		)
		(layer "In8.Cu")
	)
	(gr_line
		(start 186.3344 -340.853268)
		(end 185.166 -342.021668)
		(stroke
			(width 0.508)
			(type default)
		)
		(layer "In8.Cu")
	)
	(gr_line
		(start 186.3344 -329.082908)
		(end 186.3344 -340.853268)
		(stroke
			(width 0.508)
			(type default)
		)
		(layer "In8.Cu")
	)
	(gr_line
		(start 188.73343 -400.685254)
		(end 184.879488 -400.685254)
		(stroke
			(width 0.635)
			(type default)
		)
		(layer "In8.Cu")
	)
	(gr_line
		(start 188.93536 -403.657054)
		(end 188.93536 -400.890232)
		(stroke
			(width 0.635)
			(type default)
		)
		(layer "In8.Cu")
	)
	(gr_line
		(start 188.93536 -400.890232)
		(end 188.73343 -400.685254)
		(stroke
			(width 0.635)
			(type default)
		)
		(layer "In8.Cu")
	)
	(gr_line
		(start 189.11316 -403.834854)
		(end 188.93536 -403.657054)
		(stroke
			(width 0.635)
			(type default)
		)
		(layer "In8.Cu")
	)
	(gr_line
		(start 189.46876 -403.834854)
		(end 189.11316 -403.834854)
		(stroke
			(width 0.635)
			(type default)
		)
		(layer "In8.Cu")
	)
	(gr_line
		(start 189.680088 -404.477982)
		(end 189.680088 -404.046182)
		(stroke
			(width 0.635)
			(type default)
		)
		(layer "In8.Cu")
	)
	(gr_line
		(start 189.680088 -404.046182)
		(end 189.46876 -403.834854)
		(stroke
			(width 0.635)
			(type default)
		)
		(layer "In8.Cu")
	)
	(gr_line
		(start 190.870332 -405.66848)
		(end 189.680088 -404.477982)
		(stroke
			(width 0.635)
			(type default)
		)
		(layer "In8.Cu")
	)
	(gr_line
		(start 192.7225 -420.89578)
		(end 185.006488 -413.179768)
		(stroke
			(width 0.635)
			(type default)
		)
		(layer "In8.Cu")
	)
	(gr_line
		(start 193.701924 -5.279898)
		(end 127.102108 -5.279898)
		(stroke
			(width 3.048)
			(type default)
		)
		(layer "In8.Cu")
	)
	(gr_arc
		(start 194.505072 -441.989972)
		(mid 194.858535 -441.843563)
		(end 195.004944 -441.4901)
		(stroke
			(width 3.048)
			(type default)
		)
		(layer "In8.Cu")
	)
	(gr_line
		(start 194.701922 -9.780016)
		(end 194.701922 -6.279896)
		(stroke
			(width 3.048)
			(type default)
		)
		(layer "In8.Cu")
	)
	(gr_arc
		(start 194.701922 -9.780016)
		(mid 195.287714 -11.19421)
		(end 196.701918 -11.780012)
		(stroke
			(width 3.048)
			(type default)
		)
		(layer "In8.Cu")
	)
	(gr_arc
		(start 194.701922 -6.279896)
		(mid 194.409029 -5.572791)
		(end 193.701924 -5.279898)
		(stroke
			(width 3.048)
			(type default)
		)
		(layer "In8.Cu")
	)
	(gr_line
		(start 195.004944 -441.4901)
		(end 195.004944 -441.17006)
		(stroke
			(width 3.048)
			(type default)
		)
		(layer "In8.Cu")
	)
	(gr_arc
		(start 195.50507 -440.669934)
		(mid 195.151433 -440.816426)
		(end 195.004944 -441.17006)
		(stroke
			(width 3.048)
			(type default)
		)
		(layer "In8.Cu")
	)
	(gr_line
		(start 195.50507 -440.669934)
		(end 276.314916 -440.669934)
		(stroke
			(width 3.048)
			(type default)
		)
		(layer "In8.Cu")
	)
	(gr_line
		(start 196.969888 -405.66848)
		(end 190.870332 -405.66848)
		(stroke
			(width 0.635)
			(type default)
		)
		(layer "In8.Cu")
	)
	(gr_line
		(start 197.383908 -420.89578)
		(end 192.7225 -420.89578)
		(stroke
			(width 0.635)
			(type default)
		)
		(layer "In8.Cu")
	)
	(gr_line
		(start 198.15048 -404.487888)
		(end 196.969888 -405.66848)
		(stroke
			(width 0.635)
			(type default)
		)
		(layer "In8.Cu")
	)
	(gr_line
		(start 198.15048 -400.893788)
		(end 198.15048 -404.487888)
		(stroke
			(width 0.635)
			(type default)
		)
		(layer "In8.Cu")
	)
	(gr_line
		(start 198.341488 -400.70278)
		(end 198.15048 -400.893788)
		(stroke
			(width 0.635)
			(type default)
		)
		(layer "In8.Cu")
	)
	(gr_line
		(start 201.995532 -400.70278)
		(end 198.341488 -400.70278)
		(stroke
			(width 0.635)
			(type default)
		)
		(layer "In8.Cu")
	)
	(gr_line
		(start 202.19416 -404.462488)
		(end 202.19416 -400.901408)
		(stroke
			(width 0.635)
			(type default)
		)
		(layer "In8.Cu")
	)
	(gr_line
		(start 202.19416 -400.901408)
		(end 201.995532 -400.70278)
		(stroke
			(width 0.635)
			(type default)
		)
		(layer "In8.Cu")
	)
	(gr_line
		(start 202.380088 -407.607008)
		(end 202.380088 -404.648416)
		(stroke
			(width 0.635)
			(type default)
		)
		(layer "In8.Cu")
	)
	(gr_line
		(start 202.380088 -404.648416)
		(end 202.19416 -404.462488)
		(stroke
			(width 0.635)
			(type default)
		)
		(layer "In8.Cu")
	)
	(gr_line
		(start 204.16012 -409.38704)
		(end 202.380088 -407.607008)
		(stroke
			(width 0.635)
			(type default)
		)
		(layer "In8.Cu")
	)
	(gr_line
		(start 206.17434 -435.523132)
		(end 207.503268 -436.85206)
		(stroke
			(width 0.635)
			(type default)
		)
		(layer "In8.Cu")
	)
	(gr_line
		(start 206.17434 -429.686212)
		(end 197.383908 -420.89578)
		(stroke
			(width 0.635)
			(type default)
		)
		(layer "In8.Cu")
	)
	(gr_line
		(start 206.17434 -429.686212)
		(end 206.17434 -435.523132)
		(stroke
			(width 0.635)
			(type default)
		)
		(layer "In8.Cu")
	)
	(gr_line
		(start 206.545688 -409.38704)
		(end 204.16012 -409.38704)
		(stroke
			(width 0.635)
			(type default)
		)
		(layer "In8.Cu")
	)
	(gr_line
		(start 207.503268 -436.85206)
		(end 228.909372 -436.85206)
		(stroke
			(width 0.635)
			(type default)
		)
		(layer "In8.Cu")
	)
	(gr_line
		(start 208.628488 -407.30424)
		(end 206.545688 -409.38704)
		(stroke
			(width 0.635)
			(type default)
		)
		(layer "In8.Cu")
	)
	(gr_line
		(start 208.628488 -404.642828)
		(end 208.628488 -407.30424)
		(stroke
			(width 0.635)
			(type default)
		)
		(layer "In8.Cu")
	)
	(gr_line
		(start 208.81848 -404.452836)
		(end 208.628488 -404.642828)
		(stroke
			(width 0.635)
			(type default)
		)
		(layer "In8.Cu")
	)
	(gr_line
		(start 208.81848 -400.893788)
		(end 208.81848 -404.452836)
		(stroke
			(width 0.635)
			(type default)
		)
		(layer "In8.Cu")
	)
	(gr_line
		(start 209.009488 -400.70278)
		(end 208.81848 -400.893788)
		(stroke
			(width 0.635)
			(type default)
		)
		(layer "In8.Cu")
	)
	(gr_line
		(start 209.33664 -60.137548)
		(end 164.7444 -60.137548)
		(stroke
			(width 0.508)
			(type default)
		)
		(layer "In8.Cu")
	)
	(gr_line
		(start 210.62696 -74.336148)
		(end 210.62696 -61.427868)
		(stroke
			(width 0.508)
			(type default)
		)
		(layer "In8.Cu")
	)
	(gr_line
		(start 210.62696 -61.427868)
		(end 209.33664 -60.137548)
		(stroke
			(width 0.508)
			(type default)
		)
		(layer "In8.Cu")
	)
	(gr_line
		(start 211.767166 -130.114802)
		(end 223.09836 -118.783608)
		(stroke
			(width 0.508)
			(type default)
		)
		(layer "In8.Cu")
	)
	(gr_line
		(start 212.53196 -361.589828)
		(end 217.794078 -356.32771)
		(stroke
			(width 0.508)
			(type default)
		)
		(layer "In8.Cu")
	)
	(gr_line
		(start 212.668612 -400.70278)
		(end 209.009488 -400.70278)
		(stroke
			(width 0.635)
			(type default)
		)
		(layer "In8.Cu")
	)
	(gr_line
		(start 212.85962 -404.485348)
		(end 212.85962 -400.893788)
		(stroke
			(width 0.635)
			(type default)
		)
		(layer "In8.Cu")
	)
	(gr_line
		(start 212.85962 -400.893788)
		(end 212.668612 -400.70278)
		(stroke
			(width 0.635)
			(type default)
		)
		(layer "In8.Cu")
	)
	(gr_line
		(start 213.03742 -407.525728)
		(end 213.03742 -404.663148)
		(stroke
			(width 0.635)
			(type default)
		)
		(layer "In8.Cu")
	)
	(gr_line
		(start 213.03742 -404.663148)
		(end 212.85962 -404.485348)
		(stroke
			(width 0.635)
			(type default)
		)
		(layer "In8.Cu")
	)
	(gr_line
		(start 213.09076 -76.799948)
		(end 210.62696 -74.336148)
		(stroke
			(width 0.508)
			(type default)
		)
		(layer "In8.Cu")
	)
	(gr_line
		(start 214.794592 -409.2829)
		(end 213.03742 -407.525728)
		(stroke
			(width 0.635)
			(type default)
		)
		(layer "In8.Cu")
	)
	(gr_line
		(start 216.315798 -192.94729)
		(end 217.794078 -194.42557)
		(stroke
			(width 0.508)
			(type default)
		)
		(layer "In8.Cu")
	)
	(gr_line
		(start 217.272616 -409.2829)
		(end 214.794592 -409.2829)
		(stroke
			(width 0.635)
			(type default)
		)
		(layer "In8.Cu")
	)
	(gr_line
		(start 217.672158 -319.45453)
		(end 217.394028 -319.73266)
		(stroke
			(width 0.508)
			(type default)
		)
		(layer "In8.Cu")
	)
	(gr_line
		(start 217.678254 -319.809114)
		(end 197.5866 -319.809114)
		(stroke
			(width 0.508)
			(type default)
		)
		(layer "In8.Cu")
	)
	(gr_line
		(start 217.794078 -356.32771)
		(end 217.794078 -215.42883)
		(stroke
			(width 0.508)
			(type default)
		)
		(layer "In8.Cu")
	)
	(gr_line
		(start 217.794078 -319.69329)
		(end 217.678254 -319.809114)
		(stroke
			(width 0.508)
			(type default)
		)
		(layer "In8.Cu")
	)
	(gr_line
		(start 217.794078 -194.42557)
		(end 217.794078 -215.42883)
		(stroke
			(width 0.508)
			(type default)
		)
		(layer "In8.Cu")
	)
	(gr_line
		(start 219.296488 -407.259028)
		(end 217.272616 -409.2829)
		(stroke
			(width 0.635)
			(type default)
		)
		(layer "In8.Cu")
	)
	(gr_line
		(start 219.296488 -404.673308)
		(end 219.296488 -407.259028)
		(stroke
			(width 0.635)
			(type default)
		)
		(layer "In8.Cu")
	)
	(gr_line
		(start 219.47886 -404.490936)
		(end 219.296488 -404.673308)
		(stroke
			(width 0.635)
			(type default)
		)
		(layer "In8.Cu")
	)
	(gr_line
		(start 219.47886 -400.906488)
		(end 219.47886 -404.490936)
		(stroke
			(width 0.635)
			(type default)
		)
		(layer "In8.Cu")
	)
	(gr_line
		(start 219.682568 -400.70278)
		(end 219.47886 -400.906488)
		(stroke
			(width 0.635)
			(type default)
		)
		(layer "In8.Cu")
	)
	(gr_line
		(start 221.30004 -11.780012)
		(end 196.701918 -11.780012)
		(stroke
			(width 3.048)
			(type default)
		)
		(layer "In8.Cu")
	)
	(gr_line
		(start 223.09836 -118.783608)
		(end 240.219738 -118.783608)
		(stroke
			(width 0.508)
			(type default)
		)
		(layer "In8.Cu")
	)
	(gr_line
		(start 223.300036 -33.275016)
		(end 223.300036 -13.780008)
		(stroke
			(width 3.048)
			(type default)
		)
		(layer "In8.Cu")
	)
	(gr_arc
		(start 223.300036 -33.275016)
		(mid 223.885829 -34.689205)
		(end 225.300032 -35.275012)
		(stroke
			(width 3.048)
			(type default)
		)
		(layer "In8.Cu")
	)
	(gr_arc
		(start 223.300036 -13.780008)
		(mid 222.714251 -12.365797)
		(end 221.30004 -11.780012)
		(stroke
			(width 3.048)
			(type default)
		)
		(layer "In8.Cu")
	)
	(gr_line
		(start 223.323912 -400.70278)
		(end 219.682568 -400.70278)
		(stroke
			(width 0.635)
			(type default)
		)
		(layer "In8.Cu")
	)
	(gr_line
		(start 223.53524 -404.47976)
		(end 223.53524 -400.914108)
		(stroke
			(width 0.635)
			(type default)
		)
		(layer "In8.Cu")
	)
	(gr_line
		(start 223.53524 -400.914108)
		(end 223.323912 -400.70278)
		(stroke
			(width 0.635)
			(type default)
		)
		(layer "In8.Cu")
	)
	(gr_line
		(start 223.716088 -407.403808)
		(end 223.716088 -404.660608)
		(stroke
			(width 0.635)
			(type default)
		)
		(layer "In8.Cu")
	)
	(gr_line
		(start 223.716088 -404.660608)
		(end 223.53524 -404.47976)
		(stroke
			(width 0.635)
			(type default)
		)
		(layer "In8.Cu")
	)
	(gr_line
		(start 225.70694 -409.39466)
		(end 223.716088 -407.403808)
		(stroke
			(width 0.635)
			(type default)
		)
		(layer "In8.Cu")
	)
	(gr_line
		(start 227.935028 -409.39466)
		(end 225.70694 -409.39466)
		(stroke
			(width 0.635)
			(type default)
		)
		(layer "In8.Cu")
	)
	(gr_line
		(start 228.909372 -436.85206)
		(end 230.69804 -435.063392)
		(stroke
			(width 0.635)
			(type default)
		)
		(layer "In8.Cu")
	)
	(gr_line
		(start 229.939088 -407.3906)
		(end 227.935028 -409.39466)
		(stroke
			(width 0.635)
			(type default)
		)
		(layer "In8.Cu")
	)
	(gr_line
		(start 229.939088 -404.678388)
		(end 229.939088 -407.3906)
		(stroke
			(width 0.635)
			(type default)
		)
		(layer "In8.Cu")
	)
	(gr_line
		(start 230.14432 -404.473156)
		(end 229.939088 -404.678388)
		(stroke
			(width 0.635)
			(type default)
		)
		(layer "In8.Cu")
	)
	(gr_line
		(start 230.14432 -400.901408)
		(end 230.14432 -404.473156)
		(stroke
			(width 0.635)
			(type default)
		)
		(layer "In8.Cu")
	)
	(gr_line
		(start 230.345488 -400.70024)
		(end 230.14432 -400.901408)
		(stroke
			(width 0.635)
			(type default)
		)
		(layer "In8.Cu")
	)
	(gr_line
		(start 230.69804 -423.4688)
		(end 230.69804 -435.063392)
		(stroke
			(width 0.635)
			(type default)
		)
		(layer "In8.Cu")
	)
	(gr_line
		(start 233.20756 -420.95928)
		(end 230.69804 -423.4688)
		(stroke
			(width 0.635)
			(type default)
		)
		(layer "In8.Cu")
	)
	(gr_line
		(start 233.996992 -400.70024)
		(end 230.345488 -400.70024)
		(stroke
			(width 0.635)
			(type default)
		)
		(layer "In8.Cu")
	)
	(gr_line
		(start 234.19816 -404.477728)
		(end 234.19816 -400.901408)
		(stroke
			(width 0.635)
			(type default)
		)
		(layer "In8.Cu")
	)
	(gr_line
		(start 234.19816 -400.901408)
		(end 233.996992 -400.70024)
		(stroke
			(width 0.635)
			(type default)
		)
		(layer "In8.Cu")
	)
	(gr_line
		(start 235.520992 -405.80056)
		(end 234.19816 -404.477728)
		(stroke
			(width 0.635)
			(type default)
		)
		(layer "In8.Cu")
	)
	(gr_line
		(start 237.746032 -405.80056)
		(end 235.520992 -405.80056)
		(stroke
			(width 0.635)
			(type default)
		)
		(layer "In8.Cu")
	)
	(gr_line
		(start 239.10036 -406.737312)
		(end 238.682784 -406.737312)
		(stroke
			(width 0.635)
			(type default)
		)
		(layer "In8.Cu")
	)
	(gr_line
		(start 239.3315 -406.506172)
		(end 239.10036 -406.737312)
		(stroke
			(width 0.635)
			(type default)
		)
		(layer "In8.Cu")
	)
	(gr_arc
		(start 239.3315 -406.506172)
		(mid 239.359619 -406.647264)
		(end 239.439704 -406.766776)
		(stroke
			(width 0.635)
			(type default)
		)
		(layer "In8.Cu")
	)
	(gr_line
		(start 239.3315 -397.839946)
		(end 239.3315 -406.506172)
		(stroke
			(width 0.635)
			(type default)
		)
		(layer "In8.Cu")
	)
	(gr_line
		(start 239.387634 -397.701516)
		(end 239.3315 -397.839946)
		(stroke
			(width 0.635)
			(type default)
		)
		(layer "In8.Cu")
	)
	(gr_line
		(start 239.439704 -406.766776)
		(end 239.663224 -406.990296)
		(stroke
			(width 0.635)
			(type default)
		)
		(layer "In8.Cu")
	)
	(gr_line
		(start 239.441482 -397.649446)
		(end 239.387634 -397.701516)
		(stroke
			(width 0.635)
			(type default)
		)
		(layer "In8.Cu")
	)
	(gr_arc
		(start 239.663224 -406.990296)
		(mid 239.782747 -407.070378)
		(end 239.923828 -407.0985)
		(stroke
			(width 0.635)
			(type default)
		)
		(layer "In8.Cu")
	)
	(gr_line
		(start 239.699292 -407.75382)
		(end 237.746032 -405.80056)
		(stroke
			(width 0.635)
			(type default)
		)
		(layer "In8.Cu")
	)
	(gr_line
		(start 239.699292 -407.75382)
		(end 240.057432 -407.39568)
		(stroke
			(width 0.635)
			(type default)
		)
		(layer "In8.Cu")
	)
	(gr_line
		(start 239.917224 -397.173704)
		(end 239.441482 -397.649446)
		(stroke
			(width 0.635)
			(type default)
		)
		(layer "In8.Cu")
	)
	(gr_line
		(start 239.923828 -407.0985)
		(end 273.791172 -407.0985)
		(stroke
			(width 0.635)
			(type default)
		)
		(layer "In8.Cu")
	)
	(gr_line
		(start 240.057432 -407.39568)
		(end 273.646392 -407.39568)
		(stroke
			(width 0.635)
			(type default)
		)
		(layer "In8.Cu")
	)
	(gr_arc
		(start 240.177828 -397.0655)
		(mid 240.036774 -397.093687)
		(end 239.917224 -397.173704)
		(stroke
			(width 0.635)
			(type default)
		)
		(layer "In8.Cu")
	)
	(gr_line
		(start 240.219738 -118.783608)
		(end 255.447038 -134.010908)
		(stroke
			(width 0.508)
			(type default)
		)
		(layer "In8.Cu")
	)
	(gr_line
		(start 253.798578 -354.563426)
		(end 253.798578 -318.210946)
		(stroke
			(width 0.508)
			(type default)
		)
		(layer "In8.Cu")
	)
	(gr_line
		(start 253.798578 -308.98465)
		(end 253.798578 -308.99481)
		(stroke
			(width 0.508)
			(type default)
		)
		(layer "In8.Cu")
	)
	(gr_line
		(start 253.798578 -219.17533)
		(end 253.798578 -318.210946)
		(stroke
			(width 0.508)
			(type default)
		)
		(layer "In8.Cu")
	)
	(gr_line
		(start 253.798578 -219.17533)
		(end 253.798578 -194.91071)
		(stroke
			(width 0.508)
			(type default)
		)
		(layer "In8.Cu")
	)
	(gr_line
		(start 253.798578 -194.91071)
		(end 254.575818 -194.13347)
		(stroke
			(width 0.508)
			(type default)
		)
		(layer "In8.Cu")
	)
	(gr_line
		(start 254.171958 -319.30975)
		(end 253.84252 -319.639188)
		(stroke
			(width 0.508)
			(type default)
		)
		(layer "In8.Cu")
	)
	(gr_line
		(start 254.216662 -319.30975)
		(end 253.89332 -318.986408)
		(stroke
			(width 0.508)
			(type default)
		)
		(layer "In8.Cu")
	)
	(gr_line
		(start 254.216662 -319.30975)
		(end 254.171958 -319.30975)
		(stroke
			(width 0.508)
			(type default)
		)
		(layer "In8.Cu")
	)
	(gr_line
		(start 254.575818 -194.13347)
		(end 318.817498 -194.13347)
		(stroke
			(width 0.508)
			(type default)
		)
		(layer "In8.Cu")
	)
	(gr_line
		(start 255.447038 -134.010908)
		(end 333.9084 -134.010908)
		(stroke
			(width 0.508)
			(type default)
		)
		(layer "In8.Cu")
	)
	(gr_line
		(start 256.800096 -35.275012)
		(end 225.300032 -35.275012)
		(stroke
			(width 3.048)
			(type default)
		)
		(layer "In8.Cu")
	)
	(gr_arc
		(start 256.800096 -35.275012)
		(mid 258.214315 -34.689229)
		(end 258.800092 -33.275016)
		(stroke
			(width 3.048)
			(type default)
		)
		(layer "In8.Cu")
	)
	(gr_line
		(start 258.800092 -13.780008)
		(end 258.800092 -33.275016)
		(stroke
			(width 3.048)
			(type default)
		)
		(layer "In8.Cu")
	)
	(gr_arc
		(start 260.800088 -11.780012)
		(mid 259.385877 -12.365797)
		(end 258.800092 -13.780008)
		(stroke
			(width 3.048)
			(type default)
		)
		(layer "In8.Cu")
	)
	(gr_line
		(start 261.680198 -362.445046)
		(end 253.798578 -354.563426)
		(stroke
			(width 0.508)
			(type default)
		)
		(layer "In8.Cu")
	)
	(gr_line
		(start 269.3035 -76.799948)
		(end 213.09076 -76.799948)
		(stroke
			(width 0.508)
			(type default)
		)
		(layer "In8.Cu")
	)
	(gr_line
		(start 269.3035 -76.799948)
		(end 271.8054 -76.799948)
		(stroke
			(width 0.508)
			(type default)
		)
		(layer "In8.Cu")
	)
	(gr_line
		(start 270.481552 -420.95928)
		(end 233.20756 -420.95928)
		(stroke
			(width 0.635)
			(type default)
		)
		(layer "In8.Cu")
	)
	(gr_line
		(start 271.8054 -76.799948)
		(end 271.8308 -76.799948)
		(stroke
			(width 0.508)
			(type default)
		)
		(layer "In8.Cu")
	)
	(gr_line
		(start 271.8054 -76.799948)
		(end 272.2372 -76.368148)
		(stroke
			(width 0.508)
			(type default)
		)
		(layer "In8.Cu")
	)
	(gr_line
		(start 271.8308 -76.799948)
		(end 272.19402 -77.163168)
		(stroke
			(width 0.508)
			(type default)
		)
		(layer "In8.Cu")
	)
	(gr_line
		(start 272.2372 -82.172048)
		(end 272.2372 -76.368148)
		(stroke
			(width 0.508)
			(type default)
		)
		(layer "In8.Cu")
	)
	(gr_line
		(start 272.2372 -76.368148)
		(end 272.2372 -76.317348)
		(stroke
			(width 0.508)
			(type default)
		)
		(layer "In8.Cu")
	)
	(gr_line
		(start 272.2372 -57.671208)
		(end 272.2372 -76.317348)
		(stroke
			(width 0.508)
			(type default)
		)
		(layer "In8.Cu")
	)
	(gr_line
		(start 273.646392 -407.39568)
		(end 274.051776 -406.990296)
		(stroke
			(width 0.635)
			(type default)
		)
		(layer "In8.Cu")
	)
	(gr_arc
		(start 273.791172 -407.0985)
		(mid 273.932264 -407.070381)
		(end 274.051776 -406.990296)
		(stroke
			(width 0.635)
			(type default)
		)
		(layer "In8.Cu")
	)
	(gr_line
		(start 273.99996 -55.908448)
		(end 272.2372 -57.671208)
		(stroke
			(width 0.508)
			(type default)
		)
		(layer "In8.Cu")
	)
	(gr_line
		(start 273.99996 -37.132768)
		(end 273.99996 -55.908448)
		(stroke
			(width 0.508)
			(type default)
		)
		(layer "In8.Cu")
	)
	(gr_line
		(start 274.03552 -83.970368)
		(end 272.2372 -82.172048)
		(stroke
			(width 0.508)
			(type default)
		)
		(layer "In8.Cu")
	)
	(gr_line
		(start 274.051776 -407.33472)
		(end 274.470876 -407.75382)
		(stroke
			(width 0.635)
			(type default)
		)
		(layer "In8.Cu")
	)
	(gr_line
		(start 274.051776 -406.990296)
		(end 274.051776 -407.33472)
		(stroke
			(width 0.635)
			(type default)
		)
		(layer "In8.Cu")
	)
	(gr_line
		(start 274.051776 -406.990296)
		(end 274.529296 -406.512776)
		(stroke
			(width 0.635)
			(type default)
		)
		(layer "In8.Cu")
	)
	(gr_line
		(start 274.117054 -397.0655)
		(end 240.177828 -397.0655)
		(stroke
			(width 0.635)
			(type default)
		)
		(layer "In8.Cu")
	)
	(gr_line
		(start 274.255484 -397.121634)
		(end 274.117054 -397.0655)
		(stroke
			(width 0.635)
			(type default)
		)
		(layer "In8.Cu")
	)
	(gr_line
		(start 274.307554 -397.175482)
		(end 274.255484 -397.121634)
		(stroke
			(width 0.635)
			(type default)
		)
		(layer "In8.Cu")
	)
	(gr_line
		(start 274.4216 -42.255948)
		(end 274.066 -42.611548)
		(stroke
			(width 0.508)
			(type default)
		)
		(layer "In8.Cu")
	)
	(gr_arc
		(start 274.529296 -406.512776)
		(mid 274.609378 -406.393253)
		(end 274.6375 -406.252172)
		(stroke
			(width 0.635)
			(type default)
		)
		(layer "In8.Cu")
	)
	(gr_line
		(start 274.529296 -397.397224)
		(end 274.307554 -397.175482)
		(stroke
			(width 0.635)
			(type default)
		)
		(layer "In8.Cu")
	)
	(gr_line
		(start 274.574 -42.255948)
		(end 274.0914 -41.773348)
		(stroke
			(width 0.508)
			(type default)
		)
		(layer "In8.Cu")
	)
	(gr_line
		(start 274.574 -42.255948)
		(end 274.4216 -42.255948)
		(stroke
			(width 0.508)
			(type default)
		)
		(layer "In8.Cu")
	)
	(gr_line
		(start 274.6375 -406.252172)
		(end 274.6375 -397.657828)
		(stroke
			(width 0.635)
			(type default)
		)
		(layer "In8.Cu")
	)
	(gr_arc
		(start 274.6375 -397.657828)
		(mid 274.609313 -397.516774)
		(end 274.529296 -397.397224)
		(stroke
			(width 0.635)
			(type default)
		)
		(layer "In8.Cu")
	)
	(gr_line
		(start 275.0693 -405.960072)
		(end 275.351748 -406.24252)
		(stroke
			(width 0.635)
			(type default)
		)
		(layer "In8.Cu")
	)
	(gr_line
		(start 275.0693 -397.505428)
		(end 275.0693 -405.960072)
		(stroke
			(width 0.635)
			(type default)
		)
		(layer "In8.Cu")
	)
	(gr_line
		(start 275.351748 -406.24252)
		(end 278.143208 -406.24252)
		(stroke
			(width 0.635)
			(type default)
		)
		(layer "In8.Cu")
	)
	(gr_line
		(start 275.509228 -397.0655)
		(end 275.0693 -397.505428)
		(stroke
			(width 0.635)
			(type default)
		)
		(layer "In8.Cu")
	)
	(gr_line
		(start 275.547074 -319.30975)
		(end 254.216662 -319.30975)
		(stroke
			(width 0.508)
			(type default)
		)
		(layer "In8.Cu")
	)
	(gr_line
		(start 275.547074 -319.30975)
		(end 284.336998 -319.30975)
		(stroke
			(width 0.508)
			(type default)
		)
		(layer "In8.Cu")
	)
	(gr_line
		(start 275.680932 -415.7599)
		(end 270.481552 -420.95928)
		(stroke
			(width 0.635)
			(type default)
		)
		(layer "In8.Cu")
	)
	(gr_arc
		(start 276.815042 -441.4901)
		(mid 276.961451 -441.843563)
		(end 277.314914 -441.989972)
		(stroke
			(width 3.048)
			(type default)
		)
		(layer "In8.Cu")
	)
	(gr_arc
		(start 276.815042 -441.17006)
		(mid 276.668545 -440.816438)
		(end 276.314916 -440.669934)
		(stroke
			(width 3.048)
			(type default)
		)
		(layer "In8.Cu")
	)
	(gr_line
		(start 276.815042 -441.17006)
		(end 276.815042 -441.4901)
		(stroke
			(width 3.048)
			(type default)
		)
		(layer "In8.Cu")
	)
	(gr_line
		(start 277.314914 -441.989972)
		(end 463.300064 -441.989972)
		(stroke
			(width 3.048)
			(type default)
		)
		(layer "In8.Cu")
	)
	(gr_line
		(start 278.143208 -406.24252)
		(end 278.145748 -406.23998)
		(stroke
			(width 0.635)
			(type default)
		)
		(layer "In8.Cu")
	)
	(gr_line
		(start 278.145748 -406.23998)
		(end 281.037792 -406.23998)
		(stroke
			(width 0.635)
			(type default)
		)
		(layer "In8.Cu")
	)
	(gr_line
		(start 279.927812 -415.7599)
		(end 275.680932 -415.7599)
		(stroke
			(width 0.635)
			(type default)
		)
		(layer "In8.Cu")
	)
	(gr_line
		(start 279.927812 -415.7599)
		(end 280.51506 -415.172652)
		(stroke
			(width 0.635)
			(type default)
		)
		(layer "In8.Cu")
	)
	(gr_line
		(start 280.100532 -407.75382)
		(end 239.699292 -407.75382)
		(stroke
			(width 0.635)
			(type default)
		)
		(layer "In8.Cu")
	)
	(gr_line
		(start 280.51506 -415.172652)
		(end 280.51506 -408.168348)
		(stroke
			(width 0.635)
			(type default)
		)
		(layer "In8.Cu")
	)
	(gr_line
		(start 280.51506 -415.172652)
		(end 309.099712 -415.172652)
		(stroke
			(width 0.635)
			(type default)
		)
		(layer "In8.Cu")
	)
	(gr_line
		(start 280.51506 -408.168348)
		(end 280.100532 -407.75382)
		(stroke
			(width 0.635)
			(type default)
		)
		(layer "In8.Cu")
	)
	(gr_line
		(start 280.83764 -397.0655)
		(end 275.509228 -397.0655)
		(stroke
			(width 0.635)
			(type default)
		)
		(layer "In8.Cu")
	)
	(gr_line
		(start 281.037792 -406.23998)
		(end 281.369008 -405.908764)
		(stroke
			(width 0.635)
			(type default)
		)
		(layer "In8.Cu")
	)
	(gr_line
		(start 281.369008 -405.908764)
		(end 281.369008 -397.596868)
		(stroke
			(width 0.635)
			(type default)
		)
		(layer "In8.Cu")
	)
	(gr_line
		(start 281.369008 -397.596868)
		(end 280.83764 -397.0655)
		(stroke
			(width 0.635)
			(type default)
		)
		(layer "In8.Cu")
	)
	(gr_line
		(start 284.1498 -351.173288)
		(end 284.1498 -319.662048)
		(stroke
			(width 0.508)
			(type default)
		)
		(layer "In8.Cu")
	)
	(gr_line
		(start 284.1498 -351.173288)
		(end 284.973776 -351.997264)
		(stroke
			(width 0.508)
			(type default)
		)
		(layer "In8.Cu")
	)
	(gr_line
		(start 284.1498 -319.662048)
		(end 284.1498 -351.173288)
		(stroke
			(width 0.508)
			(type default)
		)
		(layer "In8.Cu")
	)
	(gr_line
		(start 284.336998 -319.30975)
		(end 284.5816 -319.065148)
		(stroke
			(width 0.508)
			(type default)
		)
		(layer "In8.Cu")
	)
	(gr_line
		(start 284.5816 -319.065148)
		(end 284.5816 -218.785948)
		(stroke
			(width 0.508)
			(type default)
		)
		(layer "In8.Cu")
	)
	(gr_line
		(start 284.5816 -218.785948)
		(end 285.18231 -218.185238)
		(stroke
			(width 0.508)
			(type default)
		)
		(layer "In8.Cu")
	)
	(gr_line
		(start 284.94228 -351.965768)
		(end 284.1498 -351.173288)
		(stroke
			(width 0.508)
			(type default)
		)
		(layer "In8.Cu")
	)
	(gr_line
		(start 284.973776 -351.997264)
		(end 317.060072 -351.997264)
		(stroke
			(width 0.508)
			(type default)
		)
		(layer "In8.Cu")
	)
	(gr_line
		(start 285.18231 -218.185238)
		(end 342.552274 -218.185238)
		(stroke
			(width 0.508)
			(type default)
		)
		(layer "In8.Cu")
	)
	(gr_line
		(start 287.3756 -23.757128)
		(end 273.99996 -37.132768)
		(stroke
			(width 0.508)
			(type default)
		)
		(layer "In8.Cu")
	)
	(gr_line
		(start 302.0441 -351.965768)
		(end 284.94228 -351.965768)
		(stroke
			(width 0.508)
			(type default)
		)
		(layer "In8.Cu")
	)
	(gr_line
		(start 309.099712 -415.172652)
		(end 310.28386 -416.3568)
		(stroke
			(width 0.635)
			(type default)
		)
		(layer "In8.Cu")
	)
	(gr_line
		(start 310.28386 -440.17692)
		(end 309.3085 -441.15228)
		(stroke
			(width 0.635)
			(type default)
		)
		(layer "In8.Cu")
	)
	(gr_line
		(start 310.28386 -440.17692)
		(end 311.19826 -441.09132)
		(stroke
			(width 0.635)
			(type default)
		)
		(layer "In8.Cu")
	)
	(gr_line
		(start 310.28386 -416.3568)
		(end 310.28386 -440.17692)
		(stroke
			(width 0.635)
			(type default)
		)
		(layer "In8.Cu")
	)
	(gr_line
		(start 311.19826 -441.09132)
		(end 311.34812 -441.09132)
		(stroke
			(width 0.635)
			(type default)
		)
		(layer "In8.Cu")
	)
	(gr_line
		(start 317.060072 -351.997264)
		(end 318.396874 -350.660462)
		(stroke
			(width 0.508)
			(type default)
		)
		(layer "In8.Cu")
	)
	(gr_line
		(start 317.7794 -194.179952)
		(end 318.337438 -194.73799)
		(stroke
			(width 0.508)
			(type default)
		)
		(layer "In8.Cu")
	)
	(gr_line
		(start 318.290702 -217.515186)
		(end 317.636398 -218.16949)
		(stroke
			(width 0.508)
			(type default)
		)
		(layer "In8.Cu")
	)
	(gr_line
		(start 318.31788 -218.125548)
		(end 318.31788 -194.723512)
		(stroke
			(width 0.508)
			(type default)
		)
		(layer "In8.Cu")
	)
	(gr_line
		(start 318.31788 -185.969148)
		(end 318.31788 -194.723512)
		(stroke
			(width 0.508)
			(type default)
		)
		(layer "In8.Cu")
	)
	(gr_line
		(start 318.396874 -332.950058)
		(end 318.396874 -350.660462)
		(stroke
			(width 0.508)
			(type default)
		)
		(layer "In8.Cu")
	)
	(gr_line
		(start 318.84874 -332.498192)
		(end 318.396874 -332.950058)
		(stroke
			(width 0.508)
			(type default)
		)
		(layer "In8.Cu")
	)
	(gr_line
		(start 318.951102 -218.163394)
		(end 318.296798 -217.50909)
		(stroke
			(width 0.508)
			(type default)
		)
		(layer "In8.Cu")
	)
	(gr_line
		(start 322.475098 -332.47203)
		(end 322.475098 -296.86885)
		(stroke
			(width 0.508)
			(type default)
		)
		(layer "In8.Cu")
	)
	(gr_line
		(start 322.475098 -296.86885)
		(end 330.29779 -289.046158)
		(stroke
			(width 0.508)
			(type default)
		)
		(layer "In8.Cu")
	)
	(gr_line
		(start 322.492878 -331.99197)
		(end 322.038218 -332.44663)
		(stroke
			(width 0.508)
			(type default)
		)
		(layer "In8.Cu")
	)
	(gr_line
		(start 322.978018 -332.47711)
		(end 322.492878 -331.99197)
		(stroke
			(width 0.508)
			(type default)
		)
		(layer "In8.Cu")
	)
	(gr_line
		(start 324.205854 -347.587316)
		(end 325.875142 -349.256604)
		(stroke
			(width 0.508)
			(type default)
		)
		(layer "In8.Cu")
	)
	(gr_line
		(start 324.205854 -341.251286)
		(end 324.205854 -347.587316)
		(stroke
			(width 0.508)
			(type default)
		)
		(layer "In8.Cu")
	)
	(gr_line
		(start 325.153782 -340.303358)
		(end 324.205854 -341.251286)
		(stroke
			(width 0.508)
			(type default)
		)
		(layer "In8.Cu")
	)
	(gr_line
		(start 325.875142 -349.256604)
		(end 333.772764 -349.256604)
		(stroke
			(width 0.508)
			(type default)
		)
		(layer "In8.Cu")
	)
	(gr_line
		(start 327.54824 -83.970368)
		(end 274.03552 -83.970368)
		(stroke
			(width 0.508)
			(type default)
		)
		(layer "In8.Cu")
	)
	(gr_line
		(start 328.780902 -345.232228)
		(end 330.9493 -347.400626)
		(stroke
			(width 0.254)
			(type default)
		)
		(layer "In8.Cu")
	)
	(gr_line
		(start 328.780902 -343.194894)
		(end 328.780902 -345.232228)
		(stroke
			(width 0.254)
			(type default)
		)
		(layer "In8.Cu")
	)
	(gr_line
		(start 328.95159 -343.024206)
		(end 328.780902 -343.194894)
		(stroke
			(width 0.254)
			(type default)
		)
		(layer "In8.Cu")
	)
	(gr_line
		(start 329.2602 -82.258408)
		(end 327.54824 -83.970368)
		(stroke
			(width 0.508)
			(type default)
		)
		(layer "In8.Cu")
	)
	(gr_line
		(start 329.2602 -79.212948)
		(end 329.2602 -82.258408)
		(stroke
			(width 0.508)
			(type default)
		)
		(layer "In8.Cu")
	)
	(gr_line
		(start 329.2602 -79.212948)
		(end 329.2602 -57.648348)
		(stroke
			(width 0.508)
			(type default)
		)
		(layer "In8.Cu")
	)
	(gr_line
		(start 329.2602 -57.648348)
		(end 329.9714 -56.937148)
		(stroke
			(width 0.508)
			(type default)
		)
		(layer "In8.Cu")
	)
	(gr_line
		(start 329.845416 -332.498192)
		(end 318.84874 -332.498192)
		(stroke
			(width 0.508)
			(type default)
		)
		(layer "In8.Cu")
	)
	(gr_line
		(start 329.9714 -56.937148)
		(end 338.2264 -56.937148)
		(stroke
			(width 0.508)
			(type default)
		)
		(layer "In8.Cu")
	)
	(gr_line
		(start 330.29779 -289.046158)
		(end 351.428304 -289.046158)
		(stroke
			(width 0.508)
			(type default)
		)
		(layer "In8.Cu")
	)
	(gr_line
		(start 330.935838 -348.857062)
		(end 330.69022 -349.10268)
		(stroke
			(width 0.254)
			(type default)
		)
		(layer "In8.Cu")
	)
	(gr_line
		(start 330.935838 -348.835726)
		(end 331.189838 -349.089726)
		(stroke
			(width 0.254)
			(type default)
		)
		(layer "In8.Cu")
	)
	(gr_line
		(start 330.9493 -347.400626)
		(end 330.9493 -348.962726)
		(stroke
			(width 0.254)
			(type default)
		)
		(layer "In8.Cu")
	)
	(gr_line
		(start 331.063346 -340.303358)
		(end 325.153782 -340.303358)
		(stroke
			(width 0.508)
			(type default)
		)
		(layer "In8.Cu")
	)
	(gr_line
		(start 331.226922 -362.445046)
		(end 261.680198 -362.445046)
		(stroke
			(width 0.508)
			(type default)
		)
		(layer "In8.Cu")
	)
	(gr_line
		(start 331.442822 -339.923882)
		(end 331.063346 -340.303358)
		(stroke
			(width 0.508)
			(type default)
		)
		(layer "In8.Cu")
	)
	(gr_line
		(start 331.442822 -336.81289)
		(end 331.442822 -339.923882)
		(stroke
			(width 0.508)
			(type default)
		)
		(layer "In8.Cu")
	)
	(gr_line
		(start 332.608174 -343.024206)
		(end 328.95159 -343.024206)
		(stroke
			(width 0.254)
			(type default)
		)
		(layer "In8.Cu")
	)
	(gr_line
		(start 333.083662 -343.499694)
		(end 332.608174 -343.024206)
		(stroke
			(width 0.254)
			(type default)
		)
		(layer "In8.Cu")
	)
	(gr_line
		(start 333.690976 -334.564736)
		(end 331.442822 -336.81289)
		(stroke
			(width 0.508)
			(type default)
		)
		(layer "In8.Cu")
	)
	(gr_line
		(start 333.772764 -349.256604)
		(end 335.423256 -350.907096)
		(stroke
			(width 0.508)
			(type default)
		)
		(layer "In8.Cu")
	)
	(gr_line
		(start 333.9084 -134.010908)
		(end 364.47984 -103.439468)
		(stroke
			(width 0.508)
			(type default)
		)
		(layer "In8.Cu")
	)
	(gr_line
		(start 335.423256 -350.907096)
		(end 336.191606 -351.675446)
		(stroke
			(width 0.508)
			(type default)
		)
		(layer "In8.Cu")
	)
	(gr_line
		(start 336.191606 -351.675446)
		(end 343.787984 -351.675446)
		(stroke
			(width 0.508)
			(type default)
		)
		(layer "In8.Cu")
	)
	(gr_line
		(start 336.535776 -343.499694)
		(end 333.083662 -343.499694)
		(stroke
			(width 0.254)
			(type default)
		)
		(layer "In8.Cu")
	)
	(gr_line
		(start 336.600038 -325.74357)
		(end 329.845416 -332.498192)
		(stroke
			(width 0.508)
			(type default)
		)
		(layer "In8.Cu")
	)
	(gr_line
		(start 336.991452 -339.65388)
		(end 337.6549 -340.317328)
		(stroke
			(width 0.254)
			(type default)
		)
		(layer "In8.Cu")
	)
	(gr_line
		(start 336.991452 -337.306666)
		(end 336.991452 -339.65388)
		(stroke
			(width 0.254)
			(type default)
		)
		(layer "In8.Cu")
	)
	(gr_line
		(start 337.067144 -337.230974)
		(end 336.991452 -337.306666)
		(stroke
			(width 0.254)
			(type default)
		)
		(layer "In8.Cu")
	)
	(gr_line
		(start 337.467956 -260.925056)
		(end 337.467956 -232.578656)
		(stroke
			(width 0.508)
			(type default)
		)
		(layer "In8.Cu")
	)
	(gr_line
		(start 337.467956 -232.578656)
		(end 344.859356 -225.187256)
		(stroke
			(width 0.508)
			(type default)
		)
		(layer "In8.Cu")
	)
	(gr_line
		(start 337.6549 -342.38057)
		(end 336.535776 -343.499694)
		(stroke
			(width 0.254)
			(type default)
		)
		(layer "In8.Cu")
	)
	(gr_line
		(start 337.6549 -340.317328)
		(end 337.6549 -342.38057)
		(stroke
			(width 0.254)
			(type default)
		)
		(layer "In8.Cu")
	)
	(gr_line
		(start 337.880198 -355.79177)
		(end 331.226922 -362.445046)
		(stroke
			(width 0.508)
			(type default)
		)
		(layer "In8.Cu")
	)
	(gr_line
		(start 338.2264 -56.937148)
		(end 338.963 -56.200548)
		(stroke
			(width 0.508)
			(type default)
		)
		(layer "In8.Cu")
	)
	(gr_line
		(start 338.4804 -42.255948)
		(end 274.574 -42.255948)
		(stroke
			(width 0.508)
			(type default)
		)
		(layer "In8.Cu")
	)
	(gr_line
		(start 338.963 -56.200548)
		(end 338.963 -42.738548)
		(stroke
			(width 0.508)
			(type default)
		)
		(layer "In8.Cu")
	)
	(gr_line
		(start 338.963 -42.738548)
		(end 338.4804 -42.255948)
		(stroke
			(width 0.508)
			(type default)
		)
		(layer "In8.Cu")
	)
	(gr_line
		(start 339.056472 -334.564736)
		(end 333.690976 -334.564736)
		(stroke
			(width 0.508)
			(type default)
		)
		(layer "In8.Cu")
	)
	(gr_line
		(start 339.206078 -325.74357)
		(end 336.600038 -325.74357)
		(stroke
			(width 0.508)
			(type default)
		)
		(layer "In8.Cu")
	)
	(gr_line
		(start 339.403182 -334.218026)
		(end 339.056472 -334.564736)
		(stroke
			(width 0.508)
			(type default)
		)
		(layer "In8.Cu")
	)
	(gr_line
		(start 339.403182 -332.96606)
		(end 339.403182 -334.218026)
		(stroke
			(width 0.508)
			(type default)
		)
		(layer "In8.Cu")
	)
	(gr_line
		(start 340.614508 -337.230974)
		(end 337.067144 -337.230974)
		(stroke
			(width 0.254)
			(type default)
		)
		(layer "In8.Cu")
	)
	(gr_line
		(start 340.732872 -339.38337)
		(end 340.732872 -337.349338)
		(stroke
			(width 0.254)
			(type default)
		)
		(layer "In8.Cu")
	)
	(gr_line
		(start 340.732872 -337.349338)
		(end 340.614508 -337.230974)
		(stroke
			(width 0.254)
			(type default)
		)
		(layer "In8.Cu")
	)
	(gr_line
		(start 340.984332 -339.63483)
		(end 340.732872 -339.38337)
		(stroke
			(width 0.254)
			(type default)
		)
		(layer "In8.Cu")
	)
	(gr_line
		(start 341.187278 -331.181964)
		(end 339.403182 -332.96606)
		(stroke
			(width 0.508)
			(type default)
		)
		(layer "In8.Cu")
	)
	(gr_line
		(start 341.972392 -322.977256)
		(end 339.206078 -325.74357)
		(stroke
			(width 0.508)
			(type default)
		)
		(layer "In8.Cu")
	)
	(gr_line
		(start 342.552274 -218.185238)
		(end 344.859356 -220.49232)
		(stroke
			(width 0.508)
			(type default)
		)
		(layer "In8.Cu")
	)
	(gr_line
		(start 343.787984 -351.675446)
		(end 345.661742 -349.801688)
		(stroke
			(width 0.508)
			(type default)
		)
		(layer "In8.Cu")
	)
	(gr_line
		(start 344.579956 -268.037056)
		(end 337.467956 -260.925056)
		(stroke
			(width 0.508)
			(type default)
		)
		(layer "In8.Cu")
	)
	(gr_line
		(start 344.672412 -260.523736)
		(end 345.226132 -261.077456)
		(stroke
			(width 0.508)
			(type default)
		)
		(layer "In8.Cu")
	)
	(gr_line
		(start 344.672412 -234.938316)
		(end 344.672412 -260.523736)
		(stroke
			(width 0.508)
			(type default)
		)
		(layer "In8.Cu")
	)
	(gr_line
		(start 344.859356 -225.187256)
		(end 344.859356 -220.49232)
		(stroke
			(width 0.508)
			(type default)
		)
		(layer "In8.Cu")
	)
	(gr_line
		(start 345.129358 -335.993232)
		(end 346.055188 -336.919062)
		(stroke
			(width 0.254)
			(type default)
		)
		(layer "In8.Cu")
	)
	(gr_line
		(start 345.129358 -333.929482)
		(end 345.129358 -335.993232)
		(stroke
			(width 0.254)
			(type default)
		)
		(layer "In8.Cu")
	)
	(gr_line
		(start 345.256612 -333.802228)
		(end 345.129358 -333.929482)
		(stroke
			(width 0.254)
			(type default)
		)
		(layer "In8.Cu")
	)
	(gr_line
		(start 345.369388 -339.63483)
		(end 340.984332 -339.63483)
		(stroke
			(width 0.254)
			(type default)
		)
		(layer "In8.Cu")
	)
	(gr_line
		(start 345.661742 -349.801688)
		(end 361.442 -349.801688)
		(stroke
			(width 0.508)
			(type default)
		)
		(layer "In8.Cu")
	)
	(gr_line
		(start 346.055188 -338.94903)
		(end 345.369388 -339.63483)
		(stroke
			(width 0.254)
			(type default)
		)
		(layer "In8.Cu")
	)
	(gr_line
		(start 346.055188 -336.919062)
		(end 346.055188 -338.94903)
		(stroke
			(width 0.254)
			(type default)
		)
		(layer "In8.Cu")
	)
	(gr_line
		(start 347.547692 -355.79177)
		(end 337.880198 -355.79177)
		(stroke
			(width 0.508)
			(type default)
		)
		(layer "In8.Cu")
	)
	(gr_line
		(start 348.803976 -333.802228)
		(end 345.256612 -333.802228)
		(stroke
			(width 0.254)
			(type default)
		)
		(layer "In8.Cu")
	)
	(gr_line
		(start 348.932754 -338.736686)
		(end 348.932754 -333.931006)
		(stroke
			(width 0.254)
			(type default)
		)
		(layer "In8.Cu")
	)
	(gr_line
		(start 348.932754 -333.931006)
		(end 348.803976 -333.802228)
		(stroke
			(width 0.254)
			(type default)
		)
		(layer "In8.Cu")
	)
	(gr_line
		(start 349.133668 -219.08008)
		(end 349.133668 -189.34938)
		(stroke
			(width 0.508)
			(type default)
		)
		(layer "In8.Cu")
	)
	(gr_line
		(start 349.133668 -189.34938)
		(end 349.70212 -188.780928)
		(stroke
			(width 0.508)
			(type default)
		)
		(layer "In8.Cu")
	)
	(gr_line
		(start 349.86341 -339.667342)
		(end 348.932754 -338.736686)
		(stroke
			(width 0.254)
			(type default)
		)
		(layer "In8.Cu")
	)
	(gr_line
		(start 350.472756 -261.077456)
		(end 345.226132 -261.077456)
		(stroke
			(width 0.508)
			(type default)
		)
		(layer "In8.Cu")
	)
	(gr_line
		(start 350.650556 -268.037056)
		(end 344.579956 -268.037056)
		(stroke
			(width 0.508)
			(type default)
		)
		(layer "In8.Cu")
	)
	(gr_line
		(start 350.980756 -245.329456)
		(end 350.980756 -239.436656)
		(stroke
			(width 0.508)
			(type default)
		)
		(layer "In8.Cu")
	)
	(gr_line
		(start 350.980756 -239.436656)
		(end 352.326956 -238.090456)
		(stroke
			(width 0.508)
			(type default)
		)
		(layer "In8.Cu")
	)
	(gr_line
		(start 351.031556 -260.518656)
		(end 350.472756 -261.077456)
		(stroke
			(width 0.508)
			(type default)
		)
		(layer "In8.Cu")
	)
	(gr_line
		(start 351.031556 -256.276856)
		(end 351.031556 -260.518656)
		(stroke
			(width 0.508)
			(type default)
		)
		(layer "In8.Cu")
	)
	(gr_line
		(start 351.031556 -256.276856)
		(end 351.031556 -248.504456)
		(stroke
			(width 0.508)
			(type default)
		)
		(layer "In8.Cu")
	)
	(gr_line
		(start 351.031556 -248.504456)
		(end 351.514156 -248.021856)
		(stroke
			(width 0.508)
			(type default)
		)
		(layer "In8.Cu")
	)
	(gr_line
		(start 351.09658 -256.89052)
		(end 351.42551 -256.56159)
		(stroke
			(width 0.508)
			(type default)
		)
		(layer "In8.Cu")
	)
	(gr_line
		(start 351.420176 -256.402078)
		(end 351.091246 -256.073148)
		(stroke
			(width 0.508)
			(type default)
		)
		(layer "In8.Cu")
	)
	(gr_line
		(start 351.428304 -289.046158)
		(end 352.306128 -288.168334)
		(stroke
			(width 0.508)
			(type default)
		)
		(layer "In8.Cu")
	)
	(gr_line
		(start 351.488756 -256.480056)
		(end 351.234756 -256.480056)
		(stroke
			(width 0.508)
			(type default)
		)
		(layer "In8.Cu")
	)
	(gr_line
		(start 351.514156 -248.021856)
		(end 352.428556 -248.021856)
		(stroke
			(width 0.508)
			(type default)
		)
		(layer "In8.Cu")
	)
	(gr_line
		(start 351.514156 -245.862856)
		(end 350.980756 -245.329456)
		(stroke
			(width 0.508)
			(type default)
		)
		(layer "In8.Cu")
	)
	(gr_line
		(start 352.036634 -227.574094)
		(end 344.672412 -234.938316)
		(stroke
			(width 0.508)
			(type default)
		)
		(layer "In8.Cu")
	)
	(gr_line
		(start 352.036634 -226.91217)
		(end 352.036634 -227.574094)
		(stroke
			(width 0.508)
			(type default)
		)
		(layer "In8.Cu")
	)
	(gr_line
		(start 352.036634 -226.91217)
		(end 352.036634 -221.983046)
		(stroke
			(width 0.508)
			(type default)
		)
		(layer "In8.Cu")
	)
	(gr_line
		(start 352.036634 -221.983046)
		(end 349.133668 -219.08008)
		(stroke
			(width 0.508)
			(type default)
		)
		(layer "In8.Cu")
	)
	(gr_line
		(start 352.306128 -288.168334)
		(end 352.306128 -283.765498)
		(stroke
			(width 0.508)
			(type default)
		)
		(layer "In8.Cu")
	)
	(gr_line
		(start 352.306128 -283.765498)
		(end 356.066852 -280.004774)
		(stroke
			(width 0.508)
			(type default)
		)
		(layer "In8.Cu")
	)
	(gr_line
		(start 352.326956 -238.090456)
		(end 363.274356 -238.090456)
		(stroke
			(width 0.508)
			(type default)
		)
		(layer "In8.Cu")
	)
	(gr_line
		(start 352.352356 -266.335256)
		(end 350.650556 -268.037056)
		(stroke
			(width 0.508)
			(type default)
		)
		(layer "In8.Cu")
	)
	(gr_line
		(start 352.352356 -262.017256)
		(end 352.352356 -266.335256)
		(stroke
			(width 0.508)
			(type default)
		)
		(layer "In8.Cu")
	)
	(gr_line
		(start 352.352356 -261.306056)
		(end 352.352356 -262.017256)
		(stroke
			(width 0.254)
			(type default)
		)
		(layer "In8.Cu")
	)
	(gr_line
		(start 352.428556 -248.021856)
		(end 353.063556 -247.386856)
		(stroke
			(width 0.508)
			(type default)
		)
		(layer "In8.Cu")
	)
	(gr_line
		(start 352.682556 -256.480056)
		(end 351.488756 -256.480056)
		(stroke
			(width 0.508)
			(type default)
		)
		(layer "In8.Cu")
	)
	(gr_line
		(start 352.733356 -245.862856)
		(end 351.514156 -245.862856)
		(stroke
			(width 0.508)
			(type default)
		)
		(layer "In8.Cu")
	)
	(gr_line
		(start 352.817938 -260.84149)
		(end 353.122738 -260.53669)
		(stroke
			(width 0.254)
			(type default)
		)
		(layer "In8.Cu")
	)
	(gr_line
		(start 352.885756 -260.772656)
		(end 352.352356 -261.306056)
		(stroke
			(width 0.254)
			(type default)
		)
		(layer "In8.Cu")
	)
	(gr_line
		(start 353.063556 -247.386856)
		(end 353.063556 -246.193056)
		(stroke
			(width 0.508)
			(type default)
		)
		(layer "In8.Cu")
	)
	(gr_line
		(start 353.063556 -246.193056)
		(end 352.733356 -245.862856)
		(stroke
			(width 0.508)
			(type default)
		)
		(layer "In8.Cu")
	)
	(gr_line
		(start 353.190556 -260.493256)
		(end 353.190556 -256.988056)
		(stroke
			(width 0.508)
			(type default)
		)
		(layer "In8.Cu")
	)
	(gr_line
		(start 353.190556 -256.988056)
		(end 352.682556 -256.480056)
		(stroke
			(width 0.508)
			(type default)
		)
		(layer "In8.Cu")
	)
	(gr_line
		(start 353.2886 -336.03057)
		(end 354.094288 -336.836258)
		(stroke
			(width 0.254)
			(type default)
		)
		(layer "In8.Cu")
	)
	(gr_line
		(start 353.2886 -333.93634)
		(end 353.2886 -336.03057)
		(stroke
			(width 0.254)
			(type default)
		)
		(layer "In8.Cu")
	)
	(gr_line
		(start 353.42449 -333.80045)
		(end 353.2886 -333.93634)
		(stroke
			(width 0.254)
			(type default)
		)
		(layer "In8.Cu")
	)
	(gr_line
		(start 353.469956 -260.772656)
		(end 352.885756 -260.772656)
		(stroke
			(width 0.254)
			(type default)
		)
		(layer "In8.Cu")
	)
	(gr_line
		(start 353.511358 -260.814058)
		(end 353.190556 -260.493256)
		(stroke
			(width 0.508)
			(type default)
		)
		(layer "In8.Cu")
	)
	(gr_line
		(start 353.662742 -339.667342)
		(end 349.86341 -339.667342)
		(stroke
			(width 0.254)
			(type default)
		)
		(layer "In8.Cu")
	)
	(gr_line
		(start 354.094288 -339.235796)
		(end 353.662742 -339.667342)
		(stroke
			(width 0.254)
			(type default)
		)
		(layer "In8.Cu")
	)
	(gr_line
		(start 354.094288 -336.836258)
		(end 354.094288 -339.235796)
		(stroke
			(width 0.254)
			(type default)
		)
		(layer "In8.Cu")
	)
	(gr_line
		(start 354.349812 -362.59389)
		(end 347.547692 -355.79177)
		(stroke
			(width 0.508)
			(type default)
		)
		(layer "In8.Cu")
	)
	(gr_line
		(start 354.349812 -362.59389)
		(end 440.747658 -362.59389)
		(stroke
			(width 0.508)
			(type default)
		)
		(layer "In8.Cu")
	)
	(gr_line
		(start 354.854764 -263.604502)
		(end 354.854764 -262.11784)
		(stroke
			(width 0.508)
			(type default)
		)
		(layer "In8.Cu")
	)
	(gr_line
		(start 354.854764 -263.604502)
		(end 356.066852 -264.81659)
		(stroke
			(width 0.508)
			(type default)
		)
		(layer "In8.Cu")
	)
	(gr_line
		(start 354.854764 -262.11784)
		(end 355.189028 -261.783576)
		(stroke
			(width 0.508)
			(type default)
		)
		(layer "In8.Cu")
	)
	(gr_line
		(start 355.189028 -261.783576)
		(end 355.49713 -261.783576)
		(stroke
			(width 0.508)
			(type default)
		)
		(layer "In8.Cu")
	)
	(gr_line
		(start 355.19868 -188.780928)
		(end 349.70212 -188.780928)
		(stroke
			(width 0.508)
			(type default)
		)
		(layer "In8.Cu")
	)
	(gr_line
		(start 355.19868 -188.780928)
		(end 355.83876 -188.140848)
		(stroke
			(width 0.508)
			(type default)
		)
		(layer "In8.Cu")
	)
	(gr_line
		(start 355.49713 -261.783576)
		(end 355.837744 -261.442962)
		(stroke
			(width 0.508)
			(type default)
		)
		(layer "In8.Cu")
	)
	(gr_line
		(start 355.569012 -260.814058)
		(end 353.511358 -260.814058)
		(stroke
			(width 0.508)
			(type default)
		)
		(layer "In8.Cu")
	)
	(gr_line
		(start 355.837744 -261.442962)
		(end 355.837744 -261.08279)
		(stroke
			(width 0.508)
			(type default)
		)
		(layer "In8.Cu")
	)
	(gr_line
		(start 355.837744 -261.08279)
		(end 355.569012 -260.814058)
		(stroke
			(width 0.508)
			(type default)
		)
		(layer "In8.Cu")
	)
	(gr_line
		(start 355.83876 -188.140848)
		(end 355.83876 -174.508668)
		(stroke
			(width 0.508)
			(type default)
		)
		(layer "In8.Cu")
	)
	(gr_line
		(start 355.83876 -174.508668)
		(end 373.070882 -157.276546)
		(stroke
			(width 0.508)
			(type default)
		)
		(layer "In8.Cu")
	)
	(gr_line
		(start 355.925882 -148.361146)
		(end 318.31788 -185.969148)
		(stroke
			(width 0.508)
			(type default)
		)
		(layer "In8.Cu")
	)
	(gr_line
		(start 356.066852 -264.81659)
		(end 356.066852 -280.004774)
		(stroke
			(width 0.508)
			(type default)
		)
		(layer "In8.Cu")
	)
	(gr_line
		(start 356.945184 -338.589112)
		(end 356.945184 -337.580986)
		(stroke
			(width 0.254)
			(type default)
		)
		(layer "In8.Cu")
	)
	(gr_line
		(start 356.945184 -337.580986)
		(end 357.197914 -337.328256)
		(stroke
			(width 0.254)
			(type default)
		)
		(layer "In8.Cu")
	)
	(gr_line
		(start 357.013256 -333.80045)
		(end 353.42449 -333.80045)
		(stroke
			(width 0.254)
			(type default)
		)
		(layer "In8.Cu")
	)
	(gr_line
		(start 357.197914 -337.328256)
		(end 357.197914 -333.985108)
		(stroke
			(width 0.254)
			(type default)
		)
		(layer "In8.Cu")
	)
	(gr_line
		(start 357.197914 -333.985108)
		(end 357.013256 -333.80045)
		(stroke
			(width 0.254)
			(type default)
		)
		(layer "In8.Cu")
	)
	(gr_line
		(start 357.999792 -339.64372)
		(end 356.945184 -338.589112)
		(stroke
			(width 0.254)
			(type default)
		)
		(layer "In8.Cu")
	)
	(gr_line
		(start 361.442 -349.801688)
		(end 363.59084 -351.950528)
		(stroke
			(width 0.508)
			(type default)
		)
		(layer "In8.Cu")
	)
	(gr_line
		(start 361.470448 -336.008726)
		(end 362.115354 -336.653632)
		(stroke
			(width 0.254)
			(type default)
		)
		(layer "In8.Cu")
	)
	(gr_line
		(start 361.470448 -333.912718)
		(end 361.470448 -336.008726)
		(stroke
			(width 0.254)
			(type default)
		)
		(layer "In8.Cu")
	)
	(gr_line
		(start 361.581954 -333.801212)
		(end 361.470448 -333.912718)
		(stroke
			(width 0.254)
			(type default)
		)
		(layer "In8.Cu")
	)
	(gr_line
		(start 361.659932 -339.64372)
		(end 357.999792 -339.64372)
		(stroke
			(width 0.254)
			(type default)
		)
		(layer "In8.Cu")
	)
	(gr_line
		(start 362.115354 -339.188298)
		(end 361.659932 -339.64372)
		(stroke
			(width 0.254)
			(type default)
		)
		(layer "In8.Cu")
	)
	(gr_line
		(start 362.115354 -336.653632)
		(end 362.115354 -339.188298)
		(stroke
			(width 0.254)
			(type default)
		)
		(layer "In8.Cu")
	)
	(gr_line
		(start 363.274356 -238.090456)
		(end 363.782356 -238.598456)
		(stroke
			(width 0.508)
			(type default)
		)
		(layer "In8.Cu")
	)
	(gr_line
		(start 363.299756 -227.727256)
		(end 363.299756 -201.196194)
		(stroke
			(width 0.508)
			(type default)
		)
		(layer "In8.Cu")
	)
	(gr_line
		(start 363.299756 -227.727256)
		(end 375.182892 -239.610392)
		(stroke
			(width 0.508)
			(type default)
		)
		(layer "In8.Cu")
	)
	(gr_line
		(start 363.299756 -201.196194)
		(end 397.96593 -166.53002)
		(stroke
			(width 0.508)
			(type default)
		)
		(layer "In8.Cu")
	)
	(gr_line
		(start 363.59084 -351.950528)
		(end 367.95202 -351.950528)
		(stroke
			(width 0.508)
			(type default)
		)
		(layer "In8.Cu")
	)
	(gr_line
		(start 363.782356 -240.020856)
		(end 365.687356 -241.925856)
		(stroke
			(width 0.508)
			(type default)
		)
		(layer "In8.Cu")
	)
	(gr_line
		(start 363.782356 -238.598456)
		(end 363.782356 -240.020856)
		(stroke
			(width 0.508)
			(type default)
		)
		(layer "In8.Cu")
	)
	(gr_line
		(start 363.960156 -279.086056)
		(end 369.66271 -289.030918)
		(stroke
			(width 0.508)
			(type default)
		)
		(layer "In8.Cu")
	)
	(gr_line
		(start 363.960156 -261.179056)
		(end 363.960156 -279.086056)
		(stroke
			(width 0.508)
			(type default)
		)
		(layer "In8.Cu")
	)
	(gr_line
		(start 364.47984 -103.439468)
		(end 381.84836 -103.439468)
		(stroke
			(width 0.508)
			(type default)
		)
		(layer "In8.Cu")
	)
	(gr_line
		(start 364.620556 -260.518656)
		(end 363.960156 -261.179056)
		(stroke
			(width 0.508)
			(type default)
		)
		(layer "In8.Cu")
	)
	(gr_line
		(start 364.680246 -148.361146)
		(end 355.925882 -148.361146)
		(stroke
			(width 0.508)
			(type default)
		)
		(layer "In8.Cu")
	)
	(gr_line
		(start 364.680246 -148.361146)
		(end 418.927534 -148.361146)
		(stroke
			(width 0.508)
			(type default)
		)
		(layer "In8.Cu")
	)
	(gr_line
		(start 365.165894 -333.801212)
		(end 361.581954 -333.801212)
		(stroke
			(width 0.254)
			(type default)
		)
		(layer "In8.Cu")
	)
	(gr_line
		(start 365.3155 -338.880196)
		(end 365.3155 -333.950818)
		(stroke
			(width 0.254)
			(type default)
		)
		(layer "In8.Cu")
	)
	(gr_line
		(start 365.3155 -333.950818)
		(end 365.165894 -333.801212)
		(stroke
			(width 0.254)
			(type default)
		)
		(layer "In8.Cu")
	)
	(gr_line
		(start 365.687356 -241.925856)
		(end 368.405156 -241.925856)
		(stroke
			(width 0.508)
			(type default)
		)
		(layer "In8.Cu")
	)
	(gr_line
		(start 366.240314 -339.80501)
		(end 365.3155 -338.880196)
		(stroke
			(width 0.254)
			(type default)
		)
		(layer "In8.Cu")
	)
	(gr_line
		(start 366.347756 -260.594856)
		(end 366.601756 -260.848856)
		(stroke
			(width 0.254)
			(type default)
		)
		(layer "In8.Cu")
	)
	(gr_line
		(start 366.601756 -270.069056)
		(end 367.363756 -270.831056)
		(stroke
			(width 0.254)
			(type default)
		)
		(layer "In8.Cu")
	)
	(gr_line
		(start 366.601756 -260.848856)
		(end 366.601756 -270.069056)
		(stroke
			(width 0.254)
			(type default)
		)
		(layer "In8.Cu")
	)
	(gr_line
		(start 366.728756 -246.878856)
		(end 369.040156 -249.190256)
		(stroke
			(width 0.508)
			(type default)
		)
		(layer "In8.Cu")
	)
	(gr_line
		(start 366.728756 -244.897656)
		(end 366.728756 -246.878856)
		(stroke
			(width 0.508)
			(type default)
		)
		(layer "In8.Cu")
	)
	(gr_line
		(start 366.852454 -260.614668)
		(end 366.598454 -260.868668)
		(stroke
			(width 0.254)
			(type default)
		)
		(layer "In8.Cu")
	)
	(gr_line
		(start 367.363756 -270.831056)
		(end 368.278156 -270.831056)
		(stroke
			(width 0.254)
			(type default)
		)
		(layer "In8.Cu")
	)
	(gr_line
		(start 367.95202 -351.950528)
		(end 369.725448 -350.1771)
		(stroke
			(width 0.508)
			(type default)
		)
		(layer "In8.Cu")
	)
	(gr_line
		(start 368.024156 -243.602256)
		(end 366.728756 -244.897656)
		(stroke
			(width 0.508)
			(type default)
		)
		(layer "In8.Cu")
	)
	(gr_line
		(start 368.278156 -270.831056)
		(end 379.987556 -270.831056)
		(stroke
			(width 0.508)
			(type default)
		)
		(layer "In8.Cu")
	)
	(gr_line
		(start 368.405156 -241.925856)
		(end 368.963956 -242.484656)
		(stroke
			(width 0.508)
			(type default)
		)
		(layer "In8.Cu")
	)
	(gr_line
		(start 368.608356 -260.518656)
		(end 364.620556 -260.518656)
		(stroke
			(width 0.508)
			(type default)
		)
		(layer "In8.Cu")
	)
	(gr_line
		(start 368.684556 -243.602256)
		(end 368.024156 -243.602256)
		(stroke
			(width 0.508)
			(type default)
		)
		(layer "In8.Cu")
	)
	(gr_line
		(start 368.80292 -260.30555)
		(end 369.233958 -260.30555)
		(stroke
			(width 0.254)
			(type default)
		)
		(layer "In8.Cu")
	)
	(gr_line
		(start 368.963956 -243.322856)
		(end 368.684556 -243.602256)
		(stroke
			(width 0.508)
			(type default)
		)
		(layer "In8.Cu")
	)
	(gr_line
		(start 368.963956 -242.484656)
		(end 368.963956 -243.322856)
		(stroke
			(width 0.508)
			(type default)
		)
		(layer "In8.Cu")
	)
	(gr_line
		(start 369.040156 -260.086856)
		(end 368.608356 -260.518656)
		(stroke
			(width 0.508)
			(type default)
		)
		(layer "In8.Cu")
	)
	(gr_line
		(start 369.040156 -260.086856)
		(end 369.421156 -260.467856)
		(stroke
			(width 0.254)
			(type default)
		)
		(layer "In8.Cu")
	)
	(gr_line
		(start 369.040156 -249.190256)
		(end 369.040156 -260.086856)
		(stroke
			(width 0.508)
			(type default)
		)
		(layer "In8.Cu")
	)
	(gr_line
		(start 369.421156 -261.737856)
		(end 369.725956 -262.042656)
		(stroke
			(width 0.254)
			(type default)
		)
		(layer "In8.Cu")
	)
	(gr_line
		(start 369.421156 -260.467856)
		(end 369.421156 -261.737856)
		(stroke
			(width 0.254)
			(type default)
		)
		(layer "In8.Cu")
	)
	(gr_line
		(start 369.612418 -336.04708)
		(end 370.320824 -336.755486)
		(stroke
			(width 0.254)
			(type default)
		)
		(layer "In8.Cu")
	)
	(gr_line
		(start 369.612418 -333.912718)
		(end 369.612418 -336.04708)
		(stroke
			(width 0.254)
			(type default)
		)
		(layer "In8.Cu")
	)
	(gr_line
		(start 369.66271 -289.030918)
		(end 369.702334 -289.070542)
		(stroke
			(width 0.508)
			(type default)
		)
		(layer "In8.Cu")
	)
	(gr_line
		(start 369.72494 -333.800196)
		(end 369.612418 -333.912718)
		(stroke
			(width 0.254)
			(type default)
		)
		(layer "In8.Cu")
	)
	(gr_line
		(start 369.725448 -350.1771)
		(end 387.653276 -350.1771)
		(stroke
			(width 0.508)
			(type default)
		)
		(layer "In8.Cu")
	)
	(gr_line
		(start 369.725956 -262.042656)
		(end 369.979956 -262.042656)
		(stroke
			(width 0.254)
			(type default)
		)
		(layer "In8.Cu")
	)
	(gr_line
		(start 369.799616 -339.80501)
		(end 366.240314 -339.80501)
		(stroke
			(width 0.254)
			(type default)
		)
		(layer "In8.Cu")
	)
	(gr_line
		(start 369.979956 -262.042656)
		(end 372.138956 -262.042656)
		(stroke
			(width 0.508)
			(type default)
		)
		(layer "In8.Cu")
	)
	(gr_line
		(start 370.320824 -339.283802)
		(end 369.799616 -339.80501)
		(stroke
			(width 0.254)
			(type default)
		)
		(layer "In8.Cu")
	)
	(gr_line
		(start 370.320824 -336.755486)
		(end 370.320824 -339.283802)
		(stroke
			(width 0.254)
			(type default)
		)
		(layer "In8.Cu")
	)
	(gr_line
		(start 371.681756 -236.109256)
		(end 363.299756 -227.727256)
		(stroke
			(width 0.508)
			(type default)
		)
		(layer "In8.Cu")
	)
	(gr_line
		(start 373.002556 -322.977256)
		(end 341.972392 -322.977256)
		(stroke
			(width 0.508)
			(type default)
		)
		(layer "In8.Cu")
	)
	(gr_line
		(start 373.04472 -23.757128)
		(end 287.3756 -23.757128)
		(stroke
			(width 0.508)
			(type default)
		)
		(layer "In8.Cu")
	)
	(gr_line
		(start 373.070882 -157.276546)
		(end 377.993402 -157.276546)
		(stroke
			(width 0.508)
			(type default)
		)
		(layer "In8.Cu")
	)
	(gr_line
		(start 373.332502 -333.800196)
		(end 369.72494 -333.800196)
		(stroke
			(width 0.254)
			(type default)
		)
		(layer "In8.Cu")
	)
	(gr_line
		(start 373.491506 -342.46947)
		(end 373.491506 -333.9592)
		(stroke
			(width 0.254)
			(type default)
		)
		(layer "In8.Cu")
	)
	(gr_line
		(start 373.491506 -333.9592)
		(end 373.332502 -333.800196)
		(stroke
			(width 0.254)
			(type default)
		)
		(layer "In8.Cu")
	)
	(gr_line
		(start 373.662956 -324.983856)
		(end 373.662956 -323.637656)
		(stroke
			(width 0.508)
			(type default)
		)
		(layer "In8.Cu")
	)
	(gr_line
		(start 373.662956 -323.637656)
		(end 373.002556 -322.977256)
		(stroke
			(width 0.508)
			(type default)
		)
		(layer "In8.Cu")
	)
	(gr_line
		(start 374.149112 -262.042656)
		(end 369.979956 -262.042656)
		(stroke
			(width 0.508)
			(type default)
		)
		(layer "In8.Cu")
	)
	(gr_line
		(start 374.236996 -343.21496)
		(end 373.491506 -342.46947)
		(stroke
			(width 0.254)
			(type default)
		)
		(layer "In8.Cu")
	)
	(gr_line
		(start 374.734582 -331.181964)
		(end 341.187278 -331.181964)
		(stroke
			(width 0.508)
			(type default)
		)
		(layer "In8.Cu")
	)
	(gr_line
		(start 375.182892 -261.008876)
		(end 374.149112 -262.042656)
		(stroke
			(width 0.508)
			(type default)
		)
		(layer "In8.Cu")
	)
	(gr_line
		(start 375.182892 -239.610392)
		(end 375.182892 -261.008876)
		(stroke
			(width 0.508)
			(type default)
		)
		(layer "In8.Cu")
	)
	(gr_line
		(start 375.186956 -326.507856)
		(end 373.662956 -324.983856)
		(stroke
			(width 0.508)
			(type default)
		)
		(layer "In8.Cu")
	)
	(gr_line
		(start 375.186956 -326.507856)
		(end 379.035564 -326.507856)
		(stroke
			(width 0.508)
			(type default)
		)
		(layer "In8.Cu")
	)
	(gr_line
		(start 375.200672 -333.971392)
		(end 375.200672 -331.648054)
		(stroke
			(width 0.508)
			(type default)
		)
		(layer "In8.Cu")
	)
	(gr_line
		(start 375.200672 -331.648054)
		(end 374.734582 -331.181964)
		(stroke
			(width 0.508)
			(type default)
		)
		(layer "In8.Cu")
	)
	(gr_line
		(start 375.567956 -225.441256)
		(end 375.567956 -215.281256)
		(stroke
			(width 0.508)
			(type default)
		)
		(layer "In8.Cu")
	)
	(gr_line
		(start 375.567956 -215.281256)
		(end 376.050556 -214.798656)
		(stroke
			(width 0.508)
			(type default)
		)
		(layer "In8.Cu")
	)
	(gr_line
		(start 375.779284 -334.550004)
		(end 375.200672 -333.971392)
		(stroke
			(width 0.508)
			(type default)
		)
		(layer "In8.Cu")
	)
	(gr_line
		(start 376.050556 -214.798656)
		(end 428.490634 -214.798656)
		(stroke
			(width 0.508)
			(type default)
		)
		(layer "In8.Cu")
	)
	(gr_line
		(start 377.168156 -227.041456)
		(end 375.567956 -225.441256)
		(stroke
			(width 0.508)
			(type default)
		)
		(layer "In8.Cu")
	)
	(gr_line
		(start 377.743212 -343.21496)
		(end 374.236996 -343.21496)
		(stroke
			(width 0.254)
			(type default)
		)
		(layer "In8.Cu")
	)
	(gr_line
		(start 377.783598 -340.065614)
		(end 378.51207 -340.794086)
		(stroke
			(width 0.254)
			(type default)
		)
		(layer "In8.Cu")
	)
	(gr_line
		(start 377.783598 -337.276948)
		(end 377.783598 -340.065614)
		(stroke
			(width 0.254)
			(type default)
		)
		(layer "In8.Cu")
	)
	(gr_line
		(start 377.852686 -337.20786)
		(end 377.783598 -337.276948)
		(stroke
			(width 0.254)
			(type default)
		)
		(layer "In8.Cu")
	)
	(gr_line
		(start 378.51207 -342.446102)
		(end 377.743212 -343.21496)
		(stroke
			(width 0.254)
			(type default)
		)
		(layer "In8.Cu")
	)
	(gr_line
		(start 378.51207 -340.794086)
		(end 378.51207 -342.446102)
		(stroke
			(width 0.254)
			(type default)
		)
		(layer "In8.Cu")
	)
	(gr_line
		(start 379.035564 -326.507856)
		(end 382.934718 -330.40701)
		(stroke
			(width 0.508)
			(type default)
		)
		(layer "In8.Cu")
	)
	(gr_line
		(start 380.546356 -227.041456)
		(end 377.168156 -227.041456)
		(stroke
			(width 0.508)
			(type default)
		)
		(layer "In8.Cu")
	)
	(gr_line
		(start 380.546356 -227.041456)
		(end 387.633718 -234.128818)
		(stroke
			(width 0.508)
			(type default)
		)
		(layer "In8.Cu")
	)
	(gr_line
		(start 381.49149 -337.20786)
		(end 377.852686 -337.20786)
		(stroke
			(width 0.254)
			(type default)
		)
		(layer "In8.Cu")
	)
	(gr_line
		(start 381.766572 -348.062804)
		(end 381.766572 -337.482942)
		(stroke
			(width 0.254)
			(type default)
		)
		(layer "In8.Cu")
	)
	(gr_line
		(start 381.766572 -337.482942)
		(end 381.49149 -337.20786)
		(stroke
			(width 0.254)
			(type default)
		)
		(layer "In8.Cu")
	)
	(gr_line
		(start 381.786384 -214.798656)
		(end 381.715772 -214.798656)
		(stroke
			(width 0.508)
			(type default)
		)
		(layer "In8.Cu")
	)
	(gr_line
		(start 381.84836 -103.439468)
		(end 390.88314 -94.404688)
		(stroke
			(width 0.508)
			(type default)
		)
		(layer "In8.Cu")
	)
	(gr_line
		(start 382.26492 -348.561152)
		(end 381.766572 -348.062804)
		(stroke
			(width 0.254)
			(type default)
		)
		(layer "In8.Cu")
	)
	(gr_line
		(start 382.285494 -334.550004)
		(end 375.779284 -334.550004)
		(stroke
			(width 0.508)
			(type default)
		)
		(layer "In8.Cu")
	)
	(gr_line
		(start 382.934718 -330.40701)
		(end 396.150338 -330.40701)
		(stroke
			(width 0.508)
			(type default)
		)
		(layer "In8.Cu")
	)
	(gr_line
		(start 383.651252 -341.987124)
		(end 383.651252 -335.915762)
		(stroke
			(width 0.508)
			(type default)
		)
		(layer "In8.Cu")
	)
	(gr_line
		(start 383.651252 -335.915762)
		(end 382.285494 -334.550004)
		(stroke
			(width 0.508)
			(type default)
		)
		(layer "In8.Cu")
	)
	(gr_line
		(start 384.340608 -342.67648)
		(end 383.651252 -341.987124)
		(stroke
			(width 0.508)
			(type default)
		)
		(layer "In8.Cu")
	)
	(gr_line
		(start 385.601972 -11.780012)
		(end 260.800088 -11.780012)
		(stroke
			(width 3.048)
			(type default)
		)
		(layer "In8.Cu")
	)
	(gr_arc
		(start 385.601972 -11.780012)
		(mid 387.016206 -11.194238)
		(end 387.601968 -9.780016)
		(stroke
			(width 3.048)
			(type default)
		)
		(layer "In8.Cu")
	)
	(gr_line
		(start 385.71805 -289.070542)
		(end 369.702334 -289.070542)
		(stroke
			(width 0.508)
			(type default)
		)
		(layer "In8.Cu")
	)
	(gr_line
		(start 385.944364 -345.416886)
		(end 386.513578 -345.9861)
		(stroke
			(width 0.254)
			(type default)
		)
		(layer "In8.Cu")
	)
	(gr_line
		(start 385.944364 -342.865456)
		(end 385.944364 -345.416886)
		(stroke
			(width 0.254)
			(type default)
		)
		(layer "In8.Cu")
	)
	(gr_line
		(start 385.949444 -342.997282)
		(end 385.695444 -342.743282)
		(stroke
			(width 0.254)
			(type default)
		)
		(layer "In8.Cu")
	)
	(gr_line
		(start 385.949444 -342.975946)
		(end 386.195062 -342.730328)
		(stroke
			(width 0.254)
			(type default)
		)
		(layer "In8.Cu")
	)
	(gr_line
		(start 386.18668 -36.899088)
		(end 373.04472 -23.757128)
		(stroke
			(width 0.508)
			(type default)
		)
		(layer "In8.Cu")
	)
	(gr_line
		(start 386.238496 -348.561152)
		(end 382.26492 -348.561152)
		(stroke
			(width 0.254)
			(type default)
		)
		(layer "In8.Cu")
	)
	(gr_line
		(start 386.513578 -348.28607)
		(end 386.238496 -348.561152)
		(stroke
			(width 0.254)
			(type default)
		)
		(layer "In8.Cu")
	)
	(gr_line
		(start 386.513578 -345.9861)
		(end 386.513578 -348.28607)
		(stroke
			(width 0.254)
			(type default)
		)
		(layer "In8.Cu")
	)
	(gr_line
		(start 387.601968 -0.999998)
		(end 387.601968 -9.780016)
		(stroke
			(width 3.048)
			(type default)
		)
		(layer "In8.Cu")
	)
	(gr_line
		(start 387.633718 -263.184894)
		(end 379.987556 -270.831056)
		(stroke
			(width 0.508)
			(type default)
		)
		(layer "In8.Cu")
	)
	(gr_line
		(start 387.633718 -234.128818)
		(end 387.633718 -263.184894)
		(stroke
			(width 0.508)
			(type default)
		)
		(layer "In8.Cu")
	)
	(gr_line
		(start 387.653276 -350.1771)
		(end 391.140188 -346.690188)
		(stroke
			(width 0.508)
			(type default)
		)
		(layer "In8.Cu")
	)
	(gr_arc
		(start 388.601966 0)
		(mid 387.894861 -0.292893)
		(end 387.601968 -0.999998)
		(stroke
			(width 3.048)
			(type default)
		)
		(layer "In8.Cu")
	)
	(gr_line
		(start 390.837166 -342.67648)
		(end 384.340608 -342.67648)
		(stroke
			(width 0.508)
			(type default)
		)
		(layer "In8.Cu")
	)
	(gr_line
		(start 390.88314 -94.404688)
		(end 390.88314 -78.151228)
		(stroke
			(width 0.508)
			(type default)
		)
		(layer "In8.Cu")
	)
	(gr_line
		(start 390.88314 -78.151228)
		(end 396.69212 -72.342248)
		(stroke
			(width 0.508)
			(type default)
		)
		(layer "In8.Cu")
	)
	(gr_line
		(start 391.140188 -346.690188)
		(end 391.140188 -342.979502)
		(stroke
			(width 0.508)
			(type default)
		)
		(layer "In8.Cu")
	)
	(gr_line
		(start 391.140188 -342.979502)
		(end 390.837166 -342.67648)
		(stroke
			(width 0.508)
			(type default)
		)
		(layer "In8.Cu")
	)
	(gr_line
		(start 392.863578 -330.36637)
		(end 392.863578 -296.21607)
		(stroke
			(width 0.508)
			(type default)
		)
		(layer "In8.Cu")
	)
	(gr_line
		(start 392.863578 -296.21607)
		(end 385.71805 -289.070542)
		(stroke
			(width 0.508)
			(type default)
		)
		(layer "In8.Cu")
	)
	(gr_line
		(start 392.871198 -329.91679)
		(end 392.416538 -330.37145)
		(stroke
			(width 0.508)
			(type default)
		)
		(layer "In8.Cu")
	)
	(gr_line
		(start 393.356338 -330.40193)
		(end 392.871198 -329.91679)
		(stroke
			(width 0.508)
			(type default)
		)
		(layer "In8.Cu")
	)
	(gr_line
		(start 396.150338 -330.40701)
		(end 396.564612 -330.821284)
		(stroke
			(width 0.508)
			(type default)
		)
		(layer "In8.Cu")
	)
	(gr_line
		(start 396.564612 -330.821284)
		(end 396.564612 -340.024466)
		(stroke
			(width 0.508)
			(type default)
		)
		(layer "In8.Cu")
	)
	(gr_line
		(start 396.69212 -72.342248)
		(end 450.96684 -72.342248)
		(stroke
			(width 0.508)
			(type default)
		)
		(layer "In8.Cu")
	)
	(gr_line
		(start 397.96593 -166.53002)
		(end 410.218382 -166.53002)
		(stroke
			(width 0.508)
			(type default)
		)
		(layer "In8.Cu")
	)
	(gr_line
		(start 408.285696 -351.74555)
		(end 396.564612 -340.024466)
		(stroke
			(width 0.508)
			(type default)
		)
		(layer "In8.Cu")
	)
	(gr_line
		(start 409.61945 -157.284928)
		(end 410.220668 -157.886146)
		(stroke
			(width 0.508)
			(type default)
		)
		(layer "In8.Cu")
	)
	(gr_line
		(start 409.712668 -148.488146)
		(end 410.220668 -148.996146)
		(stroke
			(width 0.508)
			(type default)
		)
		(layer "In8.Cu")
	)
	(gr_line
		(start 409.75153 -166.529766)
		(end 410.20873 -166.072566)
		(stroke
			(width 0.508)
			(type default)
		)
		(layer "In8.Cu")
	)
	(gr_line
		(start 410.195268 -148.970746)
		(end 410.195268 -148.488146)
		(stroke
			(width 0.508)
			(type default)
		)
		(layer "In8.Cu")
	)
	(gr_line
		(start 410.201872 -166.988998)
		(end 409.744672 -166.531798)
		(stroke
			(width 0.508)
			(type default)
		)
		(layer "In8.Cu")
	)
	(gr_line
		(start 410.20619 -157.276546)
		(end 377.993402 -157.276546)
		(stroke
			(width 0.508)
			(type default)
		)
		(layer "In8.Cu")
	)
	(gr_line
		(start 410.20619 -157.149546)
		(end 410.220668 -157.164024)
		(stroke
			(width 0.508)
			(type default)
		)
		(layer "In8.Cu")
	)
	(gr_line
		(start 410.212286 -156.675328)
		(end 409.611068 -157.276546)
		(stroke
			(width 0.508)
			(type default)
		)
		(layer "In8.Cu")
	)
	(gr_line
		(start 410.214318 -214.09279)
		(end 409.560014 -214.747094)
		(stroke
			(width 0.508)
			(type default)
		)
		(layer "In8.Cu")
	)
	(gr_line
		(start 410.218382 -168.05402)
		(end 410.220668 -168.056306)
		(stroke
			(width 0.508)
			(type default)
		)
		(layer "In8.Cu")
	)
	(gr_line
		(start 410.220668 -148.996146)
		(end 410.195268 -148.970746)
		(stroke
			(width 0.508)
			(type default)
		)
		(layer "In8.Cu")
	)
	(gr_line
		(start 410.220668 -148.996146)
		(end 410.220668 -214.72652)
		(stroke
			(width 0.508)
			(type default)
		)
		(layer "In8.Cu")
	)
	(gr_line
		(start 410.754068 -148.462746)
		(end 410.220668 -148.996146)
		(stroke
			(width 0.508)
			(type default)
		)
		(layer "In8.Cu")
	)
	(gr_line
		(start 410.875988 -214.75446)
		(end 410.214318 -214.09279)
		(stroke
			(width 0.508)
			(type default)
		)
		(layer "In8.Cu")
	)
	(gr_line
		(start 418.927534 -148.361146)
		(end 421.056308 -150.48992)
		(stroke
			(width 0.508)
			(type default)
		)
		(layer "In8.Cu")
	)
	(gr_line
		(start 421.056308 -169.458386)
		(end 421.489632 -169.89171)
		(stroke
			(width 0.508)
			(type default)
		)
		(layer "In8.Cu")
	)
	(gr_line
		(start 421.056308 -150.48992)
		(end 421.056308 -169.458386)
		(stroke
			(width 0.508)
			(type default)
		)
		(layer "In8.Cu")
	)
	(gr_line
		(start 421.489632 -169.89171)
		(end 428.621698 -169.89171)
		(stroke
			(width 0.508)
			(type default)
		)
		(layer "In8.Cu")
	)
	(gr_line
		(start 428.490634 -214.798656)
		(end 429.111156 -215.419178)
		(stroke
			(width 0.508)
			(type default)
		)
		(layer "In8.Cu")
	)
	(gr_line
		(start 428.621698 -169.89171)
		(end 442.70676 -169.89171)
		(stroke
			(width 0.508)
			(type default)
		)
		(layer "In8.Cu")
	)
	(gr_line
		(start 429.111156 -215.419178)
		(end 429.111156 -328.997056)
		(stroke
			(width 0.508)
			(type default)
		)
		(layer "In8.Cu")
	)
	(gr_line
		(start 429.122078 -321.85483)
		(end 452.871078 -321.85483)
		(stroke
			(width 0.508)
			(type default)
		)
		(layer "In8.Cu")
	)
	(gr_line
		(start 429.170338 -312.84291)
		(end 441.943998 -312.84291)
		(stroke
			(width 0.508)
			(type default)
		)
		(layer "In8.Cu")
	)
	(gr_line
		(start 429.201834 -322.243196)
		(end 429.60417 -321.84086)
		(stroke
			(width 0.508)
			(type default)
		)
		(layer "In8.Cu")
	)
	(gr_line
		(start 429.250094 -313.231276)
		(end 429.65243 -312.82894)
		(stroke
			(width 0.508)
			(type default)
		)
		(layer "In8.Cu")
	)
	(gr_line
		(start 429.353218 -351.74555)
		(end 408.285696 -351.74555)
		(stroke
			(width 0.508)
			(type default)
		)
		(layer "In8.Cu")
	)
	(gr_line
		(start 429.575722 -321.84086)
		(end 429.201834 -321.466972)
		(stroke
			(width 0.508)
			(type default)
		)
		(layer "In8.Cu")
	)
	(gr_line
		(start 429.60417 -321.84086)
		(end 429.575722 -321.84086)
		(stroke
			(width 0.508)
			(type default)
		)
		(layer "In8.Cu")
	)
	(gr_line
		(start 429.623982 -312.82894)
		(end 429.250094 -312.455052)
		(stroke
			(width 0.508)
			(type default)
		)
		(layer "In8.Cu")
	)
	(gr_line
		(start 429.65243 -312.82894)
		(end 429.623982 -312.82894)
		(stroke
			(width 0.508)
			(type default)
		)
		(layer "In8.Cu")
	)
	(gr_line
		(start 429.820578 -351.27819)
		(end 429.353218 -351.74555)
		(stroke
			(width 0.508)
			(type default)
		)
		(layer "In8.Cu")
	)
	(gr_line
		(start 429.820578 -329.706478)
		(end 429.111156 -328.997056)
		(stroke
			(width 0.508)
			(type default)
		)
		(layer "In8.Cu")
	)
	(gr_line
		(start 429.820578 -329.706478)
		(end 429.820578 -351.27819)
		(stroke
			(width 0.508)
			(type default)
		)
		(layer "In8.Cu")
	)
	(gr_line
		(start 440.747658 -362.59389)
		(end 445.385698 -357.95585)
		(stroke
			(width 0.508)
			(type default)
		)
		(layer "In8.Cu")
	)
	(gr_line
		(start 442.581538 -312.84291)
		(end 441.943998 -312.84291)
		(stroke
			(width 0.508)
			(type default)
		)
		(layer "In8.Cu")
	)
	(gr_line
		(start 442.70676 -169.89171)
		(end 442.718444 -169.903394)
		(stroke
			(width 0.508)
			(type default)
		)
		(layer "In8.Cu")
	)
	(gr_line
		(start 443.346078 -312.07837)
		(end 442.581538 -312.84291)
		(stroke
			(width 0.508)
			(type default)
		)
		(layer "In8.Cu")
	)
	(gr_line
		(start 443.346078 -312.07837)
		(end 443.346078 -170.53687)
		(stroke
			(width 0.508)
			(type default)
		)
		(layer "In8.Cu")
	)
	(gr_line
		(start 443.346078 -170.53687)
		(end 442.726318 -169.91711)
		(stroke
			(width 0.508)
			(type default)
		)
		(layer "In8.Cu")
	)
	(gr_line
		(start 445.385698 -357.95585)
		(end 445.385698 -335.80959)
		(stroke
			(width 0.508)
			(type default)
		)
		(layer "In8.Cu")
	)
	(gr_line
		(start 445.385698 -335.80959)
		(end 445.982598 -335.21269)
		(stroke
			(width 0.508)
			(type default)
		)
		(layer "In8.Cu")
	)
	(gr_line
		(start 445.982598 -335.21269)
		(end 453.5043 -335.21269)
		(stroke
			(width 0.508)
			(type default)
		)
		(layer "In8.Cu")
	)
	(gr_line
		(start 448.15252 -36.899088)
		(end 386.18668 -36.899088)
		(stroke
			(width 0.508)
			(type default)
		)
		(layer "In8.Cu")
	)
	(gr_line
		(start 450.96684 -72.342248)
		(end 452.37654 -70.932548)
		(stroke
			(width 0.508)
			(type default)
		)
		(layer "In8.Cu")
	)
	(gr_line
		(start 452.37654 -70.932548)
		(end 452.37654 -41.123108)
		(stroke
			(width 0.508)
			(type default)
		)
		(layer "In8.Cu")
	)
	(gr_line
		(start 452.37654 -41.123108)
		(end 448.15252 -36.899088)
		(stroke
			(width 0.508)
			(type default)
		)
		(layer "In8.Cu")
	)
	(gr_line
		(start 452.871078 -321.85483)
		(end 453.203818 -322.18757)
		(stroke
			(width 0.508)
			(type default)
		)
		(layer "In8.Cu")
	)
	(gr_line
		(start 453.203818 -328.05497)
		(end 454.214738 -329.06589)
		(stroke
			(width 0.508)
			(type default)
		)
		(layer "In8.Cu")
	)
	(gr_line
		(start 453.203818 -322.18757)
		(end 453.203818 -328.05497)
		(stroke
			(width 0.508)
			(type default)
		)
		(layer "In8.Cu")
	)
	(gr_line
		(start 453.607424 -335.214214)
		(end 454.214738 -334.6069)
		(stroke
			(width 0.508)
			(type default)
		)
		(layer "In8.Cu")
	)
	(gr_line
		(start 454.214738 -334.6069)
		(end 454.214738 -334.003396)
		(stroke
			(width 0.508)
			(type default)
		)
		(layer "In8.Cu")
	)
	(gr_line
		(start 454.214738 -329.06589)
		(end 454.214738 -334.554068)
		(stroke
			(width 0.508)
			(type default)
		)
		(layer "In8.Cu")
	)
	(gr_line
		(start 455.202036 0)
		(end 388.601966 0)
		(stroke
			(width 3.048)
			(type default)
		)
		(layer "In8.Cu")
	)
	(gr_line
		(start 456.202034 -9.780016)
		(end 456.202034 -0.999998)
		(stroke
			(width 3.048)
			(type default)
		)
		(layer "In8.Cu")
	)
	(gr_arc
		(start 456.202034 -9.780016)
		(mid 456.787827 -11.194206)
		(end 458.20203 -11.780012)
		(stroke
			(width 3.048)
			(type default)
		)
		(layer "In8.Cu")
	)
	(gr_arc
		(start 456.202034 -0.999998)
		(mid 455.909141 -0.292893)
		(end 455.202036 0)
		(stroke
			(width 3.048)
			(type default)
		)
		(layer "In8.Cu")
	)
	(gr_arc
		(start 463.300064 -441.989972)
		(mid 464.714275 -441.404187)
		(end 465.30006 -439.989976)
		(stroke
			(width 3.048)
			(type default)
		)
		(layer "In8.Cu")
	)
	(gr_line
		(start 465.30006 -439.989976)
		(end 465.30006 -409.528264)
		(stroke
			(width 3.048)
			(type default)
		)
		(layer "In8.Cu")
	)
	(gr_arc
		(start 465.885784 -408.114246)
		(mid 465.452298 -408.763001)
		(end 465.30006 -409.528264)
		(stroke
			(width 3.048)
			(type default)
		)
		(layer "In8.Cu")
	)
	(gr_line
		(start 465.885784 -408.114246)
		(end 467.71433 -406.2857)
		(stroke
			(width 3.048)
			(type default)
		)
		(layer "In8.Cu")
	)
	(gr_arc
		(start 467.71433 -406.2857)
		(mid 468.147816 -405.636943)
		(end 468.300054 -404.871682)
		(stroke
			(width 3.048)
			(type default)
		)
		(layer "In8.Cu")
	)
	(gr_line
		(start 468.300054 -404.871682)
		(end 468.300054 -82.82813)
		(stroke
			(width 3.048)
			(type default)
		)
		(layer "In8.Cu")
	)
	(gr_arc
		(start 468.885778 -81.414112)
		(mid 468.452282 -82.062865)
		(end 468.300054 -82.82813)
		(stroke
			(width 3.048)
			(type default)
		)
		(layer "In8.Cu")
	)
	(gr_line
		(start 468.885778 -81.414112)
		(end 471.214196 -79.085694)
		(stroke
			(width 3.048)
			(type default)
		)
		(layer "In8.Cu")
	)
	(gr_line
		(start 469.799924 -11.780012)
		(end 458.20203 -11.780012)
		(stroke
			(width 3.048)
			(type default)
		)
		(layer "In8.Cu")
	)
	(gr_arc
		(start 471.214196 -79.085694)
		(mid 471.647682 -78.436937)
		(end 471.79992 -77.671676)
		(stroke
			(width 3.048)
			(type default)
		)
		(layer "In8.Cu")
	)
	(gr_line
		(start 471.79992 -77.671676)
		(end 471.79992 -13.780008)
		(stroke
			(width 3.048)
			(type default)
		)
		(layer "In8.Cu")
	)
	(gr_arc
		(start 471.79992 -13.780008)
		(mid 471.214135 -12.365797)
		(end 469.799924 -11.780012)
		(stroke
			(width 3.048)
			(type default)
		)
		(layer "In8.Cu")
	)
	(gr_arc
		(start 0 -77.671676)
		(mid 0.152221 -78.436944)
		(end 0.585724 -79.085694)
		(stroke
			(width 3.048)
			(type default)
		)
		(layer "In9.Cu")
	)
	(gr_line
		(start 0 -13.780008)
		(end 0 -77.671676)
		(stroke
			(width 3.048)
			(type default)
		)
		(layer "In9.Cu")
	)
	(gr_poly
		(pts
			(arc
				(start 278.10841 -405.924766)
				(mid 278.127045 -405.923069)
				(end 278.145748 -405.92248)
			)
			(xy 280.90622 -405.92248) (xy 281.051508 -405.777192) (xy 281.051508 -397.72844) (xy 280.706068 -397.383)
			(xy 275.6408 -397.383) (xy 275.3868 -397.637) (xy 275.3868 -405.8285) (xy 275.48332 -405.92502) (xy 278.105616 -405.92502)
		)
		(stroke
			(width 0)
			(type solid)
		)
		(fill yes)
		(layer "In9.Cu")
		(net "P12V_MAIN_R_0")
	)
	(gr_poly
		(pts
			(arc
				(start 273.791172 -406.781)
				(mid 273.810393 -406.777119)
				(end 273.826732 -406.766268)
			)
			(xy 274.30476 -406.28824) (xy 274.32 -406.274016) (xy 274.32 -397.635984) (xy 274.30476 -397.62176)
			(xy 274.083018 -397.400018) (xy 274.067016 -397.383) (xy 240.155984 -397.383) (xy 240.14176 -397.39824)
			(xy 239.666018 -397.873982) (xy 239.665764 -397.874236) (xy 239.649 -397.889984) (xy 239.649 -406.528016)
			(xy 239.66424 -406.54224) (xy 239.88776 -406.76576) (xy 239.901984 -406.781)
		)
		(stroke
			(width 0)
			(type solid)
		)
		(fill yes)
		(layer "In9.Cu")
		(net "P12V_MAIN_R")
	)
	(gr_poly
		(pts
			(arc
				(start 256.998724 -319.05575)
				(mid 257.087919 -319.012511)
				(end 257.185922 -318.997584)
			)
			(arc
				(start 257.185922 -318.997584)
				(mid 257.283945 -319.012445)
				(end 257.37312 -319.05575)
			)
			(xy 272.12417 -319.05575)
			(arc
				(start 272.135092 -319.050162)
				(mid 272.285714 -319.013839)
				(end 272.436336 -319.050162)
			)
			(xy 272.447258 -319.05575)
			(arc
				(start 279.576022 -319.05575)
				(mid 279.794716 -318.9732)
				(end 280.01341 -319.05575)
			)
			(xy 284.231842 -319.05575) (xy 284.3276 -318.959992)
			(arc
				(start 284.3276 -218.785948)
				(mid 284.34695 -218.688761)
				(end 284.402022 -218.60637)
			)
			(arc
				(start 285.002732 -218.00566)
				(mid 285.085109 -217.950554)
				(end 285.18231 -217.931238)
			)
			(xy 317.515494 -217.931238) (xy 318.06388 -217.382852) (xy 318.06388 -194.823588) (xy 317.627762 -194.38747)
			(xy 254.680974 -194.38747) (xy 254.052578 -195.015866) (xy 254.052578 -318.78651)
			(arc
				(start 254.275844 -319.009776)
				(mid 254.390698 -318.933818)
				(end 254.52578 -318.90716)
			)
			(arc
				(start 254.52578 -318.90716)
				(mid 254.688389 -318.946485)
				(end 254.815086 -319.05575)
			)
		)
		(stroke
			(width 0)
			(type solid)
		)
		(fill yes)
		(layer "In9.Cu")
		(net "GND")
	)
	(gr_poly
		(pts
			(arc
				(start 183.53405 -319.555114)
				(mid 183.8198 -319.388535)
				(end 184.10555 -319.555114)
			)
			(arc
				(start 187.5663 -319.555114)
				(mid 187.883546 -319.360511)
				(end 188.200792 -319.555114)
			)
			(arc
				(start 195.1101 -319.555114)
				(mid 195.427346 -319.360511)
				(end 195.744592 -319.555114)
			)
			(xy 198.872094 -319.555114)
			(arc
				(start 198.875142 -319.55486)
				(mid 198.895043 -319.55299)
				(end 198.91502 -319.55232)
			)
			(arc
				(start 198.91502 -319.55232)
				(mid 198.934998 -319.552975)
				(end 198.954898 -319.55486)
			)
			(xy 198.957946 -319.555114)
			(arc
				(start 202.6539 -319.555114)
				(mid 202.971146 -319.360511)
				(end 203.288392 -319.555114)
			)
			(arc
				(start 206.07401 -319.555114)
				(mid 206.35976 -319.388535)
				(end 206.64551 -319.555114)
			)
			(arc
				(start 210.1977 -319.555114)
				(mid 210.514946 -319.360511)
				(end 210.832192 -319.555114)
			)
			(arc
				(start 214.329264 -319.555114)
				(mid 214.615014 -319.388535)
				(end 214.900764 -319.555114)
			)
			(xy 217.212418 -319.555114) (xy 217.21445 -319.553082)
			(arc
				(start 217.49258 -319.274952)
				(mid 217.515215 -319.254866)
				(end 217.540078 -319.237614)
			)
			(xy 217.540078 -194.530726) (xy 216.210642 -193.20129)
			(arc
				(start 170.460416 -193.20129)
				(mid 170.123612 -193.403534)
				(end 169.786808 -193.20129)
			)
			(arc
				(start 153.360628 -193.20129)
				(mid 153.281041 -193.239736)
				(end 153.261568 -193.326004)
			)
			(arc
				(start 153.261568 -193.326004)
				(mid 153.268596 -193.366247)
				(end 153.270966 -193.40703)
			)
			(arc
				(start 153.270966 -193.40703)
				(mid 153.187269 -193.636296)
				(end 152.975564 -193.757804)
			)
			(xy 152.9334 -193.76517) (xy 152.9334 -194.423792)
			(arc
				(start 154.577796 -196.068188)
				(mid 154.632902 -196.150565)
				(end 154.652218 -196.247766)
			)
			(xy 154.652218 -214.137494) (xy 155.054554 -214.53983)
			(arc
				(start 180.581808 -214.53983)
				(mid 180.678995 -214.55918)
				(end 180.761386 -214.614252)
			)
			(arc
				(start 181.35092 -215.203786)
				(mid 181.406026 -215.286163)
				(end 181.425342 -215.383364)
			)
			(xy 181.425342 -319.240662) (xy 181.441598 -319.255648) (xy 181.741064 -319.555114)
		)
		(stroke
			(width 0)
			(type solid)
		)
		(fill yes)
		(layer "In9.Cu")
		(net "GND")
	)
	(gr_poly
		(pts
			(arc
				(start 121.61139 -349.997522)
				(mid 121.693767 -349.942416)
				(end 121.790968 -349.9231)
			)
			(xy 139.60856 -349.9231) (xy 142.946374 -346.585286) (xy 142.946374 -343.084912) (xy 142.792196 -342.930734)
			(xy 138.234674 -342.930734) (xy 138.131804 -343.03335) (xy 138.131804 -345.364562) (xy 138.701272 -345.933522)
			(xy 138.701272 -348.339156) (xy 138.351514 -348.68866) (xy 134.272274 -348.68866) (xy 133.699504 -348.11589)
			(xy 133.699504 -339.350858) (xy 133.69925 -339.35035) (xy 133.69925 -339.339428) (xy 133.69925 -339.328506)
			(xy 133.699504 -339.327998) (xy 133.699504 -337.535774) (xy 133.499098 -337.335368) (xy 129.971292 -337.335368)
			(xy 129.971292 -340.01329) (xy 130.699764 -340.741508) (xy 130.699764 -342.499188) (xy 130.329686 -342.869012)
			(arc
				(start 130.326384 -342.882982)
				(mid 130.191372 -343.124398)
				(end 129.949956 -343.25941)
			)
			(xy 129.935986 -343.262712) (xy 129.85623 -343.342468) (xy 126.24435 -343.342468) (xy 125.424184 -342.522556)
			(xy 125.424184 -334.012032) (xy 125.34011 -333.927704) (xy 121.837704 -333.927704) (xy 121.800112 -333.96555)
			(xy 121.800112 -335.994756) (xy 122.508264 -336.702908) (xy 122.508264 -339.336888) (xy 121.912634 -339.932772)
			(xy 118.247668 -339.932772) (xy 117.248432 -338.933282) (xy 117.248432 -334.00365) (xy 117.173502 -333.92872)
			(xy 113.694718 -333.92872) (xy 113.657888 -333.96555) (xy 113.657888 -335.956402) (xy 114.303048 -336.601054)
			(xy 114.303048 -339.241384) (xy 113.963958 -339.58022)
			(arc
				(start 113.96091 -339.585554)
				(mid 113.883362 -339.685298)
				(end 113.783618 -339.762846)
			)
			(xy 113.778284 -339.765894) (xy 113.77295 -339.771228) (xy 113.768886 -339.771228)
			(arc
				(start 113.757964 -339.77707)
				(mid 113.644305 -339.819717)
				(end 113.523776 -339.83422)
			)
			(arc
				(start 113.523776 -339.83422)
				(mid 113.397367 -339.818193)
				(end 113.27892 -339.771228)
			)
			(arc
				(start 110.72876 -339.771228)
				(mid 110.611104 -339.81745)
				(end 110.485682 -339.833204)
			)
			(arc
				(start 110.485682 -339.833204)
				(mid 110.366124 -339.819011)
				(end 110.253272 -339.77707)
			)
			(xy 110.24235 -339.771228) (xy 110.007146 -339.771228) (xy 108.878116 -338.642198) (xy 108.878116 -337.528408)
			(xy 109.130592 -337.275932) (xy 109.130592 -334.03794) (xy 109.020864 -333.928212) (xy 105.537254 -333.928212)
			(xy 105.47604 -333.989172) (xy 105.47604 -335.978246) (xy 106.281728 -336.78368) (xy 106.281728 -339.288882)
			(xy 106.169714 -339.40115)
			(arc
				(start 106.165904 -339.41131)
				(mid 106.048757 -339.593883)
				(end 105.866184 -339.71103)
			)
			(xy 105.856024 -339.71484) (xy 105.77576 -339.795104) (xy 102.611174 -339.795104)
			(arc
				(start 102.601522 -339.799422)
				(mid 102.500563 -339.832106)
				(end 102.39502 -339.84311)
			)
			(arc
				(start 102.39502 -339.84311)
				(mid 102.28948 -339.832091)
				(end 102.188518 -339.799422)
			)
			(xy 102.178866 -339.795104) (xy 101.870764 -339.795104) (xy 100.865432 -338.789772) (xy 100.865432 -333.983838)
			(xy 100.811584 -333.929736) (xy 97.369376 -333.929736) (xy 97.317052 -333.982314) (xy 97.317052 -335.940908)
			(xy 98.242628 -336.866484) (xy 98.242628 -339.002116) (xy 97.482406 -339.762592)
			(arc
				(start 94.438978 -339.762592)
				(mid 94.324046 -339.80625)
				(end 94.201996 -339.821012)
			)
			(arc
				(start 94.201996 -339.821012)
				(mid 94.079955 -339.806213)
				(end 93.965014 -339.762592)
			)
			(xy 93.118686 -339.762592) (xy 92.792804 -339.436456) (xy 92.792804 -337.40217) (xy 92.749116 -337.358736)
			(xy 89.179908 -337.358736) (xy 89.178892 -337.359498) (xy 89.178892 -339.601556) (xy 89.84234 -340.26475)
			(xy 89.84234 -342.433656) (xy 89.516966 -342.75903)
			(arc
				(start 89.513664 -342.773)
				(mid 89.378941 -343.013181)
				(end 89.13876 -343.147904)
			)
			(xy 89.12479 -343.151206) (xy 88.648794 -343.627456) (xy 85.091016 -343.627456) (xy 84.615782 -343.151968)
			(xy 81.064354 -343.151968) (xy 80.968596 -343.247726) (xy 80.968596 -345.179904) (xy 83.13674 -347.348048)
			(xy 83.13674 -348.797118) (xy 83.342734 -349.002858)
			(arc
				(start 85.83295 -349.002858)
				(mid 85.930137 -349.022208)
				(end 86.012528 -349.07728)
			)
			(xy 88.356948 -351.4217) (xy 95.743014 -351.4217) (xy 96.179894 -350.98482)
			(arc
				(start 96.175322 -350.958912)
				(mid 96.171492 -350.928794)
				(end 96.170242 -350.89846)
			)
			(arc
				(start 96.170242 -350.89846)
				(mid 96.274544 -350.646654)
				(end 96.52635 -350.542352)
			)
			(arc
				(start 96.52635 -350.542352)
				(mid 96.556684 -350.543603)
				(end 96.586802 -350.547432)
			)
			(xy 96.61271 -350.552004)
			(arc
				(start 97.54235 -349.622364)
				(mid 97.624727 -349.567258)
				(end 97.721928 -349.547942)
			)
			(arc
				(start 113.672874 -349.547942)
				(mid 113.770061 -349.567292)
				(end 113.852452 -349.622364)
			)
			(xy 115.860576 -351.630488) (xy 119.978424 -351.630488)
		)
		(stroke
			(width 0)
			(type solid)
		)
		(fill yes)
		(layer "In9.Cu")
		(net "SW_P12V_PVCCIN_CPU1_FLT")
	)
	(gr_poly
		(pts
			(arc
				(start 369.53825 -350.005142)
				(mid 369.620627 -349.950036)
				(end 369.717828 -349.93072)
			)
			(xy 387.5405 -349.93072) (xy 390.501124 -346.970096)
			(arc
				(start 390.488932 -346.939108)
				(mid 390.469342 -346.870863)
				(end 390.46277 -346.80017)
			)
			(arc
				(start 390.46277 -346.80017)
				(mid 390.571742 -346.533201)
				(end 390.836404 -346.418662)
			)
			(arc
				(start 390.836404 -346.418662)
				(mid 390.871674 -346.403429)
				(end 390.886188 -346.367862)
			)
			(xy 390.886188 -343.084658) (xy 390.73201 -342.93048) (xy 386.174488 -342.93048) (xy 386.071872 -343.033096)
			(xy 386.071872 -345.364308) (xy 386.640832 -345.933268) (xy 386.640832 -348.338902) (xy 386.291328 -348.68866)
			(xy 382.212088 -348.68866) (xy 381.639064 -348.115636) (xy 381.639064 -339.35035) (xy 381.639064 -339.339428)
			(xy 381.639064 -337.53552) (xy 381.438912 -337.335368) (xy 377.910852 -337.335368) (xy 377.910852 -340.013036)
			(xy 378.639324 -340.741254) (xy 378.639324 -342.498934) (xy 378.284232 -342.854026)
			(arc
				(start 378.280676 -342.86571)
				(mid 378.155654 -343.071142)
				(end 377.950222 -343.196164)
			)
			(xy 377.938538 -343.19972) (xy 377.796044 -343.342468) (xy 374.184164 -343.342468) (xy 373.364252 -342.522302)
			(xy 373.364252 -334.011778) (xy 373.279924 -333.927704) (xy 369.777518 -333.927704) (xy 369.739672 -333.965296)
			(xy 369.739672 -335.994502) (xy 370.448332 -336.702654) (xy 370.448332 -339.336634) (xy 369.852448 -339.932264)
			(xy 366.187482 -339.932264) (xy 365.187992 -338.933028) (xy 365.187992 -334.003396) (xy 365.113316 -333.92872)
			(xy 361.634532 -333.92872) (xy 361.597956 -333.965296) (xy 361.597956 -335.956148) (xy 362.242608 -336.6008)
			(xy 362.242608 -339.24113) (xy 362.077254 -339.406738)
			(arc
				(start 362.073444 -339.415374)
				(mid 361.968277 -339.568525)
				(end 361.815126 -339.673692)
			)
			(xy 361.80649 -339.677502) (xy 361.712764 -339.771228)
			(arc
				(start 358.669082 -339.771228)
				(mid 358.55118 -339.817513)
				(end 358.425496 -339.833204)
			)
			(arc
				(start 358.425496 -339.833204)
				(mid 358.305662 -339.818944)
				(end 358.192578 -339.776816)
			)
			(xy 358.181656 -339.771228) (xy 357.94696 -339.771228) (xy 356.817676 -338.641944) (xy 356.817676 -337.528154)
			(xy 357.07066 -337.275678) (xy 357.07066 -334.037686) (xy 356.960678 -333.927704) (xy 353.477068 -333.927704)
			(xy 353.416108 -333.988918) (xy 353.416108 -335.977992) (xy 354.221796 -336.783426) (xy 354.221796 -339.288628)
			(xy 354.056188 -339.453982)
			(arc
				(start 354.052378 -339.462618)
				(mid 353.94683 -339.616658)
				(end 353.79279 -339.722206)
			)
			(xy 353.784154 -339.726016) (xy 353.715574 -339.794596) (xy 350.551496 -339.794596)
			(arc
				(start 350.541844 -339.799168)
				(mid 350.44065 -339.832022)
				(end 350.334834 -339.84311)
			)
			(arc
				(start 350.334834 -339.84311)
				(mid 350.229016 -339.832032)
				(end 350.127824 -339.799168)
			)
			(xy 350.118172 -339.794596) (xy 349.810578 -339.794596) (xy 348.8055 -338.789518) (xy 348.8055 -333.983584)
			(xy 348.751398 -333.929736) (xy 345.30919 -333.929736) (xy 345.256612 -333.98206) (xy 345.256612 -335.940654)
			(xy 346.182696 -336.86623) (xy 346.182696 -339.001862) (xy 345.42222 -339.762084)
			(arc
				(start 342.3793 -339.762084)
				(mid 342.264149 -339.806019)
				(end 342.14181 -339.821012)
			)
			(arc
				(start 342.14181 -339.821012)
				(mid 342.019457 -339.806073)
				(end 341.90432 -339.762084)
			)
			(xy 340.9315 -339.762084) (xy 340.605364 -339.436202) (xy 340.605364 -337.401916) (xy 340.56193 -337.358228)
			(xy 337.119722 -337.358228) (xy 337.11896 -337.359244) (xy 337.11896 -339.601302) (xy 337.782408 -340.264496)
			(xy 337.782408 -342.433402) (xy 337.613244 -342.602566) (xy 337.615022 -342.62568)
			(arc
				(start 337.616292 -342.663272)
				(mid 337.467353 -343.022841)
				(end 337.107784 -343.17178)
			)
			(xy 337.070192 -343.17051) (xy 337.047078 -343.168732) (xy 336.588608 -343.626948) (xy 333.03083 -343.626948)
			(xy 332.555596 -343.15146) (xy 329.004168 -343.15146) (xy 328.908156 -343.247472) (xy 328.908156 -343.512902)
			(xy 328.90841 -343.514172) (xy 328.909172 -343.542874) (xy 328.90841 -343.571576) (xy 328.908156 -343.572846)
			(xy 328.908156 -344.935302) (xy 328.90841 -344.936572) (xy 328.909172 -344.965274) (xy 328.90841 -344.993976)
			(xy 328.908156 -344.995246) (xy 328.908156 -345.17965) (xy 331.076808 -347.347794) (xy 331.076808 -348.796864)
			(xy 331.282548 -349.002604)
			(arc
				(start 333.772764 -349.002604)
				(mid 333.869951 -349.021954)
				(end 333.952342 -349.077026)
			)
			(xy 336.296762 -351.421446) (xy 343.682828 -351.421446)
			(arc
				(start 345.482164 -349.62211)
				(mid 345.564541 -349.567004)
				(end 345.661742 -349.547688)
			)
			(arc
				(start 361.442 -349.547688)
				(mid 361.539187 -349.567038)
				(end 361.621578 -349.62211)
			)
			(xy 363.695996 -351.696528) (xy 367.846864 -351.696528)
		)
		(stroke
			(width 0)
			(type solid)
		)
		(fill yes)
		(layer "In9.Cu")
		(net "SW_P12V_PVCCIN_CPU0_FLT")
	)
	(gr_poly
		(pts
			(xy 230.38054 -434.93182)
			(arc
				(start 230.38054 -423.43324)
				(mid 230.404693 -423.311724)
				(end 230.473504 -423.208704)
			)
			(arc
				(start 232.947464 -420.734744)
				(mid 233.050496 -420.665963)
				(end 233.172 -420.64178)
			)
			(xy 270.34998 -420.64178)
			(arc
				(start 275.456396 -415.535364)
				(mid 275.559428 -415.466583)
				(end 275.680932 -415.4424)
			)
			(xy 279.79624 -415.4424) (xy 280.19756 -415.04108) (xy 280.19756 -408.29992) (xy 279.96896 -408.07132)
			(arc
				(start 239.699292 -408.07132)
				(mid 239.577776 -408.047167)
				(end 239.474756 -407.978356)
			)
			(xy 237.61446 -406.11806)
			(arc
				(start 235.520992 -406.11806)
				(mid 235.399476 -406.093907)
				(end 235.296456 -406.025096)
			)
			(arc
				(start 233.973624 -404.702264)
				(mid 233.904843 -404.599232)
				(end 233.88066 -404.477728)
			)
			(xy 233.88066 -401.03298) (xy 233.86542 -401.01774) (xy 230.47706 -401.01774) (xy 230.46182 -401.03298)
			(arc
				(start 230.46182 -404.473156)
				(mid 230.437667 -404.594672)
				(end 230.368856 -404.697692)
			)
			(xy 230.256588 -404.80996)
			(arc
				(start 230.256588 -407.3906)
				(mid 230.232435 -407.512116)
				(end 230.163624 -407.615136)
			)
			(arc
				(start 228.159564 -409.619196)
				(mid 228.056532 -409.687977)
				(end 227.935028 -409.71216)
			)
			(arc
				(start 225.70694 -409.71216)
				(mid 225.585424 -409.688007)
				(end 225.482404 -409.619196)
			)
			(arc
				(start 223.491552 -407.628344)
				(mid 223.422771 -407.525312)
				(end 223.398588 -407.403808)
			)
			(xy 223.398588 -404.79218)
			(arc
				(start 223.310704 -404.704296)
				(mid 223.241923 -404.601264)
				(end 223.21774 -404.47976)
			)
			(xy 223.21774 -401.04568) (xy 223.19234 -401.02028) (xy 219.81414 -401.02028) (xy 219.79636 -401.03806)
			(arc
				(start 219.79636 -404.490936)
				(mid 219.772207 -404.612452)
				(end 219.703396 -404.715472)
			)
			(xy 219.613988 -404.80488)
			(arc
				(start 219.613988 -407.259028)
				(mid 219.589835 -407.380544)
				(end 219.521024 -407.483564)
			)
			(arc
				(start 217.497152 -409.507436)
				(mid 217.39412 -409.576217)
				(end 217.272616 -409.6004)
			)
			(arc
				(start 214.794592 -409.6004)
				(mid 214.673076 -409.576247)
				(end 214.570056 -409.507436)
			)
			(arc
				(start 212.812884 -407.750264)
				(mid 212.744103 -407.647232)
				(end 212.71992 -407.525728)
			)
			(xy 212.71992 -404.79472)
			(arc
				(start 212.635084 -404.709884)
				(mid 212.566303 -404.606852)
				(end 212.54212 -404.485348)
			)
			(xy 212.54212 -401.02536) (xy 212.53704 -401.02028) (xy 209.14106 -401.02028) (xy 209.13598 -401.02536)
			(arc
				(start 209.13598 -404.452836)
				(mid 209.111827 -404.574352)
				(end 209.043016 -404.677372)
			)
			(xy 208.945988 -404.7744)
			(arc
				(start 208.945988 -407.30424)
				(mid 208.921835 -407.425756)
				(end 208.853024 -407.528776)
			)
			(arc
				(start 206.770224 -409.611576)
				(mid 206.667192 -409.680357)
				(end 206.545688 -409.70454)
			)
			(arc
				(start 204.16012 -409.70454)
				(mid 204.038604 -409.680387)
				(end 203.935584 -409.611576)
			)
			(arc
				(start 202.155552 -407.831544)
				(mid 202.086771 -407.728512)
				(end 202.062588 -407.607008)
			)
			(xy 202.062588 -404.779988)
			(arc
				(start 201.969624 -404.687024)
				(mid 201.900843 -404.583992)
				(end 201.87666 -404.462488)
			)
			(xy 201.87666 -401.03298) (xy 201.86396 -401.02028) (xy 198.47306 -401.02028) (xy 198.46798 -401.02536)
			(arc
				(start 198.46798 -404.487888)
				(mid 198.443827 -404.609404)
				(end 198.375016 -404.712424)
			)
			(arc
				(start 197.194424 -405.893016)
				(mid 197.091392 -405.961797)
				(end 196.969888 -405.98598)
			)
			(arc
				(start 190.870332 -405.98598)
				(mid 190.748816 -405.961827)
				(end 190.645796 -405.893016)
			)
			(arc
				(start 189.455552 -404.702518)
				(mid 189.386771 -404.599486)
				(end 189.362588 -404.477982)
			)
			(xy 189.362588 -404.177754) (xy 189.337188 -404.152354)
			(arc
				(start 189.11316 -404.152354)
				(mid 188.991644 -404.128201)
				(end 188.888624 -404.05939)
			)
			(arc
				(start 188.710824 -403.88159)
				(mid 188.642043 -403.778558)
				(end 188.61786 -403.657054)
			)
			(xy 188.61786 -401.02028) (xy 188.600588 -401.002754) (xy 185.196988 -401.002754) (xy 185.196988 -406.489154)
			(arc
				(start 185.434224 -406.72639)
				(mid 185.480227 -406.78458)
				(end 185.51144 -406.851866)
			)
			(arc
				(start 185.51144 -406.851866)
				(mid 185.548193 -406.942536)
				(end 185.560716 -407.039572)
			)
			(arc
				(start 185.560716 -407.039572)
				(mid 185.553298 -407.114694)
				(end 185.531252 -407.186892)
			)
			(xy 185.527188 -407.19629)
			(arc
				(start 185.527188 -408.287982)
				(mid 185.503035 -408.409498)
				(end 185.434224 -408.512518)
			)
			(xy 185.323988 -408.622754) (xy 185.323988 -413.053276) (xy 192.879472 -420.60876)
			(arc
				(start 197.414388 -420.60876)
				(mid 197.535904 -420.632913)
				(end 197.638924 -420.701724)
			)
			(arc
				(start 206.398876 -429.461676)
				(mid 206.467657 -429.564708)
				(end 206.49184 -429.686212)
			)
			(xy 206.49184 -435.39156) (xy 207.63484 -436.53456) (xy 228.7778 -436.53456)
		)
		(stroke
			(width 0)
			(type solid)
		)
		(fill yes)
		(layer "In9.Cu")
		(net "P12V_PSU")
	)
	(gr_poly
		(pts
			(xy 13.1318 -318.266826) (xy 13.148732 -318.245178) (xy 13.188136 -318.206868) (xy 13.232958 -318.175068)
			(xy 13.282134 -318.150532) (xy 13.334497 -318.133844) (xy 13.388801 -318.1254) (xy 13.443759 -318.1254)
			(xy 13.498063 -318.133844) (xy 13.550426 -318.150532) (xy 13.599602 -318.175068) (xy 13.644424 -318.206868)
			(xy 13.683828 -318.245178) (xy 13.70076 -318.266826) (xy 21.256244 -318.266826) (xy 21.266658 -318.261746)
			(xy 21.290828 -318.250656) (xy 21.341657 -318.235027) (xy 21.394247 -318.227149) (xy 21.420836 -318.226694)
			(xy 21.44742 -318.227193) (xy 21.499999 -318.235096) (xy 21.550824 -318.250708) (xy 21.575014 -318.261746)
			(xy 21.585428 -318.266826) (xy 30.647386 -318.266826) (xy 31.232602 -317.68161) (xy 31.235142 -317.67907)
			(xy 31.235142 -219.006166) (xy 31.235717 -218.981207) (xy 31.245463 -218.93225) (xy 31.264573 -218.886135)
			(xy 31.292314 -218.844635) (xy 31.309564 -218.826588) (xy 31.548578 -218.587574) (xy 31.548578 -218.566492)
			(xy 31.549098 -218.540729) (xy 31.557185 -218.489841) (xy 31.573126 -218.440843) (xy 31.59653 -218.394938)
			(xy 31.626822 -218.353256) (xy 31.663256 -218.316822) (xy 31.704938 -218.28653) (xy 31.750843 -218.263126)
			(xy 31.799841 -218.247185) (xy 31.850729 -218.239098) (xy 31.876492 -218.238578) (xy 31.897574 -218.238578)
			(xy 31.991808 -218.144344) (xy 32.009849 -218.127082) (xy 32.051342 -218.099321) (xy 32.097459 -218.080202)
			(xy 32.146424 -218.070463) (xy 32.171386 -218.069922) (xy 60.33389 -218.069922) (xy 60.88634 -217.517472)
			(xy 60.88634 -162.320478) (xy 60.88253 -162.31108) (xy 60.872572 -162.285308) (xy 60.859842 -162.231546)
			(xy 60.855568 -162.176463) (xy 60.859853 -162.121381) (xy 60.872594 -162.067622) (xy 60.88253 -162.04184)
			(xy 60.88634 -162.032442) (xy 60.88634 -160.372298) (xy 60.88253 -160.3629) (xy 60.87257 -160.337128)
			(xy 60.859837 -160.283365) (xy 60.85556 -160.228281) (xy 60.859843 -160.173198) (xy 60.872582 -160.119437)
			(xy 60.88253 -160.09366) (xy 60.88634 -160.084262) (xy 60.88634 -159.711898) (xy 60.88253 -159.7025)
			(xy 60.87257 -159.676728) (xy 60.859837 -159.622965) (xy 60.85556 -159.567881) (xy 60.859843 -159.512798)
			(xy 60.872582 -159.459037) (xy 60.88253 -159.43326) (xy 60.88634 -159.423862) (xy 60.88634 -153.684478)
			(xy 60.88253 -153.67508) (xy 60.872572 -153.649308) (xy 60.859842 -153.595546) (xy 60.855568 -153.540463)
			(xy 60.859853 -153.485381) (xy 60.872594 -153.431622) (xy 60.88253 -153.40584) (xy 60.88634 -153.396442)
			(xy 60.88634 -151.736298) (xy 60.88253 -151.7269) (xy 60.87257 -151.701128) (xy 60.859837 -151.647365)
			(xy 60.85556 -151.592281) (xy 60.859843 -151.537198) (xy 60.872582 -151.483437) (xy 60.88253 -151.45766)
			(xy 60.88634 -151.448262) (xy 60.88634 -151.075898) (xy 60.88253 -151.0665) (xy 60.87257 -151.040728)
			(xy 60.859837 -150.986965) (xy 60.85556 -150.931881) (xy 60.859843 -150.876798) (xy 60.872582 -150.823037)
			(xy 60.88253 -150.79726) (xy 60.88634 -150.787862) (xy 60.88634 -145.048478) (xy 60.88253 -145.03908)
			(xy 60.872572 -145.013308) (xy 60.859842 -144.959546) (xy 60.855568 -144.904463) (xy 60.859853 -144.849381)
			(xy 60.872594 -144.795622) (xy 60.88253 -144.76984) (xy 60.88634 -144.760442) (xy 60.88634 -139.192254)
			(xy 60.394596 -138.70051) (xy 50.025554 -138.70051) (xy 49.392078 -139.333986) (xy 49.392078 -153.3017)
			(xy 49.423828 -153.3144) (xy 49.448211 -153.324722) (xy 49.493875 -153.351521) (xy 49.535069 -153.384785)
			(xy 49.570885 -153.42378) (xy 49.600534 -153.467647) (xy 49.623362 -153.51542) (xy 49.638867 -153.566046)
			(xy 49.646708 -153.618409) (xy 49.64671 -153.671356) (xy 49.638875 -153.723721) (xy 49.623375 -153.774348)
			(xy 49.600551 -153.822123) (xy 49.570906 -153.865993) (xy 49.535094 -153.904992) (xy 49.493903 -153.938259)
			(xy 49.448242 -153.965063) (xy 49.423828 -153.975308) (xy 49.392078 -153.988008) (xy 49.392078 -157.887162)
			(xy 49.391461 -157.912116) (xy 49.381712 -157.961063) (xy 49.362602 -158.007167) (xy 49.334865 -158.048658)
			(xy 49.317656 -158.06674) (xy 48.11903 -159.265366) (xy 48.100988 -159.282622) (xy 48.059492 -159.310373)
			(xy 48.013375 -159.32948) (xy 47.964412 -159.339206) (xy 47.939452 -159.339788) (xy 17.885156 -159.339788)
			(xy 15.4559 -161.769044) (xy 15.430139 -161.870778) (xy 15.424197 -161.891218) (xy 43.40429 -161.891218)
			(xy 43.408291 -161.803402) (xy 43.420261 -161.716314) (xy 43.4401 -161.630675) (xy 43.467645 -161.547195)
			(xy 43.502668 -161.466566) (xy 43.544877 -161.389456) (xy 43.593923 -161.316503) (xy 43.6494 -161.248312)
			(xy 43.710848 -161.185449) (xy 43.777758 -161.128434) (xy 43.849575 -161.07774) (xy 43.925705 -161.033787)
			(xy 44.005516 -160.996938) (xy 44.088347 -160.9675) (xy 44.173512 -160.945716) (xy 44.260306 -160.931767)
			(xy 44.348008 -160.925768) (xy 44.435892 -160.927769) (xy 44.52323 -160.937753) (xy 44.609298 -160.955638)
			(xy 44.693383 -160.981276) (xy 44.774789 -161.014454) (xy 44.85284 -161.054897) (xy 44.92689 -161.10227)
			(xy 44.996326 -161.15618) (xy 45.060572 -161.216181) (xy 45.119095 -161.281776) (xy 45.171411 -161.352421)
			(xy 45.217086 -161.42753) (xy 45.255741 -161.506482) (xy 45.287058 -161.588622) (xy 45.310775 -161.673269)
			(xy 45.326696 -161.759722) (xy 45.33469 -161.847265) (xy 45.33519 -161.891218) (xy 45.33469 -161.935171)
			(xy 45.326696 -162.022714) (xy 45.310775 -162.109167) (xy 45.287058 -162.193814) (xy 45.255741 -162.275954)
			(xy 45.217086 -162.354906) (xy 45.171411 -162.430015) (xy 45.119095 -162.50066) (xy 45.060572 -162.566255)
			(xy 44.996326 -162.626256) (xy 44.92689 -162.680166) (xy 44.85284 -162.727539) (xy 44.774789 -162.767982)
			(xy 44.693383 -162.80116) (xy 44.609298 -162.826798) (xy 44.52323 -162.844683) (xy 44.435892 -162.854667)
			(xy 44.348008 -162.856668) (xy 44.260306 -162.850669) (xy 44.173512 -162.83672) (xy 44.088347 -162.814936)
			(xy 44.005516 -162.785498) (xy 43.925705 -162.748649) (xy 43.849575 -162.704696) (xy 43.777758 -162.654002)
			(xy 43.710848 -162.596987) (xy 43.6494 -162.534124) (xy 43.593923 -162.465933) (xy 43.544877 -162.39298)
			(xy 43.502668 -162.31587) (xy 43.467645 -162.235241) (xy 43.4401 -162.151761) (xy 43.420261 -162.066122)
			(xy 43.408291 -161.979034) (xy 43.40429 -161.891218) (xy 15.424197 -161.891218) (xy 15.37155 -162.072322)
			(xy 15.304985 -162.271375) (xy 15.23055 -162.46762) (xy 15.14836 -162.660746) (xy 15.058549 -162.850447)
			(xy 14.961256 -163.036423) (xy 14.856638 -163.218378) (xy 14.744859 -163.396024) (xy 14.626097 -163.56908)
			(xy 14.50054 -163.737271) (xy 14.368387 -163.900331) (xy 14.229849 -164.058) (xy 14.085143 -164.21003)
			(xy 13.9345 -164.356178) (xy 13.778159 -164.496215) (xy 13.616367 -164.629916) (xy 13.44938 -164.757071)
			(xy 13.277465 -164.877478) (xy 13.189458 -164.934646) (xy 13.189458 -169.801794) (xy 43.330122 -169.801794)
			(xy 43.334123 -169.713978) (xy 43.346093 -169.62689) (xy 43.365932 -169.541251) (xy 43.393477 -169.457771)
			(xy 43.4285 -169.377142) (xy 43.470709 -169.300032) (xy 43.519755 -169.227079) (xy 43.575232 -169.158888)
			(xy 43.63668 -169.096025) (xy 43.70359 -169.03901) (xy 43.775407 -168.988316) (xy 43.851537 -168.944363)
			(xy 43.931348 -168.907514) (xy 44.014179 -168.878076) (xy 44.099344 -168.856292) (xy 44.186138 -168.842343)
			(xy 44.27384 -168.836344) (xy 44.361724 -168.838345) (xy 44.449062 -168.848329) (xy 44.53513 -168.866214)
			(xy 44.619215 -168.891852) (xy 44.700621 -168.92503) (xy 44.778672 -168.965473) (xy 44.852722 -169.012846)
			(xy 44.922158 -169.066756) (xy 44.986404 -169.126757) (xy 45.044927 -169.192352) (xy 45.097243 -169.262997)
			(xy 45.142918 -169.338106) (xy 45.181573 -169.417058) (xy 45.21289 -169.499198) (xy 45.236607 -169.583845)
			(xy 45.252528 -169.670298) (xy 45.260522 -169.757841) (xy 45.261022 -169.801794) (xy 45.260522 -169.845747)
			(xy 45.252528 -169.93329) (xy 45.236607 -170.019743) (xy 45.21289 -170.10439) (xy 45.181573 -170.18653)
			(xy 45.142918 -170.265482) (xy 45.097243 -170.340591) (xy 45.044927 -170.411236) (xy 44.986404 -170.476831)
			(xy 44.922158 -170.536832) (xy 44.852722 -170.590742) (xy 44.778672 -170.638115) (xy 44.700621 -170.678558)
			(xy 44.619215 -170.711736) (xy 44.53513 -170.737374) (xy 44.449062 -170.755259) (xy 44.361724 -170.765243)
			(xy 44.27384 -170.767244) (xy 44.186138 -170.761245) (xy 44.099344 -170.747296) (xy 44.014179 -170.725512)
			(xy 43.931348 -170.696074) (xy 43.851537 -170.659225) (xy 43.775407 -170.615272) (xy 43.70359 -170.564578)
			(xy 43.63668 -170.507563) (xy 43.575232 -170.4447) (xy 43.519755 -170.376509) (xy 43.470709 -170.303556)
			(xy 43.4285 -170.226446) (xy 43.393477 -170.145817) (xy 43.365932 -170.062337) (xy 43.346093 -169.976698)
			(xy 43.334123 -169.88961) (xy 43.330122 -169.801794) (xy 13.189458 -169.801794) (xy 13.189458 -175.83404)
			(xy 23.37714 -175.83404) (xy 23.381229 -175.778158) (xy 23.393412 -175.723468) (xy 23.413428 -175.671134)
			(xy 23.440851 -175.622272) (xy 23.475096 -175.577924) (xy 23.515432 -175.539034) (xy 23.561002 -175.506432)
			(xy 23.610833 -175.480813) (xy 23.663863 -175.462721) (xy 23.718961 -175.452544) (xy 23.774955 -175.450498)
			(xy 23.83065 -175.456626) (xy 23.884859 -175.470798) (xy 23.936427 -175.492712) (xy 23.984255 -175.521901)
			(xy 24.027323 -175.557742) (xy 24.064713 -175.599472) (xy 24.095629 -175.646202) (xy 24.119412 -175.696935)
			(xy 24.135554 -175.750591) (xy 24.143713 -175.806025) (xy 24.144224 -175.83404) (xy 24.143713 -175.862055)
			(xy 24.135554 -175.917489) (xy 24.119412 -175.971145) (xy 24.095629 -176.021878) (xy 24.064713 -176.068608)
			(xy 24.027323 -176.110338) (xy 23.984255 -176.146179) (xy 23.936427 -176.175368) (xy 23.884859 -176.197282)
			(xy 23.83065 -176.211454) (xy 23.774955 -176.217582) (xy 23.718961 -176.215536) (xy 23.663863 -176.205359)
			(xy 23.610833 -176.187267) (xy 23.561002 -176.161648) (xy 23.515432 -176.129046) (xy 23.475096 -176.090156)
			(xy 23.440851 -176.045808) (xy 23.413428 -175.996946) (xy 23.393412 -175.944612) (xy 23.381229 -175.889922)
			(xy 23.37714 -175.83404) (xy 13.189458 -175.83404) (xy 13.189458 -176.65065) (xy 13.189076 -176.670705)
			(xy 13.182766 -176.710316) (xy 13.170309 -176.748444) (xy 13.161518 -176.766474) (xy 6.615938 -189.53988)
			(xy 6.615938 -194.36334) (xy 6.617716 -194.369944) (xy 6.623434 -194.392628) (xy 6.629553 -194.439009)
			(xy 6.629908 -194.4624) (xy 6.629535 -194.48579) (xy 6.623416 -194.532168) (xy 6.617716 -194.554856)
			(xy 6.615938 -194.56146) (xy 6.615938 -317.725298) (xy 7.157466 -318.266826)
		)
		(stroke
			(width 0)
			(type solid)
		)
		(fill yes)
		(layer "In9.Cu")
		(net "GND")
	)
	(gr_poly
		(pts
			(xy 193.607436 -440.465972) (xy 193.630444 -440.405446) (xy 193.683164 -440.287163) (xy 193.743337 -440.172493)
			(xy 193.810717 -440.061903) (xy 193.885029 -439.955847) (xy 193.965968 -439.854758) (xy 194.053203 -439.759049)
			(xy 194.146378 -439.669112) (xy 194.245112 -439.585316) (xy 194.349 -439.508002) (xy 194.457617 -439.437487)
			(xy 194.57052 -439.37406) (xy 194.687247 -439.317979) (xy 194.80732 -439.269475) (xy 194.930248 -439.228745)
			(xy 195.055527 -439.195957) (xy 195.182647 -439.171243) (xy 195.311086 -439.154707) (xy 195.44032 -439.146414)
			(xy 195.50507 -439.145934) (xy 276.314916 -439.145934) (xy 276.379667 -439.146447) (xy 276.508904 -439.154722)
			(xy 276.637348 -439.171243) (xy 276.764472 -439.195942) (xy 276.889757 -439.22872) (xy 277.01269 -439.26944)
			(xy 277.132768 -439.317938) (xy 277.2495 -439.374014) (xy 277.362407 -439.437438) (xy 277.471028 -439.507952)
			(xy 277.574918 -439.585267) (xy 277.673652 -439.669066) (xy 277.766826 -439.759006) (xy 277.854059 -439.85472)
			(xy 277.934994 -439.955815) (xy 278.009299 -440.061879) (xy 278.076671 -440.172476) (xy 278.136833 -440.287155)
			(xy 278.18954 -440.405445) (xy 278.21255 -440.465972) (xy 309.545736 -440.465972) (xy 309.96636 -440.045348)
			(xy 309.96636 -416.488372) (xy 308.96814 -415.490152) (xy 280.646632 -415.490152) (xy 280.152348 -415.984436)
			(xy 280.13435 -416.001722) (xy 280.093968 -416.031034) (xy 280.049502 -416.053677) (xy 280.002045 -416.069094)
			(xy 279.952761 -416.076908) (xy 279.927812 -416.0774) (xy 275.812504 -416.0774) (xy 270.706088 -421.183816)
			(xy 270.688089 -421.2011) (xy 270.647706 -421.23041) (xy 270.60324 -421.253053) (xy 270.555784 -421.268472)
			(xy 270.506501 -421.27629) (xy 270.481552 -421.27678) (xy 233.303572 -421.27678) (xy 231.01554 -423.564812)
			(xy 231.01554 -433.130695) (xy 266.885917 -433.130695) (xy 266.885917 -432.953425) (xy 266.89387 -432.776334)
			(xy 266.909761 -432.599778) (xy 266.933556 -432.424113) (xy 266.965209 -432.249692) (xy 267.004655 -432.076867)
			(xy 267.051815 -431.905986) (xy 267.106594 -431.737392) (xy 267.168882 -431.571427) (xy 267.238554 -431.408422)
			(xy 267.315468 -431.248708) (xy 267.399471 -431.092605) (xy 267.490392 -430.940428) (xy 267.588049 -430.792484)
			(xy 267.692246 -430.64907) (xy 267.802772 -430.510475) (xy 267.919404 -430.376978) (xy 268.041909 -430.248849)
			(xy 268.170038 -430.126344) (xy 268.303535 -430.009712) (xy 268.44213 -429.899186) (xy 268.585544 -429.794989)
			(xy 268.733488 -429.697332) (xy 268.885665 -429.606411) (xy 269.041768 -429.522408) (xy 269.201482 -429.445494)
			(xy 269.364487 -429.375822) (xy 269.530452 -429.313534) (xy 269.699046 -429.258755) (xy 269.869927 -429.211595)
			(xy 270.042752 -429.172149) (xy 270.217173 -429.140496) (xy 270.392838 -429.116701) (xy 270.569394 -429.10081)
			(xy 270.746485 -429.092857) (xy 270.923755 -429.092857) (xy 271.100846 -429.10081) (xy 271.277402 -429.116701)
			(xy 271.453067 -429.140496) (xy 271.627488 -429.172149) (xy 271.800313 -429.211595) (xy 271.971194 -429.258755)
			(xy 272.139788 -429.313534) (xy 272.305753 -429.375822) (xy 272.468758 -429.445494) (xy 272.628472 -429.522408)
			(xy 272.784575 -429.606411) (xy 272.936752 -429.697332) (xy 273.084696 -429.794989) (xy 273.22811 -429.899186)
			(xy 273.366705 -430.009712) (xy 273.500202 -430.126344) (xy 273.628331 -430.248849) (xy 273.750836 -430.376978)
			(xy 273.867468 -430.510475) (xy 273.977994 -430.64907) (xy 274.082191 -430.792484) (xy 274.179848 -430.940428)
			(xy 274.270769 -431.092605) (xy 274.354772 -431.248708) (xy 274.431686 -431.408422) (xy 274.501358 -431.571427)
			(xy 274.563646 -431.737392) (xy 274.618425 -431.905986) (xy 274.665585 -432.076867) (xy 274.705031 -432.249692)
			(xy 274.736684 -432.424113) (xy 274.760479 -432.599778) (xy 274.77637 -432.776334) (xy 274.784323 -432.953425)
			(xy 274.78482 -433.04206) (xy 274.784323 -433.130695) (xy 274.77637 -433.307786) (xy 274.760479 -433.484342)
			(xy 274.736684 -433.660007) (xy 274.705031 -433.834428) (xy 274.665585 -434.007253) (xy 274.618425 -434.178134)
			(xy 274.563646 -434.346728) (xy 274.501358 -434.512693) (xy 274.431686 -434.675698) (xy 274.354772 -434.835412)
			(xy 274.270769 -434.991515) (xy 274.179848 -435.143692) (xy 274.082191 -435.291636) (xy 273.977994 -435.43505)
			(xy 273.867468 -435.573645) (xy 273.750836 -435.707142) (xy 273.628331 -435.835271) (xy 273.500202 -435.957776)
			(xy 273.366705 -436.074408) (xy 273.22811 -436.184934) (xy 273.084696 -436.289131) (xy 272.936752 -436.386788)
			(xy 272.784575 -436.477709) (xy 272.628472 -436.561712) (xy 272.468758 -436.638626) (xy 272.305753 -436.708298)
			(xy 272.139788 -436.770586) (xy 271.971194 -436.825365) (xy 271.800313 -436.872525) (xy 271.627488 -436.911971)
			(xy 271.453067 -436.943624) (xy 271.277402 -436.967419) (xy 271.100846 -436.98331) (xy 270.923755 -436.991263)
			(xy 270.746485 -436.991263) (xy 270.569394 -436.98331) (xy 270.392838 -436.967419) (xy 270.217173 -436.943624)
			(xy 270.042752 -436.911971) (xy 269.869927 -436.872525) (xy 269.699046 -436.825365) (xy 269.530452 -436.770586)
			(xy 269.364487 -436.708298) (xy 269.201482 -436.638626) (xy 269.041768 -436.561712) (xy 268.885665 -436.477709)
			(xy 268.733488 -436.386788) (xy 268.585544 -436.289131) (xy 268.44213 -436.184934) (xy 268.303535 -436.074408)
			(xy 268.170038 -435.957776) (xy 268.041909 -435.835271) (xy 267.919404 -435.707142) (xy 267.802772 -435.573645)
			(xy 267.692246 -435.43505) (xy 267.588049 -435.291636) (xy 267.490392 -435.143692) (xy 267.399471 -434.991515)
			(xy 267.315468 -434.835412) (xy 267.238554 -434.675698) (xy 267.168882 -434.512693) (xy 267.106594 -434.346728)
			(xy 267.051815 -434.178134) (xy 267.004655 -434.007253) (xy 266.965209 -433.834428) (xy 266.933556 -433.660007)
			(xy 266.909761 -433.484342) (xy 266.89387 -433.307786) (xy 266.885917 -433.130695) (xy 231.01554 -433.130695)
			(xy 231.01554 -435.063392) (xy 231.015051 -435.088342) (xy 231.007247 -435.137627) (xy 230.99183 -435.185086)
			(xy 230.96918 -435.229548) (xy 230.939853 -435.269921) (xy 230.922576 -435.287928) (xy 229.133908 -437.076596)
			(xy 229.115908 -437.093876) (xy 229.075523 -437.123178) (xy 229.031056 -437.145811) (xy 228.9836 -437.161219)
			(xy 228.934319 -437.169025) (xy 228.909372 -437.16956) (xy 207.503268 -437.16956) (xy 207.478316 -437.169076)
			(xy 207.429025 -437.161281) (xy 207.38156 -437.145871) (xy 207.33709 -437.123227) (xy 207.29671 -437.093905)
			(xy 207.278732 -437.076596) (xy 205.949804 -435.747668) (xy 205.93252 -435.729669) (xy 205.903211 -435.689286)
			(xy 205.88057 -435.64482) (xy 205.865152 -435.597363) (xy 205.857337 -435.548081) (xy 205.85684 -435.523132)
			(xy 205.85684 -429.817784) (xy 197.282816 -421.24376) (xy 192.7479 -421.24376) (xy 192.72295 -421.243271)
			(xy 192.673665 -421.235466) (xy 192.626207 -421.220049) (xy 192.581744 -421.197399) (xy 192.541371 -421.168073)
			(xy 192.523364 -421.150796) (xy 185.6994 -414.326832) (xy 181.345586 -414.326832) (xy 181.342538 -414.327086)
			(xy 181.332666 -414.328145) (xy 181.312842 -414.329286) (xy 181.302914 -414.329372) (xy 181.292986 -414.32928)
			(xy 181.273163 -414.328136) (xy 181.26329 -414.327086) (xy 181.260242 -414.326832) (xy 180.598826 -414.326832)
			(xy 180.591206 -414.329118) (xy 180.565269 -414.336788) (xy 180.511822 -414.345084) (xy 180.48478 -414.345628)
			(xy 180.457734 -414.345125) (xy 180.40428 -414.336837) (xy 180.378354 -414.329118) (xy 180.370734 -414.326832)
			(xy 170.59656 -414.326832) (xy 167.90924 -417.014152) (xy 167.90924 -433.130695) (xy 197.035917 -433.130695)
			(xy 197.035917 -432.953425) (xy 197.04387 -432.776334) (xy 197.059761 -432.599778) (xy 197.083556 -432.424113)
			(xy 197.115209 -432.249692) (xy 197.154655 -432.076867) (xy 197.201815 -431.905986) (xy 197.256594 -431.737392)
			(xy 197.318882 -431.571427) (xy 197.388554 -431.408422) (xy 197.465468 -431.248708) (xy 197.549471 -431.092605)
			(xy 197.640392 -430.940428) (xy 197.738049 -430.792484) (xy 197.842246 -430.64907) (xy 197.952772 -430.510475)
			(xy 198.069404 -430.376978) (xy 198.191909 -430.248849) (xy 198.320038 -430.126344) (xy 198.453535 -430.009712)
			(xy 198.59213 -429.899186) (xy 198.735544 -429.794989) (xy 198.883488 -429.697332) (xy 199.035665 -429.606411)
			(xy 199.191768 -429.522408) (xy 199.351482 -429.445494) (xy 199.514487 -429.375822) (xy 199.680452 -429.313534)
			(xy 199.849046 -429.258755) (xy 200.019927 -429.211595) (xy 200.192752 -429.172149) (xy 200.367173 -429.140496)
			(xy 200.542838 -429.116701) (xy 200.719394 -429.10081) (xy 200.896485 -429.092857) (xy 201.073755 -429.092857)
			(xy 201.250846 -429.10081) (xy 201.427402 -429.116701) (xy 201.603067 -429.140496) (xy 201.777488 -429.172149)
			(xy 201.950313 -429.211595) (xy 202.121194 -429.258755) (xy 202.289788 -429.313534) (xy 202.455753 -429.375822)
			(xy 202.618758 -429.445494) (xy 202.778472 -429.522408) (xy 202.934575 -429.606411) (xy 203.086752 -429.697332)
			(xy 203.234696 -429.794989) (xy 203.37811 -429.899186) (xy 203.516705 -430.009712) (xy 203.650202 -430.126344)
			(xy 203.778331 -430.248849) (xy 203.900836 -430.376978) (xy 204.017468 -430.510475) (xy 204.127994 -430.64907)
			(xy 204.232191 -430.792484) (xy 204.329848 -430.940428) (xy 204.420769 -431.092605) (xy 204.504772 -431.248708)
			(xy 204.581686 -431.408422) (xy 204.651358 -431.571427) (xy 204.713646 -431.737392) (xy 204.768425 -431.905986)
			(xy 204.815585 -432.076867) (xy 204.855031 -432.249692) (xy 204.886684 -432.424113) (xy 204.910479 -432.599778)
			(xy 204.92637 -432.776334) (xy 204.934323 -432.953425) (xy 204.93482 -433.04206) (xy 204.934323 -433.130695)
			(xy 204.92637 -433.307786) (xy 204.910479 -433.484342) (xy 204.886684 -433.660007) (xy 204.855031 -433.834428)
			(xy 204.815585 -434.007253) (xy 204.768425 -434.178134) (xy 204.713646 -434.346728) (xy 204.651358 -434.512693)
			(xy 204.581686 -434.675698) (xy 204.504772 -434.835412) (xy 204.420769 -434.991515) (xy 204.329848 -435.143692)
			(xy 204.232191 -435.291636) (xy 204.127994 -435.43505) (xy 204.017468 -435.573645) (xy 203.900836 -435.707142)
			(xy 203.778331 -435.835271) (xy 203.650202 -435.957776) (xy 203.516705 -436.074408) (xy 203.37811 -436.184934)
			(xy 203.234696 -436.289131) (xy 203.086752 -436.386788) (xy 202.934575 -436.477709) (xy 202.778472 -436.561712)
			(xy 202.618758 -436.638626) (xy 202.455753 -436.708298) (xy 202.289788 -436.770586) (xy 202.121194 -436.825365)
			(xy 201.950313 -436.872525) (xy 201.777488 -436.911971) (xy 201.603067 -436.943624) (xy 201.427402 -436.967419)
			(xy 201.250846 -436.98331) (xy 201.073755 -436.991263) (xy 200.896485 -436.991263) (xy 200.719394 -436.98331)
			(xy 200.542838 -436.967419) (xy 200.367173 -436.943624) (xy 200.192752 -436.911971) (xy 200.019927 -436.872525)
			(xy 199.849046 -436.825365) (xy 199.680452 -436.770586) (xy 199.514487 -436.708298) (xy 199.351482 -436.638626)
			(xy 199.191768 -436.561712) (xy 199.035665 -436.477709) (xy 198.883488 -436.386788) (xy 198.735544 -436.289131)
			(xy 198.59213 -436.184934) (xy 198.453535 -436.074408) (xy 198.320038 -435.957776) (xy 198.191909 -435.835271)
			(xy 198.069404 -435.707142) (xy 197.952772 -435.573645) (xy 197.842246 -435.43505) (xy 197.738049 -435.291636)
			(xy 197.640392 -435.143692) (xy 197.549471 -434.991515) (xy 197.465468 -434.835412) (xy 197.388554 -434.675698)
			(xy 197.318882 -434.512693) (xy 197.256594 -434.346728) (xy 197.201815 -434.178134) (xy 197.154655 -434.007253)
			(xy 197.115209 -433.834428) (xy 197.083556 -433.660007) (xy 197.059761 -433.484342) (xy 197.04387 -433.307786)
			(xy 197.035917 -433.130695) (xy 167.90924 -433.130695) (xy 167.90924 -439.925968) (xy 168.449244 -440.465972)
		)
		(stroke
			(width 0)
			(type solid)
		)
		(fill yes)
		(layer "In9.Cu")
		(net "GND")
	)
	(gr_poly
		(pts
			(xy 531.7998 -462.520284) (xy 531.855607 -462.519775) (xy 531.96691 -462.511434) (xy 532.077278 -462.494798)
			(xy 532.186094 -462.469962) (xy 532.29275 -462.437062) (xy 532.396649 -462.396285) (xy 532.49721 -462.347857)
			(xy 532.593871 -462.292049) (xy 532.686092 -462.229174) (xy 532.773355 -462.159583) (xy 532.855174 -462.083666)
			(xy 532.931091 -462.001846) (xy 533.000681 -461.914582) (xy 533.063556 -461.822361) (xy 533.119362 -461.7257)
			(xy 533.16779 -461.625138) (xy 533.208566 -461.521239) (xy 533.241465 -461.414583) (xy 533.266301 -461.305766)
			(xy 533.282935 -461.195398) (xy 533.291275 -461.084095) (xy 533.291796 -461.028288) (xy 533.291796 -455.0283)
			(xy 533.291274 -454.972493) (xy 533.282933 -454.861191) (xy 533.266298 -454.750824) (xy 533.241462 -454.642008)
			(xy 533.208563 -454.535353) (xy 533.167786 -454.431454) (xy 533.119358 -454.330893) (xy 533.063551 -454.234233)
			(xy 533.000677 -454.142013) (xy 532.931086 -454.054749) (xy 532.85517 -453.97293) (xy 532.773351 -453.897014)
			(xy 532.686087 -453.827423) (xy 532.593867 -453.764549) (xy 532.497207 -453.708742) (xy 532.396646 -453.660314)
			(xy 532.292747 -453.619537) (xy 532.186092 -453.586638) (xy 532.077276 -453.561802) (xy 531.966909 -453.545167)
			(xy 531.855607 -453.536826) (xy 531.7998 -453.536304) (xy 516.019796 -453.536304) (xy 515.949442 -453.535811)
			(xy 515.808956 -453.527921) (xy 515.669133 -453.512166) (xy 515.530414 -453.488597) (xy 515.393234 -453.457286)
			(xy 515.258026 -453.418334) (xy 515.125215 -453.371861) (xy 514.995218 -453.318014) (xy 514.868445 -453.256963)
			(xy 514.745294 -453.188901) (xy 514.626154 -453.11404) (xy 514.511398 -453.032616) (xy 514.401389 -452.944887)
			(xy 514.296471 -452.851127) (xy 514.196976 -452.751632) (xy 514.103216 -452.646714) (xy 514.015486 -452.536705)
			(xy 513.934063 -452.421949) (xy 513.859201 -452.302809) (xy 513.791138 -452.179659) (xy 513.730087 -452.052886)
			(xy 513.676241 -451.922889) (xy 513.629768 -451.790078) (xy 513.590815 -451.65487) (xy 513.559504 -451.51769)
			(xy 513.535934 -451.378971) (xy 513.520179 -451.239148) (xy 513.512289 -451.098662) (xy 513.5118 -451.028308)
			(xy 513.5118 -312.408316) (xy 513.512284 -312.337962) (xy 513.520173 -312.197474) (xy 513.535926 -312.05765)
			(xy 513.559495 -311.91893) (xy 513.590805 -311.781749) (xy 513.629757 -311.646539) (xy 513.676229 -311.513726)
			(xy 513.730076 -311.383728) (xy 513.791126 -311.256954) (xy 513.859189 -311.133802) (xy 513.93405 -311.01466)
			(xy 514.015474 -310.899903) (xy 514.103203 -310.789893) (xy 514.196964 -310.684974) (xy 514.296459 -310.585477)
			(xy 514.401377 -310.491716) (xy 514.511387 -310.403986) (xy 514.626144 -310.322561) (xy 514.745285 -310.247699)
			(xy 514.868436 -310.179635) (xy 514.99521 -310.118584) (xy 515.125208 -310.064737) (xy 515.25802 -310.018263)
			(xy 515.393229 -309.97931) (xy 515.53041 -309.947999) (xy 515.669131 -309.924429) (xy 515.808954 -309.908674)
			(xy 515.949442 -309.900784) (xy 516.019796 -309.90032) (xy 531.7998 -309.90032) (xy 531.855607 -309.899798)
			(xy 531.96691 -309.891457) (xy 532.077278 -309.874822) (xy 532.186094 -309.849986) (xy 532.292751 -309.817087)
			(xy 532.39665 -309.77631) (xy 532.497211 -309.727883) (xy 532.593873 -309.672076) (xy 532.686094 -309.609202)
			(xy 532.773358 -309.539612) (xy 532.855178 -309.463695) (xy 532.931096 -309.381876) (xy 533.000687 -309.294613)
			(xy 533.063563 -309.202393) (xy 533.119372 -309.105733) (xy 533.167801 -309.005172) (xy 533.208579 -308.901273)
			(xy 533.24148 -308.794618) (xy 533.266318 -308.685802) (xy 533.282955 -308.575434) (xy 533.291297 -308.464131)
			(xy 533.291796 -308.408324) (xy 533.291796 10.40003) (xy 533.291273 10.455836) (xy 533.28293 10.567137)
			(xy 533.266293 10.677502) (xy 533.241455 10.786316) (xy 533.208555 10.89297) (xy 533.167777 10.996866)
			(xy 533.119348 11.097425) (xy 533.063541 11.194084) (xy 533.000666 11.286302) (xy 532.931076 11.373563)
			(xy 532.855159 11.45538) (xy 532.77334 11.531295) (xy 532.686078 11.600884) (xy 532.593858 11.663757)
			(xy 532.497199 11.719562) (xy 532.396639 11.767989) (xy 532.292741 11.808765) (xy 532.186087 11.841663)
			(xy 532.077273 11.866499) (xy 531.966907 11.883134) (xy 531.855606 11.891474) (xy 531.7998 11.892026)
			(xy 475.799912 11.892026) (xy 475.744104 11.891505) (xy 475.632801 11.883165) (xy 475.522432 11.86653)
			(xy 475.413615 11.841695) (xy 475.306958 11.808796) (xy 475.203057 11.76802) (xy 475.102495 11.719593)
			(xy 475.005832 11.663786) (xy 474.91361 11.600912) (xy 474.826345 11.531322) (xy 474.744524 11.455406)
			(xy 474.668605 11.373587) (xy 474.599013 11.286323) (xy 474.536136 11.194103) (xy 474.480327 11.097442)
			(xy 474.431897 10.996881) (xy 474.391117 10.892982) (xy 474.358216 10.786326) (xy 474.333378 10.677509)
			(xy 474.31674 10.567141) (xy 474.308397 10.455838) (xy 474.307916 10.40003) (xy 474.307916 7.335466)
			(xy 526.704041 7.335466) (xy 526.704041 7.464606) (xy 526.711991 7.593501) (xy 526.727861 7.721661)
			(xy 526.75159 7.848602) (xy 526.783089 7.973841) (xy 526.822238 8.096904) (xy 526.868889 8.217323)
			(xy 526.922864 8.334642) (xy 526.983959 8.448416) (xy 527.051942 8.558213) (xy 527.126556 8.663616)
			(xy 527.207517 8.764226) (xy 527.294517 8.859661) (xy 527.387228 8.94956) (xy 527.485298 9.033581)
			(xy 527.588353 9.111405) (xy 527.696004 9.182737) (xy 527.807843 9.247307) (xy 527.923444 9.304869)
			(xy 528.042369 9.355206) (xy 528.164168 9.398126) (xy 528.288378 9.433467) (xy 528.414527 9.461094)
			(xy 528.542139 9.480903) (xy 528.670728 9.492819) (xy 528.799806 9.496796) (xy 528.928884 9.492819)
			(xy 529.057473 9.480903) (xy 529.185085 9.461094) (xy 529.311234 9.433467) (xy 529.435444 9.398126)
			(xy 529.557243 9.355206) (xy 529.676168 9.304869) (xy 529.791769 9.247307) (xy 529.903608 9.182737)
			(xy 530.011259 9.111405) (xy 530.114314 9.033581) (xy 530.212384 8.94956) (xy 530.305095 8.859661)
			(xy 530.392095 8.764226) (xy 530.473056 8.663616) (xy 530.54767 8.558213) (xy 530.615653 8.448416)
			(xy 530.676748 8.334642) (xy 530.730723 8.217323) (xy 530.777374 8.096904) (xy 530.816523 7.973841)
			(xy 530.848022 7.848602) (xy 530.871751 7.721661) (xy 530.887621 7.593501) (xy 530.895571 7.464606)
			(xy 530.896068 7.400036) (xy 530.895571 7.335466) (xy 530.887621 7.206571) (xy 530.871751 7.078411)
			(xy 530.848022 6.95147) (xy 530.816523 6.826231) (xy 530.777374 6.703168) (xy 530.730723 6.582749)
			(xy 530.676748 6.46543) (xy 530.615653 6.351656) (xy 530.54767 6.241859) (xy 530.473056 6.136456)
			(xy 530.392095 6.035846) (xy 530.305095 5.940411) (xy 530.212384 5.850512) (xy 530.114314 5.766491)
			(xy 530.011259 5.688667) (xy 529.903608 5.617335) (xy 529.791769 5.552765) (xy 529.676168 5.495203)
			(xy 529.557243 5.444866) (xy 529.435444 5.401946) (xy 529.311234 5.366605) (xy 529.185085 5.338978)
			(xy 529.057473 5.319169) (xy 528.928884 5.307253) (xy 528.799806 5.303277) (xy 528.670728 5.307253)
			(xy 528.542139 5.319169) (xy 528.414527 5.338978) (xy 528.288378 5.366605) (xy 528.164168 5.401946)
			(xy 528.042369 5.444866) (xy 527.923444 5.495203) (xy 527.807843 5.552765) (xy 527.696004 5.617335)
			(xy 527.588353 5.688667) (xy 527.485298 5.766491) (xy 527.387228 5.850512) (xy 527.294517 5.940411)
			(xy 527.207517 6.035846) (xy 527.126556 6.136456) (xy 527.051942 6.241859) (xy 526.983959 6.351656)
			(xy 526.922864 6.46543) (xy 526.868889 6.582749) (xy 526.822238 6.703168) (xy 526.783089 6.826231)
			(xy 526.75159 6.95147) (xy 526.727861 7.078411) (xy 526.711991 7.206571) (xy 526.704041 7.335466)
			(xy 474.307916 7.335466) (xy 474.307916 -77.67193) (xy 474.307428 -77.765094) (xy 474.299715 -77.951262)
			(xy 474.284317 -78.136953) (xy 474.261258 -78.321849) (xy 474.23058 -78.505634) (xy 474.192333 -78.687994)
			(xy 474.146584 -78.868619) (xy 474.093411 -79.047199) (xy 474.032904 -79.223429) (xy 473.965167 -79.397008)
			(xy 473.890315 -79.56764) (xy 473.808477 -79.735034) (xy 473.719792 -79.898903) (xy 473.624411 -80.058968)
			(xy 473.522498 -80.214955) (xy 473.414227 -80.366597) (xy 473.299782 -80.513637) (xy 473.17936 -80.655821)
			(xy 473.053165 -80.792909) (xy 472.987624 -80.859122) (xy 471.245184 -82.601562) (xy 471.207836 -82.63956)
			(xy 471.138049 -82.720082) (xy 471.074185 -82.805378) (xy 471.01657 -82.895014) (xy 470.965496 -82.988531)
			(xy 470.921226 -83.085455) (xy 470.883983 -83.18529) (xy 470.853958 -83.287527) (xy 470.831304 -83.391646)
			(xy 470.816136 -83.497117) (xy 470.808532 -83.6034) (xy 470.80805 -83.656678) (xy 470.80805 -404.871936)
			(xy 470.807562 -404.9651) (xy 470.799849 -405.151268) (xy 470.78445 -405.336959) (xy 470.761392 -405.521855)
			(xy 470.730713 -405.70564) (xy 470.692467 -405.888001) (xy 470.646718 -406.068625) (xy 470.593544 -406.247205)
			(xy 470.533038 -406.423435) (xy 470.465301 -406.597015) (xy 470.39045 -406.767647) (xy 470.308612 -406.935041)
			(xy 470.219927 -407.098911) (xy 470.124547 -407.258976) (xy 470.022634 -407.414963) (xy 469.914363 -407.566606)
			(xy 469.799919 -407.713645) (xy 469.679497 -407.855831) (xy 469.553302 -407.992919) (xy 469.487758 -408.059128)
			(xy 468.244936 -409.30195) (xy 468.207612 -409.339964) (xy 468.137859 -409.4205) (xy 468.074028 -409.505805)
			(xy 468.016443 -409.595446) (xy 467.965398 -409.688966) (xy 467.921153 -409.785888) (xy 467.883933 -409.885719)
			(xy 467.853928 -409.98795) (xy 467.831291 -410.092061) (xy 467.816137 -410.197522) (xy 467.808543 -410.303794)
			(xy 467.808056 -410.357066) (xy 467.808056 -439.989976) (xy 467.808577 -440.045784) (xy 467.816916 -440.157089)
			(xy 467.83355 -440.267459) (xy 467.858385 -440.376277) (xy 467.891282 -440.482936) (xy 467.932058 -440.586837)
			(xy 467.980485 -440.687401) (xy 468.036291 -440.784065) (xy 468.099165 -440.876289) (xy 468.168754 -440.963556)
			(xy 468.244671 -441.045378) (xy 468.32649 -441.121299) (xy 468.413753 -441.190893) (xy 468.505974 -441.253771)
			(xy 468.602635 -441.309582) (xy 468.703197 -441.358013) (xy 468.807096 -441.398794) (xy 468.913753 -441.431697)
			(xy 469.02257 -441.456537) (xy 469.13294 -441.473176) (xy 469.244244 -441.48152) (xy 469.300052 -441.481972)
			(xy 471.79992 -441.481972) (xy 471.870274 -441.482466) (xy 472.01076 -441.490356) (xy 472.150582 -441.506112)
			(xy 472.289302 -441.529682) (xy 472.426481 -441.560993) (xy 472.561689 -441.599946) (xy 472.6945 -441.646419)
			(xy 472.824497 -441.700266) (xy 472.95127 -441.761317) (xy 473.07442 -441.82938) (xy 473.19356 -441.904241)
			(xy 473.308316 -441.985664) (xy 473.418325 -442.073394) (xy 473.523243 -442.167153) (xy 473.622738 -442.266648)
			(xy 473.716499 -442.371565) (xy 473.804229 -442.481575) (xy 473.885652 -442.59633) (xy 473.960514 -442.71547)
			(xy 474.028578 -442.83862) (xy 474.089629 -442.965392) (xy 474.143476 -443.095389) (xy 474.18995 -443.2282)
			(xy 474.228904 -443.363407) (xy 474.260216 -443.500587) (xy 474.283787 -443.639306) (xy 474.299543 -443.779128)
			(xy 474.307434 -443.919614) (xy 474.307916 -443.989968) (xy 474.307916 -458.092864) (xy 526.704041 -458.092864)
			(xy 526.704041 -457.963724) (xy 526.711991 -457.834829) (xy 526.727861 -457.706669) (xy 526.75159 -457.579728)
			(xy 526.783089 -457.454489) (xy 526.822238 -457.331426) (xy 526.868889 -457.211007) (xy 526.922864 -457.093688)
			(xy 526.983959 -456.979914) (xy 527.051942 -456.870117) (xy 527.126556 -456.764714) (xy 527.207517 -456.664104)
			(xy 527.294517 -456.568669) (xy 527.387228 -456.47877) (xy 527.485298 -456.394749) (xy 527.588353 -456.316925)
			(xy 527.696004 -456.245593) (xy 527.807843 -456.181023) (xy 527.923444 -456.123461) (xy 528.042369 -456.073124)
			(xy 528.164168 -456.030204) (xy 528.288378 -455.994863) (xy 528.414527 -455.967236) (xy 528.542139 -455.947427)
			(xy 528.670728 -455.935511) (xy 528.799806 -455.931535) (xy 528.928884 -455.935511) (xy 529.057473 -455.947427)
			(xy 529.185085 -455.967236) (xy 529.311234 -455.994863) (xy 529.435444 -456.030204) (xy 529.557243 -456.073124)
			(xy 529.676168 -456.123461) (xy 529.791769 -456.181023) (xy 529.903608 -456.245593) (xy 530.011259 -456.316925)
			(xy 530.114314 -456.394749) (xy 530.212384 -456.47877) (xy 530.305095 -456.568669) (xy 530.392095 -456.664104)
			(xy 530.473056 -456.764714) (xy 530.54767 -456.870117) (xy 530.615653 -456.979914) (xy 530.676748 -457.093688)
			(xy 530.730723 -457.211007) (xy 530.777374 -457.331426) (xy 530.816523 -457.454489) (xy 530.848022 -457.579728)
			(xy 530.871751 -457.706669) (xy 530.887621 -457.834829) (xy 530.895571 -457.963724) (xy 530.896068 -458.028294)
			(xy 530.895571 -458.092864) (xy 530.887621 -458.221759) (xy 530.871751 -458.349919) (xy 530.848022 -458.47686)
			(xy 530.816523 -458.602099) (xy 530.777374 -458.725162) (xy 530.730723 -458.845581) (xy 530.676748 -458.9629)
			(xy 530.615653 -459.076674) (xy 530.54767 -459.186471) (xy 530.473056 -459.291874) (xy 530.392095 -459.392484)
			(xy 530.305095 -459.487919) (xy 530.212384 -459.577818) (xy 530.114314 -459.661839) (xy 530.011259 -459.739663)
			(xy 529.903608 -459.810995) (xy 529.791769 -459.875565) (xy 529.676168 -459.933127) (xy 529.557243 -459.983464)
			(xy 529.435444 -460.026384) (xy 529.311234 -460.061725) (xy 529.185085 -460.089352) (xy 529.057473 -460.109161)
			(xy 528.928884 -460.121077) (xy 528.799806 -460.125054) (xy 528.670728 -460.121077) (xy 528.542139 -460.109161)
			(xy 528.414527 -460.089352) (xy 528.288378 -460.061725) (xy 528.164168 -460.026384) (xy 528.042369 -459.983464)
			(xy 527.923444 -459.933127) (xy 527.807843 -459.875565) (xy 527.696004 -459.810995) (xy 527.588353 -459.739663)
			(xy 527.485298 -459.661839) (xy 527.387228 -459.577818) (xy 527.294517 -459.487919) (xy 527.207517 -459.392484)
			(xy 527.126556 -459.291874) (xy 527.051942 -459.186471) (xy 526.983959 -459.076674) (xy 526.922864 -458.9629)
			(xy 526.868889 -458.845581) (xy 526.822238 -458.725162) (xy 526.783089 -458.602099) (xy 526.75159 -458.47686)
			(xy 526.727861 -458.349919) (xy 526.711991 -458.221759) (xy 526.704041 -458.092864) (xy 474.307916 -458.092864)
			(xy 474.307916 -461.028288) (xy 474.308425 -461.084096) (xy 474.316765 -461.195399) (xy 474.3334 -461.305768)
			(xy 474.358236 -461.414584) (xy 474.391134 -461.521241) (xy 474.431912 -461.625141) (xy 474.480339 -461.725703)
			(xy 474.536147 -461.822365) (xy 474.599022 -461.914586) (xy 474.668612 -462.00185) (xy 474.74453 -462.08367)
			(xy 474.82635 -462.159588) (xy 474.913614 -462.229178) (xy 475.005835 -462.292053) (xy 475.102497 -462.347861)
			(xy 475.203059 -462.396288) (xy 475.306959 -462.437066) (xy 475.413616 -462.469964) (xy 475.522432 -462.4948)
			(xy 475.632801 -462.511435) (xy 475.744104 -462.519775) (xy 475.799912 -462.520284)
		)
		(stroke
			(width 0)
			(type solid)
		)
		(fill yes)
		(layer "In9.Cu")
		(net "T1_GND")
	)
	(gr_poly
		(pts
			(xy 82.873596 -348.800166) (xy 82.87766 -348.790006) (xy 82.878676 -348.787466) (xy 82.882486 -348.778068)
			(xy 82.882486 -347.453458)
			(arc
				(start 80.751172 -345.322398)
				(mid 80.723787 -345.281364)
				(end 80.714088 -345.23299)
			)
			(arc
				(start 80.714088 -343.19464)
				(mid 80.723769 -343.146259)
				(end 80.751172 -343.105232)
			)
			(arc
				(start 80.92186 -342.934544)
				(mid 80.962894 -342.907159)
				(end 81.011268 -342.89746)
			)
			(arc
				(start 84.668868 -342.89746)
				(mid 84.717249 -342.907141)
				(end 84.758276 -342.934544)
			)
			(xy 85.196426 -343.372948) (xy 88.543384 -343.372948) (xy 89.588086 -342.328246) (xy 89.588086 -340.37016)
			(arc
				(start 88.961722 -339.74405)
				(mid 88.934337 -339.703016)
				(end 88.924638 -339.654642)
			)
			(arc
				(start 88.924638 -337.306412)
				(mid 88.934319 -337.258031)
				(end 88.961722 -337.217004)
			)
			(arc
				(start 89.037414 -337.141312)
				(mid 89.078448 -337.113927)
				(end 89.126822 -337.104228)
			)
			(arc
				(start 92.802202 -337.104228)
				(mid 92.850583 -337.113909)
				(end 92.89161 -337.141312)
			)
			(arc
				(start 93.009974 -337.259676)
				(mid 93.037359 -337.30071)
				(end 93.047058 -337.349084)
			)
			(xy 93.047058 -339.331046) (xy 93.224096 -339.508084) (xy 97.376996 -339.508084) (xy 97.988374 -338.896706)
			(xy 97.988374 -336.971894)
			(arc
				(start 97.099628 -336.083402)
				(mid 97.072243 -336.042368)
				(end 97.062544 -335.993994)
			)
			(arc
				(start 97.062544 -333.929228)
				(mid 97.072225 -333.880847)
				(end 97.099628 -333.83982)
			)
			(arc
				(start 97.226882 -333.712566)
				(mid 97.267916 -333.685181)
				(end 97.31629 -333.675482)
			)
			(arc
				(start 100.86467 -333.675482)
				(mid 100.913051 -333.685163)
				(end 100.954078 -333.712566)
			)
			(arc
				(start 101.082856 -333.841344)
				(mid 101.110241 -333.882378)
				(end 101.11994 -333.930752)
			)
			(arc
				(start 101.11994 -335.44637)
				(mid 101.174662 -335.572917)
				(end 101.193346 -335.709514)
			)
			(arc
				(start 101.193346 -335.709514)
				(mid 101.176327 -335.839718)
				(end 101.126544 -335.961228)
			)
			(xy 101.11994 -335.973166) (xy 101.11994 -336.182462)
			(arc
				(start 101.126544 -336.1944)
				(mid 101.176338 -336.315907)
				(end 101.193346 -336.446114)
			)
			(arc
				(start 101.193346 -336.446114)
				(mid 101.176327 -336.576318)
				(end 101.126544 -336.697828)
			)
			(xy 101.11994 -336.709766) (xy 101.11994 -336.919062)
			(arc
				(start 101.126544 -336.931)
				(mid 101.176338 -337.052507)
				(end 101.193346 -337.182714)
			)
			(arc
				(start 101.193346 -337.182714)
				(mid 101.174647 -337.319307)
				(end 101.11994 -337.445858)
			)
			(xy 101.11994 -338.684362) (xy 101.976174 -339.540596) (xy 105.67035 -339.540596) (xy 106.027474 -339.183472)
			(xy 106.027474 -336.88909)
			(arc
				(start 105.25887 -336.12074)
				(mid 105.231485 -336.079706)
				(end 105.221786 -336.031332)
			)
			(arc
				(start 105.221786 -333.936086)
				(mid 105.231467 -333.887705)
				(end 105.25887 -333.846678)
			)
			(arc
				(start 105.39476 -333.710788)
				(mid 105.435794 -333.683403)
				(end 105.484168 -333.673704)
			)
			(arc
				(start 109.07395 -333.673704)
				(mid 109.122331 -333.683385)
				(end 109.163358 -333.710788)
			)
			(arc
				(start 109.348016 -333.895446)
				(mid 109.375401 -333.93648)
				(end 109.3851 -333.984854)
			)
			(arc
				(start 109.3851 -337.329018)
				(mid 109.375419 -337.377399)
				(end 109.348016 -337.418426)
			)
			(xy 109.13237 -337.633818) (xy 109.13237 -338.536788) (xy 110.112556 -339.516974) (xy 113.66754 -339.516974)
			(xy 114.04854 -339.135974) (xy 114.04854 -336.706464)
			(arc
				(start 113.440718 -336.098896)
				(mid 113.413333 -336.057862)
				(end 113.403634 -336.009488)
			)
			(arc
				(start 113.403634 -333.912464)
				(mid 113.413315 -333.864083)
				(end 113.440718 -333.823056)
			)
			(arc
				(start 113.552224 -333.71155)
				(mid 113.593258 -333.684165)
				(end 113.641632 -333.674466)
			)
			(arc
				(start 117.226588 -333.674466)
				(mid 117.274969 -333.684147)
				(end 117.315996 -333.71155)
			)
			(arc
				(start 117.465602 -333.861156)
				(mid 117.492987 -333.90219)
				(end 117.502686 -333.950564)
			)
			(xy 117.502686 -335.601056)
			(arc
				(start 117.503702 -335.606136)
				(mid 117.511686 -335.657552)
				(end 117.51437 -335.709514)
			)
			(arc
				(start 117.51437 -335.709514)
				(mid 117.511682 -335.761476)
				(end 117.503702 -335.812892)
			)
			(xy 117.502686 -335.817972) (xy 117.502686 -336.337656)
			(arc
				(start 117.503702 -336.342736)
				(mid 117.511686 -336.394152)
				(end 117.51437 -336.446114)
			)
			(arc
				(start 117.51437 -336.446114)
				(mid 117.511682 -336.498076)
				(end 117.503702 -336.549492)
			)
			(xy 117.502686 -336.554572) (xy 117.502686 -337.074256)
			(arc
				(start 117.503702 -337.079336)
				(mid 117.511686 -337.130752)
				(end 117.51437 -337.182714)
			)
			(arc
				(start 117.51437 -337.182714)
				(mid 117.511682 -337.234676)
				(end 117.503702 -337.286092)
			)
			(xy 117.502686 -337.291172) (xy 117.502686 -338.827872) (xy 118.353078 -339.678264) (xy 121.807224 -339.678264)
			(xy 122.25401 -339.231478) (xy 122.25401 -336.808318)
			(arc
				(start 121.582688 -336.13725)
				(mid 121.555303 -336.096216)
				(end 121.545604 -336.047842)
			)
			(arc
				(start 121.545604 -333.912464)
				(mid 121.555285 -333.864083)
				(end 121.582688 -333.823056)
			)
			(arc
				(start 121.69521 -333.710534)
				(mid 121.736244 -333.683149)
				(end 121.784618 -333.67345)
			)
			(arc
				(start 125.393196 -333.67345)
				(mid 125.441577 -333.683131)
				(end 125.482604 -333.710534)
			)
			(arc
				(start 125.641608 -333.869538)
				(mid 125.668993 -333.910572)
				(end 125.678692 -333.958946)
			)
			(xy 125.678692 -335.8007)
			(arc
				(start 125.68047 -335.807558)
				(mid 125.694708 -335.875612)
				(end 125.69952 -335.944972)
			)
			(arc
				(start 125.69952 -335.944972)
				(mid 125.694698 -336.014331)
				(end 125.68047 -336.082386)
			)
			(xy 125.678692 -336.089244) (xy 125.678692 -336.5373)
			(arc
				(start 125.68047 -336.544158)
				(mid 125.694708 -336.612212)
				(end 125.69952 -336.681572)
			)
			(arc
				(start 125.69952 -336.681572)
				(mid 125.694698 -336.750931)
				(end 125.68047 -336.818986)
			)
			(xy 125.678692 -336.825844) (xy 125.678692 -337.2739)
			(arc
				(start 125.68047 -337.280758)
				(mid 125.694708 -337.348812)
				(end 125.69952 -337.418172)
			)
			(arc
				(start 125.69952 -337.418172)
				(mid 125.694698 -337.487531)
				(end 125.68047 -337.555586)
			)
			(xy 125.678692 -337.562444) (xy 125.678692 -342.417146) (xy 126.34976 -343.088214) (xy 129.75082 -343.088214)
			(xy 130.445256 -342.393778) (xy 130.445256 -340.846918)
			(arc
				(start 129.753868 -340.155784)
				(mid 129.726483 -340.11475)
				(end 129.716784 -340.066376)
			)
			(arc
				(start 129.716784 -337.276694)
				(mid 129.726465 -337.228313)
				(end 129.753868 -337.187286)
			)
			(arc
				(start 129.822956 -337.118198)
				(mid 129.86399 -337.090813)
				(end 129.912364 -337.081114)
			)
			(arc
				(start 133.552184 -337.081114)
				(mid 133.600565 -337.090795)
				(end 133.641592 -337.118198)
			)
			(arc
				(start 133.916674 -337.39328)
				(mid 133.944059 -337.434314)
				(end 133.953758 -337.482688)
			)
			(xy 133.953758 -348.01048) (xy 134.377684 -348.434406) (xy 138.246104 -348.434406) (xy 138.446764 -348.233746)
			(xy 138.446764 -346.038932)
			(arc
				(start 137.914634 -345.507056)
				(mid 137.887249 -345.466022)
				(end 137.87755 -345.417648)
			)
			(xy 137.87755 -343.045034) (xy 137.76325 -342.930734)
			(arc
				(start 136.400794 -342.930734)
				(mid 136.303607 -342.911384)
				(end 136.221216 -342.856312)
			)
			(arc
				(start 135.53186 -342.166956)
				(mid 135.476754 -342.084579)
				(end 135.457438 -341.987378)
			)
			(xy 135.457438 -341.874602)
			(arc
				(start 135.455152 -341.867236)
				(mid 135.444102 -341.817612)
				(end 135.44042 -341.766906)
			)
			(arc
				(start 135.44042 -341.766906)
				(mid 135.444105 -341.716201)
				(end 135.455152 -341.666576)
			)
			(xy 135.457438 -341.65921) (xy 135.457438 -341.085424)
			(arc
				(start 135.455152 -341.078058)
				(mid 135.444102 -341.028434)
				(end 135.44042 -340.977728)
			)
			(arc
				(start 135.44042 -340.977728)
				(mid 135.444105 -340.927023)
				(end 135.455152 -340.877398)
			)
			(xy 135.457438 -340.870032) (xy 135.457438 -336.021172) (xy 134.240524 -334.804258)
			(arc
				(start 127.83947 -334.804258)
				(mid 127.742283 -334.784908)
				(end 127.659892 -334.729836)
			)
			(arc
				(start 127.08128 -334.151224)
				(mid 127.026174 -334.068847)
				(end 127.006858 -333.971646)
			)
			(xy 127.006858 -331.753464) (xy 126.689612 -331.436218) (xy 125.05944 -331.436218)
			(arc
				(start 125.055884 -331.436726)
				(mid 125.031683 -331.439198)
				(end 125.00737 -331.440028)
			)
			(arc
				(start 125.00737 -331.440028)
				(mid 124.983056 -331.439214)
				(end 124.958856 -331.436726)
			)
			(xy 124.9553 -331.436218) (xy 124.39904 -331.436218)
			(arc
				(start 124.395484 -331.436726)
				(mid 124.371283 -331.439198)
				(end 124.34697 -331.440028)
			)
			(arc
				(start 124.34697 -331.440028)
				(mid 124.322656 -331.439214)
				(end 124.298456 -331.436726)
			)
			(xy 124.2949 -331.436218)
			(arc
				(start 117.351302 -331.436218)
				(mid 117.075458 -331.566986)
				(end 116.799614 -331.436218)
			)
			(arc
				(start 116.690902 -331.436218)
				(mid 116.415058 -331.566986)
				(end 116.139214 -331.436218)
			)
			(xy 108.738416 -331.436218)
			(arc
				(start 108.73486 -331.436726)
				(mid 108.710659 -331.439198)
				(end 108.686346 -331.440028)
			)
			(arc
				(start 108.686346 -331.440028)
				(mid 108.662032 -331.439214)
				(end 108.637832 -331.436726)
			)
			(xy 108.634276 -331.436218) (xy 108.078016 -331.436218)
			(arc
				(start 108.07446 -331.436726)
				(mid 108.050259 -331.439198)
				(end 108.025946 -331.440028)
			)
			(arc
				(start 108.025946 -331.440028)
				(mid 108.001632 -331.439214)
				(end 107.977432 -331.436726)
			)
			(xy 107.973876 -331.436218) (xy 100.577904 -331.436218)
			(arc
				(start 100.574348 -331.436726)
				(mid 100.550147 -331.439198)
				(end 100.525834 -331.440028)
			)
			(arc
				(start 100.525834 -331.440028)
				(mid 100.50152 -331.439214)
				(end 100.47732 -331.436726)
			)
			(xy 100.473764 -331.436218) (xy 99.917504 -331.436218)
			(arc
				(start 99.913948 -331.436726)
				(mid 99.889747 -331.439198)
				(end 99.865434 -331.440028)
			)
			(arc
				(start 99.865434 -331.440028)
				(mid 99.84112 -331.439214)
				(end 99.81692 -331.436726)
			)
			(xy 99.813364 -331.436218) (xy 93.35262 -331.436218)
			(arc
				(start 91.982798 -332.80604)
				(mid 91.953115 -332.873608)
				(end 91.976956 -332.943454)
			)
			(arc
				(start 91.976956 -332.943454)
				(mid 92.039339 -333.050946)
				(end 92.06103 -333.173324)
			)
			(arc
				(start 92.06103 -333.173324)
				(mid 92.032516 -333.312898)
				(end 91.951556 -333.430118)
			)
			(arc
				(start 91.951556 -333.430118)
				(mid 91.920235 -333.503524)
				(end 91.951556 -333.57693)
			)
			(arc
				(start 91.951556 -333.57693)
				(mid 92.032534 -333.694142)
				(end 92.06103 -333.833724)
			)
			(arc
				(start 92.06103 -333.833724)
				(mid 91.975434 -334.065318)
				(end 91.759786 -334.185514)
			)
			(arc
				(start 91.759786 -334.185514)
				(mid 91.72999 -334.201568)
				(end 91.71686 -334.232758)
			)
			(arc
				(start 91.71686 -334.232758)
				(mid 91.695079 -334.322096)
				(end 91.642946 -334.397858)
			)
			(arc
				(start 91.296236 -334.744568)
				(mid 91.213859 -334.799674)
				(end 91.116658 -334.81899)
			)
			(xy 85.856318 -334.81899) (xy 83.860386 -336.814922)
			(arc
				(start 83.87334 -336.846418)
				(mid 83.893658 -336.913276)
				(end 83.900518 -336.982816)
			)
			(arc
				(start 83.900518 -336.982816)
				(mid 83.867692 -337.132407)
				(end 83.775042 -337.254342)
			)
			(xy 83.757008 -337.269582) (xy 83.757008 -337.35645)
			(arc
				(start 83.775042 -337.37169)
				(mid 83.86765 -337.493644)
				(end 83.900518 -337.643216)
			)
			(arc
				(start 83.900518 -337.643216)
				(mid 83.867692 -337.792807)
				(end 83.775042 -337.914742)
			)
			(xy 83.757008 -337.929982) (xy 83.757008 -338.01685)
			(arc
				(start 83.775042 -338.03209)
				(mid 83.86765 -338.154044)
				(end 83.900518 -338.303616)
			)
			(arc
				(start 83.900518 -338.303616)
				(mid 83.867692 -338.453207)
				(end 83.775042 -338.575142)
			)
			(xy 83.757008 -338.590382) (xy 83.757008 -338.67725)
			(arc
				(start 83.775042 -338.69249)
				(mid 83.86765 -338.814444)
				(end 83.900518 -338.964016)
			)
			(arc
				(start 83.900518 -338.964016)
				(mid 83.867692 -339.113607)
				(end 83.775042 -339.235542)
			)
			(xy 83.757008 -339.250782) (xy 83.757008 -339.33765)
			(arc
				(start 83.775042 -339.35289)
				(mid 83.86765 -339.474844)
				(end 83.900518 -339.624416)
			)
			(arc
				(start 83.900518 -339.624416)
				(mid 83.862554 -339.784467)
				(end 83.756754 -339.91042)
			)
			(arc
				(start 83.756754 -339.91042)
				(mid 83.740308 -340.014995)
				(end 83.682586 -340.103714)
			)
			(arc
				(start 83.30311 -340.48319)
				(mid 83.220733 -340.538296)
				(end 83.123532 -340.557612)
			)
			(xy 77.319124 -340.557612) (xy 76.52004 -341.356696) (xy 76.52004 -347.482414) (xy 78.040484 -349.002858)
			(xy 82.670904 -349.002858)
		)
		(stroke
			(width 0)
			(type solid)
		)
		(fill yes)
		(layer "In9.Cu")
		(net "GND")
	)
	(gr_poly
		(pts
			(xy 330.81341 -348.799912) (xy 330.817474 -348.789752) (xy 330.81849 -348.787212) (xy 330.8223 -348.777814)
			(xy 330.8223 -347.453204)
			(arc
				(start 328.690986 -345.322144)
				(mid 328.663601 -345.28111)
				(end 328.653902 -345.232736)
			)
			(arc
				(start 328.653902 -343.194386)
				(mid 328.663583 -343.146005)
				(end 328.690986 -343.104978)
			)
			(arc
				(start 328.861674 -342.93429)
				(mid 328.902708 -342.906905)
				(end 328.951082 -342.897206)
			)
			(arc
				(start 332.608682 -342.897206)
				(mid 332.657063 -342.906887)
				(end 332.69809 -342.93429)
			)
			(xy 333.13624 -343.372694) (xy 336.483198 -343.372694) (xy 337.5279 -342.327992) (xy 337.5279 -340.369906)
			(arc
				(start 336.901536 -339.743796)
				(mid 336.874151 -339.702762)
				(end 336.864452 -339.654388)
			)
			(arc
				(start 336.864452 -337.306158)
				(mid 336.874133 -337.257777)
				(end 336.901536 -337.21675)
			)
			(arc
				(start 336.977228 -337.141058)
				(mid 337.018262 -337.113673)
				(end 337.066636 -337.103974)
			)
			(arc
				(start 340.615016 -337.103974)
				(mid 340.663397 -337.113655)
				(end 340.704424 -337.141058)
			)
			(arc
				(start 340.822788 -337.259422)
				(mid 340.850173 -337.300456)
				(end 340.859872 -337.34883)
			)
			(arc
				(start 340.859872 -338.807552)
				(mid 340.922879 -339.052662)
				(end 340.859872 -339.297772)
			)
			(xy 340.859872 -339.330792) (xy 341.03691 -339.50783) (xy 345.31681 -339.50783) (xy 345.928188 -338.896452)
			(xy 345.928188 -336.97164)
			(arc
				(start 345.039442 -336.083148)
				(mid 345.012057 -336.042114)
				(end 345.002358 -335.99374)
			)
			(arc
				(start 345.002358 -333.928974)
				(mid 345.012039 -333.880593)
				(end 345.039442 -333.839566)
			)
			(arc
				(start 345.166696 -333.712312)
				(mid 345.20773 -333.684927)
				(end 345.256104 -333.675228)
			)
			(arc
				(start 348.804484 -333.675228)
				(mid 348.852865 -333.684909)
				(end 348.893892 -333.712312)
			)
			(arc
				(start 349.02267 -333.84109)
				(mid 349.050055 -333.882124)
				(end 349.059754 -333.930498)
			)
			(arc
				(start 349.059754 -335.44637)
				(mid 349.114476 -335.572917)
				(end 349.13316 -335.709514)
			)
			(arc
				(start 349.13316 -335.709514)
				(mid 349.116141 -335.839718)
				(end 349.066358 -335.961228)
			)
			(xy 349.059754 -335.973166) (xy 349.059754 -336.182462)
			(arc
				(start 349.066358 -336.1944)
				(mid 349.116152 -336.315907)
				(end 349.13316 -336.446114)
			)
			(arc
				(start 349.13316 -336.446114)
				(mid 349.116141 -336.576318)
				(end 349.066358 -336.697828)
			)
			(xy 349.059754 -336.709766) (xy 349.059754 -336.919062)
			(arc
				(start 349.066358 -336.931)
				(mid 349.116152 -337.052507)
				(end 349.13316 -337.182714)
			)
			(arc
				(start 349.13316 -337.182714)
				(mid 349.114461 -337.319307)
				(end 349.059754 -337.445858)
			)
			(xy 349.059754 -338.684108) (xy 349.915988 -339.540342) (xy 353.610164 -339.540342) (xy 353.967288 -339.183218)
			(xy 353.967288 -336.888836)
			(arc
				(start 353.198684 -336.120486)
				(mid 353.171299 -336.079452)
				(end 353.1616 -336.031078)
			)
			(arc
				(start 353.1616 -333.935832)
				(mid 353.171281 -333.887451)
				(end 353.198684 -333.846424)
			)
			(arc
				(start 353.334574 -333.710534)
				(mid 353.375608 -333.683149)
				(end 353.423982 -333.67345)
			)
			(arc
				(start 357.013764 -333.67345)
				(mid 357.062145 -333.683131)
				(end 357.103172 -333.710534)
			)
			(arc
				(start 357.28783 -333.895192)
				(mid 357.315215 -333.936226)
				(end 357.324914 -333.9846)
			)
			(arc
				(start 357.324914 -337.328764)
				(mid 357.315233 -337.377145)
				(end 357.28783 -337.418172)
			)
			(xy 357.072184 -337.633564) (xy 357.072184 -338.536534) (xy 358.05237 -339.51672) (xy 361.607354 -339.51672)
			(xy 361.988354 -339.13572) (xy 361.988354 -336.70621)
			(arc
				(start 361.380532 -336.098642)
				(mid 361.353147 -336.057608)
				(end 361.343448 -336.009234)
			)
			(arc
				(start 361.343448 -333.91221)
				(mid 361.353129 -333.863829)
				(end 361.380532 -333.822802)
			)
			(arc
				(start 361.492038 -333.711296)
				(mid 361.533072 -333.683911)
				(end 361.581446 -333.674212)
			)
			(arc
				(start 365.166402 -333.674212)
				(mid 365.214783 -333.683893)
				(end 365.25581 -333.711296)
			)
			(arc
				(start 365.405416 -333.860902)
				(mid 365.432801 -333.901936)
				(end 365.4425 -333.95031)
			)
			(xy 365.4425 -335.601056)
			(arc
				(start 365.443516 -335.606136)
				(mid 365.4515 -335.657552)
				(end 365.454184 -335.709514)
			)
			(arc
				(start 365.454184 -335.709514)
				(mid 365.451496 -335.761476)
				(end 365.443516 -335.812892)
			)
			(xy 365.4425 -335.817972) (xy 365.4425 -336.337656)
			(arc
				(start 365.443516 -336.342736)
				(mid 365.4515 -336.394152)
				(end 365.454184 -336.446114)
			)
			(arc
				(start 365.454184 -336.446114)
				(mid 365.451496 -336.498076)
				(end 365.443516 -336.549492)
			)
			(xy 365.4425 -336.554572) (xy 365.4425 -337.074256)
			(arc
				(start 365.443516 -337.079336)
				(mid 365.4515 -337.130752)
				(end 365.454184 -337.182714)
			)
			(arc
				(start 365.454184 -337.182714)
				(mid 365.451496 -337.234676)
				(end 365.443516 -337.286092)
			)
			(xy 365.4425 -337.291172) (xy 365.4425 -338.827618) (xy 366.292892 -339.67801) (xy 369.747038 -339.67801)
			(xy 370.193824 -339.231224) (xy 370.193824 -336.808064)
			(arc
				(start 369.522502 -336.136996)
				(mid 369.495117 -336.095962)
				(end 369.485418 -336.047588)
			)
			(arc
				(start 369.485418 -333.91221)
				(mid 369.495099 -333.863829)
				(end 369.522502 -333.822802)
			)
			(arc
				(start 369.635024 -333.71028)
				(mid 369.676058 -333.682895)
				(end 369.724432 -333.673196)
			)
			(arc
				(start 373.33301 -333.673196)
				(mid 373.381391 -333.682877)
				(end 373.422418 -333.71028)
			)
			(arc
				(start 373.581422 -333.869284)
				(mid 373.608807 -333.910318)
				(end 373.618506 -333.958692)
			)
			(xy 373.618506 -335.8007)
			(arc
				(start 373.620284 -335.807558)
				(mid 373.634522 -335.875612)
				(end 373.639334 -335.944972)
			)
			(arc
				(start 373.639334 -335.944972)
				(mid 373.634512 -336.014331)
				(end 373.620284 -336.082386)
			)
			(xy 373.618506 -336.089244) (xy 373.618506 -336.5373)
			(arc
				(start 373.620284 -336.544158)
				(mid 373.634522 -336.612212)
				(end 373.639334 -336.681572)
			)
			(arc
				(start 373.639334 -336.681572)
				(mid 373.634512 -336.750931)
				(end 373.620284 -336.818986)
			)
			(xy 373.618506 -336.825844) (xy 373.618506 -337.2739)
			(arc
				(start 373.620284 -337.280758)
				(mid 373.634522 -337.348812)
				(end 373.639334 -337.418172)
			)
			(arc
				(start 373.639334 -337.418172)
				(mid 373.634512 -337.487531)
				(end 373.620284 -337.555586)
			)
			(xy 373.618506 -337.562444) (xy 373.618506 -342.416892) (xy 374.289574 -343.08796) (xy 377.690634 -343.08796)
			(xy 378.38507 -342.393524) (xy 378.38507 -340.846664)
			(arc
				(start 377.693682 -340.15553)
				(mid 377.666297 -340.114496)
				(end 377.656598 -340.066122)
			)
			(arc
				(start 377.656598 -337.27644)
				(mid 377.666279 -337.228059)
				(end 377.693682 -337.187032)
			)
			(arc
				(start 377.76277 -337.117944)
				(mid 377.803804 -337.090559)
				(end 377.852178 -337.08086)
			)
			(arc
				(start 381.491998 -337.08086)
				(mid 381.540379 -337.090541)
				(end 381.581406 -337.117944)
			)
			(arc
				(start 381.856488 -337.393026)
				(mid 381.883873 -337.43406)
				(end 381.893572 -337.482434)
			)
			(xy 381.893572 -348.010226) (xy 382.317498 -348.434152) (xy 386.185918 -348.434152) (xy 386.386578 -348.233492)
			(xy 386.386578 -346.038678)
			(arc
				(start 385.854448 -345.506802)
				(mid 385.827063 -345.465768)
				(end 385.817364 -345.417394)
			)
			(xy 385.817364 -343.04478) (xy 385.703064 -342.93048)
			(arc
				(start 384.340608 -342.93048)
				(mid 384.243421 -342.91113)
				(end 384.16103 -342.856058)
			)
			(arc
				(start 383.471674 -342.166702)
				(mid 383.416568 -342.084325)
				(end 383.397252 -341.987124)
			)
			(xy 383.397252 -341.874602)
			(arc
				(start 383.394966 -341.867236)
				(mid 383.383916 -341.817612)
				(end 383.380234 -341.766906)
			)
			(arc
				(start 383.380234 -341.766906)
				(mid 383.383919 -341.716201)
				(end 383.394966 -341.666576)
			)
			(xy 383.397252 -341.65921) (xy 383.397252 -341.085424)
			(arc
				(start 383.394966 -341.078058)
				(mid 383.383916 -341.028434)
				(end 383.380234 -340.977728)
			)
			(arc
				(start 383.380234 -340.977728)
				(mid 383.383919 -340.927023)
				(end 383.394966 -340.877398)
			)
			(xy 383.397252 -340.870032) (xy 383.397252 -336.020918) (xy 382.180338 -334.804004)
			(arc
				(start 375.779284 -334.804004)
				(mid 375.682097 -334.784654)
				(end 375.599706 -334.729582)
			)
			(arc
				(start 375.021094 -334.15097)
				(mid 374.965988 -334.068593)
				(end 374.946672 -333.971392)
			)
			(xy 374.946672 -331.75321) (xy 374.629426 -331.435964) (xy 373.001032 -331.435964)
			(arc
				(start 372.997476 -331.436472)
				(mid 372.972393 -331.439148)
				(end 372.947184 -331.440028)
			)
			(arc
				(start 372.947184 -331.440028)
				(mid 372.921976 -331.439135)
				(end 372.896892 -331.436472)
			)
			(xy 372.893336 -331.435964) (xy 372.340632 -331.435964)
			(arc
				(start 372.337076 -331.436472)
				(mid 372.311993 -331.439148)
				(end 372.286784 -331.440028)
			)
			(arc
				(start 372.286784 -331.440028)
				(mid 372.261576 -331.439135)
				(end 372.236492 -331.436472)
			)
			(xy 372.232936 -331.435964)
			(arc
				(start 365.356394 -331.435964)
				(mid 365.225585 -331.57103)
				(end 365.044228 -331.620622)
			)
			(arc
				(start 365.044228 -331.620622)
				(mid 364.904654 -331.592108)
				(end 364.787434 -331.511148)
			)
			(arc
				(start 364.787434 -331.511148)
				(mid 364.714028 -331.479827)
				(end 364.640622 -331.511148)
			)
			(arc
				(start 364.640622 -331.511148)
				(mid 364.52341 -331.592126)
				(end 364.383828 -331.620622)
			)
			(arc
				(start 364.383828 -331.620622)
				(mid 364.202492 -331.570994)
				(end 364.071662 -331.435964)
			)
			(xy 356.680008 -331.435964)
			(arc
				(start 356.676452 -331.436472)
				(mid 356.651369 -331.439148)
				(end 356.62616 -331.440028)
			)
			(arc
				(start 356.62616 -331.440028)
				(mid 356.600952 -331.439135)
				(end 356.575868 -331.436472)
			)
			(xy 356.572312 -331.435964) (xy 356.019608 -331.435964)
			(arc
				(start 356.016052 -331.436472)
				(mid 355.990969 -331.439148)
				(end 355.96576 -331.440028)
			)
			(arc
				(start 355.96576 -331.440028)
				(mid 355.940552 -331.439135)
				(end 355.915468 -331.436472)
			)
			(xy 355.911912 -331.435964) (xy 348.519496 -331.435964)
			(arc
				(start 348.51594 -331.436472)
				(mid 348.490857 -331.439148)
				(end 348.465648 -331.440028)
			)
			(arc
				(start 348.465648 -331.440028)
				(mid 348.44044 -331.439135)
				(end 348.415356 -331.436472)
			)
			(xy 348.4118 -331.435964) (xy 347.859096 -331.435964)
			(arc
				(start 347.85554 -331.436472)
				(mid 347.830457 -331.439148)
				(end 347.805248 -331.440028)
			)
			(arc
				(start 347.805248 -331.440028)
				(mid 347.78004 -331.439135)
				(end 347.754956 -331.436472)
			)
			(xy 347.7514 -331.435964) (xy 341.292434 -331.435964)
			(arc
				(start 339.922358 -332.80604)
				(mid 339.892843 -332.87363)
				(end 339.91677 -332.943454)
			)
			(arc
				(start 339.91677 -332.943454)
				(mid 339.979153 -333.050946)
				(end 340.000844 -333.173324)
			)
			(arc
				(start 340.000844 -333.173324)
				(mid 339.97233 -333.312898)
				(end 339.89137 -333.430118)
			)
			(arc
				(start 339.89137 -333.430118)
				(mid 339.860049 -333.503524)
				(end 339.89137 -333.57693)
			)
			(arc
				(start 339.89137 -333.57693)
				(mid 339.972348 -333.694142)
				(end 340.000844 -333.833724)
			)
			(arc
				(start 340.000844 -333.833724)
				(mid 339.915248 -334.065318)
				(end 339.6996 -334.185514)
			)
			(arc
				(start 339.6996 -334.185514)
				(mid 339.669804 -334.201568)
				(end 339.656674 -334.232758)
			)
			(arc
				(start 339.656674 -334.232758)
				(mid 339.634854 -334.321964)
				(end 339.58276 -334.397604)
			)
			(arc
				(start 339.23605 -334.744314)
				(mid 339.153673 -334.79942)
				(end 339.056472 -334.818736)
			)
			(xy 333.796132 -334.818736) (xy 331.799946 -336.814922)
			(arc
				(start 331.813154 -336.846164)
				(mid 331.833482 -336.913149)
				(end 331.840332 -336.982816)
			)
			(arc
				(start 331.840332 -336.982816)
				(mid 331.807506 -337.132407)
				(end 331.714856 -337.254342)
			)
			(xy 331.696822 -337.269582) (xy 331.696822 -337.35645)
			(arc
				(start 331.714856 -337.37169)
				(mid 331.807464 -337.493644)
				(end 331.840332 -337.643216)
			)
			(arc
				(start 331.840332 -337.643216)
				(mid 331.807506 -337.792807)
				(end 331.714856 -337.914742)
			)
			(xy 331.696822 -337.929982) (xy 331.696822 -338.01685)
			(arc
				(start 331.714856 -338.03209)
				(mid 331.807464 -338.154044)
				(end 331.840332 -338.303616)
			)
			(arc
				(start 331.840332 -338.303616)
				(mid 331.807506 -338.453207)
				(end 331.714856 -338.575142)
			)
			(xy 331.696822 -338.590382) (xy 331.696822 -338.67725)
			(arc
				(start 331.714856 -338.69249)
				(mid 331.807464 -338.814444)
				(end 331.840332 -338.964016)
			)
			(arc
				(start 331.840332 -338.964016)
				(mid 331.807506 -339.113607)
				(end 331.714856 -339.235542)
			)
			(xy 331.696822 -339.250782) (xy 331.696822 -339.33765)
			(arc
				(start 331.714856 -339.35289)
				(mid 331.807464 -339.474844)
				(end 331.840332 -339.624416)
			)
			(arc
				(start 331.840332 -339.624416)
				(mid 331.802368 -339.784467)
				(end 331.696568 -339.91042)
			)
			(arc
				(start 331.696568 -339.91042)
				(mid 331.680064 -340.014855)
				(end 331.6224 -340.10346)
			)
			(arc
				(start 331.242924 -340.482936)
				(mid 331.160547 -340.538042)
				(end 331.063346 -340.557358)
			)
			(arc
				(start 325.450962 -340.557358)
				(mid 325.322658 -340.674316)
				(end 325.15429 -340.716616)
			)
			(xy 325.126096 -340.7156) (xy 325.102728 -340.713568) (xy 324.459854 -341.356442) (xy 324.459854 -345.813888)
			(arc
				(start 324.489572 -345.827604)
				(mid 324.711852 -346.174314)
				(end 324.489572 -346.521024)
			)
			(xy 324.459854 -346.53474) (xy 324.459854 -347.48216) (xy 325.980298 -349.002604) (xy 330.610718 -349.002604)
		)
		(stroke
			(width 0)
			(type solid)
		)
		(fill yes)
		(layer "In9.Cu")
		(net "GND")
	)
	(gr_poly
		(pts
			(xy 329.0062 -82.153252) (xy 329.0062 -80.507586) (xy 328.978768 -80.493362) (xy 328.954418 -80.480076)
			(xy 328.909492 -80.44754) (xy 328.869748 -80.408845) (xy 328.836022 -80.364806) (xy 328.809024 -80.31635)
			(xy 328.789323 -80.264497) (xy 328.777333 -80.210339) (xy 328.773306 -80.155016) (xy 328.777328 -80.099692)
			(xy 328.789314 -80.045533) (xy 328.809011 -79.993679) (xy 328.836005 -79.94522) (xy 328.869727 -79.901179)
			(xy 328.909468 -79.862481) (xy 328.954391 -79.829941) (xy 328.978768 -79.816706) (xy 329.0062 -79.802482)
			(xy 329.0062 -76.594208) (xy 329.00565 -76.579087) (xy 328.996799 -76.550168) (xy 328.979871 -76.525107)
			(xy 328.956347 -76.506099) (xy 328.92829 -76.49481) (xy 328.898158 -76.492229) (xy 328.883264 -76.494894)
			(xy 328.863435 -76.498846) (xy 328.823218 -76.503043) (xy 328.803 -76.503276) (xy 327.9394 -76.503276)
			(xy 327.912151 -76.50279) (xy 327.858208 -76.495034) (xy 327.805918 -76.47968) (xy 327.756345 -76.457041)
			(xy 327.710498 -76.427577) (xy 327.669311 -76.391889) (xy 327.633623 -76.350702) (xy 327.604159 -76.304855)
			(xy 327.58152 -76.255282) (xy 327.566166 -76.202992) (xy 327.55841 -76.149049) (xy 327.55841 -76.094551)
			(xy 327.566166 -76.040608) (xy 327.58152 -75.988318) (xy 327.604159 -75.938745) (xy 327.633623 -75.892898)
			(xy 327.669311 -75.851711) (xy 327.710498 -75.816023) (xy 327.756345 -75.786559) (xy 327.805918 -75.76392)
			(xy 327.858208 -75.748566) (xy 327.912151 -75.74081) (xy 327.9394 -75.74026) (xy 328.803 -75.74026)
			(xy 328.823218 -75.740484) (xy 328.863436 -75.744683) (xy 328.883264 -75.748642) (xy 328.898161 -75.751278)
			(xy 328.928289 -75.748698) (xy 328.956342 -75.737412) (xy 328.979864 -75.718411) (xy 328.996795 -75.693358)
			(xy 329.005653 -75.664447) (xy 329.0062 -75.649328) (xy 329.0062 -57.648348) (xy 329.006816 -57.623393)
			(xy 329.016563 -57.574445) (xy 329.03567 -57.528338) (xy 329.063405 -57.486844) (xy 329.080622 -57.46877)
			(xy 329.791822 -56.75757) (xy 329.809862 -56.740308) (xy 329.851355 -56.712546) (xy 329.897473 -56.693427)
			(xy 329.946438 -56.68369) (xy 329.9714 -56.683148) (xy 330.794106 -56.683148) (xy 330.81112 -56.663084)
			(xy 330.850045 -56.627699) (xy 330.89375 -56.59842) (xy 330.941284 -56.575886) (xy 330.991614 -56.560586)
			(xy 331.043648 -56.552851) (xy 331.096252 -56.552851) (xy 331.148286 -56.560586) (xy 331.198616 -56.575886)
			(xy 331.24615 -56.59842) (xy 331.289855 -56.627699) (xy 331.32878 -56.663084) (xy 331.345794 -56.683148)
			(xy 332.420468 -56.683148) (xy 332.437482 -56.663084) (xy 332.476407 -56.627699) (xy 332.520112 -56.59842)
			(xy 332.567646 -56.575886) (xy 332.617976 -56.560586) (xy 332.67001 -56.552851) (xy 332.722614 -56.552851)
			(xy 332.774648 -56.560586) (xy 332.824978 -56.575886) (xy 332.872512 -56.59842) (xy 332.916217 -56.627699)
			(xy 332.955142 -56.663084) (xy 332.972156 -56.683148) (xy 335.677764 -56.683148) (xy 335.694778 -56.663084)
			(xy 335.733703 -56.627699) (xy 335.777408 -56.59842) (xy 335.824942 -56.575886) (xy 335.875272 -56.560586)
			(xy 335.927306 -56.552851) (xy 335.97991 -56.552851) (xy 336.031944 -56.560586) (xy 336.082274 -56.575886)
			(xy 336.129808 -56.59842) (xy 336.173513 -56.627699) (xy 336.212438 -56.663084) (xy 336.229452 -56.683148)
			(xy 337.30565 -56.683148) (xy 337.322664 -56.663084) (xy 337.361589 -56.627699) (xy 337.405294 -56.59842)
			(xy 337.452828 -56.575886) (xy 337.503158 -56.560586) (xy 337.555192 -56.552851) (xy 337.607796 -56.552851)
			(xy 337.65983 -56.560586) (xy 337.71016 -56.575886) (xy 337.757694 -56.59842) (xy 337.801399 -56.627699)
			(xy 337.840324 -56.663084) (xy 337.857338 -56.683148) (xy 337.96097 -56.683148) (xy 337.974705 -56.682702)
			(xy 338.001182 -56.675389) (xy 338.024753 -56.661283) (xy 338.043711 -56.641405) (xy 338.056686 -56.617193)
			(xy 338.062738 -56.590399) (xy 338.061429 -56.562961) (xy 338.05749 -56.549798) (xy 338.049185 -56.522738)
			(xy 338.040246 -56.466847) (xy 338.03971 -56.438546) (xy 338.040227 -56.410559) (xy 338.048977 -56.355273)
			(xy 338.066269 -56.302036) (xy 338.091677 -56.252161) (xy 338.124576 -56.206875) (xy 338.164154 -56.167294)
			(xy 338.209437 -56.134392) (xy 338.259311 -56.10898) (xy 338.312545 -56.091684) (xy 338.367831 -56.082929)
			(xy 338.395818 -56.082438) (xy 338.422867 -56.082939) (xy 338.476341 -56.091128) (xy 338.527956 -56.107331)
			(xy 338.576517 -56.131171) (xy 338.599018 -56.146192) (xy 338.63407 -56.170322) (xy 338.709 -56.095392)
			(xy 338.709 -49.950878) (xy 338.686043 -49.935677) (xy 338.644679 -49.899341) (xy 338.609401 -49.857071)
			(xy 338.581051 -49.809874) (xy 338.560304 -49.758875) (xy 338.547655 -49.705291) (xy 338.543405 -49.650398)
			(xy 338.547655 -49.595505) (xy 338.560305 -49.541921) (xy 338.581053 -49.490922) (xy 338.609404 -49.443726)
			(xy 338.644682 -49.401456) (xy 338.686047 -49.365121) (xy 338.709 -49.349914) (xy 338.709 -45.150278)
			(xy 338.686043 -45.135077) (xy 338.644679 -45.098741) (xy 338.609401 -45.056471) (xy 338.581051 -45.009274)
			(xy 338.560304 -44.958275) (xy 338.547655 -44.904691) (xy 338.543405 -44.849798) (xy 338.547655 -44.794905)
			(xy 338.560305 -44.741321) (xy 338.581053 -44.690322) (xy 338.609404 -44.643126) (xy 338.644682 -44.600856)
			(xy 338.686047 -44.564521) (xy 338.709 -44.549314) (xy 338.709 -42.843704) (xy 338.535772 -42.670476)
			(xy 338.506308 -42.680128) (xy 338.479479 -42.688277) (xy 338.424106 -42.697076) (xy 338.396072 -42.697654)
			(xy 338.368635 -42.697145) (xy 338.314413 -42.688722) (xy 338.262124 -42.67208) (xy 338.213008 -42.647613)
			(xy 338.168226 -42.6159) (xy 338.128841 -42.577692) (xy 338.095784 -42.533894) (xy 338.082382 -42.509948)
			(xy 335.454498 -42.509948) (xy 335.441088 -42.533893) (xy 335.408044 -42.577708) (xy 335.368666 -42.615932)
			(xy 335.323887 -42.647659) (xy 335.274769 -42.672136) (xy 335.222476 -42.688784) (xy 335.168248 -42.697208)
			(xy 335.113368 -42.697208) (xy 335.05914 -42.688784) (xy 335.006847 -42.672136) (xy 334.957729 -42.647659)
			(xy 334.91295 -42.615932) (xy 334.873572 -42.577708) (xy 334.840528 -42.533893) (xy 334.827118 -42.509948)
			(xy 333.824072 -42.509948) (xy 333.810662 -42.533893) (xy 333.777618 -42.577708) (xy 333.73824 -42.615932)
			(xy 333.693461 -42.647659) (xy 333.644343 -42.672136) (xy 333.59205 -42.688784) (xy 333.537822 -42.697208)
			(xy 333.482942 -42.697208) (xy 333.428714 -42.688784) (xy 333.376421 -42.672136) (xy 333.327303 -42.647659)
			(xy 333.282524 -42.615932) (xy 333.243146 -42.577708) (xy 333.210102 -42.533893) (xy 333.196692 -42.509948)
			(xy 332.195678 -42.509948) (xy 332.182268 -42.533893) (xy 332.149224 -42.577708) (xy 332.109846 -42.615932)
			(xy 332.065067 -42.647659) (xy 332.015949 -42.672136) (xy 331.963656 -42.688784) (xy 331.909428 -42.697208)
			(xy 331.854548 -42.697208) (xy 331.80032 -42.688784) (xy 331.748027 -42.672136) (xy 331.698909 -42.647659)
			(xy 331.65413 -42.615932) (xy 331.614752 -42.577708) (xy 331.581708 -42.533893) (xy 331.568298 -42.509948)
			(xy 330.567538 -42.509948) (xy 330.554128 -42.533893) (xy 330.521084 -42.577708) (xy 330.481706 -42.615932)
			(xy 330.436927 -42.647659) (xy 330.387809 -42.672136) (xy 330.335516 -42.688784) (xy 330.281288 -42.697208)
			(xy 330.226408 -42.697208) (xy 330.17218 -42.688784) (xy 330.119887 -42.672136) (xy 330.070769 -42.647659)
			(xy 330.02599 -42.615932) (xy 329.986612 -42.577708) (xy 329.953568 -42.533893) (xy 329.940158 -42.509948)
			(xy 328.939398 -42.509948) (xy 328.925988 -42.533893) (xy 328.892944 -42.577708) (xy 328.853566 -42.615932)
			(xy 328.808787 -42.647659) (xy 328.759669 -42.672136) (xy 328.707376 -42.688784) (xy 328.653148 -42.697208)
			(xy 328.598268 -42.697208) (xy 328.54404 -42.688784) (xy 328.491747 -42.672136) (xy 328.442629 -42.647659)
			(xy 328.39785 -42.615932) (xy 328.358472 -42.577708) (xy 328.325428 -42.533893) (xy 328.312018 -42.509948)
			(xy 323.123052 -42.509948) (xy 323.11467 -42.512996) (xy 323.089553 -42.521622) (xy 323.0376 -42.532632)
			(xy 322.984622 -42.536326) (xy 322.931644 -42.532632) (xy 322.879691 -42.521622) (xy 322.854574 -42.512996)
			(xy 322.846192 -42.509948) (xy 274.526756 -42.509948) (xy 274.25396 -42.782744) (xy 274.25396 -55.908448)
			(xy 274.253384 -55.933406) (xy 274.243636 -55.982362) (xy 274.224523 -56.028475) (xy 274.196782 -56.069973)
			(xy 274.179538 -56.088026) (xy 272.4912 -57.776364) (xy 272.4912 -74.760836) (xy 287.494472 -74.760836)
			(xy 287.494472 -66.060828) (xy 287.494977 -65.955304) (xy 287.503061 -65.74441) (xy 287.519217 -65.533981)
			(xy 287.54342 -65.324324) (xy 287.575637 -65.115749) (xy 287.615819 -64.908561) (xy 287.663907 -64.703064)
			(xy 287.719831 -64.49956) (xy 287.783508 -64.298347) (xy 287.854846 -64.09972) (xy 287.93374 -63.903972)
			(xy 288.020073 -63.71139) (xy 288.11372 -63.522255) (xy 288.214542 -63.336846) (xy 288.322392 -63.155435)
			(xy 288.437111 -62.978288) (xy 288.558531 -62.805666) (xy 288.686474 -62.63782) (xy 288.820752 -62.474998)
			(xy 288.961168 -62.317439) (xy 289.107516 -62.165374) (xy 289.259581 -62.019026) (xy 289.41714 -61.87861)
			(xy 289.579962 -61.744332) (xy 289.747808 -61.616389) (xy 289.92043 -61.494969) (xy 290.097577 -61.38025)
			(xy 290.278988 -61.2724) (xy 290.464397 -61.171578) (xy 290.653532 -61.077931) (xy 290.846114 -60.991598)
			(xy 291.041862 -60.912704) (xy 291.240489 -60.841366) (xy 291.441702 -60.777689) (xy 291.645206 -60.721765)
			(xy 291.850703 -60.673677) (xy 292.057891 -60.633495) (xy 292.266466 -60.601278) (xy 292.476123 -60.577075)
			(xy 292.686552 -60.560919) (xy 292.897446 -60.552835) (xy 293.108494 -60.552835) (xy 293.319388 -60.560919)
			(xy 293.529817 -60.577075) (xy 293.739474 -60.601278) (xy 293.948049 -60.633495) (xy 294.155237 -60.673677)
			(xy 294.360734 -60.721765) (xy 294.564238 -60.777689) (xy 294.765451 -60.841366) (xy 294.964078 -60.912704)
			(xy 295.159826 -60.991598) (xy 295.352408 -61.077931) (xy 295.541543 -61.171578) (xy 295.726952 -61.2724)
			(xy 295.908363 -61.38025) (xy 296.08551 -61.494969) (xy 296.258132 -61.616389) (xy 296.425978 -61.744332)
			(xy 296.5888 -61.87861) (xy 296.746359 -62.019026) (xy 296.898424 -62.165374) (xy 297.044772 -62.317439)
			(xy 297.185188 -62.474998) (xy 297.319466 -62.63782) (xy 297.447409 -62.805666) (xy 297.568829 -62.978288)
			(xy 297.683548 -63.155435) (xy 297.791398 -63.336846) (xy 297.89222 -63.522255) (xy 297.985867 -63.71139)
			(xy 298.0722 -63.903972) (xy 298.151094 -64.09972) (xy 298.222432 -64.298347) (xy 298.286109 -64.49956)
			(xy 298.342033 -64.703064) (xy 298.390121 -64.908561) (xy 298.396302 -64.940434) (xy 325.410068 -64.940434)
			(xy 325.410068 -64.076834) (xy 325.410554 -64.049565) (xy 325.418316 -63.995581) (xy 325.433681 -63.943251)
			(xy 325.456338 -63.893641) (xy 325.485824 -63.84776) (xy 325.521539 -63.806543) (xy 325.562756 -63.770828)
			(xy 325.608637 -63.741342) (xy 325.658247 -63.718685) (xy 325.710577 -63.70332) (xy 325.764561 -63.695558)
			(xy 325.819099 -63.695558) (xy 325.873083 -63.70332) (xy 325.925413 -63.718685) (xy 325.975023 -63.741342)
			(xy 326.020904 -63.770828) (xy 326.062121 -63.806543) (xy 326.097836 -63.84776) (xy 326.127322 -63.893641)
			(xy 326.149979 -63.943251) (xy 326.165344 -63.995581) (xy 326.173106 -64.049565) (xy 326.173592 -64.076834)
			(xy 326.173592 -64.940434) (xy 326.173106 -64.967703) (xy 326.165344 -65.021687) (xy 326.149979 -65.074017)
			(xy 326.127322 -65.123627) (xy 326.097836 -65.169508) (xy 326.062121 -65.210725) (xy 326.020904 -65.24644)
			(xy 325.975023 -65.275926) (xy 325.925413 -65.298583) (xy 325.873083 -65.313948) (xy 325.819099 -65.32171)
			(xy 325.764561 -65.32171) (xy 325.710577 -65.313948) (xy 325.658247 -65.298583) (xy 325.608637 -65.275926)
			(xy 325.562756 -65.24644) (xy 325.521539 -65.210725) (xy 325.485824 -65.169508) (xy 325.456338 -65.123627)
			(xy 325.433681 -65.074017) (xy 325.418316 -65.021687) (xy 325.410554 -64.967703) (xy 325.410068 -64.940434)
			(xy 298.396302 -64.940434) (xy 298.430303 -65.115749) (xy 298.46252 -65.324324) (xy 298.486723 -65.533981)
			(xy 298.502879 -65.74441) (xy 298.510963 -65.955304) (xy 298.511468 -66.060828) (xy 298.511468 -68.449952)
			(xy 314.840884 -68.449952) (xy 314.844867 -68.321934) (xy 314.856802 -68.194412) (xy 314.876641 -68.067878)
			(xy 314.904308 -67.942822) (xy 314.939697 -67.819729) (xy 314.98267 -67.699073) (xy 315.033061 -67.581323)
			(xy 315.090675 -67.466933) (xy 315.155289 -67.356346) (xy 315.226653 -67.24999) (xy 315.304491 -67.148277)
			(xy 315.388502 -67.051599) (xy 315.478361 -66.960332) (xy 315.57372 -66.874827) (xy 315.674211 -66.795417)
			(xy 315.779444 -66.722407) (xy 315.889013 -66.656081) (xy 316.002493 -66.596695) (xy 316.119445 -66.544479)
			(xy 316.239418 -66.499635) (xy 316.361946 -66.462337) (xy 316.486557 -66.432728) (xy 316.612766 -66.410923)
			(xy 316.740088 -66.397007) (xy 316.868028 -66.391033) (xy 316.996092 -66.393025) (xy 317.123785 -66.402975)
			(xy 317.250612 -66.420844) (xy 317.376083 -66.446563) (xy 317.499712 -66.480033) (xy 317.621021 -66.521124)
			(xy 317.739541 -66.569678) (xy 317.854813 -66.625506) (xy 317.966391 -66.688392) (xy 318.073844 -66.758094)
			(xy 318.176756 -66.834341) (xy 318.274728 -66.916838) (xy 318.367382 -67.005267) (xy 318.454359 -67.099285)
			(xy 318.535323 -67.198528) (xy 318.60996 -67.302613) (xy 318.677982 -67.411137) (xy 318.739126 -67.52368)
			(xy 318.793154 -67.639806) (xy 318.839859 -67.759067) (xy 318.879059 -67.881) (xy 318.910602 -68.005135)
			(xy 318.934367 -68.130991) (xy 318.950261 -68.25808) (xy 318.958224 -68.385912) (xy 318.958722 -68.449952)
			(xy 318.958224 -68.513992) (xy 318.950261 -68.641824) (xy 318.934367 -68.768913) (xy 318.910602 -68.894769)
			(xy 318.879059 -69.018904) (xy 318.839859 -69.140837) (xy 318.793154 -69.260098) (xy 318.739126 -69.376224)
			(xy 318.677982 -69.488767) (xy 318.60996 -69.597291) (xy 318.535323 -69.701376) (xy 318.454359 -69.800619)
			(xy 318.367382 -69.894637) (xy 318.274728 -69.983066) (xy 318.176756 -70.065563) (xy 318.073844 -70.14181)
			(xy 317.966391 -70.211512) (xy 317.854813 -70.274398) (xy 317.739541 -70.330226) (xy 317.621021 -70.37878)
			(xy 317.499712 -70.419871) (xy 317.376083 -70.453341) (xy 317.250612 -70.47906) (xy 317.123785 -70.496929)
			(xy 316.996092 -70.506879) (xy 316.868028 -70.508871) (xy 316.740088 -70.502897) (xy 316.612766 -70.488981)
			(xy 316.486557 -70.467176) (xy 316.361946 -70.437567) (xy 316.239418 -70.400269) (xy 316.119445 -70.355425)
			(xy 316.002493 -70.303209) (xy 315.889013 -70.243823) (xy 315.779444 -70.177497) (xy 315.674211 -70.104487)
			(xy 315.57372 -70.025077) (xy 315.478361 -69.939572) (xy 315.388502 -69.848305) (xy 315.304491 -69.751627)
			(xy 315.226653 -69.649914) (xy 315.155289 -69.543558) (xy 315.090675 -69.432971) (xy 315.033061 -69.318581)
			(xy 314.98267 -69.200831) (xy 314.939697 -69.080175) (xy 314.904308 -68.957082) (xy 314.876641 -68.832026)
			(xy 314.856802 -68.705492) (xy 314.844867 -68.57797) (xy 314.840884 -68.449952) (xy 298.511468 -68.449952)
			(xy 298.511468 -74.617072) (xy 327.277726 -74.617072) (xy 327.281813 -74.561227) (xy 327.293988 -74.506573)
			(xy 327.31399 -74.454274) (xy 327.341395 -74.405445) (xy 327.375617 -74.361126) (xy 327.415927 -74.322262)
			(xy 327.461466 -74.289681) (xy 327.511264 -74.264078) (xy 327.564259 -74.245999) (xy 327.619321 -74.235828)
			(xy 327.675278 -74.233783) (xy 327.730936 -74.239908) (xy 327.785109 -74.25407) (xy 327.836643 -74.27597)
			(xy 327.884439 -74.305139) (xy 327.927478 -74.340957) (xy 327.964844 -74.38266) (xy 327.99574 -74.429358)
			(xy 328.019507 -74.480058) (xy 328.035639 -74.533678) (xy 328.043791 -74.589075) (xy 328.044302 -74.617072)
			(xy 328.043791 -74.645069) (xy 328.035639 -74.700466) (xy 328.019507 -74.754086) (xy 327.99574 -74.804786)
			(xy 327.964844 -74.851484) (xy 327.927478 -74.893187) (xy 327.884439 -74.929005) (xy 327.836643 -74.958174)
			(xy 327.785109 -74.980074) (xy 327.730936 -74.994236) (xy 327.675278 -75.000361) (xy 327.619321 -74.998316)
			(xy 327.564259 -74.988145) (xy 327.511264 -74.970066) (xy 327.461466 -74.944463) (xy 327.415927 -74.911882)
			(xy 327.375617 -74.873018) (xy 327.341395 -74.828699) (xy 327.31399 -74.77987) (xy 327.293988 -74.727571)
			(xy 327.281813 -74.672917) (xy 327.277726 -74.617072) (xy 298.511468 -74.617072) (xy 298.511468 -74.760836)
			(xy 298.510963 -74.86636) (xy 298.502879 -75.077254) (xy 298.486723 -75.287683) (xy 298.46252 -75.49734)
			(xy 298.430303 -75.705915) (xy 298.390121 -75.913103) (xy 298.342033 -76.1186) (xy 298.286109 -76.322104)
			(xy 298.222432 -76.523317) (xy 298.151094 -76.721944) (xy 298.0722 -76.917692) (xy 297.985867 -77.110274)
			(xy 297.89222 -77.299409) (xy 297.791398 -77.484818) (xy 297.683548 -77.666229) (xy 297.568829 -77.843376)
			(xy 297.447409 -78.015998) (xy 297.319466 -78.183844) (xy 297.185188 -78.346666) (xy 297.044772 -78.504225)
			(xy 296.898424 -78.65629) (xy 296.746359 -78.802638) (xy 296.5888 -78.943054) (xy 296.425978 -79.077332)
			(xy 296.258132 -79.205275) (xy 296.08551 -79.326695) (xy 295.908363 -79.441414) (xy 295.726952 -79.549264)
			(xy 295.541543 -79.650086) (xy 295.352408 -79.743733) (xy 295.159826 -79.830066) (xy 294.964078 -79.90896)
			(xy 294.765451 -79.980298) (xy 294.564238 -80.043975) (xy 294.360734 -80.099899) (xy 294.155237 -80.147987)
			(xy 293.948049 -80.188169) (xy 293.739474 -80.220386) (xy 293.529817 -80.244589) (xy 293.319388 -80.260745)
			(xy 293.108494 -80.268829) (xy 292.897446 -80.268829) (xy 292.686552 -80.260745) (xy 292.476123 -80.244589)
			(xy 292.266466 -80.220386) (xy 292.057891 -80.188169) (xy 291.850703 -80.147987) (xy 291.645206 -80.099899)
			(xy 291.441702 -80.043975) (xy 291.240489 -79.980298) (xy 291.041862 -79.90896) (xy 290.846114 -79.830066)
			(xy 290.653532 -79.743733) (xy 290.464397 -79.650086) (xy 290.278988 -79.549264) (xy 290.097577 -79.441414)
			(xy 289.92043 -79.326695) (xy 289.747808 -79.205275) (xy 289.579962 -79.077332) (xy 289.41714 -78.943054)
			(xy 289.259581 -78.802638) (xy 289.107516 -78.65629) (xy 288.961168 -78.504225) (xy 288.820752 -78.346666)
			(xy 288.686474 -78.183844) (xy 288.558531 -78.015998) (xy 288.437111 -77.843376) (xy 288.322392 -77.666229)
			(xy 288.214542 -77.484818) (xy 288.11372 -77.299409) (xy 288.020073 -77.110274) (xy 287.93374 -76.917692)
			(xy 287.854846 -76.721944) (xy 287.783508 -76.523317) (xy 287.719831 -76.322104) (xy 287.663907 -76.1186)
			(xy 287.615819 -75.913103) (xy 287.575637 -75.705915) (xy 287.54342 -75.49734) (xy 287.519217 -75.287683)
			(xy 287.503061 -75.077254) (xy 287.494977 -74.86636) (xy 287.494472 -74.760836) (xy 272.4912 -74.760836)
			(xy 272.4912 -82.066892) (xy 274.140676 -83.716368) (xy 327.443084 -83.716368)
		)
		(stroke
			(width 0)
			(type solid)
		)
		(fill yes)
		(layer "In9.Cu")
		(net "P1V05_PCH_AUX")
	)
	(gr_poly
		(pts
			(xy 432.338226 -312.588402) (xy 432.348597 -312.587192) (xy 432.369441 -312.58592) (xy 432.379882 -312.585862)
			(xy 432.390323 -312.585918) (xy 432.411167 -312.587187) (xy 432.421538 -312.588402) (xy 432.42484 -312.58891)
			(xy 434.544724 -312.58891) (xy 434.548026 -312.588402) (xy 434.558397 -312.587192) (xy 434.579241 -312.58592)
			(xy 434.589682 -312.585862) (xy 434.600123 -312.585918) (xy 434.620967 -312.587187) (xy 434.631338 -312.588402)
			(xy 434.63464 -312.58891) (xy 435.806596 -312.58891) (xy 435.823614 -312.588402) (xy 435.840632 -312.58891)
			(xy 439.878724 -312.58891) (xy 439.882026 -312.588402) (xy 439.892397 -312.587192) (xy 439.913241 -312.58592)
			(xy 439.923682 -312.585862) (xy 439.934123 -312.585918) (xy 439.954967 -312.587187) (xy 439.965338 -312.588402)
			(xy 439.96864 -312.58891) (xy 442.088524 -312.58891) (xy 442.091826 -312.588402) (xy 442.102197 -312.587192)
			(xy 442.123041 -312.58592) (xy 442.133482 -312.585862) (xy 442.143923 -312.585918) (xy 442.164767 -312.587187)
			(xy 442.175138 -312.588402) (xy 442.17844 -312.58891) (xy 442.476382 -312.58891) (xy 443.092078 -311.973214)
			(xy 443.092078 -311.399936) (xy 443.078983 -311.379491) (xy 443.058283 -311.335576) (xy 443.04423 -311.289104)
			(xy 443.037127 -311.241077) (xy 443.037127 -311.192527) (xy 443.044229 -311.144499) (xy 443.058282 -311.098027)
			(xy 443.078981 -311.054111) (xy 443.092078 -311.033668) (xy 443.092078 -309.699914) (xy 443.078985 -309.679469)
			(xy 443.058288 -309.635554) (xy 443.044238 -309.589084) (xy 443.037138 -309.541057) (xy 443.03714 -309.492509)
			(xy 443.044245 -309.444484) (xy 443.0583 -309.398015) (xy 443.079001 -309.354101) (xy 443.092078 -309.333646)
			(xy 443.092078 -307.999892) (xy 443.078986 -307.979448) (xy 443.058292 -307.935533) (xy 443.044246 -307.889063)
			(xy 443.037149 -307.841038) (xy 443.037154 -307.792492) (xy 443.044261 -307.744469) (xy 443.058318 -307.698002)
			(xy 443.079021 -307.654091) (xy 443.092078 -307.633624) (xy 443.092078 -306.29987) (xy 443.078981 -306.279425)
			(xy 443.058275 -306.235509) (xy 443.044218 -306.189036) (xy 443.03711 -306.141006) (xy 443.037106 -306.092454)
			(xy 443.044205 -306.044423) (xy 443.058254 -305.997947) (xy 443.078951 -305.954027) (xy 443.092078 -305.933602)
			(xy 443.092078 -304.599848) (xy 443.078982 -304.579403) (xy 443.05828 -304.535487) (xy 443.044226 -304.489015)
			(xy 443.037121 -304.440987) (xy 443.037119 -304.392436) (xy 443.044221 -304.344407) (xy 443.058272 -304.297934)
			(xy 443.078971 -304.254017) (xy 443.092078 -304.23358) (xy 443.092078 -302.049942) (xy 443.078983 -302.029497)
			(xy 443.058282 -301.985582) (xy 443.044228 -301.93911) (xy 443.037124 -301.891082) (xy 443.037123 -301.842531)
			(xy 443.044225 -301.794503) (xy 443.058277 -301.748031) (xy 443.078976 -301.704114) (xy 443.092078 -301.683674)
			(xy 443.092078 -300.34992) (xy 443.078984 -300.329475) (xy 443.058286 -300.28556) (xy 443.044236 -300.239089)
			(xy 443.037135 -300.191063) (xy 443.037137 -300.142514) (xy 443.044241 -300.094488) (xy 443.058295 -300.048018)
			(xy 443.078996 -300.004104) (xy 443.092078 -299.983652) (xy 443.092078 -298.649898) (xy 443.078986 -298.629454)
			(xy 443.058291 -298.585539) (xy 443.044244 -298.539069) (xy 443.037146 -298.491043) (xy 443.03715 -298.442497)
			(xy 443.044257 -298.394473) (xy 443.058313 -298.348005) (xy 443.079015 -298.304094) (xy 443.092078 -298.28363)
			(xy 443.092078 -296.949876) (xy 443.07898 -296.929431) (xy 443.058274 -296.885515) (xy 443.044216 -296.839041)
			(xy 443.037107 -296.791011) (xy 443.037102 -296.742458) (xy 443.0442 -296.694427) (xy 443.058249 -296.647951)
			(xy 443.078946 -296.60403) (xy 443.092078 -296.583608) (xy 443.092078 -295.249854) (xy 443.078982 -295.229409)
			(xy 443.058279 -295.185493) (xy 443.044224 -295.139021) (xy 443.037118 -295.090992) (xy 443.037116 -295.042441)
			(xy 443.044216 -294.994412) (xy 443.058267 -294.947938) (xy 443.078965 -294.90402) (xy 443.092078 -294.883586)
			(xy 443.092078 -292.699948) (xy 443.078982 -292.679503) (xy 443.05828 -292.635587) (xy 443.044226 -292.589115)
			(xy 443.037121 -292.541087) (xy 443.037119 -292.492536) (xy 443.044221 -292.444507) (xy 443.058272 -292.398034)
			(xy 443.078971 -292.354117) (xy 443.092078 -292.33368) (xy 443.092078 -290.999926) (xy 443.078984 -290.979481)
			(xy 443.058285 -290.935566) (xy 443.044234 -290.889095) (xy 443.037132 -290.841068) (xy 443.037133 -290.792519)
			(xy 443.044237 -290.744492) (xy 443.05829 -290.698022) (xy 443.07899 -290.654107) (xy 443.092078 -290.633658)
			(xy 443.092078 -289.299904) (xy 443.078985 -289.27946) (xy 443.05829 -289.235544) (xy 443.044241 -289.189074)
			(xy 443.037143 -289.141049) (xy 443.037146 -289.092501) (xy 443.044252 -289.044477) (xy 443.058308 -288.998009)
			(xy 443.07901 -288.954097) (xy 443.092078 -288.933636) (xy 443.092078 -287.599882) (xy 443.07898 -287.579437)
			(xy 443.058273 -287.535521) (xy 443.044214 -287.489047) (xy 443.037104 -287.441017) (xy 443.037099 -287.392463)
			(xy 443.044196 -287.344431) (xy 443.058244 -287.297954) (xy 443.07894 -287.254032) (xy 443.092078 -287.233614)
			(xy 443.092078 -285.89986) (xy 443.078981 -285.879415) (xy 443.058278 -285.835499) (xy 443.044221 -285.789027)
			(xy 443.037115 -285.740998) (xy 443.037112 -285.692446) (xy 443.044212 -285.644416) (xy 443.058262 -285.597941)
			(xy 443.07896 -285.554022) (xy 443.092078 -285.533592) (xy 443.092078 -283.3497) (xy 443.078986 -283.329256)
			(xy 443.058291 -283.285341) (xy 443.044243 -283.23887) (xy 443.037145 -283.190845) (xy 443.037149 -283.142298)
			(xy 443.044255 -283.094274) (xy 443.058311 -283.047807) (xy 443.079014 -283.003895) (xy 443.092078 -282.983432)
			(xy 443.092078 -281.649932) (xy 443.078983 -281.629487) (xy 443.058284 -281.585572) (xy 443.044231 -281.5391)
			(xy 443.037129 -281.491073) (xy 443.037129 -281.442524) (xy 443.044232 -281.394496) (xy 443.058285 -281.348025)
			(xy 443.078985 -281.30411) (xy 443.092078 -281.283664) (xy 443.092078 -279.94991) (xy 443.078985 -279.929465)
			(xy 443.058288 -279.88555) (xy 443.044239 -279.83908) (xy 443.03714 -279.791054) (xy 443.037143 -279.742506)
			(xy 443.044248 -279.694481) (xy 443.058303 -279.648012) (xy 443.079005 -279.6041) (xy 443.092078 -279.583642)
			(xy 443.092078 -278.249888) (xy 443.078987 -278.229444) (xy 443.058293 -278.185529) (xy 443.044247 -278.139059)
			(xy 443.037151 -278.091035) (xy 443.037156 -278.042489) (xy 443.044264 -277.994466) (xy 443.058321 -277.948)
			(xy 443.079024 -277.90409) (xy 443.092078 -277.88362) (xy 443.092078 -276.549866) (xy 443.078981 -276.529421)
			(xy 443.058276 -276.485505) (xy 443.044219 -276.439032) (xy 443.037112 -276.391003) (xy 443.037108 -276.34245)
			(xy 443.044208 -276.29442) (xy 443.058257 -276.247945) (xy 443.078955 -276.204025) (xy 443.092078 -276.183598)
			(xy 443.092078 -273.999706) (xy 443.078985 -273.979262) (xy 443.058289 -273.935346) (xy 443.044241 -273.888876)
			(xy 443.037142 -273.84085) (xy 443.037145 -273.792303) (xy 443.044251 -273.744278) (xy 443.058306 -273.69781)
			(xy 443.079008 -273.653898) (xy 443.092078 -273.633438) (xy 443.092078 -272.299938) (xy 443.078983 -272.279493)
			(xy 443.058282 -272.235578) (xy 443.044229 -272.189106) (xy 443.037126 -272.141078) (xy 443.037126 -272.092528)
			(xy 443.044228 -272.044501) (xy 443.05828 -271.998029) (xy 443.07898 -271.954112) (xy 443.092078 -271.93367)
			(xy 443.092078 -270.599916) (xy 443.078985 -270.579471) (xy 443.058287 -270.535556) (xy 443.044237 -270.489085)
			(xy 443.037137 -270.441059) (xy 443.037139 -270.392511) (xy 443.044244 -270.344485) (xy 443.058298 -270.298016)
			(xy 443.078999 -270.254102) (xy 443.092078 -270.233648) (xy 443.092078 -268.899894) (xy 443.078986 -268.87945)
			(xy 443.058292 -268.835535) (xy 443.044245 -268.789065) (xy 443.037148 -268.74104) (xy 443.037153 -268.692494)
			(xy 443.04426 -268.64447) (xy 443.058316 -268.598003) (xy 443.079019 -268.554092) (xy 443.092078 -268.533626)
			(xy 443.092078 -268.045184) (xy 443.07785 -268.022243) (xy 443.056283 -267.97276) (xy 443.043104 -267.920415)
			(xy 443.038669 -267.866618) (xy 443.043098 -267.812822) (xy 443.056271 -267.760475) (xy 443.077832 -267.71099)
			(xy 443.092078 -267.68806) (xy 443.092078 -267.199872) (xy 443.07898 -267.179427) (xy 443.058275 -267.135511)
			(xy 443.044217 -267.089038) (xy 443.037109 -267.041008) (xy 443.037105 -266.992455) (xy 443.044203 -266.944424)
			(xy 443.058252 -266.897948) (xy 443.078949 -266.854028) (xy 443.092078 -266.833604) (xy 443.092078 -265.49985)
			(xy 443.078982 -265.479405) (xy 443.05828 -265.435489) (xy 443.044225 -265.389017) (xy 443.03712 -265.340989)
			(xy 443.037118 -265.292438) (xy 443.044219 -265.244409) (xy 443.05827 -265.197935) (xy 443.078969 -265.154018)
			(xy 443.092078 -265.133582) (xy 443.092078 -263.799828) (xy 443.078984 -263.779383) (xy 443.058285 -263.735468)
			(xy 443.044233 -263.688997) (xy 443.037131 -263.64097) (xy 443.037132 -263.59242) (xy 443.044235 -263.544394)
			(xy 443.058288 -263.497923) (xy 443.078989 -263.454008) (xy 443.092078 -263.43356) (xy 443.092078 -262.099806)
			(xy 443.078985 -262.079362) (xy 443.058289 -262.035446) (xy 443.044241 -261.988976) (xy 443.037142 -261.94095)
			(xy 443.037145 -261.892403) (xy 443.044251 -261.844378) (xy 443.058306 -261.79791) (xy 443.079008 -261.753998)
			(xy 443.092078 -261.733538) (xy 443.092078 -260.399784) (xy 443.07898 -260.379339) (xy 443.058272 -260.335423)
			(xy 443.044213 -260.288949) (xy 443.037103 -260.240918) (xy 443.037097 -260.192365) (xy 443.044195 -260.144332)
			(xy 443.058242 -260.097855) (xy 443.078939 -260.053933) (xy 443.092078 -260.033516) (xy 443.092078 -258.699762)
			(xy 443.078981 -258.679317) (xy 443.058277 -258.635401) (xy 443.044221 -258.588928) (xy 443.037114 -258.540899)
			(xy 443.037111 -258.492347) (xy 443.04421 -258.444317) (xy 443.05826 -258.397842) (xy 443.078958 -258.353923)
			(xy 443.092078 -258.333494) (xy 443.092078 -251.899928) (xy 443.078984 -251.879483) (xy 443.058285 -251.835568)
			(xy 443.044233 -251.789097) (xy 443.037131 -251.74107) (xy 443.037132 -251.69252) (xy 443.044235 -251.644494)
			(xy 443.058288 -251.598023) (xy 443.078989 -251.554108) (xy 443.092078 -251.53366) (xy 443.092078 -250.199906)
			(xy 443.078985 -250.179462) (xy 443.058289 -250.135546) (xy 443.044241 -250.089076) (xy 443.037142 -250.04105)
			(xy 443.037145 -249.992503) (xy 443.044251 -249.944478) (xy 443.058306 -249.89801) (xy 443.079008 -249.854098)
			(xy 443.092078 -249.833638) (xy 443.092078 -248.499884) (xy 443.07898 -248.479439) (xy 443.058272 -248.435523)
			(xy 443.044213 -248.389049) (xy 443.037103 -248.341018) (xy 443.037097 -248.292465) (xy 443.044195 -248.244432)
			(xy 443.058242 -248.197955) (xy 443.078939 -248.154033) (xy 443.092078 -248.133616) (xy 443.092078 -246.799862)
			(xy 443.078981 -246.779417) (xy 443.058277 -246.735501) (xy 443.044221 -246.689028) (xy 443.037114 -246.640999)
			(xy 443.037111 -246.592447) (xy 443.04421 -246.544417) (xy 443.05826 -246.497942) (xy 443.078958 -246.454023)
			(xy 443.092078 -246.433594) (xy 443.092078 -245.945152) (xy 443.077853 -245.922211) (xy 443.05629 -245.872729)
			(xy 443.043117 -245.820385) (xy 443.038687 -245.766592) (xy 443.043119 -245.712798) (xy 443.056296 -245.660455)
			(xy 443.077861 -245.610974) (xy 443.092078 -245.588028) (xy 443.092078 -245.09984) (xy 443.078983 -245.079395)
			(xy 443.058282 -245.03548) (xy 443.044229 -244.989008) (xy 443.037125 -244.94098) (xy 443.037124 -244.89243)
			(xy 443.044226 -244.844402) (xy 443.058278 -244.79793) (xy 443.078978 -244.754013) (xy 443.092078 -244.733572)
			(xy 443.092078 -244.24513) (xy 443.077854 -244.222189) (xy 443.056296 -244.172708) (xy 443.043126 -244.120365)
			(xy 443.038699 -244.066573) (xy 443.043134 -244.012782) (xy 443.056313 -243.960441) (xy 443.07788 -243.910964)
			(xy 443.092078 -243.888006) (xy 443.092078 -243.395246) (xy 443.077853 -243.372305) (xy 443.056292 -243.322823)
			(xy 443.043119 -243.27048) (xy 443.03869 -243.216687) (xy 443.043124 -243.162894) (xy 443.056301 -243.110551)
			(xy 443.077866 -243.061071) (xy 443.092078 -243.038122) (xy 443.092078 -242.549934) (xy 443.078983 -242.529489)
			(xy 443.058283 -242.485574) (xy 443.044231 -242.439102) (xy 443.037128 -242.391075) (xy 443.037128 -242.342525)
			(xy 443.044231 -242.294498) (xy 443.058283 -242.248026) (xy 443.078983 -242.204111) (xy 443.092078 -242.183666)
			(xy 443.092078 -240.849912) (xy 443.078985 -240.829467) (xy 443.058288 -240.785552) (xy 443.044239 -240.739082)
			(xy 443.037139 -240.691056) (xy 443.037142 -240.642508) (xy 443.044247 -240.594483) (xy 443.058301 -240.548013)
			(xy 443.079003 -240.504101) (xy 443.092078 -240.483644) (xy 443.092078 -239.14989) (xy 443.078986 -239.129446)
			(xy 443.058293 -239.085531) (xy 443.044247 -239.039061) (xy 443.03715 -238.991037) (xy 443.037155 -238.94249)
			(xy 443.044263 -238.894467) (xy 443.058319 -238.848001) (xy 443.079022 -238.804091) (xy 443.092078 -238.783622)
			(xy 443.092078 -236.59973) (xy 443.078984 -236.579285) (xy 443.058284 -236.53537) (xy 443.044232 -236.488899)
			(xy 443.03713 -236.440871) (xy 443.03713 -236.392322) (xy 443.044234 -236.344295) (xy 443.058287 -236.297824)
			(xy 443.078987 -236.253909) (xy 443.092078 -236.233462) (xy 443.092078 -234.899708) (xy 443.078985 -234.879264)
			(xy 443.058289 -234.835348) (xy 443.04424 -234.788878) (xy 443.037141 -234.740852) (xy 443.037144 -234.692305)
			(xy 443.04425 -234.64428) (xy 443.058304 -234.597811) (xy 443.079006 -234.553899) (xy 443.092078 -234.53344)
			(xy 443.092078 -233.19994) (xy 443.078983 -233.179495) (xy 443.058282 -233.13558) (xy 443.044229 -233.089108)
			(xy 443.037125 -233.04108) (xy 443.037124 -232.99253) (xy 443.044226 -232.944502) (xy 443.058278 -232.89803)
			(xy 443.078978 -232.854113) (xy 443.092078 -232.833672) (xy 443.092078 -231.499918) (xy 443.078984 -231.479473)
			(xy 443.058287 -231.435558) (xy 443.044236 -231.389087) (xy 443.037136 -231.341061) (xy 443.037138 -231.292512)
			(xy 443.044242 -231.244487) (xy 443.058296 -231.198017) (xy 443.078998 -231.154103) (xy 443.092078 -231.13365)
			(xy 443.092078 -229.799896) (xy 443.078986 -229.779452) (xy 443.058292 -229.735537) (xy 443.044244 -229.689067)
			(xy 443.037147 -229.641042) (xy 443.037151 -229.592495) (xy 443.044258 -229.544471) (xy 443.058314 -229.498004)
			(xy 443.079017 -229.454093) (xy 443.092078 -229.433628) (xy 443.092078 -227.249736) (xy 443.078983 -227.229291)
			(xy 443.058283 -227.185376) (xy 443.04423 -227.138904) (xy 443.037127 -227.090877) (xy 443.037127 -227.042327)
			(xy 443.044229 -226.994299) (xy 443.058282 -226.947827) (xy 443.078981 -226.903911) (xy 443.092078 -226.883468)
			(xy 443.092078 -225.549714) (xy 443.078985 -225.529269) (xy 443.058288 -225.485354) (xy 443.044238 -225.438884)
			(xy 443.037138 -225.390857) (xy 443.03714 -225.342309) (xy 443.044245 -225.294284) (xy 443.0583 -225.247815)
			(xy 443.079001 -225.203901) (xy 443.092078 -225.183446) (xy 443.092078 -223.849692) (xy 443.078986 -223.829248)
			(xy 443.058292 -223.785333) (xy 443.044246 -223.738863) (xy 443.037149 -223.690838) (xy 443.037154 -223.642292)
			(xy 443.044261 -223.594269) (xy 443.058318 -223.547802) (xy 443.079021 -223.503891) (xy 443.092078 -223.483424)
			(xy 443.092078 -222.149924) (xy 443.078984 -222.129479) (xy 443.058285 -222.085564) (xy 443.044234 -222.039093)
			(xy 443.037133 -221.991066) (xy 443.037134 -221.942517) (xy 443.044238 -221.894491) (xy 443.058291 -221.84802)
			(xy 443.078992 -221.804106) (xy 443.092078 -221.783656) (xy 443.092078 -220.449902) (xy 443.078986 -220.429458)
			(xy 443.05829 -220.385543) (xy 443.044242 -220.339072) (xy 443.037144 -220.291047) (xy 443.037148 -220.2425)
			(xy 443.044254 -220.194476) (xy 443.058309 -220.148008) (xy 443.079012 -220.104096) (xy 443.092078 -220.083634)
			(xy 443.092078 -217.899742) (xy 443.078983 -217.879297) (xy 443.058282 -217.835382) (xy 443.044228 -217.78891)
			(xy 443.037124 -217.740882) (xy 443.037123 -217.692331) (xy 443.044225 -217.644303) (xy 443.058277 -217.597831)
			(xy 443.078976 -217.553914) (xy 443.092078 -217.533474) (xy 443.092078 -216.19972) (xy 443.078984 -216.179275)
			(xy 443.058286 -216.13536) (xy 443.044236 -216.088889) (xy 443.037135 -216.040863) (xy 443.037137 -215.992314)
			(xy 443.044241 -215.944288) (xy 443.058295 -215.897818) (xy 443.078996 -215.853904) (xy 443.092078 -215.833452)
			(xy 443.092078 -214.499698) (xy 443.078986 -214.479254) (xy 443.058291 -214.435339) (xy 443.044244 -214.388869)
			(xy 443.037146 -214.340843) (xy 443.03715 -214.292297) (xy 443.044257 -214.244273) (xy 443.058313 -214.197805)
			(xy 443.079015 -214.153894) (xy 443.092078 -214.13343) (xy 443.092078 -212.79993) (xy 443.078984 -212.779485)
			(xy 443.058284 -212.73557) (xy 443.044232 -212.689099) (xy 443.03713 -212.641071) (xy 443.03713 -212.592522)
			(xy 443.044234 -212.544495) (xy 443.058287 -212.498024) (xy 443.078987 -212.454109) (xy 443.092078 -212.433662)
			(xy 443.092078 -211.099908) (xy 443.078985 -211.079464) (xy 443.058289 -211.035548) (xy 443.04424 -210.989078)
			(xy 443.037141 -210.941052) (xy 443.037144 -210.892505) (xy 443.04425 -210.84448) (xy 443.058304 -210.798011)
			(xy 443.079006 -210.754099) (xy 443.092078 -210.73364) (xy 443.092078 -208.549748) (xy 443.078982 -208.529303)
			(xy 443.05828 -208.485387) (xy 443.044226 -208.438915) (xy 443.037121 -208.390887) (xy 443.037119 -208.342336)
			(xy 443.044221 -208.294307) (xy 443.058272 -208.247834) (xy 443.078971 -208.203917) (xy 443.092078 -208.18348)
			(xy 443.092078 -206.849726) (xy 443.078984 -206.829281) (xy 443.058285 -206.785366) (xy 443.044234 -206.738895)
			(xy 443.037132 -206.690868) (xy 443.037133 -206.642319) (xy 443.044237 -206.594292) (xy 443.05829 -206.547822)
			(xy 443.07899 -206.503907) (xy 443.092078 -206.483458) (xy 443.092078 -205.149704) (xy 443.078985 -205.12926)
			(xy 443.05829 -205.085344) (xy 443.044241 -205.038874) (xy 443.037143 -204.990849) (xy 443.037146 -204.942301)
			(xy 443.044252 -204.894277) (xy 443.058308 -204.847809) (xy 443.07901 -204.803897) (xy 443.092078 -204.783436)
			(xy 443.092078 -203.449936) (xy 443.078983 -203.429491) (xy 443.058283 -203.385576) (xy 443.04423 -203.339104)
			(xy 443.037127 -203.291077) (xy 443.037127 -203.242527) (xy 443.044229 -203.194499) (xy 443.058282 -203.148027)
			(xy 443.078981 -203.104111) (xy 443.092078 -203.083668) (xy 443.092078 -201.749914) (xy 443.078985 -201.729469)
			(xy 443.058288 -201.685554) (xy 443.044238 -201.639084) (xy 443.037138 -201.591057) (xy 443.03714 -201.542509)
			(xy 443.044245 -201.494484) (xy 443.0583 -201.448015) (xy 443.079001 -201.404101) (xy 443.092078 -201.383646)
			(xy 443.092078 -199.199754) (xy 443.078982 -199.179309) (xy 443.058279 -199.135393) (xy 443.044224 -199.088921)
			(xy 443.037118 -199.040892) (xy 443.037116 -198.992341) (xy 443.044216 -198.944312) (xy 443.058267 -198.897838)
			(xy 443.078965 -198.85392) (xy 443.092078 -198.833486) (xy 443.092078 -197.499732) (xy 443.078983 -197.479287)
			(xy 443.058284 -197.435372) (xy 443.044231 -197.3889) (xy 443.037129 -197.340873) (xy 443.037129 -197.292324)
			(xy 443.044232 -197.244296) (xy 443.058285 -197.197825) (xy 443.078985 -197.15391) (xy 443.092078 -197.133464)
			(xy 443.092078 -195.79971) (xy 443.078985 -195.779265) (xy 443.058288 -195.73535) (xy 443.044239 -195.68888)
			(xy 443.03714 -195.640854) (xy 443.037143 -195.592306) (xy 443.044248 -195.544281) (xy 443.058303 -195.497812)
			(xy 443.079005 -195.4539) (xy 443.092078 -195.433442) (xy 443.092078 -194.992498) (xy 443.075233 -194.971148)
			(xy 443.047543 -194.924346) (xy 443.027292 -194.873877) (xy 443.01495 -194.820916) (xy 443.010804 -194.766694)
			(xy 443.014952 -194.712472) (xy 443.027296 -194.659511) (xy 443.047549 -194.609043) (xy 443.07524 -194.562242)
			(xy 443.092078 -194.540886) (xy 443.092078 -170.642026) (xy 442.595762 -170.14571) (xy 428.295308 -170.14571)
			(xy 428.285148 -170.183048) (xy 428.273602 -170.223103) (xy 428.243837 -170.300973) (xy 428.20671 -170.375614)
			(xy 428.162568 -170.446333) (xy 428.111821 -170.512472) (xy 428.05494 -170.573417) (xy 427.992453 -170.6286)
			(xy 427.924943 -170.677509) (xy 427.853037 -170.719689) (xy 427.777402 -170.754748) (xy 427.698743 -170.78236)
			(xy 427.61779 -170.802268) (xy 427.535296 -170.814288) (xy 427.452028 -170.818307) (xy 427.36876 -170.814288)
			(xy 427.286266 -170.802268) (xy 427.205313 -170.78236) (xy 427.126654 -170.754748) (xy 427.051019 -170.719689)
			(xy 426.979113 -170.677509) (xy 426.911603 -170.6286) (xy 426.849116 -170.573417) (xy 426.792235 -170.512472)
			(xy 426.741488 -170.446333) (xy 426.697346 -170.375614) (xy 426.660219 -170.300973) (xy 426.630454 -170.223103)
			(xy 426.618908 -170.183048) (xy 426.608748 -170.14571) (xy 421.489632 -170.14571) (xy 421.464678 -170.145092)
			(xy 421.415731 -170.135344) (xy 421.369626 -170.116235) (xy 421.328134 -170.088499) (xy 421.310054 -170.071288)
			(xy 420.87673 -169.637964) (xy 420.859471 -169.619922) (xy 420.831716 -169.578428) (xy 420.812603 -169.53231)
			(xy 420.80287 -169.483347) (xy 420.802308 -169.458386) (xy 420.802308 -162.494468) (xy 420.8018 -162.490404)
			(xy 420.799797 -162.47684) (xy 420.797637 -162.449504) (xy 420.797482 -162.435794) (xy 420.797644 -162.422084)
			(xy 420.799803 -162.394749) (xy 420.8018 -162.381184) (xy 420.802308 -162.37712) (xy 420.802308 -157.980634)
			(xy 420.774368 -157.96641) (xy 420.751078 -157.954233) (xy 420.708045 -157.924065) (xy 420.669916 -157.887897)
			(xy 420.637521 -157.846515) (xy 420.611562 -157.800819) (xy 420.592606 -157.751803) (xy 420.581063 -157.700532)
			(xy 420.577185 -157.648122) (xy 420.581057 -157.59571) (xy 420.592593 -157.544438) (xy 420.611544 -157.49542)
			(xy 420.637497 -157.449721) (xy 420.669887 -157.408335) (xy 420.708012 -157.372162) (xy 420.751041 -157.341989)
			(xy 420.774368 -157.329886) (xy 420.802308 -157.315662) (xy 420.802308 -155.594812) (xy 420.76497 -155.584652)
			(xy 420.738503 -155.576832) (xy 420.687982 -155.554621) (xy 420.641189 -155.525364) (xy 420.599099 -155.489669)
			(xy 420.562591 -155.448284) (xy 420.532426 -155.402069) (xy 420.509234 -155.351992) (xy 420.493499 -155.299095)
			(xy 420.48555 -155.244483) (xy 420.485551 -155.189296) (xy 420.493504 -155.134684) (xy 420.509242 -155.081788)
			(xy 420.532436 -155.031712) (xy 420.562604 -154.985499) (xy 420.599114 -154.944116) (xy 420.641206 -154.908424)
			(xy 420.688001 -154.879169) (xy 420.738523 -154.856961) (xy 420.76497 -154.849068) (xy 420.802308 -154.838908)
			(xy 420.802308 -150.879556) (xy 420.801871 -150.865957) (xy 420.794685 -150.839724) (xy 420.780833 -150.816317)
			(xy 420.761296 -150.797393) (xy 420.73746 -150.784293) (xy 420.711012 -150.777946) (xy 420.697406 -150.777956)
			(xy 420.684452 -150.77821) (xy 420.657203 -150.777721) (xy 420.60326 -150.769959) (xy 420.550971 -150.7546)
			(xy 420.5014 -150.731956) (xy 420.455555 -150.702488) (xy 420.414371 -150.666797) (xy 420.378684 -150.625608)
			(xy 420.349222 -150.57976) (xy 420.326584 -150.530186) (xy 420.311231 -150.477895) (xy 420.303476 -150.423951)
			(xy 420.302944 -150.396702) (xy 420.303368 -150.371243) (xy 420.310147 -150.320778) (xy 420.323584 -150.271665)
			(xy 420.343441 -150.224779) (xy 420.35603 -150.202646) (xy 420.376096 -150.168864) (xy 418.822378 -148.615146)
			(xy 410.957268 -148.615146) (xy 410.951788 -148.622299) (xy 410.939968 -148.635903) (xy 410.933646 -148.642324)
			(xy 410.474668 -149.101302) (xy 410.474668 -164.785548) (xy 410.504386 -164.79901) (xy 410.528949 -164.810713)
			(xy 410.574506 -164.840455) (xy 410.615011 -164.876779) (xy 410.64952 -164.918841) (xy 410.677231 -164.965662)
			(xy 410.697498 -165.016153) (xy 410.709851 -165.069139) (xy 410.714003 -165.123387) (xy 410.709855 -165.177635)
			(xy 410.697506 -165.230622) (xy 410.677242 -165.281114) (xy 410.649535 -165.327937) (xy 410.615029 -165.370002)
			(xy 410.574527 -165.406329) (xy 410.528972 -165.436075) (xy 410.504386 -165.447726) (xy 410.474668 -165.461188)
			(xy 410.474668 -166.733728) (xy 410.504386 -166.74719) (xy 410.527433 -166.758116) (xy 410.570409 -166.785584)
			(xy 410.609026 -166.818902) (xy 410.642493 -166.85739) (xy 410.670127 -166.90026) (xy 410.69136 -166.946634)
			(xy 410.70576 -166.995563) (xy 410.713031 -167.046046) (xy 410.713428 -167.071548) (xy 410.712877 -167.10025)
			(xy 410.703657 -167.15691) (xy 410.685463 -167.211355) (xy 410.658768 -167.262175) (xy 410.624263 -167.308052)
			(xy 410.603954 -167.328342) (xy 410.594382 -167.338136) (xy 410.580367 -167.361651) (xy 410.573103 -167.388045)
			(xy 410.573112 -167.415421) (xy 410.580393 -167.44181) (xy 410.594423 -167.465316) (xy 410.603954 -167.475154)
			(xy 410.624291 -167.49542) (xy 410.658805 -167.541298) (xy 410.685505 -167.592123) (xy 410.703696 -167.646575)
			(xy 410.712907 -167.703242) (xy 410.713428 -167.731948) (xy 410.712989 -167.757447) (xy 410.705709 -167.807922)
			(xy 410.691307 -167.856844) (xy 410.670075 -167.903211) (xy 410.642447 -167.946078) (xy 410.60899 -167.984566)
			(xy 410.570386 -168.01789) (xy 410.527424 -168.045368) (xy 410.504386 -168.056306) (xy 410.474668 -168.069768)
			(xy 410.474668 -173.421548) (xy 410.504386 -173.43501) (xy 410.528949 -173.446713) (xy 410.574506 -173.476455)
			(xy 410.615011 -173.512779) (xy 410.64952 -173.554841) (xy 410.677231 -173.601662) (xy 410.697498 -173.652153)
			(xy 410.709851 -173.705139) (xy 410.714003 -173.759387) (xy 410.709855 -173.813635) (xy 410.697506 -173.866622)
			(xy 410.677242 -173.917114) (xy 410.649535 -173.963937) (xy 410.615029 -174.006002) (xy 410.574527 -174.042329)
			(xy 410.528972 -174.072075) (xy 410.504386 -174.083726) (xy 410.474668 -174.097188) (xy 410.474668 -175.369728)
			(xy 410.504386 -175.38319) (xy 410.527433 -175.394116) (xy 410.570409 -175.421584) (xy 410.609026 -175.454902)
			(xy 410.642493 -175.49339) (xy 410.670127 -175.53626) (xy 410.69136 -175.582634) (xy 410.695605 -175.597058)
			(xy 434.095902 -175.597058) (xy 434.099991 -175.541176) (xy 434.112174 -175.486486) (xy 434.13219 -175.434152)
			(xy 434.159613 -175.38529) (xy 434.193858 -175.340942) (xy 434.234194 -175.302052) (xy 434.279764 -175.26945)
			(xy 434.329595 -175.243831) (xy 434.382625 -175.225739) (xy 434.437723 -175.215562) (xy 434.493717 -175.213516)
			(xy 434.549412 -175.219644) (xy 434.603621 -175.233816) (xy 434.655189 -175.25573) (xy 434.703017 -175.284919)
			(xy 434.746085 -175.32076) (xy 434.783475 -175.36249) (xy 434.814391 -175.40922) (xy 434.838174 -175.459953)
			(xy 434.854316 -175.513609) (xy 434.862475 -175.569043) (xy 434.862986 -175.597058) (xy 434.862475 -175.625073)
			(xy 434.854316 -175.680507) (xy 434.838174 -175.734163) (xy 434.814391 -175.784896) (xy 434.783475 -175.831626)
			(xy 434.746085 -175.873356) (xy 434.703017 -175.909197) (xy 434.655189 -175.938386) (xy 434.603621 -175.9603)
			(xy 434.549412 -175.974472) (xy 434.493717 -175.9806) (xy 434.437723 -175.978554) (xy 434.382625 -175.968377)
			(xy 434.329595 -175.950285) (xy 434.279764 -175.924666) (xy 434.234194 -175.892064) (xy 434.193858 -175.853174)
			(xy 434.159613 -175.808826) (xy 434.13219 -175.759964) (xy 434.112174 -175.70763) (xy 434.099991 -175.65294)
			(xy 434.095902 -175.597058) (xy 410.695605 -175.597058) (xy 410.70576 -175.631563) (xy 410.713031 -175.682046)
			(xy 410.713428 -175.707548) (xy 410.712877 -175.73625) (xy 410.703657 -175.79291) (xy 410.685463 -175.847355)
			(xy 410.658768 -175.898175) (xy 410.624263 -175.944052) (xy 410.603954 -175.964342) (xy 410.594382 -175.974136)
			(xy 410.580367 -175.997651) (xy 410.573103 -176.024045) (xy 410.573112 -176.051421) (xy 410.580393 -176.07781)
			(xy 410.594423 -176.101316) (xy 410.603954 -176.111154) (xy 410.624291 -176.13142) (xy 410.658805 -176.177298)
			(xy 410.685505 -176.228123) (xy 410.703696 -176.282575) (xy 410.712907 -176.339242) (xy 410.713428 -176.367948)
			(xy 410.712989 -176.393447) (xy 410.705709 -176.443922) (xy 410.691307 -176.492844) (xy 410.670075 -176.539211)
			(xy 410.642447 -176.582078) (xy 410.60899 -176.620566) (xy 410.570386 -176.65389) (xy 410.527424 -176.681368)
			(xy 410.504386 -176.692306) (xy 410.474668 -176.705768) (xy 410.474668 -182.057548) (xy 410.504386 -182.07101)
			(xy 410.528949 -182.082713) (xy 410.574506 -182.112455) (xy 410.615011 -182.148779) (xy 410.64952 -182.190841)
			(xy 410.677231 -182.237662) (xy 410.697498 -182.288153) (xy 410.709851 -182.341139) (xy 410.714003 -182.395387)
			(xy 410.709855 -182.449635) (xy 410.697506 -182.502622) (xy 410.677242 -182.553114) (xy 410.649535 -182.599937)
			(xy 410.615029 -182.642002) (xy 410.574527 -182.678329) (xy 410.528972 -182.708075) (xy 410.504386 -182.719726)
			(xy 410.474668 -182.733188) (xy 410.474668 -191.864488) (xy 410.489551 -191.887992) (xy 410.513089 -191.938396)
			(xy 410.529061 -191.991683) (xy 410.53713 -192.046724) (xy 410.537125 -192.102353) (xy 410.529045 -192.157392)
			(xy 410.513061 -192.210676) (xy 410.489513 -192.261076) (xy 410.474668 -192.284604) (xy 410.474668 -213.993984)
			(xy 411.02534 -214.544656) (xy 428.490634 -214.544656) (xy 428.515593 -214.545231) (xy 428.564549 -214.554977)
			(xy 428.610664 -214.574089) (xy 428.652162 -214.60183) (xy 428.670212 -214.619078) (xy 429.290734 -215.2396)
			(xy 429.30799 -215.257643) (xy 429.335739 -215.299138) (xy 429.354843 -215.345256) (xy 429.364564 -215.394218)
			(xy 429.365156 -215.419178) (xy 429.365156 -312.226706) (xy 429.38827 -312.241946) (xy 429.399376 -312.249351)
			(xy 429.420118 -312.266153) (xy 429.429672 -312.275474) (xy 429.743108 -312.58891) (xy 432.334924 -312.58891)
		)
		(stroke
			(width 0)
			(type solid)
		)
		(fill yes)
		(layer "In9.Cu")
		(net "GND")
	)
	(gr_poly
		(pts
			(xy 358.994964 -362.3056) (xy 359.004511 -362.279475) (xy 359.030096 -362.230089) (xy 359.06258 -362.18494)
			(xy 359.101275 -362.144987) (xy 359.145361 -362.111075) (xy 359.193904 -362.083924) (xy 359.245875 -362.064108)
			(xy 359.300171 -362.052048) (xy 359.355644 -362.048) (xy 359.411117 -362.052048) (xy 359.465413 -362.064108)
			(xy 359.517384 -362.083924) (xy 359.565927 -362.111075) (xy 359.610013 -362.144987) (xy 359.648708 -362.18494)
			(xy 359.681192 -362.230089) (xy 359.706777 -362.279475) (xy 359.716324 -362.3056) (xy 359.728008 -362.33989)
			(xy 363.395514 -362.33989) (xy 363.416832 -362.320662) (xy 363.464161 -362.288172) (xy 363.515824 -362.263141)
			(xy 363.570654 -362.246132) (xy 363.627414 -362.237531) (xy 363.684822 -362.237531) (xy 363.741582 -362.246132)
			(xy 363.796412 -362.263141) (xy 363.848075 -362.288172) (xy 363.895404 -362.320662) (xy 363.916722 -362.33989)
			(xy 383.885186 -362.33989) (xy 383.908491 -362.32533) (xy 383.9584 -362.302338) (xy 384.011095 -362.286757)
			(xy 384.065482 -362.27891) (xy 384.092958 -362.278422) (xy 384.120431 -362.278909) (xy 384.174807 -362.286798)
			(xy 384.227493 -362.302391) (xy 384.277405 -362.325366) (xy 384.30073 -362.33989) (xy 414.451292 -362.33989)
			(xy 414.474454 -362.324944) (xy 414.524249 -362.301303) (xy 414.576982 -362.28525) (xy 414.631503 -362.277135)
			(xy 414.686625 -362.277135) (xy 414.741146 -362.28525) (xy 414.793879 -362.301303) (xy 414.843674 -362.324944)
			(xy 414.866836 -362.33989) (xy 415.078672 -362.33989) (xy 415.101834 -362.324944) (xy 415.151629 -362.301303)
			(xy 415.204362 -362.28525) (xy 415.258883 -362.277135) (xy 415.314005 -362.277135) (xy 415.368526 -362.28525)
			(xy 415.421259 -362.301303) (xy 415.471054 -362.324944) (xy 415.494216 -362.33989) (xy 415.695892 -362.33989)
			(xy 415.719054 -362.324944) (xy 415.768849 -362.301303) (xy 415.821582 -362.28525) (xy 415.876103 -362.277135)
			(xy 415.931225 -362.277135) (xy 415.985746 -362.28525) (xy 416.038479 -362.301303) (xy 416.088274 -362.324944)
			(xy 416.111436 -362.33989) (xy 424.139614 -362.33989) (xy 424.162776 -362.324944) (xy 424.212571 -362.301303)
			(xy 424.265304 -362.28525) (xy 424.319825 -362.277135) (xy 424.374947 -362.277135) (xy 424.429468 -362.28525)
			(xy 424.482201 -362.301303) (xy 424.531996 -362.324944) (xy 424.555158 -362.33989) (xy 424.766994 -362.33989)
			(xy 424.790156 -362.324944) (xy 424.839951 -362.301303) (xy 424.892684 -362.28525) (xy 424.947205 -362.277135)
			(xy 425.002327 -362.277135) (xy 425.056848 -362.28525) (xy 425.109581 -362.301303) (xy 425.159376 -362.324944)
			(xy 425.182538 -362.33989) (xy 425.384214 -362.33989) (xy 425.407376 -362.324944) (xy 425.457171 -362.301303)
			(xy 425.509904 -362.28525) (xy 425.564425 -362.277135) (xy 425.619547 -362.277135) (xy 425.674068 -362.28525)
			(xy 425.726801 -362.301303) (xy 425.776596 -362.324944) (xy 425.799758 -362.33989) (xy 440.642502 -362.33989)
			(xy 445.131698 -357.850694) (xy 445.131698 -335.80959) (xy 445.13231 -335.784634) (xy 445.14205 -335.735681)
			(xy 445.161152 -335.689568) (xy 445.188883 -335.648068) (xy 445.20612 -335.630012) (xy 445.80302 -335.033112)
			(xy 445.821059 -335.015847) (xy 445.86255 -334.98808) (xy 445.908669 -334.968958) (xy 445.957635 -334.959219)
			(xy 445.982598 -334.95869) (xy 453.503792 -334.95869) (xy 453.960738 -334.501744) (xy 453.960738 -329.171046)
			(xy 453.02424 -328.234548) (xy 453.006982 -328.216506) (xy 452.979228 -328.175012) (xy 452.960117 -328.128894)
			(xy 452.950387 -328.079931) (xy 452.949818 -328.05497) (xy 452.949818 -327.83653) (xy 452.913405 -327.812576)
			(xy 452.844846 -327.758748) (xy 452.78172 -327.698642) (xy 452.724598 -327.632803) (xy 452.673999 -327.561828)
			(xy 452.630383 -327.48636) (xy 452.594145 -327.407086) (xy 452.565613 -327.324723) (xy 452.545047 -327.240019)
			(xy 452.532633 -327.153742) (xy 452.528484 -327.066676) (xy 452.532638 -326.97961) (xy 452.545056 -326.893335)
			(xy 452.565626 -326.808632) (xy 452.594162 -326.72627) (xy 452.630405 -326.646997) (xy 452.674025 -326.571532)
			(xy 452.724627 -326.500559) (xy 452.781752 -326.434723) (xy 452.844882 -326.37462) (xy 452.913444 -326.320797)
			(xy 452.949818 -326.296782) (xy 452.949818 -322.292726) (xy 452.765922 -322.10883) (xy 429.695356 -322.10883)
			(xy 429.381412 -322.422774) (xy 429.365156 -322.43776) (xy 429.365156 -323.256148) (xy 429.370744 -323.26707)
			(xy 429.383075 -323.292329) (xy 429.400506 -323.345765) (xy 429.409333 -323.401275) (xy 429.409336 -323.457482)
			(xy 429.400516 -323.512993) (xy 429.383092 -323.566431) (xy 429.370744 -323.591682) (xy 429.365156 -323.602604)
			(xy 429.365156 -328.8919) (xy 430.000156 -329.5269) (xy 430.017411 -329.544943) (xy 430.045157 -329.586439)
			(xy 430.06426 -329.632557) (xy 430.073981 -329.681519) (xy 430.074578 -329.706478) (xy 430.074578 -351.27819)
			(xy 430.073958 -351.303143) (xy 430.064205 -351.352087) (xy 430.045091 -351.398188) (xy 430.017351 -351.439674)
			(xy 430.000156 -351.457768) (xy 429.532796 -351.925128) (xy 429.514754 -351.942384) (xy 429.473259 -351.970133)
			(xy 429.42714 -351.989236) (xy 429.378178 -351.998958) (xy 429.353218 -351.99955) (xy 408.285696 -351.99955)
			(xy 408.260736 -351.998978) (xy 408.211776 -351.989237) (xy 408.165658 -351.97013) (xy 408.124154 -351.942391)
			(xy 408.106118 -351.925128) (xy 396.385034 -340.204044) (xy 396.367777 -340.186002) (xy 396.340024 -340.144507)
			(xy 396.320914 -340.098389) (xy 396.311185 -340.049426) (xy 396.310612 -340.024466) (xy 396.310612 -330.92644)
			(xy 396.045182 -330.66101) (xy 382.934718 -330.66101) (xy 382.909765 -330.660391) (xy 382.860819 -330.65064)
			(xy 382.814716 -330.631529) (xy 382.773225 -330.603793) (xy 382.75514 -330.586588) (xy 378.930408 -326.761856)
			(xy 375.186956 -326.761856) (xy 375.161998 -326.76128) (xy 375.113042 -326.751533) (xy 375.066928 -326.732421)
			(xy 375.02543 -326.704679) (xy 375.007378 -326.687434) (xy 373.483378 -325.163434) (xy 373.466119 -325.145393)
			(xy 373.438363 -325.103899) (xy 373.419252 -325.057781) (xy 373.409523 -325.008817) (xy 373.408956 -324.983856)
			(xy 373.408956 -323.742812) (xy 372.8974 -323.231256) (xy 342.077548 -323.231256) (xy 339.385656 -325.923148)
			(xy 339.367615 -325.940407) (xy 339.326121 -325.968164) (xy 339.280003 -325.987277) (xy 339.231039 -325.997009)
			(xy 339.206078 -325.99757) (xy 336.705194 -325.99757) (xy 330.024994 -332.67777) (xy 330.00695 -332.695023)
			(xy 329.965454 -332.722768) (xy 329.919336 -332.741868) (xy 329.870375 -332.751587) (xy 329.845416 -332.752192)
			(xy 318.953896 -332.752192) (xy 318.650874 -333.055214) (xy 318.650874 -338.704428) (xy 318.672557 -338.722634)
			(xy 318.710821 -338.764362) (xy 318.742494 -338.81129) (xy 318.766877 -338.862386) (xy 318.783436 -338.916527)
			(xy 318.791805 -338.972521) (xy 318.7918 -339.029137) (xy 318.783423 -339.08513) (xy 318.766856 -339.139268)
			(xy 318.742465 -339.19036) (xy 318.710785 -339.237283) (xy 318.672514 -339.279005) (xy 318.650874 -339.297264)
			(xy 318.650874 -344.98494) (xy 323.686468 -344.98494) (xy 323.686468 -344.928854) (xy 323.694682 -344.873372)
			(xy 323.710932 -344.819691) (xy 323.734868 -344.768969) (xy 323.765973 -344.722299) (xy 323.803578 -344.680687)
			(xy 323.846871 -344.64503) (xy 323.894919 -344.616098) (xy 323.920612 -344.604848) (xy 323.951854 -344.59164)
			(xy 323.951854 -341.251286) (xy 323.952386 -341.226323) (xy 323.962126 -341.177358) (xy 323.981247 -341.13124)
			(xy 324.009013 -341.089748) (xy 324.026276 -341.071708) (xy 324.774052 -340.323932) (xy 324.776592 -340.306914)
			(xy 324.780876 -340.279961) (xy 324.796164 -340.227571) (xy 324.81876 -340.177894) (xy 324.848205 -340.131944)
			(xy 324.883897 -340.090659) (xy 324.925108 -340.054881) (xy 324.970997 -340.025341) (xy 325.020627 -340.002641)
			(xy 325.072985 -339.987245) (xy 325.127003 -339.979467) (xy 325.15429 -339.979) (xy 325.183729 -339.979554)
			(xy 325.241906 -339.988609) (xy 325.298002 -340.006489) (xy 325.350688 -340.032772) (xy 325.375016 -340.049358)
			(xy 330.95819 -340.049358) (xy 331.168756 -339.838792) (xy 331.153178 -339.814953) (xy 331.128525 -339.76362)
			(xy 331.111763 -339.709197) (xy 331.103265 -339.652889) (xy 331.102716 -339.624416) (xy 331.10315 -339.598276)
			(xy 331.110302 -339.546488) (xy 331.124461 -339.496163) (xy 331.145361 -339.448243) (xy 331.172611 -339.403626)
			(xy 331.188822 -339.383116) (xy 331.188822 -339.205316) (xy 331.170877 -339.182472) (xy 331.141358 -339.132442)
			(xy 331.119771 -339.078513) (xy 331.106614 -339.021933) (xy 331.102194 -338.964012) (xy 331.106611 -338.906091)
			(xy 331.119763 -338.849511) (xy 331.141347 -338.795581) (xy 331.170862 -338.745549) (xy 331.188822 -338.722716)
			(xy 331.188822 -338.544916) (xy 331.170877 -338.522072) (xy 331.141358 -338.472042) (xy 331.119771 -338.418113)
			(xy 331.106614 -338.361533) (xy 331.102194 -338.303612) (xy 331.106611 -338.245691) (xy 331.119763 -338.189111)
			(xy 331.141347 -338.135181) (xy 331.170862 -338.085149) (xy 331.188822 -338.062316) (xy 331.188822 -337.884516)
			(xy 331.170877 -337.861672) (xy 331.141358 -337.811642) (xy 331.119771 -337.757713) (xy 331.106614 -337.701133)
			(xy 331.102194 -337.643212) (xy 331.106611 -337.585291) (xy 331.119763 -337.528711) (xy 331.141347 -337.474781)
			(xy 331.170862 -337.424749) (xy 331.188822 -337.401916) (xy 331.188822 -337.224116) (xy 331.172625 -337.203594)
			(xy 331.145364 -337.158985) (xy 331.124457 -337.111069) (xy 331.110297 -337.060744) (xy 331.103148 -337.008956)
			(xy 331.102716 -336.982816) (xy 331.103231 -336.954112) (xy 331.11183 -336.897352) (xy 331.128837 -336.842522)
			(xy 331.153868 -336.790859) (xy 331.186357 -336.743529) (xy 331.205586 -336.722212) (xy 331.215747 -336.697496)
			(xy 331.244819 -336.652668) (xy 331.263244 -336.633312) (xy 333.511398 -334.385158) (xy 333.52944 -334.367902)
			(xy 333.570942 -334.340163) (xy 333.617058 -334.321054) (xy 333.666017 -334.31131) (xy 333.690976 -334.310736)
			(xy 338.951316 -334.310736) (xy 339.149182 -334.11287) (xy 339.149182 -332.96606) (xy 339.149752 -332.941099)
			(xy 339.159479 -332.892135) (xy 339.178589 -332.846016) (xy 339.206345 -332.804523) (xy 339.223604 -332.786482)
			(xy 339.310218 -332.699868) (xy 339.296248 -332.667864) (xy 339.285823 -332.643378) (xy 339.271124 -332.592229)
			(xy 339.263686 -332.539533) (xy 339.263228 -332.512924) (xy 339.263678 -332.48567) (xy 339.271432 -332.431717)
			(xy 339.286787 -332.379417) (xy 339.30943 -332.329834) (xy 339.338898 -332.283979) (xy 339.374594 -332.242785)
			(xy 339.415789 -332.207091) (xy 339.461645 -332.177624) (xy 339.511228 -332.154983) (xy 339.563529 -332.13963)
			(xy 339.617482 -332.131877) (xy 339.644736 -332.131416) (xy 339.671343 -332.131908) (xy 339.724033 -332.139352)
			(xy 339.775181 -332.154036) (xy 339.799676 -332.164436) (xy 339.83168 -332.178406) (xy 339.970618 -332.039468)
			(xy 339.956648 -332.007464) (xy 339.946223 -331.982978) (xy 339.931524 -331.931829) (xy 339.924086 -331.879133)
			(xy 339.923628 -331.852524) (xy 339.924078 -331.82527) (xy 339.931832 -331.771317) (xy 339.947187 -331.719017)
			(xy 339.96983 -331.669434) (xy 339.999298 -331.623579) (xy 340.034994 -331.582385) (xy 340.076189 -331.546691)
			(xy 340.122045 -331.517224) (xy 340.171628 -331.494583) (xy 340.223929 -331.47923) (xy 340.277882 -331.471477)
			(xy 340.305136 -331.471016) (xy 340.331743 -331.471508) (xy 340.384433 -331.478952) (xy 340.435581 -331.493636)
			(xy 340.460076 -331.504036) (xy 340.49208 -331.518006) (xy 341.0077 -331.002386) (xy 341.025756 -330.985149)
			(xy 341.067257 -330.957419) (xy 341.113369 -330.938318) (xy 341.162322 -330.928577) (xy 341.187278 -330.927964)
			(xy 347.457014 -330.927964) (xy 347.468663 -330.903128) (xy 347.498038 -330.856799) (xy 347.533743 -330.815153)
			(xy 347.575042 -330.779047) (xy 347.621085 -330.749226) (xy 347.670923 -330.726303) (xy 347.723529 -330.710751)
			(xy 347.77782 -330.702891) (xy 347.805248 -330.702412) (xy 347.833988 -330.702903) (xy 347.890817 -330.711533)
			(xy 347.945708 -330.728591) (xy 347.99742 -330.75369) (xy 348.04478 -330.786262) (xy 348.066106 -330.805536)
			(xy 348.07764 -330.815608) (xy 348.105186 -330.82895) (xy 348.135448 -330.833535) (xy 348.16571 -330.82895)
			(xy 348.193256 -330.815608) (xy 348.20479 -330.805536) (xy 348.226097 -330.786242) (xy 348.273465 -330.753679)
			(xy 348.325181 -330.728591) (xy 348.380076 -330.711546) (xy 348.436908 -330.702929) (xy 348.465648 -330.702412)
			(xy 348.493079 -330.702892) (xy 348.547376 -330.710731) (xy 348.599991 -330.726269) (xy 348.649835 -330.749187)
			(xy 348.695882 -330.779009) (xy 348.737181 -330.815122) (xy 348.772878 -330.85678) (xy 348.802239 -330.903123)
			(xy 348.813882 -330.927964) (xy 349.19158 -330.927964) (xy 349.204534 -330.896722) (xy 349.215764 -330.87098)
			(xy 349.244675 -330.822833) (xy 349.280332 -330.779445) (xy 349.321966 -330.741754) (xy 349.368676 -330.710574)
			(xy 349.419452 -330.68658) (xy 349.473198 -330.670289) (xy 349.528752 -330.662055) (xy 349.584912 -330.662055)
			(xy 349.640466 -330.670289) (xy 349.694212 -330.68658) (xy 349.744988 -330.710574) (xy 349.791698 -330.741754)
			(xy 349.833332 -330.779445) (xy 349.868989 -330.822833) (xy 349.8979 -330.87098) (xy 349.90913 -330.896722)
			(xy 349.922084 -330.927964) (xy 355.617526 -330.927964) (xy 355.629165 -330.903123) (xy 355.658542 -330.856794)
			(xy 355.694248 -330.815148) (xy 355.735549 -330.779042) (xy 355.781593 -330.749222) (xy 355.831432 -330.7263)
			(xy 355.88404 -330.710749) (xy 355.938331 -330.70289) (xy 355.96576 -330.702412) (xy 355.9945 -330.702896)
			(xy 356.05133 -330.711528) (xy 356.106221 -330.728587) (xy 356.157932 -330.753687) (xy 356.205293 -330.786261)
			(xy 356.226618 -330.805536) (xy 356.238152 -330.815608) (xy 356.265698 -330.82895) (xy 356.29596 -330.833535)
			(xy 356.326222 -330.82895) (xy 356.353768 -330.815608) (xy 356.365302 -330.805536) (xy 356.386645 -330.786284)
			(xy 356.434003 -330.753715) (xy 356.48571 -330.728619) (xy 356.540598 -330.711564) (xy 356.597422 -330.702936)
			(xy 356.62616 -330.702412) (xy 356.653591 -330.702882) (xy 356.707889 -330.710723) (xy 356.760504 -330.726263)
			(xy 356.810348 -330.749181) (xy 356.856395 -330.779005) (xy 356.897693 -330.815119) (xy 356.933391 -330.856778)
			(xy 356.962751 -330.903122) (xy 356.974394 -330.927964) (xy 357.352092 -330.927964) (xy 357.365046 -330.896722)
			(xy 357.376276 -330.87098) (xy 357.405187 -330.822833) (xy 357.440844 -330.779445) (xy 357.482478 -330.741754)
			(xy 357.529188 -330.710574) (xy 357.579964 -330.68658) (xy 357.63371 -330.670289) (xy 357.689264 -330.662055)
			(xy 357.745424 -330.662055) (xy 357.800978 -330.670289) (xy 357.854724 -330.68658) (xy 357.9055 -330.710574)
			(xy 357.95221 -330.741754) (xy 357.993844 -330.779445) (xy 358.029501 -330.822833) (xy 358.058412 -330.87098)
			(xy 358.069642 -330.896722) (xy 358.082596 -330.927964) (xy 364.203742 -330.927964) (xy 364.21441 -330.92263)
			(xy 364.240887 -330.910141) (xy 364.296705 -330.892499) (xy 364.354558 -330.883568) (xy 364.383828 -330.883006)
			(xy 364.413101 -330.883534) (xy 364.470965 -330.892443) (xy 364.526781 -330.910109) (xy 364.553246 -330.92263)
			(xy 364.563914 -330.927964) (xy 364.864142 -330.927964) (xy 364.87481 -330.92263) (xy 364.901287 -330.910141)
			(xy 364.957105 -330.892499) (xy 365.014958 -330.883568) (xy 365.044228 -330.883006) (xy 365.073501 -330.883534)
			(xy 365.131365 -330.892443) (xy 365.187181 -330.910109) (xy 365.213646 -330.92263) (xy 365.224314 -330.927964)
			(xy 371.93855 -330.927964) (xy 371.95017 -330.903114) (xy 371.979549 -330.856784) (xy 372.015258 -330.815138)
			(xy 372.056562 -330.779033) (xy 372.102609 -330.749213) (xy 372.152451 -330.726293) (xy 372.20506 -330.710744)
			(xy 372.259354 -330.702888) (xy 372.286784 -330.702412) (xy 372.315523 -330.702942) (xy 372.37235 -330.711563)
			(xy 372.427241 -330.728611) (xy 372.478953 -330.753701) (xy 372.526315 -330.786266) (xy 372.547642 -330.805536)
			(xy 372.559176 -330.815608) (xy 372.586722 -330.82895) (xy 372.616984 -330.833535) (xy 372.647246 -330.82895)
			(xy 372.674792 -330.815608) (xy 372.686326 -330.805536) (xy 372.707659 -330.786273) (xy 372.75502 -330.753705)
			(xy 372.80673 -330.728612) (xy 372.861619 -330.711559) (xy 372.918445 -330.702934) (xy 372.947184 -330.702412)
			(xy 372.974616 -330.702861) (xy 373.028915 -330.710706) (xy 373.08153 -330.726249) (xy 373.131375 -330.749171)
			(xy 373.177421 -330.778997) (xy 373.218719 -330.815114) (xy 373.254416 -330.856775) (xy 373.283775 -330.903121)
			(xy 373.295418 -330.927964) (xy 374.734582 -330.927964) (xy 374.759544 -330.928513) (xy 374.808509 -330.938247)
			(xy 374.854627 -330.957363) (xy 374.89612 -330.985124) (xy 374.91416 -331.002386) (xy 375.38025 -331.468476)
			(xy 375.397497 -331.486526) (xy 375.425237 -331.528025) (xy 375.444349 -331.574139) (xy 375.454096 -331.623096)
			(xy 375.454672 -331.648054) (xy 375.454672 -333.866236) (xy 375.88444 -334.296004) (xy 382.285494 -334.296004)
			(xy 382.310457 -334.296534) (xy 382.359423 -334.306273) (xy 382.405542 -334.325394) (xy 382.447033 -334.353161)
			(xy 382.465072 -334.370426) (xy 383.83083 -335.736184) (xy 383.848077 -335.754234) (xy 383.875819 -335.795733)
			(xy 383.89493 -335.841847) (xy 383.904677 -335.890803) (xy 383.905252 -335.915762) (xy 383.905252 -340.650322)
			(xy 383.9285 -340.663408) (xy 383.971273 -340.69529) (xy 384.009062 -340.732948) (xy 384.041093 -340.775611)
			(xy 384.066711 -340.822406) (xy 384.085393 -340.872377) (xy 384.096757 -340.924501) (xy 384.100569 -340.977713)
			(xy 384.096753 -341.030925) (xy 384.085386 -341.083049) (xy 384.0667 -341.133018) (xy 384.041078 -341.179812)
			(xy 384.009044 -341.222472) (xy 383.971253 -341.260127) (xy 383.928477 -341.292007) (xy 383.905252 -341.305134)
			(xy 383.905252 -341.4395) (xy 383.930114 -341.453609) (xy 383.975601 -341.488226) (xy 384.015265 -341.529387)
			(xy 384.048175 -341.576125) (xy 384.073558 -341.627341) (xy 384.090818 -341.681835) (xy 384.09955 -341.738325)
			(xy 384.10007 -341.766906) (xy 384.099658 -341.791727) (xy 384.093028 -341.840924) (xy 384.079924 -341.888805)
			(xy 384.060581 -341.934523) (xy 384.035339 -341.977269) (xy 384.020314 -341.99703) (xy 384.445764 -342.42248)
			(xy 384.749802 -342.42248) (xy 384.763518 -342.393778) (xy 384.775286 -342.370472) (xy 384.804372 -342.327115)
			(xy 384.839223 -342.288242) (xy 384.879158 -342.254612) (xy 384.923396 -342.226884) (xy 384.97107 -342.205601)
			(xy 385.021248 -342.191179) (xy 385.072947 -342.1839) (xy 385.099052 -342.183466) (xy 385.127758 -342.183957)
			(xy 385.184489 -342.192777) (xy 385.239194 -342.210199) (xy 385.290577 -342.235812) (xy 385.33742 -342.269007)
			(xy 385.358386 -342.288622) (xy 385.370061 -342.299161) (xy 385.39819 -342.313195) (xy 385.429252 -342.318024)
			(xy 385.460314 -342.313195) (xy 385.488443 -342.299161) (xy 385.500118 -342.288622) (xy 385.521111 -342.269039)
			(xy 385.567948 -342.235848) (xy 385.619326 -342.210239) (xy 385.674025 -342.192819) (xy 385.730749 -342.184)
			(xy 385.759452 -342.183466) (xy 385.785554 -342.183928) (xy 385.837247 -342.191216) (xy 385.887419 -342.205643)
			(xy 385.935088 -342.226926) (xy 385.979323 -342.254649) (xy 386.019258 -342.288271) (xy 386.054115 -342.327134)
			(xy 386.08321 -342.370479) (xy 386.094986 -342.393778) (xy 386.108702 -342.42248) (xy 387.555486 -342.42248)
			(xy 387.569456 -342.394032) (xy 387.582071 -342.369304) (xy 387.61352 -342.32356) (xy 387.65141 -342.282991)
			(xy 387.694904 -342.248497) (xy 387.743036 -342.220842) (xy 387.79474 -342.200639) (xy 387.848871 -342.188335)
			(xy 387.904228 -342.184203) (xy 387.959585 -342.188335) (xy 388.013716 -342.200639) (xy 388.06542 -342.220842)
			(xy 388.113552 -342.248497) (xy 388.157046 -342.282991) (xy 388.194936 -342.32356) (xy 388.226385 -342.369304)
			(xy 388.239 -342.394032) (xy 388.25297 -342.42248) (xy 390.837166 -342.42248) (xy 390.862128 -342.423034)
			(xy 390.911093 -342.432766) (xy 390.957211 -342.451881) (xy 390.998704 -342.479641) (xy 391.016744 -342.496902)
			(xy 391.319766 -342.799924) (xy 391.336959 -342.81802) (xy 391.364699 -342.859506) (xy 391.383813 -342.905606)
			(xy 391.393567 -342.954549) (xy 391.394188 -342.979502) (xy 391.394188 -346.690188) (xy 391.393628 -346.715149)
			(xy 391.383895 -346.764113) (xy 391.364781 -346.81023) (xy 391.337025 -346.851724) (xy 391.319766 -346.869766)
			(xy 387.825234 -350.364298) (xy 387.807161 -350.381517) (xy 387.765667 -350.40925) (xy 387.719559 -350.428357)
			(xy 387.670611 -350.438103) (xy 387.645656 -350.43872) (xy 369.822984 -350.43872) (xy 368.131598 -352.130106)
			(xy 368.113542 -352.147343) (xy 368.072041 -352.175073) (xy 368.025929 -352.194175) (xy 367.976976 -352.203915)
			(xy 367.95202 -352.204528) (xy 363.59084 -352.204528) (xy 363.565879 -352.203968) (xy 363.516914 -352.194237)
			(xy 363.470796 -352.175124) (xy 363.429303 -352.147366) (xy 363.411262 -352.130106) (xy 361.336844 -350.055688)
			(xy 345.766898 -350.055688) (xy 343.967562 -351.855024) (xy 343.949491 -351.872248) (xy 343.908 -351.899994)
			(xy 343.861892 -351.919112) (xy 343.812941 -351.928867) (xy 343.787984 -351.929446) (xy 336.191606 -351.929446)
			(xy 336.166644 -351.928902) (xy 336.117679 -351.919166) (xy 336.071561 -351.900048) (xy 336.030068 -351.872286)
			(xy 336.012028 -351.855024) (xy 333.667608 -349.510604) (xy 325.875142 -349.510604) (xy 325.85018 -349.510049)
			(xy 325.801215 -349.500318) (xy 325.755097 -349.481204) (xy 325.713604 -349.453443) (xy 325.695564 -349.436182)
			(xy 324.026276 -347.766894) (xy 324.00902 -347.748852) (xy 323.981279 -347.707351) (xy 323.96217 -347.661234)
			(xy 323.952427 -347.612275) (xy 323.951854 -347.587316) (xy 323.951854 -346.222574) (xy 323.9516 -346.219526)
			(xy 323.950306 -346.208268) (xy 323.948909 -346.185646) (xy 323.948806 -346.174314) (xy 323.948919 -346.162982)
			(xy 323.950318 -346.140362) (xy 323.9516 -346.129102) (xy 323.951854 -346.126054) (xy 323.951854 -345.322144)
			(xy 323.920612 -345.308936) (xy 323.894914 -345.297699) (xy 323.846866 -345.268766) (xy 323.803574 -345.233109)
			(xy 323.76597 -345.191497) (xy 323.734865 -345.144826) (xy 323.71093 -345.094103) (xy 323.69468 -345.040422)
			(xy 323.686468 -344.98494) (xy 318.650874 -344.98494) (xy 318.650874 -350.660462) (xy 318.650297 -350.68542)
			(xy 318.640547 -350.734374) (xy 318.621433 -350.780486) (xy 318.593691 -350.821983) (xy 318.576452 -350.84004)
			(xy 317.23965 -352.176842) (xy 317.221609 -352.194101) (xy 317.180115 -352.221858) (xy 317.133997 -352.24097)
			(xy 317.085033 -352.250701) (xy 317.060072 -352.251264) (xy 284.973776 -352.251264) (xy 284.948817 -352.25069)
			(xy 284.899858 -352.240946) (xy 284.853742 -352.221837) (xy 284.81224 -352.194098) (xy 284.794198 -352.176842)
			(xy 283.970222 -351.352866) (xy 283.952958 -351.334827) (xy 283.925192 -351.293335) (xy 283.906072 -351.247217)
			(xy 283.896335 -351.198251) (xy 283.8958 -351.173288) (xy 283.8958 -319.56375) (xy 280.038302 -319.56375)
			(xy 280.018384 -319.581738) (xy 279.974154 -319.612134) (xy 279.925865 -319.635554) (xy 279.874611 -319.651468)
			(xy 279.82155 -319.659516) (xy 279.767882 -319.659516) (xy 279.714821 -319.651468) (xy 279.663567 -319.635554)
			(xy 279.615278 -319.612134) (xy 279.571048 -319.581738) (xy 279.55113 -319.56375) (xy 272.566384 -319.56375)
			(xy 272.549403 -319.584687) (xy 272.510198 -319.621686) (xy 272.465865 -319.652353) (xy 272.417416 -319.675989)
			(xy 272.365958 -319.692052) (xy 272.312667 -319.700177) (xy 272.258761 -319.700177) (xy 272.20547 -319.692052)
			(xy 272.154012 -319.675989) (xy 272.105563 -319.652353) (xy 272.06123 -319.621686) (xy 272.022025 -319.584687)
			(xy 272.005044 -319.56375) (xy 265.06932 -319.56375) (xy 265.05705 -319.586801) (xy 265.026787 -319.629356)
			(xy 264.990633 -319.667035) (xy 264.949365 -319.699031) (xy 264.903867 -319.724657) (xy 264.855114 -319.743364)
			(xy 264.804152 -319.754751) (xy 264.752074 -319.758575) (xy 264.699996 -319.754751) (xy 264.649034 -319.743364)
			(xy 264.600281 -319.724657) (xy 264.554783 -319.699031) (xy 264.513515 -319.667035) (xy 264.477361 -319.629356)
			(xy 264.447098 -319.586801) (xy 264.434828 -319.56375) (xy 257.45313 -319.56375) (xy 257.434575 -319.584035)
			(xy 257.392326 -319.619205) (xy 257.345173 -319.647466) (xy 257.294239 -319.668146) (xy 257.240731 -319.680753)
			(xy 257.185922 -319.684989) (xy 257.131113 -319.680753) (xy 257.077605 -319.668146) (xy 257.026671 -319.647466)
			(xy 256.979518 -319.619205) (xy 256.937269 -319.584035) (xy 256.918714 -319.56375) (xy 254.716788 -319.56375)
			(xy 254.695277 -319.576912) (xy 254.649334 -319.597701) (xy 254.600916 -319.611799) (xy 254.550994 -319.618925)
			(xy 254.52578 -319.619376) (xy 254.502205 -319.618993) (xy 254.455469 -319.612768) (xy 254.409963 -319.600429)
			(xy 254.366483 -319.582192) (xy 254.345948 -319.570608) (xy 254.334264 -319.56375) (xy 254.282702 -319.56375)
			(xy 254.052578 -319.793874) (xy 254.052578 -353.603129) (xy 326.814684 -353.603129) (xy 326.814684 -353.446511)
			(xy 326.822747 -353.290099) (xy 326.838851 -353.13431) (xy 326.862953 -352.979557) (xy 326.89499 -352.82625)
			(xy 326.934876 -352.674795) (xy 326.982506 -352.525594) (xy 327.037754 -352.379043) (xy 327.100472 -352.23553)
			(xy 327.170496 -352.095436) (xy 327.247638 -351.959133) (xy 327.331695 -351.826982) (xy 327.422443 -351.699333)
			(xy 327.519643 -351.576525) (xy 327.623035 -351.458884) (xy 327.732346 -351.34672) (xy 327.847287 -351.240333)
			(xy 327.967551 -351.140004) (xy 328.092821 -351.045999) (xy 328.222764 -350.958568) (xy 328.357036 -350.877941)
			(xy 328.495281 -350.804334) (xy 328.637131 -350.737941) (xy 328.782211 -350.678938) (xy 328.930136 -350.627482)
			(xy 329.080513 -350.58371) (xy 329.232945 -350.547736) (xy 329.387026 -350.519657) (xy 329.542349 -350.499548)
			(xy 329.698501 -350.487461) (xy 329.855068 -350.483428) (xy 330.011635 -350.487461) (xy 330.167787 -350.499548)
			(xy 330.32311 -350.519657) (xy 330.477191 -350.547736) (xy 330.629623 -350.58371) (xy 330.78 -350.627482)
			(xy 330.927925 -350.678938) (xy 331.073005 -350.737941) (xy 331.214855 -350.804334) (xy 331.3531 -350.877941)
			(xy 331.487372 -350.958568) (xy 331.617315 -351.045999) (xy 331.742585 -351.140004) (xy 331.862849 -351.240333)
			(xy 331.97779 -351.34672) (xy 332.087101 -351.458884) (xy 332.190493 -351.576525) (xy 332.287693 -351.699333)
			(xy 332.378441 -351.826982) (xy 332.462498 -351.959133) (xy 332.53964 -352.095436) (xy 332.609664 -352.23553)
			(xy 332.672382 -352.379043) (xy 332.72763 -352.525594) (xy 332.77526 -352.674795) (xy 332.815146 -352.82625)
			(xy 332.847183 -352.979557) (xy 332.871285 -353.13431) (xy 332.887389 -353.290099) (xy 332.895452 -353.446511)
			(xy 332.895956 -353.52482) (xy 332.895452 -353.603129) (xy 332.887389 -353.759541) (xy 332.871285 -353.91533)
			(xy 332.847183 -354.070083) (xy 332.815146 -354.22339) (xy 332.77526 -354.374845) (xy 332.731089 -354.513211)
			(xy 381.418588 -354.513211) (xy 381.418588 -354.356593) (xy 381.426651 -354.200181) (xy 381.442755 -354.044392)
			(xy 381.466857 -353.889639) (xy 381.498894 -353.736332) (xy 381.53878 -353.584877) (xy 381.58641 -353.435676)
			(xy 381.641658 -353.289125) (xy 381.704376 -353.145612) (xy 381.7744 -353.005518) (xy 381.851542 -352.869215)
			(xy 381.935599 -352.737064) (xy 382.026347 -352.609415) (xy 382.123547 -352.486607) (xy 382.226939 -352.368966)
			(xy 382.33625 -352.256802) (xy 382.451191 -352.150415) (xy 382.571455 -352.050086) (xy 382.696725 -351.956081)
			(xy 382.826668 -351.86865) (xy 382.96094 -351.788023) (xy 383.099185 -351.714416) (xy 383.241035 -351.648023)
			(xy 383.386115 -351.58902) (xy 383.53404 -351.537564) (xy 383.684417 -351.493792) (xy 383.836849 -351.457818)
			(xy 383.99093 -351.429739) (xy 384.146253 -351.40963) (xy 384.302405 -351.397543) (xy 384.458972 -351.39351)
			(xy 384.615539 -351.397543) (xy 384.771691 -351.40963) (xy 384.927014 -351.429739) (xy 385.081095 -351.457818)
			(xy 385.233527 -351.493792) (xy 385.383904 -351.537564) (xy 385.531829 -351.58902) (xy 385.676909 -351.648023)
			(xy 385.818759 -351.714416) (xy 385.957004 -351.788023) (xy 386.091276 -351.86865) (xy 386.221219 -351.956081)
			(xy 386.346489 -352.050086) (xy 386.466753 -352.150415) (xy 386.581694 -352.256802) (xy 386.691005 -352.368966)
			(xy 386.794397 -352.486607) (xy 386.891597 -352.609415) (xy 386.982345 -352.737064) (xy 387.066402 -352.869215)
			(xy 387.143544 -353.005518) (xy 387.213568 -353.145612) (xy 387.276286 -353.289125) (xy 387.331534 -353.435676)
			(xy 387.379164 -353.584877) (xy 387.41905 -353.736332) (xy 387.451087 -353.889639) (xy 387.475189 -354.044392)
			(xy 387.491293 -354.200181) (xy 387.499356 -354.356593) (xy 387.49986 -354.434902) (xy 387.499356 -354.513211)
			(xy 387.491293 -354.669623) (xy 387.475189 -354.825412) (xy 387.451087 -354.980165) (xy 387.41905 -355.133472)
			(xy 387.379164 -355.284927) (xy 387.331534 -355.434128) (xy 387.276286 -355.580679) (xy 387.213568 -355.724192)
			(xy 387.143544 -355.864286) (xy 387.066402 -356.000589) (xy 386.982345 -356.13274) (xy 386.891597 -356.260389)
			(xy 386.794397 -356.383197) (xy 386.691005 -356.500838) (xy 386.581694 -356.613002) (xy 386.466753 -356.719389)
			(xy 386.346489 -356.819718) (xy 386.221219 -356.913723) (xy 386.091276 -357.001154) (xy 385.957004 -357.081781)
			(xy 385.818759 -357.155388) (xy 385.676909 -357.221781) (xy 385.531829 -357.280784) (xy 385.383904 -357.33224)
			(xy 385.233527 -357.376012) (xy 385.081095 -357.411986) (xy 384.927014 -357.440065) (xy 384.771691 -357.460174)
			(xy 384.615539 -357.472261) (xy 384.458972 -357.476294) (xy 384.302405 -357.472261) (xy 384.146253 -357.460174)
			(xy 383.99093 -357.440065) (xy 383.836849 -357.411986) (xy 383.684417 -357.376012) (xy 383.53404 -357.33224)
			(xy 383.386115 -357.280784) (xy 383.241035 -357.221781) (xy 383.099185 -357.155388) (xy 382.96094 -357.081781)
			(xy 382.826668 -357.001154) (xy 382.696725 -356.913723) (xy 382.571455 -356.819718) (xy 382.451191 -356.719389)
			(xy 382.33625 -356.613002) (xy 382.226939 -356.500838) (xy 382.123547 -356.383197) (xy 382.026347 -356.260389)
			(xy 381.935599 -356.13274) (xy 381.851542 -356.000589) (xy 381.7744 -355.864286) (xy 381.704376 -355.724192)
			(xy 381.641658 -355.580679) (xy 381.58641 -355.434128) (xy 381.53878 -355.284927) (xy 381.498894 -355.133472)
			(xy 381.466857 -354.980165) (xy 381.442755 -354.825412) (xy 381.426651 -354.669623) (xy 381.418588 -354.513211)
			(xy 332.731089 -354.513211) (xy 332.72763 -354.524046) (xy 332.672382 -354.670597) (xy 332.609664 -354.81411)
			(xy 332.53964 -354.954204) (xy 332.462498 -355.090507) (xy 332.378441 -355.222658) (xy 332.287693 -355.350307)
			(xy 332.190493 -355.473115) (xy 332.087101 -355.590756) (xy 331.97779 -355.70292) (xy 331.862849 -355.809307)
			(xy 331.742585 -355.909636) (xy 331.617315 -356.003641) (xy 331.487372 -356.091072) (xy 331.3531 -356.171699)
			(xy 331.214855 -356.245306) (xy 331.073005 -356.311699) (xy 330.927925 -356.370702) (xy 330.78 -356.422158)
			(xy 330.629623 -356.46593) (xy 330.477191 -356.501904) (xy 330.32311 -356.529983) (xy 330.167787 -356.550092)
			(xy 330.011635 -356.562179) (xy 329.855068 -356.566212) (xy 329.698501 -356.562179) (xy 329.542349 -356.550092)
			(xy 329.387026 -356.529983) (xy 329.232945 -356.501904) (xy 329.080513 -356.46593) (xy 328.930136 -356.422158)
			(xy 328.782211 -356.370702) (xy 328.637131 -356.311699) (xy 328.495281 -356.245306) (xy 328.357036 -356.171699)
			(xy 328.222764 -356.091072) (xy 328.092821 -356.003641) (xy 327.967551 -355.909636) (xy 327.847287 -355.809307)
			(xy 327.732346 -355.70292) (xy 327.623035 -355.590756) (xy 327.519643 -355.473115) (xy 327.422443 -355.350307)
			(xy 327.331695 -355.222658) (xy 327.247638 -355.090507) (xy 327.170496 -354.954204) (xy 327.100472 -354.81411)
			(xy 327.037754 -354.670597) (xy 326.982506 -354.524046) (xy 326.934876 -354.374845) (xy 326.89499 -354.22339)
			(xy 326.862953 -354.070083) (xy 326.838851 -353.91533) (xy 326.822747 -353.759541) (xy 326.814684 -353.603129)
			(xy 254.052578 -353.603129) (xy 254.052578 -354.45827) (xy 255.68529 -356.090982) (xy 255.71831 -356.074218)
			(xy 255.811197 -356.027133) (xy 256.000112 -355.939442) (xy 256.192344 -355.859282) (xy 256.387592 -355.786776)
			(xy 256.585551 -355.722038) (xy 256.785912 -355.66517) (xy 256.988364 -355.616259) (xy 257.192589 -355.575383)
			(xy 257.398269 -355.542605) (xy 257.605083 -355.517976) (xy 257.812709 -355.501535) (xy 258.020822 -355.493307)
			(xy 258.12496 -355.492812) (xy 258.22846 -355.493313) (xy 258.4353 -355.501438) (xy 258.641662 -355.517678)
			(xy 258.847226 -355.542006) (xy 259.051678 -355.574387) (xy 259.2547 -355.614769) (xy 259.455981 -355.663091)
			(xy 259.655209 -355.719278) (xy 259.852078 -355.783244) (xy 260.046283 -355.854889) (xy 260.237526 -355.934103)
			(xy 260.425512 -356.020765) (xy 260.60995 -356.11474) (xy 260.790557 -356.215884) (xy 260.967054 -356.32404)
			(xy 261.139168 -356.439042) (xy 261.306634 -356.560713) (xy 261.469195 -356.688865) (xy 261.626599 -356.8233)
			(xy 261.778604 -356.963811) (xy 261.924975 -357.110182) (xy 262.065487 -357.262186) (xy 262.199923 -357.419589)
			(xy 262.328075 -357.58215) (xy 262.449746 -357.749616) (xy 262.564749 -357.92173) (xy 262.672906 -358.098226)
			(xy 262.774051 -358.278832) (xy 262.868027 -358.46327) (xy 262.954689 -358.651255) (xy 263.033904 -358.842498)
			(xy 263.10555 -359.036704) (xy 263.169516 -359.233572) (xy 263.225704 -359.4328) (xy 263.274026 -359.63408)
			(xy 263.314409 -359.837103) (xy 263.346791 -360.041554) (xy 263.37112 -360.247119) (xy 263.387361 -360.45348)
			(xy 263.395487 -360.66032) (xy 263.395968 -360.76382) (xy 263.395411 -360.873327) (xy 263.386334 -361.092152)
			(xy 263.368176 -361.310411) (xy 263.340969 -361.527727) (xy 263.304758 -361.743727) (xy 263.259608 -361.958035)
			(xy 263.233154 -362.0643) (xy 263.229844 -362.079421) (xy 263.231488 -362.110317) (xy 263.242296 -362.139306)
			(xy 263.261281 -362.163736) (xy 263.286703 -362.18137) (xy 263.316236 -362.190593) (xy 263.331706 -362.191046)
			(xy 283.056838 -362.191046) (xy 283.06903 -362.158026) (xy 283.078966 -362.132613) (xy 283.10506 -362.08469)
			(xy 283.137715 -362.040974) (xy 283.176266 -362.002357) (xy 283.219925 -361.969626) (xy 283.267801 -361.943448)
			(xy 283.318919 -361.924359) (xy 283.372235 -361.912748) (xy 283.426662 -361.908851) (xy 283.481089 -361.912748)
			(xy 283.534405 -361.924359) (xy 283.585523 -361.943448) (xy 283.633399 -361.969626) (xy 283.677058 -362.002357)
			(xy 283.715609 -362.040974) (xy 283.748264 -362.08469) (xy 283.774358 -362.132613) (xy 283.784294 -362.158026)
			(xy 283.796486 -362.191046) (xy 287.84677 -362.191046) (xy 287.864499 -362.168322) (xy 287.905778 -362.1281)
			(xy 287.952751 -362.094705) (xy 288.004302 -362.068932) (xy 288.059204 -362.051395) (xy 288.116149 -362.04251)
			(xy 288.144966 -362.041948) (xy 288.171863 -362.042439) (xy 288.225093 -362.05021) (xy 288.276653 -362.065552)
			(xy 288.325472 -362.088146) (xy 288.370536 -362.117523) (xy 288.41091 -362.153073) (xy 288.428684 -362.173266)
			(xy 288.443924 -362.191046) (xy 288.506408 -362.191046) (xy 288.521648 -362.173266) (xy 288.539423 -362.153073)
			(xy 288.579789 -362.117511) (xy 288.62485 -362.088126) (xy 288.673671 -362.065531) (xy 288.725235 -362.050194)
			(xy 288.778468 -362.042435) (xy 288.805366 -362.041948) (xy 288.834186 -362.042484) (xy 288.891139 -362.051353)
			(xy 288.946046 -362.068887) (xy 288.9976 -362.094665) (xy 289.044569 -362.128074) (xy 289.085835 -362.168317)
			(xy 289.103562 -362.191046) (xy 290.675822 -362.191046) (xy 290.693594 -362.16946) (xy 290.734509 -362.13135)
			(xy 290.780659 -362.099782) (xy 290.831008 -362.075465) (xy 290.884425 -362.058943) (xy 290.939711 -362.050588)
			(xy 290.995625 -362.050588) (xy 291.050911 -362.058943) (xy 291.104328 -362.075465) (xy 291.154677 -362.099782)
			(xy 291.200827 -362.13135) (xy 291.241742 -362.16946) (xy 291.259514 -362.191046) (xy 297.535092 -362.191046)
			(xy 297.552822 -362.168323) (xy 297.594101 -362.128104) (xy 297.641075 -362.094712) (xy 297.692626 -362.068942)
			(xy 297.747527 -362.051408) (xy 297.804472 -362.042526) (xy 297.833288 -362.041948) (xy 297.860184 -362.042441)
			(xy 297.913412 -362.050214) (xy 297.96497 -362.065558) (xy 298.013787 -362.088155) (xy 298.058849 -362.117533)
			(xy 298.09922 -362.153084) (xy 298.117006 -362.173266) (xy 298.132246 -362.191046) (xy 298.19473 -362.191046)
			(xy 298.20997 -362.173266) (xy 298.227746 -362.153074) (xy 298.268112 -362.117514) (xy 298.313174 -362.088133)
			(xy 298.361995 -362.06554) (xy 298.413558 -362.050206) (xy 298.466791 -362.04245) (xy 298.493688 -362.041948)
			(xy 298.522507 -362.042485) (xy 298.579458 -362.051358) (xy 298.634363 -362.068894) (xy 298.685914 -362.094674)
			(xy 298.732881 -362.128084) (xy 298.774144 -362.168327) (xy 298.791884 -362.191046) (xy 300.364144 -362.191046)
			(xy 300.381916 -362.16946) (xy 300.422831 -362.13135) (xy 300.468981 -362.099782) (xy 300.51933 -362.075465)
			(xy 300.572747 -362.058943) (xy 300.628033 -362.050588) (xy 300.683947 -362.050588) (xy 300.739233 -362.058943)
			(xy 300.79265 -362.075465) (xy 300.842999 -362.099782) (xy 300.889149 -362.13135) (xy 300.930064 -362.16946)
			(xy 300.947836 -362.191046) (xy 331.121766 -362.191046) (xy 337.70062 -355.612192) (xy 337.718659 -355.594928)
			(xy 337.760151 -355.567163) (xy 337.80627 -355.548043) (xy 337.855235 -355.538305) (xy 337.880198 -355.53777)
			(xy 347.547692 -355.53777) (xy 347.572645 -355.53839) (xy 347.62159 -355.548142) (xy 347.667693 -355.567253)
			(xy 347.709183 -355.594989) (xy 347.72727 -355.612192) (xy 353.248214 -361.133136) (xy 369.3861 -361.133136)
			(xy 369.390189 -361.077254) (xy 369.402372 -361.022564) (xy 369.422388 -360.97023) (xy 369.449811 -360.921368)
			(xy 369.484056 -360.87702) (xy 369.524392 -360.83813) (xy 369.569962 -360.805528) (xy 369.619793 -360.779909)
			(xy 369.672823 -360.761817) (xy 369.727921 -360.75164) (xy 369.783915 -360.749594) (xy 369.83961 -360.755722)
			(xy 369.893819 -360.769894) (xy 369.945387 -360.791808) (xy 369.993215 -360.820997) (xy 370.036283 -360.856838)
			(xy 370.073673 -360.898568) (xy 370.104589 -360.945298) (xy 370.128372 -360.996031) (xy 370.144514 -361.049687)
			(xy 370.152673 -361.105121) (xy 370.153184 -361.133136) (xy 370.152673 -361.161151) (xy 370.144514 -361.216585)
			(xy 370.128372 -361.270241) (xy 370.104589 -361.320974) (xy 370.073673 -361.367704) (xy 370.036283 -361.409434)
			(xy 369.993215 -361.445275) (xy 369.945387 -361.474464) (xy 369.893819 -361.496378) (xy 369.83961 -361.51055)
			(xy 369.783915 -361.516678) (xy 369.727921 -361.514632) (xy 369.672823 -361.504455) (xy 369.619793 -361.486363)
			(xy 369.569962 -361.460744) (xy 369.524392 -361.428142) (xy 369.484056 -361.389252) (xy 369.449811 -361.344904)
			(xy 369.422388 -361.296042) (xy 369.402372 -361.243708) (xy 369.390189 -361.189018) (xy 369.3861 -361.133136)
			(xy 353.248214 -361.133136) (xy 354.098352 -361.983274) (xy 354.10902 -361.987084) (xy 354.135593 -361.997018)
			(xy 354.185697 -362.02362) (xy 354.23131 -362.057348) (xy 354.271425 -362.097459) (xy 354.305159 -362.143068)
			(xy 354.331765 -362.19317) (xy 354.341684 -362.219748) (xy 354.345494 -362.230416) (xy 354.454968 -362.33989)
			(xy 358.98328 -362.33989)
		)
		(stroke
			(width 0)
			(type solid)
		)
		(fill yes)
		(layer "In9.Cu")
		(net "P12V_S3_AUX_CPU0_NVDIMM")
	)
	(gr_poly
		(pts
			(xy 146.160236 -361.335828) (xy 146.182855 -361.322453) (xy 146.230985 -361.301361) (xy 146.281554 -361.287074)
			(xy 146.333606 -361.279863) (xy 146.386154 -361.279863) (xy 146.438206 -361.287074) (xy 146.488775 -361.301361)
			(xy 146.536905 -361.322453) (xy 146.559524 -361.335828) (xy 175.211994 -361.335828) (xy 175.225501 -361.312178)
			(xy 175.258191 -361.268616) (xy 175.29674 -361.230144) (xy 175.340366 -361.197541) (xy 175.388183 -361.17147)
			(xy 175.439221 -361.15246) (xy 175.492442 -361.140898) (xy 175.546766 -361.137017) (xy 175.60109 -361.140898)
			(xy 175.654311 -361.15246) (xy 175.705349 -361.17147) (xy 175.753166 -361.197541) (xy 175.796792 -361.230144)
			(xy 175.835341 -361.268616) (xy 175.868031 -361.312178) (xy 175.881538 -361.335828) (xy 175.973994 -361.335828)
			(xy 175.988499 -361.310502) (xy 176.024 -361.264181) (xy 176.066136 -361.223802) (xy 176.113926 -361.190304)
			(xy 176.166256 -361.164467) (xy 176.221908 -361.146894) (xy 176.279586 -361.137994) (xy 176.308766 -361.137454)
			(xy 176.335082 -361.13789) (xy 176.387215 -361.145123) (xy 176.437855 -361.159469) (xy 176.486035 -361.180656)
			(xy 176.508664 -361.194096) (xy 176.520532 -361.20085) (xy 176.546755 -361.208435) (xy 176.574049 -361.208811)
			(xy 176.600471 -361.201953) (xy 176.624136 -361.188348) (xy 176.643359 -361.168967) (xy 176.650396 -361.157266)
			(xy 176.664994 -361.132331) (xy 176.700537 -361.086779) (xy 176.742544 -361.047108) (xy 176.790052 -361.014225)
			(xy 176.841977 -360.988883) (xy 176.897128 -360.971661) (xy 176.954247 -360.962953) (xy 176.983136 -360.962448)
			(xy 177.012051 -360.962985) (xy 177.069218 -360.971717) (xy 177.124412 -360.988977) (xy 177.17637 -361.014368)
			(xy 177.223901 -361.047309) (xy 177.265917 -361.087046) (xy 177.284126 -361.109514) (xy 177.294023 -361.121319)
			(xy 177.319347 -361.138838) (xy 177.34874 -361.148014) (xy 177.379532 -361.148014) (xy 177.408925 -361.138838)
			(xy 177.434249 -361.121319) (xy 177.444146 -361.109514) (xy 177.462336 -361.087028) (xy 177.504352 -361.047287)
			(xy 177.551886 -361.014344) (xy 177.603848 -360.988954) (xy 177.659047 -360.971699) (xy 177.716219 -360.962974)
			(xy 177.745136 -360.962448) (xy 177.772501 -360.962921) (xy 177.826667 -360.970746) (xy 177.879161 -360.98623)
			(xy 177.928903 -361.009055) (xy 177.974874 -361.038753) (xy 178.01613 -361.074714) (xy 178.051824 -361.116202)
			(xy 178.081225 -361.162363) (xy 178.103728 -361.212252) (xy 178.118873 -361.264844) (xy 178.123088 -361.291886)
			(xy 178.129184 -361.335828) (xy 191.528446 -361.335828) (xy 191.539622 -361.300268) (xy 191.54802 -361.275335)
			(xy 191.571153 -361.228084) (xy 191.601032 -361.184783) (xy 191.636998 -361.146388) (xy 191.678256 -361.113747)
			(xy 191.723897 -361.08758) (xy 191.772911 -361.068465) (xy 191.824216 -361.056825) (xy 191.87668 -361.052916)
			(xy 191.929144 -361.056825) (xy 191.980449 -361.068465) (xy 192.029463 -361.08758) (xy 192.075104 -361.113747)
			(xy 192.116362 -361.146388) (xy 192.152328 -361.184783) (xy 192.182207 -361.228084) (xy 192.20534 -361.275335)
			(xy 192.213738 -361.300268) (xy 192.224914 -361.335828) (xy 208.322926 -361.335828) (xy 208.336993 -361.335385)
			(xy 208.36406 -361.327715) (xy 208.388001 -361.31294) (xy 208.406992 -361.292185) (xy 208.419587 -361.267029)
			(xy 208.424827 -361.239388) (xy 208.424018 -361.225338) (xy 208.414574 -361.110193) (xy 208.404537 -360.87935)
			(xy 208.403952 -360.76382) (xy 208.40446 -360.66032) (xy 208.412586 -360.45348) (xy 208.428826 -360.247118)
			(xy 208.453155 -360.041553) (xy 208.485536 -359.837102) (xy 208.525919 -359.63408) (xy 208.574241 -359.432799)
			(xy 208.630429 -359.233571) (xy 208.694394 -359.036702) (xy 208.766039 -358.842496) (xy 208.845254 -358.651253)
			(xy 208.931915 -358.463267) (xy 209.02589 -358.278829) (xy 209.127034 -358.098222) (xy 209.23519 -357.921725)
			(xy 209.350192 -357.749611) (xy 209.471862 -357.582144) (xy 209.600014 -357.419583) (xy 209.734449 -357.262178)
			(xy 209.874959 -357.110173) (xy 210.021329 -356.963801) (xy 210.173333 -356.823288) (xy 210.330736 -356.688852)
			(xy 210.493296 -356.560699) (xy 210.660761 -356.439026) (xy 210.832875 -356.324022) (xy 211.00937 -356.215864)
			(xy 211.189976 -356.114719) (xy 211.374413 -356.020741) (xy 211.562398 -355.934078) (xy 211.753641 -355.854861)
			(xy 211.947845 -355.783214) (xy 212.144713 -355.719246) (xy 212.343941 -355.663056) (xy 212.545221 -355.614732)
			(xy 212.748243 -355.574347) (xy 212.952694 -355.541963) (xy 213.158259 -355.517632) (xy 213.36462 -355.501389)
			(xy 213.57146 -355.493261) (xy 213.67496 -355.492812) (xy 213.775383 -355.493279) (xy 213.976085 -355.500918)
			(xy 214.176349 -355.516197) (xy 214.375886 -355.539095) (xy 214.574406 -355.569578) (xy 214.77162 -355.607602)
			(xy 214.967243 -355.653112) (xy 215.16099 -355.706041) (xy 215.352579 -355.766313) (xy 215.541734 -355.833841)
			(xy 215.728178 -355.908526) (xy 215.911642 -355.990259) (xy 216.091859 -356.078923) (xy 216.268567 -356.174388)
			(xy 216.441509 -356.276516) (xy 216.610436 -356.385159) (xy 216.775101 -356.500158) (xy 216.935265 -356.621347)
			(xy 217.013282 -356.68458) (xy 217.048842 -356.71379) (xy 217.540078 -356.222554) (xy 217.540078 -320.063114)
			(xy 210.597496 -320.063114) (xy 210.592162 -320.064384) (xy 210.573101 -320.068318) (xy 210.534407 -320.072514)
			(xy 210.514946 -320.072766) (xy 210.495484 -320.072537) (xy 210.456787 -320.068341) (xy 210.43773 -320.064384)
			(xy 210.432396 -320.063114) (xy 203.053696 -320.063114) (xy 203.048362 -320.064384) (xy 203.029301 -320.068318)
			(xy 202.990607 -320.072514) (xy 202.971146 -320.072766) (xy 202.951684 -320.072537) (xy 202.912987 -320.068341)
			(xy 202.89393 -320.064384) (xy 202.888596 -320.063114) (xy 199.187562 -320.063114) (xy 199.173416 -320.083441)
			(xy 199.14 -320.11999) (xy 199.101468 -320.151098) (xy 199.058697 -320.176059) (xy 199.012659 -320.194305)
			(xy 198.964401 -320.205422) (xy 198.91502 -320.209155) (xy 198.865639 -320.205422) (xy 198.817381 -320.194305)
			(xy 198.771343 -320.176059) (xy 198.728572 -320.151098) (xy 198.69004 -320.11999) (xy 198.656624 -320.083441)
			(xy 198.642478 -320.063114) (xy 195.509896 -320.063114) (xy 195.504562 -320.064384) (xy 195.485501 -320.068318)
			(xy 195.446807 -320.072514) (xy 195.427346 -320.072766) (xy 195.407884 -320.072537) (xy 195.369187 -320.068341)
			(xy 195.35013 -320.064384) (xy 195.344796 -320.063114) (xy 187.966096 -320.063114) (xy 187.960762 -320.064384)
			(xy 187.941701 -320.068318) (xy 187.903007 -320.072514) (xy 187.883546 -320.072766) (xy 187.864084 -320.072537)
			(xy 187.825387 -320.068341) (xy 187.80633 -320.064384) (xy 187.800996 -320.063114) (xy 181.769512 -320.063114)
			(xy 181.441598 -320.391028) (xy 181.425342 -320.406014) (xy 181.425342 -323.261736) (xy 181.43093 -323.272658)
			(xy 181.443185 -323.297849) (xy 181.460502 -323.351124) (xy 181.469272 -323.406452) (xy 181.469278 -323.46247)
			(xy 181.460521 -323.5178) (xy 181.443215 -323.571078) (xy 181.43093 -323.596254) (xy 181.425342 -323.607176)
			(xy 181.425342 -325.690484) (xy 181.457092 -325.703184) (xy 181.483165 -325.714263) (xy 181.531985 -325.742998)
			(xy 181.57602 -325.778636) (xy 181.614302 -325.820393) (xy 181.645989 -325.867351) (xy 181.670384 -325.918479)
			(xy 181.686951 -325.972651) (xy 181.695327 -326.028678) (xy 181.695327 -326.085327) (xy 181.68695 -326.141353)
			(xy 181.670382 -326.195525) (xy 181.645986 -326.246652) (xy 181.614299 -326.29361) (xy 181.576017 -326.335367)
			(xy 181.531982 -326.371004) (xy 181.483161 -326.399739) (xy 181.457092 -326.410828) (xy 181.425342 -326.423528)
			(xy 181.425342 -327.393554) (xy 182.126636 -328.094848) (xy 185.60034 -328.094848) (xy 185.625299 -328.095423)
			(xy 185.674255 -328.10517) (xy 185.720369 -328.124282) (xy 185.761867 -328.152024) (xy 185.779918 -328.16927)
			(xy 186.513978 -328.90333) (xy 186.531242 -328.921369) (xy 186.559009 -328.96286) (xy 186.57813 -329.008979)
			(xy 186.587867 -329.057945) (xy 186.5884 -329.082908) (xy 186.5884 -340.853268) (xy 186.587782 -340.878222)
			(xy 186.578033 -340.927169) (xy 186.558924 -340.973274) (xy 186.531188 -341.014765) (xy 186.513978 -341.032846)
			(xy 185.345578 -342.201246) (xy 185.32938 -342.216787) (xy 185.292573 -342.242475) (xy 185.251823 -342.261291)
			(xy 185.2084 -342.272651) (xy 185.186066 -342.274906) (xy 185.165256 -342.292053) (xy 185.119715 -342.320924)
			(xy 185.070558 -342.343084) (xy 185.018767 -342.358089) (xy 184.965377 -342.36564) (xy 184.938416 -342.366092)
			(xy 184.913287 -342.365692) (xy 184.863465 -342.359093) (xy 184.81494 -342.346008) (xy 184.768555 -342.326663)
			(xy 184.725113 -342.301393) (xy 184.70499 -342.286336) (xy 184.691274 -342.275668) (xy 184.550558 -342.275668)
			(xy 184.536842 -342.286336) (xy 184.51672 -342.301392) (xy 184.473274 -342.326653) (xy 184.426888 -342.345993)
			(xy 184.378365 -342.359075) (xy 184.328544 -342.365674) (xy 184.303416 -342.366092) (xy 184.276586 -342.365637)
			(xy 184.223455 -342.358122) (xy 184.1719 -342.343238) (xy 184.12294 -342.321277) (xy 184.077539 -342.292674)
			(xy 184.056782 -342.275668) (xy 183.90235 -342.275668) (xy 183.881585 -342.292664) (xy 183.836188 -342.321274)
			(xy 183.78723 -342.343241) (xy 183.735677 -342.35813) (xy 183.682546 -342.365649) (xy 183.628886 -342.365649)
			(xy 183.575755 -342.35813) (xy 183.524202 -342.343241) (xy 183.475244 -342.321274) (xy 183.429847 -342.292664)
			(xy 183.409082 -342.275668) (xy 180.113432 -342.275668) (xy 180.092667 -342.292664) (xy 180.04727 -342.321274)
			(xy 179.998312 -342.343241) (xy 179.946759 -342.35813) (xy 179.893628 -342.365649) (xy 179.839968 -342.365649)
			(xy 179.786837 -342.35813) (xy 179.735284 -342.343241) (xy 179.686326 -342.321274) (xy 179.640929 -342.292664)
			(xy 179.620164 -342.275668) (xy 179.465732 -342.275668) (xy 179.444967 -342.292663) (xy 179.39957 -342.321269)
			(xy 179.350611 -342.343229) (xy 179.299058 -342.35811) (xy 179.245927 -342.365617) (xy 179.219098 -342.366092)
			(xy 179.19397 -342.365691) (xy 179.144148 -342.35909) (xy 179.095625 -342.346003) (xy 179.049241 -342.326656)
			(xy 179.0058 -342.301384) (xy 178.985672 -342.286336) (xy 178.971956 -342.275668) (xy 178.83124 -342.275668)
			(xy 178.817524 -342.286336) (xy 178.797402 -342.301391) (xy 178.753956 -342.32665) (xy 178.707569 -342.345987)
			(xy 178.659046 -342.359068) (xy 178.609226 -342.365665) (xy 178.584098 -342.366092) (xy 178.557268 -342.365636)
			(xy 178.504138 -342.358119) (xy 178.452585 -342.343232) (xy 178.403627 -342.32127) (xy 178.358227 -342.292666)
			(xy 178.337464 -342.275668) (xy 175.406304 -342.275668) (xy 175.38554 -342.292667) (xy 175.340145 -342.321282)
			(xy 175.291187 -342.343251) (xy 175.239633 -342.358141) (xy 175.186501 -342.365658) (xy 175.15967 -342.366092)
			(xy 175.134542 -342.365689) (xy 175.084722 -342.359085) (xy 175.036201 -342.345995) (xy 174.98982 -342.326645)
			(xy 174.946382 -342.301372) (xy 174.926244 -342.286336) (xy 174.912528 -342.275668) (xy 174.771812 -342.275668)
			(xy 174.758096 -342.286336) (xy 174.737975 -342.301395) (xy 174.69453 -342.326662) (xy 174.648145 -342.346008)
			(xy 174.599621 -342.359097) (xy 174.549799 -342.365704) (xy 174.52467 -342.366092) (xy 174.497841 -342.365634)
			(xy 174.444713 -342.358113) (xy 174.393162 -342.343224) (xy 174.344206 -342.321259) (xy 174.298809 -342.292653)
			(xy 174.278036 -342.275668) (xy 174.123604 -342.275668) (xy 174.102839 -342.292664) (xy 174.057442 -342.321274)
			(xy 174.008484 -342.343241) (xy 173.956931 -342.35813) (xy 173.9038 -342.365649) (xy 173.85014 -342.365649)
			(xy 173.797009 -342.35813) (xy 173.745456 -342.343241) (xy 173.696498 -342.321274) (xy 173.651101 -342.292664)
			(xy 173.630336 -342.275668) (xy 170.436032 -342.275668) (xy 170.415267 -342.292664) (xy 170.36987 -342.321274)
			(xy 170.320912 -342.343241) (xy 170.269359 -342.35813) (xy 170.216228 -342.365649) (xy 170.162568 -342.365649)
			(xy 170.109437 -342.35813) (xy 170.057884 -342.343241) (xy 170.008926 -342.321274) (xy 169.963529 -342.292664)
			(xy 169.942764 -342.275668) (xy 169.788332 -342.275668) (xy 169.767567 -342.292663) (xy 169.72217 -342.321269)
			(xy 169.673211 -342.343229) (xy 169.621658 -342.35811) (xy 169.568527 -342.365617) (xy 169.541698 -342.366092)
			(xy 169.51657 -342.365691) (xy 169.466748 -342.35909) (xy 169.418225 -342.346003) (xy 169.371841 -342.326656)
			(xy 169.3284 -342.301384) (xy 169.308272 -342.286336) (xy 169.294556 -342.275668) (xy 169.15384 -342.275668)
			(xy 169.140124 -342.286336) (xy 169.120002 -342.301391) (xy 169.076556 -342.32665) (xy 169.030169 -342.345987)
			(xy 168.981646 -342.359068) (xy 168.931826 -342.365665) (xy 168.906698 -342.366092) (xy 168.879868 -342.365636)
			(xy 168.826738 -342.358119) (xy 168.775185 -342.343232) (xy 168.726227 -342.32127) (xy 168.680827 -342.292666)
			(xy 168.660064 -342.275668) (xy 149.83714 -342.275668) (xy 149.812182 -342.275091) (xy 149.763227 -342.265341)
			(xy 149.717116 -342.246228) (xy 149.675619 -342.218485) (xy 149.657562 -342.201246) (xy 148.44522 -340.988904)
			(xy 148.427961 -340.970863) (xy 148.400205 -340.92937) (xy 148.381096 -340.883251) (xy 148.371372 -340.834287)
			(xy 148.370798 -340.809326) (xy 148.370798 -332.386686) (xy 147.902422 -331.91831) (xy 134.257542 -331.91831)
			(xy 134.232588 -331.917693) (xy 134.183639 -331.907946) (xy 134.137533 -331.888838) (xy 134.096039 -331.861104)
			(xy 134.077964 -331.843888) (xy 133.646164 -331.412088) (xy 133.628902 -331.394048) (xy 133.601138 -331.352555)
			(xy 133.582019 -331.306437) (xy 133.57228 -331.257472) (xy 133.571742 -331.23251) (xy 133.571742 -329.000866)
			(xy 131.332986 -326.76211) (xy 127.247142 -326.76211) (xy 127.222188 -326.761493) (xy 127.173239 -326.751746)
			(xy 127.127133 -326.732638) (xy 127.085639 -326.704904) (xy 127.067564 -326.687688) (xy 125.543564 -325.163688)
			(xy 125.526302 -325.145648) (xy 125.498538 -325.104155) (xy 125.479419 -325.058037) (xy 125.46968 -325.009072)
			(xy 125.469142 -324.98411) (xy 125.469142 -323.743066) (xy 124.957586 -323.23151) (xy 93.367098 -323.23151)
			(xy 93.033342 -323.565266) (xy 93.033342 -325.13651) (xy 93.03277 -325.16147) (xy 93.023027 -325.210429)
			(xy 93.003919 -325.256546) (xy 92.976179 -325.298048) (xy 92.95892 -325.316088) (xy 91.63812 -326.636888)
			(xy 91.620079 -326.654148) (xy 91.578586 -326.681905) (xy 91.532468 -326.701016) (xy 91.483503 -326.710744)
			(xy 91.458542 -326.71131) (xy 85.874098 -326.71131) (xy 85.108542 -327.476866) (xy 85.108542 -329.290426)
			(xy 85.107968 -329.315385) (xy 85.098223 -329.364343) (xy 85.079112 -329.410458) (xy 85.051371 -329.451957)
			(xy 85.03412 -329.470004) (xy 83.772756 -330.731368) (xy 83.754714 -330.748626) (xy 83.71322 -330.776381)
			(xy 83.667102 -330.795492) (xy 83.618139 -330.805223) (xy 83.593178 -330.80579) (xy 80.078834 -330.80579)
			(xy 76.240894 -334.64373) (xy 76.222851 -334.660985) (xy 76.181356 -334.688734) (xy 76.135238 -334.707837)
			(xy 76.086276 -334.717558) (xy 76.061316 -334.718152) (xy 68.036186 -334.718152) (xy 59.101736 -343.652602)
			(xy 59.083695 -343.669862) (xy 59.042202 -343.697621) (xy 58.996084 -343.716733) (xy 58.947119 -343.726464)
			(xy 58.922158 -343.727024) (xy 38.225476 -343.727024) (xy 38.20052 -343.72641) (xy 38.151568 -343.716669)
			(xy 38.105456 -343.697567) (xy 38.063957 -343.669836) (xy 38.045898 -343.652602) (xy 36.120832 -341.727536)
			(xy 36.103575 -341.709494) (xy 36.075824 -341.667999) (xy 36.056716 -341.621881) (xy 36.046989 -341.572918)
			(xy 36.04641 -341.547958) (xy 36.04641 -323.43725) (xy 31.383986 -318.774826) (xy 29.346398 -318.774826)
			(xy 29.333444 -318.806068) (xy 29.322944 -318.830086) (xy 29.295929 -318.875005) (xy 29.262624 -318.915482)
			(xy 29.223748 -318.950642) (xy 29.18014 -318.979726) (xy 29.132741 -319.002107) (xy 29.082574 -319.017301)
			(xy 29.030723 -319.024981) (xy 28.978305 -319.024981) (xy 28.926454 -319.017301) (xy 28.876287 -319.002107)
			(xy 28.828888 -318.979726) (xy 28.78528 -318.950642) (xy 28.746404 -318.915482) (xy 28.713099 -318.875005)
			(xy 28.686084 -318.830086) (xy 28.675584 -318.806068) (xy 28.66263 -318.774826) (xy 21.72081 -318.774826)
			(xy 21.705574 -318.797659) (xy 21.669216 -318.838781) (xy 21.626982 -318.873842) (xy 21.579871 -318.90201)
			(xy 21.528997 -318.922621) (xy 21.475564 -318.935185) (xy 21.420836 -318.939407) (xy 21.366108 -318.935185)
			(xy 21.312675 -318.922621) (xy 21.261801 -318.90201) (xy 21.21469 -318.873842) (xy 21.172456 -318.838781)
			(xy 21.136098 -318.797659) (xy 21.120862 -318.774826) (xy 13.617448 -318.774826) (xy 13.595111 -318.789524)
			(xy 13.546964 -318.812776) (xy 13.495882 -318.828573) (xy 13.443014 -318.836562) (xy 13.389546 -318.836562)
			(xy 13.336678 -318.828573) (xy 13.285596 -318.812776) (xy 13.237449 -318.789524) (xy 13.215112 -318.774826)
			(xy 7.493254 -318.774826) (xy 7.480104 -318.775244) (xy 7.45468 -318.781972) (xy 7.431818 -318.794971)
			(xy 7.413034 -318.813379) (xy 7.399574 -318.835973) (xy 7.392332 -318.861255) (xy 7.391654 -318.874394)
			(xy 7.390548 -318.901984) (xy 7.380867 -318.956344) (xy 7.36291 -319.008558) (xy 7.337108 -319.057374)
			(xy 7.304079 -319.101621) (xy 7.264616 -319.14024) (xy 7.219664 -319.172303) (xy 7.170301 -319.197042)
			(xy 7.117711 -319.213864) (xy 7.063154 -319.222366) (xy 7.035546 -319.222882) (xy 7.009082 -319.222421)
			(xy 6.956731 -319.214622) (xy 6.906117 -319.199145) (xy 6.858358 -319.176333) (xy 6.836156 -319.161922)
			(xy 6.801612 -319.1383) (xy 6.615938 -319.323974) (xy 6.615938 -327.65365) (xy 6.61543 -327.668128)
			(xy 6.61543 -334.888586) (xy 8.902954 -337.17611) (xy 22.328378 -337.17611) (xy 22.353331 -337.176729)
			(xy 22.402277 -337.18648) (xy 22.44838 -337.205591) (xy 22.489869 -337.233329) (xy 22.507956 -337.250532)
			(xy 25.248616 -339.991192) (xy 25.265873 -340.009234) (xy 25.293626 -340.050728) (xy 25.312732 -340.096846)
			(xy 25.322456 -340.14581) (xy 25.323038 -340.17077) (xy 25.323038 -347.58757) (xy 76.01204 -347.58757)
			(xy 76.01204 -341.25154) (xy 76.012609 -341.226579) (xy 76.022338 -341.177616) (xy 76.041449 -341.131498)
			(xy 76.069203 -341.090003) (xy 76.086462 -341.071962) (xy 77.03439 -340.124034) (xy 77.052458 -340.106809)
			(xy 77.093953 -340.079076) (xy 77.140062 -340.05997) (xy 77.189013 -340.050227) (xy 77.213968 -340.049612)
			(xy 83.018376 -340.049612) (xy 83.227672 -339.840316) (xy 83.209384 -339.807042) (xy 83.194759 -339.778848)
			(xy 83.174048 -339.718808) (xy 83.163538 -339.656172) (xy 83.162902 -339.624416) (xy 83.163339 -339.598276)
			(xy 83.170491 -339.546489) (xy 83.184649 -339.496163) (xy 83.205549 -339.448243) (xy 83.232797 -339.403627)
			(xy 83.249008 -339.383116) (xy 83.249008 -339.205316) (xy 83.231063 -339.182471) (xy 83.201546 -339.132441)
			(xy 83.179959 -339.078512) (xy 83.166803 -339.021933) (xy 83.162383 -338.964012) (xy 83.1668 -338.906092)
			(xy 83.179952 -338.849512) (xy 83.201535 -338.795581) (xy 83.231049 -338.745549) (xy 83.249008 -338.722716)
			(xy 83.249008 -338.544916) (xy 83.231063 -338.522071) (xy 83.201546 -338.472041) (xy 83.179959 -338.418112)
			(xy 83.166803 -338.361533) (xy 83.162383 -338.303612) (xy 83.1668 -338.245692) (xy 83.179952 -338.189112)
			(xy 83.201535 -338.135181) (xy 83.231049 -338.085149) (xy 83.249008 -338.062316) (xy 83.249008 -337.884516)
			(xy 83.231063 -337.861671) (xy 83.201546 -337.811641) (xy 83.179959 -337.757712) (xy 83.166803 -337.701133)
			(xy 83.162383 -337.643212) (xy 83.1668 -337.585292) (xy 83.179952 -337.528712) (xy 83.201535 -337.474781)
			(xy 83.231049 -337.424749) (xy 83.249008 -337.401916) (xy 83.249008 -337.224116) (xy 83.232809 -337.203596)
			(xy 83.205549 -337.158986) (xy 83.184643 -337.111069) (xy 83.170482 -337.060744) (xy 83.163334 -337.008956)
			(xy 83.162902 -336.982816) (xy 83.163435 -336.954077) (xy 83.172055 -336.89725) (xy 83.189103 -336.84236)
			(xy 83.214193 -336.790648) (xy 83.246756 -336.743285) (xy 83.266026 -336.721958) (xy 83.276197 -336.697407)
			(xy 83.305145 -336.652851) (xy 83.32343 -336.633566) (xy 85.571584 -334.385412) (xy 85.589651 -334.368187)
			(xy 85.631147 -334.340454) (xy 85.677257 -334.321349) (xy 85.726207 -334.311605) (xy 85.751162 -334.31099)
			(xy 91.011502 -334.31099) (xy 91.209368 -334.113124) (xy 91.209368 -332.966314) (xy 91.209913 -332.941352)
			(xy 91.219648 -332.892387) (xy 91.238766 -332.846268) (xy 91.266528 -332.804776) (xy 91.28379 -332.786736)
			(xy 91.370658 -332.699868) (xy 91.356434 -332.668118) (xy 91.345999 -332.64359) (xy 91.331289 -332.592358)
			(xy 91.32386 -332.539575) (xy 91.323414 -332.512924) (xy 91.323878 -332.485671) (xy 91.331632 -332.431719)
			(xy 91.346986 -332.379419) (xy 91.369627 -332.329838) (xy 91.399095 -332.283984) (xy 91.434789 -332.24279)
			(xy 91.475982 -332.207096) (xy 91.521836 -332.177628) (xy 91.571418 -332.154987) (xy 91.623717 -332.139632)
			(xy 91.677669 -332.131878) (xy 91.704922 -332.131416) (xy 91.731574 -332.131859) (xy 91.784357 -332.139286)
			(xy 91.835592 -332.153992) (xy 91.860116 -332.164436) (xy 91.891866 -332.17866) (xy 92.031058 -332.039468)
			(xy 92.016834 -332.007718) (xy 92.006399 -331.98319) (xy 91.991689 -331.931958) (xy 91.98426 -331.879175)
			(xy 91.983814 -331.852524) (xy 91.984278 -331.825271) (xy 91.992032 -331.771319) (xy 92.007386 -331.719019)
			(xy 92.030027 -331.669438) (xy 92.059495 -331.623584) (xy 92.095189 -331.58239) (xy 92.136382 -331.546696)
			(xy 92.182236 -331.517228) (xy 92.231818 -331.494587) (xy 92.284117 -331.479232) (xy 92.338069 -331.471478)
			(xy 92.365322 -331.471016) (xy 92.391974 -331.471459) (xy 92.444757 -331.478886) (xy 92.495992 -331.493592)
			(xy 92.520516 -331.504036) (xy 92.552266 -331.51826) (xy 93.078046 -330.99248) (xy 93.08084 -330.976732)
			(xy 93.085958 -330.950582) (xy 93.102415 -330.899904) (xy 93.125766 -330.85201) (xy 93.155556 -330.807832)
			(xy 93.191206 -330.768231) (xy 93.23202 -330.733978) (xy 93.277205 -330.705739) (xy 93.325881 -330.684065)
			(xy 93.3771 -330.669377) (xy 93.429864 -330.661961) (xy 93.456506 -330.661518) (xy 93.484601 -330.662034)
			(xy 93.540183 -330.670269) (xy 93.593954 -330.686575) (xy 93.644748 -330.710599) (xy 93.691465 -330.741819)
			(xy 93.733093 -330.77956) (xy 93.768729 -330.823003) (xy 93.7976 -330.871207) (xy 93.808804 -330.896976)
			(xy 93.822012 -330.928218) (xy 99.5172 -330.928218) (xy 99.528821 -330.903354) (xy 99.558162 -330.856972)
			(xy 99.593848 -330.815275) (xy 99.635142 -330.779124) (xy 99.681192 -330.749265) (xy 99.731046 -330.726315)
			(xy 99.783675 -330.710749) (xy 99.837992 -330.702887) (xy 99.865434 -330.702412) (xy 99.894174 -330.702912)
			(xy 99.951002 -330.71154) (xy 100.005894 -330.728595) (xy 100.057605 -330.753692) (xy 100.104966 -330.786263)
			(xy 100.126292 -330.805536) (xy 100.137826 -330.815608) (xy 100.165372 -330.82895) (xy 100.195634 -330.833535)
			(xy 100.225896 -330.82895) (xy 100.253442 -330.815608) (xy 100.264976 -330.805536) (xy 100.286289 -330.786249)
			(xy 100.333655 -330.753685) (xy 100.38537 -330.728596) (xy 100.440264 -330.711549) (xy 100.497094 -330.70293)
			(xy 100.525834 -330.702412) (xy 100.553274 -330.702873) (xy 100.607585 -330.710753) (xy 100.660208 -330.726333)
			(xy 100.710056 -330.749289) (xy 100.756101 -330.77915) (xy 100.797394 -330.815299) (xy 100.833083 -330.856989)
			(xy 100.862432 -330.903363) (xy 100.874068 -330.928218) (xy 101.251512 -330.928218) (xy 101.26472 -330.896976)
			(xy 101.275926 -330.871207) (xy 101.3048 -330.823003) (xy 101.340436 -330.779559) (xy 101.382063 -330.741816)
			(xy 101.428779 -330.71059) (xy 101.479571 -330.68656) (xy 101.533341 -330.670244) (xy 101.588923 -330.661997)
			(xy 101.645113 -330.661997) (xy 101.700695 -330.670244) (xy 101.754465 -330.68656) (xy 101.805257 -330.71059)
			(xy 101.851973 -330.741816) (xy 101.8936 -330.779559) (xy 101.929236 -330.823003) (xy 101.95811 -330.871207)
			(xy 101.969316 -330.896976) (xy 101.982524 -330.928218) (xy 107.677712 -330.928218) (xy 107.689324 -330.90335)
			(xy 107.718665 -330.856967) (xy 107.754353 -330.81527) (xy 107.795649 -330.779119) (xy 107.8417 -330.749261)
			(xy 107.891556 -330.726312) (xy 107.944186 -330.710747) (xy 107.998504 -330.702886) (xy 108.025946 -330.702412)
			(xy 108.054686 -330.702905) (xy 108.111515 -330.711534) (xy 108.166406 -330.728591) (xy 108.218117 -330.75369)
			(xy 108.265478 -330.786262) (xy 108.286804 -330.805536) (xy 108.298338 -330.815608) (xy 108.325884 -330.82895)
			(xy 108.356146 -330.833535) (xy 108.386408 -330.82895) (xy 108.413954 -330.815608) (xy 108.425488 -330.805536)
			(xy 108.446796 -330.786243) (xy 108.494163 -330.75368) (xy 108.54588 -330.728592) (xy 108.600775 -330.711546)
			(xy 108.657606 -330.70293) (xy 108.686346 -330.702412) (xy 108.713786 -330.702863) (xy 108.768098 -330.710745)
			(xy 108.820721 -330.726326) (xy 108.870569 -330.749284) (xy 108.916614 -330.779146) (xy 108.957907 -330.815296)
			(xy 108.993596 -330.856988) (xy 109.022944 -330.903362) (xy 109.03458 -330.928218) (xy 109.412024 -330.928218)
			(xy 109.425232 -330.896976) (xy 109.436438 -330.871207) (xy 109.465312 -330.823003) (xy 109.500948 -330.779559)
			(xy 109.542575 -330.741816) (xy 109.589291 -330.71059) (xy 109.640083 -330.68656) (xy 109.693853 -330.670244)
			(xy 109.749435 -330.661997) (xy 109.805625 -330.661997) (xy 109.861207 -330.670244) (xy 109.914977 -330.68656)
			(xy 109.965769 -330.71059) (xy 110.012485 -330.741816) (xy 110.054112 -330.779559) (xy 110.089748 -330.823003)
			(xy 110.118622 -330.871207) (xy 110.129828 -330.896976) (xy 110.143036 -330.928218) (xy 116.158772 -330.928218)
			(xy 116.179943 -330.909717) (xy 116.226699 -330.878494) (xy 116.277528 -330.854465) (xy 116.331332 -330.838152)
			(xy 116.386947 -330.829906) (xy 116.443169 -330.829906) (xy 116.498784 -330.838152) (xy 116.552588 -330.854465)
			(xy 116.603417 -330.878494) (xy 116.650173 -330.909717) (xy 116.671344 -330.928218) (xy 116.819172 -330.928218)
			(xy 116.840343 -330.909717) (xy 116.887099 -330.878494) (xy 116.937928 -330.854465) (xy 116.991732 -330.838152)
			(xy 117.047347 -330.829906) (xy 117.103569 -330.829906) (xy 117.159184 -330.838152) (xy 117.212988 -330.854465)
			(xy 117.263817 -330.878494) (xy 117.310573 -330.909717) (xy 117.331744 -330.928218) (xy 123.998736 -330.928218)
			(xy 124.010329 -330.90334) (xy 124.039673 -330.856957) (xy 124.075363 -330.81526) (xy 124.116661 -330.77911)
			(xy 124.162715 -330.749252) (xy 124.212574 -330.726305) (xy 124.265207 -330.710742) (xy 124.319527 -330.702884)
			(xy 124.34697 -330.702412) (xy 124.375708 -330.702951) (xy 124.432535 -330.711569) (xy 124.487426 -330.728616)
			(xy 124.539138 -330.753704) (xy 124.586501 -330.786266) (xy 124.607828 -330.805536) (xy 124.619362 -330.815608)
			(xy 124.646908 -330.82895) (xy 124.67717 -330.833535) (xy 124.707432 -330.82895) (xy 124.734978 -330.815608)
			(xy 124.746512 -330.805536) (xy 124.767851 -330.786279) (xy 124.81521 -330.753711) (xy 124.866918 -330.728616)
			(xy 124.921807 -330.711562) (xy 124.978632 -330.702935) (xy 125.00737 -330.702412) (xy 125.034811 -330.702843)
			(xy 125.089124 -330.710728) (xy 125.141747 -330.726312) (xy 125.191595 -330.749274) (xy 125.23764 -330.779138)
			(xy 125.278933 -330.815291) (xy 125.314621 -330.856985) (xy 125.343968 -330.903361) (xy 125.355604 -330.928218)
			(xy 126.794768 -330.928218) (xy 126.819729 -330.928789) (xy 126.868692 -330.938518) (xy 126.91481 -330.957628)
			(xy 126.956304 -330.985382) (xy 126.974346 -331.00264) (xy 127.440436 -331.46873) (xy 127.457658 -331.486802)
			(xy 127.485404 -331.528293) (xy 127.504522 -331.5744) (xy 127.514278 -331.623351) (xy 127.514858 -331.648308)
			(xy 127.514858 -333.86649) (xy 127.944626 -334.296258) (xy 134.34568 -334.296258) (xy 134.370642 -334.29681)
			(xy 134.419606 -334.306543) (xy 134.465725 -334.325659) (xy 134.507218 -334.353419) (xy 134.525258 -334.37068)
			(xy 135.891016 -335.736438) (xy 135.908224 -335.75452) (xy 135.935959 -335.796012) (xy 135.955068 -335.842116)
			(xy 135.964819 -335.891062) (xy 135.965438 -335.916016) (xy 135.965438 -340.650322) (xy 135.988681 -340.663411)
			(xy 136.031446 -340.695299) (xy 136.069226 -340.732959) (xy 136.101249 -340.775622) (xy 136.126861 -340.822416)
			(xy 136.145538 -340.872384) (xy 136.156899 -340.924505) (xy 136.16071 -340.977713) (xy 136.156895 -341.030921)
			(xy 136.145531 -341.083041) (xy 136.12685 -341.133008) (xy 136.101235 -341.1798) (xy 136.069208 -341.222461)
			(xy 136.031426 -341.260119) (xy 135.988659 -341.292003) (xy 135.965438 -341.305134) (xy 135.965438 -341.4395)
			(xy 135.990297 -341.453614) (xy 136.035784 -341.48823) (xy 136.075449 -341.52939) (xy 136.108359 -341.576126)
			(xy 136.133743 -341.627342) (xy 136.151004 -341.681835) (xy 136.159736 -341.738325) (xy 136.160256 -341.766906)
			(xy 136.159837 -341.791752) (xy 136.153232 -341.841002) (xy 136.140141 -341.888937) (xy 136.120795 -341.934708)
			(xy 136.095537 -341.977501) (xy 136.0805 -341.997284) (xy 136.50595 -342.422734) (xy 136.809734 -342.422734)
			(xy 136.823704 -342.394032) (xy 136.83542 -342.370687) (xy 136.864487 -342.327287) (xy 136.899329 -342.288372)
			(xy 136.939265 -342.254704) (xy 136.983511 -342.226943) (xy 137.0312 -342.205633) (xy 137.081398 -342.191192)
			(xy 137.133121 -342.183903) (xy 137.159238 -342.183466) (xy 137.187944 -342.183966) (xy 137.244674 -342.192783)
			(xy 137.299379 -342.210204) (xy 137.350762 -342.235814) (xy 137.397605 -342.269008) (xy 137.418572 -342.288622)
			(xy 137.430247 -342.299161) (xy 137.458376 -342.313195) (xy 137.489438 -342.318024) (xy 137.5205 -342.313195)
			(xy 137.548629 -342.299161) (xy 137.560304 -342.288622) (xy 137.58126 -342.268998) (xy 137.628108 -342.235812)
			(xy 137.679494 -342.210211) (xy 137.734201 -342.192801) (xy 137.790933 -342.183994) (xy 137.819638 -342.183466)
			(xy 137.845754 -342.183883) (xy 137.897474 -342.191182) (xy 137.947667 -342.205631) (xy 137.995352 -342.226948)
			(xy 138.039592 -342.254715) (xy 138.079522 -342.288387) (xy 138.114358 -342.327305) (xy 138.143419 -342.370706)
			(xy 138.155172 -342.394032) (xy 138.169142 -342.422734) (xy 139.615418 -342.422734) (xy 139.629388 -342.394286)
			(xy 139.642007 -342.369532) (xy 139.673471 -342.32374) (xy 139.711387 -342.283127) (xy 139.754912 -342.248595)
			(xy 139.803083 -342.220909) (xy 139.85483 -342.200682) (xy 139.909008 -342.188364) (xy 139.964414 -342.184228)
			(xy 140.01982 -342.188364) (xy 140.073998 -342.200682) (xy 140.125745 -342.220909) (xy 140.173916 -342.248595)
			(xy 140.217441 -342.283127) (xy 140.255357 -342.32374) (xy 140.286821 -342.369532) (xy 140.29944 -342.394286)
			(xy 140.31341 -342.422734) (xy 142.897352 -342.422734) (xy 142.922312 -342.42331) (xy 142.971276 -342.433037)
			(xy 143.017394 -342.452145) (xy 143.058888 -342.479898) (xy 143.07693 -342.497156) (xy 143.379952 -342.800178)
			(xy 143.3972 -342.818227) (xy 143.42494 -342.859727) (xy 143.444051 -342.905841) (xy 143.453799 -342.954797)
			(xy 143.454374 -342.979756) (xy 143.454374 -346.690442) (xy 143.45379 -346.715402) (xy 143.444065 -346.764365)
			(xy 143.424959 -346.810483) (xy 143.397208 -346.851978) (xy 143.379952 -346.87002) (xy 139.893294 -350.356678)
			(xy 139.875235 -350.373912) (xy 139.833736 -350.401644) (xy 139.787624 -350.420747) (xy 139.738672 -350.430487)
			(xy 139.713716 -350.4311) (xy 121.896124 -350.4311) (xy 120.263158 -352.064066) (xy 120.24507 -352.081268)
			(xy 120.203581 -352.109006) (xy 120.157479 -352.128118) (xy 120.108533 -352.137869) (xy 120.08358 -352.138488)
			(xy 115.75542 -352.138488) (xy 115.730459 -352.137923) (xy 115.681496 -352.128191) (xy 115.635378 -352.10908)
			(xy 115.593884 -352.081324) (xy 115.575842 -352.064066) (xy 113.567718 -350.055942) (xy 97.827084 -350.055942)
			(xy 96.898206 -350.98482) (xy 96.89465 -350.998028) (xy 96.886668 -351.025318) (xy 96.863856 -351.077395)
			(xy 96.833569 -351.12551) (xy 96.796476 -351.168598) (xy 96.753399 -351.205703) (xy 96.705293 -351.236004)
			(xy 96.653222 -351.258831) (xy 96.625918 -351.26676) (xy 96.61271 -351.270316) (xy 96.027748 -351.855278)
			(xy 96.009666 -351.872487) (xy 95.968175 -351.900223) (xy 95.92207 -351.919333) (xy 95.873124 -351.929082)
			(xy 95.84817 -351.9297) (xy 88.251792 -351.9297) (xy 88.226829 -351.929178) (xy 88.177862 -351.919437)
			(xy 88.131743 -351.900313) (xy 88.090252 -351.872544) (xy 88.072214 -351.855278) (xy 85.727794 -349.510858)
			(xy 77.935328 -349.510858) (xy 77.910367 -349.510297) (xy 77.861403 -349.500565) (xy 77.815285 -349.481453)
			(xy 77.773791 -349.453696) (xy 77.75575 -349.436436) (xy 76.086462 -347.767148) (xy 76.069229 -347.749086)
			(xy 76.041485 -347.707591) (xy 76.02237 -347.661481) (xy 76.012618 -347.612527) (xy 76.01204 -347.58757)
			(xy 25.323038 -347.58757) (xy 25.323038 -347.8149) (xy 31.111267 -353.603129) (xy 78.874616 -353.603129)
			(xy 78.874616 -353.446511) (xy 78.882679 -353.290099) (xy 78.898783 -353.13431) (xy 78.922885 -352.979557)
			(xy 78.954922 -352.82625) (xy 78.994808 -352.674795) (xy 79.042438 -352.525594) (xy 79.097686 -352.379043)
			(xy 79.160404 -352.23553) (xy 79.230428 -352.095436) (xy 79.30757 -351.959133) (xy 79.391627 -351.826982)
			(xy 79.482375 -351.699333) (xy 79.579575 -351.576525) (xy 79.682967 -351.458884) (xy 79.792278 -351.34672)
			(xy 79.907219 -351.240333) (xy 80.027483 -351.140004) (xy 80.152753 -351.045999) (xy 80.282696 -350.958568)
			(xy 80.416968 -350.877941) (xy 80.555213 -350.804334) (xy 80.697063 -350.737941) (xy 80.842143 -350.678938)
			(xy 80.990068 -350.627482) (xy 81.140445 -350.58371) (xy 81.292877 -350.547736) (xy 81.446958 -350.519657)
			(xy 81.602281 -350.499548) (xy 81.758433 -350.487461) (xy 81.915 -350.483428) (xy 82.071567 -350.487461)
			(xy 82.227719 -350.499548) (xy 82.383042 -350.519657) (xy 82.537123 -350.547736) (xy 82.689555 -350.58371)
			(xy 82.839932 -350.627482) (xy 82.987857 -350.678938) (xy 83.132937 -350.737941) (xy 83.274787 -350.804334)
			(xy 83.413032 -350.877941) (xy 83.547304 -350.958568) (xy 83.677247 -351.045999) (xy 83.802517 -351.140004)
			(xy 83.922781 -351.240333) (xy 84.037722 -351.34672) (xy 84.147033 -351.458884) (xy 84.250425 -351.576525)
			(xy 84.347625 -351.699333) (xy 84.438373 -351.826982) (xy 84.52243 -351.959133) (xy 84.599572 -352.095436)
			(xy 84.669596 -352.23553) (xy 84.732314 -352.379043) (xy 84.787562 -352.525594) (xy 84.835192 -352.674795)
			(xy 84.875078 -352.82625) (xy 84.907115 -352.979557) (xy 84.931217 -353.13431) (xy 84.947321 -353.290099)
			(xy 84.955384 -353.446511) (xy 84.955888 -353.52482) (xy 84.955384 -353.603129) (xy 84.947321 -353.759541)
			(xy 84.931217 -353.91533) (xy 84.907115 -354.070083) (xy 84.875078 -354.22339) (xy 84.835192 -354.374845)
			(xy 84.791021 -354.513211) (xy 133.478774 -354.513211) (xy 133.478774 -354.356593) (xy 133.486837 -354.200181)
			(xy 133.502941 -354.044392) (xy 133.527043 -353.889639) (xy 133.55908 -353.736332) (xy 133.598966 -353.584877)
			(xy 133.646596 -353.435676) (xy 133.701844 -353.289125) (xy 133.764562 -353.145612) (xy 133.834586 -353.005518)
			(xy 133.911728 -352.869215) (xy 133.995785 -352.737064) (xy 134.086533 -352.609415) (xy 134.183733 -352.486607)
			(xy 134.287125 -352.368966) (xy 134.396436 -352.256802) (xy 134.511377 -352.150415) (xy 134.631641 -352.050086)
			(xy 134.756911 -351.956081) (xy 134.886854 -351.86865) (xy 135.021126 -351.788023) (xy 135.159371 -351.714416)
			(xy 135.301221 -351.648023) (xy 135.446301 -351.58902) (xy 135.594226 -351.537564) (xy 135.744603 -351.493792)
			(xy 135.897035 -351.457818) (xy 136.051116 -351.429739) (xy 136.206439 -351.40963) (xy 136.362591 -351.397543)
			(xy 136.519158 -351.39351) (xy 136.675725 -351.397543) (xy 136.831877 -351.40963) (xy 136.9872 -351.429739)
			(xy 137.141281 -351.457818) (xy 137.293713 -351.493792) (xy 137.44409 -351.537564) (xy 137.592015 -351.58902)
			(xy 137.737095 -351.648023) (xy 137.878945 -351.714416) (xy 138.01719 -351.788023) (xy 138.151462 -351.86865)
			(xy 138.281405 -351.956081) (xy 138.406675 -352.050086) (xy 138.526939 -352.150415) (xy 138.64188 -352.256802)
			(xy 138.751191 -352.368966) (xy 138.854583 -352.486607) (xy 138.951783 -352.609415) (xy 139.042531 -352.737064)
			(xy 139.126588 -352.869215) (xy 139.20373 -353.005518) (xy 139.273754 -353.145612) (xy 139.336472 -353.289125)
			(xy 139.39172 -353.435676) (xy 139.43935 -353.584877) (xy 139.479236 -353.736332) (xy 139.511273 -353.889639)
			(xy 139.535375 -354.044392) (xy 139.551479 -354.200181) (xy 139.559542 -354.356593) (xy 139.560046 -354.434902)
			(xy 139.559542 -354.513211) (xy 139.551479 -354.669623) (xy 139.535375 -354.825412) (xy 139.511273 -354.980165)
			(xy 139.479236 -355.133472) (xy 139.43935 -355.284927) (xy 139.39172 -355.434128) (xy 139.336472 -355.580679)
			(xy 139.273754 -355.724192) (xy 139.20373 -355.864286) (xy 139.126588 -356.000589) (xy 139.042531 -356.13274)
			(xy 138.951783 -356.260389) (xy 138.854583 -356.383197) (xy 138.751191 -356.500838) (xy 138.64188 -356.613002)
			(xy 138.526939 -356.719389) (xy 138.406675 -356.819718) (xy 138.281405 -356.913723) (xy 138.151462 -357.001154)
			(xy 138.01719 -357.081781) (xy 137.878945 -357.155388) (xy 137.737095 -357.221781) (xy 137.592015 -357.280784)
			(xy 137.44409 -357.33224) (xy 137.293713 -357.376012) (xy 137.141281 -357.411986) (xy 136.9872 -357.440065)
			(xy 136.831877 -357.460174) (xy 136.675725 -357.472261) (xy 136.519158 -357.476294) (xy 136.362591 -357.472261)
			(xy 136.206439 -357.460174) (xy 136.051116 -357.440065) (xy 135.897035 -357.411986) (xy 135.744603 -357.376012)
			(xy 135.594226 -357.33224) (xy 135.446301 -357.280784) (xy 135.301221 -357.221781) (xy 135.159371 -357.155388)
			(xy 135.021126 -357.081781) (xy 134.886854 -357.001154) (xy 134.756911 -356.913723) (xy 134.631641 -356.819718)
			(xy 134.511377 -356.719389) (xy 134.396436 -356.613002) (xy 134.287125 -356.500838) (xy 134.183733 -356.383197)
			(xy 134.086533 -356.260389) (xy 133.995785 -356.13274) (xy 133.911728 -356.000589) (xy 133.834586 -355.864286)
			(xy 133.764562 -355.724192) (xy 133.701844 -355.580679) (xy 133.646596 -355.434128) (xy 133.598966 -355.284927)
			(xy 133.55908 -355.133472) (xy 133.527043 -354.980165) (xy 133.502941 -354.825412) (xy 133.486837 -354.669623)
			(xy 133.478774 -354.513211) (xy 84.791021 -354.513211) (xy 84.787562 -354.524046) (xy 84.732314 -354.670597)
			(xy 84.669596 -354.81411) (xy 84.599572 -354.954204) (xy 84.52243 -355.090507) (xy 84.438373 -355.222658)
			(xy 84.347625 -355.350307) (xy 84.250425 -355.473115) (xy 84.147033 -355.590756) (xy 84.037722 -355.70292)
			(xy 83.922781 -355.809307) (xy 83.802517 -355.909636) (xy 83.677247 -356.003641) (xy 83.547304 -356.091072)
			(xy 83.413032 -356.171699) (xy 83.274787 -356.245306) (xy 83.132937 -356.311699) (xy 82.987857 -356.370702)
			(xy 82.839932 -356.422158) (xy 82.689555 -356.46593) (xy 82.537123 -356.501904) (xy 82.383042 -356.529983)
			(xy 82.227719 -356.550092) (xy 82.071567 -356.562179) (xy 81.915 -356.566212) (xy 81.758433 -356.562179)
			(xy 81.602281 -356.550092) (xy 81.446958 -356.529983) (xy 81.292877 -356.501904) (xy 81.140445 -356.46593)
			(xy 80.990068 -356.422158) (xy 80.842143 -356.370702) (xy 80.697063 -356.311699) (xy 80.555213 -356.245306)
			(xy 80.416968 -356.171699) (xy 80.282696 -356.091072) (xy 80.152753 -356.003641) (xy 80.027483 -355.909636)
			(xy 79.907219 -355.809307) (xy 79.792278 -355.70292) (xy 79.682967 -355.590756) (xy 79.579575 -355.473115)
			(xy 79.482375 -355.350307) (xy 79.391627 -355.222658) (xy 79.30757 -355.090507) (xy 79.230428 -354.954204)
			(xy 79.160404 -354.81411) (xy 79.097686 -354.670597) (xy 79.042438 -354.524046) (xy 78.994808 -354.374845)
			(xy 78.954922 -354.22339) (xy 78.922885 -354.070083) (xy 78.898783 -353.91533) (xy 78.882679 -353.759541)
			(xy 78.874616 -353.603129) (xy 31.111267 -353.603129) (xy 37.087048 -359.57891) (xy 56.728614 -359.57891)
			(xy 56.739536 -359.573068) (xy 56.766887 -359.559549) (xy 56.824818 -359.540419) (xy 56.885054 -359.530743)
			(xy 56.915558 -359.530142) (xy 56.946065 -359.530715) (xy 57.006308 -359.540381) (xy 57.064241 -359.55952)
			(xy 57.09158 -359.573068) (xy 57.102502 -359.57891) (xy 85.812122 -359.57891) (xy 87.080598 -358.310434)
			(xy 87.080598 -355.68763) (xy 87.081216 -355.662676) (xy 87.090965 -355.613729) (xy 87.110075 -355.567625)
			(xy 87.137811 -355.526134) (xy 87.15502 -355.508052) (xy 88.04148 -354.621592) (xy 88.059521 -354.604333)
			(xy 88.101015 -354.576578) (xy 88.147133 -354.557469) (xy 88.196097 -354.547742) (xy 88.221058 -354.54717)
			(xy 101.689662 -354.54717) (xy 101.714616 -354.547787) (xy 101.763565 -354.557534) (xy 101.809672 -354.576641)
			(xy 101.851166 -354.604375) (xy 101.86924 -354.621592) (xy 104.562402 -357.314754) (xy 104.572054 -357.318564)
			(xy 104.597413 -357.32908) (xy 104.645069 -357.356335) (xy 104.688327 -357.390136) (xy 104.726297 -357.429786)
			(xy 104.758193 -357.474468) (xy 104.77119 -357.49865) (xy 112.964214 -357.49865) (xy 112.974374 -357.461312)
			(xy 112.982097 -357.434727) (xy 113.004162 -357.383954) (xy 113.033336 -357.336905) (xy 113.069007 -357.294569)
			(xy 113.110425 -357.257836) (xy 113.156719 -357.227477) (xy 113.206916 -357.204132) (xy 113.259961 -357.188291)
			(xy 113.31474 -357.180286) (xy 113.3701 -357.180286) (xy 113.424879 -357.188291) (xy 113.477924 -357.204132)
			(xy 113.528121 -357.227477) (xy 113.574415 -357.257836) (xy 113.615833 -357.294569) (xy 113.651504 -357.336905)
			(xy 113.680678 -357.383954) (xy 113.702743 -357.434727) (xy 113.710466 -357.461312) (xy 113.720626 -357.49865)
			(xy 127.523748 -357.49865) (xy 127.530352 -357.455724) (xy 127.535004 -357.429115) (xy 127.550824 -357.377468)
			(xy 127.573771 -357.328568) (xy 127.603384 -357.283394) (xy 127.639073 -357.242847) (xy 127.680124 -357.207739)
			(xy 127.725715 -357.178771) (xy 127.774937 -357.156523) (xy 127.826804 -357.141439) (xy 127.88028 -357.133821)
			(xy 127.934296 -357.133821) (xy 127.987772 -357.141439) (xy 128.039639 -357.156523) (xy 128.088861 -357.178771)
			(xy 128.134452 -357.207739) (xy 128.175503 -357.242847) (xy 128.211192 -357.283394) (xy 128.240805 -357.328568)
			(xy 128.263752 -357.377468) (xy 128.279572 -357.429115) (xy 128.284224 -357.455724) (xy 128.290828 -357.49865)
			(xy 128.981962 -357.49865) (xy 129.00692 -357.499227) (xy 129.055874 -357.508978) (xy 129.101984 -357.528093)
			(xy 129.143479 -357.555837) (xy 129.16154 -357.573072) (xy 129.33299 -357.744522) (xy 129.344928 -357.748332)
			(xy 129.369533 -357.756653) (xy 129.416408 -357.779026) (xy 129.459814 -357.807551) (xy 129.49895 -357.8417)
			(xy 129.533092 -357.880842) (xy 129.561609 -357.924254) (xy 129.583973 -357.971133) (xy 129.592324 -357.995728)
			(xy 129.596134 -358.007666) (xy 132.924296 -361.335828)
		)
		(stroke
			(width 0)
			(type solid)
		)
		(fill yes)
		(layer "In9.Cu")
		(net "P12V_S3_AUX_CPU1_NVDIMM")
	)
	(gr_poly
		(pts
			(xy 336.42046 -325.563992) (xy 336.438501 -325.546732) (xy 336.479994 -325.518973) (xy 336.526112 -325.49986)
			(xy 336.575077 -325.49013) (xy 336.600038 -325.48957) (xy 339.100922 -325.48957) (xy 341.792814 -322.797678)
			(xy 341.810854 -322.780415) (xy 341.852346 -322.75265) (xy 341.898464 -322.73353) (xy 341.947429 -322.723791)
			(xy 341.972392 -322.723256) (xy 373.002556 -322.723256) (xy 373.027514 -322.723833) (xy 373.076468 -322.733583)
			(xy 373.122579 -322.752697) (xy 373.164075 -322.780441) (xy 373.182134 -322.797678) (xy 373.842534 -323.458078)
			(xy 373.859792 -323.47612) (xy 373.887544 -323.517614) (xy 373.906652 -323.563732) (xy 373.916378 -323.612696)
			(xy 373.916956 -323.637656) (xy 373.916956 -324.8787) (xy 375.292112 -326.253856) (xy 379.035564 -326.253856)
			(xy 379.060522 -326.254434) (xy 379.109475 -326.264185) (xy 379.155585 -326.2833) (xy 379.19708 -326.311045)
			(xy 379.215142 -326.328278) (xy 383.039874 -330.15301) (xy 392.275822 -330.15301) (xy 392.609578 -329.819254)
			(xy 392.609578 -296.321226) (xy 385.612894 -289.324542) (xy 381.76962 -289.324542) (xy 381.5969 -289.651186)
			(xy 381.606806 -289.673792) (xy 381.61571 -289.694883) (xy 381.628263 -289.73891) (xy 381.634597 -289.784251)
			(xy 381.635 -289.807142) (xy 381.634492 -289.833029) (xy 381.626393 -289.884167) (xy 381.610394 -289.933407)
			(xy 381.586888 -289.979539) (xy 381.556456 -290.021426) (xy 381.519846 -290.058036) (xy 381.477959 -290.088468)
			(xy 381.431827 -290.111974) (xy 381.382587 -290.127973) (xy 381.331449 -290.136072) (xy 381.279675 -290.136072)
			(xy 381.228537 -290.127973) (xy 381.179297 -290.111974) (xy 381.133165 -290.088468) (xy 381.091278 -290.058036)
			(xy 381.054668 -290.021426) (xy 381.024236 -289.979539) (xy 381.00073 -289.933407) (xy 380.984731 -289.884167)
			(xy 380.976632 -289.833029) (xy 380.976124 -289.807142) (xy 380.976593 -289.78171) (xy 380.984403 -289.731448)
			(xy 380.999846 -289.682984) (xy 381.022553 -289.637469) (xy 381.051985 -289.595984) (xy 381.087443 -289.559516)
			(xy 381.128084 -289.52893) (xy 381.172943 -289.504953) (xy 381.220954 -289.488156) (xy 381.245872 -289.483038)
			(xy 381.270002 -289.478466) (xy 381.312166 -289.398964) (xy 381.316594 -289.389446) (xy 381.318133 -289.368533)
			(xy 381.311187 -289.348747) (xy 381.296915 -289.333384) (xy 381.277693 -289.325003) (xy 381.267208 -289.324542)
			(xy 379.89002 -289.324542) (xy 379.7173 -289.651186) (xy 379.727206 -289.673792) (xy 379.73611 -289.694883)
			(xy 379.748663 -289.73891) (xy 379.754997 -289.784251) (xy 379.7554 -289.807142) (xy 379.754892 -289.833029)
			(xy 379.746793 -289.884167) (xy 379.730794 -289.933407) (xy 379.707288 -289.979539) (xy 379.676856 -290.021426)
			(xy 379.640246 -290.058036) (xy 379.598359 -290.088468) (xy 379.552227 -290.111974) (xy 379.502987 -290.127973)
			(xy 379.451849 -290.136072) (xy 379.400075 -290.136072) (xy 379.348937 -290.127973) (xy 379.299697 -290.111974)
			(xy 379.253565 -290.088468) (xy 379.211678 -290.058036) (xy 379.175068 -290.021426) (xy 379.144636 -289.979539)
			(xy 379.12113 -289.933407) (xy 379.105131 -289.884167) (xy 379.097032 -289.833029) (xy 379.096524 -289.807142)
			(xy 379.096993 -289.78171) (xy 379.104803 -289.731448) (xy 379.120246 -289.682984) (xy 379.142953 -289.637469)
			(xy 379.172385 -289.595984) (xy 379.207843 -289.559516) (xy 379.248484 -289.52893) (xy 379.293343 -289.504953)
			(xy 379.341354 -289.488156) (xy 379.366272 -289.483038) (xy 379.390402 -289.478466) (xy 379.432566 -289.398964)
			(xy 379.436994 -289.389446) (xy 379.438533 -289.368533) (xy 379.431587 -289.348747) (xy 379.417315 -289.333384)
			(xy 379.398093 -289.325003) (xy 379.387608 -289.324542) (xy 378.01042 -289.324542) (xy 377.8377 -289.651186)
			(xy 377.847606 -289.673792) (xy 377.85651 -289.694883) (xy 377.869063 -289.73891) (xy 377.875397 -289.784251)
			(xy 377.8758 -289.807142) (xy 377.875292 -289.833029) (xy 377.867193 -289.884167) (xy 377.851194 -289.933407)
			(xy 377.827688 -289.979539) (xy 377.797256 -290.021426) (xy 377.760646 -290.058036) (xy 377.718759 -290.088468)
			(xy 377.672627 -290.111974) (xy 377.623387 -290.127973) (xy 377.572249 -290.136072) (xy 377.520475 -290.136072)
			(xy 377.469337 -290.127973) (xy 377.420097 -290.111974) (xy 377.373965 -290.088468) (xy 377.332078 -290.058036)
			(xy 377.295468 -290.021426) (xy 377.265036 -289.979539) (xy 377.24153 -289.933407) (xy 377.225531 -289.884167)
			(xy 377.217432 -289.833029) (xy 377.216924 -289.807142) (xy 377.217393 -289.78171) (xy 377.225203 -289.731448)
			(xy 377.240646 -289.682984) (xy 377.263353 -289.637469) (xy 377.292785 -289.595984) (xy 377.328243 -289.559516)
			(xy 377.368884 -289.52893) (xy 377.413743 -289.504953) (xy 377.461754 -289.488156) (xy 377.486672 -289.483038)
			(xy 377.510802 -289.478466) (xy 377.552966 -289.398964) (xy 377.557394 -289.389446) (xy 377.558933 -289.368533)
			(xy 377.551987 -289.348747) (xy 377.537715 -289.333384) (xy 377.518493 -289.325003) (xy 377.508008 -289.324542)
			(xy 376.13082 -289.324542) (xy 375.9581 -289.651186) (xy 375.968006 -289.673792) (xy 375.97691 -289.694883)
			(xy 375.989463 -289.73891) (xy 375.995797 -289.784251) (xy 375.9962 -289.807142) (xy 375.995692 -289.833029)
			(xy 375.987593 -289.884167) (xy 375.971594 -289.933407) (xy 375.948088 -289.979539) (xy 375.917656 -290.021426)
			(xy 375.881046 -290.058036) (xy 375.839159 -290.088468) (xy 375.793027 -290.111974) (xy 375.743787 -290.127973)
			(xy 375.692649 -290.136072) (xy 375.640875 -290.136072) (xy 375.589737 -290.127973) (xy 375.540497 -290.111974)
			(xy 375.494365 -290.088468) (xy 375.452478 -290.058036) (xy 375.415868 -290.021426) (xy 375.385436 -289.979539)
			(xy 375.36193 -289.933407) (xy 375.345931 -289.884167) (xy 375.337832 -289.833029) (xy 375.337324 -289.807142)
			(xy 375.337793 -289.78171) (xy 375.345603 -289.731448) (xy 375.361046 -289.682984) (xy 375.383753 -289.637469)
			(xy 375.413185 -289.595984) (xy 375.448643 -289.559516) (xy 375.489284 -289.52893) (xy 375.534143 -289.504953)
			(xy 375.582154 -289.488156) (xy 375.607072 -289.483038) (xy 375.631202 -289.478466) (xy 375.673366 -289.398964)
			(xy 375.677794 -289.389446) (xy 375.679333 -289.368533) (xy 375.672387 -289.348747) (xy 375.658115 -289.333384)
			(xy 375.638893 -289.325003) (xy 375.628408 -289.324542) (xy 374.25122 -289.324542) (xy 374.0785 -289.651186)
			(xy 374.088406 -289.673792) (xy 374.09731 -289.694883) (xy 374.109863 -289.73891) (xy 374.116197 -289.784251)
			(xy 374.1166 -289.807142) (xy 374.116092 -289.833029) (xy 374.107993 -289.884167) (xy 374.091994 -289.933407)
			(xy 374.068488 -289.979539) (xy 374.038056 -290.021426) (xy 374.001446 -290.058036) (xy 373.959559 -290.088468)
			(xy 373.913427 -290.111974) (xy 373.864187 -290.127973) (xy 373.813049 -290.136072) (xy 373.761275 -290.136072)
			(xy 373.710137 -290.127973) (xy 373.660897 -290.111974) (xy 373.614765 -290.088468) (xy 373.572878 -290.058036)
			(xy 373.536268 -290.021426) (xy 373.505836 -289.979539) (xy 373.48233 -289.933407) (xy 373.466331 -289.884167)
			(xy 373.458232 -289.833029) (xy 373.457724 -289.807142) (xy 373.458193 -289.78171) (xy 373.466003 -289.731448)
			(xy 373.481446 -289.682984) (xy 373.504153 -289.637469) (xy 373.533585 -289.595984) (xy 373.569043 -289.559516)
			(xy 373.609684 -289.52893) (xy 373.654543 -289.504953) (xy 373.702554 -289.488156) (xy 373.727472 -289.483038)
			(xy 373.751602 -289.478466) (xy 373.793766 -289.398964) (xy 373.798194 -289.389446) (xy 373.799733 -289.368533)
			(xy 373.792787 -289.348747) (xy 373.778515 -289.333384) (xy 373.759293 -289.325003) (xy 373.748808 -289.324542)
			(xy 372.37162 -289.324542) (xy 372.1989 -289.651186) (xy 372.208806 -289.673792) (xy 372.21771 -289.694883)
			(xy 372.230263 -289.73891) (xy 372.236597 -289.784251) (xy 372.237 -289.807142) (xy 372.236492 -289.833029)
			(xy 372.228393 -289.884167) (xy 372.212394 -289.933407) (xy 372.188888 -289.979539) (xy 372.158456 -290.021426)
			(xy 372.121846 -290.058036) (xy 372.079959 -290.088468) (xy 372.033827 -290.111974) (xy 371.984587 -290.127973)
			(xy 371.933449 -290.136072) (xy 371.881675 -290.136072) (xy 371.830537 -290.127973) (xy 371.781297 -290.111974)
			(xy 371.735165 -290.088468) (xy 371.693278 -290.058036) (xy 371.656668 -290.021426) (xy 371.626236 -289.979539)
			(xy 371.60273 -289.933407) (xy 371.586731 -289.884167) (xy 371.578632 -289.833029) (xy 371.578124 -289.807142)
			(xy 371.578593 -289.78171) (xy 371.586403 -289.731448) (xy 371.601846 -289.682984) (xy 371.624553 -289.637469)
			(xy 371.653985 -289.595984) (xy 371.689443 -289.559516) (xy 371.730084 -289.52893) (xy 371.774943 -289.504953)
			(xy 371.822954 -289.488156) (xy 371.847872 -289.483038) (xy 371.872002 -289.478466) (xy 371.914166 -289.398964)
			(xy 371.918594 -289.389446) (xy 371.920133 -289.368533) (xy 371.913187 -289.348747) (xy 371.898915 -289.333384)
			(xy 371.879693 -289.325003) (xy 371.869208 -289.324542) (xy 370.49202 -289.324542) (xy 370.3193 -289.651186)
			(xy 370.329206 -289.673792) (xy 370.33811 -289.694883) (xy 370.350663 -289.73891) (xy 370.356997 -289.784251)
			(xy 370.3574 -289.807142) (xy 370.356892 -289.833029) (xy 370.348793 -289.884167) (xy 370.332794 -289.933407)
			(xy 370.309288 -289.979539) (xy 370.278856 -290.021426) (xy 370.242246 -290.058036) (xy 370.200359 -290.088468)
			(xy 370.154227 -290.111974) (xy 370.104987 -290.127973) (xy 370.053849 -290.136072) (xy 370.002075 -290.136072)
			(xy 369.950937 -290.127973) (xy 369.901697 -290.111974) (xy 369.855565 -290.088468) (xy 369.813678 -290.058036)
			(xy 369.777068 -290.021426) (xy 369.746636 -289.979539) (xy 369.72313 -289.933407) (xy 369.707131 -289.884167)
			(xy 369.699032 -289.833029) (xy 369.698524 -289.807142) (xy 369.698993 -289.78171) (xy 369.706803 -289.731448)
			(xy 369.722246 -289.682984) (xy 369.744953 -289.637469) (xy 369.774385 -289.595984) (xy 369.809843 -289.559516)
			(xy 369.850484 -289.52893) (xy 369.895343 -289.504953) (xy 369.943354 -289.488156) (xy 369.968272 -289.483038)
			(xy 369.992402 -289.478466) (xy 370.034566 -289.398964) (xy 370.038994 -289.389446) (xy 370.040533 -289.368533)
			(xy 370.033587 -289.348747) (xy 370.019315 -289.333384) (xy 370.000093 -289.325003) (xy 369.989608 -289.324542)
			(xy 369.702334 -289.324542) (xy 369.677377 -289.323964) (xy 369.628423 -289.314213) (xy 369.582313 -289.295097)
			(xy 369.54082 -289.267352) (xy 369.522756 -289.25012) (xy 369.51666 -289.244024) (xy 369.490475 -289.240179)
			(xy 369.43971 -289.225225) (xy 369.391989 -289.202346) (xy 369.348542 -289.172129) (xy 369.310486 -289.135354)
			(xy 369.278801 -289.092966) (xy 369.254302 -289.046056) (xy 369.23762 -288.995832) (xy 369.229185 -288.943587)
			(xy 369.228624 -288.917126) (xy 369.229026 -288.895857) (xy 369.234637 -288.853689) (xy 369.2398 -288.833052)
			(xy 369.245134 -288.812732) (xy 369.023646 -288.426906) (xy 369.003326 -288.421572) (xy 368.977374 -288.414082)
			(xy 368.928158 -288.391827) (xy 368.883228 -288.36185) (xy 368.843785 -288.32495) (xy 368.810882 -288.282116)
			(xy 368.785401 -288.234492) (xy 368.768022 -288.183351) (xy 368.75921 -288.130062) (xy 368.758724 -288.103056)
			(xy 368.759113 -288.080934) (xy 368.765099 -288.037095) (xy 368.770662 -288.01568) (xy 368.77625 -287.99536)
			(xy 368.55654 -287.612328) (xy 368.535966 -287.606994) (xy 368.509929 -287.599682) (xy 368.46051 -287.577725)
			(xy 368.415361 -287.547961) (xy 368.375704 -287.511195) (xy 368.342614 -287.468424) (xy 368.316986 -287.420805)
			(xy 368.299514 -287.369628) (xy 368.290671 -287.316279) (xy 368.290094 -287.28924) (xy 368.290471 -287.26659)
			(xy 368.296712 -287.221722) (xy 368.30254 -287.199832) (xy 368.308382 -287.179258) (xy 368.091212 -286.800798)
			(xy 368.07013 -286.795464) (xy 368.046556 -286.789252) (xy 368.001422 -286.770828) (xy 367.959496 -286.745953)
			(xy 367.921694 -286.71517) (xy 367.888843 -286.679152) (xy 367.861659 -286.638685) (xy 367.840738 -286.594653)
			(xy 367.826534 -286.548018) (xy 367.81936 -286.499799) (xy 367.818924 -286.475424) (xy 367.819343 -286.451585)
			(xy 367.826228 -286.404408) (xy 367.83264 -286.381444) (xy 367.83899 -286.360616) (xy 367.624868 -285.987236)
			(xy 367.603278 -285.982156) (xy 367.579479 -285.976115) (xy 367.533867 -285.957942) (xy 367.491458 -285.9332)
			(xy 367.453193 -285.902435) (xy 367.419919 -285.86633) (xy 367.392374 -285.825686) (xy 367.371169 -285.781402)
			(xy 367.356772 -285.734462) (xy 367.349505 -285.685904) (xy 367.349024 -285.661354) (xy 367.349404 -285.636658)
			(xy 367.356672 -285.587807) (xy 367.363502 -285.564072) (xy 367.370106 -285.54299) (xy 367.158524 -285.173928)
			(xy 367.13668 -285.169102) (xy 367.112633 -285.163273) (xy 367.066503 -285.145381) (xy 367.023569 -285.120789)
			(xy 366.984797 -285.090051) (xy 366.95106 -285.053858) (xy 366.923116 -285.013026) (xy 366.901595 -284.968473)
			(xy 366.886982 -284.921203) (xy 366.879604 -284.872277) (xy 366.879124 -284.847538) (xy 366.879637 -284.822097)
			(xy 366.887554 -284.771833) (xy 366.894872 -284.747462) (xy 366.90173 -284.726126) (xy 366.691164 -284.35935)
			(xy 366.66932 -284.354524) (xy 366.645201 -284.348851) (xy 366.598895 -284.331228) (xy 366.555765 -284.306842)
			(xy 366.516792 -284.27625) (xy 366.482861 -284.240145) (xy 366.454744 -284.199349) (xy 366.43308 -284.15479)
			(xy 366.418363 -284.10748) (xy 366.410925 -284.058495) (xy 366.410494 -284.033722) (xy 366.410988 -284.007751)
			(xy 366.419152 -283.956454) (xy 366.42675 -283.931614) (xy 366.433862 -283.910278) (xy 366.22482 -283.545788)
			(xy 366.202468 -283.541216) (xy 366.178157 -283.535703) (xy 366.131437 -283.51832) (xy 366.087883 -283.494073)
			(xy 366.048495 -283.463519) (xy 366.014181 -283.427361) (xy 365.985728 -283.38643) (xy 365.963791 -283.341668)
			(xy 365.948874 -283.294103) (xy 365.941321 -283.24483) (xy 365.940848 -283.219906) (xy 365.941399 -283.193195)
			(xy 365.950084 -283.140483) (xy 365.95812 -283.115004) (xy 365.965486 -283.093414) (xy 365.758476 -282.732226)
			(xy 365.735616 -282.727908) (xy 365.711086 -282.722561) (xy 365.663899 -282.705423) (xy 365.619868 -282.681307)
			(xy 365.580019 -282.650773) (xy 365.545278 -282.614532) (xy 365.516454 -282.573428) (xy 365.494218 -282.528419)
			(xy 365.479088 -282.48055) (xy 365.471415 -282.430937) (xy 365.470948 -282.405836) (xy 365.47151 -282.378318)
			(xy 365.480707 -282.324055) (xy 365.489236 -282.297886) (xy 365.496856 -282.276042) (xy 365.291878 -281.918918)
			(xy 365.269018 -281.9146) (xy 365.244244 -281.909504) (xy 365.196537 -281.89271) (xy 365.151971 -281.868796)
			(xy 365.111602 -281.838327) (xy 365.076386 -281.802026) (xy 365.047156 -281.760751) (xy 365.024604 -281.71548)
			(xy 365.009266 -281.667286) (xy 365.001503 -281.617308) (xy 365.001048 -281.59202) (xy 365.001644 -281.563695)
			(xy 365.011347 -281.507883) (xy 365.020352 -281.481022) (xy 365.028226 -281.459178) (xy 364.825534 -281.10561)
			(xy 364.802166 -281.101292) (xy 364.777185 -281.096381) (xy 364.729027 -281.07987) (xy 364.683997 -281.056121)
			(xy 364.643173 -281.025705) (xy 364.607535 -280.989349) (xy 364.577938 -280.947927) (xy 364.555091 -280.902432)
			(xy 364.539543 -280.853955) (xy 364.531667 -280.803659) (xy 364.531148 -280.778204) (xy 364.531774 -280.749135)
			(xy 364.541993 -280.691901) (xy 364.551468 -280.664412) (xy 364.55985 -280.64206) (xy 364.358936 -280.291794)
			(xy 364.335314 -280.28773) (xy 364.310121 -280.283014) (xy 364.261502 -280.266799) (xy 364.215994 -280.243225)
			(xy 364.174704 -280.212864) (xy 364.138634 -280.176454) (xy 364.108661 -280.134881) (xy 364.085514 -280.089154)
			(xy 364.069756 -280.040385) (xy 364.06177 -279.98976) (xy 364.061248 -279.964134) (xy 364.061874 -279.934316)
			(xy 364.072606 -279.875654) (xy 364.082584 -279.847548) (xy 364.09122 -279.824942) (xy 363.892592 -279.478232)
			(xy 363.868462 -279.474422) (xy 363.843038 -279.469942) (xy 363.793922 -279.45405) (xy 363.747899 -279.430667)
			(xy 363.706103 -279.400369) (xy 363.669563 -279.363904) (xy 363.639181 -279.322169) (xy 363.615705 -279.276193)
			(xy 363.599713 -279.22711) (xy 363.5916 -279.176129) (xy 363.591094 -279.150318) (xy 363.591505 -279.126669)
			(xy 363.598288 -279.079859) (xy 363.611716 -279.034507) (xy 363.631511 -278.99155) (xy 363.657264 -278.951878)
			(xy 363.688442 -278.91631) (xy 363.706156 -278.900636) (xy 363.706156 -277.771606) (xy 363.686917 -277.754463)
			(xy 363.6535 -277.715241) (xy 363.626619 -277.671282) (xy 363.606933 -277.623663) (xy 363.594926 -277.573555)
			(xy 363.590892 -277.522186) (xy 363.59493 -277.470817) (xy 363.606942 -277.420709) (xy 363.626632 -277.373093)
			(xy 363.653517 -277.329135) (xy 363.686937 -277.289917) (xy 363.706156 -277.27275) (xy 363.706156 -276.144482)
			(xy 363.686869 -276.127337) (xy 363.653364 -276.088094) (xy 363.626409 -276.044093) (xy 363.606667 -275.996418)
			(xy 363.594624 -275.946242) (xy 363.590576 -275.8948) (xy 363.594624 -275.843358) (xy 363.606667 -275.793182)
			(xy 363.626409 -275.745507) (xy 363.653364 -275.701506) (xy 363.686869 -275.662263) (xy 363.706156 -275.645118)
			(xy 363.706156 -274.516342) (xy 363.686914 -274.499199) (xy 363.653491 -274.459977) (xy 363.626604 -274.416015)
			(xy 363.606914 -274.368394) (xy 363.594902 -274.318282) (xy 363.590864 -274.266909) (xy 363.594899 -274.215536)
			(xy 363.606908 -274.165423) (xy 363.626596 -274.117801) (xy 363.65348 -274.073838) (xy 363.686901 -274.034613)
			(xy 363.706156 -274.017486) (xy 363.706156 -272.888964) (xy 363.686871 -272.871819) (xy 363.653369 -272.832576)
			(xy 363.626416 -272.788576) (xy 363.606677 -272.740902) (xy 363.594636 -272.690728) (xy 363.590591 -272.639288)
			(xy 363.59464 -272.587849) (xy 363.606684 -272.537675) (xy 363.626427 -272.490003) (xy 363.653383 -272.446005)
			(xy 363.686888 -272.406764) (xy 363.706156 -272.3896) (xy 363.706156 -271.261078) (xy 363.68687 -271.243933)
			(xy 363.653365 -271.20469) (xy 363.626411 -271.160689) (xy 363.606669 -271.113014) (xy 363.594627 -271.062839)
			(xy 363.59058 -271.011397) (xy 363.594627 -270.959956) (xy 363.606671 -270.909781) (xy 363.626413 -270.862106)
			(xy 363.653368 -270.818106) (xy 363.686873 -270.778863) (xy 363.706156 -270.761714) (xy 363.706156 -269.633192)
			(xy 363.686868 -269.616047) (xy 363.653362 -269.576803) (xy 363.626405 -269.532802) (xy 363.606662 -269.485126)
			(xy 363.594618 -269.43495) (xy 363.590569 -269.383507) (xy 363.594615 -269.332063) (xy 363.606658 -269.281886)
			(xy 363.626399 -269.23421) (xy 363.653354 -269.190207) (xy 363.686859 -269.150962) (xy 363.706156 -269.133828)
			(xy 363.706156 -268.00556) (xy 363.686871 -267.988415) (xy 363.65337 -267.949172) (xy 363.626418 -267.905172)
			(xy 363.606679 -267.857499) (xy 363.594639 -267.807325) (xy 363.590594 -267.755886) (xy 363.594643 -267.704447)
			(xy 363.606688 -267.654274) (xy 363.626431 -267.606602) (xy 363.653387 -267.562605) (xy 363.686892 -267.523365)
			(xy 363.706156 -267.506196) (xy 363.706156 -266.377928) (xy 363.686866 -266.360783) (xy 363.653353 -266.321538)
			(xy 363.626391 -266.277535) (xy 363.606643 -266.229857) (xy 363.594594 -266.179677) (xy 363.590541 -266.12823)
			(xy 363.594585 -266.076782) (xy 363.606624 -266.0266) (xy 363.626364 -265.978918) (xy 363.653318 -265.93491)
			(xy 363.686823 -265.895659) (xy 363.706156 -265.878564) (xy 363.706156 -264.750042) (xy 363.686873 -264.732897)
			(xy 363.653374 -264.693654) (xy 363.626425 -264.649656) (xy 363.606688 -264.601984) (xy 363.59465 -264.551811)
			(xy 363.590607 -264.500374) (xy 363.594659 -264.448937) (xy 363.606704 -264.398767) (xy 363.626448 -264.351098)
			(xy 363.653405 -264.307103) (xy 363.686909 -264.267866) (xy 363.706156 -264.250678) (xy 363.706156 -261.179056)
			(xy 363.706732 -261.154098) (xy 363.71648 -261.105142) (xy 363.735592 -261.059029) (xy 363.763335 -261.017532)
			(xy 363.780578 -260.999478) (xy 364.440978 -260.339078) (xy 364.45902 -260.32182) (xy 364.500514 -260.294066)
			(xy 364.546632 -260.274957) (xy 364.595595 -260.265231) (xy 364.620556 -260.264656) (xy 368.5032 -260.264656)
			(xy 368.662966 -260.10489) (xy 368.673467 -260.093672) (xy 368.687778 -260.066495) (xy 368.69335 -260.03629)
			(xy 368.689678 -260.005796) (xy 368.677094 -259.977778) (xy 368.667284 -259.965952) (xy 368.651949 -259.947902)
			(xy 368.626092 -259.908222) (xy 368.60621 -259.865236) (xy 368.592717 -259.819838) (xy 368.585893 -259.772971)
			(xy 368.585496 -259.74929) (xy 368.585968 -259.72394) (xy 368.593766 -259.673844) (xy 368.609175 -259.625544)
			(xy 368.631828 -259.580187) (xy 368.661186 -259.538853) (xy 368.696552 -259.502525) (xy 368.737083 -259.472068)
			(xy 368.759232 -259.45973) (xy 368.786156 -259.445252) (xy 368.786156 -258.754118) (xy 368.759486 -258.73964)
			(xy 368.737595 -258.727222) (xy 368.697564 -258.69672) (xy 368.662659 -258.660464) (xy 368.633698 -258.619304)
			(xy 368.611361 -258.574205) (xy 368.59617 -258.526225) (xy 368.588483 -258.476488) (xy 368.58848 -258.42616)
			(xy 368.59616 -258.376422) (xy 368.611343 -258.328439) (xy 368.633674 -258.283337) (xy 368.662628 -258.242173)
			(xy 368.697528 -258.205912) (xy 368.737555 -258.175404) (xy 368.759486 -258.16306) (xy 368.786156 -258.148582)
			(xy 368.786156 -257.585718) (xy 368.759486 -257.57124) (xy 368.737615 -257.558798) (xy 368.697601 -257.528295)
			(xy 368.662711 -257.492042) (xy 368.633762 -257.450889) (xy 368.611434 -257.4058) (xy 368.596248 -257.357832)
			(xy 368.588562 -257.308107) (xy 368.588036 -257.28295) (xy 368.588566 -257.256569) (xy 368.597011 -257.204486)
			(xy 368.613676 -257.154423) (xy 368.638132 -257.10767) (xy 368.669749 -257.065429) (xy 368.688366 -257.04673)
			(xy 368.697788 -257.036999) (xy 368.711589 -257.013702) (xy 368.718791 -256.9876) (xy 368.718887 -256.960523)
			(xy 368.711872 -256.934369) (xy 368.698238 -256.910975) (xy 368.688874 -256.901188) (xy 368.670585 -256.882532)
			(xy 368.639566 -256.840497) (xy 368.615595 -256.79408) (xy 368.599279 -256.744452) (xy 368.59103 -256.692867)
			(xy 368.590576 -256.666746) (xy 368.591049 -256.641747) (xy 368.598638 -256.592328) (xy 368.613632 -256.54463)
			(xy 368.635685 -256.499758) (xy 368.664286 -256.458748) (xy 368.698775 -256.422548) (xy 368.738353 -256.391997)
			(xy 368.759994 -256.379472) (xy 368.786156 -256.364994) (xy 368.786156 -255.833118) (xy 368.759486 -255.81864)
			(xy 368.737615 -255.806198) (xy 368.697601 -255.775695) (xy 368.662711 -255.739442) (xy 368.633762 -255.698289)
			(xy 368.611434 -255.6532) (xy 368.596248 -255.605232) (xy 368.588562 -255.555507) (xy 368.588036 -255.53035)
			(xy 368.588495 -255.505822) (xy 368.595801 -255.457312) (xy 368.610242 -255.410429) (xy 368.631498 -255.366216)
			(xy 368.659095 -255.325658) (xy 368.675412 -255.307338) (xy 368.685412 -255.295827) (xy 368.698651 -255.268374)
			(xy 368.703207 -255.238237) (xy 368.698673 -255.208097) (xy 368.685453 -255.180634) (xy 368.675412 -255.169162)
			(xy 368.659078 -255.150856) (xy 368.631472 -255.1103) (xy 368.610216 -255.066084) (xy 368.595784 -255.019196)
			(xy 368.588498 -254.97068) (xy 368.588036 -254.94615) (xy 368.58849 -254.920987) (xy 368.596168 -254.871249)
			(xy 368.611352 -254.823268) (xy 368.633686 -254.778168) (xy 368.662645 -254.737008) (xy 368.69755 -254.700753)
			(xy 368.737583 -254.670255) (xy 368.759486 -254.65786) (xy 368.786156 -254.643382) (xy 368.786156 -253.496318)
			(xy 368.759486 -253.48184) (xy 368.737615 -253.469398) (xy 368.697601 -253.438895) (xy 368.662711 -253.402642)
			(xy 368.633762 -253.361489) (xy 368.611434 -253.3164) (xy 368.596248 -253.268432) (xy 368.588562 -253.218707)
			(xy 368.588036 -253.19355) (xy 368.588495 -253.169022) (xy 368.595801 -253.120512) (xy 368.610242 -253.073629)
			(xy 368.631498 -253.029416) (xy 368.659095 -252.988858) (xy 368.675412 -252.970538) (xy 368.685412 -252.959027)
			(xy 368.698651 -252.931574) (xy 368.703207 -252.901437) (xy 368.698673 -252.871297) (xy 368.685453 -252.843834)
			(xy 368.675412 -252.832362) (xy 368.659078 -252.814056) (xy 368.631472 -252.7735) (xy 368.610216 -252.729284)
			(xy 368.595784 -252.682396) (xy 368.588498 -252.63388) (xy 368.588036 -252.60935) (xy 368.58849 -252.584187)
			(xy 368.596168 -252.534449) (xy 368.611352 -252.486468) (xy 368.633686 -252.441368) (xy 368.662645 -252.400208)
			(xy 368.69755 -252.363953) (xy 368.737583 -252.333455) (xy 368.759486 -252.32106) (xy 368.786156 -252.306582)
			(xy 368.786156 -251.743718) (xy 368.759486 -251.72924) (xy 368.737615 -251.716798) (xy 368.697601 -251.686295)
			(xy 368.662711 -251.650042) (xy 368.633762 -251.608889) (xy 368.611434 -251.5638) (xy 368.596248 -251.515832)
			(xy 368.588562 -251.466107) (xy 368.588036 -251.44095) (xy 368.588495 -251.416422) (xy 368.595801 -251.367912)
			(xy 368.610242 -251.321029) (xy 368.631498 -251.276816) (xy 368.659095 -251.236258) (xy 368.675412 -251.217938)
			(xy 368.685412 -251.206427) (xy 368.698651 -251.178974) (xy 368.703207 -251.148837) (xy 368.698673 -251.118697)
			(xy 368.685453 -251.091234) (xy 368.675412 -251.079762) (xy 368.659078 -251.061456) (xy 368.631472 -251.0209)
			(xy 368.610216 -250.976684) (xy 368.595784 -250.929796) (xy 368.588498 -250.88128) (xy 368.588036 -250.85675)
			(xy 368.58849 -250.831587) (xy 368.596168 -250.781849) (xy 368.611352 -250.733868) (xy 368.633686 -250.688768)
			(xy 368.662645 -250.647608) (xy 368.69755 -250.611353) (xy 368.737583 -250.580855) (xy 368.759486 -250.56846)
			(xy 368.786156 -250.553982) (xy 368.786156 -249.402346) (xy 368.764083 -249.391179) (xy 368.723279 -249.363214)
			(xy 368.687134 -249.329443) (xy 368.656465 -249.290631) (xy 368.631967 -249.247657) (xy 368.614195 -249.201493)
			(xy 368.60355 -249.153186) (xy 368.601498 -249.128534) (xy 368.600228 -249.109484) (xy 366.549178 -247.058434)
			(xy 366.531919 -247.040393) (xy 366.504163 -246.998899) (xy 366.485052 -246.952781) (xy 366.475323 -246.903817)
			(xy 366.474756 -246.878856) (xy 366.474756 -244.897656) (xy 366.475332 -244.872698) (xy 366.48508 -244.823742)
			(xy 366.504192 -244.777629) (xy 366.531935 -244.736132) (xy 366.549178 -244.718078) (xy 367.844578 -243.422678)
			(xy 367.86262 -243.40542) (xy 367.904114 -243.377666) (xy 367.950232 -243.358557) (xy 367.999195 -243.348831)
			(xy 368.024156 -243.348256) (xy 368.5794 -243.348256) (xy 368.709956 -243.2177) (xy 368.709956 -242.589812)
			(xy 368.3 -242.179856) (xy 365.687356 -242.179856) (xy 365.662398 -242.17928) (xy 365.613442 -242.169533)
			(xy 365.567328 -242.150421) (xy 365.52583 -242.122679) (xy 365.507778 -242.105434) (xy 363.602778 -240.200434)
			(xy 363.585519 -240.182393) (xy 363.557763 -240.140899) (xy 363.538652 -240.094781) (xy 363.528923 -240.045817)
			(xy 363.528356 -240.020856) (xy 363.528356 -238.703612) (xy 363.1692 -238.344456) (xy 362.237274 -238.344456)
			(xy 362.22305 -238.372396) (xy 362.211008 -238.395396) (xy 362.180779 -238.437603) (xy 362.144279 -238.47452)
			(xy 362.102418 -238.505225) (xy 362.056241 -238.528951) (xy 362.006904 -238.545106) (xy 361.955637 -238.553285)
			(xy 361.903723 -238.553285) (xy 361.852456 -238.545106) (xy 361.803119 -238.528951) (xy 361.756942 -238.505225)
			(xy 361.715081 -238.47452) (xy 361.678581 -238.437603) (xy 361.648352 -238.395396) (xy 361.63631 -238.372396)
			(xy 361.622086 -238.344456) (xy 361.297474 -238.344456) (xy 361.28325 -238.372396) (xy 361.271208 -238.395396)
			(xy 361.240979 -238.437603) (xy 361.204479 -238.47452) (xy 361.162618 -238.505225) (xy 361.116441 -238.528951)
			(xy 361.067104 -238.545106) (xy 361.015837 -238.553285) (xy 360.963923 -238.553285) (xy 360.912656 -238.545106)
			(xy 360.863319 -238.528951) (xy 360.817142 -238.505225) (xy 360.775281 -238.47452) (xy 360.738781 -238.437603)
			(xy 360.708552 -238.395396) (xy 360.69651 -238.372396) (xy 360.682286 -238.344456) (xy 360.357674 -238.344456)
			(xy 360.34345 -238.372396) (xy 360.331408 -238.395396) (xy 360.301179 -238.437603) (xy 360.264679 -238.47452)
			(xy 360.222818 -238.505225) (xy 360.176641 -238.528951) (xy 360.127304 -238.545106) (xy 360.076037 -238.553285)
			(xy 360.024123 -238.553285) (xy 359.972856 -238.545106) (xy 359.923519 -238.528951) (xy 359.877342 -238.505225)
			(xy 359.835481 -238.47452) (xy 359.798981 -238.437603) (xy 359.768752 -238.395396) (xy 359.75671 -238.372396)
			(xy 359.742486 -238.344456) (xy 359.417874 -238.344456) (xy 359.40365 -238.372396) (xy 359.391608 -238.395396)
			(xy 359.361379 -238.437603) (xy 359.324879 -238.47452) (xy 359.283018 -238.505225) (xy 359.236841 -238.528951)
			(xy 359.187504 -238.545106) (xy 359.136237 -238.553285) (xy 359.084323 -238.553285) (xy 359.033056 -238.545106)
			(xy 358.983719 -238.528951) (xy 358.937542 -238.505225) (xy 358.895681 -238.47452) (xy 358.859181 -238.437603)
			(xy 358.828952 -238.395396) (xy 358.81691 -238.372396) (xy 358.802686 -238.344456) (xy 358.478074 -238.344456)
			(xy 358.46385 -238.372396) (xy 358.451808 -238.395396) (xy 358.421579 -238.437603) (xy 358.385079 -238.47452)
			(xy 358.343218 -238.505225) (xy 358.297041 -238.528951) (xy 358.247704 -238.545106) (xy 358.196437 -238.553285)
			(xy 358.144523 -238.553285) (xy 358.093256 -238.545106) (xy 358.043919 -238.528951) (xy 357.997742 -238.505225)
			(xy 357.955881 -238.47452) (xy 357.919381 -238.437603) (xy 357.889152 -238.395396) (xy 357.87711 -238.372396)
			(xy 357.862886 -238.344456) (xy 357.538274 -238.344456) (xy 357.52405 -238.372396) (xy 357.512008 -238.395396)
			(xy 357.481779 -238.437603) (xy 357.445279 -238.47452) (xy 357.403418 -238.505225) (xy 357.357241 -238.528951)
			(xy 357.307904 -238.545106) (xy 357.256637 -238.553285) (xy 357.204723 -238.553285) (xy 357.153456 -238.545106)
			(xy 357.104119 -238.528951) (xy 357.057942 -238.505225) (xy 357.016081 -238.47452) (xy 356.979581 -238.437603)
			(xy 356.949352 -238.395396) (xy 356.93731 -238.372396) (xy 356.923086 -238.344456) (xy 352.432112 -238.344456)
			(xy 351.234756 -239.541812) (xy 351.234756 -245.2243) (xy 351.619312 -245.608856) (xy 352.733356 -245.608856)
			(xy 352.758314 -245.609433) (xy 352.807268 -245.619183) (xy 352.853379 -245.638297) (xy 352.894875 -245.666041)
			(xy 352.912934 -245.683278) (xy 353.243134 -246.013478) (xy 353.260392 -246.03152) (xy 353.288144 -246.073014)
			(xy 353.307252 -246.119132) (xy 353.316978 -246.168096) (xy 353.317556 -246.193056) (xy 353.317556 -246.36603)
			(xy 353.344226 -246.380508) (xy 353.366236 -246.392881) (xy 353.406504 -246.423341) (xy 353.441628 -246.459612)
			(xy 353.470778 -246.500838) (xy 353.493265 -246.546045) (xy 353.508558 -246.594163) (xy 353.516296 -246.644058)
			(xy 353.516296 -246.694548) (xy 353.508557 -246.744442) (xy 353.493263 -246.792561) (xy 353.470775 -246.837767)
			(xy 353.441624 -246.878992) (xy 353.4065 -246.915263) (xy 353.366231 -246.945722) (xy 353.344226 -246.958104)
			(xy 353.317556 -246.972582) (xy 353.317556 -247.386856) (xy 353.316979 -247.411814) (xy 353.30723 -247.460769)
			(xy 353.288116 -247.50688) (xy 353.260373 -247.548377) (xy 353.243134 -247.566434) (xy 352.608134 -248.201434)
			(xy 352.590093 -248.218693) (xy 352.548599 -248.246447) (xy 352.50248 -248.265557) (xy 352.453517 -248.275286)
			(xy 352.428556 -248.275856) (xy 351.619312 -248.275856) (xy 351.285556 -248.609612) (xy 351.285556 -255.908302)
			(xy 351.60331 -256.226056) (xy 352.682556 -256.226056) (xy 352.707514 -256.226633) (xy 352.756468 -256.236383)
			(xy 352.802579 -256.255497) (xy 352.844075 -256.283241) (xy 352.862134 -256.300478) (xy 353.370134 -256.808478)
			(xy 353.387392 -256.82652) (xy 353.415144 -256.868014) (xy 353.434252 -256.914132) (xy 353.443978 -256.963096)
			(xy 353.444556 -256.988056) (xy 353.444556 -257.366008) (xy 353.482148 -257.375914) (xy 353.506415 -257.382944)
			(xy 353.552599 -257.403424) (xy 353.595101 -257.430737) (xy 353.632917 -257.464238) (xy 353.665155 -257.503136)
			(xy 353.691054 -257.546514) (xy 353.710003 -257.593347) (xy 353.721554 -257.64253) (xy 353.725434 -257.692902)
			(xy 353.721553 -257.743273) (xy 353.710002 -257.792456) (xy 353.691053 -257.839289) (xy 353.665153 -257.882666)
			(xy 353.632915 -257.921565) (xy 353.595098 -257.955065) (xy 353.552596 -257.982378) (xy 353.506412 -258.002857)
			(xy 353.482148 -258.009898) (xy 353.444556 -258.019804) (xy 353.444556 -260.3881) (xy 353.616514 -260.560058)
			(xy 355.569012 -260.560058) (xy 355.593972 -260.560631) (xy 355.642931 -260.570373) (xy 355.689048 -260.589482)
			(xy 355.730549 -260.617222) (xy 355.74859 -260.63448) (xy 356.017322 -260.903212) (xy 356.034585 -260.921252)
			(xy 356.06235 -260.962744) (xy 356.081471 -261.008862) (xy 356.09121 -261.057827) (xy 356.091744 -261.08279)
			(xy 356.091744 -261.442962) (xy 356.091167 -261.46792) (xy 356.081416 -261.516873) (xy 356.062301 -261.562984)
			(xy 356.034556 -261.604478) (xy 356.017322 -261.62254) (xy 355.676708 -261.963154) (xy 355.658665 -261.980409)
			(xy 355.61717 -262.008158) (xy 355.571052 -262.027261) (xy 355.52209 -262.036984) (xy 355.49713 -262.037576)
			(xy 355.294184 -262.037576) (xy 355.108764 -262.222996) (xy 355.108764 -263.499346) (xy 356.24643 -264.637012)
			(xy 356.263693 -264.655052) (xy 356.291457 -264.696544) (xy 356.310577 -264.742662) (xy 356.320316 -264.791628)
			(xy 356.320852 -264.81659) (xy 356.320852 -273.453098) (xy 356.541324 -273.453098) (xy 356.541832 -273.427211)
			(xy 356.549931 -273.376073) (xy 356.56593 -273.326833) (xy 356.589436 -273.280701) (xy 356.619868 -273.238814)
			(xy 356.656478 -273.202204) (xy 356.698365 -273.171772) (xy 356.744497 -273.148266) (xy 356.793737 -273.132267)
			(xy 356.844875 -273.124168) (xy 356.896649 -273.124168) (xy 356.947787 -273.132267) (xy 356.997027 -273.148266)
			(xy 357.043159 -273.171772) (xy 357.085046 -273.202204) (xy 357.121656 -273.238814) (xy 357.152088 -273.280701)
			(xy 357.175594 -273.326833) (xy 357.191593 -273.376073) (xy 357.199692 -273.427211) (xy 357.2002 -273.453098)
			(xy 357.19967 -273.480806) (xy 357.190475 -273.535453) (xy 357.181912 -273.56181) (xy 357.174292 -273.583654)
			(xy 357.37927 -273.938746) (xy 357.40213 -273.943064) (xy 357.426938 -273.948232) (xy 357.474677 -273.965225)
			(xy 357.519254 -273.989322) (xy 357.559619 -274.019956) (xy 357.594821 -274.056405) (xy 357.624032 -274.097811)
			(xy 357.646564 -274.143199) (xy 357.661886 -274.191501) (xy 357.669637 -274.241577) (xy 357.6701 -274.266914)
			(xy 357.669592 -274.292801) (xy 357.661493 -274.343939) (xy 357.645494 -274.393179) (xy 357.621988 -274.439311)
			(xy 357.591556 -274.481198) (xy 357.554946 -274.517808) (xy 357.513059 -274.54824) (xy 357.466927 -274.571746)
			(xy 357.417687 -274.587745) (xy 357.366549 -274.595844) (xy 357.314775 -274.595844) (xy 357.263637 -274.587745)
			(xy 357.214397 -274.571746) (xy 357.168265 -274.54824) (xy 357.126378 -274.517808) (xy 357.089768 -274.481198)
			(xy 357.059336 -274.439311) (xy 357.03583 -274.393179) (xy 357.019831 -274.343939) (xy 357.011732 -274.292801)
			(xy 357.011224 -274.266914) (xy 357.011756 -274.239206) (xy 357.020949 -274.184559) (xy 357.029512 -274.158202)
			(xy 357.037386 -274.136104) (xy 356.832408 -273.781266) (xy 356.809548 -273.776948) (xy 356.784736 -273.771741)
			(xy 356.73696 -273.75479) (xy 356.692344 -273.730722) (xy 356.651938 -273.700106) (xy 356.616698 -273.663665)
			(xy 356.587453 -273.622257) (xy 356.564893 -273.576859) (xy 356.549551 -273.528542) (xy 356.541789 -273.478445)
			(xy 356.541324 -273.453098) (xy 356.320852 -273.453098) (xy 356.320852 -275.360892) (xy 356.439724 -275.566632)
			(xy 356.462584 -275.57095) (xy 356.487395 -275.576139) (xy 356.535155 -275.593113) (xy 356.579755 -275.617196)
			(xy 356.620145 -275.64782) (xy 356.655372 -275.684264) (xy 356.684609 -275.725669) (xy 356.707164 -275.771061)
			(xy 356.722509 -275.819369) (xy 356.73028 -275.869457) (xy 356.730808 -275.8948) (xy 356.730345 -275.919893)
			(xy 356.72275 -275.969502) (xy 356.70772 -276.017384) (xy 356.685602 -276.062434) (xy 356.656909 -276.103609)
			(xy 356.622304 -276.139957) (xy 356.582587 -276.170636) (xy 356.538677 -276.194938) (xy 356.49159 -276.212301)
			(xy 356.442414 -276.222322) (xy 356.417372 -276.223984) (xy 356.401951 -276.22532) (xy 356.372938 -276.236066)
			(xy 356.34846 -276.254989) (xy 356.330753 -276.28036) (xy 356.321432 -276.309862) (xy 356.320852 -276.32533)
			(xy 356.320852 -276.708616) (xy 356.541324 -276.708616) (xy 356.541802 -276.683281) (xy 356.549553 -276.633207)
			(xy 356.564874 -276.584909) (xy 356.587406 -276.539525) (xy 356.616616 -276.498122) (xy 356.651818 -276.461676)
			(xy 356.692181 -276.431046) (xy 356.736757 -276.406953) (xy 356.784494 -276.389964) (xy 356.809294 -276.384766)
			(xy 356.832154 -276.380448) (xy 357.037132 -276.02561) (xy 357.029258 -276.003766) (xy 357.020612 -275.977358)
			(xy 357.011292 -275.922582) (xy 357.010716 -275.8948) (xy 357.011224 -275.868893) (xy 357.01933 -275.817716)
			(xy 357.035342 -275.768437) (xy 357.058865 -275.72227) (xy 357.089321 -275.680351) (xy 357.125959 -275.643713)
			(xy 357.167878 -275.613257) (xy 357.214045 -275.589734) (xy 357.263324 -275.573722) (xy 357.314501 -275.565616)
			(xy 357.366315 -275.565616) (xy 357.417492 -275.573722) (xy 357.466771 -275.589734) (xy 357.512938 -275.613257)
			(xy 357.554857 -275.643713) (xy 357.591495 -275.680351) (xy 357.621951 -275.72227) (xy 357.645474 -275.768437)
			(xy 357.661486 -275.817716) (xy 357.669592 -275.868893) (xy 357.6701 -275.8948) (xy 357.669579 -275.920144)
			(xy 357.661807 -275.970232) (xy 357.646462 -276.018541) (xy 357.623906 -276.063932) (xy 357.594669 -276.105338)
			(xy 357.55944 -276.141782) (xy 357.519049 -276.172406) (xy 357.474448 -276.196488) (xy 357.426687 -276.213462)
			(xy 357.401876 -276.21865) (xy 357.379016 -276.222968) (xy 357.174038 -276.577806) (xy 357.181912 -276.599904)
			(xy 357.190474 -276.626262) (xy 357.199672 -276.680908) (xy 357.2002 -276.708616) (xy 357.199692 -276.734503)
			(xy 357.191593 -276.785641) (xy 357.175594 -276.834881) (xy 357.152088 -276.881013) (xy 357.121656 -276.9229)
			(xy 357.085046 -276.95951) (xy 357.043159 -276.989942) (xy 356.997027 -277.013448) (xy 356.947787 -277.029447)
			(xy 356.896649 -277.037546) (xy 356.844875 -277.037546) (xy 356.793737 -277.029447) (xy 356.744497 -277.013448)
			(xy 356.698365 -276.989942) (xy 356.656478 -276.95951) (xy 356.619868 -276.9229) (xy 356.589436 -276.881013)
			(xy 356.56593 -276.834881) (xy 356.549931 -276.785641) (xy 356.541832 -276.734503) (xy 356.541324 -276.708616)
			(xy 356.320852 -276.708616) (xy 356.320852 -277.091902) (xy 356.321388 -277.107385) (xy 356.330653 -277.136932)
			(xy 356.348358 -277.162336) (xy 356.372872 -277.181256) (xy 356.401934 -277.191946) (xy 356.417372 -277.193248)
			(xy 356.441444 -277.194906) (xy 356.488765 -277.204333) (xy 356.534208 -277.22055) (xy 356.576807 -277.24321)
			(xy 356.615652 -277.271831) (xy 356.649916 -277.305802) (xy 356.664768 -277.32482) (xy 357.076756 -277.32482)
			(xy 357.092427 -277.304681) (xy 357.128935 -277.26903) (xy 357.170499 -277.239429) (xy 357.216128 -277.216585)
			(xy 357.264731 -277.201044) (xy 357.315148 -277.193177) (xy 357.340662 -277.19274) (xy 357.366571 -277.193219)
			(xy 357.417751 -277.20132) (xy 357.467034 -277.217328) (xy 357.513206 -277.240849) (xy 357.555129 -277.271303)
			(xy 357.591772 -277.307942) (xy 357.622231 -277.349862) (xy 357.645758 -277.396031) (xy 357.661771 -277.445312)
			(xy 357.669878 -277.496491) (xy 357.669878 -277.548309) (xy 357.661771 -277.599488) (xy 357.645758 -277.648769)
			(xy 357.622231 -277.694938) (xy 357.591772 -277.736858) (xy 357.555129 -277.773497) (xy 357.513206 -277.803951)
			(xy 357.467034 -277.827472) (xy 357.417751 -277.84348) (xy 357.366571 -277.851581) (xy 357.340662 -277.852124)
			(xy 357.315151 -277.851644) (xy 357.264739 -277.843779) (xy 357.21614 -277.828242) (xy 357.170514 -277.805404)
			(xy 357.128951 -277.775811) (xy 357.092443 -277.740168) (xy 357.076756 -277.720044) (xy 356.664768 -277.720044)
			(xy 356.649971 -277.739111) (xy 356.615721 -277.773116) (xy 356.576873 -277.801756) (xy 356.534261 -277.824416)
			(xy 356.488796 -277.840612) (xy 356.441453 -277.849996) (xy 356.417372 -277.851616) (xy 356.401953 -277.852952)
			(xy 356.372944 -277.8637) (xy 356.348472 -277.882624) (xy 356.330771 -277.907995) (xy 356.32146 -277.937496)
			(xy 356.320852 -277.952962) (xy 356.320852 -280.004774) (xy 356.320274 -280.029731) (xy 356.310521 -280.078684)
			(xy 356.291405 -280.124793) (xy 356.26366 -280.166287) (xy 356.24643 -280.184352) (xy 355.769164 -280.661618)
			(xy 355.777292 -280.690066) (xy 355.782886 -280.711669) (xy 355.788871 -280.755891) (xy 355.78923 -280.778204)
			(xy 355.78875 -280.803992) (xy 355.78068 -280.854934) (xy 355.764741 -280.903986) (xy 355.741323 -280.94994)
			(xy 355.711005 -280.991665) (xy 355.674533 -281.028132) (xy 355.632804 -281.058445) (xy 355.586847 -281.081857)
			(xy 355.537793 -281.09779) (xy 355.48685 -281.105853) (xy 355.461062 -281.106372) (xy 355.438748 -281.106031)
			(xy 355.394525 -281.100039) (xy 355.372924 -281.094434) (xy 355.344476 -281.086306) (xy 354.484178 -281.946604)
			(xy 354.55987 -282.077668) (xy 354.58273 -282.081986) (xy 354.607532 -282.087184) (xy 354.655272 -282.104174)
			(xy 354.69985 -282.128267) (xy 354.740218 -282.158896) (xy 354.775426 -282.195341) (xy 354.804643 -282.236743)
			(xy 354.827182 -282.282127) (xy 354.842514 -282.330425) (xy 354.850275 -282.3805) (xy 354.8507 -282.405836)
			(xy 354.85019 -282.431729) (xy 354.842088 -282.482877) (xy 354.826089 -282.53213) (xy 354.802586 -282.578276)
			(xy 354.772157 -282.620179) (xy 354.735551 -282.65681) (xy 354.693669 -282.687267) (xy 354.647539 -282.710802)
			(xy 354.598297 -282.726835) (xy 354.547155 -282.734972) (xy 354.521262 -282.735528) (xy 354.495573 -282.735034)
			(xy 354.444817 -282.727056) (xy 354.395914 -282.7113) (xy 354.350048 -282.688147) (xy 354.308329 -282.658158)
			(xy 354.271769 -282.62206) (xy 354.241252 -282.580726) (xy 354.217519 -282.535158) (xy 354.201142 -282.486459)
			(xy 354.196396 -282.461208) (xy 354.193633 -282.447564) (xy 354.181724 -282.422412) (xy 354.16347 -282.401407)
			(xy 354.140225 -282.386107) (xy 354.113714 -282.377646) (xy 354.085903 -282.376654) (xy 354.058856 -282.383204)
			(xy 354.03458 -282.396809) (xy 354.024438 -282.406344) (xy 353.875086 -282.555696) (xy 353.87153 -282.5623)
			(xy 353.859771 -282.583185) (xy 353.831142 -282.621623) (xy 353.797247 -282.655508) (xy 353.758801 -282.684125)
			(xy 353.737926 -282.695904) (xy 353.731322 -282.69946) (xy 353.515676 -282.915106) (xy 353.415092 -283.089096)
			(xy 353.422966 -283.111194) (xy 353.43159 -283.137542) (xy 353.440912 -283.192189) (xy 353.441508 -283.219906)
			(xy 353.441025 -283.245807) (xy 353.432916 -283.29697) (xy 353.4169 -283.346234) (xy 353.393369 -283.392383)
			(xy 353.362906 -283.434281) (xy 353.32626 -283.470895) (xy 353.284336 -283.501321) (xy 353.238166 -283.524811)
			(xy 353.188888 -283.540784) (xy 353.137717 -283.548848) (xy 353.111816 -283.549344) (xy 353.086439 -283.548877)
			(xy 353.036286 -283.541093) (xy 352.987921 -283.525708) (xy 352.965004 -283.5148) (xy 352.932238 -283.498544)
			(xy 352.560128 -283.870654) (xy 352.560128 -288.168334) (xy 352.559513 -288.19329) (xy 352.549771 -288.242241)
			(xy 352.530667 -288.288351) (xy 352.502936 -288.32985) (xy 352.485706 -288.347912) (xy 352.017076 -288.816542)
			(xy 352.023426 -288.84372) (xy 352.027333 -288.86182) (xy 352.031534 -288.898611) (xy 352.031808 -288.917126)
			(xy 352.031324 -288.943026) (xy 352.023212 -288.994187) (xy 352.007194 -289.043448) (xy 351.983663 -289.089595)
			(xy 351.953199 -289.13149) (xy 351.916554 -289.168101) (xy 351.87463 -289.198525) (xy 351.828461 -289.222013)
			(xy 351.779185 -289.237985) (xy 351.728016 -289.246048) (xy 351.702116 -289.246564) (xy 351.676757 -289.246153)
			(xy 351.626622 -289.238495) (xy 351.602294 -289.231324) (xy 351.584431 -289.247316) (xy 351.54394 -289.27298)
			(xy 351.499363 -289.290617) (xy 351.452273 -289.299603) (xy 351.428304 -289.300158) (xy 351.34169 -289.300158)
			(xy 351.326722 -289.300686) (xy 351.298069 -289.309353) (xy 351.273151 -289.325942) (xy 351.2541 -289.349033)
			(xy 351.242548 -289.376649) (xy 351.239484 -289.406428) (xy 351.245169 -289.435818) (xy 351.251774 -289.449256)
			(xy 351.267522 -289.478466) (xy 351.291652 -289.483038) (xy 351.31657 -289.488131) (xy 351.364563 -289.50496)
			(xy 351.409403 -289.528957) (xy 351.450027 -289.559553) (xy 351.485472 -289.596024) (xy 351.514898 -289.637504)
			(xy 351.537608 -289.68301) (xy 351.553061 -289.731463) (xy 351.560893 -289.781713) (xy 351.5614 -289.807142)
			(xy 367.818924 -289.807142) (xy 367.819411 -289.781712) (xy 367.827244 -289.73146) (xy 367.842699 -289.683005)
			(xy 367.86541 -289.637498) (xy 367.894839 -289.596018) (xy 367.930287 -289.559547) (xy 367.970914 -289.528951)
			(xy 368.015757 -289.504956) (xy 368.063753 -289.48813) (xy 368.088672 -289.483038) (xy 368.112802 -289.478466)
			(xy 368.327178 -289.073082) (xy 368.317272 -289.050476) (xy 368.308309 -289.029398) (xy 368.295664 -288.985377)
			(xy 368.289249 -288.940026) (xy 368.288824 -288.917126) (xy 368.289332 -288.891219) (xy 368.297438 -288.840042)
			(xy 368.31345 -288.790763) (xy 368.336973 -288.744596) (xy 368.367429 -288.702677) (xy 368.404067 -288.666039)
			(xy 368.445986 -288.635583) (xy 368.492153 -288.61206) (xy 368.541432 -288.596048) (xy 368.592609 -288.587942)
			(xy 368.644423 -288.587942) (xy 368.6956 -288.596048) (xy 368.744879 -288.61206) (xy 368.791046 -288.635583)
			(xy 368.832965 -288.666039) (xy 368.869603 -288.702677) (xy 368.900059 -288.744596) (xy 368.923582 -288.790763)
			(xy 368.939594 -288.840042) (xy 368.9477 -288.891219) (xy 368.948208 -288.917126) (xy 368.947753 -288.942575)
			(xy 368.939949 -288.992871) (xy 368.924499 -289.041367) (xy 368.901771 -289.086909) (xy 368.872307 -289.128411)
			(xy 368.836809 -289.164887) (xy 368.796121 -289.195466) (xy 368.751213 -289.21942) (xy 368.703153 -289.23618)
			(xy 368.678206 -289.24123) (xy 368.654076 -289.245802) (xy 368.4397 -289.651186) (xy 368.449606 -289.673792)
			(xy 368.458528 -289.694877) (xy 368.471078 -289.738907) (xy 368.47741 -289.78425) (xy 368.4778 -289.807142)
			(xy 368.477292 -289.833029) (xy 368.469193 -289.884167) (xy 368.453194 -289.933407) (xy 368.429688 -289.979539)
			(xy 368.399256 -290.021426) (xy 368.362646 -290.058036) (xy 368.320759 -290.088468) (xy 368.274627 -290.111974)
			(xy 368.225387 -290.127973) (xy 368.174249 -290.136072) (xy 368.122475 -290.136072) (xy 368.071337 -290.127973)
			(xy 368.022097 -290.111974) (xy 367.975965 -290.088468) (xy 367.934078 -290.058036) (xy 367.897468 -290.021426)
			(xy 367.867036 -289.979539) (xy 367.84353 -289.933407) (xy 367.827531 -289.884167) (xy 367.819432 -289.833029)
			(xy 367.818924 -289.807142) (xy 351.5614 -289.807142) (xy 351.560892 -289.833029) (xy 351.552793 -289.884167)
			(xy 351.536794 -289.933407) (xy 351.513288 -289.979539) (xy 351.482856 -290.021426) (xy 351.446246 -290.058036)
			(xy 351.404359 -290.088468) (xy 351.358227 -290.111974) (xy 351.308987 -290.127973) (xy 351.257849 -290.136072)
			(xy 351.206075 -290.136072) (xy 351.154937 -290.127973) (xy 351.105697 -290.111974) (xy 351.059565 -290.088468)
			(xy 351.017678 -290.058036) (xy 350.981068 -290.021426) (xy 350.950636 -289.979539) (xy 350.92713 -289.933407)
			(xy 350.911131 -289.884167) (xy 350.903032 -289.833029) (xy 350.902524 -289.807142) (xy 350.902903 -289.784208)
			(xy 350.909231 -289.738781) (xy 350.9218 -289.69467) (xy 350.930718 -289.673538) (xy 350.940624 -289.650932)
			(xy 350.755712 -289.300158) (xy 349.46209 -289.300158) (xy 349.447122 -289.300686) (xy 349.418469 -289.309353)
			(xy 349.393551 -289.325942) (xy 349.3745 -289.349033) (xy 349.362948 -289.376649) (xy 349.359884 -289.406428)
			(xy 349.365569 -289.435818) (xy 349.372174 -289.449256) (xy 349.387922 -289.478466) (xy 349.412052 -289.483038)
			(xy 349.43697 -289.488131) (xy 349.484963 -289.50496) (xy 349.529803 -289.528957) (xy 349.570427 -289.559553)
			(xy 349.605872 -289.596024) (xy 349.635298 -289.637504) (xy 349.658008 -289.68301) (xy 349.673461 -289.731463)
			(xy 349.681293 -289.781713) (xy 349.6818 -289.807142) (xy 349.681292 -289.833029) (xy 349.673193 -289.884167)
			(xy 349.657194 -289.933407) (xy 349.633688 -289.979539) (xy 349.603256 -290.021426) (xy 349.566646 -290.058036)
			(xy 349.524759 -290.088468) (xy 349.478627 -290.111974) (xy 349.429387 -290.127973) (xy 349.378249 -290.136072)
			(xy 349.326475 -290.136072) (xy 349.275337 -290.127973) (xy 349.226097 -290.111974) (xy 349.179965 -290.088468)
			(xy 349.138078 -290.058036) (xy 349.101468 -290.021426) (xy 349.071036 -289.979539) (xy 349.04753 -289.933407)
			(xy 349.031531 -289.884167) (xy 349.023432 -289.833029) (xy 349.022924 -289.807142) (xy 349.023303 -289.784208)
			(xy 349.029631 -289.738781) (xy 349.0422 -289.69467) (xy 349.051118 -289.673538) (xy 349.061024 -289.650932)
			(xy 348.876112 -289.300158) (xy 347.58249 -289.300158) (xy 347.567522 -289.300686) (xy 347.538869 -289.309353)
			(xy 347.513951 -289.325942) (xy 347.4949 -289.349033) (xy 347.483348 -289.376649) (xy 347.480284 -289.406428)
			(xy 347.485969 -289.435818) (xy 347.492574 -289.449256) (xy 347.508322 -289.478466) (xy 347.532452 -289.483038)
			(xy 347.55737 -289.488131) (xy 347.605363 -289.50496) (xy 347.650203 -289.528957) (xy 347.690827 -289.559553)
			(xy 347.726272 -289.596024) (xy 347.755698 -289.637504) (xy 347.778408 -289.68301) (xy 347.793861 -289.731463)
			(xy 347.801693 -289.781713) (xy 347.8022 -289.807142) (xy 347.801692 -289.833029) (xy 347.793593 -289.884167)
			(xy 347.777594 -289.933407) (xy 347.754088 -289.979539) (xy 347.723656 -290.021426) (xy 347.687046 -290.058036)
			(xy 347.645159 -290.088468) (xy 347.599027 -290.111974) (xy 347.549787 -290.127973) (xy 347.498649 -290.136072)
			(xy 347.446875 -290.136072) (xy 347.395737 -290.127973) (xy 347.346497 -290.111974) (xy 347.300365 -290.088468)
			(xy 347.258478 -290.058036) (xy 347.221868 -290.021426) (xy 347.191436 -289.979539) (xy 347.16793 -289.933407)
			(xy 347.151931 -289.884167) (xy 347.143832 -289.833029) (xy 347.143324 -289.807142) (xy 347.143703 -289.784208)
			(xy 347.150031 -289.738781) (xy 347.1626 -289.69467) (xy 347.171518 -289.673538) (xy 347.181424 -289.650932)
			(xy 346.996512 -289.300158) (xy 345.70289 -289.300158) (xy 345.687922 -289.300686) (xy 345.659269 -289.309353)
			(xy 345.634351 -289.325942) (xy 345.6153 -289.349033) (xy 345.603748 -289.376649) (xy 345.600684 -289.406428)
			(xy 345.606369 -289.435818) (xy 345.612974 -289.449256) (xy 345.628722 -289.478466) (xy 345.652852 -289.483038)
			(xy 345.67777 -289.488131) (xy 345.725763 -289.50496) (xy 345.770603 -289.528957) (xy 345.811227 -289.559553)
			(xy 345.846672 -289.596024) (xy 345.876098 -289.637504) (xy 345.898808 -289.68301) (xy 345.914261 -289.731463)
			(xy 345.922093 -289.781713) (xy 345.9226 -289.807142) (xy 345.922092 -289.833029) (xy 345.913993 -289.884167)
			(xy 345.897994 -289.933407) (xy 345.874488 -289.979539) (xy 345.844056 -290.021426) (xy 345.807446 -290.058036)
			(xy 345.765559 -290.088468) (xy 345.719427 -290.111974) (xy 345.670187 -290.127973) (xy 345.619049 -290.136072)
			(xy 345.567275 -290.136072) (xy 345.516137 -290.127973) (xy 345.466897 -290.111974) (xy 345.420765 -290.088468)
			(xy 345.378878 -290.058036) (xy 345.342268 -290.021426) (xy 345.311836 -289.979539) (xy 345.28833 -289.933407)
			(xy 345.272331 -289.884167) (xy 345.264232 -289.833029) (xy 345.263724 -289.807142) (xy 345.264103 -289.784208)
			(xy 345.270431 -289.738781) (xy 345.283 -289.69467) (xy 345.291918 -289.673538) (xy 345.301824 -289.650932)
			(xy 345.116912 -289.300158) (xy 343.82329 -289.300158) (xy 343.808322 -289.300686) (xy 343.779669 -289.309353)
			(xy 343.754751 -289.325942) (xy 343.7357 -289.349033) (xy 343.724148 -289.376649) (xy 343.721084 -289.406428)
			(xy 343.726769 -289.435818) (xy 343.733374 -289.449256) (xy 343.749122 -289.478466) (xy 343.773252 -289.483038)
			(xy 343.79817 -289.488131) (xy 343.846163 -289.50496) (xy 343.891003 -289.528957) (xy 343.931627 -289.559553)
			(xy 343.967072 -289.596024) (xy 343.996498 -289.637504) (xy 344.019208 -289.68301) (xy 344.034661 -289.731463)
			(xy 344.042493 -289.781713) (xy 344.043 -289.807142) (xy 344.042492 -289.833029) (xy 344.034393 -289.884167)
			(xy 344.018394 -289.933407) (xy 343.994888 -289.979539) (xy 343.964456 -290.021426) (xy 343.927846 -290.058036)
			(xy 343.885959 -290.088468) (xy 343.839827 -290.111974) (xy 343.790587 -290.127973) (xy 343.739449 -290.136072)
			(xy 343.687675 -290.136072) (xy 343.636537 -290.127973) (xy 343.587297 -290.111974) (xy 343.541165 -290.088468)
			(xy 343.499278 -290.058036) (xy 343.462668 -290.021426) (xy 343.432236 -289.979539) (xy 343.40873 -289.933407)
			(xy 343.392731 -289.884167) (xy 343.384632 -289.833029) (xy 343.384124 -289.807142) (xy 343.384503 -289.784208)
			(xy 343.390831 -289.738781) (xy 343.4034 -289.69467) (xy 343.412318 -289.673538) (xy 343.422224 -289.650932)
			(xy 343.237312 -289.300158) (xy 341.94369 -289.300158) (xy 341.928722 -289.300686) (xy 341.900069 -289.309353)
			(xy 341.875151 -289.325942) (xy 341.8561 -289.349033) (xy 341.844548 -289.376649) (xy 341.841484 -289.406428)
			(xy 341.847169 -289.435818) (xy 341.853774 -289.449256) (xy 341.869522 -289.478466) (xy 341.893652 -289.483038)
			(xy 341.91857 -289.488131) (xy 341.966563 -289.50496) (xy 342.011403 -289.528957) (xy 342.052027 -289.559553)
			(xy 342.087472 -289.596024) (xy 342.116898 -289.637504) (xy 342.139608 -289.68301) (xy 342.155061 -289.731463)
			(xy 342.162893 -289.781713) (xy 342.1634 -289.807142) (xy 342.162892 -289.833029) (xy 342.154793 -289.884167)
			(xy 342.138794 -289.933407) (xy 342.115288 -289.979539) (xy 342.084856 -290.021426) (xy 342.048246 -290.058036)
			(xy 342.006359 -290.088468) (xy 341.960227 -290.111974) (xy 341.910987 -290.127973) (xy 341.859849 -290.136072)
			(xy 341.808075 -290.136072) (xy 341.756937 -290.127973) (xy 341.707697 -290.111974) (xy 341.661565 -290.088468)
			(xy 341.619678 -290.058036) (xy 341.583068 -290.021426) (xy 341.552636 -289.979539) (xy 341.52913 -289.933407)
			(xy 341.513131 -289.884167) (xy 341.505032 -289.833029) (xy 341.504524 -289.807142) (xy 341.504903 -289.784208)
			(xy 341.511231 -289.738781) (xy 341.5238 -289.69467) (xy 341.532718 -289.673538) (xy 341.542624 -289.650932)
			(xy 341.357712 -289.300158) (xy 340.06409 -289.300158) (xy 340.049122 -289.300686) (xy 340.020469 -289.309353)
			(xy 339.995551 -289.325942) (xy 339.9765 -289.349033) (xy 339.964948 -289.376649) (xy 339.961884 -289.406428)
			(xy 339.967569 -289.435818) (xy 339.974174 -289.449256) (xy 339.989922 -289.478466) (xy 340.014052 -289.483038)
			(xy 340.03897 -289.488131) (xy 340.086963 -289.50496) (xy 340.131803 -289.528957) (xy 340.172427 -289.559553)
			(xy 340.207872 -289.596024) (xy 340.237298 -289.637504) (xy 340.260008 -289.68301) (xy 340.275461 -289.731463)
			(xy 340.283293 -289.781713) (xy 340.2838 -289.807142) (xy 340.283292 -289.833029) (xy 340.275193 -289.884167)
			(xy 340.259194 -289.933407) (xy 340.235688 -289.979539) (xy 340.205256 -290.021426) (xy 340.168646 -290.058036)
			(xy 340.126759 -290.088468) (xy 340.080627 -290.111974) (xy 340.031387 -290.127973) (xy 339.980249 -290.136072)
			(xy 339.928475 -290.136072) (xy 339.877337 -290.127973) (xy 339.828097 -290.111974) (xy 339.781965 -290.088468)
			(xy 339.740078 -290.058036) (xy 339.703468 -290.021426) (xy 339.673036 -289.979539) (xy 339.64953 -289.933407)
			(xy 339.633531 -289.884167) (xy 339.625432 -289.833029) (xy 339.624924 -289.807142) (xy 339.625303 -289.784208)
			(xy 339.631631 -289.738781) (xy 339.6442 -289.69467) (xy 339.653118 -289.673538) (xy 339.663024 -289.650932)
			(xy 339.478112 -289.300158) (xy 330.402946 -289.300158) (xy 322.729098 -296.974006) (xy 322.729098 -297.515026)
			(xy 336.155548 -297.515026) (xy 336.159529 -297.382006) (xy 336.171458 -297.249461) (xy 336.191293 -297.117868)
			(xy 336.218962 -296.987696) (xy 336.254366 -296.859411) (xy 336.297379 -296.733474) (xy 336.347846 -296.610335)
			(xy 336.405587 -296.490434) (xy 336.470396 -296.374201) (xy 336.54204 -296.262051) (xy 336.620262 -296.154387)
			(xy 336.704783 -296.051594) (xy 336.795301 -295.954039) (xy 336.89149 -295.862073) (xy 336.993008 -295.776023)
			(xy 337.099489 -295.696199) (xy 337.210554 -295.622886) (xy 337.325805 -295.556346) (xy 337.444829 -295.496817)
			(xy 337.5672 -295.444513) (xy 337.692479 -295.399621) (xy 337.82022 -295.362302) (xy 337.949963 -295.332689)
			(xy 338.081245 -295.310888) (xy 338.213596 -295.296978) (xy 338.346542 -295.291007) (xy 338.479607 -295.292998)
			(xy 338.612315 -295.302943) (xy 338.744191 -295.320807) (xy 338.874762 -295.346525) (xy 339.003562 -295.380006)
			(xy 339.130128 -295.42113) (xy 339.254009 -295.46975) (xy 339.37476 -295.525691) (xy 339.49195 -295.588753)
			(xy 339.605159 -295.658711) (xy 339.713981 -295.735315) (xy 339.818027 -295.818289) (xy 339.916925 -295.907337)
			(xy 340.01032 -296.00214) (xy 340.097878 -296.102358) (xy 340.179287 -296.207634) (xy 340.254253 -296.31759)
			(xy 340.32251 -296.431832) (xy 340.383812 -296.549952) (xy 340.437941 -296.671527) (xy 340.484702 -296.796121)
			(xy 340.523928 -296.923289) (xy 340.555478 -297.052575) (xy 340.579241 -297.183516) (xy 340.59513 -297.315644)
			(xy 340.603088 -297.448486) (xy 340.603586 -297.515026) (xy 379.13565 -297.515026) (xy 379.139631 -297.382006)
			(xy 379.15156 -297.249461) (xy 379.171395 -297.117868) (xy 379.199064 -296.987696) (xy 379.234468 -296.859411)
			(xy 379.277481 -296.733474) (xy 379.327948 -296.610335) (xy 379.385689 -296.490434) (xy 379.450498 -296.374201)
			(xy 379.522142 -296.262051) (xy 379.600364 -296.154387) (xy 379.684885 -296.051594) (xy 379.775403 -295.954039)
			(xy 379.871592 -295.862073) (xy 379.97311 -295.776023) (xy 380.079591 -295.696199) (xy 380.190656 -295.622886)
			(xy 380.305907 -295.556346) (xy 380.424931 -295.496817) (xy 380.547302 -295.444513) (xy 380.672581 -295.399621)
			(xy 380.800322 -295.362302) (xy 380.930065 -295.332689) (xy 381.061347 -295.310888) (xy 381.193698 -295.296978)
			(xy 381.326644 -295.291007) (xy 381.459709 -295.292998) (xy 381.592417 -295.302943) (xy 381.724293 -295.320807)
			(xy 381.854864 -295.346525) (xy 381.983664 -295.380006) (xy 382.11023 -295.42113) (xy 382.234111 -295.46975)
			(xy 382.354862 -295.525691) (xy 382.472052 -295.588753) (xy 382.585261 -295.658711) (xy 382.694083 -295.735315)
			(xy 382.798129 -295.818289) (xy 382.897027 -295.907337) (xy 382.990422 -296.00214) (xy 383.07798 -296.102358)
			(xy 383.159389 -296.207634) (xy 383.234355 -296.31759) (xy 383.302612 -296.431832) (xy 383.363914 -296.549952)
			(xy 383.418043 -296.671527) (xy 383.464804 -296.796121) (xy 383.50403 -296.923289) (xy 383.53558 -297.052575)
			(xy 383.559343 -297.183516) (xy 383.575232 -297.315644) (xy 383.58319 -297.448486) (xy 383.583688 -297.515026)
			(xy 383.58319 -297.581566) (xy 383.575232 -297.714408) (xy 383.559343 -297.846536) (xy 383.53558 -297.977477)
			(xy 383.50403 -298.106763) (xy 383.464804 -298.233931) (xy 383.418043 -298.358525) (xy 383.363914 -298.4801)
			(xy 383.302612 -298.59822) (xy 383.234355 -298.712462) (xy 383.159389 -298.822418) (xy 383.07798 -298.927694)
			(xy 382.990422 -299.027912) (xy 382.897027 -299.122715) (xy 382.798129 -299.211763) (xy 382.694083 -299.294737)
			(xy 382.585261 -299.371341) (xy 382.472052 -299.441299) (xy 382.354862 -299.504361) (xy 382.234111 -299.560302)
			(xy 382.11023 -299.608922) (xy 381.983664 -299.650046) (xy 381.854864 -299.683527) (xy 381.724293 -299.709245)
			(xy 381.592417 -299.727109) (xy 381.459709 -299.737054) (xy 381.326644 -299.739045) (xy 381.193698 -299.733074)
			(xy 381.061347 -299.719164) (xy 380.930065 -299.697363) (xy 380.800322 -299.66775) (xy 380.672581 -299.630431)
			(xy 380.547302 -299.585539) (xy 380.424931 -299.533235) (xy 380.305907 -299.473706) (xy 380.190656 -299.407166)
			(xy 380.079591 -299.333853) (xy 379.97311 -299.254029) (xy 379.871592 -299.167979) (xy 379.775403 -299.076013)
			(xy 379.684885 -298.978458) (xy 379.600364 -298.875665) (xy 379.522142 -298.768001) (xy 379.450498 -298.655851)
			(xy 379.385689 -298.539618) (xy 379.327948 -298.419717) (xy 379.277481 -298.296578) (xy 379.234468 -298.170641)
			(xy 379.199064 -298.042356) (xy 379.171395 -297.912184) (xy 379.15156 -297.780591) (xy 379.139631 -297.648046)
			(xy 379.13565 -297.515026) (xy 340.603586 -297.515026) (xy 340.603088 -297.581566) (xy 340.59513 -297.714408)
			(xy 340.579241 -297.846536) (xy 340.555478 -297.977477) (xy 340.523928 -298.106763) (xy 340.484702 -298.233931)
			(xy 340.437941 -298.358525) (xy 340.383812 -298.4801) (xy 340.32251 -298.59822) (xy 340.254253 -298.712462)
			(xy 340.179287 -298.822418) (xy 340.097878 -298.927694) (xy 340.01032 -299.027912) (xy 339.916925 -299.122715)
			(xy 339.818027 -299.211763) (xy 339.713981 -299.294737) (xy 339.605159 -299.371341) (xy 339.49195 -299.441299)
			(xy 339.37476 -299.504361) (xy 339.254009 -299.560302) (xy 339.130128 -299.608922) (xy 339.003562 -299.650046)
			(xy 338.874762 -299.683527) (xy 338.744191 -299.709245) (xy 338.612315 -299.727109) (xy 338.479607 -299.737054)
			(xy 338.346542 -299.739045) (xy 338.213596 -299.733074) (xy 338.081245 -299.719164) (xy 337.949963 -299.697363)
			(xy 337.82022 -299.66775) (xy 337.692479 -299.630431) (xy 337.5672 -299.585539) (xy 337.444829 -299.533235)
			(xy 337.325805 -299.473706) (xy 337.210554 -299.407166) (xy 337.099489 -299.333853) (xy 336.993008 -299.254029)
			(xy 336.89149 -299.167979) (xy 336.795301 -299.076013) (xy 336.704783 -298.978458) (xy 336.620262 -298.875665)
			(xy 336.54204 -298.768001) (xy 336.470396 -298.655851) (xy 336.405587 -298.539618) (xy 336.347846 -298.419717)
			(xy 336.297379 -298.296578) (xy 336.254366 -298.170641) (xy 336.218962 -298.042356) (xy 336.191293 -297.912184)
			(xy 336.171458 -297.780591) (xy 336.159529 -297.648046) (xy 336.155548 -297.515026) (xy 322.729098 -297.515026)
			(xy 322.729098 -331.869034) (xy 323.104256 -332.244192) (xy 329.74026 -332.244192)
		)
		(stroke
			(width 0)
			(type solid)
		)
		(fill yes)
		(layer "In9.Cu")
		(net "PVCCIN_CPU0")
	)
	(gr_poly
		(pts
			(xy 79.7941 -330.372212) (xy 79.812141 -330.354954) (xy 79.853635 -330.3272) (xy 79.899754 -330.308092)
			(xy 79.948718 -330.298368) (xy 79.973678 -330.29779) (xy 83.488022 -330.29779) (xy 84.600542 -329.18527)
			(xy 84.600542 -327.37171) (xy 84.601122 -327.346753) (xy 84.610877 -327.297802) (xy 84.629995 -327.251695)
			(xy 84.657741 -327.210203) (xy 84.674964 -327.192132) (xy 85.589364 -326.277732) (xy 85.607406 -326.260475)
			(xy 85.648901 -326.232724) (xy 85.695019 -326.213616) (xy 85.743982 -326.203889) (xy 85.768942 -326.20331)
			(xy 91.353386 -326.20331) (xy 92.525342 -325.031354) (xy 92.525342 -323.46011) (xy 92.525922 -323.435153)
			(xy 92.535677 -323.386202) (xy 92.554795 -323.340095) (xy 92.582541 -323.298603) (xy 92.599764 -323.280532)
			(xy 93.082364 -322.797932) (xy 93.100406 -322.780675) (xy 93.141901 -322.752924) (xy 93.188019 -322.733816)
			(xy 93.236982 -322.724089) (xy 93.261942 -322.72351) (xy 125.062742 -322.72351) (xy 125.087697 -322.724126)
			(xy 125.136646 -322.73387) (xy 125.182754 -322.752977) (xy 125.224248 -322.780712) (xy 125.24232 -322.797932)
			(xy 125.90272 -323.458332) (xy 125.919982 -323.476372) (xy 125.947744 -323.517865) (xy 125.966861 -323.563983)
			(xy 125.976596 -323.612948) (xy 125.977142 -323.63791) (xy 125.977142 -324.878954) (xy 127.352298 -326.25411)
			(xy 131.438142 -326.25411) (xy 131.463097 -326.254726) (xy 131.512046 -326.26447) (xy 131.558154 -326.283577)
			(xy 131.599648 -326.311312) (xy 131.61772 -326.328532) (xy 134.00532 -328.716132) (xy 134.022582 -328.734172)
			(xy 134.050344 -328.775665) (xy 134.069461 -328.821783) (xy 134.079196 -328.870748) (xy 134.079742 -328.89571)
			(xy 134.079742 -331.127354) (xy 134.362698 -331.41031) (xy 144.253204 -331.41031) (xy 144.258469 -331.403506)
			(xy 144.269783 -331.390542) (xy 144.27581 -331.384402) (xy 144.626838 -331.033374) (xy 144.626838 -296.608246)
			(xy 137.343388 -289.324796) (xy 133.829298 -289.324796) (xy 133.656832 -289.651186) (xy 133.666738 -289.673792)
			(xy 133.675642 -289.694884) (xy 133.688193 -289.738911) (xy 133.694526 -289.784251) (xy 133.694932 -289.807142)
			(xy 133.694424 -289.833029) (xy 133.686325 -289.884167) (xy 133.670326 -289.933407) (xy 133.64682 -289.979539)
			(xy 133.616388 -290.021426) (xy 133.579778 -290.058036) (xy 133.537891 -290.088468) (xy 133.491759 -290.111974)
			(xy 133.442519 -290.127973) (xy 133.391381 -290.136072) (xy 133.339607 -290.136072) (xy 133.288469 -290.127973)
			(xy 133.239229 -290.111974) (xy 133.193097 -290.088468) (xy 133.15121 -290.058036) (xy 133.1146 -290.021426)
			(xy 133.084168 -289.979539) (xy 133.060662 -289.933407) (xy 133.044663 -289.884167) (xy 133.036564 -289.833029)
			(xy 133.036056 -289.807142) (xy 133.036525 -289.781708) (xy 133.044335 -289.731443) (xy 133.059776 -289.682976)
			(xy 133.082481 -289.637456) (xy 133.111911 -289.595967) (xy 133.147367 -289.559492) (xy 133.188007 -289.528899)
			(xy 133.232865 -289.504913) (xy 133.280876 -289.488106) (xy 133.305804 -289.483038) (xy 133.329934 -289.478466)
			(xy 133.371844 -289.399218) (xy 133.376263 -289.389706) (xy 133.377788 -289.368811) (xy 133.370838 -289.349046)
			(xy 133.356571 -289.333703) (xy 133.337362 -289.325338) (xy 133.326886 -289.324796) (xy 131.949698 -289.324796)
			(xy 131.777232 -289.651186) (xy 131.787138 -289.673792) (xy 131.796042 -289.694884) (xy 131.808593 -289.738911)
			(xy 131.814926 -289.784251) (xy 131.815332 -289.807142) (xy 131.814824 -289.833029) (xy 131.806725 -289.884167)
			(xy 131.790726 -289.933407) (xy 131.76722 -289.979539) (xy 131.736788 -290.021426) (xy 131.700178 -290.058036)
			(xy 131.658291 -290.088468) (xy 131.612159 -290.111974) (xy 131.562919 -290.127973) (xy 131.511781 -290.136072)
			(xy 131.460007 -290.136072) (xy 131.408869 -290.127973) (xy 131.359629 -290.111974) (xy 131.313497 -290.088468)
			(xy 131.27161 -290.058036) (xy 131.235 -290.021426) (xy 131.204568 -289.979539) (xy 131.181062 -289.933407)
			(xy 131.165063 -289.884167) (xy 131.156964 -289.833029) (xy 131.156456 -289.807142) (xy 131.156925 -289.781708)
			(xy 131.164735 -289.731443) (xy 131.180176 -289.682976) (xy 131.202881 -289.637456) (xy 131.232311 -289.595967)
			(xy 131.267767 -289.559492) (xy 131.308407 -289.528899) (xy 131.353265 -289.504913) (xy 131.401276 -289.488106)
			(xy 131.426204 -289.483038) (xy 131.450334 -289.478466) (xy 131.492244 -289.399218) (xy 131.496663 -289.389706)
			(xy 131.498188 -289.368811) (xy 131.491238 -289.349046) (xy 131.476971 -289.333703) (xy 131.457762 -289.325338)
			(xy 131.447286 -289.324796) (xy 130.070098 -289.324796) (xy 129.897632 -289.651186) (xy 129.907538 -289.673792)
			(xy 129.916442 -289.694884) (xy 129.928993 -289.738911) (xy 129.935326 -289.784251) (xy 129.935732 -289.807142)
			(xy 129.935224 -289.833029) (xy 129.927125 -289.884167) (xy 129.911126 -289.933407) (xy 129.88762 -289.979539)
			(xy 129.857188 -290.021426) (xy 129.820578 -290.058036) (xy 129.778691 -290.088468) (xy 129.732559 -290.111974)
			(xy 129.683319 -290.127973) (xy 129.632181 -290.136072) (xy 129.580407 -290.136072) (xy 129.529269 -290.127973)
			(xy 129.480029 -290.111974) (xy 129.433897 -290.088468) (xy 129.39201 -290.058036) (xy 129.3554 -290.021426)
			(xy 129.324968 -289.979539) (xy 129.301462 -289.933407) (xy 129.285463 -289.884167) (xy 129.277364 -289.833029)
			(xy 129.276856 -289.807142) (xy 129.277325 -289.781708) (xy 129.285135 -289.731443) (xy 129.300576 -289.682976)
			(xy 129.323281 -289.637456) (xy 129.352711 -289.595967) (xy 129.388167 -289.559492) (xy 129.428807 -289.528899)
			(xy 129.473665 -289.504913) (xy 129.521676 -289.488106) (xy 129.546604 -289.483038) (xy 129.570734 -289.478466)
			(xy 129.612644 -289.399218) (xy 129.617063 -289.389706) (xy 129.618588 -289.368811) (xy 129.611638 -289.349046)
			(xy 129.597371 -289.333703) (xy 129.578162 -289.325338) (xy 129.567686 -289.324796) (xy 128.190498 -289.324796)
			(xy 128.018032 -289.651186) (xy 128.027938 -289.673792) (xy 128.036842 -289.694884) (xy 128.049393 -289.738911)
			(xy 128.055726 -289.784251) (xy 128.056132 -289.807142) (xy 128.055624 -289.833029) (xy 128.047525 -289.884167)
			(xy 128.031526 -289.933407) (xy 128.00802 -289.979539) (xy 127.977588 -290.021426) (xy 127.940978 -290.058036)
			(xy 127.899091 -290.088468) (xy 127.852959 -290.111974) (xy 127.803719 -290.127973) (xy 127.752581 -290.136072)
			(xy 127.700807 -290.136072) (xy 127.649669 -290.127973) (xy 127.600429 -290.111974) (xy 127.554297 -290.088468)
			(xy 127.51241 -290.058036) (xy 127.4758 -290.021426) (xy 127.445368 -289.979539) (xy 127.421862 -289.933407)
			(xy 127.405863 -289.884167) (xy 127.397764 -289.833029) (xy 127.397256 -289.807142) (xy 127.397725 -289.781708)
			(xy 127.405535 -289.731443) (xy 127.420976 -289.682976) (xy 127.443681 -289.637456) (xy 127.473111 -289.595967)
			(xy 127.508567 -289.559492) (xy 127.549207 -289.528899) (xy 127.594065 -289.504913) (xy 127.642076 -289.488106)
			(xy 127.667004 -289.483038) (xy 127.691134 -289.478466) (xy 127.733044 -289.399218) (xy 127.737463 -289.389706)
			(xy 127.738988 -289.368811) (xy 127.732038 -289.349046) (xy 127.717771 -289.333703) (xy 127.698562 -289.325338)
			(xy 127.688086 -289.324796) (xy 126.310898 -289.324796) (xy 126.138432 -289.651186) (xy 126.148338 -289.673792)
			(xy 126.157242 -289.694884) (xy 126.169793 -289.738911) (xy 126.176126 -289.784251) (xy 126.176532 -289.807142)
			(xy 126.176024 -289.833029) (xy 126.167925 -289.884167) (xy 126.151926 -289.933407) (xy 126.12842 -289.979539)
			(xy 126.097988 -290.021426) (xy 126.061378 -290.058036) (xy 126.019491 -290.088468) (xy 125.973359 -290.111974)
			(xy 125.924119 -290.127973) (xy 125.872981 -290.136072) (xy 125.821207 -290.136072) (xy 125.770069 -290.127973)
			(xy 125.720829 -290.111974) (xy 125.674697 -290.088468) (xy 125.63281 -290.058036) (xy 125.5962 -290.021426)
			(xy 125.565768 -289.979539) (xy 125.542262 -289.933407) (xy 125.526263 -289.884167) (xy 125.518164 -289.833029)
			(xy 125.517656 -289.807142) (xy 125.518125 -289.781708) (xy 125.525935 -289.731443) (xy 125.541376 -289.682976)
			(xy 125.564081 -289.637456) (xy 125.593511 -289.595967) (xy 125.628967 -289.559492) (xy 125.669607 -289.528899)
			(xy 125.714465 -289.504913) (xy 125.762476 -289.488106) (xy 125.787404 -289.483038) (xy 125.811534 -289.478466)
			(xy 125.853444 -289.399218) (xy 125.857863 -289.389706) (xy 125.859388 -289.368811) (xy 125.852438 -289.349046)
			(xy 125.838171 -289.333703) (xy 125.818962 -289.325338) (xy 125.808486 -289.324796) (xy 124.431298 -289.324796)
			(xy 124.258832 -289.651186) (xy 124.268738 -289.673792) (xy 124.277642 -289.694884) (xy 124.290193 -289.738911)
			(xy 124.296526 -289.784251) (xy 124.296932 -289.807142) (xy 124.296424 -289.833029) (xy 124.288325 -289.884167)
			(xy 124.272326 -289.933407) (xy 124.24882 -289.979539) (xy 124.218388 -290.021426) (xy 124.181778 -290.058036)
			(xy 124.139891 -290.088468) (xy 124.093759 -290.111974) (xy 124.044519 -290.127973) (xy 123.993381 -290.136072)
			(xy 123.941607 -290.136072) (xy 123.890469 -290.127973) (xy 123.841229 -290.111974) (xy 123.795097 -290.088468)
			(xy 123.75321 -290.058036) (xy 123.7166 -290.021426) (xy 123.686168 -289.979539) (xy 123.662662 -289.933407)
			(xy 123.646663 -289.884167) (xy 123.638564 -289.833029) (xy 123.638056 -289.807142) (xy 123.638525 -289.781708)
			(xy 123.646335 -289.731443) (xy 123.661776 -289.682976) (xy 123.684481 -289.637456) (xy 123.713911 -289.595967)
			(xy 123.749367 -289.559492) (xy 123.790007 -289.528899) (xy 123.834865 -289.504913) (xy 123.882876 -289.488106)
			(xy 123.907804 -289.483038) (xy 123.931934 -289.478466) (xy 123.973844 -289.399218) (xy 123.978263 -289.389706)
			(xy 123.979788 -289.368811) (xy 123.972838 -289.349046) (xy 123.958571 -289.333703) (xy 123.939362 -289.325338)
			(xy 123.928886 -289.324796) (xy 122.551698 -289.324796) (xy 122.379232 -289.651186) (xy 122.389138 -289.673792)
			(xy 122.398042 -289.694884) (xy 122.410593 -289.738911) (xy 122.416926 -289.784251) (xy 122.417332 -289.807142)
			(xy 122.416824 -289.833029) (xy 122.408725 -289.884167) (xy 122.392726 -289.933407) (xy 122.36922 -289.979539)
			(xy 122.338788 -290.021426) (xy 122.302178 -290.058036) (xy 122.260291 -290.088468) (xy 122.214159 -290.111974)
			(xy 122.164919 -290.127973) (xy 122.113781 -290.136072) (xy 122.062007 -290.136072) (xy 122.010869 -290.127973)
			(xy 121.961629 -290.111974) (xy 121.915497 -290.088468) (xy 121.87361 -290.058036) (xy 121.837 -290.021426)
			(xy 121.806568 -289.979539) (xy 121.783062 -289.933407) (xy 121.767063 -289.884167) (xy 121.758964 -289.833029)
			(xy 121.758456 -289.807142) (xy 121.758925 -289.781708) (xy 121.766735 -289.731443) (xy 121.782176 -289.682976)
			(xy 121.804881 -289.637456) (xy 121.834311 -289.595967) (xy 121.869767 -289.559492) (xy 121.910407 -289.528899)
			(xy 121.955265 -289.504913) (xy 122.003276 -289.488106) (xy 122.028204 -289.483038) (xy 122.052334 -289.478466)
			(xy 122.094244 -289.399218) (xy 122.098663 -289.389706) (xy 122.100188 -289.368811) (xy 122.093238 -289.349046)
			(xy 122.078971 -289.333703) (xy 122.059762 -289.325338) (xy 122.049286 -289.324796) (xy 121.76252 -289.324796)
			(xy 121.737567 -289.324177) (xy 121.688621 -289.314426) (xy 121.642518 -289.295315) (xy 121.601029 -289.267577)
			(xy 121.582942 -289.250374) (xy 121.576592 -289.244024) (xy 121.550405 -289.240181) (xy 121.499636 -289.225231)
			(xy 121.451911 -289.202354) (xy 121.40846 -289.172138) (xy 121.3704 -289.135363) (xy 121.338711 -289.092974)
			(xy 121.314209 -289.046062) (xy 121.297525 -288.995836) (xy 121.289089 -288.943589) (xy 121.288556 -288.917126)
			(xy 121.288944 -288.895793) (xy 121.294555 -288.853497) (xy 121.299732 -288.832798) (xy 121.305066 -288.812732)
			(xy 121.083832 -288.426906) (xy 121.063258 -288.421572) (xy 121.03731 -288.414077) (xy 120.988103 -288.391817)
			(xy 120.943182 -288.361835) (xy 120.903747 -288.324935) (xy 120.870852 -288.282101) (xy 120.845376 -288.23448)
			(xy 120.828002 -288.183344) (xy 120.819192 -288.13006) (xy 120.818656 -288.103056) (xy 120.819045 -288.080934)
			(xy 120.825029 -288.037094) (xy 120.830594 -288.01568) (xy 120.836182 -287.995106) (xy 120.616726 -287.612328)
			(xy 120.595898 -287.606994) (xy 120.569859 -287.599684) (xy 120.520436 -287.57773) (xy 120.475283 -287.547968)
			(xy 120.435622 -287.511203) (xy 120.402528 -287.468431) (xy 120.376897 -287.420811) (xy 120.359423 -287.369632)
			(xy 120.35058 -287.31628) (xy 120.350026 -287.28924) (xy 120.350403 -287.26659) (xy 120.356645 -287.221723)
			(xy 120.362472 -287.199832) (xy 120.368314 -287.179258) (xy 120.151398 -286.800798) (xy 120.130062 -286.795464)
			(xy 120.106492 -286.789248) (xy 120.061365 -286.770818) (xy 120.019447 -286.745939) (xy 119.981654 -286.715154)
			(xy 119.94881 -286.679136) (xy 119.921633 -286.63867) (xy 119.900716 -286.594641) (xy 119.886516 -286.548011)
			(xy 119.879343 -286.499797) (xy 119.878856 -286.475424) (xy 119.879275 -286.451585) (xy 119.886161 -286.404408)
			(xy 119.892572 -286.381444) (xy 119.898922 -286.360616) (xy 119.6848 -285.987236) (xy 119.663464 -285.982156)
			(xy 119.639649 -285.976128) (xy 119.594 -285.957977) (xy 119.551553 -285.93325) (xy 119.513247 -285.902495)
			(xy 119.479932 -285.866393) (xy 119.452347 -285.825745) (xy 119.431102 -285.781452) (xy 119.416669 -285.734495)
			(xy 119.409367 -285.685916) (xy 119.408956 -285.661354) (xy 119.409336 -285.636658) (xy 119.416602 -285.587807)
			(xy 119.423434 -285.564072) (xy 119.430038 -285.54299) (xy 119.218456 -285.173928) (xy 119.196612 -285.169102)
			(xy 119.172564 -285.163275) (xy 119.12643 -285.145385) (xy 119.083492 -285.120795) (xy 119.044716 -285.090058)
			(xy 119.010975 -285.053866) (xy 118.983028 -285.013033) (xy 118.961505 -284.968479) (xy 118.94689 -284.921206)
			(xy 118.939511 -284.872279) (xy 118.939056 -284.847538) (xy 118.939551 -284.822033) (xy 118.947462 -284.771639)
			(xy 118.954804 -284.747208) (xy 118.961662 -284.725872) (xy 118.75135 -284.35935) (xy 118.729252 -284.354524)
			(xy 118.705131 -284.348853) (xy 118.658821 -284.331233) (xy 118.615687 -284.306849) (xy 118.57671 -284.276258)
			(xy 118.542776 -284.240153) (xy 118.514656 -284.199356) (xy 118.49299 -284.154796) (xy 118.47827 -284.107484)
			(xy 118.470832 -284.058496) (xy 118.470426 -284.033722) (xy 118.47092 -284.007751) (xy 118.479082 -283.956453)
			(xy 118.486682 -283.931614) (xy 118.493794 -283.910024) (xy 118.285006 -283.546042) (xy 118.262654 -283.541216)
			(xy 118.238329 -283.535715) (xy 118.19158 -283.518352) (xy 118.147995 -283.494119) (xy 118.108576 -283.463573)
			(xy 118.07423 -283.427416) (xy 118.045747 -283.386482) (xy 118.023783 -283.34171) (xy 118.008842 -283.294131)
			(xy 118.001269 -283.24484) (xy 118.00078 -283.219906) (xy 118.001331 -283.193195) (xy 118.010017 -283.140484)
			(xy 118.018052 -283.115004) (xy 118.025418 -283.09316) (xy 117.818408 -282.732226) (xy 117.795802 -282.727908)
			(xy 117.771245 -282.722601) (xy 117.723997 -282.705524) (xy 117.679905 -282.681445) (xy 117.639997 -282.650927)
			(xy 117.605208 -282.614682) (xy 117.57635 -282.573559) (xy 117.554097 -282.528517) (xy 117.53897 -282.480609)
			(xy 117.531322 -282.430956) (xy 117.53088 -282.405836) (xy 117.531442 -282.378318) (xy 117.540641 -282.324056)
			(xy 117.549168 -282.297886) (xy 117.556788 -282.276042) (xy 117.352064 -281.918918) (xy 117.32895 -281.9146)
			(xy 117.30418 -281.909499) (xy 117.256481 -281.892699) (xy 117.211924 -281.86878) (xy 117.171563 -281.83831)
			(xy 117.136355 -281.802008) (xy 117.107131 -281.760735) (xy 117.084586 -281.715468) (xy 117.069251 -281.667278)
			(xy 117.06149 -281.617306) (xy 117.06098 -281.59202) (xy 117.061576 -281.563696) (xy 117.07128 -281.507884)
			(xy 117.080284 -281.481022) (xy 117.088158 -281.458924) (xy 116.885466 -281.10561) (xy 116.862098 -281.101292)
			(xy 116.837115 -281.096383) (xy 116.788954 -281.079875) (xy 116.743919 -281.056129) (xy 116.703091 -281.025713)
			(xy 116.667449 -280.989358) (xy 116.637849 -280.947935) (xy 116.615 -280.902438) (xy 116.59945 -280.853959)
			(xy 116.591573 -280.80366) (xy 116.59108 -280.778204) (xy 116.591694 -280.749072) (xy 116.601923 -280.691713)
			(xy 116.6114 -280.664158) (xy 116.619782 -280.64206) (xy 116.418868 -280.291794) (xy 116.395246 -280.28773)
			(xy 116.370051 -280.283016) (xy 116.321429 -280.266804) (xy 116.275917 -280.243232) (xy 116.234622 -280.212872)
			(xy 116.198548 -280.176463) (xy 116.168572 -280.134888) (xy 116.145423 -280.08916) (xy 116.129663 -280.040389)
			(xy 116.121675 -279.989761) (xy 116.12118 -279.964134) (xy 116.121861 -279.934243) (xy 116.132719 -279.875453)
			(xy 116.14277 -279.847294) (xy 116.151152 -279.824942) (xy 115.952524 -279.478232) (xy 115.928394 -279.474422)
			(xy 115.902968 -279.469945) (xy 115.853849 -279.454056) (xy 115.807821 -279.430675) (xy 115.766021 -279.400378)
			(xy 115.729477 -279.363912) (xy 115.699092 -279.322177) (xy 115.675613 -279.276199) (xy 115.659619 -279.227114)
			(xy 115.651505 -279.17613) (xy 115.651026 -279.150318) (xy 115.65144 -279.126656) (xy 115.658238 -279.079824)
			(xy 115.671697 -279.034456) (xy 115.691537 -278.991492) (xy 115.717346 -278.951826) (xy 115.748587 -278.916282)
			(xy 115.766342 -278.900636) (xy 115.766342 -277.77186) (xy 115.747058 -277.754715) (xy 115.713558 -277.715471)
			(xy 115.686607 -277.671471) (xy 115.666869 -277.623798) (xy 115.654829 -277.573625) (xy 115.650785 -277.522186)
			(xy 115.654834 -277.470747) (xy 115.666878 -277.420575) (xy 115.68662 -277.372903) (xy 115.713575 -277.328906)
			(xy 115.747078 -277.289665) (xy 115.766342 -277.272496) (xy 115.766342 -276.144482) (xy 115.746997 -276.127379)
			(xy 115.713412 -276.088161) (xy 115.686389 -276.044164) (xy 115.666595 -275.996475) (xy 115.65452 -275.946274)
			(xy 115.650461 -275.8948) (xy 115.65452 -275.843326) (xy 115.666595 -275.793125) (xy 115.686389 -275.745436)
			(xy 115.713412 -275.701439) (xy 115.746997 -275.662221) (xy 115.766342 -275.645118) (xy 115.766342 -274.516596)
			(xy 115.747055 -274.499451) (xy 115.713549 -274.460206) (xy 115.686593 -274.416205) (xy 115.66685 -274.368529)
			(xy 115.654806 -274.318352) (xy 115.650757 -274.266909) (xy 115.654803 -274.215466) (xy 115.666844 -274.165288)
			(xy 115.686585 -274.117612) (xy 115.713538 -274.073608) (xy 115.747042 -274.034362) (xy 115.766342 -274.017232)
			(xy 115.766342 -272.888964) (xy 115.746998 -272.871861) (xy 115.713417 -272.832643) (xy 115.686396 -272.788647)
			(xy 115.666605 -272.74096) (xy 115.654531 -272.69076) (xy 115.650475 -272.639288) (xy 115.654535 -272.587817)
			(xy 115.666612 -272.537618) (xy 115.686407 -272.489932) (xy 115.71343 -272.445938) (xy 115.747015 -272.406722)
			(xy 115.766342 -272.3896) (xy 115.766342 -271.261078) (xy 115.746997 -271.243975) (xy 115.713413 -271.204757)
			(xy 115.686391 -271.16076) (xy 115.666597 -271.113072) (xy 115.654522 -271.062871) (xy 115.650464 -271.011397)
			(xy 115.654523 -270.959924) (xy 115.666599 -270.909723) (xy 115.686393 -270.862035) (xy 115.713416 -270.818039)
			(xy 115.747001 -270.778821) (xy 115.766342 -270.761714) (xy 115.766342 -269.633192) (xy 115.746996 -269.616089)
			(xy 115.71341 -269.576871) (xy 115.686385 -269.532873) (xy 115.66659 -269.485184) (xy 115.654513 -269.434981)
			(xy 115.650453 -269.383506) (xy 115.654511 -269.332032) (xy 115.666586 -269.281829) (xy 115.686379 -269.234139)
			(xy 115.713402 -269.19014) (xy 115.746987 -269.15092) (xy 115.766342 -269.133828) (xy 115.766342 -268.00556)
			(xy 115.746999 -267.988457) (xy 115.713417 -267.94924) (xy 115.686398 -267.905243) (xy 115.666607 -267.857556)
			(xy 115.654534 -267.807357) (xy 115.650478 -267.755886) (xy 115.654538 -267.704415) (xy 115.666615 -267.654216)
			(xy 115.68641 -267.606531) (xy 115.713434 -267.562537) (xy 115.747019 -267.523322) (xy 115.766342 -267.506196)
			(xy 115.766342 -266.377928) (xy 115.746993 -266.360825) (xy 115.713402 -266.321606) (xy 115.686371 -266.277606)
			(xy 115.666571 -266.229914) (xy 115.65449 -266.179709) (xy 115.650426 -266.12823) (xy 115.65448 -266.07675)
			(xy 115.666553 -266.026542) (xy 115.686344 -265.978847) (xy 115.713366 -265.934843) (xy 115.746951 -265.895617)
			(xy 115.766342 -265.878564) (xy 115.766342 -264.750042) (xy 115.747 -264.732939) (xy 115.713422 -264.693722)
			(xy 115.686404 -264.649727) (xy 115.666616 -264.602041) (xy 115.654546 -264.551843) (xy 115.650491 -264.500374)
			(xy 115.654554 -264.448905) (xy 115.666632 -264.39871) (xy 115.686428 -264.351027) (xy 115.713452 -264.307036)
			(xy 115.747037 -264.267824) (xy 115.766342 -264.250678) (xy 115.766342 -261.17931) (xy 115.766922 -261.154353)
			(xy 115.776677 -261.105402) (xy 115.795795 -261.059295) (xy 115.823541 -261.017803) (xy 115.840764 -260.999732)
			(xy 116.501164 -260.339332) (xy 116.519206 -260.322075) (xy 116.560701 -260.294324) (xy 116.606819 -260.275216)
			(xy 116.655782 -260.265489) (xy 116.680742 -260.26491) (xy 120.563386 -260.26491) (xy 120.723152 -260.105144)
			(xy 120.733639 -260.093922) (xy 120.747924 -260.066749) (xy 120.753479 -260.036556) (xy 120.749802 -260.006077)
			(xy 120.737224 -259.978072) (xy 120.72747 -259.966206) (xy 120.712138 -259.948155) (xy 120.686288 -259.908474)
			(xy 120.666413 -259.865487) (xy 120.652926 -259.820089) (xy 120.646109 -259.773223) (xy 120.645682 -259.749544)
			(xy 120.64615 -259.724194) (xy 120.653943 -259.674095) (xy 120.669348 -259.625791) (xy 120.692001 -259.580432)
			(xy 120.721361 -259.539098) (xy 120.75673 -259.502771) (xy 120.797265 -259.472317) (xy 120.819418 -259.459984)
			(xy 120.846342 -259.445506) (xy 120.846342 -258.754372) (xy 120.819672 -258.739894) (xy 120.797785 -258.727475)
			(xy 120.757763 -258.696974) (xy 120.722866 -258.660719) (xy 120.693913 -258.619562) (xy 120.671582 -258.574468)
			(xy 120.656398 -258.526493) (xy 120.648715 -258.476762) (xy 120.648715 -258.426442) (xy 120.656397 -258.376711)
			(xy 120.671581 -258.328736) (xy 120.693911 -258.283641) (xy 120.722863 -258.242484) (xy 120.75776 -258.206229)
			(xy 120.797782 -258.175727) (xy 120.819672 -258.163314) (xy 120.846342 -258.148836) (xy 120.846342 -257.585972)
			(xy 120.819672 -257.571494) (xy 120.7978 -257.559052) (xy 120.757782 -257.52855) (xy 120.722887 -257.492298)
			(xy 120.693933 -257.451146) (xy 120.671598 -257.406057) (xy 120.656406 -257.358088) (xy 120.648712 -257.308363)
			(xy 120.648222 -257.283204) (xy 120.648748 -257.256822) (xy 120.657187 -257.204736) (xy 120.673849 -257.154671)
			(xy 120.698305 -257.107915) (xy 120.729924 -257.065674) (xy 120.748552 -257.046984) (xy 120.757969 -257.037253)
			(xy 120.77176 -257.01396) (xy 120.778952 -256.987864) (xy 120.77904 -256.960794) (xy 120.772018 -256.934652)
			(xy 120.758378 -256.911269) (xy 120.74906 -256.901442) (xy 120.730775 -256.882785) (xy 120.699762 -256.840748)
			(xy 120.6758 -256.79433) (xy 120.659491 -256.744703) (xy 120.651249 -256.693119) (xy 120.650762 -256.667)
			(xy 120.651231 -256.641999) (xy 120.658813 -256.592574) (xy 120.673801 -256.54487) (xy 120.695849 -256.499991)
			(xy 120.724447 -256.458973) (xy 120.758934 -256.422766) (xy 120.798512 -256.392207) (xy 120.82018 -256.379726)
			(xy 120.846342 -256.365248) (xy 120.846342 -255.833372) (xy 120.819672 -255.818894) (xy 120.7978 -255.806452)
			(xy 120.757782 -255.77595) (xy 120.722887 -255.739698) (xy 120.693933 -255.698546) (xy 120.671598 -255.653457)
			(xy 120.656406 -255.605488) (xy 120.648712 -255.555763) (xy 120.648222 -255.530604) (xy 120.648677 -255.506074)
			(xy 120.655976 -255.45756) (xy 120.670411 -255.410672) (xy 120.691661 -255.366453) (xy 120.719253 -255.325888)
			(xy 120.735598 -255.307592) (xy 120.745592 -255.296082) (xy 120.75882 -255.268633) (xy 120.763365 -255.238503)
			(xy 120.758822 -255.208373) (xy 120.745596 -255.180923) (xy 120.735598 -255.169416) (xy 120.719261 -255.15111)
			(xy 120.69165 -255.110556) (xy 120.670388 -255.066341) (xy 120.655949 -255.019452) (xy 120.648655 -254.970935)
			(xy 120.648222 -254.946404) (xy 120.64868 -254.921242) (xy 120.656363 -254.871509) (xy 120.671552 -254.823532)
			(xy 120.693888 -254.778437) (xy 120.722849 -254.737282) (xy 120.757754 -254.701031) (xy 120.797786 -254.670536)
			(xy 120.819672 -254.658114) (xy 120.846342 -254.643636) (xy 120.846342 -253.496572) (xy 120.819672 -253.482094)
			(xy 120.7978 -253.469652) (xy 120.757782 -253.43915) (xy 120.722887 -253.402898) (xy 120.693933 -253.361746)
			(xy 120.671598 -253.316657) (xy 120.656406 -253.268688) (xy 120.648712 -253.218963) (xy 120.648222 -253.193804)
			(xy 120.648677 -253.169274) (xy 120.655976 -253.12076) (xy 120.670411 -253.073872) (xy 120.691661 -253.029653)
			(xy 120.719253 -252.989088) (xy 120.735598 -252.970792) (xy 120.745592 -252.959282) (xy 120.75882 -252.931833)
			(xy 120.763365 -252.901703) (xy 120.758822 -252.871573) (xy 120.745596 -252.844123) (xy 120.735598 -252.832616)
			(xy 120.719261 -252.81431) (xy 120.69165 -252.773756) (xy 120.670388 -252.729541) (xy 120.655949 -252.682652)
			(xy 120.648655 -252.634135) (xy 120.648222 -252.609604) (xy 120.64868 -252.584442) (xy 120.656363 -252.534709)
			(xy 120.671552 -252.486732) (xy 120.693888 -252.441637) (xy 120.722849 -252.400482) (xy 120.757754 -252.364231)
			(xy 120.797786 -252.333736) (xy 120.819672 -252.321314) (xy 120.846342 -252.306836) (xy 120.846342 -251.743972)
			(xy 120.819672 -251.729494) (xy 120.7978 -251.717052) (xy 120.757782 -251.68655) (xy 120.722887 -251.650298)
			(xy 120.693933 -251.609146) (xy 120.671598 -251.564057) (xy 120.656406 -251.516088) (xy 120.648712 -251.466363)
			(xy 120.648222 -251.441204) (xy 120.648677 -251.416674) (xy 120.655976 -251.36816) (xy 120.670411 -251.321272)
			(xy 120.691661 -251.277053) (xy 120.719253 -251.236488) (xy 120.735598 -251.218192) (xy 120.745592 -251.206682)
			(xy 120.75882 -251.179233) (xy 120.763365 -251.149103) (xy 120.758822 -251.118973) (xy 120.745596 -251.091523)
			(xy 120.735598 -251.080016) (xy 120.719261 -251.06171) (xy 120.69165 -251.021156) (xy 120.670388 -250.976941)
			(xy 120.655949 -250.930052) (xy 120.648655 -250.881535) (xy 120.648222 -250.857004) (xy 120.64868 -250.831842)
			(xy 120.656363 -250.782109) (xy 120.671552 -250.734132) (xy 120.693888 -250.689037) (xy 120.722849 -250.647882)
			(xy 120.757754 -250.611631) (xy 120.797786 -250.581136) (xy 120.819672 -250.568714) (xy 120.846342 -250.554236)
			(xy 120.846342 -249.422666) (xy 120.796812 -249.373136) (xy 120.793764 -249.371104) (xy 120.774457 -249.356263)
			(xy 120.740026 -249.32183) (xy 120.725184 -249.302524) (xy 120.723152 -249.299476) (xy 118.438422 -247.014746)
			(xy 118.432027 -247.008203) (xy 118.420078 -246.994347) (xy 118.414546 -246.98706) (xy 118.389751 -246.985197)
			(xy 118.341103 -246.97493) (xy 118.294559 -246.957442) (xy 118.251186 -246.933133) (xy 118.211977 -246.90256)
			(xy 118.177827 -246.866423) (xy 118.14952 -246.825547) (xy 118.127702 -246.780869) (xy 118.112874 -246.733412)
			(xy 118.105374 -246.68426) (xy 118.10492 -246.6594) (xy 118.105405 -246.633766) (xy 118.11336 -246.58312)
			(xy 118.12909 -246.534326) (xy 118.152215 -246.488571) (xy 118.182171 -246.446966) (xy 118.21823 -246.410525)
			(xy 118.259516 -246.380131) (xy 118.305025 -246.356525) (xy 118.329202 -246.347996) (xy 118.364 -246.336566)
			(xy 118.364 -245.068852) (xy 118.364616 -245.043897) (xy 118.374362 -244.994948) (xy 118.393469 -244.948841)
			(xy 118.421203 -244.907347) (xy 118.438422 -244.889274) (xy 119.904764 -243.422932) (xy 119.922806 -243.405675)
			(xy 119.964301 -243.377924) (xy 120.010419 -243.358816) (xy 120.059382 -243.349089) (xy 120.084342 -243.34851)
			(xy 120.639586 -243.34851) (xy 120.770142 -243.217954) (xy 120.770142 -242.590066) (xy 120.360186 -242.18011)
			(xy 117.747542 -242.18011) (xy 117.722588 -242.179493) (xy 117.673639 -242.169746) (xy 117.627533 -242.150638)
			(xy 117.586039 -242.122904) (xy 117.567964 -242.105688) (xy 115.662964 -240.200688) (xy 115.645702 -240.182648)
			(xy 115.617938 -240.141155) (xy 115.598819 -240.095037) (xy 115.58908 -240.046072) (xy 115.588542 -240.02111)
			(xy 115.588542 -238.703866) (xy 115.229386 -238.34471) (xy 114.29746 -238.34471) (xy 114.283236 -238.37265)
			(xy 114.271194 -238.39565) (xy 114.240965 -238.437857) (xy 114.204465 -238.474774) (xy 114.162604 -238.505479)
			(xy 114.116427 -238.529205) (xy 114.06709 -238.54536) (xy 114.015823 -238.553539) (xy 113.963909 -238.553539)
			(xy 113.912642 -238.54536) (xy 113.863305 -238.529205) (xy 113.817128 -238.505479) (xy 113.775267 -238.474774)
			(xy 113.738767 -238.437857) (xy 113.708538 -238.39565) (xy 113.696496 -238.37265) (xy 113.682272 -238.34471)
			(xy 113.35766 -238.34471) (xy 113.343436 -238.37265) (xy 113.331394 -238.39565) (xy 113.301165 -238.437857)
			(xy 113.264665 -238.474774) (xy 113.222804 -238.505479) (xy 113.176627 -238.529205) (xy 113.12729 -238.54536)
			(xy 113.076023 -238.553539) (xy 113.024109 -238.553539) (xy 112.972842 -238.54536) (xy 112.923505 -238.529205)
			(xy 112.877328 -238.505479) (xy 112.835467 -238.474774) (xy 112.798967 -238.437857) (xy 112.768738 -238.39565)
			(xy 112.756696 -238.37265) (xy 112.742472 -238.34471) (xy 112.41786 -238.34471) (xy 112.403636 -238.37265)
			(xy 112.391594 -238.39565) (xy 112.361365 -238.437857) (xy 112.324865 -238.474774) (xy 112.283004 -238.505479)
			(xy 112.236827 -238.529205) (xy 112.18749 -238.54536) (xy 112.136223 -238.553539) (xy 112.084309 -238.553539)
			(xy 112.033042 -238.54536) (xy 111.983705 -238.529205) (xy 111.937528 -238.505479) (xy 111.895667 -238.474774)
			(xy 111.859167 -238.437857) (xy 111.828938 -238.39565) (xy 111.816896 -238.37265) (xy 111.802672 -238.34471)
			(xy 111.47806 -238.34471) (xy 111.463836 -238.37265) (xy 111.451794 -238.39565) (xy 111.421565 -238.437857)
			(xy 111.385065 -238.474774) (xy 111.343204 -238.505479) (xy 111.297027 -238.529205) (xy 111.24769 -238.54536)
			(xy 111.196423 -238.553539) (xy 111.144509 -238.553539) (xy 111.093242 -238.54536) (xy 111.043905 -238.529205)
			(xy 110.997728 -238.505479) (xy 110.955867 -238.474774) (xy 110.919367 -238.437857) (xy 110.889138 -238.39565)
			(xy 110.877096 -238.37265) (xy 110.862872 -238.34471) (xy 110.53826 -238.34471) (xy 110.524036 -238.37265)
			(xy 110.511994 -238.39565) (xy 110.481765 -238.437857) (xy 110.445265 -238.474774) (xy 110.403404 -238.505479)
			(xy 110.357227 -238.529205) (xy 110.30789 -238.54536) (xy 110.256623 -238.553539) (xy 110.204709 -238.553539)
			(xy 110.153442 -238.54536) (xy 110.104105 -238.529205) (xy 110.057928 -238.505479) (xy 110.016067 -238.474774)
			(xy 109.979567 -238.437857) (xy 109.949338 -238.39565) (xy 109.937296 -238.37265) (xy 109.923072 -238.34471)
			(xy 109.59846 -238.34471) (xy 109.584236 -238.37265) (xy 109.572194 -238.39565) (xy 109.541965 -238.437857)
			(xy 109.505465 -238.474774) (xy 109.463604 -238.505479) (xy 109.417427 -238.529205) (xy 109.36809 -238.54536)
			(xy 109.316823 -238.553539) (xy 109.264909 -238.553539) (xy 109.213642 -238.54536) (xy 109.164305 -238.529205)
			(xy 109.118128 -238.505479) (xy 109.076267 -238.474774) (xy 109.039767 -238.437857) (xy 109.009538 -238.39565)
			(xy 108.997496 -238.37265) (xy 108.983272 -238.34471) (xy 104.492298 -238.34471) (xy 103.294942 -239.542066)
			(xy 103.294942 -245.224554) (xy 103.679498 -245.60911) (xy 104.793542 -245.60911) (xy 104.818497 -245.609726)
			(xy 104.867446 -245.61947) (xy 104.913554 -245.638577) (xy 104.955048 -245.666312) (xy 104.97312 -245.683532)
			(xy 105.30332 -246.013732) (xy 105.320582 -246.031772) (xy 105.348344 -246.073265) (xy 105.367461 -246.119383)
			(xy 105.377196 -246.168348) (xy 105.377742 -246.19331) (xy 105.377742 -246.366284) (xy 105.404412 -246.380762)
			(xy 105.426426 -246.393135) (xy 105.466703 -246.423595) (xy 105.501835 -246.459868) (xy 105.530993 -246.501097)
			(xy 105.553487 -246.546308) (xy 105.568786 -246.594432) (xy 105.576528 -246.644332) (xy 105.576531 -246.69483)
			(xy 105.568794 -246.744731) (xy 105.553501 -246.792857) (xy 105.531012 -246.838071) (xy 105.501859 -246.879303)
			(xy 105.466731 -246.91558) (xy 105.426458 -246.946045) (xy 105.404412 -246.958358) (xy 105.377742 -246.972836)
			(xy 105.377742 -247.38711) (xy 105.37717 -247.41207) (xy 105.367427 -247.461029) (xy 105.348319 -247.507146)
			(xy 105.320579 -247.548648) (xy 105.30332 -247.566688) (xy 104.66832 -248.201688) (xy 104.650279 -248.218948)
			(xy 104.608786 -248.246705) (xy 104.562668 -248.265816) (xy 104.513703 -248.275544) (xy 104.488742 -248.27611)
			(xy 103.679498 -248.27611) (xy 103.345742 -248.609866) (xy 103.345742 -255.908556) (xy 103.663496 -256.22631)
			(xy 104.742742 -256.22631) (xy 104.767697 -256.226926) (xy 104.816646 -256.23667) (xy 104.862754 -256.255777)
			(xy 104.904248 -256.283512) (xy 104.92232 -256.300732) (xy 105.43032 -256.808732) (xy 105.447582 -256.826772)
			(xy 105.475344 -256.868265) (xy 105.494461 -256.914383) (xy 105.504196 -256.963348) (xy 105.504742 -256.98831)
			(xy 105.504742 -257.366262) (xy 105.542334 -257.376168) (xy 105.5666 -257.383203) (xy 105.61278 -257.403692)
			(xy 105.655278 -257.431012) (xy 105.693091 -257.464518) (xy 105.725325 -257.50342) (xy 105.751222 -257.5468)
			(xy 105.770169 -257.593634) (xy 105.781719 -257.642817) (xy 105.785601 -257.69319) (xy 105.781723 -257.743562)
			(xy 105.770175 -257.792746) (xy 105.751231 -257.839582) (xy 105.725337 -257.882963) (xy 105.693105 -257.921867)
			(xy 105.655295 -257.955376) (xy 105.612799 -257.982698) (xy 105.56662 -258.00319) (xy 105.542334 -258.010152)
			(xy 105.504742 -258.020058) (xy 105.504742 -260.388354) (xy 105.6767 -260.560312) (xy 107.629198 -260.560312)
			(xy 107.654151 -260.560933) (xy 107.703094 -260.570687) (xy 107.749194 -260.589801) (xy 107.79068 -260.617541)
			(xy 107.808776 -260.634734) (xy 108.077508 -260.903466) (xy 108.094768 -260.921507) (xy 108.122525 -260.963)
			(xy 108.141637 -261.009119) (xy 108.151367 -261.058083) (xy 108.15193 -261.083044) (xy 108.15193 -261.443216)
			(xy 108.151317 -261.468172) (xy 108.141578 -261.517125) (xy 108.122476 -261.563238) (xy 108.094747 -261.60474)
			(xy 108.077508 -261.622794) (xy 107.736894 -261.963408) (xy 107.718852 -261.980665) (xy 107.677358 -262.008416)
			(xy 107.631239 -262.02752) (xy 107.582276 -262.037242) (xy 107.557316 -262.03783) (xy 107.35437 -262.03783)
			(xy 107.16895 -262.22325) (xy 107.16895 -263.4996) (xy 108.306616 -264.637266) (xy 108.323876 -264.655307)
			(xy 108.351632 -264.6968) (xy 108.370744 -264.742919) (xy 108.380473 -264.791883) (xy 108.381038 -264.816844)
			(xy 108.381038 -273.453098) (xy 108.601256 -273.453098) (xy 108.601764 -273.427211) (xy 108.609863 -273.376073)
			(xy 108.625862 -273.326833) (xy 108.649368 -273.280701) (xy 108.6798 -273.238814) (xy 108.71641 -273.202204)
			(xy 108.758297 -273.171772) (xy 108.804429 -273.148266) (xy 108.853669 -273.132267) (xy 108.904807 -273.124168)
			(xy 108.956581 -273.124168) (xy 109.007719 -273.132267) (xy 109.056959 -273.148266) (xy 109.103091 -273.171772)
			(xy 109.144978 -273.202204) (xy 109.181588 -273.238814) (xy 109.21202 -273.280701) (xy 109.235526 -273.326833)
			(xy 109.251525 -273.376073) (xy 109.259624 -273.427211) (xy 109.260132 -273.453098) (xy 109.259601 -273.480806)
			(xy 109.250407 -273.535453) (xy 109.241844 -273.56181) (xy 109.234224 -273.583654) (xy 109.439202 -273.938746)
			(xy 109.462062 -273.943064) (xy 109.486859 -273.948281) (xy 109.534598 -273.965264) (xy 109.579176 -273.989353)
			(xy 109.619543 -274.019979) (xy 109.654747 -274.056422) (xy 109.683961 -274.097824) (xy 109.706494 -274.143208)
			(xy 109.721817 -274.191505) (xy 109.729569 -274.241579) (xy 109.730032 -274.266914) (xy 109.729524 -274.292801)
			(xy 109.721425 -274.343939) (xy 109.705426 -274.393179) (xy 109.68192 -274.439311) (xy 109.651488 -274.481198)
			(xy 109.614878 -274.517808) (xy 109.572991 -274.54824) (xy 109.526859 -274.571746) (xy 109.477619 -274.587745)
			(xy 109.426481 -274.595844) (xy 109.374707 -274.595844) (xy 109.323569 -274.587745) (xy 109.274329 -274.571746)
			(xy 109.228197 -274.54824) (xy 109.18631 -274.517808) (xy 109.1497 -274.481198) (xy 109.119268 -274.439311)
			(xy 109.095762 -274.393179) (xy 109.079763 -274.343939) (xy 109.071664 -274.292801) (xy 109.071156 -274.266914)
			(xy 109.071691 -274.239206) (xy 109.080883 -274.184559) (xy 109.089444 -274.158202) (xy 109.097318 -274.136104)
			(xy 108.89234 -273.781266) (xy 108.86948 -273.776948) (xy 108.844673 -273.771718) (xy 108.796897 -273.754771)
			(xy 108.75228 -273.730708) (xy 108.711874 -273.700095) (xy 108.676632 -273.663656) (xy 108.647386 -273.622251)
			(xy 108.624826 -273.576855) (xy 108.609484 -273.528539) (xy 108.601721 -273.478444) (xy 108.601256 -273.453098)
			(xy 108.381038 -273.453098) (xy 108.381038 -275.3614) (xy 108.499656 -275.566632) (xy 108.522516 -275.57095)
			(xy 108.547331 -275.576134) (xy 108.595099 -275.593102) (xy 108.639707 -275.617181) (xy 108.680106 -275.647803)
			(xy 108.715341 -275.684246) (xy 108.744584 -275.725654) (xy 108.767146 -275.771048) (xy 108.782494 -275.819361)
			(xy 108.790267 -275.869454) (xy 108.79074 -275.8948) (xy 108.790278 -275.919881) (xy 108.782691 -275.969467)
			(xy 108.767676 -276.01733) (xy 108.745581 -276.062364) (xy 108.716915 -276.10353) (xy 108.682342 -276.139875)
			(xy 108.64266 -276.170561) (xy 108.598785 -276.194878) (xy 108.551732 -276.212265) (xy 108.502588 -276.22232)
			(xy 108.477558 -276.223984) (xy 108.462128 -276.225308) (xy 108.433093 -276.236041) (xy 108.408593 -276.254961)
			(xy 108.390868 -276.280339) (xy 108.381538 -276.309854) (xy 108.381038 -276.32533) (xy 108.381038 -276.708616)
			(xy 108.601256 -276.708616) (xy 108.601789 -276.683284) (xy 108.609538 -276.633215) (xy 108.624856 -276.584922)
			(xy 108.647381 -276.53954) (xy 108.676585 -276.498139) (xy 108.711779 -276.461694) (xy 108.752134 -276.431062)
			(xy 108.796701 -276.406964) (xy 108.844429 -276.389968) (xy 108.869226 -276.384766) (xy 108.892086 -276.380448)
			(xy 109.097064 -276.02561) (xy 109.08919 -276.003766) (xy 109.080545 -275.977358) (xy 109.071224 -275.922582)
			(xy 109.070648 -275.8948) (xy 109.071156 -275.868893) (xy 109.079262 -275.817716) (xy 109.095274 -275.768437)
			(xy 109.118797 -275.72227) (xy 109.149253 -275.680351) (xy 109.185891 -275.643713) (xy 109.22781 -275.613257)
			(xy 109.273977 -275.589734) (xy 109.323256 -275.573722) (xy 109.374433 -275.565616) (xy 109.426247 -275.565616)
			(xy 109.477424 -275.573722) (xy 109.526703 -275.589734) (xy 109.57287 -275.613257) (xy 109.614789 -275.643713)
			(xy 109.651427 -275.680351) (xy 109.681883 -275.72227) (xy 109.705406 -275.768437) (xy 109.721418 -275.817716)
			(xy 109.729524 -275.868893) (xy 109.730032 -275.8948) (xy 109.729566 -275.920146) (xy 109.721792 -275.97024)
			(xy 109.706443 -276.018553) (xy 109.683881 -276.063948) (xy 109.654638 -276.105356) (xy 109.619401 -276.1418)
			(xy 109.579002 -276.172421) (xy 109.534392 -276.196499) (xy 109.486623 -276.213466) (xy 109.461808 -276.21865)
			(xy 109.438948 -276.222968) (xy 109.23397 -276.577806) (xy 109.241844 -276.599904) (xy 109.250407 -276.626262)
			(xy 109.259604 -276.680908) (xy 109.260132 -276.708616) (xy 109.259624 -276.734503) (xy 109.251525 -276.785641)
			(xy 109.235526 -276.834881) (xy 109.21202 -276.881013) (xy 109.181588 -276.9229) (xy 109.144978 -276.95951)
			(xy 109.103091 -276.989942) (xy 109.056959 -277.013448) (xy 109.007719 -277.029447) (xy 108.956581 -277.037546)
			(xy 108.904807 -277.037546) (xy 108.853669 -277.029447) (xy 108.804429 -277.013448) (xy 108.758297 -276.989942)
			(xy 108.71641 -276.95951) (xy 108.6798 -276.9229) (xy 108.649368 -276.881013) (xy 108.625862 -276.834881)
			(xy 108.609863 -276.785641) (xy 108.601764 -276.734503) (xy 108.601256 -276.708616) (xy 108.381038 -276.708616)
			(xy 108.381038 -277.091902) (xy 108.381574 -277.107386) (xy 108.390838 -277.136935) (xy 108.408543 -277.162341)
			(xy 108.433057 -277.181263) (xy 108.462119 -277.191957) (xy 108.477558 -277.193248) (xy 108.501611 -277.194917)
			(xy 108.548892 -277.204359) (xy 108.594296 -277.220578) (xy 108.636857 -277.243231) (xy 108.67567 -277.271834)
			(xy 108.709909 -277.30578) (xy 108.7247 -277.32482) (xy 109.136688 -277.32482) (xy 109.15236 -277.304683)
			(xy 109.188869 -277.269036) (xy 109.230434 -277.239439) (xy 109.276062 -277.216599) (xy 109.324665 -277.201063)
			(xy 109.375081 -277.1932) (xy 109.400594 -277.19274) (xy 109.426501 -277.193221) (xy 109.477678 -277.201326)
			(xy 109.526956 -277.217337) (xy 109.573124 -277.24086) (xy 109.615043 -277.271315) (xy 109.651681 -277.307953)
			(xy 109.682137 -277.349871) (xy 109.705661 -277.396038) (xy 109.721672 -277.445316) (xy 109.729778 -277.496493)
			(xy 109.729778 -277.548307) (xy 109.721672 -277.599484) (xy 109.705661 -277.648762) (xy 109.682137 -277.694929)
			(xy 109.651681 -277.736847) (xy 109.615043 -277.773485) (xy 109.573124 -277.80394) (xy 109.526956 -277.827463)
			(xy 109.477678 -277.843474) (xy 109.426501 -277.851579) (xy 109.400594 -277.852124) (xy 109.375082 -277.851647)
			(xy 109.324667 -277.843786) (xy 109.276065 -277.828252) (xy 109.230435 -277.805417) (xy 109.188868 -277.775825)
			(xy 109.152356 -277.740183) (xy 109.136688 -277.720044) (xy 108.7247 -277.720044) (xy 108.709917 -277.739097)
			(xy 108.675703 -277.773079) (xy 108.636897 -277.801708) (xy 108.594331 -277.824369) (xy 108.548914 -277.840578)
			(xy 108.501618 -277.849989) (xy 108.477558 -277.851616) (xy 108.46213 -277.85294) (xy 108.433099 -277.863674)
			(xy 108.408605 -277.882595) (xy 108.390887 -277.907973) (xy 108.381565 -277.937488) (xy 108.381038 -277.952962)
			(xy 108.381038 -280.005028) (xy 108.380424 -280.029984) (xy 108.370683 -280.078936) (xy 108.351581 -280.125048)
			(xy 108.323851 -280.166548) (xy 108.306616 -280.184606) (xy 107.82935 -280.661872) (xy 107.837224 -280.690574)
			(xy 107.842791 -280.712053) (xy 107.848775 -280.756019) (xy 107.849162 -280.778204) (xy 107.848682 -280.803993)
			(xy 107.840613 -280.854937) (xy 107.824674 -280.903991) (xy 107.801257 -280.949947) (xy 107.770939 -280.991675)
			(xy 107.734467 -281.028146) (xy 107.692739 -281.058462) (xy 107.646781 -281.081878) (xy 107.597727 -281.097815)
			(xy 107.546783 -281.105883) (xy 107.520994 -281.106372) (xy 107.498807 -281.106008) (xy 107.454839 -281.100019)
			(xy 107.433364 -281.094434) (xy 107.404662 -281.08656) (xy 106.544364 -281.946858) (xy 106.619802 -282.077668)
			(xy 106.642662 -282.081986) (xy 106.667462 -282.087186) (xy 106.715198 -282.104179) (xy 106.759773 -282.128274)
			(xy 106.800137 -282.158905) (xy 106.83534 -282.195349) (xy 106.864554 -282.23675) (xy 106.887091 -282.282133)
			(xy 106.902421 -282.330428) (xy 106.910182 -282.380501) (xy 106.910632 -282.405836) (xy 106.910122 -282.43173)
			(xy 106.902021 -282.48288) (xy 106.886022 -282.532135) (xy 106.862519 -282.578283) (xy 106.832091 -282.620189)
			(xy 106.795486 -282.656823) (xy 106.753603 -282.687284) (xy 106.707474 -282.710823) (xy 106.658232 -282.72686)
			(xy 106.607088 -282.735002) (xy 106.581194 -282.735528) (xy 106.555515 -282.735044) (xy 106.504776 -282.727091)
			(xy 106.455885 -282.711362) (xy 106.410027 -282.688239) (xy 106.368311 -282.658281) (xy 106.331748 -282.622214)
			(xy 106.301223 -282.580911) (xy 106.277476 -282.535373) (xy 106.261081 -282.486701) (xy 106.256328 -282.461462)
			(xy 106.253493 -282.447854) (xy 106.241546 -282.422769) (xy 106.223279 -282.401833) (xy 106.200044 -282.386598)
			(xy 106.173562 -282.378192) (xy 106.145794 -282.377236) (xy 106.118796 -282.383803) (xy 106.094569 -282.397405)
			(xy 106.08437 -282.406852) (xy 105.93451 -282.556712) (xy 105.930954 -282.563316) (xy 105.919276 -282.583925)
			(xy 105.890919 -282.621865) (xy 105.857422 -282.655356) (xy 105.819477 -282.683707) (xy 105.798874 -282.695396)
			(xy 105.79227 -282.698952) (xy 105.574846 -282.916376) (xy 105.475024 -283.089096) (xy 105.482898 -283.111194)
			(xy 105.491524 -283.137542) (xy 105.500848 -283.192189) (xy 105.50144 -283.219906) (xy 105.500957 -283.245808)
			(xy 105.492849 -283.296973) (xy 105.476832 -283.346239) (xy 105.453303 -283.392391) (xy 105.42284 -283.434291)
			(xy 105.386195 -283.470908) (xy 105.34427 -283.501338) (xy 105.2981 -283.524831) (xy 105.248822 -283.540809)
			(xy 105.19765 -283.548878) (xy 105.171748 -283.549344) (xy 105.146424 -283.548898) (xy 105.096369 -283.541177)
			(xy 105.048088 -283.52588) (xy 105.02519 -283.515054) (xy 104.992424 -283.498798) (xy 104.620314 -283.870908)
			(xy 104.620314 -288.168588) (xy 104.619694 -288.193541) (xy 104.609943 -288.242486) (xy 104.590831 -288.288589)
			(xy 104.563094 -288.330079) (xy 104.545892 -288.348166) (xy 104.077262 -288.816796) (xy 104.083358 -288.844228)
			(xy 104.087233 -288.862204) (xy 104.091432 -288.898739) (xy 104.09174 -288.917126) (xy 104.091256 -288.943027)
			(xy 104.083145 -288.99419) (xy 104.067126 -289.043453) (xy 104.043596 -289.089602) (xy 104.013133 -289.1315)
			(xy 103.976488 -289.168113) (xy 103.934564 -289.198541) (xy 103.888395 -289.222033) (xy 103.839119 -289.23801)
			(xy 103.787949 -289.246078) (xy 103.762048 -289.246564) (xy 103.736753 -289.246138) (xy 103.686747 -289.238477)
			(xy 103.66248 -289.231324) (xy 103.64464 -289.247364) (xy 103.60417 -289.273116) (xy 103.559587 -289.290815)
			(xy 103.512474 -289.299833) (xy 103.48849 -289.300412) (xy 103.401876 -289.300412) (xy 103.386914 -289.300941)
			(xy 103.358274 -289.30961) (xy 103.333369 -289.326198) (xy 103.314332 -289.349285) (xy 103.302793 -289.376894)
			(xy 103.299739 -289.406661) (xy 103.305433 -289.436037) (xy 103.31196 -289.44951) (xy 103.327454 -289.478466)
			(xy 103.351584 -289.483038) (xy 103.3765 -289.488133) (xy 103.424489 -289.504965) (xy 103.469325 -289.528964)
			(xy 103.509945 -289.559562) (xy 103.545387 -289.596032) (xy 103.57481 -289.637512) (xy 103.597516 -289.683016)
			(xy 103.612968 -289.731466) (xy 103.620799 -289.781715) (xy 103.621332 -289.807142) (xy 119.878856 -289.807142)
			(xy 119.879399 -289.781715) (xy 119.887229 -289.731468) (xy 119.90268 -289.683018) (xy 119.925386 -289.637514)
			(xy 119.954808 -289.596036) (xy 119.990248 -289.559565) (xy 120.030867 -289.528967) (xy 120.075701 -289.504967)
			(xy 120.123688 -289.488134) (xy 120.148604 -289.483038) (xy 120.172734 -289.478466) (xy 120.38711 -289.073082)
			(xy 120.377204 -289.050476) (xy 120.368243 -289.029398) (xy 120.355596 -288.985377) (xy 120.349182 -288.940026)
			(xy 120.348756 -288.917126) (xy 120.349264 -288.891219) (xy 120.35737 -288.840042) (xy 120.373382 -288.790763)
			(xy 120.396905 -288.744596) (xy 120.427361 -288.702677) (xy 120.463999 -288.666039) (xy 120.505918 -288.635583)
			(xy 120.552085 -288.61206) (xy 120.601364 -288.596048) (xy 120.652541 -288.587942) (xy 120.704355 -288.587942)
			(xy 120.755532 -288.596048) (xy 120.804811 -288.61206) (xy 120.850978 -288.635583) (xy 120.892897 -288.666039)
			(xy 120.929535 -288.702677) (xy 120.959991 -288.744596) (xy 120.983514 -288.790763) (xy 120.999526 -288.840042)
			(xy 121.007632 -288.891219) (xy 121.00814 -288.917126) (xy 121.007659 -288.942574) (xy 120.999856 -288.992867)
			(xy 120.984408 -289.041361) (xy 120.961683 -289.086901) (xy 120.932222 -289.128403) (xy 120.896727 -289.164878)
			(xy 120.856043 -289.195458) (xy 120.811139 -289.219415) (xy 120.763084 -289.236178) (xy 120.738138 -289.24123)
			(xy 120.714008 -289.245802) (xy 120.499632 -289.651186) (xy 120.509538 -289.673792) (xy 120.518456 -289.694878)
			(xy 120.531008 -289.738907) (xy 120.537342 -289.78425) (xy 120.537732 -289.807142) (xy 120.537224 -289.833029)
			(xy 120.529125 -289.884167) (xy 120.513126 -289.933407) (xy 120.48962 -289.979539) (xy 120.459188 -290.021426)
			(xy 120.422578 -290.058036) (xy 120.380691 -290.088468) (xy 120.334559 -290.111974) (xy 120.285319 -290.127973)
			(xy 120.234181 -290.136072) (xy 120.182407 -290.136072) (xy 120.131269 -290.127973) (xy 120.082029 -290.111974)
			(xy 120.035897 -290.088468) (xy 119.99401 -290.058036) (xy 119.9574 -290.021426) (xy 119.926968 -289.979539)
			(xy 119.903462 -289.933407) (xy 119.887463 -289.884167) (xy 119.879364 -289.833029) (xy 119.878856 -289.807142)
			(xy 103.621332 -289.807142) (xy 103.620824 -289.833029) (xy 103.612725 -289.884167) (xy 103.596726 -289.933407)
			(xy 103.57322 -289.979539) (xy 103.542788 -290.021426) (xy 103.506178 -290.058036) (xy 103.464291 -290.088468)
			(xy 103.418159 -290.111974) (xy 103.368919 -290.127973) (xy 103.317781 -290.136072) (xy 103.266007 -290.136072)
			(xy 103.214869 -290.127973) (xy 103.165629 -290.111974) (xy 103.119497 -290.088468) (xy 103.07761 -290.058036)
			(xy 103.041 -290.021426) (xy 103.010568 -289.979539) (xy 102.987062 -289.933407) (xy 102.971063 -289.884167)
			(xy 102.962964 -289.833029) (xy 102.962456 -289.807142) (xy 102.962835 -289.784209) (xy 102.969164 -289.738781)
			(xy 102.981734 -289.694671) (xy 102.99065 -289.673538) (xy 103.000556 -289.650932) (xy 102.815644 -289.300412)
			(xy 101.522276 -289.300412) (xy 101.507314 -289.300941) (xy 101.478674 -289.30961) (xy 101.453769 -289.326198)
			(xy 101.434732 -289.349285) (xy 101.423193 -289.376894) (xy 101.420139 -289.406661) (xy 101.425833 -289.436037)
			(xy 101.43236 -289.44951) (xy 101.447854 -289.478466) (xy 101.471984 -289.483038) (xy 101.4969 -289.488133)
			(xy 101.544889 -289.504965) (xy 101.589725 -289.528964) (xy 101.630345 -289.559562) (xy 101.665787 -289.596032)
			(xy 101.69521 -289.637512) (xy 101.717916 -289.683016) (xy 101.733368 -289.731466) (xy 101.741199 -289.781715)
			(xy 101.741732 -289.807142) (xy 101.741224 -289.833029) (xy 101.733125 -289.884167) (xy 101.717126 -289.933407)
			(xy 101.69362 -289.979539) (xy 101.663188 -290.021426) (xy 101.626578 -290.058036) (xy 101.584691 -290.088468)
			(xy 101.538559 -290.111974) (xy 101.489319 -290.127973) (xy 101.438181 -290.136072) (xy 101.386407 -290.136072)
			(xy 101.335269 -290.127973) (xy 101.286029 -290.111974) (xy 101.239897 -290.088468) (xy 101.19801 -290.058036)
			(xy 101.1614 -290.021426) (xy 101.130968 -289.979539) (xy 101.107462 -289.933407) (xy 101.091463 -289.884167)
			(xy 101.083364 -289.833029) (xy 101.082856 -289.807142) (xy 101.083235 -289.784209) (xy 101.089564 -289.738781)
			(xy 101.102134 -289.694671) (xy 101.11105 -289.673538) (xy 101.120956 -289.650932) (xy 100.936044 -289.300412)
			(xy 99.642676 -289.300412) (xy 99.627714 -289.300941) (xy 99.599074 -289.30961) (xy 99.574169 -289.326198)
			(xy 99.555132 -289.349285) (xy 99.543593 -289.376894) (xy 99.540539 -289.406661) (xy 99.546233 -289.436037)
			(xy 99.55276 -289.44951) (xy 99.568254 -289.478466) (xy 99.592384 -289.483038) (xy 99.6173 -289.488133)
			(xy 99.665289 -289.504965) (xy 99.710125 -289.528964) (xy 99.750745 -289.559562) (xy 99.786187 -289.596032)
			(xy 99.81561 -289.637512) (xy 99.838316 -289.683016) (xy 99.853768 -289.731466) (xy 99.861599 -289.781715)
			(xy 99.862132 -289.807142) (xy 99.861624 -289.833029) (xy 99.853525 -289.884167) (xy 99.837526 -289.933407)
			(xy 99.81402 -289.979539) (xy 99.783588 -290.021426) (xy 99.746978 -290.058036) (xy 99.705091 -290.088468)
			(xy 99.658959 -290.111974) (xy 99.609719 -290.127973) (xy 99.558581 -290.136072) (xy 99.506807 -290.136072)
			(xy 99.455669 -290.127973) (xy 99.406429 -290.111974) (xy 99.360297 -290.088468) (xy 99.31841 -290.058036)
			(xy 99.2818 -290.021426) (xy 99.251368 -289.979539) (xy 99.227862 -289.933407) (xy 99.211863 -289.884167)
			(xy 99.203764 -289.833029) (xy 99.203256 -289.807142) (xy 99.203635 -289.784209) (xy 99.209964 -289.738781)
			(xy 99.222534 -289.694671) (xy 99.23145 -289.673538) (xy 99.241356 -289.650932) (xy 99.056444 -289.300412)
			(xy 97.763076 -289.300412) (xy 97.748114 -289.300941) (xy 97.719474 -289.30961) (xy 97.694569 -289.326198)
			(xy 97.675532 -289.349285) (xy 97.663993 -289.376894) (xy 97.660939 -289.406661) (xy 97.666633 -289.436037)
			(xy 97.67316 -289.44951) (xy 97.688654 -289.478466) (xy 97.712784 -289.483038) (xy 97.7377 -289.488133)
			(xy 97.785689 -289.504965) (xy 97.830525 -289.528964) (xy 97.871145 -289.559562) (xy 97.906587 -289.596032)
			(xy 97.93601 -289.637512) (xy 97.958716 -289.683016) (xy 97.974168 -289.731466) (xy 97.981999 -289.781715)
			(xy 97.982532 -289.807142) (xy 97.982024 -289.833029) (xy 97.973925 -289.884167) (xy 97.957926 -289.933407)
			(xy 97.93442 -289.979539) (xy 97.903988 -290.021426) (xy 97.867378 -290.058036) (xy 97.825491 -290.088468)
			(xy 97.779359 -290.111974) (xy 97.730119 -290.127973) (xy 97.678981 -290.136072) (xy 97.627207 -290.136072)
			(xy 97.576069 -290.127973) (xy 97.526829 -290.111974) (xy 97.480697 -290.088468) (xy 97.43881 -290.058036)
			(xy 97.4022 -290.021426) (xy 97.371768 -289.979539) (xy 97.348262 -289.933407) (xy 97.332263 -289.884167)
			(xy 97.324164 -289.833029) (xy 97.323656 -289.807142) (xy 97.324035 -289.784209) (xy 97.330364 -289.738781)
			(xy 97.342934 -289.694671) (xy 97.35185 -289.673538) (xy 97.361756 -289.650932) (xy 97.176844 -289.300412)
			(xy 95.883476 -289.300412) (xy 95.868514 -289.300941) (xy 95.839874 -289.30961) (xy 95.814969 -289.326198)
			(xy 95.795932 -289.349285) (xy 95.784393 -289.376894) (xy 95.781339 -289.406661) (xy 95.787033 -289.436037)
			(xy 95.79356 -289.44951) (xy 95.809054 -289.478466) (xy 95.833184 -289.483038) (xy 95.8581 -289.488133)
			(xy 95.906089 -289.504965) (xy 95.950925 -289.528964) (xy 95.991545 -289.559562) (xy 96.026987 -289.596032)
			(xy 96.05641 -289.637512) (xy 96.079116 -289.683016) (xy 96.094568 -289.731466) (xy 96.102399 -289.781715)
			(xy 96.102932 -289.807142) (xy 96.102424 -289.833029) (xy 96.094325 -289.884167) (xy 96.078326 -289.933407)
			(xy 96.05482 -289.979539) (xy 96.024388 -290.021426) (xy 95.987778 -290.058036) (xy 95.945891 -290.088468)
			(xy 95.899759 -290.111974) (xy 95.850519 -290.127973) (xy 95.799381 -290.136072) (xy 95.747607 -290.136072)
			(xy 95.696469 -290.127973) (xy 95.647229 -290.111974) (xy 95.601097 -290.088468) (xy 95.55921 -290.058036)
			(xy 95.5226 -290.021426) (xy 95.492168 -289.979539) (xy 95.468662 -289.933407) (xy 95.452663 -289.884167)
			(xy 95.444564 -289.833029) (xy 95.444056 -289.807142) (xy 95.444435 -289.784209) (xy 95.450764 -289.738781)
			(xy 95.463334 -289.694671) (xy 95.47225 -289.673538) (xy 95.482156 -289.650932) (xy 95.297244 -289.300412)
			(xy 94.003876 -289.300412) (xy 93.988914 -289.300941) (xy 93.960274 -289.30961) (xy 93.935369 -289.326198)
			(xy 93.916332 -289.349285) (xy 93.904793 -289.376894) (xy 93.901739 -289.406661) (xy 93.907433 -289.436037)
			(xy 93.91396 -289.44951) (xy 93.929454 -289.478466) (xy 93.953584 -289.483038) (xy 93.9785 -289.488133)
			(xy 94.026489 -289.504965) (xy 94.071325 -289.528964) (xy 94.111945 -289.559562) (xy 94.147387 -289.596032)
			(xy 94.17681 -289.637512) (xy 94.199516 -289.683016) (xy 94.214968 -289.731466) (xy 94.222799 -289.781715)
			(xy 94.223332 -289.807142) (xy 94.222824 -289.833029) (xy 94.214725 -289.884167) (xy 94.198726 -289.933407)
			(xy 94.17522 -289.979539) (xy 94.144788 -290.021426) (xy 94.108178 -290.058036) (xy 94.066291 -290.088468)
			(xy 94.020159 -290.111974) (xy 93.970919 -290.127973) (xy 93.919781 -290.136072) (xy 93.868007 -290.136072)
			(xy 93.816869 -290.127973) (xy 93.767629 -290.111974) (xy 93.721497 -290.088468) (xy 93.67961 -290.058036)
			(xy 93.643 -290.021426) (xy 93.612568 -289.979539) (xy 93.589062 -289.933407) (xy 93.573063 -289.884167)
			(xy 93.564964 -289.833029) (xy 93.564456 -289.807142) (xy 93.564835 -289.784209) (xy 93.571164 -289.738781)
			(xy 93.583734 -289.694671) (xy 93.59265 -289.673538) (xy 93.602556 -289.650932) (xy 93.417644 -289.300412)
			(xy 92.124276 -289.300412) (xy 92.109314 -289.300941) (xy 92.080674 -289.30961) (xy 92.055769 -289.326198)
			(xy 92.036732 -289.349285) (xy 92.025193 -289.376894) (xy 92.022139 -289.406661) (xy 92.027833 -289.436037)
			(xy 92.03436 -289.44951) (xy 92.049854 -289.478466) (xy 92.073984 -289.483038) (xy 92.0989 -289.488133)
			(xy 92.146889 -289.504965) (xy 92.191725 -289.528964) (xy 92.232345 -289.559562) (xy 92.267787 -289.596032)
			(xy 92.29721 -289.637512) (xy 92.319916 -289.683016) (xy 92.335368 -289.731466) (xy 92.343199 -289.781715)
			(xy 92.343732 -289.807142) (xy 92.343224 -289.833029) (xy 92.335125 -289.884167) (xy 92.319126 -289.933407)
			(xy 92.29562 -289.979539) (xy 92.265188 -290.021426) (xy 92.228578 -290.058036) (xy 92.186691 -290.088468)
			(xy 92.140559 -290.111974) (xy 92.091319 -290.127973) (xy 92.040181 -290.136072) (xy 91.988407 -290.136072)
			(xy 91.937269 -290.127973) (xy 91.888029 -290.111974) (xy 91.841897 -290.088468) (xy 91.80001 -290.058036)
			(xy 91.7634 -290.021426) (xy 91.732968 -289.979539) (xy 91.709462 -289.933407) (xy 91.693463 -289.884167)
			(xy 91.685364 -289.833029) (xy 91.684856 -289.807142) (xy 91.685235 -289.784209) (xy 91.691564 -289.738781)
			(xy 91.704134 -289.694671) (xy 91.71305 -289.673538) (xy 91.722956 -289.650932) (xy 91.538044 -289.300412)
			(xy 80.263492 -289.300412) (xy 72.968358 -296.595546) (xy 72.968358 -297.515026) (xy 88.21548 -297.515026)
			(xy 88.219461 -297.382006) (xy 88.23139 -297.249461) (xy 88.251225 -297.117868) (xy 88.278894 -296.987696)
			(xy 88.314298 -296.859411) (xy 88.357311 -296.733474) (xy 88.407778 -296.610335) (xy 88.465519 -296.490434)
			(xy 88.530328 -296.374201) (xy 88.601972 -296.262051) (xy 88.680194 -296.154387) (xy 88.764715 -296.051594)
			(xy 88.855233 -295.954039) (xy 88.951422 -295.862073) (xy 89.05294 -295.776023) (xy 89.159421 -295.696199)
			(xy 89.270486 -295.622886) (xy 89.385737 -295.556346) (xy 89.504761 -295.496817) (xy 89.627132 -295.444513)
			(xy 89.752411 -295.399621) (xy 89.880152 -295.362302) (xy 90.009895 -295.332689) (xy 90.141177 -295.310888)
			(xy 90.273528 -295.296978) (xy 90.406474 -295.291007) (xy 90.539539 -295.292998) (xy 90.672247 -295.302943)
			(xy 90.804123 -295.320807) (xy 90.934694 -295.346525) (xy 91.063494 -295.380006) (xy 91.19006 -295.42113)
			(xy 91.313941 -295.46975) (xy 91.434692 -295.525691) (xy 91.551882 -295.588753) (xy 91.665091 -295.658711)
			(xy 91.773913 -295.735315) (xy 91.877959 -295.818289) (xy 91.976857 -295.907337) (xy 92.070252 -296.00214)
			(xy 92.15781 -296.102358) (xy 92.239219 -296.207634) (xy 92.314185 -296.31759) (xy 92.382442 -296.431832)
			(xy 92.443744 -296.549952) (xy 92.497873 -296.671527) (xy 92.544634 -296.796121) (xy 92.58386 -296.923289)
			(xy 92.61541 -297.052575) (xy 92.639173 -297.183516) (xy 92.655062 -297.315644) (xy 92.66302 -297.448486)
			(xy 92.663518 -297.515026) (xy 131.195582 -297.515026) (xy 131.199563 -297.382006) (xy 131.211492 -297.249461)
			(xy 131.231327 -297.117868) (xy 131.258996 -296.987696) (xy 131.2944 -296.859411) (xy 131.337413 -296.733474)
			(xy 131.38788 -296.610335) (xy 131.445621 -296.490434) (xy 131.51043 -296.374201) (xy 131.582074 -296.262051)
			(xy 131.660296 -296.154387) (xy 131.744817 -296.051594) (xy 131.835335 -295.954039) (xy 131.931524 -295.862073)
			(xy 132.033042 -295.776023) (xy 132.139523 -295.696199) (xy 132.250588 -295.622886) (xy 132.365839 -295.556346)
			(xy 132.484863 -295.496817) (xy 132.607234 -295.444513) (xy 132.732513 -295.399621) (xy 132.860254 -295.362302)
			(xy 132.989997 -295.332689) (xy 133.121279 -295.310888) (xy 133.25363 -295.296978) (xy 133.386576 -295.291007)
			(xy 133.519641 -295.292998) (xy 133.652349 -295.302943) (xy 133.784225 -295.320807) (xy 133.914796 -295.346525)
			(xy 134.043596 -295.380006) (xy 134.170162 -295.42113) (xy 134.294043 -295.46975) (xy 134.414794 -295.525691)
			(xy 134.531984 -295.588753) (xy 134.645193 -295.658711) (xy 134.754015 -295.735315) (xy 134.858061 -295.818289)
			(xy 134.956959 -295.907337) (xy 135.050354 -296.00214) (xy 135.137912 -296.102358) (xy 135.219321 -296.207634)
			(xy 135.294287 -296.31759) (xy 135.362544 -296.431832) (xy 135.423846 -296.549952) (xy 135.477975 -296.671527)
			(xy 135.524736 -296.796121) (xy 135.563962 -296.923289) (xy 135.595512 -297.052575) (xy 135.619275 -297.183516)
			(xy 135.635164 -297.315644) (xy 135.643122 -297.448486) (xy 135.64362 -297.515026) (xy 135.643122 -297.581566)
			(xy 135.635164 -297.714408) (xy 135.619275 -297.846536) (xy 135.595512 -297.977477) (xy 135.563962 -298.106763)
			(xy 135.524736 -298.233931) (xy 135.477975 -298.358525) (xy 135.423846 -298.4801) (xy 135.362544 -298.59822)
			(xy 135.294287 -298.712462) (xy 135.219321 -298.822418) (xy 135.137912 -298.927694) (xy 135.050354 -299.027912)
			(xy 134.956959 -299.122715) (xy 134.858061 -299.211763) (xy 134.754015 -299.294737) (xy 134.645193 -299.371341)
			(xy 134.531984 -299.441299) (xy 134.414794 -299.504361) (xy 134.294043 -299.560302) (xy 134.170162 -299.608922)
			(xy 134.043596 -299.650046) (xy 133.914796 -299.683527) (xy 133.784225 -299.709245) (xy 133.652349 -299.727109)
			(xy 133.519641 -299.737054) (xy 133.386576 -299.739045) (xy 133.25363 -299.733074) (xy 133.121279 -299.719164)
			(xy 132.989997 -299.697363) (xy 132.860254 -299.66775) (xy 132.732513 -299.630431) (xy 132.607234 -299.585539)
			(xy 132.484863 -299.533235) (xy 132.365839 -299.473706) (xy 132.250588 -299.407166) (xy 132.139523 -299.333853)
			(xy 132.033042 -299.254029) (xy 131.931524 -299.167979) (xy 131.835335 -299.076013) (xy 131.744817 -298.978458)
			(xy 131.660296 -298.875665) (xy 131.582074 -298.768001) (xy 131.51043 -298.655851) (xy 131.445621 -298.539618)
			(xy 131.38788 -298.419717) (xy 131.337413 -298.296578) (xy 131.2944 -298.170641) (xy 131.258996 -298.042356)
			(xy 131.231327 -297.912184) (xy 131.211492 -297.780591) (xy 131.199563 -297.648046) (xy 131.195582 -297.515026)
			(xy 92.663518 -297.515026) (xy 92.66302 -297.581566) (xy 92.655062 -297.714408) (xy 92.639173 -297.846536)
			(xy 92.61541 -297.977477) (xy 92.58386 -298.106763) (xy 92.544634 -298.233931) (xy 92.497873 -298.358525)
			(xy 92.443744 -298.4801) (xy 92.382442 -298.59822) (xy 92.314185 -298.712462) (xy 92.239219 -298.822418)
			(xy 92.15781 -298.927694) (xy 92.070252 -299.027912) (xy 91.976857 -299.122715) (xy 91.877959 -299.211763)
			(xy 91.773913 -299.294737) (xy 91.665091 -299.371341) (xy 91.551882 -299.441299) (xy 91.434692 -299.504361)
			(xy 91.313941 -299.560302) (xy 91.19006 -299.608922) (xy 91.063494 -299.650046) (xy 90.934694 -299.683527)
			(xy 90.804123 -299.709245) (xy 90.672247 -299.727109) (xy 90.539539 -299.737054) (xy 90.406474 -299.739045)
			(xy 90.273528 -299.733074) (xy 90.141177 -299.719164) (xy 90.009895 -299.697363) (xy 89.880152 -299.66775)
			(xy 89.752411 -299.630431) (xy 89.627132 -299.585539) (xy 89.504761 -299.533235) (xy 89.385737 -299.473706)
			(xy 89.270486 -299.407166) (xy 89.159421 -299.333853) (xy 89.05294 -299.254029) (xy 88.951422 -299.167979)
			(xy 88.855233 -299.076013) (xy 88.764715 -298.978458) (xy 88.680194 -298.875665) (xy 88.601972 -298.768001)
			(xy 88.530328 -298.655851) (xy 88.465519 -298.539618) (xy 88.407778 -298.419717) (xy 88.357311 -298.296578)
			(xy 88.314298 -298.170641) (xy 88.278894 -298.042356) (xy 88.251225 -297.912184) (xy 88.23139 -297.780591)
			(xy 88.219461 -297.648046) (xy 88.21548 -297.515026) (xy 72.968358 -297.515026) (xy 72.968358 -333.883254)
			(xy 73.295256 -334.210152) (xy 75.95616 -334.210152)
		)
		(stroke
			(width 0)
			(type solid)
		)
		(fill yes)
		(layer "In9.Cu")
		(net "PVCCIN_CPU1")
	)
	(gr_poly
		(pts
			(xy 102.494334 -267.735558) (xy 102.49634 -267.710864) (xy 102.506842 -267.662447) (xy 102.524496 -267.616156)
			(xy 102.5489 -267.573041) (xy 102.579502 -267.534079) (xy 102.615607 -267.500154) (xy 102.656397 -267.472035)
			(xy 102.700947 -267.45036) (xy 102.748246 -267.435621) (xy 102.797223 -267.428151) (xy 102.821994 -267.42771)
			(xy 102.844771 -267.428063) (xy 102.889893 -267.43431) (xy 102.91191 -267.440156) (xy 102.940612 -267.448284)
			(xy 104.158542 -266.230354) (xy 104.158542 -265.635994) (xy 104.124506 -265.62431) (xy 104.100664 -265.615551)
			(xy 104.055804 -265.591734) (xy 104.015149 -265.561291) (xy 103.979669 -265.524947) (xy 103.950212 -265.483572)
			(xy 103.927481 -265.438151) (xy 103.912019 -265.389772) (xy 103.904195 -265.339587) (xy 103.904196 -265.288797)
			(xy 103.912022 -265.238613) (xy 103.927487 -265.190234) (xy 103.95022 -265.144815) (xy 103.979679 -265.103441)
			(xy 104.01516 -265.067099) (xy 104.055817 -265.036657) (xy 104.100679 -265.012843) (xy 104.124506 -265.004042)
			(xy 104.158542 -264.992358) (xy 104.158542 -262.01751) (xy 104.15905 -261.995402) (xy 104.166757 -261.951861)
			(xy 104.181872 -261.910307) (xy 104.203939 -261.871989) (xy 104.217724 -261.854696) (xy 104.247442 -261.818882)
			(xy 104.111044 -261.682484) (xy 104.099727 -261.670367) (xy 104.083175 -261.641653) (xy 104.074572 -261.609646)
			(xy 104.07396 -261.593076) (xy 104.07396 -261.1628) (xy 104.074522 -261.146224) (xy 104.083128 -261.114207)
			(xy 104.099704 -261.085495) (xy 104.111044 -261.073392) (xy 104.501442 -260.682994) (xy 104.513555 -260.671666)
			(xy 104.542265 -260.65509) (xy 104.574276 -260.646466) (xy 104.59085 -260.64591) (xy 104.898698 -260.64591)
			(xy 104.913241 -260.645444) (xy 104.941149 -260.63725) (xy 104.965617 -260.621525) (xy 104.984664 -260.599542)
			(xy 104.996746 -260.573084) (xy 105.000884 -260.544294) (xy 104.999282 -260.529832) (xy 104.998079 -260.5208)
			(xy 104.996811 -260.502621) (xy 104.996742 -260.49351) (xy 104.996742 -257.093466) (xy 104.637586 -256.73431)
			(xy 103.672132 -256.73431) (xy 103.665274 -256.741422) (xy 103.345742 -257.060954) (xy 103.345742 -257.134868)
			(xy 103.345164 -257.159825) (xy 103.335412 -257.208778) (xy 103.316296 -257.254888) (xy 103.288551 -257.296382)
			(xy 103.27132 -257.314446) (xy 103.05288 -257.532886) (xy 103.05288 -258.060952) (xy 103.27132 -258.279392)
			(xy 103.288577 -258.297434) (xy 103.316329 -258.338928) (xy 103.335435 -258.385047) (xy 103.345159 -258.43401)
			(xy 103.345742 -258.45897) (xy 103.345742 -260.51891) (xy 103.34517 -260.54387) (xy 103.335427 -260.592829)
			(xy 103.316319 -260.638946) (xy 103.288579 -260.680448) (xy 103.27132 -260.698488) (xy 103.196136 -260.773672)
			(xy 103.197152 -260.796278) (xy 103.19766 -260.812534) (xy 103.197152 -260.83832) (xy 103.189079 -260.889255)
			(xy 103.173139 -260.938301) (xy 103.149722 -260.98425) (xy 103.119406 -261.025969) (xy 103.082937 -261.062434)
			(xy 103.041214 -261.092744) (xy 102.995262 -261.116155) (xy 102.946214 -261.132089) (xy 102.895278 -261.140155)
			(xy 102.869492 -261.140702) (xy 102.853236 -261.140194) (xy 102.83063 -261.139178) (xy 102.71252 -261.257288)
			(xy 102.694479 -261.274548) (xy 102.652986 -261.302305) (xy 102.606868 -261.321416) (xy 102.557903 -261.331144)
			(xy 102.532942 -261.33171) (xy 102.200456 -261.33171) (xy 102.18801 -261.363968) (xy 102.177999 -261.388246)
			(xy 102.15139 -261.433518) (xy 102.117912 -261.473975) (xy 102.078419 -261.508586) (xy 102.033919 -261.536466)
			(xy 101.985548 -261.556905) (xy 101.934539 -261.569381) (xy 101.882194 -261.573575) (xy 101.829849 -261.569381)
			(xy 101.77884 -261.556905) (xy 101.730469 -261.536466) (xy 101.685969 -261.508586) (xy 101.646476 -261.473975)
			(xy 101.612998 -261.433518) (xy 101.586389 -261.388246) (xy 101.576378 -261.363968) (xy 101.563932 -261.33171)
			(xy 101.260656 -261.33171) (xy 101.24821 -261.363968) (xy 101.238199 -261.388246) (xy 101.21159 -261.433518)
			(xy 101.178112 -261.473975) (xy 101.138619 -261.508586) (xy 101.094119 -261.536466) (xy 101.045748 -261.556905)
			(xy 100.994739 -261.569381) (xy 100.942394 -261.573575) (xy 100.890049 -261.569381) (xy 100.83904 -261.556905)
			(xy 100.790669 -261.536466) (xy 100.746169 -261.508586) (xy 100.706676 -261.473975) (xy 100.673198 -261.433518)
			(xy 100.646589 -261.388246) (xy 100.636578 -261.363968) (xy 100.624132 -261.33171) (xy 100.320856 -261.33171)
			(xy 100.30841 -261.363968) (xy 100.298399 -261.388246) (xy 100.27179 -261.433518) (xy 100.238312 -261.473975)
			(xy 100.198819 -261.508586) (xy 100.154319 -261.536466) (xy 100.105948 -261.556905) (xy 100.054939 -261.569381)
			(xy 100.002594 -261.573575) (xy 99.950249 -261.569381) (xy 99.89924 -261.556905) (xy 99.850869 -261.536466)
			(xy 99.806369 -261.508586) (xy 99.766876 -261.473975) (xy 99.733398 -261.433518) (xy 99.706789 -261.388246)
			(xy 99.696778 -261.363968) (xy 99.684332 -261.33171) (xy 99.381056 -261.33171) (xy 99.36861 -261.363968)
			(xy 99.358599 -261.388246) (xy 99.33199 -261.433518) (xy 99.298512 -261.473975) (xy 99.259019 -261.508586)
			(xy 99.214519 -261.536466) (xy 99.166148 -261.556905) (xy 99.115139 -261.569381) (xy 99.062794 -261.573575)
			(xy 99.010449 -261.569381) (xy 98.95944 -261.556905) (xy 98.911069 -261.536466) (xy 98.866569 -261.508586)
			(xy 98.827076 -261.473975) (xy 98.793598 -261.433518) (xy 98.766989 -261.388246) (xy 98.756978 -261.363968)
			(xy 98.744532 -261.33171) (xy 98.441256 -261.33171) (xy 98.42881 -261.363968) (xy 98.418799 -261.388246)
			(xy 98.39219 -261.433518) (xy 98.358712 -261.473975) (xy 98.319219 -261.508586) (xy 98.274719 -261.536466)
			(xy 98.226348 -261.556905) (xy 98.175339 -261.569381) (xy 98.122994 -261.573575) (xy 98.070649 -261.569381)
			(xy 98.01964 -261.556905) (xy 97.971269 -261.536466) (xy 97.926769 -261.508586) (xy 97.887276 -261.473975)
			(xy 97.853798 -261.433518) (xy 97.827189 -261.388246) (xy 97.817178 -261.363968) (xy 97.804732 -261.33171)
			(xy 97.501456 -261.33171) (xy 97.48901 -261.363968) (xy 97.479667 -261.386743) (xy 97.455149 -261.429429)
			(xy 97.424528 -261.467973) (xy 97.388493 -261.501509) (xy 97.347852 -261.529286) (xy 97.303517 -261.550679)
			(xy 97.256484 -261.565207) (xy 97.207807 -261.572546) (xy 97.183194 -261.57301) (xy 97.157406 -261.572504)
			(xy 97.106464 -261.564435) (xy 97.057411 -261.548498) (xy 97.011455 -261.525083) (xy 96.969727 -261.494769)
			(xy 96.933255 -261.4583) (xy 96.902935 -261.416576) (xy 96.879516 -261.370623) (xy 96.863573 -261.321571)
			(xy 96.855499 -261.27063) (xy 96.855026 -261.244842) (xy 96.855533 -261.218517) (xy 96.863896 -261.166535)
			(xy 96.880432 -261.116549) (xy 96.89211 -261.09295) (xy 96.909382 -261.05993) (xy 96.580706 -260.731254)
			(xy 96.572578 -260.727444) (xy 96.548896 -260.715613) (xy 96.505334 -260.685539) (xy 96.467157 -260.64887)
			(xy 96.435352 -260.606556) (xy 96.410741 -260.55969) (xy 96.393963 -260.509485) (xy 96.385449 -260.457239)
			(xy 96.384872 -260.430772) (xy 96.385353 -260.405326) (xy 96.393215 -260.355046) (xy 96.408745 -260.306582)
			(xy 96.431571 -260.261097) (xy 96.461147 -260.219681) (xy 96.478598 -260.201156) (xy 96.478598 -259.032248)
			(xy 96.461216 -259.013751) (xy 96.431791 -258.972396) (xy 96.409084 -258.927003) (xy 96.393637 -258.878656)
			(xy 96.385818 -258.828506) (xy 96.385813 -258.777751) (xy 96.393624 -258.7276) (xy 96.409062 -258.67925)
			(xy 96.431761 -258.633853) (xy 96.461179 -258.592493) (xy 96.478598 -258.574032) (xy 96.478598 -257.404362)
			(xy 96.461223 -257.385866) (xy 96.431811 -257.344512) (xy 96.409116 -257.299124) (xy 96.393681 -257.250782)
			(xy 96.385873 -257.20064) (xy 96.385878 -257.149894) (xy 96.393696 -257.099754) (xy 96.409141 -257.051415)
			(xy 96.431845 -257.006031) (xy 96.461265 -256.964684) (xy 96.478598 -256.946146) (xy 96.478598 -255.77673)
			(xy 96.461218 -255.758233) (xy 96.431795 -255.716879) (xy 96.409091 -255.671487) (xy 96.393646 -255.62314)
			(xy 96.385829 -255.572992) (xy 96.385827 -255.522239) (xy 96.393639 -255.47209) (xy 96.409079 -255.423743)
			(xy 96.431779 -255.378349) (xy 96.461197 -255.336991) (xy 96.478598 -255.318514) (xy 96.478598 -254.148844)
			(xy 96.461217 -254.130347) (xy 96.431792 -254.088992) (xy 96.409086 -254.0436) (xy 96.393639 -253.995252)
			(xy 96.38582 -253.945103) (xy 96.385816 -253.894348) (xy 96.393627 -253.844198) (xy 96.409066 -253.795848)
			(xy 96.431765 -253.750452) (xy 96.461183 -253.709092) (xy 96.478598 -253.690628) (xy 96.478598 -249.111262)
			(xy 96.45142 -249.097038) (xy 96.429016 -249.084767) (xy 96.387972 -249.05436) (xy 96.352134 -249.017963)
			(xy 96.322366 -248.976454) (xy 96.299388 -248.930835) (xy 96.283753 -248.882207) (xy 96.27584 -248.831744)
			(xy 96.27584 -248.780664) (xy 96.283752 -248.730201) (xy 96.299385 -248.681572) (xy 96.322362 -248.635952)
			(xy 96.352129 -248.594442) (xy 96.387967 -248.558044) (xy 96.42901 -248.527637) (xy 96.45142 -248.515378)
			(xy 96.478598 -248.501154) (xy 96.478598 -247.483376) (xy 96.45142 -247.469152) (xy 96.428998 -247.456894)
			(xy 96.387918 -247.426506) (xy 96.352045 -247.390118) (xy 96.322247 -247.348608) (xy 96.299243 -247.302981)
			(xy 96.283591 -247.254339) (xy 96.275668 -247.203859) (xy 96.275667 -247.152761) (xy 96.283586 -247.102281)
			(xy 96.299236 -247.053638) (xy 96.322236 -247.008009) (xy 96.352032 -246.966498) (xy 96.387903 -246.930107)
			(xy 96.428981 -246.899717) (xy 96.45142 -246.887492) (xy 96.478598 -246.873268) (xy 96.478598 -245.855744)
			(xy 96.45142 -245.84152) (xy 96.429017 -245.829249) (xy 96.387976 -245.798843) (xy 96.352141 -245.762447)
			(xy 96.322376 -245.720939) (xy 96.299399 -245.675321) (xy 96.283767 -245.626695) (xy 96.275856 -245.576234)
			(xy 96.275856 -245.525157) (xy 96.283769 -245.474696) (xy 96.299403 -245.42607) (xy 96.32238 -245.380453)
			(xy 96.352147 -245.338946) (xy 96.387983 -245.302551) (xy 96.429025 -245.272146) (xy 96.45142 -245.25986)
			(xy 96.478598 -245.245636) (xy 96.478598 -244.227858) (xy 96.45142 -244.213634) (xy 96.429016 -244.201363)
			(xy 96.387973 -244.170957) (xy 96.352135 -244.13456) (xy 96.322368 -244.093051) (xy 96.29939 -244.047432)
			(xy 96.283756 -243.998804) (xy 96.275844 -243.948341) (xy 96.275843 -243.897262) (xy 96.283755 -243.8468)
			(xy 96.299389 -243.798172) (xy 96.322366 -243.752552) (xy 96.352133 -243.711043) (xy 96.38797 -243.674646)
			(xy 96.429013 -243.644239) (xy 96.45142 -243.631974) (xy 96.478598 -243.61775) (xy 96.478598 -242.599972)
			(xy 96.45142 -242.585748) (xy 96.429015 -242.573477) (xy 96.38797 -242.54307) (xy 96.35213 -242.506673)
			(xy 96.322361 -242.465163) (xy 96.299381 -242.419542) (xy 96.283746 -242.370913) (xy 96.275832 -242.320449)
			(xy 96.27583 -242.269368) (xy 96.283742 -242.218903) (xy 96.299375 -242.170273) (xy 96.322352 -242.124652)
			(xy 96.352119 -242.08314) (xy 96.387957 -242.046741) (xy 96.429001 -242.016332) (xy 96.45142 -242.004088)
			(xy 96.478598 -241.989864) (xy 96.478598 -240.97234) (xy 96.45142 -240.958116) (xy 96.429018 -240.945845)
			(xy 96.387977 -240.915439) (xy 96.352142 -240.879043) (xy 96.322378 -240.837535) (xy 96.299402 -240.791918)
			(xy 96.28377 -240.743292) (xy 96.275859 -240.692832) (xy 96.27586 -240.641755) (xy 96.283773 -240.591295)
			(xy 96.299407 -240.54267) (xy 96.322384 -240.497054) (xy 96.352151 -240.455547) (xy 96.387987 -240.419152)
			(xy 96.429029 -240.388748) (xy 96.45142 -240.376456) (xy 96.478598 -240.362232) (xy 96.478598 -239.344454)
			(xy 96.45142 -239.33023) (xy 96.429017 -239.317959) (xy 96.387974 -239.287553) (xy 96.352137 -239.251156)
			(xy 96.32237 -239.209647) (xy 96.299393 -239.164029) (xy 96.283759 -239.115401) (xy 96.275847 -239.064939)
			(xy 96.275847 -239.013861) (xy 96.283759 -238.963399) (xy 96.299393 -238.914771) (xy 96.32237 -238.869153)
			(xy 96.352137 -238.827644) (xy 96.387974 -238.791247) (xy 96.429017 -238.760841) (xy 96.45142 -238.74857)
			(xy 96.478598 -238.734346) (xy 96.478598 -237.716568) (xy 96.45142 -237.702344) (xy 96.429016 -237.690073)
			(xy 96.387971 -237.659666) (xy 96.352132 -237.623269) (xy 96.322363 -237.581759) (xy 96.299384 -237.536139)
			(xy 96.283749 -237.487511) (xy 96.275835 -237.437047) (xy 96.275834 -237.385966) (xy 96.283746 -237.335502)
			(xy 96.299379 -237.286873) (xy 96.322356 -237.241252) (xy 96.352123 -237.199741) (xy 96.387961 -237.163342)
			(xy 96.429005 -237.132934) (xy 96.45142 -237.120684) (xy 96.478598 -237.10646) (xy 96.478598 -236.088936)
			(xy 96.45142 -236.074712) (xy 96.429018 -236.062441) (xy 96.387978 -236.032035) (xy 96.352144 -235.995639)
			(xy 96.32238 -235.954132) (xy 96.299404 -235.908515) (xy 96.283773 -235.85989) (xy 96.275862 -235.80943)
			(xy 96.275864 -235.758354) (xy 96.283777 -235.707894) (xy 96.299411 -235.65927) (xy 96.322388 -235.613654)
			(xy 96.352155 -235.572148) (xy 96.387991 -235.535754) (xy 96.429032 -235.50535) (xy 96.45142 -235.493052)
			(xy 96.478598 -235.478828) (xy 96.478598 -234.93857) (xy 96.479212 -234.913615) (xy 96.488955 -234.864664)
			(xy 96.508059 -234.818554) (xy 96.535792 -234.777057) (xy 96.55302 -234.758992) (xy 97.221548 -234.090464)
			(xy 97.22485 -234.076748) (xy 97.231451 -234.052238) (xy 97.251168 -234.005467) (xy 97.277848 -233.962287)
			(xy 97.310856 -233.923728) (xy 97.349405 -233.890708) (xy 97.392576 -233.864015) (xy 97.439341 -233.844283)
			(xy 97.463864 -233.837734) (xy 97.47758 -233.834432) (xy 97.758758 -233.553254) (xy 97.73666 -233.518964)
			(xy 97.724452 -233.499065) (xy 97.705171 -233.456551) (xy 97.692103 -233.411736) (xy 97.685511 -233.365521)
			(xy 97.685098 -233.34218) (xy 97.685605 -233.316392) (xy 97.693676 -233.265453) (xy 97.709615 -233.216402)
			(xy 97.73303 -233.170449) (xy 97.763345 -233.128724) (xy 97.799813 -233.092254) (xy 97.841537 -233.061937)
			(xy 97.887489 -233.03852) (xy 97.936539 -233.022579) (xy 97.987478 -233.014506) (xy 98.013266 -233.014012)
			(xy 98.03661 -233.014401) (xy 98.082831 -233.020978) (xy 98.127651 -233.034047) (xy 98.170164 -233.053343)
			(xy 98.19005 -233.065574) (xy 98.22434 -233.087672) (xy 99.565206 -231.746806) (xy 99.564698 -231.724708)
			(xy 99.564444 -231.714548) (xy 99.56492 -231.688756) (xy 99.572983 -231.637807) (xy 99.588917 -231.588746)
			(xy 99.612332 -231.542783) (xy 99.642649 -231.501049) (xy 99.679121 -231.464572) (xy 99.720852 -231.43425)
			(xy 99.766813 -231.410831) (xy 99.815872 -231.394891) (xy 99.86682 -231.386823) (xy 99.892612 -231.38638)
			(xy 99.902772 -231.386634) (xy 99.92487 -231.387142) (xy 101.931216 -229.380796) (xy 101.924104 -229.352856)
			(xy 101.919476 -229.333178) (xy 101.914507 -229.293059) (xy 101.914198 -229.272846) (xy 101.914674 -229.247053)
			(xy 101.922737 -229.196101) (xy 101.938671 -229.147038) (xy 101.962085 -229.101072) (xy 101.992401 -229.059334)
			(xy 102.028873 -229.022853) (xy 102.070603 -228.992526) (xy 102.116564 -228.969102) (xy 102.165623 -228.953155)
			(xy 102.216573 -228.94508) (xy 102.242366 -228.944678) (xy 102.26258 -228.944975) (xy 102.302701 -228.94994)
			(xy 102.322376 -228.954584) (xy 102.350316 -228.961696) (xy 102.429818 -228.882194) (xy 102.429818 -228.626924)
			(xy 102.423722 -228.615748) (xy 102.411171 -228.591553) (xy 102.393394 -228.54003) (xy 102.38438 -228.486278)
			(xy 102.384375 -228.431775) (xy 102.393381 -228.378021) (xy 102.411149 -228.326495) (xy 102.423722 -228.302312)
			(xy 102.429818 -228.291136) (xy 102.429818 -226.999038) (xy 102.423722 -226.987862) (xy 102.41117 -226.963667)
			(xy 102.393391 -226.912144) (xy 102.384374 -226.858391) (xy 102.384368 -226.803886) (xy 102.393372 -226.750131)
			(xy 102.411138 -226.698604) (xy 102.423722 -226.674426) (xy 102.429818 -226.66325) (xy 102.429818 -225.373946)
			(xy 102.423468 -225.362516) (xy 102.410549 -225.337978) (xy 102.392211 -225.285646) (xy 102.382889 -225.230983)
			(xy 102.38232 -225.203258) (xy 102.382911 -225.17554) (xy 102.392235 -225.120894) (xy 102.400862 -225.094546)
			(xy 102.408736 -225.072448) (xy 102.203758 -224.71761) (xy 102.180898 -224.713292) (xy 102.156095 -224.708095)
			(xy 102.108354 -224.691108) (xy 102.063773 -224.667016) (xy 102.023404 -224.636387) (xy 101.988196 -224.599942)
			(xy 101.958978 -224.55854) (xy 101.936439 -224.513155) (xy 101.921109 -224.464855) (xy 101.91335 -224.414779)
			(xy 101.912928 -224.389442) (xy 101.913406 -224.363549) (xy 101.921501 -224.312401) (xy 101.937497 -224.263148)
			(xy 101.961001 -224.217005) (xy 101.991435 -224.175106) (xy 102.028048 -224.138484) (xy 102.06994 -224.108041)
			(xy 102.116078 -224.084526) (xy 102.165327 -224.068518) (xy 102.216474 -224.060412) (xy 102.242366 -224.060004)
			(xy 102.258857 -224.060161) (xy 102.291685 -224.063338) (xy 102.307898 -224.066354) (xy 102.322715 -224.06883)
			(xy 102.35261 -224.066018) (xy 102.380396 -224.054639) (xy 102.403675 -224.035674) (xy 102.420436 -224.010761)
			(xy 102.429232 -223.982052) (xy 102.429818 -223.96704) (xy 102.429818 -223.743266) (xy 102.423722 -223.731836)
			(xy 102.411293 -223.70769) (xy 102.39365 -223.656333) (xy 102.38468 -223.602777) (xy 102.384098 -223.575626)
			(xy 102.384623 -223.548469) (xy 102.393568 -223.494897) (xy 102.411234 -223.443537) (xy 102.423722 -223.419416)
			(xy 102.429818 -223.407986) (xy 102.429818 -222.118428) (xy 102.423468 -222.106998) (xy 102.41055 -222.082459)
			(xy 102.392215 -222.030127) (xy 102.382896 -221.975465) (xy 102.38232 -221.94774) (xy 102.382913 -221.920023)
			(xy 102.392239 -221.865377) (xy 102.400862 -221.839028) (xy 102.408736 -221.81693) (xy 102.203758 -221.462092)
			(xy 102.180898 -221.457774) (xy 102.156096 -221.452577) (xy 102.108356 -221.435589) (xy 102.063777 -221.411497)
			(xy 102.023409 -221.380868) (xy 101.988203 -221.344423) (xy 101.958987 -221.30302) (xy 101.936451 -221.257635)
			(xy 101.921123 -221.209336) (xy 101.913367 -221.15926) (xy 101.912928 -221.133924) (xy 101.913418 -221.108253)
			(xy 101.921386 -221.057534) (xy 101.937131 -221.008666) (xy 101.960273 -220.962836) (xy 101.990249 -220.921154)
			(xy 102.007924 -220.90253) (xy 102.016926 -220.892782) (xy 102.030042 -220.869728) (xy 102.036776 -220.844073)
			(xy 102.036674 -220.817549) (xy 102.029743 -220.791947) (xy 102.016451 -220.768995) (xy 102.007416 -220.759274)
			(xy 101.88067 -220.632528) (xy 101.85273 -220.639386) (xy 101.83368 -220.643704) (xy 101.81082 -220.648022)
			(xy 101.605842 -221.003114) (xy 101.613716 -221.024958) (xy 101.622297 -221.051376) (xy 101.631497 -221.106152)
			(xy 101.632004 -221.133924) (xy 101.631496 -221.159811) (xy 101.623397 -221.210949) (xy 101.607398 -221.260189)
			(xy 101.583892 -221.306321) (xy 101.55346 -221.348208) (xy 101.51685 -221.384818) (xy 101.474963 -221.41525)
			(xy 101.428831 -221.438756) (xy 101.379591 -221.454755) (xy 101.328453 -221.462854) (xy 101.276679 -221.462854)
			(xy 101.225541 -221.454755) (xy 101.176301 -221.438756) (xy 101.130169 -221.41525) (xy 101.088282 -221.384818)
			(xy 101.051672 -221.348208) (xy 101.02124 -221.306321) (xy 100.997734 -221.260189) (xy 100.981735 -221.210949)
			(xy 100.973636 -221.159811) (xy 100.973128 -221.133924) (xy 100.97359 -221.108588) (xy 100.98134 -221.058511)
			(xy 100.996662 -221.01021) (xy 101.019194 -220.964822) (xy 101.048405 -220.923417) (xy 101.083609 -220.886969)
			(xy 101.123975 -220.856337) (xy 101.168553 -220.832242) (xy 101.216292 -220.815252) (xy 101.241098 -220.810074)
			(xy 101.263958 -220.805756) (xy 101.468936 -220.450664) (xy 101.461062 -220.42882) (xy 101.452419 -220.402411)
			(xy 101.443103 -220.347635) (xy 101.44252 -220.319854) (xy 101.442884 -220.299508) (xy 101.447983 -220.259136)
			(xy 101.45268 -220.239336) (xy 101.459538 -220.211396) (xy 100.714556 -219.466414) (xy 100.6973 -219.448372)
			(xy 100.669549 -219.406877) (xy 100.650444 -219.360759) (xy 100.640719 -219.311796) (xy 100.640134 -219.286836)
			(xy 100.640134 -218.959938) (xy 100.619248 -218.944349) (xy 100.582212 -218.907684) (xy 100.551412 -218.865645)
			(xy 100.527616 -218.81928) (xy 100.511419 -218.769746) (xy 100.503224 -218.71828) (xy 100.50272 -218.692222)
			(xy 100.503306 -218.664503) (xy 100.51262 -218.609853) (xy 100.521262 -218.58351) (xy 100.529136 -218.561412)
			(xy 100.324158 -218.206574) (xy 100.301298 -218.202256) (xy 100.276497 -218.197058) (xy 100.228758 -218.18007)
			(xy 100.18418 -218.155978) (xy 100.143814 -218.125348) (xy 100.10861 -218.088903) (xy 100.079396 -218.0475)
			(xy 100.056862 -218.002115) (xy 100.041537 -217.953817) (xy 100.033783 -217.903742) (xy 100.033328 -217.878406)
			(xy 100.033835 -217.852517) (xy 100.041934 -217.801377) (xy 100.057932 -217.752134) (xy 100.081436 -217.705999)
			(xy 100.111868 -217.664108) (xy 100.148478 -217.627494) (xy 100.190364 -217.597057) (xy 100.236497 -217.573547)
			(xy 100.285738 -217.557543) (xy 100.336877 -217.549438) (xy 100.362766 -217.548968) (xy 100.385834 -217.549363)
			(xy 100.431525 -217.555753) (xy 100.475889 -217.568415) (xy 100.497132 -217.577416) (xy 100.510548 -217.582841)
			(xy 100.53921 -217.586738) (xy 100.567814 -217.582443) (xy 100.594068 -217.570302) (xy 100.615865 -217.551287)
			(xy 100.631458 -217.526925) (xy 100.639596 -217.499168) (xy 100.640134 -217.484706) (xy 100.640134 -217.33002)
			(xy 100.619494 -217.314489) (xy 100.582909 -217.278024) (xy 100.552493 -217.236276) (xy 100.528997 -217.190276)
			(xy 100.513001 -217.141162) (xy 100.504901 -217.090148) (xy 100.504898 -217.038494) (xy 100.512991 -216.987479)
			(xy 100.52898 -216.938363) (xy 100.552471 -216.89236) (xy 100.582882 -216.850608) (xy 100.619461 -216.814139)
			(xy 100.640134 -216.798652) (xy 100.640134 -215.70442) (xy 100.619249 -215.688829) (xy 100.582214 -215.652162)
			(xy 100.551413 -215.610123) (xy 100.527613 -215.563759) (xy 100.511409 -215.514226) (xy 100.503205 -215.46276)
			(xy 100.503205 -215.410644) (xy 100.511408 -215.359179) (xy 100.527612 -215.309646) (xy 100.55141 -215.263281)
			(xy 100.582211 -215.221241) (xy 100.619246 -215.184574) (xy 100.640134 -215.168988) (xy 100.640134 -215.01608)
			(xy 100.639621 -215.00159) (xy 100.631477 -214.973778) (xy 100.615851 -214.949371) (xy 100.594001 -214.930335)
			(xy 100.567683 -214.918201) (xy 100.539017 -214.913945) (xy 100.51031 -214.91791) (xy 100.496878 -214.92337)
			(xy 100.475616 -214.932468) (xy 100.431178 -214.945274) (xy 100.385382 -214.951717) (xy 100.362258 -214.952072)
			(xy 100.336372 -214.951561) (xy 100.285238 -214.943457) (xy 100.236 -214.927454) (xy 100.189872 -214.903947)
			(xy 100.147988 -214.873515) (xy 100.11138 -214.836906) (xy 100.080948 -214.795021) (xy 100.057443 -214.748892)
			(xy 100.041441 -214.699655) (xy 100.033338 -214.64852) (xy 100.03282 -214.622634) (xy 100.033181 -214.599657)
			(xy 100.039493 -214.554141) (xy 100.052069 -214.509943) (xy 100.061014 -214.488776) (xy 100.07092 -214.466424)
			(xy 99.857306 -214.061294) (xy 99.833176 -214.056722) (xy 99.808255 -214.051631) (xy 99.760254 -214.034807)
			(xy 99.715406 -214.010813) (xy 99.674773 -213.980218) (xy 99.639318 -213.943748) (xy 99.609882 -213.902268)
			(xy 99.587163 -213.856761) (xy 99.571699 -213.808305) (xy 99.563858 -213.758049) (xy 99.563428 -213.732618)
			(xy 99.563936 -213.706731) (xy 99.572035 -213.655593) (xy 99.588034 -213.606353) (xy 99.61154 -213.560221)
			(xy 99.641972 -213.518334) (xy 99.678582 -213.481724) (xy 99.720469 -213.451292) (xy 99.766601 -213.427786)
			(xy 99.815841 -213.411787) (xy 99.866979 -213.403688) (xy 99.918753 -213.403688) (xy 99.969891 -213.411787)
			(xy 100.019131 -213.427786) (xy 100.065263 -213.451292) (xy 100.10715 -213.481724) (xy 100.14376 -213.518334)
			(xy 100.174192 -213.560221) (xy 100.197698 -213.606353) (xy 100.213697 -213.655593) (xy 100.221796 -213.706731)
			(xy 100.222304 -213.732618) (xy 100.221939 -213.755594) (xy 100.215621 -213.801108) (xy 100.20304 -213.845303)
			(xy 100.19411 -213.866476) (xy 100.184204 -213.888828) (xy 100.397818 -214.293958) (xy 100.421948 -214.29853)
			(xy 100.441244 -214.302388) (xy 100.478811 -214.314102) (xy 100.496878 -214.321898) (xy 100.510306 -214.327368)
			(xy 100.539014 -214.331335) (xy 100.56768 -214.327079) (xy 100.593997 -214.314943) (xy 100.615846 -214.295903)
			(xy 100.631468 -214.271493) (xy 100.639605 -214.243678) (xy 100.640134 -214.229188) (xy 100.640134 -213.998302)
			(xy 100.619495 -213.982774) (xy 100.582917 -213.946314) (xy 100.55251 -213.904567) (xy 100.529029 -213.858567)
			(xy 100.513053 -213.809453) (xy 100.50498 -213.758442) (xy 100.504498 -213.732618) (xy 100.504928 -213.708732)
			(xy 100.511856 -213.661464) (xy 100.525567 -213.615701) (xy 100.545772 -213.572411) (xy 100.572044 -213.532511)
			(xy 100.603826 -213.496843) (xy 100.621846 -213.481158) (xy 100.640134 -213.465918) (xy 100.640134 -213.38286)
			(xy 90.686382 -207.382872) (xy 90.658696 -207.417416) (xy 90.616807 -207.468784) (xy 90.527782 -207.567004)
			(xy 90.433063 -207.659746) (xy 90.332988 -207.746679) (xy 90.22791 -207.827496) (xy 90.118204 -207.901909)
			(xy 90.00426 -207.969653) (xy 89.886482 -208.030488) (xy 89.765288 -208.084198) (xy 89.64111 -208.130592)
			(xy 89.514389 -208.169505) (xy 89.385574 -208.200799) (xy 89.255123 -208.224363) (xy 89.1235 -208.240112)
			(xy 88.991173 -208.247992) (xy 88.924892 -208.248504) (xy 88.85772 -208.248007) (xy 88.72362 -208.239895)
			(xy 88.590255 -208.223701) (xy 88.458112 -208.199484) (xy 88.327671 -208.167333) (xy 88.19941 -208.127364)
			(xy 88.073796 -208.079724) (xy 87.951287 -208.024587) (xy 87.832331 -207.962154) (xy 87.717362 -207.892652)
			(xy 87.606799 -207.816335) (xy 87.501045 -207.733482) (xy 87.400487 -207.644394) (xy 87.305492 -207.549398)
			(xy 87.216406 -207.448839) (xy 87.133553 -207.343085) (xy 87.057237 -207.232521) (xy 86.987736 -207.117552)
			(xy 86.925304 -206.998595) (xy 86.870168 -206.876086) (xy 86.822529 -206.750471) (xy 86.782562 -206.62221)
			(xy 86.750412 -206.491769) (xy 86.726196 -206.359625) (xy 86.710004 -206.22626) (xy 86.701893 -206.09216)
			(xy 86.701376 -206.024988) (xy 86.701855 -205.959707) (xy 86.709517 -205.829369) (xy 86.724813 -205.699706)
			(xy 86.74769 -205.571163) (xy 86.778071 -205.444185) (xy 86.815849 -205.319207) (xy 86.860896 -205.196662)
			(xy 86.913056 -205.076971) (xy 86.972148 -204.960546) (xy 87.037971 -204.84779) (xy 87.110295 -204.73909)
			(xy 87.188873 -204.634821) (xy 87.273434 -204.535342) (xy 87.363686 -204.440996) (xy 87.459319 -204.352108)
			(xy 87.560002 -204.268985) (xy 87.665389 -204.191913) (xy 87.775116 -204.121157) (xy 87.888807 -204.056961)
			(xy 88.006068 -203.999547) (xy 88.066118 -203.973938) (xy 88.107012 -203.956666) (xy 86.495128 -197.951598)
			(xy 86.486746 -197.942454) (xy 86.469443 -197.922794) (xy 86.440226 -197.879329) (xy 86.417738 -197.832031)
			(xy 86.40247 -197.781934) (xy 86.394755 -197.730134) (xy 86.39429 -197.703948) (xy 86.394529 -197.684874)
			(xy 86.398597 -197.646945) (xy 86.402418 -197.628256) (xy 86.405212 -197.616064) (xy 85.700616 -194.991482)
			(xy 76.85659 -175.174656) (xy 74.874882 -173.192948) (xy 68.072 -173.192948) (xy 68.04704 -173.192377)
			(xy 67.998079 -173.182636) (xy 67.951961 -173.163529) (xy 67.910457 -173.13579) (xy 67.892422 -173.118526)
			(xy 65.579244 -170.805348) (xy 61.852556 -170.805348) (xy 61.39434 -171.263564) (xy 61.39434 -213.732618)
			(xy 90.165428 -213.732618) (xy 90.165936 -213.706731) (xy 90.174035 -213.655593) (xy 90.190034 -213.606353)
			(xy 90.21354 -213.560221) (xy 90.243972 -213.518334) (xy 90.280582 -213.481724) (xy 90.322469 -213.451292)
			(xy 90.368601 -213.427786) (xy 90.417841 -213.411787) (xy 90.468979 -213.403688) (xy 90.520753 -213.403688)
			(xy 90.571891 -213.411787) (xy 90.621131 -213.427786) (xy 90.667263 -213.451292) (xy 90.70915 -213.481724)
			(xy 90.74576 -213.518334) (xy 90.776192 -213.560221) (xy 90.799698 -213.606353) (xy 90.815697 -213.655593)
			(xy 90.823796 -213.706731) (xy 90.824304 -213.732618) (xy 92.045028 -213.732618) (xy 92.045536 -213.706731)
			(xy 92.053635 -213.655593) (xy 92.069634 -213.606353) (xy 92.09314 -213.560221) (xy 92.123572 -213.518334)
			(xy 92.160182 -213.481724) (xy 92.202069 -213.451292) (xy 92.248201 -213.427786) (xy 92.297441 -213.411787)
			(xy 92.348579 -213.403688) (xy 92.400353 -213.403688) (xy 92.451491 -213.411787) (xy 92.500731 -213.427786)
			(xy 92.546863 -213.451292) (xy 92.58875 -213.481724) (xy 92.62536 -213.518334) (xy 92.655792 -213.560221)
			(xy 92.679298 -213.606353) (xy 92.695297 -213.655593) (xy 92.703396 -213.706731) (xy 92.703904 -213.732618)
			(xy 93.924628 -213.732618) (xy 93.925136 -213.706731) (xy 93.933235 -213.655593) (xy 93.949234 -213.606353)
			(xy 93.97274 -213.560221) (xy 94.003172 -213.518334) (xy 94.039782 -213.481724) (xy 94.081669 -213.451292)
			(xy 94.127801 -213.427786) (xy 94.177041 -213.411787) (xy 94.228179 -213.403688) (xy 94.279953 -213.403688)
			(xy 94.331091 -213.411787) (xy 94.380331 -213.427786) (xy 94.426463 -213.451292) (xy 94.46835 -213.481724)
			(xy 94.50496 -213.518334) (xy 94.535392 -213.560221) (xy 94.558898 -213.606353) (xy 94.574897 -213.655593)
			(xy 94.582996 -213.706731) (xy 94.583504 -213.732618) (xy 95.804228 -213.732618) (xy 95.804736 -213.706731)
			(xy 95.812835 -213.655593) (xy 95.828834 -213.606353) (xy 95.85234 -213.560221) (xy 95.882772 -213.518334)
			(xy 95.919382 -213.481724) (xy 95.961269 -213.451292) (xy 96.007401 -213.427786) (xy 96.056641 -213.411787)
			(xy 96.107779 -213.403688) (xy 96.159553 -213.403688) (xy 96.210691 -213.411787) (xy 96.259931 -213.427786)
			(xy 96.306063 -213.451292) (xy 96.34795 -213.481724) (xy 96.38456 -213.518334) (xy 96.414992 -213.560221)
			(xy 96.438498 -213.606353) (xy 96.454497 -213.655593) (xy 96.462596 -213.706731) (xy 96.463104 -213.732618)
			(xy 97.683828 -213.732618) (xy 97.684336 -213.706731) (xy 97.692435 -213.655593) (xy 97.708434 -213.606353)
			(xy 97.73194 -213.560221) (xy 97.762372 -213.518334) (xy 97.798982 -213.481724) (xy 97.840869 -213.451292)
			(xy 97.887001 -213.427786) (xy 97.936241 -213.411787) (xy 97.987379 -213.403688) (xy 98.039153 -213.403688)
			(xy 98.090291 -213.411787) (xy 98.139531 -213.427786) (xy 98.185663 -213.451292) (xy 98.22755 -213.481724)
			(xy 98.26416 -213.518334) (xy 98.294592 -213.560221) (xy 98.318098 -213.606353) (xy 98.334097 -213.655593)
			(xy 98.342196 -213.706731) (xy 98.342704 -213.732618) (xy 98.342353 -213.755595) (xy 98.336032 -213.80111)
			(xy 98.323448 -213.845306) (xy 98.31451 -213.866476) (xy 98.304604 -213.888828) (xy 98.518218 -214.293958)
			(xy 98.542348 -214.29853) (xy 98.567267 -214.303641) (xy 98.615277 -214.320441) (xy 98.660136 -214.344419)
			(xy 98.700776 -214.375006) (xy 98.736234 -214.411476) (xy 98.765666 -214.452961) (xy 98.788373 -214.498476)
			(xy 98.803815 -214.54694) (xy 98.811627 -214.597201) (xy 98.812096 -214.622634) (xy 98.811588 -214.648521)
			(xy 98.803489 -214.699659) (xy 98.78749 -214.748899) (xy 98.763984 -214.795031) (xy 98.733552 -214.836918)
			(xy 98.696942 -214.873528) (xy 98.655055 -214.90396) (xy 98.608923 -214.927466) (xy 98.559683 -214.943465)
			(xy 98.508545 -214.951564) (xy 98.456771 -214.951564) (xy 98.405633 -214.943465) (xy 98.356393 -214.927466)
			(xy 98.310261 -214.90396) (xy 98.268374 -214.873528) (xy 98.231764 -214.836918) (xy 98.201332 -214.795031)
			(xy 98.177826 -214.748899) (xy 98.161827 -214.699659) (xy 98.153728 -214.648521) (xy 98.15322 -214.622634)
			(xy 98.153587 -214.599658) (xy 98.1599 -214.554143) (xy 98.172479 -214.509947) (xy 98.181414 -214.488776)
			(xy 98.19132 -214.466424) (xy 97.977706 -214.061294) (xy 97.953576 -214.056722) (xy 97.92865 -214.051639)
			(xy 97.880636 -214.034839) (xy 97.835775 -214.010859) (xy 97.795132 -213.980269) (xy 97.759674 -213.943796)
			(xy 97.730243 -213.902307) (xy 97.707538 -213.856787) (xy 97.6921 -213.808318) (xy 97.684294 -213.758052)
			(xy 97.683828 -213.732618) (xy 96.463104 -213.732618) (xy 96.462753 -213.755595) (xy 96.456432 -213.80111)
			(xy 96.443848 -213.845306) (xy 96.43491 -213.866476) (xy 96.425004 -213.888828) (xy 96.638618 -214.293958)
			(xy 96.662748 -214.29853) (xy 96.687667 -214.303641) (xy 96.735677 -214.320441) (xy 96.780536 -214.344419)
			(xy 96.821176 -214.375006) (xy 96.856634 -214.411476) (xy 96.886066 -214.452961) (xy 96.908773 -214.498476)
			(xy 96.924215 -214.54694) (xy 96.932027 -214.597201) (xy 96.932496 -214.622634) (xy 96.931988 -214.648521)
			(xy 96.923889 -214.699659) (xy 96.90789 -214.748899) (xy 96.884384 -214.795031) (xy 96.853952 -214.836918)
			(xy 96.817342 -214.873528) (xy 96.775455 -214.90396) (xy 96.729323 -214.927466) (xy 96.680083 -214.943465)
			(xy 96.628945 -214.951564) (xy 96.577171 -214.951564) (xy 96.526033 -214.943465) (xy 96.476793 -214.927466)
			(xy 96.430661 -214.90396) (xy 96.388774 -214.873528) (xy 96.352164 -214.836918) (xy 96.321732 -214.795031)
			(xy 96.298226 -214.748899) (xy 96.282227 -214.699659) (xy 96.274128 -214.648521) (xy 96.27362 -214.622634)
			(xy 96.273987 -214.599658) (xy 96.2803 -214.554143) (xy 96.292879 -214.509947) (xy 96.301814 -214.488776)
			(xy 96.31172 -214.466424) (xy 96.098106 -214.061294) (xy 96.073976 -214.056722) (xy 96.04905 -214.051639)
			(xy 96.001036 -214.034839) (xy 95.956175 -214.010859) (xy 95.915532 -213.980269) (xy 95.880074 -213.943796)
			(xy 95.850643 -213.902307) (xy 95.827938 -213.856787) (xy 95.8125 -213.808318) (xy 95.804694 -213.758052)
			(xy 95.804228 -213.732618) (xy 94.583504 -213.732618) (xy 94.583153 -213.755595) (xy 94.576832 -213.80111)
			(xy 94.564248 -213.845306) (xy 94.55531 -213.866476) (xy 94.545404 -213.888828) (xy 94.759018 -214.293958)
			(xy 94.783148 -214.29853) (xy 94.808067 -214.303641) (xy 94.856077 -214.320441) (xy 94.900936 -214.344419)
			(xy 94.941576 -214.375006) (xy 94.977034 -214.411476) (xy 95.006466 -214.452961) (xy 95.029173 -214.498476)
			(xy 95.044615 -214.54694) (xy 95.052427 -214.597201) (xy 95.052896 -214.622634) (xy 95.052388 -214.648521)
			(xy 95.044289 -214.699659) (xy 95.02829 -214.748899) (xy 95.004784 -214.795031) (xy 94.974352 -214.836918)
			(xy 94.937742 -214.873528) (xy 94.895855 -214.90396) (xy 94.849723 -214.927466) (xy 94.800483 -214.943465)
			(xy 94.749345 -214.951564) (xy 94.697571 -214.951564) (xy 94.646433 -214.943465) (xy 94.597193 -214.927466)
			(xy 94.551061 -214.90396) (xy 94.509174 -214.873528) (xy 94.472564 -214.836918) (xy 94.442132 -214.795031)
			(xy 94.418626 -214.748899) (xy 94.402627 -214.699659) (xy 94.394528 -214.648521) (xy 94.39402 -214.622634)
			(xy 94.394387 -214.599658) (xy 94.4007 -214.554143) (xy 94.413279 -214.509947) (xy 94.422214 -214.488776)
			(xy 94.43212 -214.466424) (xy 94.218506 -214.061294) (xy 94.194376 -214.056722) (xy 94.16945 -214.051639)
			(xy 94.121436 -214.034839) (xy 94.076575 -214.010859) (xy 94.035932 -213.980269) (xy 94.000474 -213.943796)
			(xy 93.971043 -213.902307) (xy 93.948338 -213.856787) (xy 93.9329 -213.808318) (xy 93.925094 -213.758052)
			(xy 93.924628 -213.732618) (xy 92.703904 -213.732618) (xy 92.703553 -213.755595) (xy 92.697232 -213.80111)
			(xy 92.684648 -213.845306) (xy 92.67571 -213.866476) (xy 92.665804 -213.888828) (xy 92.879418 -214.293958)
			(xy 92.903548 -214.29853) (xy 92.928467 -214.303641) (xy 92.976477 -214.320441) (xy 93.021336 -214.344419)
			(xy 93.061976 -214.375006) (xy 93.097434 -214.411476) (xy 93.126866 -214.452961) (xy 93.149573 -214.498476)
			(xy 93.165015 -214.54694) (xy 93.172827 -214.597201) (xy 93.173296 -214.622634) (xy 93.172788 -214.648521)
			(xy 93.164689 -214.699659) (xy 93.14869 -214.748899) (xy 93.125184 -214.795031) (xy 93.094752 -214.836918)
			(xy 93.058142 -214.873528) (xy 93.016255 -214.90396) (xy 92.970123 -214.927466) (xy 92.920883 -214.943465)
			(xy 92.869745 -214.951564) (xy 92.817971 -214.951564) (xy 92.766833 -214.943465) (xy 92.717593 -214.927466)
			(xy 92.671461 -214.90396) (xy 92.629574 -214.873528) (xy 92.592964 -214.836918) (xy 92.562532 -214.795031)
			(xy 92.539026 -214.748899) (xy 92.523027 -214.699659) (xy 92.514928 -214.648521) (xy 92.51442 -214.622634)
			(xy 92.514787 -214.599658) (xy 92.5211 -214.554143) (xy 92.533679 -214.509947) (xy 92.542614 -214.488776)
			(xy 92.55252 -214.466424) (xy 92.338906 -214.061294) (xy 92.314776 -214.056722) (xy 92.28985 -214.051639)
			(xy 92.241836 -214.034839) (xy 92.196975 -214.010859) (xy 92.156332 -213.980269) (xy 92.120874 -213.943796)
			(xy 92.091443 -213.902307) (xy 92.068738 -213.856787) (xy 92.0533 -213.808318) (xy 92.045494 -213.758052)
			(xy 92.045028 -213.732618) (xy 90.824304 -213.732618) (xy 90.823953 -213.755595) (xy 90.817632 -213.80111)
			(xy 90.805048 -213.845306) (xy 90.79611 -213.866476) (xy 90.786204 -213.888828) (xy 90.999818 -214.293958)
			(xy 91.023948 -214.29853) (xy 91.048867 -214.303641) (xy 91.096877 -214.320441) (xy 91.141736 -214.344419)
			(xy 91.182376 -214.375006) (xy 91.217834 -214.411476) (xy 91.247266 -214.452961) (xy 91.269973 -214.498476)
			(xy 91.285415 -214.54694) (xy 91.293227 -214.597201) (xy 91.293696 -214.622634) (xy 91.293188 -214.648521)
			(xy 91.285089 -214.699659) (xy 91.26909 -214.748899) (xy 91.245584 -214.795031) (xy 91.215152 -214.836918)
			(xy 91.178542 -214.873528) (xy 91.136655 -214.90396) (xy 91.090523 -214.927466) (xy 91.041283 -214.943465)
			(xy 90.990145 -214.951564) (xy 90.938371 -214.951564) (xy 90.887233 -214.943465) (xy 90.837993 -214.927466)
			(xy 90.791861 -214.90396) (xy 90.749974 -214.873528) (xy 90.713364 -214.836918) (xy 90.682932 -214.795031)
			(xy 90.659426 -214.748899) (xy 90.643427 -214.699659) (xy 90.635328 -214.648521) (xy 90.63482 -214.622634)
			(xy 90.635187 -214.599658) (xy 90.6415 -214.554143) (xy 90.654079 -214.509947) (xy 90.663014 -214.488776)
			(xy 90.67292 -214.466424) (xy 90.459306 -214.061294) (xy 90.435176 -214.056722) (xy 90.41025 -214.051639)
			(xy 90.362236 -214.034839) (xy 90.317375 -214.010859) (xy 90.276732 -213.980269) (xy 90.241274 -213.943796)
			(xy 90.211843 -213.902307) (xy 90.189138 -213.856787) (xy 90.1737 -213.808318) (xy 90.165894 -213.758052)
			(xy 90.165428 -213.732618) (xy 61.39434 -213.732618) (xy 61.39434 -215.436704) (xy 88.28532 -215.436704)
			(xy 88.285828 -215.410797) (xy 88.293934 -215.35962) (xy 88.309946 -215.310341) (xy 88.333469 -215.264174)
			(xy 88.363925 -215.222255) (xy 88.400563 -215.185617) (xy 88.442482 -215.155161) (xy 88.488649 -215.131638)
			(xy 88.537928 -215.115626) (xy 88.589105 -215.10752) (xy 88.640919 -215.10752) (xy 88.692096 -215.115626)
			(xy 88.741375 -215.131638) (xy 88.787542 -215.155161) (xy 88.829461 -215.185617) (xy 88.866099 -215.222255)
			(xy 88.896555 -215.264174) (xy 88.920078 -215.310341) (xy 88.93609 -215.35962) (xy 88.944196 -215.410797)
			(xy 88.944704 -215.436704) (xy 89.22512 -215.436704) (xy 89.225629 -215.41136) (xy 89.2334 -215.36127)
			(xy 89.248746 -215.31296) (xy 89.271303 -215.267567) (xy 89.300542 -215.226161) (xy 89.335773 -215.189717)
			(xy 89.376165 -215.159094) (xy 89.420769 -215.135013) (xy 89.468532 -215.118041) (xy 89.493344 -215.112854)
			(xy 89.516204 -215.108536) (xy 89.721182 -214.753444) (xy 89.713308 -214.7316) (xy 89.704729 -214.705181)
			(xy 89.695532 -214.650406) (xy 89.69502 -214.622634) (xy 89.695528 -214.596747) (xy 89.703627 -214.545609)
			(xy 89.719626 -214.496369) (xy 89.743132 -214.450237) (xy 89.773564 -214.40835) (xy 89.810174 -214.37174)
			(xy 89.852061 -214.341308) (xy 89.898193 -214.317802) (xy 89.947433 -214.301803) (xy 89.998571 -214.293704)
			(xy 90.050345 -214.293704) (xy 90.101483 -214.301803) (xy 90.150723 -214.317802) (xy 90.196855 -214.341308)
			(xy 90.238742 -214.37174) (xy 90.275352 -214.40835) (xy 90.305784 -214.450237) (xy 90.32929 -214.496369)
			(xy 90.345289 -214.545609) (xy 90.353388 -214.596747) (xy 90.353896 -214.622634) (xy 90.353447 -214.64797)
			(xy 90.34569 -214.698044) (xy 90.330363 -214.746341) (xy 90.307827 -214.791726) (xy 90.278612 -214.833128)
			(xy 90.243408 -214.869572) (xy 90.203042 -214.900202) (xy 90.158465 -214.924296) (xy 90.110727 -214.941286)
			(xy 90.085926 -214.946484) (xy 90.063066 -214.950802) (xy 89.858088 -215.305894) (xy 89.865962 -215.327738)
			(xy 89.87461 -215.354146) (xy 89.883929 -215.408922) (xy 89.884504 -215.436704) (xy 91.10472 -215.436704)
			(xy 91.105229 -215.41136) (xy 91.113 -215.36127) (xy 91.128346 -215.31296) (xy 91.150903 -215.267567)
			(xy 91.180142 -215.226161) (xy 91.215373 -215.189717) (xy 91.255765 -215.159094) (xy 91.300369 -215.135013)
			(xy 91.348132 -215.118041) (xy 91.372944 -215.112854) (xy 91.395804 -215.108536) (xy 91.600782 -214.753444)
			(xy 91.592908 -214.7316) (xy 91.584329 -214.705181) (xy 91.575132 -214.650406) (xy 91.57462 -214.622634)
			(xy 91.575128 -214.596747) (xy 91.583227 -214.545609) (xy 91.599226 -214.496369) (xy 91.622732 -214.450237)
			(xy 91.653164 -214.40835) (xy 91.689774 -214.37174) (xy 91.731661 -214.341308) (xy 91.777793 -214.317802)
			(xy 91.827033 -214.301803) (xy 91.878171 -214.293704) (xy 91.929945 -214.293704) (xy 91.981083 -214.301803)
			(xy 92.030323 -214.317802) (xy 92.076455 -214.341308) (xy 92.118342 -214.37174) (xy 92.154952 -214.40835)
			(xy 92.185384 -214.450237) (xy 92.20889 -214.496369) (xy 92.224889 -214.545609) (xy 92.232988 -214.596747)
			(xy 92.233496 -214.622634) (xy 92.233047 -214.64797) (xy 92.22529 -214.698044) (xy 92.209963 -214.746341)
			(xy 92.187427 -214.791726) (xy 92.158212 -214.833128) (xy 92.123008 -214.869572) (xy 92.082642 -214.900202)
			(xy 92.038065 -214.924296) (xy 91.990327 -214.941286) (xy 91.965526 -214.946484) (xy 91.942666 -214.950802)
			(xy 91.737688 -215.305894) (xy 91.745562 -215.327738) (xy 91.75421 -215.354146) (xy 91.763529 -215.408922)
			(xy 91.764104 -215.436704) (xy 92.98432 -215.436704) (xy 92.984829 -215.41136) (xy 92.9926 -215.36127)
			(xy 93.007946 -215.31296) (xy 93.030503 -215.267567) (xy 93.059742 -215.226161) (xy 93.094973 -215.189717)
			(xy 93.135365 -215.159094) (xy 93.179969 -215.135013) (xy 93.227732 -215.118041) (xy 93.252544 -215.112854)
			(xy 93.275404 -215.108536) (xy 93.480382 -214.753444) (xy 93.472508 -214.7316) (xy 93.463929 -214.705181)
			(xy 93.454732 -214.650406) (xy 93.45422 -214.622634) (xy 93.454728 -214.596747) (xy 93.462827 -214.545609)
			(xy 93.478826 -214.496369) (xy 93.502332 -214.450237) (xy 93.532764 -214.40835) (xy 93.569374 -214.37174)
			(xy 93.611261 -214.341308) (xy 93.657393 -214.317802) (xy 93.706633 -214.301803) (xy 93.757771 -214.293704)
			(xy 93.809545 -214.293704) (xy 93.860683 -214.301803) (xy 93.909923 -214.317802) (xy 93.956055 -214.341308)
			(xy 93.997942 -214.37174) (xy 94.034552 -214.40835) (xy 94.064984 -214.450237) (xy 94.08849 -214.496369)
			(xy 94.104489 -214.545609) (xy 94.112588 -214.596747) (xy 94.113096 -214.622634) (xy 94.112647 -214.64797)
			(xy 94.10489 -214.698044) (xy 94.089563 -214.746341) (xy 94.067027 -214.791726) (xy 94.037812 -214.833128)
			(xy 94.002608 -214.869572) (xy 93.962242 -214.900202) (xy 93.917665 -214.924296) (xy 93.869927 -214.941286)
			(xy 93.845126 -214.946484) (xy 93.822266 -214.950802) (xy 93.617288 -215.305894) (xy 93.625162 -215.327738)
			(xy 93.63381 -215.354146) (xy 93.643129 -215.408922) (xy 93.643704 -215.436704) (xy 94.86392 -215.436704)
			(xy 94.864429 -215.41136) (xy 94.8722 -215.36127) (xy 94.887546 -215.31296) (xy 94.910103 -215.267567)
			(xy 94.939342 -215.226161) (xy 94.974573 -215.189717) (xy 95.014965 -215.159094) (xy 95.059569 -215.135013)
			(xy 95.107332 -215.118041) (xy 95.132144 -215.112854) (xy 95.155004 -215.108536) (xy 95.359982 -214.753444)
			(xy 95.352108 -214.7316) (xy 95.343529 -214.705181) (xy 95.334332 -214.650406) (xy 95.33382 -214.622634)
			(xy 95.334328 -214.596747) (xy 95.342427 -214.545609) (xy 95.358426 -214.496369) (xy 95.381932 -214.450237)
			(xy 95.412364 -214.40835) (xy 95.448974 -214.37174) (xy 95.490861 -214.341308) (xy 95.536993 -214.317802)
			(xy 95.586233 -214.301803) (xy 95.637371 -214.293704) (xy 95.689145 -214.293704) (xy 95.740283 -214.301803)
			(xy 95.789523 -214.317802) (xy 95.835655 -214.341308) (xy 95.877542 -214.37174) (xy 95.914152 -214.40835)
			(xy 95.944584 -214.450237) (xy 95.96809 -214.496369) (xy 95.984089 -214.545609) (xy 95.992188 -214.596747)
			(xy 95.992696 -214.622634) (xy 95.992247 -214.64797) (xy 95.98449 -214.698044) (xy 95.969163 -214.746341)
			(xy 95.946627 -214.791726) (xy 95.917412 -214.833128) (xy 95.882208 -214.869572) (xy 95.841842 -214.900202)
			(xy 95.797265 -214.924296) (xy 95.749527 -214.941286) (xy 95.724726 -214.946484) (xy 95.701866 -214.950802)
			(xy 95.496888 -215.305894) (xy 95.504762 -215.327738) (xy 95.51341 -215.354146) (xy 95.522729 -215.408922)
			(xy 95.523304 -215.436704) (xy 96.74352 -215.436704) (xy 96.744029 -215.41136) (xy 96.7518 -215.36127)
			(xy 96.767146 -215.31296) (xy 96.789703 -215.267567) (xy 96.818942 -215.226161) (xy 96.854173 -215.189717)
			(xy 96.894565 -215.159094) (xy 96.939169 -215.135013) (xy 96.986932 -215.118041) (xy 97.011744 -215.112854)
			(xy 97.034604 -215.108536) (xy 97.239582 -214.753444) (xy 97.231708 -214.7316) (xy 97.223129 -214.705181)
			(xy 97.213932 -214.650406) (xy 97.21342 -214.622634) (xy 97.213928 -214.596747) (xy 97.222027 -214.545609)
			(xy 97.238026 -214.496369) (xy 97.261532 -214.450237) (xy 97.291964 -214.40835) (xy 97.328574 -214.37174)
			(xy 97.370461 -214.341308) (xy 97.416593 -214.317802) (xy 97.465833 -214.301803) (xy 97.516971 -214.293704)
			(xy 97.568745 -214.293704) (xy 97.619883 -214.301803) (xy 97.669123 -214.317802) (xy 97.715255 -214.341308)
			(xy 97.757142 -214.37174) (xy 97.793752 -214.40835) (xy 97.824184 -214.450237) (xy 97.84769 -214.496369)
			(xy 97.863689 -214.545609) (xy 97.871788 -214.596747) (xy 97.872296 -214.622634) (xy 97.871847 -214.64797)
			(xy 97.86409 -214.698044) (xy 97.848763 -214.746341) (xy 97.826227 -214.791726) (xy 97.797012 -214.833128)
			(xy 97.761808 -214.869572) (xy 97.721442 -214.900202) (xy 97.676865 -214.924296) (xy 97.629127 -214.941286)
			(xy 97.604326 -214.946484) (xy 97.581466 -214.950802) (xy 97.376488 -215.305894) (xy 97.384362 -215.327738)
			(xy 97.39301 -215.354146) (xy 97.402329 -215.408922) (xy 97.402904 -215.436704) (xy 98.62312 -215.436704)
			(xy 98.623629 -215.41136) (xy 98.6314 -215.36127) (xy 98.646746 -215.31296) (xy 98.669303 -215.267567)
			(xy 98.698542 -215.226161) (xy 98.733773 -215.189717) (xy 98.774165 -215.159094) (xy 98.818769 -215.135013)
			(xy 98.866532 -215.118041) (xy 98.891344 -215.112854) (xy 98.914204 -215.108536) (xy 99.119182 -214.753444)
			(xy 99.111308 -214.7316) (xy 99.102729 -214.705181) (xy 99.093532 -214.650406) (xy 99.09302 -214.622634)
			(xy 99.093528 -214.596747) (xy 99.101627 -214.545609) (xy 99.117626 -214.496369) (xy 99.141132 -214.450237)
			(xy 99.171564 -214.40835) (xy 99.208174 -214.37174) (xy 99.250061 -214.341308) (xy 99.296193 -214.317802)
			(xy 99.345433 -214.301803) (xy 99.396571 -214.293704) (xy 99.448345 -214.293704) (xy 99.499483 -214.301803)
			(xy 99.548723 -214.317802) (xy 99.594855 -214.341308) (xy 99.636742 -214.37174) (xy 99.673352 -214.40835)
			(xy 99.703784 -214.450237) (xy 99.72729 -214.496369) (xy 99.743289 -214.545609) (xy 99.751388 -214.596747)
			(xy 99.751896 -214.622634) (xy 99.751447 -214.64797) (xy 99.74369 -214.698044) (xy 99.728363 -214.746341)
			(xy 99.705827 -214.791726) (xy 99.676612 -214.833128) (xy 99.641408 -214.869572) (xy 99.601042 -214.900202)
			(xy 99.556465 -214.924296) (xy 99.508727 -214.941286) (xy 99.483926 -214.946484) (xy 99.461066 -214.950802)
			(xy 99.256088 -215.305894) (xy 99.263962 -215.327738) (xy 99.27261 -215.354146) (xy 99.281929 -215.408922)
			(xy 99.282504 -215.436704) (xy 99.281996 -215.462611) (xy 99.27389 -215.513788) (xy 99.257878 -215.563067)
			(xy 99.234355 -215.609234) (xy 99.203899 -215.651153) (xy 99.167261 -215.687791) (xy 99.125342 -215.718247)
			(xy 99.079175 -215.74177) (xy 99.029896 -215.757782) (xy 98.978719 -215.765888) (xy 98.926905 -215.765888)
			(xy 98.875728 -215.757782) (xy 98.826449 -215.74177) (xy 98.780282 -215.718247) (xy 98.738363 -215.687791)
			(xy 98.701725 -215.651153) (xy 98.671269 -215.609234) (xy 98.647746 -215.563067) (xy 98.631734 -215.513788)
			(xy 98.623628 -215.462611) (xy 98.62312 -215.436704) (xy 97.402904 -215.436704) (xy 97.402396 -215.462611)
			(xy 97.39429 -215.513788) (xy 97.378278 -215.563067) (xy 97.354755 -215.609234) (xy 97.324299 -215.651153)
			(xy 97.287661 -215.687791) (xy 97.245742 -215.718247) (xy 97.199575 -215.74177) (xy 97.150296 -215.757782)
			(xy 97.099119 -215.765888) (xy 97.047305 -215.765888) (xy 96.996128 -215.757782) (xy 96.946849 -215.74177)
			(xy 96.900682 -215.718247) (xy 96.858763 -215.687791) (xy 96.822125 -215.651153) (xy 96.791669 -215.609234)
			(xy 96.768146 -215.563067) (xy 96.752134 -215.513788) (xy 96.744028 -215.462611) (xy 96.74352 -215.436704)
			(xy 95.523304 -215.436704) (xy 95.522796 -215.462611) (xy 95.51469 -215.513788) (xy 95.498678 -215.563067)
			(xy 95.475155 -215.609234) (xy 95.444699 -215.651153) (xy 95.408061 -215.687791) (xy 95.366142 -215.718247)
			(xy 95.319975 -215.74177) (xy 95.270696 -215.757782) (xy 95.219519 -215.765888) (xy 95.167705 -215.765888)
			(xy 95.116528 -215.757782) (xy 95.067249 -215.74177) (xy 95.021082 -215.718247) (xy 94.979163 -215.687791)
			(xy 94.942525 -215.651153) (xy 94.912069 -215.609234) (xy 94.888546 -215.563067) (xy 94.872534 -215.513788)
			(xy 94.864428 -215.462611) (xy 94.86392 -215.436704) (xy 93.643704 -215.436704) (xy 93.643196 -215.462611)
			(xy 93.63509 -215.513788) (xy 93.619078 -215.563067) (xy 93.595555 -215.609234) (xy 93.565099 -215.651153)
			(xy 93.528461 -215.687791) (xy 93.486542 -215.718247) (xy 93.440375 -215.74177) (xy 93.391096 -215.757782)
			(xy 93.339919 -215.765888) (xy 93.288105 -215.765888) (xy 93.236928 -215.757782) (xy 93.187649 -215.74177)
			(xy 93.141482 -215.718247) (xy 93.099563 -215.687791) (xy 93.062925 -215.651153) (xy 93.032469 -215.609234)
			(xy 93.008946 -215.563067) (xy 92.992934 -215.513788) (xy 92.984828 -215.462611) (xy 92.98432 -215.436704)
			(xy 91.764104 -215.436704) (xy 91.763596 -215.462611) (xy 91.75549 -215.513788) (xy 91.739478 -215.563067)
			(xy 91.715955 -215.609234) (xy 91.685499 -215.651153) (xy 91.648861 -215.687791) (xy 91.606942 -215.718247)
			(xy 91.560775 -215.74177) (xy 91.511496 -215.757782) (xy 91.460319 -215.765888) (xy 91.408505 -215.765888)
			(xy 91.357328 -215.757782) (xy 91.308049 -215.74177) (xy 91.261882 -215.718247) (xy 91.219963 -215.687791)
			(xy 91.183325 -215.651153) (xy 91.152869 -215.609234) (xy 91.129346 -215.563067) (xy 91.113334 -215.513788)
			(xy 91.105228 -215.462611) (xy 91.10472 -215.436704) (xy 89.884504 -215.436704) (xy 89.883996 -215.462611)
			(xy 89.87589 -215.513788) (xy 89.859878 -215.563067) (xy 89.836355 -215.609234) (xy 89.805899 -215.651153)
			(xy 89.769261 -215.687791) (xy 89.727342 -215.718247) (xy 89.681175 -215.74177) (xy 89.631896 -215.757782)
			(xy 89.580719 -215.765888) (xy 89.528905 -215.765888) (xy 89.477728 -215.757782) (xy 89.428449 -215.74177)
			(xy 89.382282 -215.718247) (xy 89.340363 -215.687791) (xy 89.303725 -215.651153) (xy 89.273269 -215.609234)
			(xy 89.249746 -215.563067) (xy 89.233734 -215.513788) (xy 89.225628 -215.462611) (xy 89.22512 -215.436704)
			(xy 88.944704 -215.436704) (xy 88.944111 -215.464421) (xy 88.934787 -215.519068) (xy 88.926162 -215.545416)
			(xy 88.918288 -215.567514) (xy 89.123266 -215.922352) (xy 89.146126 -215.92667) (xy 89.170934 -215.931835)
			(xy 89.218674 -215.948828) (xy 89.263251 -215.972925) (xy 89.303616 -216.003559) (xy 89.338819 -216.040009)
			(xy 89.36803 -216.081415) (xy 89.390562 -216.126804) (xy 89.405883 -216.175106) (xy 89.413634 -216.225183)
			(xy 89.414096 -216.25052) (xy 89.413588 -216.276407) (xy 89.405489 -216.327545) (xy 89.38949 -216.376785)
			(xy 89.365984 -216.422917) (xy 89.335552 -216.464804) (xy 89.298942 -216.501414) (xy 89.257055 -216.531846)
			(xy 89.210923 -216.555352) (xy 89.161683 -216.571351) (xy 89.110545 -216.57945) (xy 89.058771 -216.57945)
			(xy 89.007633 -216.571351) (xy 88.958393 -216.555352) (xy 88.912261 -216.531846) (xy 88.870374 -216.501414)
			(xy 88.833764 -216.464804) (xy 88.803332 -216.422917) (xy 88.779826 -216.376785) (xy 88.763827 -216.327545)
			(xy 88.755728 -216.276407) (xy 88.75522 -216.25052) (xy 88.755754 -216.222812) (xy 88.764946 -216.168165)
			(xy 88.773508 -216.141808) (xy 88.781382 -216.11971) (xy 88.576404 -215.764872) (xy 88.553544 -215.760554)
			(xy 88.528711 -215.755439) (xy 88.480928 -215.73848) (xy 88.436306 -215.714403) (xy 88.395898 -215.683776)
			(xy 88.360658 -215.647323) (xy 88.331415 -215.605902) (xy 88.308862 -215.560492) (xy 88.293529 -215.512163)
			(xy 88.285778 -215.462056) (xy 88.28532 -215.436704) (xy 61.39434 -215.436704) (xy 61.39434 -217.585544)
			(xy 61.878718 -218.069922) (xy 74.355198 -218.069922) (xy 74.361294 -218.068398) (xy 74.376895 -218.064607)
			(xy 74.408741 -218.060533) (xy 74.424794 -218.06027) (xy 88.661494 -218.06027) (xy 88.676398 -218.059751)
			(xy 88.704938 -218.051147) (xy 88.729779 -218.034669) (xy 88.748804 -218.011721) (xy 88.760394 -217.984258)
			(xy 88.763562 -217.954618) (xy 88.761316 -217.939874) (xy 88.758653 -217.924648) (xy 88.755856 -217.893863)
			(xy 88.755728 -217.878406) (xy 88.756235 -217.852517) (xy 88.764334 -217.801377) (xy 88.780332 -217.752134)
			(xy 88.803836 -217.705999) (xy 88.834268 -217.664108) (xy 88.870878 -217.627494) (xy 88.912764 -217.597057)
			(xy 88.958897 -217.573547) (xy 89.008138 -217.557543) (xy 89.059277 -217.549438) (xy 89.085166 -217.548968)
			(xy 89.112663 -217.549501) (xy 89.166899 -217.558597) (xy 89.218871 -217.576575) (xy 89.267134 -217.602937)
			(xy 89.310349 -217.636949) (xy 89.32926 -217.656918) (xy 89.336191 -217.663877) (xy 89.353872 -217.672388)
			(xy 89.373454 -217.673647) (xy 89.39208 -217.667472) (xy 89.399872 -217.66149) (xy 89.417234 -217.647245)
			(xy 89.455946 -217.624489) (xy 89.498063 -217.608911) (xy 89.542265 -217.601) (xy 89.564718 -217.60053)
			(xy 89.847674 -217.60053) (xy 89.874515 -217.584284) (xy 89.93282 -217.561134) (xy 89.963498 -217.554556)
			(xy 89.986358 -217.550238) (xy 90.191336 -217.195146) (xy 90.183462 -217.173302) (xy 90.174812 -217.146894)
			(xy 90.165483 -217.092118) (xy 90.16492 -217.064336) (xy 90.165428 -217.038429) (xy 90.173534 -216.987252)
			(xy 90.189546 -216.937973) (xy 90.213069 -216.891806) (xy 90.243525 -216.849887) (xy 90.280163 -216.813249)
			(xy 90.322082 -216.782793) (xy 90.368249 -216.75927) (xy 90.417528 -216.743258) (xy 90.468705 -216.735152)
			(xy 90.520519 -216.735152) (xy 90.571696 -216.743258) (xy 90.620975 -216.75927) (xy 90.667142 -216.782793)
			(xy 90.709061 -216.813249) (xy 90.745699 -216.849887) (xy 90.776155 -216.891806) (xy 90.799678 -216.937973)
			(xy 90.81569 -216.987252) (xy 90.823796 -217.038429) (xy 90.824304 -217.064336) (xy 90.823844 -217.089687)
			(xy 90.816089 -217.139791) (xy 90.800754 -217.188117) (xy 90.778199 -217.233525) (xy 90.748956 -217.274944)
			(xy 90.713716 -217.311396) (xy 90.67331 -217.342021) (xy 90.62869 -217.366098) (xy 90.58091 -217.383058)
			(xy 90.55608 -217.388186) (xy 90.53322 -217.392504) (xy 90.500962 -217.44813) (xy 90.493787 -217.461591)
			(xy 90.48702 -217.49132) (xy 90.489318 -217.521722) (xy 90.500477 -217.550097) (xy 90.519505 -217.57392)
			(xy 90.544711 -217.591074) (xy 90.573855 -217.600034) (xy 90.5891 -217.60053) (xy 90.787474 -217.60053)
			(xy 90.807431 -217.588297) (xy 90.85007 -217.568983) (xy 90.895016 -217.55591) (xy 90.941361 -217.54934)
			(xy 90.964766 -217.548968) (xy 90.988167 -217.549367) (xy 91.034503 -217.555962) (xy 91.079441 -217.569039)
			(xy 91.12208 -217.588335) (xy 91.142058 -217.60053) (xy 91.727274 -217.60053) (xy 91.754115 -217.584284)
			(xy 91.81242 -217.561134) (xy 91.843098 -217.554556) (xy 91.865958 -217.550238) (xy 92.070936 -217.195146)
			(xy 92.063062 -217.173302) (xy 92.054412 -217.146894) (xy 92.045083 -217.092118) (xy 92.04452 -217.064336)
			(xy 92.045028 -217.038429) (xy 92.053134 -216.987252) (xy 92.069146 -216.937973) (xy 92.092669 -216.891806)
			(xy 92.123125 -216.849887) (xy 92.159763 -216.813249) (xy 92.201682 -216.782793) (xy 92.247849 -216.75927)
			(xy 92.297128 -216.743258) (xy 92.348305 -216.735152) (xy 92.400119 -216.735152) (xy 92.451296 -216.743258)
			(xy 92.500575 -216.75927) (xy 92.546742 -216.782793) (xy 92.588661 -216.813249) (xy 92.625299 -216.849887)
			(xy 92.655755 -216.891806) (xy 92.679278 -216.937973) (xy 92.69529 -216.987252) (xy 92.703396 -217.038429)
			(xy 92.703904 -217.064336) (xy 92.703444 -217.089687) (xy 92.695689 -217.139791) (xy 92.680354 -217.188117)
			(xy 92.657799 -217.233525) (xy 92.628556 -217.274944) (xy 92.593316 -217.311396) (xy 92.55291 -217.342021)
			(xy 92.50829 -217.366098) (xy 92.46051 -217.383058) (xy 92.43568 -217.388186) (xy 92.41282 -217.392504)
			(xy 92.380562 -217.44813) (xy 92.373387 -217.461591) (xy 92.36662 -217.49132) (xy 92.368918 -217.521722)
			(xy 92.380077 -217.550097) (xy 92.399105 -217.57392) (xy 92.424311 -217.591074) (xy 92.453455 -217.600034)
			(xy 92.4687 -217.60053) (xy 92.667074 -217.60053) (xy 92.687031 -217.588297) (xy 92.72967 -217.568983)
			(xy 92.774616 -217.55591) (xy 92.820961 -217.54934) (xy 92.844366 -217.548968) (xy 92.867767 -217.549367)
			(xy 92.914103 -217.555962) (xy 92.959041 -217.569039) (xy 93.00168 -217.588335) (xy 93.021658 -217.60053)
			(xy 93.606874 -217.60053) (xy 93.633715 -217.584284) (xy 93.69202 -217.561134) (xy 93.722698 -217.554556)
			(xy 93.745558 -217.550238) (xy 93.950536 -217.195146) (xy 93.942662 -217.173302) (xy 93.934012 -217.146894)
			(xy 93.924683 -217.092118) (xy 93.92412 -217.064336) (xy 93.924628 -217.038429) (xy 93.932734 -216.987252)
			(xy 93.948746 -216.937973) (xy 93.972269 -216.891806) (xy 94.002725 -216.849887) (xy 94.039363 -216.813249)
			(xy 94.081282 -216.782793) (xy 94.127449 -216.75927) (xy 94.176728 -216.743258) (xy 94.227905 -216.735152)
			(xy 94.279719 -216.735152) (xy 94.330896 -216.743258) (xy 94.380175 -216.75927) (xy 94.426342 -216.782793)
			(xy 94.468261 -216.813249) (xy 94.504899 -216.849887) (xy 94.535355 -216.891806) (xy 94.558878 -216.937973)
			(xy 94.57489 -216.987252) (xy 94.582996 -217.038429) (xy 94.583504 -217.064336) (xy 94.583044 -217.089687)
			(xy 94.575289 -217.139791) (xy 94.559954 -217.188117) (xy 94.537399 -217.233525) (xy 94.508156 -217.274944)
			(xy 94.472916 -217.311396) (xy 94.43251 -217.342021) (xy 94.38789 -217.366098) (xy 94.34011 -217.383058)
			(xy 94.31528 -217.388186) (xy 94.29242 -217.392504) (xy 94.260162 -217.44813) (xy 94.252987 -217.461591)
			(xy 94.24622 -217.49132) (xy 94.248518 -217.521722) (xy 94.259677 -217.550097) (xy 94.278705 -217.57392)
			(xy 94.303911 -217.591074) (xy 94.333055 -217.600034) (xy 94.3483 -217.60053) (xy 94.546674 -217.60053)
			(xy 94.566631 -217.588297) (xy 94.60927 -217.568983) (xy 94.654216 -217.55591) (xy 94.700561 -217.54934)
			(xy 94.723966 -217.548968) (xy 94.750058 -217.54946) (xy 94.801591 -217.55767) (xy 94.85119 -217.573888)
			(xy 94.897618 -217.597713) (xy 94.939716 -217.628548) (xy 94.958408 -217.646758) (xy 94.967313 -217.65316)
			(xy 94.9841 -217.667278) (xy 94.991936 -217.674952) (xy 95.171514 -217.85453) (xy 95.181408 -217.863826)
			(xy 95.20497 -217.877291) (xy 95.231247 -217.884074) (xy 95.258382 -217.883695) (xy 95.284459 -217.87618)
			(xy 95.307636 -217.862061) (xy 95.326274 -217.842335) (xy 95.339057 -217.818396) (xy 95.342456 -217.805254)
			(xy 95.34905 -217.77875) (xy 95.3698 -217.728234) (xy 95.398588 -217.681825) (xy 95.434628 -217.640793)
			(xy 95.476935 -217.606258) (xy 95.524352 -217.579163) (xy 95.575585 -217.56025) (xy 95.602298 -217.554556)
			(xy 95.625158 -217.550238) (xy 95.830136 -217.195146) (xy 95.822262 -217.173302) (xy 95.813612 -217.146894)
			(xy 95.804283 -217.092118) (xy 95.80372 -217.064336) (xy 95.804228 -217.038429) (xy 95.812334 -216.987252)
			(xy 95.828346 -216.937973) (xy 95.851869 -216.891806) (xy 95.882325 -216.849887) (xy 95.918963 -216.813249)
			(xy 95.960882 -216.782793) (xy 96.007049 -216.75927) (xy 96.056328 -216.743258) (xy 96.107505 -216.735152)
			(xy 96.159319 -216.735152) (xy 96.210496 -216.743258) (xy 96.259775 -216.75927) (xy 96.305942 -216.782793)
			(xy 96.347861 -216.813249) (xy 96.384499 -216.849887) (xy 96.414955 -216.891806) (xy 96.438478 -216.937973)
			(xy 96.45449 -216.987252) (xy 96.462596 -217.038429) (xy 96.463104 -217.064336) (xy 96.462644 -217.089687)
			(xy 96.454889 -217.139791) (xy 96.439554 -217.188117) (xy 96.416999 -217.233525) (xy 96.387756 -217.274944)
			(xy 96.352516 -217.311396) (xy 96.31211 -217.342021) (xy 96.26749 -217.366098) (xy 96.21971 -217.383058)
			(xy 96.19488 -217.388186) (xy 96.17202 -217.392504) (xy 95.967042 -217.747596) (xy 95.974916 -217.76944)
			(xy 95.983491 -217.795859) (xy 95.992677 -217.850635) (xy 95.993204 -217.878406) (xy 96.274128 -217.878406)
			(xy 96.274636 -217.852519) (xy 96.282735 -217.801381) (xy 96.298734 -217.752141) (xy 96.32224 -217.706009)
			(xy 96.352672 -217.664122) (xy 96.389282 -217.627512) (xy 96.431169 -217.59708) (xy 96.477301 -217.573574)
			(xy 96.526541 -217.557575) (xy 96.577679 -217.549476) (xy 96.629453 -217.549476) (xy 96.680591 -217.557575)
			(xy 96.729831 -217.573574) (xy 96.775963 -217.59708) (xy 96.81785 -217.627512) (xy 96.85446 -217.664122)
			(xy 96.884892 -217.706009) (xy 96.908398 -217.752141) (xy 96.924397 -217.801381) (xy 96.932496 -217.852519)
			(xy 96.933004 -217.878406) (xy 97.213928 -217.878406) (xy 97.214394 -217.853071) (xy 97.222146 -217.802996)
			(xy 97.237469 -217.754698) (xy 97.260002 -217.709313) (xy 97.289214 -217.66791) (xy 97.324417 -217.631464)
			(xy 97.364782 -217.600835) (xy 97.409359 -217.576742) (xy 97.457097 -217.559754) (xy 97.481898 -217.554556)
			(xy 97.504758 -217.550238) (xy 97.709736 -217.195146) (xy 97.701862 -217.173302) (xy 97.693224 -217.146891)
			(xy 97.683899 -217.092117) (xy 97.68332 -217.064336) (xy 97.683828 -217.038429) (xy 97.691934 -216.987252)
			(xy 97.707946 -216.937973) (xy 97.731469 -216.891806) (xy 97.761925 -216.849887) (xy 97.798563 -216.813249)
			(xy 97.840482 -216.782793) (xy 97.886649 -216.75927) (xy 97.935928 -216.743258) (xy 97.987105 -216.735152)
			(xy 98.038919 -216.735152) (xy 98.090096 -216.743258) (xy 98.139375 -216.75927) (xy 98.185542 -216.782793)
			(xy 98.227461 -216.813249) (xy 98.264099 -216.849887) (xy 98.294555 -216.891806) (xy 98.318078 -216.937973)
			(xy 98.33409 -216.987252) (xy 98.342196 -217.038429) (xy 98.342704 -217.064336) (xy 98.342212 -217.08968)
			(xy 98.334435 -217.13977) (xy 98.319086 -217.188079) (xy 98.296525 -217.233471) (xy 98.267284 -217.274876)
			(xy 98.232052 -217.311319) (xy 98.191659 -217.341943) (xy 98.147055 -217.366024) (xy 98.099292 -217.382998)
			(xy 98.07448 -217.388186) (xy 98.05162 -217.392504) (xy 97.846642 -217.747596) (xy 97.854516 -217.76944)
			(xy 97.863106 -217.795856) (xy 97.872295 -217.850633) (xy 97.872804 -217.878406) (xy 98.153728 -217.878406)
			(xy 98.154236 -217.852519) (xy 98.162335 -217.801381) (xy 98.178334 -217.752141) (xy 98.20184 -217.706009)
			(xy 98.232272 -217.664122) (xy 98.268882 -217.627512) (xy 98.310769 -217.59708) (xy 98.356901 -217.573574)
			(xy 98.406141 -217.557575) (xy 98.457279 -217.549476) (xy 98.509053 -217.549476) (xy 98.560191 -217.557575)
			(xy 98.609431 -217.573574) (xy 98.655563 -217.59708) (xy 98.69745 -217.627512) (xy 98.73406 -217.664122)
			(xy 98.764492 -217.706009) (xy 98.787998 -217.752141) (xy 98.803997 -217.801381) (xy 98.812096 -217.852519)
			(xy 98.812604 -217.878406) (xy 99.093528 -217.878406) (xy 99.093994 -217.853071) (xy 99.101746 -217.802996)
			(xy 99.117069 -217.754698) (xy 99.139602 -217.709313) (xy 99.168814 -217.66791) (xy 99.204017 -217.631464)
			(xy 99.244382 -217.600835) (xy 99.288959 -217.576742) (xy 99.336697 -217.559754) (xy 99.361498 -217.554556)
			(xy 99.384358 -217.550238) (xy 99.589336 -217.195146) (xy 99.581462 -217.173302) (xy 99.572824 -217.146891)
			(xy 99.563499 -217.092117) (xy 99.56292 -217.064336) (xy 99.563428 -217.038429) (xy 99.571534 -216.987252)
			(xy 99.587546 -216.937973) (xy 99.611069 -216.891806) (xy 99.641525 -216.849887) (xy 99.678163 -216.813249)
			(xy 99.720082 -216.782793) (xy 99.766249 -216.75927) (xy 99.815528 -216.743258) (xy 99.866705 -216.735152)
			(xy 99.918519 -216.735152) (xy 99.969696 -216.743258) (xy 100.018975 -216.75927) (xy 100.065142 -216.782793)
			(xy 100.107061 -216.813249) (xy 100.143699 -216.849887) (xy 100.174155 -216.891806) (xy 100.197678 -216.937973)
			(xy 100.21369 -216.987252) (xy 100.221796 -217.038429) (xy 100.222304 -217.064336) (xy 100.221812 -217.08968)
			(xy 100.214035 -217.13977) (xy 100.198686 -217.188079) (xy 100.176125 -217.233471) (xy 100.146884 -217.274876)
			(xy 100.111652 -217.311319) (xy 100.071259 -217.341943) (xy 100.026655 -217.366024) (xy 99.978892 -217.382998)
			(xy 99.95408 -217.388186) (xy 99.93122 -217.392504) (xy 99.726242 -217.747596) (xy 99.734116 -217.76944)
			(xy 99.742706 -217.795856) (xy 99.751895 -217.850633) (xy 99.752404 -217.878406) (xy 99.751896 -217.904293)
			(xy 99.743797 -217.955431) (xy 99.727798 -218.004671) (xy 99.704292 -218.050803) (xy 99.67386 -218.09269)
			(xy 99.63725 -218.1293) (xy 99.595363 -218.159732) (xy 99.549231 -218.183238) (xy 99.499991 -218.199237)
			(xy 99.448853 -218.207336) (xy 99.397079 -218.207336) (xy 99.345941 -218.199237) (xy 99.296701 -218.183238)
			(xy 99.250569 -218.159732) (xy 99.208682 -218.1293) (xy 99.172072 -218.09269) (xy 99.14164 -218.050803)
			(xy 99.118134 -218.004671) (xy 99.102135 -217.955431) (xy 99.094036 -217.904293) (xy 99.093528 -217.878406)
			(xy 98.812604 -217.878406) (xy 98.812076 -217.906114) (xy 98.80288 -217.960761) (xy 98.794316 -217.987118)
			(xy 98.786442 -218.009216) (xy 98.99142 -218.364054) (xy 99.01428 -218.368372) (xy 99.0391 -218.37354)
			(xy 99.086878 -218.390497) (xy 99.131495 -218.41457) (xy 99.1719 -218.44519) (xy 99.20714 -218.481637)
			(xy 99.236384 -218.52305) (xy 99.258942 -218.568452) (xy 99.274281 -218.616773) (xy 99.282041 -218.666873)
			(xy 99.282504 -218.692222) (xy 99.281996 -218.718129) (xy 99.27389 -218.769306) (xy 99.257878 -218.818585)
			(xy 99.234355 -218.864752) (xy 99.203899 -218.906671) (xy 99.167261 -218.943309) (xy 99.125342 -218.973765)
			(xy 99.079175 -218.997288) (xy 99.029896 -219.0133) (xy 98.978719 -219.021406) (xy 98.926905 -219.021406)
			(xy 98.875728 -219.0133) (xy 98.826449 -218.997288) (xy 98.780282 -218.973765) (xy 98.738363 -218.943309)
			(xy 98.701725 -218.906671) (xy 98.671269 -218.864752) (xy 98.647746 -218.818585) (xy 98.631734 -218.769306)
			(xy 98.623628 -218.718129) (xy 98.62312 -218.692222) (xy 98.623718 -218.664505) (xy 98.633039 -218.609858)
			(xy 98.641662 -218.58351) (xy 98.649536 -218.561412) (xy 98.444558 -218.206574) (xy 98.421698 -218.202256)
			(xy 98.396899 -218.197049) (xy 98.349162 -218.180062) (xy 98.304585 -218.15597) (xy 98.26422 -218.125341)
			(xy 98.229017 -218.088897) (xy 98.199804 -218.047495) (xy 98.177271 -218.002112) (xy 98.161946 -217.953814)
			(xy 98.154192 -217.903741) (xy 98.153728 -217.878406) (xy 97.872804 -217.878406) (xy 97.872296 -217.904293)
			(xy 97.864197 -217.955431) (xy 97.848198 -218.004671) (xy 97.824692 -218.050803) (xy 97.79426 -218.09269)
			(xy 97.75765 -218.1293) (xy 97.715763 -218.159732) (xy 97.669631 -218.183238) (xy 97.620391 -218.199237)
			(xy 97.569253 -218.207336) (xy 97.517479 -218.207336) (xy 97.466341 -218.199237) (xy 97.417101 -218.183238)
			(xy 97.370969 -218.159732) (xy 97.329082 -218.1293) (xy 97.292472 -218.09269) (xy 97.26204 -218.050803)
			(xy 97.238534 -218.004671) (xy 97.222535 -217.955431) (xy 97.214436 -217.904293) (xy 97.213928 -217.878406)
			(xy 96.933004 -217.878406) (xy 96.932476 -217.906114) (xy 96.92328 -217.960761) (xy 96.914716 -217.987118)
			(xy 96.906842 -218.009216) (xy 97.11182 -218.364054) (xy 97.13468 -218.368372) (xy 97.1595 -218.37354)
			(xy 97.207278 -218.390497) (xy 97.251895 -218.41457) (xy 97.2923 -218.44519) (xy 97.32754 -218.481637)
			(xy 97.356784 -218.52305) (xy 97.379342 -218.568452) (xy 97.394681 -218.616773) (xy 97.402441 -218.666873)
			(xy 97.402904 -218.692222) (xy 97.402396 -218.718129) (xy 97.39429 -218.769306) (xy 97.378278 -218.818585)
			(xy 97.354755 -218.864752) (xy 97.324299 -218.906671) (xy 97.287661 -218.943309) (xy 97.245742 -218.973765)
			(xy 97.199575 -218.997288) (xy 97.150296 -219.0133) (xy 97.099119 -219.021406) (xy 97.047305 -219.021406)
			(xy 96.996128 -219.0133) (xy 96.946849 -218.997288) (xy 96.900682 -218.973765) (xy 96.858763 -218.943309)
			(xy 96.822125 -218.906671) (xy 96.791669 -218.864752) (xy 96.768146 -218.818585) (xy 96.752134 -218.769306)
			(xy 96.744028 -218.718129) (xy 96.74352 -218.692222) (xy 96.744118 -218.664505) (xy 96.753439 -218.609858)
			(xy 96.762062 -218.58351) (xy 96.769936 -218.561412) (xy 96.564958 -218.206574) (xy 96.542098 -218.202256)
			(xy 96.517299 -218.197049) (xy 96.469562 -218.180062) (xy 96.424985 -218.15597) (xy 96.38462 -218.125341)
			(xy 96.349417 -218.088897) (xy 96.320204 -218.047495) (xy 96.297671 -218.002112) (xy 96.282346 -217.953814)
			(xy 96.274592 -217.903741) (xy 96.274128 -217.878406) (xy 95.993204 -217.878406) (xy 95.992722 -217.904294)
			(xy 95.984621 -217.955433) (xy 95.96862 -218.004675) (xy 95.945112 -218.050807) (xy 95.914676 -218.092693)
			(xy 95.878063 -218.129302) (xy 95.836173 -218.159733) (xy 95.790038 -218.183235) (xy 95.740794 -218.199231)
			(xy 95.689654 -218.207325) (xy 95.663766 -218.207844) (xy 95.63692 -218.207358) (xy 95.58393 -218.198725)
			(xy 95.533046 -218.181596) (xy 95.50908 -218.16949) (xy 95.499444 -218.165048) (xy 95.478298 -218.163627)
			(xy 95.458378 -218.170862) (xy 95.443072 -218.185521) (xy 95.434985 -218.20511) (xy 95.434658 -218.215718)
			(xy 95.434658 -218.467432) (xy 95.451221 -218.485832) (xy 95.479205 -218.52667) (xy 95.500766 -218.571234)
			(xy 95.515419 -218.618522) (xy 95.522835 -218.667469) (xy 95.523304 -218.692222) (xy 95.522796 -218.718796)
			(xy 95.514265 -218.771255) (xy 95.497427 -218.821665) (xy 95.47272 -218.868721) (xy 95.440782 -218.911202)
			(xy 95.421958 -218.929966) (xy 95.421958 -219.512134) (xy 95.952056 -220.042232) (xy 95.984822 -220.025722)
			(xy 96.007993 -220.01459) (xy 96.056927 -219.998849) (xy 96.10771 -219.99089) (xy 96.133412 -219.990416)
			(xy 96.159306 -219.990924) (xy 96.210456 -219.999024) (xy 96.259711 -220.015021) (xy 96.305859 -220.038523)
			(xy 96.347764 -220.068951) (xy 96.384397 -220.105558) (xy 96.414855 -220.147441) (xy 96.438389 -220.193573)
			(xy 96.454422 -220.242816) (xy 96.462557 -220.293961) (xy 96.463104 -220.319854) (xy 96.462595 -220.345566)
			(xy 96.454568 -220.396361) (xy 96.438733 -220.445288) (xy 96.427544 -220.468444) (xy 96.411034 -220.50121)
			(xy 96.746822 -220.836998) (xy 96.753934 -220.840554) (xy 96.776587 -220.852717) (xy 96.818148 -220.882987)
			(xy 96.854505 -220.919342) (xy 96.884776 -220.960901) (xy 96.896936 -220.983556) (xy 96.900492 -220.990668)
			(xy 97.046034 -221.13621) (xy 97.056218 -221.145723) (xy 97.080546 -221.159294) (xy 97.107636 -221.165791)
			(xy 97.135474 -221.16473) (xy 97.161991 -221.156191) (xy 97.185216 -221.140807) (xy 97.203424 -221.119722)
			(xy 97.21526 -221.094504) (xy 97.217992 -221.080838) (xy 97.222516 -221.056063) (xy 97.23809 -221.00817)
			(xy 97.260769 -220.963205) (xy 97.290023 -220.922212) (xy 97.325173 -220.886147) (xy 97.365401 -220.855848)
			(xy 97.409769 -220.832022) (xy 97.457245 -220.815222) (xy 97.481898 -220.810074) (xy 97.504758 -220.805756)
			(xy 97.709736 -220.450664) (xy 97.701862 -220.42882) (xy 97.693219 -220.402411) (xy 97.683903 -220.347635)
			(xy 97.68332 -220.319854) (xy 97.683828 -220.293947) (xy 97.691934 -220.24277) (xy 97.707946 -220.193491)
			(xy 97.731469 -220.147324) (xy 97.761925 -220.105405) (xy 97.798563 -220.068767) (xy 97.840482 -220.038311)
			(xy 97.886649 -220.014788) (xy 97.935928 -219.998776) (xy 97.987105 -219.99067) (xy 98.038919 -219.99067)
			(xy 98.090096 -219.998776) (xy 98.139375 -220.014788) (xy 98.185542 -220.038311) (xy 98.227461 -220.068767)
			(xy 98.264099 -220.105405) (xy 98.294555 -220.147324) (xy 98.318078 -220.193491) (xy 98.33409 -220.24277)
			(xy 98.342196 -220.293947) (xy 98.342704 -220.319854) (xy 98.342242 -220.345204) (xy 98.334486 -220.395306)
			(xy 98.319149 -220.44363) (xy 98.296592 -220.489036) (xy 98.26735 -220.530452) (xy 98.232109 -220.566902)
			(xy 98.191704 -220.597525) (xy 98.147085 -220.6216) (xy 98.099306 -220.638559) (xy 98.07448 -220.643704)
			(xy 98.05162 -220.648022) (xy 97.846642 -221.003114) (xy 97.854516 -221.024958) (xy 97.863097 -221.051376)
			(xy 97.872297 -221.106152) (xy 97.872804 -221.133924) (xy 98.153728 -221.133924) (xy 98.154236 -221.108037)
			(xy 98.162335 -221.056899) (xy 98.178334 -221.007659) (xy 98.20184 -220.961527) (xy 98.232272 -220.91964)
			(xy 98.268882 -220.88303) (xy 98.310769 -220.852598) (xy 98.356901 -220.829092) (xy 98.406141 -220.813093)
			(xy 98.457279 -220.804994) (xy 98.509053 -220.804994) (xy 98.560191 -220.813093) (xy 98.609431 -220.829092)
			(xy 98.655563 -220.852598) (xy 98.69745 -220.88303) (xy 98.73406 -220.91964) (xy 98.764492 -220.961527)
			(xy 98.787998 -221.007659) (xy 98.803997 -221.056899) (xy 98.812096 -221.108037) (xy 98.812604 -221.133924)
			(xy 99.093528 -221.133924) (xy 99.09401 -221.108589) (xy 99.10176 -221.058515) (xy 99.11708 -221.010217)
			(xy 99.139611 -220.964832) (xy 99.168821 -220.923429) (xy 99.204022 -220.886984) (xy 99.244386 -220.856354)
			(xy 99.288961 -220.83226) (xy 99.336698 -220.815272) (xy 99.361498 -220.810074) (xy 99.384358 -220.805756)
			(xy 99.589336 -220.450664) (xy 99.581462 -220.42882) (xy 99.572829 -220.402408) (xy 99.5635 -220.347635)
			(xy 99.56292 -220.319854) (xy 99.563428 -220.293947) (xy 99.571534 -220.24277) (xy 99.587546 -220.193491)
			(xy 99.611069 -220.147324) (xy 99.641525 -220.105405) (xy 99.678163 -220.068767) (xy 99.720082 -220.038311)
			(xy 99.766249 -220.014788) (xy 99.815528 -219.998776) (xy 99.866705 -219.99067) (xy 99.918519 -219.99067)
			(xy 99.969696 -219.998776) (xy 100.018975 -220.014788) (xy 100.065142 -220.038311) (xy 100.107061 -220.068767)
			(xy 100.143699 -220.105405) (xy 100.174155 -220.147324) (xy 100.197678 -220.193491) (xy 100.21369 -220.24277)
			(xy 100.221796 -220.293947) (xy 100.222304 -220.319854) (xy 100.221828 -220.345199) (xy 100.214049 -220.395289)
			(xy 100.198697 -220.443599) (xy 100.176134 -220.48899) (xy 100.146891 -220.530396) (xy 100.111657 -220.566839)
			(xy 100.071262 -220.597461) (xy 100.026657 -220.621543) (xy 99.978893 -220.638516) (xy 99.95408 -220.643704)
			(xy 99.93122 -220.648022) (xy 99.726242 -221.003114) (xy 99.734116 -221.024958) (xy 99.74271 -221.051373)
			(xy 99.751897 -221.106151) (xy 99.752404 -221.133924) (xy 100.033328 -221.133924) (xy 100.033836 -221.108037)
			(xy 100.041935 -221.056899) (xy 100.057934 -221.007659) (xy 100.08144 -220.961527) (xy 100.111872 -220.91964)
			(xy 100.148482 -220.88303) (xy 100.190369 -220.852598) (xy 100.236501 -220.829092) (xy 100.285741 -220.813093)
			(xy 100.336879 -220.804994) (xy 100.388653 -220.804994) (xy 100.439791 -220.813093) (xy 100.489031 -220.829092)
			(xy 100.535163 -220.852598) (xy 100.57705 -220.88303) (xy 100.61366 -220.91964) (xy 100.644092 -220.961527)
			(xy 100.667598 -221.007659) (xy 100.683597 -221.056899) (xy 100.691696 -221.108037) (xy 100.692204 -221.133924)
			(xy 100.69168 -221.161632) (xy 100.682481 -221.216279) (xy 100.673916 -221.242636) (xy 100.666042 -221.264734)
			(xy 100.87102 -221.619572) (xy 100.89388 -221.62389) (xy 100.918705 -221.629041) (xy 100.966483 -221.645999)
			(xy 101.011102 -221.670074) (xy 101.051507 -221.700696) (xy 101.086747 -221.737145) (xy 101.11599 -221.778561)
			(xy 101.138547 -221.823965) (xy 101.153885 -221.872289) (xy 101.161642 -221.92239) (xy 101.162104 -221.94774)
			(xy 101.161596 -221.973647) (xy 101.15349 -222.024824) (xy 101.137478 -222.074103) (xy 101.113955 -222.12027)
			(xy 101.083499 -222.162189) (xy 101.046861 -222.198827) (xy 101.004942 -222.229283) (xy 100.958775 -222.252806)
			(xy 100.909496 -222.268818) (xy 100.858319 -222.276924) (xy 100.806505 -222.276924) (xy 100.755328 -222.268818)
			(xy 100.706049 -222.252806) (xy 100.659882 -222.229283) (xy 100.617963 -222.198827) (xy 100.581325 -222.162189)
			(xy 100.550869 -222.12027) (xy 100.527346 -222.074103) (xy 100.511334 -222.024824) (xy 100.503228 -221.973647)
			(xy 100.50272 -221.94774) (xy 100.503323 -221.920023) (xy 100.51264 -221.865377) (xy 100.521262 -221.839028)
			(xy 100.529136 -221.81693) (xy 100.324158 -221.462092) (xy 100.301298 -221.457774) (xy 100.276503 -221.45255)
			(xy 100.228767 -221.435564) (xy 100.184192 -221.411474) (xy 100.143827 -221.380847) (xy 100.108624 -221.344405)
			(xy 100.079411 -221.303006) (xy 100.056876 -221.257625) (xy 100.04155 -221.20933) (xy 100.033794 -221.159258)
			(xy 100.033328 -221.133924) (xy 99.752404 -221.133924) (xy 99.751896 -221.159811) (xy 99.743797 -221.210949)
			(xy 99.727798 -221.260189) (xy 99.704292 -221.306321) (xy 99.67386 -221.348208) (xy 99.63725 -221.384818)
			(xy 99.595363 -221.41525) (xy 99.549231 -221.438756) (xy 99.499991 -221.454755) (xy 99.448853 -221.462854)
			(xy 99.397079 -221.462854) (xy 99.345941 -221.454755) (xy 99.296701 -221.438756) (xy 99.250569 -221.41525)
			(xy 99.208682 -221.384818) (xy 99.172072 -221.348208) (xy 99.14164 -221.306321) (xy 99.118134 -221.260189)
			(xy 99.102135 -221.210949) (xy 99.094036 -221.159811) (xy 99.093528 -221.133924) (xy 98.812604 -221.133924)
			(xy 98.81208 -221.161632) (xy 98.802881 -221.216279) (xy 98.794316 -221.242636) (xy 98.786442 -221.264734)
			(xy 98.99142 -221.619572) (xy 99.01428 -221.62389) (xy 99.039105 -221.629041) (xy 99.086883 -221.645999)
			(xy 99.131502 -221.670074) (xy 99.171907 -221.700696) (xy 99.207147 -221.737145) (xy 99.23639 -221.778561)
			(xy 99.258947 -221.823965) (xy 99.274285 -221.872289) (xy 99.282042 -221.92239) (xy 99.282504 -221.94774)
			(xy 99.281996 -221.973647) (xy 99.27389 -222.024824) (xy 99.257878 -222.074103) (xy 99.234355 -222.12027)
			(xy 99.203899 -222.162189) (xy 99.167261 -222.198827) (xy 99.125342 -222.229283) (xy 99.079175 -222.252806)
			(xy 99.029896 -222.268818) (xy 98.978719 -222.276924) (xy 98.926905 -222.276924) (xy 98.875728 -222.268818)
			(xy 98.826449 -222.252806) (xy 98.780282 -222.229283) (xy 98.738363 -222.198827) (xy 98.701725 -222.162189)
			(xy 98.671269 -222.12027) (xy 98.647746 -222.074103) (xy 98.631734 -222.024824) (xy 98.623628 -221.973647)
			(xy 98.62312 -221.94774) (xy 98.623723 -221.920023) (xy 98.63304 -221.865377) (xy 98.641662 -221.839028)
			(xy 98.649536 -221.81693) (xy 98.444558 -221.462092) (xy 98.421698 -221.457774) (xy 98.396903 -221.45255)
			(xy 98.349167 -221.435564) (xy 98.304592 -221.411474) (xy 98.264227 -221.380847) (xy 98.229024 -221.344405)
			(xy 98.199811 -221.303006) (xy 98.177276 -221.257625) (xy 98.16195 -221.20933) (xy 98.154194 -221.159258)
			(xy 98.153728 -221.133924) (xy 97.872804 -221.133924) (xy 97.872295 -221.159818) (xy 97.864195 -221.210968)
			(xy 97.848197 -221.260223) (xy 97.824694 -221.30637) (xy 97.794266 -221.348276) (xy 97.75766 -221.384909)
			(xy 97.715777 -221.415368) (xy 97.669646 -221.438904) (xy 97.620404 -221.454938) (xy 97.569259 -221.463076)
			(xy 97.543366 -221.463616) (xy 97.528095 -221.463398) (xy 97.497692 -221.460472) (xy 97.48266 -221.457774)
			(xy 97.467913 -221.455562) (xy 97.438285 -221.458805) (xy 97.410852 -221.470457) (xy 97.387947 -221.489528)
			(xy 97.371518 -221.514396) (xy 97.362961 -221.542947) (xy 97.362518 -221.55785) (xy 97.362518 -221.789498)
			(xy 97.367852 -221.800166) (xy 97.378867 -221.823193) (xy 97.394457 -221.871797) (xy 97.40239 -221.922219)
			(xy 97.402904 -221.94774) (xy 97.402411 -221.973263) (xy 97.3945 -222.023694) (xy 97.378891 -222.072296)
			(xy 97.367852 -222.095314) (xy 97.362518 -222.105982) (xy 97.362518 -223.41967) (xy 97.367852 -223.430338)
			(xy 97.378513 -223.453058) (xy 97.393575 -223.500928) (xy 97.401169 -223.550534) (xy 97.401634 -223.575626)
			(xy 97.401179 -223.600719) (xy 97.393581 -223.650326) (xy 97.37852 -223.698197) (xy 97.367852 -223.720914)
			(xy 97.362518 -223.731582) (xy 97.362518 -224.082864) (xy 97.422208 -224.082864) (xy 97.43059 -224.079816)
			(xy 97.443145 -224.075343) (xy 97.468831 -224.068219) (xy 97.481898 -224.065592) (xy 97.504758 -224.061274)
			(xy 97.709482 -223.706436) (xy 97.701862 -223.684338) (xy 97.693235 -223.65799) (xy 97.683906 -223.603344)
			(xy 97.68332 -223.575626) (xy 97.683828 -223.549719) (xy 97.691934 -223.498542) (xy 97.707946 -223.449263)
			(xy 97.731469 -223.403096) (xy 97.761925 -223.361177) (xy 97.798563 -223.324539) (xy 97.840482 -223.294083)
			(xy 97.886649 -223.27056) (xy 97.935928 -223.254548) (xy 97.987105 -223.246442) (xy 98.038919 -223.246442)
			(xy 98.090096 -223.254548) (xy 98.139375 -223.27056) (xy 98.185542 -223.294083) (xy 98.227461 -223.324539)
			(xy 98.264099 -223.361177) (xy 98.294555 -223.403096) (xy 98.318078 -223.449263) (xy 98.33409 -223.498542)
			(xy 98.342196 -223.549719) (xy 98.342704 -223.575626) (xy 98.342229 -223.600984) (xy 98.334444 -223.651099)
			(xy 98.319076 -223.699431) (xy 98.296488 -223.744839) (xy 98.267213 -223.786253) (xy 98.231942 -223.822696)
			(xy 98.191506 -223.853307) (xy 98.14686 -223.877366) (xy 98.099055 -223.894304) (xy 98.074226 -223.899476)
			(xy 98.051366 -223.903794) (xy 97.846642 -224.258632) (xy 97.854516 -224.280476) (xy 97.863096 -224.306895)
			(xy 97.872293 -224.36167) (xy 97.872804 -224.389442) (xy 98.153728 -224.389442) (xy 98.154236 -224.363555)
			(xy 98.162335 -224.312417) (xy 98.178334 -224.263177) (xy 98.20184 -224.217045) (xy 98.232272 -224.175158)
			(xy 98.268882 -224.138548) (xy 98.310769 -224.108116) (xy 98.356901 -224.08461) (xy 98.406141 -224.068611)
			(xy 98.457279 -224.060512) (xy 98.509053 -224.060512) (xy 98.560191 -224.068611) (xy 98.609431 -224.08461)
			(xy 98.655563 -224.108116) (xy 98.69745 -224.138548) (xy 98.73406 -224.175158) (xy 98.764492 -224.217045)
			(xy 98.787998 -224.263177) (xy 98.803997 -224.312417) (xy 98.812096 -224.363555) (xy 98.812604 -224.389442)
			(xy 99.093528 -224.389442) (xy 99.093935 -224.364105) (xy 99.101697 -224.314028) (xy 99.117029 -224.265728)
			(xy 99.13957 -224.220343) (xy 99.168789 -224.17894) (xy 99.203999 -224.142496) (xy 99.24437 -224.111867)
			(xy 99.288952 -224.087776) (xy 99.336695 -224.070789) (xy 99.361498 -224.065592) (xy 99.384358 -224.061274)
			(xy 99.589082 -223.706436) (xy 99.581462 -223.684338) (xy 99.572831 -223.657991) (xy 99.56351 -223.603344)
			(xy 99.56292 -223.575626) (xy 99.563428 -223.549719) (xy 99.571534 -223.498542) (xy 99.587546 -223.449263)
			(xy 99.611069 -223.403096) (xy 99.641525 -223.361177) (xy 99.678163 -223.324539) (xy 99.720082 -223.294083)
			(xy 99.766249 -223.27056) (xy 99.815528 -223.254548) (xy 99.866705 -223.246442) (xy 99.918519 -223.246442)
			(xy 99.969696 -223.254548) (xy 100.018975 -223.27056) (xy 100.065142 -223.294083) (xy 100.107061 -223.324539)
			(xy 100.143699 -223.361177) (xy 100.174155 -223.403096) (xy 100.197678 -223.449263) (xy 100.21369 -223.498542)
			(xy 100.221796 -223.549719) (xy 100.222304 -223.575626) (xy 100.221887 -223.600992) (xy 100.214134 -223.651127)
			(xy 100.198785 -223.69948) (xy 100.176203 -223.744908) (xy 100.146922 -223.786336) (xy 100.111634 -223.822783)
			(xy 100.071175 -223.853388) (xy 100.026501 -223.877427) (xy 99.978669 -223.894332) (xy 99.953826 -223.899476)
			(xy 99.930966 -223.903794) (xy 99.726242 -224.258632) (xy 99.734116 -224.280476) (xy 99.74269 -224.306896)
			(xy 99.75189 -224.36167) (xy 99.752404 -224.389442) (xy 100.033328 -224.389442) (xy 100.033836 -224.363555)
			(xy 100.041935 -224.312417) (xy 100.057934 -224.263177) (xy 100.08144 -224.217045) (xy 100.111872 -224.175158)
			(xy 100.148482 -224.138548) (xy 100.190369 -224.108116) (xy 100.236501 -224.08461) (xy 100.285741 -224.068611)
			(xy 100.336879 -224.060512) (xy 100.388653 -224.060512) (xy 100.439791 -224.068611) (xy 100.489031 -224.08461)
			(xy 100.535163 -224.108116) (xy 100.57705 -224.138548) (xy 100.61366 -224.175158) (xy 100.644092 -224.217045)
			(xy 100.667598 -224.263177) (xy 100.683597 -224.312417) (xy 100.691696 -224.363555) (xy 100.692204 -224.389442)
			(xy 100.973128 -224.389442) (xy 100.973535 -224.364105) (xy 100.981297 -224.314028) (xy 100.996629 -224.265728)
			(xy 101.01917 -224.220343) (xy 101.048389 -224.17894) (xy 101.083599 -224.142496) (xy 101.12397 -224.111867)
			(xy 101.168552 -224.087776) (xy 101.216295 -224.070789) (xy 101.241098 -224.065592) (xy 101.263958 -224.061274)
			(xy 101.468682 -223.706436) (xy 101.461062 -223.684338) (xy 101.452431 -223.657991) (xy 101.44311 -223.603344)
			(xy 101.44252 -223.575626) (xy 101.443028 -223.549719) (xy 101.451134 -223.498542) (xy 101.467146 -223.449263)
			(xy 101.490669 -223.403096) (xy 101.521125 -223.361177) (xy 101.557763 -223.324539) (xy 101.599682 -223.294083)
			(xy 101.645849 -223.27056) (xy 101.695128 -223.254548) (xy 101.746305 -223.246442) (xy 101.798119 -223.246442)
			(xy 101.849296 -223.254548) (xy 101.898575 -223.27056) (xy 101.944742 -223.294083) (xy 101.986661 -223.324539)
			(xy 102.023299 -223.361177) (xy 102.053755 -223.403096) (xy 102.077278 -223.449263) (xy 102.09329 -223.498542)
			(xy 102.101396 -223.549719) (xy 102.101904 -223.575626) (xy 102.101487 -223.600992) (xy 102.093734 -223.651127)
			(xy 102.078385 -223.69948) (xy 102.055803 -223.744908) (xy 102.026522 -223.786336) (xy 101.991234 -223.822783)
			(xy 101.950775 -223.853388) (xy 101.906101 -223.877427) (xy 101.858269 -223.894332) (xy 101.833426 -223.899476)
			(xy 101.810566 -223.903794) (xy 101.605842 -224.258632) (xy 101.613716 -224.280476) (xy 101.62229 -224.306896)
			(xy 101.63149 -224.36167) (xy 101.632004 -224.389442) (xy 101.631496 -224.415329) (xy 101.623397 -224.466467)
			(xy 101.607398 -224.515707) (xy 101.583892 -224.561839) (xy 101.55346 -224.603726) (xy 101.51685 -224.640336)
			(xy 101.474963 -224.670768) (xy 101.428831 -224.694274) (xy 101.379591 -224.710273) (xy 101.328453 -224.718372)
			(xy 101.276679 -224.718372) (xy 101.225541 -224.710273) (xy 101.176301 -224.694274) (xy 101.130169 -224.670768)
			(xy 101.088282 -224.640336) (xy 101.051672 -224.603726) (xy 101.02124 -224.561839) (xy 100.997734 -224.515707)
			(xy 100.981735 -224.466467) (xy 100.973636 -224.415329) (xy 100.973128 -224.389442) (xy 100.692204 -224.389442)
			(xy 100.69166 -224.417149) (xy 100.682474 -224.471796) (xy 100.673916 -224.498154) (xy 100.666042 -224.520252)
			(xy 100.87102 -224.87509) (xy 100.89388 -224.879408) (xy 100.918709 -224.884542) (xy 100.966488 -224.901501)
			(xy 101.011108 -224.925578) (xy 101.051514 -224.956202) (xy 101.086754 -224.992654) (xy 101.115997 -225.034071)
			(xy 101.138552 -225.079478) (xy 101.153888 -225.127804) (xy 101.161643 -225.177908) (xy 101.162104 -225.203258)
			(xy 101.161596 -225.229165) (xy 101.15349 -225.280342) (xy 101.137478 -225.329621) (xy 101.113955 -225.375788)
			(xy 101.083499 -225.417707) (xy 101.046861 -225.454345) (xy 101.004942 -225.484801) (xy 100.958775 -225.508324)
			(xy 100.909496 -225.524336) (xy 100.858319 -225.532442) (xy 100.806505 -225.532442) (xy 100.755328 -225.524336)
			(xy 100.706049 -225.508324) (xy 100.659882 -225.484801) (xy 100.617963 -225.454345) (xy 100.581325 -225.417707)
			(xy 100.550869 -225.375788) (xy 100.527346 -225.329621) (xy 100.511334 -225.280342) (xy 100.503228 -225.229165)
			(xy 100.50272 -225.203258) (xy 100.503327 -225.175541) (xy 100.512642 -225.120895) (xy 100.521262 -225.094546)
			(xy 100.529136 -225.072448) (xy 100.324158 -224.71761) (xy 100.301298 -224.713292) (xy 100.276485 -224.708145)
			(xy 100.228743 -224.691153) (xy 100.184163 -224.667056) (xy 100.143796 -224.63642) (xy 100.108593 -224.599968)
			(xy 100.079382 -224.558558) (xy 100.056852 -224.513166) (xy 100.041534 -224.46486) (xy 100.033788 -224.41478)
			(xy 100.033328 -224.389442) (xy 99.752404 -224.389442) (xy 99.751896 -224.415329) (xy 99.743797 -224.466467)
			(xy 99.727798 -224.515707) (xy 99.704292 -224.561839) (xy 99.67386 -224.603726) (xy 99.63725 -224.640336)
			(xy 99.595363 -224.670768) (xy 99.549231 -224.694274) (xy 99.499991 -224.710273) (xy 99.448853 -224.718372)
			(xy 99.397079 -224.718372) (xy 99.345941 -224.710273) (xy 99.296701 -224.694274) (xy 99.250569 -224.670768)
			(xy 99.208682 -224.640336) (xy 99.172072 -224.603726) (xy 99.14164 -224.561839) (xy 99.118134 -224.515707)
			(xy 99.102135 -224.466467) (xy 99.094036 -224.415329) (xy 99.093528 -224.389442) (xy 98.812604 -224.389442)
			(xy 98.81206 -224.417149) (xy 98.802874 -224.471796) (xy 98.794316 -224.498154) (xy 98.786442 -224.520252)
			(xy 98.99142 -224.87509) (xy 99.01428 -224.879408) (xy 99.039109 -224.884542) (xy 99.086888 -224.901501)
			(xy 99.131508 -224.925578) (xy 99.171914 -224.956202) (xy 99.207154 -224.992654) (xy 99.236397 -225.034071)
			(xy 99.258952 -225.079478) (xy 99.274288 -225.127804) (xy 99.282043 -225.177908) (xy 99.282504 -225.203258)
			(xy 99.281996 -225.229165) (xy 99.27389 -225.280342) (xy 99.257878 -225.329621) (xy 99.234355 -225.375788)
			(xy 99.203899 -225.417707) (xy 99.167261 -225.454345) (xy 99.125342 -225.484801) (xy 99.079175 -225.508324)
			(xy 99.029896 -225.524336) (xy 98.978719 -225.532442) (xy 98.926905 -225.532442) (xy 98.875728 -225.524336)
			(xy 98.826449 -225.508324) (xy 98.780282 -225.484801) (xy 98.738363 -225.454345) (xy 98.701725 -225.417707)
			(xy 98.671269 -225.375788) (xy 98.647746 -225.329621) (xy 98.631734 -225.280342) (xy 98.623628 -225.229165)
			(xy 98.62312 -225.203258) (xy 98.623727 -225.175541) (xy 98.633042 -225.120895) (xy 98.641662 -225.094546)
			(xy 98.649536 -225.072448) (xy 98.444558 -224.71761) (xy 98.421698 -224.713292) (xy 98.396885 -224.708145)
			(xy 98.349143 -224.691153) (xy 98.304563 -224.667056) (xy 98.264196 -224.63642) (xy 98.228993 -224.599968)
			(xy 98.199782 -224.558558) (xy 98.177252 -224.513166) (xy 98.161934 -224.46486) (xy 98.154188 -224.41478)
			(xy 98.153728 -224.389442) (xy 97.872804 -224.389442) (xy 97.872293 -224.415326) (xy 97.864188 -224.466457)
			(xy 97.848185 -224.515689) (xy 97.824677 -224.561813) (xy 97.794243 -224.603691) (xy 97.757633 -224.640293)
			(xy 97.715748 -224.670717) (xy 97.669619 -224.694214) (xy 97.620383 -224.710206) (xy 97.56925 -224.718299)
			(xy 97.543366 -224.71888) (xy 97.528101 -224.718716) (xy 97.497699 -224.715913) (xy 97.48266 -224.713292)
			(xy 97.467914 -224.71108) (xy 97.438288 -224.714322) (xy 97.410857 -224.725975) (xy 97.387954 -224.745047)
			(xy 97.371528 -224.769915) (xy 97.362977 -224.798465) (xy 97.362518 -224.813368) (xy 97.362518 -225.045016)
			(xy 97.367852 -225.055684) (xy 97.378865 -225.078711) (xy 97.394453 -225.127315) (xy 97.402383 -225.177738)
			(xy 97.402904 -225.203258) (xy 97.40241 -225.228781) (xy 97.394497 -225.279211) (xy 97.378885 -225.327811)
			(xy 97.367852 -225.350832) (xy 97.362518 -225.3615) (xy 97.362518 -226.085146) (xy 97.361902 -226.110101)
			(xy 97.352158 -226.159051) (xy 97.333052 -226.205159) (xy 97.305319 -226.246655) (xy 97.288096 -226.264724)
			(xy 95.98406 -227.56876) (xy 95.988124 -227.594414) (xy 95.989926 -227.606972) (xy 95.99183 -227.632273)
			(xy 95.991934 -227.64496) (xy 95.991457 -227.670751) (xy 95.983393 -227.721698) (xy 95.967457 -227.770756)
			(xy 95.944042 -227.816716) (xy 95.913725 -227.858447) (xy 95.877252 -227.894921) (xy 95.835521 -227.925239)
			(xy 95.789561 -227.948655) (xy 95.740504 -227.964592) (xy 95.689557 -227.972657) (xy 95.663766 -227.973128)
			(xy 95.651079 -227.97304) (xy 95.625777 -227.971134) (xy 95.61322 -227.969318) (xy 95.587566 -227.965254)
			(xy 93.61043 -229.94239) (xy 93.62186 -229.97287) (xy 93.631353 -230.000354) (xy 93.641567 -230.057591)
			(xy 93.64218 -230.086662) (xy 93.641704 -230.112454) (xy 93.63364 -230.163404) (xy 93.617704 -230.212464)
			(xy 93.59429 -230.258428) (xy 93.563973 -230.300163) (xy 93.527501 -230.336641) (xy 93.485771 -230.366964)
			(xy 93.439811 -230.390385) (xy 93.390752 -230.406328) (xy 93.339804 -230.4144) (xy 93.314012 -230.41483)
			(xy 93.284942 -230.414206) (xy 93.227707 -230.40399) (xy 93.20022 -230.39451) (xy 93.16974 -230.38308)
			(xy 91.750896 -231.801924) (xy 91.74734 -231.813608) (xy 91.738945 -231.838443) (xy 91.71539 -231.885274)
			(xy 91.68469 -231.927766) (xy 91.647627 -231.964838) (xy 91.605143 -231.995548) (xy 91.558318 -232.019115)
			(xy 91.533472 -232.027476) (xy 91.521788 -232.031032) (xy 91.226386 -232.326434) (xy 91.246706 -232.36047)
			(xy 91.261196 -232.386056) (xy 91.281816 -232.441114) (xy 91.292288 -232.498967) (xy 91.292934 -232.528364)
			(xy 91.292457 -232.554155) (xy 91.284392 -232.605101) (xy 91.268456 -232.654158) (xy 91.245041 -232.700118)
			(xy 91.214724 -232.741849) (xy 91.178251 -232.778322) (xy 91.13652 -232.80864) (xy 91.09056 -232.832056)
			(xy 91.041503 -232.847992) (xy 90.990556 -232.856057) (xy 90.964766 -232.856532) (xy 90.93537 -232.855875)
			(xy 90.87752 -232.845399) (xy 90.82246 -232.824787) (xy 90.796872 -232.810304) (xy 90.762836 -232.789984)
			(xy 89.782142 -233.770678) (xy 89.782142 -234.733338) (xy 89.800879 -234.752028) (xy 89.832677 -234.794331)
			(xy 89.857276 -234.841186) (xy 89.874039 -234.891382) (xy 89.882533 -234.943616) (xy 89.882537 -234.996537)
			(xy 89.87405 -235.048772) (xy 89.857294 -235.09897) (xy 89.832702 -235.145829) (xy 89.80091 -235.188137)
			(xy 89.782142 -235.206794) (xy 89.782142 -236.361224) (xy 89.80088 -236.379914) (xy 89.83268 -236.422217)
			(xy 89.857281 -236.469074) (xy 89.874047 -236.51927) (xy 89.882542 -236.571506) (xy 89.882547 -236.624428)
			(xy 89.874063 -236.676665) (xy 89.857307 -236.726865) (xy 89.832715 -236.773727) (xy 89.800924 -236.816036)
			(xy 89.782142 -236.83468) (xy 89.782142 -237.988856) (xy 89.800878 -238.007546) (xy 89.832672 -238.049848)
			(xy 89.857269 -238.096703) (xy 89.87403 -238.146897) (xy 89.882521 -238.19913) (xy 89.882523 -238.252048)
			(xy 89.874035 -238.304281) (xy 89.857277 -238.354477) (xy 89.832684 -238.401333) (xy 89.800892 -238.443637)
			(xy 89.782142 -238.462312) (xy 89.782142 -239.616488) (xy 89.800875 -239.635178) (xy 89.832665 -239.677479)
			(xy 89.857256 -239.724333) (xy 89.874012 -239.774524) (xy 89.8825 -239.826754) (xy 89.882498 -239.879668)
			(xy 89.874007 -239.931897) (xy 89.857247 -239.982088) (xy 89.832653 -240.028939) (xy 89.80086 -240.071239)
			(xy 89.782142 -240.089944) (xy 89.782142 -241.244374) (xy 89.800876 -241.263064) (xy 89.832668 -241.305366)
			(xy 89.857262 -241.35222) (xy 89.87402 -241.402412) (xy 89.882509 -241.454643) (xy 89.882509 -241.50756)
			(xy 89.874019 -241.55979) (xy 89.85726 -241.609983) (xy 89.832666 -241.656837) (xy 89.800874 -241.699138)
			(xy 89.782142 -241.71783) (xy 89.782142 -242.87226) (xy 89.800877 -242.89095) (xy 89.832671 -242.933252)
			(xy 89.857267 -242.980107) (xy 89.874027 -243.0303) (xy 89.882518 -243.082533) (xy 89.88252 -243.135451)
			(xy 89.874031 -243.187683) (xy 89.857274 -243.237878) (xy 89.83268 -243.284734) (xy 89.800888 -243.327037)
			(xy 89.782142 -243.345716) (xy 89.782142 -244.499892) (xy 89.800875 -244.518582) (xy 89.832664 -244.560883)
			(xy 89.857255 -244.607736) (xy 89.87401 -244.657927) (xy 89.882497 -244.710157) (xy 89.882495 -244.763071)
			(xy 89.874004 -244.815299) (xy 89.857244 -244.865489) (xy 89.832649 -244.91234) (xy 89.800856 -244.954639)
			(xy 89.782142 -244.973348) (xy 89.782142 -246.127778) (xy 89.800876 -246.146468) (xy 89.832667 -246.18877)
			(xy 89.85726 -246.235623) (xy 89.874018 -246.285816) (xy 89.882506 -246.338046) (xy 89.882506 -246.390962)
			(xy 89.874016 -246.443192) (xy 89.857257 -246.493384) (xy 89.832663 -246.540237) (xy 89.80087 -246.582538)
			(xy 89.782142 -246.601234) (xy 89.782142 -247.755156) (xy 89.800905 -247.77386) (xy 89.832748 -247.816198)
			(xy 89.857381 -247.8631) (xy 89.874166 -247.913347) (xy 89.882666 -247.965638) (xy 89.882662 -248.018615)
			(xy 89.874153 -248.070904) (xy 89.857361 -248.121149) (xy 89.83272 -248.168046) (xy 89.80087 -248.21038)
			(xy 89.782142 -248.22912) (xy 89.782142 -249.383296) (xy 89.800874 -249.401986) (xy 89.832663 -249.444287)
			(xy 89.857253 -249.49114) (xy 89.874008 -249.541331) (xy 89.882494 -249.59356) (xy 89.882492 -249.646473)
			(xy 89.874 -249.698701) (xy 89.85724 -249.748891) (xy 89.832645 -249.795741) (xy 89.800852 -249.838039)
			(xy 89.782142 -249.856752) (xy 89.782142 -254.42545) (xy 89.810336 -254.43942) (xy 89.833479 -254.451429)
			(xy 89.875967 -254.481644) (xy 89.913144 -254.518197) (xy 89.944075 -254.560168) (xy 89.967982 -254.6065)
			(xy 89.984262 -254.65603) (xy 89.992508 -254.70751) (xy 89.992512 -254.759647) (xy 89.984273 -254.811129)
			(xy 89.967998 -254.86066) (xy 89.944098 -254.906996) (xy 89.913172 -254.948971) (xy 89.876 -254.985528)
			(xy 89.833516 -255.01575) (xy 89.810336 -255.027684) (xy 89.782142 -255.041654) (xy 89.782142 -256.053336)
			(xy 89.810336 -256.067306) (xy 89.833472 -256.079315) (xy 89.875947 -256.109528) (xy 89.913111 -256.146077)
			(xy 89.944029 -256.188041) (xy 89.967925 -256.234366) (xy 89.984196 -256.283885) (xy 89.992434 -256.335355)
			(xy 89.992431 -256.387479) (xy 89.984188 -256.438948) (xy 89.967912 -256.488466) (xy 89.944012 -256.534788)
			(xy 89.913089 -256.576749) (xy 89.875921 -256.613293) (xy 89.833443 -256.643503) (xy 89.810336 -256.65557)
			(xy 89.782142 -256.66954) (xy 89.782142 -257.680968) (xy 89.810336 -257.694938) (xy 89.833478 -257.706946)
			(xy 89.875963 -257.737162) (xy 89.913138 -257.773714) (xy 89.944066 -257.815683) (xy 89.96797 -257.862014)
			(xy 89.984249 -257.911541) (xy 89.992493 -257.96302) (xy 89.992495 -258.015154) (xy 89.984255 -258.066633)
			(xy 89.96798 -258.116161) (xy 89.94408 -258.162494) (xy 89.913155 -258.204466) (xy 89.875984 -258.241021)
			(xy 89.833501 -258.27124) (xy 89.810336 -258.283202) (xy 89.782142 -258.297172) (xy 89.782142 -259.308854)
			(xy 89.810336 -259.322824) (xy 89.833479 -259.334832) (xy 89.875966 -259.365048) (xy 89.913143 -259.401601)
			(xy 89.944073 -259.443571) (xy 89.967979 -259.489903) (xy 89.984259 -259.539432) (xy 89.992505 -259.590912)
			(xy 89.992508 -259.643049) (xy 89.984269 -259.69453) (xy 89.967994 -259.744061) (xy 89.944094 -259.790396)
			(xy 89.913169 -259.83237) (xy 89.875996 -259.868927) (xy 89.833512 -259.899147) (xy 89.810336 -259.911088)
			(xy 89.782142 -259.925058) (xy 89.782142 -260.820154) (xy 91.507564 -262.545576) (xy 91.529916 -262.54456)
			(xy 91.544394 -262.544306) (xy 91.570183 -262.544811) (xy 91.621125 -262.552878) (xy 91.670178 -262.568815)
			(xy 91.716135 -262.592229) (xy 91.757863 -262.622544) (xy 91.794336 -262.659013) (xy 91.824654 -262.700738)
			(xy 91.848073 -262.746692) (xy 91.864014 -262.795744) (xy 91.872086 -262.846685) (xy 91.872562 -262.872474)
			(xy 91.872308 -262.886952) (xy 91.871292 -262.909304) (xy 93.210126 -264.248138) (xy 93.24467 -264.225532)
			(xy 93.26477 -264.212922) (xy 93.307832 -264.192994) (xy 93.353314 -264.179473) (xy 93.400269 -264.17264)
			(xy 93.423994 -264.172192) (xy 93.449783 -264.172697) (xy 93.500726 -264.180764) (xy 93.549781 -264.196701)
			(xy 93.595738 -264.220115) (xy 93.637467 -264.250429) (xy 93.673941 -264.286898) (xy 93.704261 -264.328623)
			(xy 93.727681 -264.374577) (xy 93.743625 -264.423629) (xy 93.751699 -264.474571) (xy 93.752162 -264.50036)
			(xy 93.751746 -264.524087) (xy 93.744915 -264.571046) (xy 93.731389 -264.616531) (xy 93.711451 -264.659593)
			(xy 93.698822 -264.679684) (xy 93.676216 -264.714228) (xy 93.953076 -264.991088) (xy 93.9673 -264.994136)
			(xy 93.992831 -265.000509) (xy 94.041598 -265.02027) (xy 94.086588 -265.047557) (xy 94.126651 -265.08167)
			(xy 94.16076 -265.121735) (xy 94.188043 -265.166728) (xy 94.2078 -265.215496) (xy 94.214188 -265.241024)
			(xy 94.217236 -265.255248) (xy 95.614744 -266.652756) (xy 95.64624 -266.639548) (xy 95.666496 -266.63138)
			(xy 95.708626 -266.619863) (xy 95.75191 -266.61403) (xy 95.773748 -266.61364) (xy 95.799533 -266.614149)
			(xy 95.850467 -266.622223) (xy 95.899511 -266.638165) (xy 95.945457 -266.661583) (xy 95.987175 -266.691899)
			(xy 96.023638 -266.728367) (xy 96.053947 -266.77009) (xy 96.077356 -266.816041) (xy 96.09329 -266.865088)
			(xy 96.101355 -266.916023) (xy 96.101916 -266.941808) (xy 96.101542 -266.963647) (xy 96.095714 -267.006934)
			(xy 96.08419 -267.049064) (xy 96.076008 -267.069316) (xy 96.0628 -267.100812) (xy 96.745298 -267.78331)
			(xy 102.49154 -267.78331)
		)
		(stroke
			(width 0)
			(type solid)
		)
		(fill yes)
		(layer "In9.Cu")
		(net "PVCCFA_EHV_CPU1")
	)
	(gr_poly
		(pts
			(xy 367.571274 -270.701262) (xy 367.59727 -270.692852) (xy 367.651146 -270.683782) (xy 367.678462 -270.683228)
			(xy 367.705781 -270.683767) (xy 367.759661 -270.692825) (xy 367.78565 -270.701262) (xy 367.793778 -270.704056)
			(xy 368.058192 -270.704056) (xy 368.069702 -270.685091) (xy 368.098216 -270.651111) (xy 368.132196 -270.622597)
			(xy 368.170611 -270.600416) (xy 368.212293 -270.585241) (xy 368.255977 -270.577532) (xy 368.278156 -270.577056)
			(xy 379.8824 -270.577056) (xy 380.086362 -270.373094) (xy 380.070614 -270.340582) (xy 380.06027 -270.318178)
			(xy 380.045671 -270.271042) (xy 380.038291 -270.222252) (xy 380.037848 -270.19758) (xy 380.038355 -270.171794)
			(xy 380.046426 -270.120857) (xy 380.062365 -270.07181) (xy 380.085781 -270.02586) (xy 380.116097 -269.984139)
			(xy 380.152566 -269.947674) (xy 380.194291 -269.917363) (xy 380.240243 -269.893952) (xy 380.289292 -269.878018)
			(xy 380.34023 -269.869952) (xy 380.366016 -269.869412) (xy 380.390688 -269.869856) (xy 380.439477 -269.877239)
			(xy 380.486613 -269.891837) (xy 380.509018 -269.902178) (xy 380.54153 -269.917926) (xy 381.91821 -268.541246)
			(xy 381.920496 -268.524228) (xy 381.924678 -268.498011) (xy 381.940396 -268.447304) (xy 381.964069 -268.399788)
			(xy 381.995079 -268.3567) (xy 382.032619 -268.319163) (xy 382.075709 -268.288156) (xy 382.123228 -268.264487)
			(xy 382.173935 -268.248773) (xy 382.20015 -268.244574) (xy 382.217168 -268.242288) (xy 382.477518 -267.981938)
			(xy 382.460642 -267.963544) (xy 382.432092 -267.922598) (xy 382.410082 -267.877797) (xy 382.39512 -267.830176)
			(xy 382.387554 -267.780836) (xy 382.387094 -267.755878) (xy 382.387601 -267.73009) (xy 382.395672 -267.679151)
			(xy 382.411611 -267.6301) (xy 382.435026 -267.584147) (xy 382.465341 -267.542421) (xy 382.501809 -267.505951)
			(xy 382.543533 -267.475635) (xy 382.589486 -267.452217) (xy 382.638535 -267.436276) (xy 382.689474 -267.428203)
			(xy 382.715262 -267.42771) (xy 382.740216 -267.428201) (xy 382.789542 -267.435801) (xy 382.837153 -267.45077)
			(xy 382.881953 -267.472765) (xy 382.922913 -267.501281) (xy 382.941322 -267.518134) (xy 387.197092 -263.262364)
			(xy 387.206494 -263.25235) (xy 387.220064 -263.22848) (xy 387.226784 -263.201858) (xy 387.226169 -263.174407)
			(xy 387.218263 -263.148112) (xy 387.203637 -263.124874) (xy 387.19379 -263.115298) (xy 387.173916 -263.096494)
			(xy 387.140096 -263.053491) (xy 387.113872 -263.005476) (xy 387.095972 -262.953778) (xy 387.086889 -262.899828)
			(xy 387.086348 -262.872474) (xy 387.086797 -262.847974) (xy 387.09407 -262.799518) (xy 387.108464 -262.752681)
			(xy 387.129662 -262.708504) (xy 387.15719 -262.667969) (xy 387.190439 -262.631977) (xy 387.228668 -262.601326)
			(xy 387.271029 -262.576699) (xy 387.316579 -262.558643) (xy 387.340348 -262.552688) (xy 387.379718 -262.543544)
			(xy 387.379718 -258.318) (xy 387.340348 -258.308856) (xy 387.315201 -258.302498) (xy 387.267164 -258.282939)
			(xy 387.222799 -258.256071) (xy 387.18321 -258.222561) (xy 387.149383 -258.183244) (xy 387.122159 -258.139096)
			(xy 387.102214 -258.091218) (xy 387.090046 -258.040798) (xy 387.085957 -257.989093) (xy 387.090048 -257.937388)
			(xy 387.102218 -257.886969) (xy 387.122165 -257.839092) (xy 387.149391 -257.794945) (xy 387.18322 -257.755629)
			(xy 387.22281 -257.722121) (xy 387.267176 -257.695255) (xy 387.315214 -257.675698) (xy 387.340348 -257.669284)
			(xy 387.379718 -257.66014) (xy 387.379718 -254.487172) (xy 387.345174 -254.475488) (xy 387.321159 -254.466817)
			(xy 387.275943 -254.443108) (xy 387.234941 -254.412686) (xy 387.199143 -254.376284) (xy 387.16941 -254.33478)
			(xy 387.14646 -254.289174) (xy 387.130845 -254.240565) (xy 387.122943 -254.190125) (xy 387.122943 -254.13907)
			(xy 387.130846 -254.08863) (xy 387.146462 -254.040021) (xy 387.169412 -253.994415) (xy 387.199146 -253.952912)
			(xy 387.234945 -253.916511) (xy 387.275947 -253.886089) (xy 387.321164 -253.862381) (xy 387.345174 -253.853696)
			(xy 387.379718 -253.842012) (xy 387.379718 -244.726968) (xy 387.358589 -244.711481) (xy 387.321077 -244.674918)
			(xy 387.289854 -244.632858) (xy 387.265713 -244.586369) (xy 387.249268 -244.536634) (xy 387.240938 -244.484917)
			(xy 387.240934 -244.432534) (xy 387.249256 -244.380816) (xy 387.265693 -244.331078) (xy 387.289827 -244.284585)
			(xy 387.321044 -244.24252) (xy 387.35855 -244.205951) (xy 387.379718 -244.19052) (xy 387.379718 -241.524282)
			(xy 387.345936 -241.51209) (xy 387.322399 -241.503164) (xy 387.278168 -241.479137) (xy 387.238124 -241.448637)
			(xy 387.203207 -241.41238) (xy 387.174237 -241.371216) (xy 387.151892 -241.326111) (xy 387.136697 -241.278123)
			(xy 387.129009 -241.228377) (xy 387.129008 -241.178041) (xy 387.136693 -241.128294) (xy 387.151885 -241.080305)
			(xy 387.174228 -241.035199) (xy 387.203196 -240.994033) (xy 387.238111 -240.957775) (xy 387.278153 -240.927273)
			(xy 387.322383 -240.903243) (xy 387.345936 -240.894362) (xy 387.379718 -240.88217) (xy 387.379718 -234.233974)
			(xy 383.560828 -230.415084) (xy 383.540254 -230.41483) (xy 383.51498 -230.413975) (xy 383.465136 -230.40545)
			(xy 383.417189 -230.389381) (xy 383.372275 -230.366147) (xy 383.331456 -230.336298) (xy 383.2957 -230.300541)
			(xy 383.265851 -230.259722) (xy 383.242618 -230.214807) (xy 383.226549 -230.16686) (xy 383.218025 -230.117016)
			(xy 383.217166 -230.091742) (xy 383.216912 -230.071168) (xy 381.866902 -228.721158) (xy 381.83312 -228.741224)
			(xy 381.80759 -228.75561) (xy 381.752689 -228.776085) (xy 381.695031 -228.786518) (xy 381.665734 -228.787198)
			(xy 381.639942 -228.786721) (xy 381.588992 -228.778657) (xy 381.53993 -228.762721) (xy 381.493966 -228.739307)
			(xy 381.45223 -228.708991) (xy 381.415751 -228.672519) (xy 381.385426 -228.630789) (xy 381.362003 -228.584829)
			(xy 381.346058 -228.535771) (xy 381.337984 -228.484822) (xy 381.337566 -228.45903) (xy 381.338076 -228.432191)
			(xy 381.346767 -228.379222) (xy 381.36397 -228.328376) (xy 381.389228 -228.281012) (xy 381.40513 -228.259386)
			(xy 381.10668 -227.960936) (xy 381.09525 -227.95738) (xy 381.070708 -227.948964) (xy 381.02444 -227.925496)
			(xy 380.98244 -227.89504) (xy 380.945756 -227.858354) (xy 380.9153 -227.816354) (xy 380.891833 -227.770085)
			(xy 380.883414 -227.745544) (xy 380.879858 -227.734114) (xy 380.4412 -227.295456) (xy 377.168156 -227.295456)
			(xy 377.143198 -227.29488) (xy 377.094242 -227.285133) (xy 377.048128 -227.266021) (xy 377.00663 -227.238279)
			(xy 376.988578 -227.221034) (xy 376.92457 -227.157026) (xy 376.908822 -227.154232) (xy 376.884305 -227.14938)
			(xy 376.837006 -227.133242) (xy 376.7927 -227.110119) (xy 376.752411 -227.080548) (xy 376.71707 -227.04521)
			(xy 376.687495 -227.004924) (xy 376.664369 -226.96062) (xy 376.648227 -226.913322) (xy 376.643392 -226.888802)
			(xy 376.640598 -226.873054) (xy 375.388378 -225.620834) (xy 375.374425 -225.60636) (xy 375.350818 -225.57382)
			(xy 375.341388 -225.556064) (xy 375.334027 -225.542763) (xy 375.312939 -225.52089) (xy 375.286348 -225.506191)
			(xy 375.256609 -225.499968) (xy 375.226355 -225.502772) (xy 375.212102 -225.508058) (xy 375.182077 -225.519537)
			(xy 375.119016 -225.53195) (xy 375.08688 -225.532696) (xy 375.060986 -225.532187) (xy 375.009836 -225.524087)
			(xy 374.960582 -225.508089) (xy 374.914434 -225.484587) (xy 374.872529 -225.454159) (xy 374.835896 -225.417553)
			(xy 374.805438 -225.375669) (xy 374.781902 -225.329539) (xy 374.765869 -225.280296) (xy 374.757732 -225.229151)
			(xy 374.757188 -225.203258) (xy 374.75778 -225.17554) (xy 374.767105 -225.120894) (xy 374.77573 -225.094546)
			(xy 374.783604 -225.072448) (xy 374.578626 -224.71761) (xy 374.555766 -224.713292) (xy 374.530965 -224.708093)
			(xy 374.483227 -224.691103) (xy 374.438651 -224.667009) (xy 374.398285 -224.636379) (xy 374.363081 -224.599934)
			(xy 374.333867 -224.558532) (xy 374.31133 -224.513149) (xy 374.296002 -224.464851) (xy 374.288244 -224.414778)
			(xy 374.287796 -224.389442) (xy 374.288304 -224.363555) (xy 374.296403 -224.312417) (xy 374.312402 -224.263177)
			(xy 374.335908 -224.217045) (xy 374.36634 -224.175158) (xy 374.40295 -224.138548) (xy 374.444837 -224.108116)
			(xy 374.490969 -224.08461) (xy 374.540209 -224.068611) (xy 374.591347 -224.060512) (xy 374.643121 -224.060512)
			(xy 374.694259 -224.068611) (xy 374.743499 -224.08461) (xy 374.789631 -224.108116) (xy 374.831518 -224.138548)
			(xy 374.868128 -224.175158) (xy 374.89856 -224.217045) (xy 374.922066 -224.263177) (xy 374.938065 -224.312417)
			(xy 374.946164 -224.363555) (xy 374.946672 -224.389442) (xy 374.946148 -224.417151) (xy 374.936958 -224.4718)
			(xy 374.928384 -224.498154) (xy 374.92051 -224.520252) (xy 375.125488 -224.87509) (xy 375.148348 -224.879408)
			(xy 375.182892 -224.888044) (xy 375.195998 -224.891574) (xy 375.223121 -224.892335) (xy 375.249486 -224.885926)
			(xy 375.273233 -224.872799) (xy 375.292683 -224.85388) (xy 375.306463 -224.830507) (xy 375.3136 -224.804329)
			(xy 375.313956 -224.790762) (xy 375.313956 -224.611946) (xy 375.2978 -224.593611) (xy 375.270518 -224.553068)
			(xy 375.249515 -224.508945) (xy 375.23525 -224.462207) (xy 375.228036 -224.413875) (xy 375.227596 -224.389442)
			(xy 375.228017 -224.365005) (xy 375.235199 -224.316663) (xy 375.249455 -224.269916) (xy 375.270472 -224.225793)
			(xy 375.297786 -224.185265) (xy 375.313956 -224.166938) (xy 375.313956 -222.982028) (xy 375.2963 -222.961759)
			(xy 375.267162 -222.916591) (xy 375.245776 -222.867278) (xy 375.232713 -222.815139) (xy 375.228323 -222.761567)
			(xy 375.232724 -222.707997) (xy 375.245797 -222.65586) (xy 375.267193 -222.606551) (xy 375.296339 -222.561389)
			(xy 375.313956 -222.541084) (xy 375.313956 -222.360236) (xy 375.313522 -222.346681) (xy 375.306373 -222.320531)
			(xy 375.292596 -222.297182) (xy 375.273162 -222.278281) (xy 375.24944 -222.265158) (xy 375.223101 -222.258739)
			(xy 375.196001 -222.259475) (xy 375.182892 -222.262954) (xy 375.159457 -222.269672) (xy 375.111254 -222.276948)
			(xy 375.08688 -222.277432) (xy 375.060973 -222.276923) (xy 375.009796 -222.268815) (xy 374.960517 -222.252802)
			(xy 374.91435 -222.229278) (xy 374.87243 -222.198823) (xy 374.83579 -222.162185) (xy 374.805332 -222.120267)
			(xy 374.781806 -222.074101) (xy 374.76579 -222.024824) (xy 374.757679 -221.973647) (xy 374.757188 -221.94774)
			(xy 374.75765 -221.922393) (xy 374.765408 -221.872295) (xy 374.780748 -221.823976) (xy 374.803307 -221.778577)
			(xy 374.832552 -221.737169) (xy 374.867795 -221.700729) (xy 374.908203 -221.670116) (xy 374.952823 -221.646053)
			(xy 375.000602 -221.629107) (xy 375.025412 -221.62389) (xy 375.048272 -221.619572) (xy 375.253504 -221.264226)
			(xy 375.24563 -221.242128) (xy 375.237167 -221.215884) (xy 375.228103 -221.161494) (xy 375.227596 -221.133924)
			(xy 375.228019 -221.109488) (xy 375.235203 -221.061147) (xy 375.249461 -221.014401) (xy 375.270479 -220.97028)
			(xy 375.297795 -220.929754) (xy 375.313956 -220.91142) (xy 375.313956 -219.72651) (xy 375.296293 -219.706241)
			(xy 375.267142 -219.661071) (xy 375.245743 -219.611753) (xy 375.232669 -219.559608) (xy 375.228268 -219.506028)
			(xy 375.23266 -219.452448) (xy 375.245725 -219.4003) (xy 375.267115 -219.350979) (xy 375.296259 -219.305804)
			(xy 375.313956 -219.285566) (xy 375.313956 -219.104718) (xy 375.313532 -219.091155) (xy 375.306396 -219.064986)
			(xy 375.292624 -219.041617) (xy 375.273186 -219.022698) (xy 375.249453 -219.009563) (xy 375.2231 -219.003139)
			(xy 375.195985 -219.003878) (xy 375.182892 -219.007436) (xy 375.159451 -219.0141) (xy 375.111246 -219.021246)
			(xy 375.08688 -219.02166) (xy 375.060987 -219.021151) (xy 375.009839 -219.013051) (xy 374.960587 -218.997052)
			(xy 374.914442 -218.97355) (xy 374.87254 -218.943121) (xy 374.835911 -218.906514) (xy 374.805456 -218.86463)
			(xy 374.781925 -218.8185) (xy 374.765897 -218.769257) (xy 374.757765 -218.718114) (xy 374.757188 -218.692222)
			(xy 374.757652 -218.666875) (xy 374.765412 -218.61678) (xy 374.780753 -218.568464) (xy 374.803313 -218.523067)
			(xy 374.832559 -218.481661) (xy 374.867802 -218.445223) (xy 374.908209 -218.414612) (xy 374.952828 -218.39055)
			(xy 375.000606 -218.373606) (xy 375.025412 -218.368372) (xy 375.048272 -218.364054) (xy 375.253504 -218.008708)
			(xy 375.24563 -217.98661) (xy 375.237169 -217.960365) (xy 375.228108 -217.905976) (xy 375.227596 -217.878406)
			(xy 375.22802 -217.85397) (xy 375.235206 -217.805631) (xy 375.249467 -217.758886) (xy 375.270486 -217.714767)
			(xy 375.297803 -217.674244) (xy 375.313956 -217.655902) (xy 375.313956 -216.470992) (xy 375.296294 -216.450723)
			(xy 375.267146 -216.405553) (xy 375.24575 -216.356237) (xy 375.232678 -216.304092) (xy 375.22828 -216.250515)
			(xy 375.232674 -216.196937) (xy 375.245741 -216.144791) (xy 375.267132 -216.095473) (xy 375.296276 -216.050301)
			(xy 375.313956 -216.030048) (xy 375.313956 -215.281256) (xy 375.314532 -215.256298) (xy 375.32428 -215.207342)
			(xy 375.343392 -215.161229) (xy 375.371135 -215.119732) (xy 375.388378 -215.101678) (xy 375.870978 -214.619078)
			(xy 375.88902 -214.60182) (xy 375.930514 -214.574066) (xy 375.976632 -214.554957) (xy 376.025595 -214.545231)
			(xy 376.050556 -214.544656) (xy 381.804418 -214.544656) (xy 381.810514 -214.500968) (xy 381.814651 -214.475175)
			(xy 381.830024 -214.425252) (xy 381.853107 -214.378394) (xy 381.883319 -214.335782) (xy 381.919897 -214.298491)
			(xy 381.961919 -214.267462) (xy 382.008323 -214.243478) (xy 382.057939 -214.227145) (xy 382.109516 -214.218874)
			(xy 382.161752 -214.218874) (xy 382.213329 -214.227145) (xy 382.262945 -214.243478) (xy 382.309349 -214.267462)
			(xy 382.351371 -214.298491) (xy 382.387949 -214.335782) (xy 382.418161 -214.378394) (xy 382.441244 -214.425252)
			(xy 382.456617 -214.475175) (xy 382.460754 -214.500968) (xy 382.46685 -214.544656) (xy 383.684018 -214.544656)
			(xy 383.690114 -214.500968) (xy 383.694251 -214.475175) (xy 383.709624 -214.425252) (xy 383.732707 -214.378394)
			(xy 383.762919 -214.335782) (xy 383.799497 -214.298491) (xy 383.841519 -214.267462) (xy 383.887923 -214.243478)
			(xy 383.937539 -214.227145) (xy 383.989116 -214.218874) (xy 384.041352 -214.218874) (xy 384.092929 -214.227145)
			(xy 384.142545 -214.243478) (xy 384.188949 -214.267462) (xy 384.230971 -214.298491) (xy 384.267549 -214.335782)
			(xy 384.297761 -214.378394) (xy 384.320844 -214.425252) (xy 384.336217 -214.475175) (xy 384.340354 -214.500968)
			(xy 384.34645 -214.544656) (xy 409.403296 -214.544656) (xy 409.966668 -213.981284) (xy 409.966668 -192.405762)
			(xy 409.943679 -192.392077) (xy 409.901423 -192.359266) (xy 409.864161 -192.320877) (xy 409.832624 -192.277661)
			(xy 409.80743 -192.230465) (xy 409.789072 -192.180213) (xy 409.77791 -192.127891) (xy 409.774163 -192.074523)
			(xy 409.777904 -192.021154) (xy 409.789059 -191.968831) (xy 409.807411 -191.918577) (xy 409.8326 -191.871378)
			(xy 409.864131 -191.828158) (xy 409.901388 -191.789764) (xy 409.943641 -191.756948) (xy 409.966668 -191.74333)
			(xy 409.966668 -168.08831) (xy 409.966414 -168.085008) (xy 409.964382 -168.05402) (xy 409.966414 -168.023032)
			(xy 409.966668 -168.01973) (xy 409.966668 -167.11295) (xy 409.637738 -166.78402) (xy 398.071086 -166.78402)
			(xy 363.553756 -201.30135) (xy 363.553756 -206.024988) (xy 380.650506 -206.024988) (xy 380.654487 -205.891968)
			(xy 380.666416 -205.759423) (xy 380.686251 -205.62783) (xy 380.71392 -205.497658) (xy 380.749324 -205.369373)
			(xy 380.792337 -205.243436) (xy 380.842804 -205.120297) (xy 380.900545 -205.000396) (xy 380.965354 -204.884163)
			(xy 381.036998 -204.772013) (xy 381.11522 -204.664349) (xy 381.199741 -204.561556) (xy 381.290259 -204.464001)
			(xy 381.386448 -204.372035) (xy 381.487966 -204.285985) (xy 381.594447 -204.206161) (xy 381.705512 -204.132848)
			(xy 381.820763 -204.066308) (xy 381.939787 -204.006779) (xy 382.062158 -203.954475) (xy 382.187437 -203.909583)
			(xy 382.315178 -203.872264) (xy 382.444921 -203.842651) (xy 382.576203 -203.82085) (xy 382.708554 -203.80694)
			(xy 382.8415 -203.800969) (xy 382.974565 -203.80296) (xy 383.107273 -203.812905) (xy 383.239149 -203.830769)
			(xy 383.36972 -203.856487) (xy 383.49852 -203.889968) (xy 383.625086 -203.931092) (xy 383.748967 -203.979712)
			(xy 383.869718 -204.035653) (xy 383.986908 -204.098715) (xy 384.100117 -204.168673) (xy 384.208939 -204.245277)
			(xy 384.312985 -204.328251) (xy 384.411883 -204.417299) (xy 384.505278 -204.512102) (xy 384.592836 -204.61232)
			(xy 384.674245 -204.717596) (xy 384.749211 -204.827552) (xy 384.817468 -204.941794) (xy 384.87877 -205.059914)
			(xy 384.932899 -205.181489) (xy 384.97966 -205.306083) (xy 385.018886 -205.433251) (xy 385.050436 -205.562537)
			(xy 385.074199 -205.693478) (xy 385.090088 -205.825606) (xy 385.098046 -205.958448) (xy 385.098544 -206.024988)
			(xy 385.098046 -206.091528) (xy 385.090088 -206.22437) (xy 385.074199 -206.356498) (xy 385.050436 -206.487439)
			(xy 385.018886 -206.616725) (xy 384.97966 -206.743893) (xy 384.932899 -206.868487) (xy 384.87877 -206.990062)
			(xy 384.817468 -207.108182) (xy 384.749211 -207.222424) (xy 384.674245 -207.33238) (xy 384.592836 -207.437656)
			(xy 384.505278 -207.537874) (xy 384.411883 -207.632677) (xy 384.312985 -207.721725) (xy 384.208939 -207.804699)
			(xy 384.100117 -207.881303) (xy 383.986908 -207.951261) (xy 383.869718 -208.014323) (xy 383.748967 -208.070264)
			(xy 383.625086 -208.118884) (xy 383.49852 -208.160008) (xy 383.36972 -208.193489) (xy 383.239149 -208.219207)
			(xy 383.107273 -208.237071) (xy 382.974565 -208.247016) (xy 382.8415 -208.249007) (xy 382.708554 -208.243036)
			(xy 382.576203 -208.229126) (xy 382.444921 -208.207325) (xy 382.315178 -208.177712) (xy 382.187437 -208.140393)
			(xy 382.062158 -208.095501) (xy 381.939787 -208.043197) (xy 381.820763 -207.983668) (xy 381.705512 -207.917128)
			(xy 381.594447 -207.843815) (xy 381.487966 -207.763991) (xy 381.386448 -207.677941) (xy 381.290259 -207.585975)
			(xy 381.199741 -207.48842) (xy 381.11522 -207.385627) (xy 381.036998 -207.277963) (xy 380.965354 -207.165813)
			(xy 380.900545 -207.04958) (xy 380.842804 -206.929679) (xy 380.792337 -206.80654) (xy 380.749324 -206.680603)
			(xy 380.71392 -206.552318) (xy 380.686251 -206.422146) (xy 380.666416 -206.290553) (xy 380.654487 -206.158008)
			(xy 380.650506 -206.024988) (xy 363.553756 -206.024988) (xy 363.553756 -216.002108) (xy 363.572838 -216.019227)
			(xy 363.605965 -216.058346) (xy 363.632606 -216.102141) (xy 363.652112 -216.149546) (xy 363.664007 -216.199408)
			(xy 363.668004 -216.250513) (xy 363.664003 -216.301618) (xy 363.652104 -216.351479) (xy 363.632594 -216.398883)
			(xy 363.60595 -216.442675) (xy 363.572819 -216.481792) (xy 363.553756 -216.498932) (xy 363.553756 -217.064336)
			(xy 364.419388 -217.064336) (xy 364.419896 -217.038429) (xy 364.428002 -216.987252) (xy 364.444014 -216.937973)
			(xy 364.467537 -216.891806) (xy 364.497993 -216.849887) (xy 364.534631 -216.813249) (xy 364.57655 -216.782793)
			(xy 364.622717 -216.75927) (xy 364.671996 -216.743258) (xy 364.723173 -216.735152) (xy 364.774987 -216.735152)
			(xy 364.826164 -216.743258) (xy 364.875443 -216.75927) (xy 364.92161 -216.782793) (xy 364.963529 -216.813249)
			(xy 365.000167 -216.849887) (xy 365.030623 -216.891806) (xy 365.054146 -216.937973) (xy 365.070158 -216.987252)
			(xy 365.078264 -217.038429) (xy 365.078772 -217.064336) (xy 366.298988 -217.064336) (xy 366.299496 -217.038429)
			(xy 366.307602 -216.987252) (xy 366.323614 -216.937973) (xy 366.347137 -216.891806) (xy 366.377593 -216.849887)
			(xy 366.414231 -216.813249) (xy 366.45615 -216.782793) (xy 366.502317 -216.75927) (xy 366.551596 -216.743258)
			(xy 366.602773 -216.735152) (xy 366.654587 -216.735152) (xy 366.705764 -216.743258) (xy 366.755043 -216.75927)
			(xy 366.80121 -216.782793) (xy 366.843129 -216.813249) (xy 366.879767 -216.849887) (xy 366.910223 -216.891806)
			(xy 366.933746 -216.937973) (xy 366.949758 -216.987252) (xy 366.957864 -217.038429) (xy 366.958372 -217.064336)
			(xy 368.178588 -217.064336) (xy 368.179096 -217.038429) (xy 368.187202 -216.987252) (xy 368.203214 -216.937973)
			(xy 368.226737 -216.891806) (xy 368.257193 -216.849887) (xy 368.293831 -216.813249) (xy 368.33575 -216.782793)
			(xy 368.381917 -216.75927) (xy 368.431196 -216.743258) (xy 368.482373 -216.735152) (xy 368.534187 -216.735152)
			(xy 368.585364 -216.743258) (xy 368.634643 -216.75927) (xy 368.68081 -216.782793) (xy 368.722729 -216.813249)
			(xy 368.759367 -216.849887) (xy 368.789823 -216.891806) (xy 368.813346 -216.937973) (xy 368.829358 -216.987252)
			(xy 368.837464 -217.038429) (xy 368.837972 -217.064336) (xy 370.058188 -217.064336) (xy 370.058696 -217.038429)
			(xy 370.066802 -216.987252) (xy 370.082814 -216.937973) (xy 370.106337 -216.891806) (xy 370.136793 -216.849887)
			(xy 370.173431 -216.813249) (xy 370.21535 -216.782793) (xy 370.261517 -216.75927) (xy 370.310796 -216.743258)
			(xy 370.361973 -216.735152) (xy 370.413787 -216.735152) (xy 370.464964 -216.743258) (xy 370.514243 -216.75927)
			(xy 370.56041 -216.782793) (xy 370.602329 -216.813249) (xy 370.638967 -216.849887) (xy 370.669423 -216.891806)
			(xy 370.692946 -216.937973) (xy 370.708958 -216.987252) (xy 370.717064 -217.038429) (xy 370.717572 -217.064336)
			(xy 371.937788 -217.064336) (xy 371.938296 -217.038429) (xy 371.946402 -216.987252) (xy 371.962414 -216.937973)
			(xy 371.985937 -216.891806) (xy 372.016393 -216.849887) (xy 372.053031 -216.813249) (xy 372.09495 -216.782793)
			(xy 372.141117 -216.75927) (xy 372.190396 -216.743258) (xy 372.241573 -216.735152) (xy 372.293387 -216.735152)
			(xy 372.344564 -216.743258) (xy 372.393843 -216.75927) (xy 372.44001 -216.782793) (xy 372.481929 -216.813249)
			(xy 372.518567 -216.849887) (xy 372.549023 -216.891806) (xy 372.572546 -216.937973) (xy 372.588558 -216.987252)
			(xy 372.596664 -217.038429) (xy 372.597172 -217.064336) (xy 373.817388 -217.064336) (xy 373.817896 -217.038429)
			(xy 373.826002 -216.987252) (xy 373.842014 -216.937973) (xy 373.865537 -216.891806) (xy 373.895993 -216.849887)
			(xy 373.932631 -216.813249) (xy 373.97455 -216.782793) (xy 374.020717 -216.75927) (xy 374.069996 -216.743258)
			(xy 374.121173 -216.735152) (xy 374.172987 -216.735152) (xy 374.224164 -216.743258) (xy 374.273443 -216.75927)
			(xy 374.31961 -216.782793) (xy 374.361529 -216.813249) (xy 374.398167 -216.849887) (xy 374.428623 -216.891806)
			(xy 374.452146 -216.937973) (xy 374.468158 -216.987252) (xy 374.476264 -217.038429) (xy 374.476772 -217.064336)
			(xy 374.476159 -217.091989) (xy 374.466838 -217.146507) (xy 374.45823 -217.172794) (xy 374.45061 -217.194892)
			(xy 374.655842 -217.550238) (xy 374.678702 -217.554556) (xy 374.703503 -217.559751) (xy 374.751242 -217.57674)
			(xy 374.795819 -217.600833) (xy 374.836184 -217.631463) (xy 374.871388 -217.667908) (xy 374.9006 -217.709312)
			(xy 374.923133 -217.754697) (xy 374.938456 -217.802996) (xy 374.946208 -217.85307) (xy 374.946672 -217.878406)
			(xy 374.946164 -217.904293) (xy 374.938065 -217.955431) (xy 374.922066 -218.004671) (xy 374.89856 -218.050803)
			(xy 374.868128 -218.09269) (xy 374.831518 -218.1293) (xy 374.789631 -218.159732) (xy 374.743499 -218.183238)
			(xy 374.694259 -218.199237) (xy 374.643121 -218.207336) (xy 374.591347 -218.207336) (xy 374.540209 -218.199237)
			(xy 374.490969 -218.183238) (xy 374.444837 -218.159732) (xy 374.40295 -218.1293) (xy 374.36634 -218.09269)
			(xy 374.335908 -218.050803) (xy 374.312402 -218.004671) (xy 374.296403 -217.955431) (xy 374.288304 -217.904293)
			(xy 374.287796 -217.878406) (xy 374.288327 -217.850698) (xy 374.297521 -217.796051) (xy 374.306084 -217.769694)
			(xy 374.313958 -217.747596) (xy 374.10898 -217.392504) (xy 374.08612 -217.388186) (xy 374.061275 -217.38302)
			(xy 374.013426 -217.366126) (xy 373.968733 -217.342096) (xy 373.928253 -217.311499) (xy 373.892941 -217.275058)
			(xy 373.863633 -217.233634) (xy 373.841022 -217.188207) (xy 373.825643 -217.13985) (xy 373.817858 -217.089708)
			(xy 373.817388 -217.064336) (xy 372.597172 -217.064336) (xy 372.596559 -217.091989) (xy 372.587238 -217.146507)
			(xy 372.57863 -217.172794) (xy 372.57101 -217.194892) (xy 372.776242 -217.550238) (xy 372.799102 -217.554556)
			(xy 372.823903 -217.559751) (xy 372.871642 -217.57674) (xy 372.916219 -217.600833) (xy 372.956584 -217.631463)
			(xy 372.991788 -217.667908) (xy 373.021 -217.709312) (xy 373.043533 -217.754697) (xy 373.058856 -217.802996)
			(xy 373.066608 -217.85307) (xy 373.067072 -217.878406) (xy 373.066564 -217.904293) (xy 373.058465 -217.955431)
			(xy 373.042466 -218.004671) (xy 373.01896 -218.050803) (xy 372.988528 -218.09269) (xy 372.951918 -218.1293)
			(xy 372.910031 -218.159732) (xy 372.863899 -218.183238) (xy 372.814659 -218.199237) (xy 372.763521 -218.207336)
			(xy 372.711747 -218.207336) (xy 372.660609 -218.199237) (xy 372.611369 -218.183238) (xy 372.565237 -218.159732)
			(xy 372.52335 -218.1293) (xy 372.48674 -218.09269) (xy 372.456308 -218.050803) (xy 372.432802 -218.004671)
			(xy 372.416803 -217.955431) (xy 372.408704 -217.904293) (xy 372.408196 -217.878406) (xy 372.408727 -217.850698)
			(xy 372.417921 -217.796051) (xy 372.426484 -217.769694) (xy 372.434358 -217.747596) (xy 372.22938 -217.392504)
			(xy 372.20652 -217.388186) (xy 372.181675 -217.38302) (xy 372.133826 -217.366126) (xy 372.089133 -217.342096)
			(xy 372.048653 -217.311499) (xy 372.013341 -217.275058) (xy 371.984033 -217.233634) (xy 371.961422 -217.188207)
			(xy 371.946043 -217.13985) (xy 371.938258 -217.089708) (xy 371.937788 -217.064336) (xy 370.717572 -217.064336)
			(xy 370.716959 -217.091989) (xy 370.707638 -217.146507) (xy 370.69903 -217.172794) (xy 370.69141 -217.194892)
			(xy 370.896642 -217.550238) (xy 370.919502 -217.554556) (xy 370.944303 -217.559751) (xy 370.992042 -217.57674)
			(xy 371.036619 -217.600833) (xy 371.076984 -217.631463) (xy 371.112188 -217.667908) (xy 371.1414 -217.709312)
			(xy 371.163933 -217.754697) (xy 371.179256 -217.802996) (xy 371.187008 -217.85307) (xy 371.187472 -217.878406)
			(xy 371.186964 -217.904293) (xy 371.178865 -217.955431) (xy 371.162866 -218.004671) (xy 371.13936 -218.050803)
			(xy 371.108928 -218.09269) (xy 371.072318 -218.1293) (xy 371.030431 -218.159732) (xy 370.984299 -218.183238)
			(xy 370.935059 -218.199237) (xy 370.883921 -218.207336) (xy 370.832147 -218.207336) (xy 370.781009 -218.199237)
			(xy 370.731769 -218.183238) (xy 370.685637 -218.159732) (xy 370.64375 -218.1293) (xy 370.60714 -218.09269)
			(xy 370.576708 -218.050803) (xy 370.553202 -218.004671) (xy 370.537203 -217.955431) (xy 370.529104 -217.904293)
			(xy 370.528596 -217.878406) (xy 370.529127 -217.850698) (xy 370.538321 -217.796051) (xy 370.546884 -217.769694)
			(xy 370.554758 -217.747596) (xy 370.34978 -217.392504) (xy 370.32692 -217.388186) (xy 370.302075 -217.38302)
			(xy 370.254226 -217.366126) (xy 370.209533 -217.342096) (xy 370.169053 -217.311499) (xy 370.133741 -217.275058)
			(xy 370.104433 -217.233634) (xy 370.081822 -217.188207) (xy 370.066443 -217.13985) (xy 370.058658 -217.089708)
			(xy 370.058188 -217.064336) (xy 368.837972 -217.064336) (xy 368.837359 -217.091989) (xy 368.828038 -217.146507)
			(xy 368.81943 -217.172794) (xy 368.81181 -217.194892) (xy 369.017042 -217.550238) (xy 369.039902 -217.554556)
			(xy 369.064703 -217.559751) (xy 369.112442 -217.57674) (xy 369.157019 -217.600833) (xy 369.197384 -217.631463)
			(xy 369.232588 -217.667908) (xy 369.2618 -217.709312) (xy 369.284333 -217.754697) (xy 369.299656 -217.802996)
			(xy 369.307408 -217.85307) (xy 369.307872 -217.878406) (xy 369.307364 -217.904293) (xy 369.299265 -217.955431)
			(xy 369.283266 -218.004671) (xy 369.25976 -218.050803) (xy 369.229328 -218.09269) (xy 369.192718 -218.1293)
			(xy 369.150831 -218.159732) (xy 369.104699 -218.183238) (xy 369.055459 -218.199237) (xy 369.004321 -218.207336)
			(xy 368.952547 -218.207336) (xy 368.901409 -218.199237) (xy 368.852169 -218.183238) (xy 368.806037 -218.159732)
			(xy 368.76415 -218.1293) (xy 368.72754 -218.09269) (xy 368.697108 -218.050803) (xy 368.673602 -218.004671)
			(xy 368.657603 -217.955431) (xy 368.649504 -217.904293) (xy 368.648996 -217.878406) (xy 368.649527 -217.850698)
			(xy 368.658721 -217.796051) (xy 368.667284 -217.769694) (xy 368.675158 -217.747596) (xy 368.47018 -217.392504)
			(xy 368.44732 -217.388186) (xy 368.422475 -217.38302) (xy 368.374626 -217.366126) (xy 368.329933 -217.342096)
			(xy 368.289453 -217.311499) (xy 368.254141 -217.275058) (xy 368.224833 -217.233634) (xy 368.202222 -217.188207)
			(xy 368.186843 -217.13985) (xy 368.179058 -217.089708) (xy 368.178588 -217.064336) (xy 366.958372 -217.064336)
			(xy 366.957759 -217.091989) (xy 366.948438 -217.146507) (xy 366.93983 -217.172794) (xy 366.93221 -217.194892)
			(xy 367.137442 -217.550238) (xy 367.160302 -217.554556) (xy 367.185103 -217.559751) (xy 367.232842 -217.57674)
			(xy 367.277419 -217.600833) (xy 367.317784 -217.631463) (xy 367.352988 -217.667908) (xy 367.3822 -217.709312)
			(xy 367.404733 -217.754697) (xy 367.420056 -217.802996) (xy 367.427808 -217.85307) (xy 367.428272 -217.878406)
			(xy 367.427764 -217.904293) (xy 367.419665 -217.955431) (xy 367.403666 -218.004671) (xy 367.38016 -218.050803)
			(xy 367.349728 -218.09269) (xy 367.313118 -218.1293) (xy 367.271231 -218.159732) (xy 367.225099 -218.183238)
			(xy 367.175859 -218.199237) (xy 367.124721 -218.207336) (xy 367.072947 -218.207336) (xy 367.021809 -218.199237)
			(xy 366.972569 -218.183238) (xy 366.926437 -218.159732) (xy 366.88455 -218.1293) (xy 366.84794 -218.09269)
			(xy 366.817508 -218.050803) (xy 366.794002 -218.004671) (xy 366.778003 -217.955431) (xy 366.769904 -217.904293)
			(xy 366.769396 -217.878406) (xy 366.769927 -217.850698) (xy 366.779121 -217.796051) (xy 366.787684 -217.769694)
			(xy 366.795558 -217.747596) (xy 366.59058 -217.392504) (xy 366.56772 -217.388186) (xy 366.542875 -217.38302)
			(xy 366.495026 -217.366126) (xy 366.450333 -217.342096) (xy 366.409853 -217.311499) (xy 366.374541 -217.275058)
			(xy 366.345233 -217.233634) (xy 366.322622 -217.188207) (xy 366.307243 -217.13985) (xy 366.299458 -217.089708)
			(xy 366.298988 -217.064336) (xy 365.078772 -217.064336) (xy 365.078159 -217.091989) (xy 365.068838 -217.146507)
			(xy 365.06023 -217.172794) (xy 365.05261 -217.194892) (xy 365.257842 -217.550238) (xy 365.280702 -217.554556)
			(xy 365.305503 -217.559751) (xy 365.353242 -217.57674) (xy 365.397819 -217.600833) (xy 365.438184 -217.631463)
			(xy 365.473388 -217.667908) (xy 365.5026 -217.709312) (xy 365.525133 -217.754697) (xy 365.540456 -217.802996)
			(xy 365.548208 -217.85307) (xy 365.548672 -217.878406) (xy 365.548164 -217.904293) (xy 365.540065 -217.955431)
			(xy 365.524066 -218.004671) (xy 365.50056 -218.050803) (xy 365.470128 -218.09269) (xy 365.433518 -218.1293)
			(xy 365.391631 -218.159732) (xy 365.345499 -218.183238) (xy 365.296259 -218.199237) (xy 365.245121 -218.207336)
			(xy 365.193347 -218.207336) (xy 365.142209 -218.199237) (xy 365.092969 -218.183238) (xy 365.046837 -218.159732)
			(xy 365.00495 -218.1293) (xy 364.96834 -218.09269) (xy 364.937908 -218.050803) (xy 364.914402 -218.004671)
			(xy 364.898403 -217.955431) (xy 364.890304 -217.904293) (xy 364.889796 -217.878406) (xy 364.890327 -217.850698)
			(xy 364.899521 -217.796051) (xy 364.908084 -217.769694) (xy 364.915958 -217.747596) (xy 364.71098 -217.392504)
			(xy 364.68812 -217.388186) (xy 364.663275 -217.38302) (xy 364.615426 -217.366126) (xy 364.570733 -217.342096)
			(xy 364.530253 -217.311499) (xy 364.494941 -217.275058) (xy 364.465633 -217.233634) (xy 364.443022 -217.188207)
			(xy 364.427643 -217.13985) (xy 364.419858 -217.089708) (xy 364.419388 -217.064336) (xy 363.553756 -217.064336)
			(xy 363.553756 -217.627962) (xy 363.573083 -217.64517) (xy 363.606654 -217.684546) (xy 363.63366 -217.728684)
			(xy 363.653439 -217.7765) (xy 363.665503 -217.826818) (xy 363.669557 -217.878404) (xy 363.665502 -217.929989)
			(xy 363.653436 -217.980308) (xy 363.633657 -218.028123) (xy 363.606649 -218.07226) (xy 363.573077 -218.111636)
			(xy 363.553756 -218.12885) (xy 363.553756 -218.289378) (xy 363.554218 -218.303458) (xy 363.561919 -218.330544)
			(xy 363.576715 -218.354503) (xy 363.597485 -218.373519) (xy 363.622654 -218.386149) (xy 363.650313 -218.391435)
			(xy 363.678365 -218.388978) (xy 363.691678 -218.384374) (xy 363.705378 -218.379283) (xy 363.733488 -218.371273)
			(xy 363.747812 -218.368372) (xy 363.770672 -218.364054) (xy 363.975904 -218.008708) (xy 363.96803 -217.98661)
			(xy 363.959569 -217.960365) (xy 363.950508 -217.905976) (xy 363.949996 -217.878406) (xy 363.950504 -217.852519)
			(xy 363.958603 -217.801381) (xy 363.974602 -217.752141) (xy 363.998108 -217.706009) (xy 364.02854 -217.664122)
			(xy 364.06515 -217.627512) (xy 364.107037 -217.59708) (xy 364.153169 -217.573574) (xy 364.202409 -217.557575)
			(xy 364.253547 -217.549476) (xy 364.305321 -217.549476) (xy 364.356459 -217.557575) (xy 364.405699 -217.573574)
			(xy 364.451831 -217.59708) (xy 364.493718 -217.627512) (xy 364.530328 -217.664122) (xy 364.56076 -217.706009)
			(xy 364.584266 -217.752141) (xy 364.600265 -217.801381) (xy 364.608364 -217.852519) (xy 364.608872 -217.878406)
			(xy 364.608404 -217.90378) (xy 364.600624 -217.953929) (xy 364.585248 -218.002293) (xy 364.562641 -218.047728)
			(xy 364.533336 -218.08916) (xy 364.498026 -218.12561) (xy 364.457545 -218.156217) (xy 364.412852 -218.180257)
			(xy 364.365001 -218.197162) (xy 364.34014 -218.202256) (xy 364.31728 -218.206574) (xy 364.112556 -218.561412)
			(xy 364.12043 -218.583256) (xy 364.129075 -218.609664) (xy 364.138395 -218.66444) (xy 364.138972 -218.692222)
			(xy 365.359188 -218.692222) (xy 365.359739 -218.66688) (xy 365.367507 -218.616793) (xy 365.382848 -218.568485)
			(xy 365.405401 -218.523094) (xy 365.434634 -218.481689) (xy 365.469859 -218.445245) (xy 365.510246 -218.41462)
			(xy 365.554844 -218.390537) (xy 365.602602 -218.373561) (xy 365.627412 -218.368372) (xy 365.650272 -218.364054)
			(xy 365.855504 -218.008708) (xy 365.84763 -217.98661) (xy 365.839161 -217.960367) (xy 365.830092 -217.905977)
			(xy 365.829596 -217.878406) (xy 365.830104 -217.852519) (xy 365.838203 -217.801381) (xy 365.854202 -217.752141)
			(xy 365.877708 -217.706009) (xy 365.90814 -217.664122) (xy 365.94475 -217.627512) (xy 365.986637 -217.59708)
			(xy 366.032769 -217.573574) (xy 366.082009 -217.557575) (xy 366.133147 -217.549476) (xy 366.184921 -217.549476)
			(xy 366.236059 -217.557575) (xy 366.285299 -217.573574) (xy 366.331431 -217.59708) (xy 366.373318 -217.627512)
			(xy 366.409928 -217.664122) (xy 366.44036 -217.706009) (xy 366.463866 -217.752141) (xy 366.479865 -217.801381)
			(xy 366.487964 -217.852519) (xy 366.488472 -217.878406) (xy 366.488025 -217.903782) (xy 366.480255 -217.953934)
			(xy 366.464885 -218.002302) (xy 366.442277 -218.047739) (xy 366.412967 -218.089171) (xy 366.37765 -218.125617)
			(xy 366.33716 -218.156215) (xy 366.292456 -218.18024) (xy 366.244596 -218.197124) (xy 366.21974 -218.202256)
			(xy 366.19688 -218.206574) (xy 365.992156 -218.561412) (xy 366.00003 -218.583256) (xy 366.008681 -218.609663)
			(xy 366.017998 -218.66444) (xy 366.018572 -218.692222) (xy 367.238788 -218.692222) (xy 367.239339 -218.66688)
			(xy 367.247107 -218.616793) (xy 367.262448 -218.568485) (xy 367.285001 -218.523094) (xy 367.314234 -218.481689)
			(xy 367.349459 -218.445245) (xy 367.389846 -218.41462) (xy 367.434444 -218.390537) (xy 367.482202 -218.373561)
			(xy 367.507012 -218.368372) (xy 367.529872 -218.364054) (xy 367.735104 -218.008708) (xy 367.72723 -217.98661)
			(xy 367.718761 -217.960367) (xy 367.709692 -217.905977) (xy 367.709196 -217.878406) (xy 367.709704 -217.852519)
			(xy 367.717803 -217.801381) (xy 367.733802 -217.752141) (xy 367.757308 -217.706009) (xy 367.78774 -217.664122)
			(xy 367.82435 -217.627512) (xy 367.866237 -217.59708) (xy 367.912369 -217.573574) (xy 367.961609 -217.557575)
			(xy 368.012747 -217.549476) (xy 368.064521 -217.549476) (xy 368.115659 -217.557575) (xy 368.164899 -217.573574)
			(xy 368.211031 -217.59708) (xy 368.252918 -217.627512) (xy 368.289528 -217.664122) (xy 368.31996 -217.706009)
			(xy 368.343466 -217.752141) (xy 368.359465 -217.801381) (xy 368.367564 -217.852519) (xy 368.368072 -217.878406)
			(xy 368.367625 -217.903782) (xy 368.359855 -217.953934) (xy 368.344485 -218.002302) (xy 368.321877 -218.047739)
			(xy 368.292567 -218.089171) (xy 368.25725 -218.125617) (xy 368.21676 -218.156215) (xy 368.172056 -218.18024)
			(xy 368.124196 -218.197124) (xy 368.09934 -218.202256) (xy 368.07648 -218.206574) (xy 367.871756 -218.561412)
			(xy 367.87963 -218.583256) (xy 367.888281 -218.609663) (xy 367.897598 -218.66444) (xy 367.898172 -218.692222)
			(xy 369.118388 -218.692222) (xy 369.118939 -218.66688) (xy 369.126707 -218.616793) (xy 369.142048 -218.568485)
			(xy 369.164601 -218.523094) (xy 369.193834 -218.481689) (xy 369.229059 -218.445245) (xy 369.269446 -218.41462)
			(xy 369.314044 -218.390537) (xy 369.361802 -218.373561) (xy 369.386612 -218.368372) (xy 369.409472 -218.364054)
			(xy 369.614704 -218.008708) (xy 369.60683 -217.98661) (xy 369.598361 -217.960367) (xy 369.589292 -217.905977)
			(xy 369.588796 -217.878406) (xy 369.589304 -217.852519) (xy 369.597403 -217.801381) (xy 369.613402 -217.752141)
			(xy 369.636908 -217.706009) (xy 369.66734 -217.664122) (xy 369.70395 -217.627512) (xy 369.745837 -217.59708)
			(xy 369.791969 -217.573574) (xy 369.841209 -217.557575) (xy 369.892347 -217.549476) (xy 369.944121 -217.549476)
			(xy 369.995259 -217.557575) (xy 370.044499 -217.573574) (xy 370.090631 -217.59708) (xy 370.132518 -217.627512)
			(xy 370.169128 -217.664122) (xy 370.19956 -217.706009) (xy 370.223066 -217.752141) (xy 370.239065 -217.801381)
			(xy 370.247164 -217.852519) (xy 370.247672 -217.878406) (xy 370.247225 -217.903782) (xy 370.239455 -217.953934)
			(xy 370.224085 -218.002302) (xy 370.201477 -218.047739) (xy 370.172167 -218.089171) (xy 370.13685 -218.125617)
			(xy 370.09636 -218.156215) (xy 370.051656 -218.18024) (xy 370.003796 -218.197124) (xy 369.97894 -218.202256)
			(xy 369.95608 -218.206574) (xy 369.751356 -218.561412) (xy 369.75923 -218.583256) (xy 369.767881 -218.609663)
			(xy 369.777198 -218.66444) (xy 369.777772 -218.692222) (xy 370.997988 -218.692222) (xy 370.998539 -218.66688)
			(xy 371.006307 -218.616793) (xy 371.021648 -218.568485) (xy 371.044201 -218.523094) (xy 371.073434 -218.481689)
			(xy 371.108659 -218.445245) (xy 371.149046 -218.41462) (xy 371.193644 -218.390537) (xy 371.241402 -218.373561)
			(xy 371.266212 -218.368372) (xy 371.289072 -218.364054) (xy 371.494304 -218.008708) (xy 371.48643 -217.98661)
			(xy 371.477961 -217.960367) (xy 371.468892 -217.905977) (xy 371.468396 -217.878406) (xy 371.468904 -217.852519)
			(xy 371.477003 -217.801381) (xy 371.493002 -217.752141) (xy 371.516508 -217.706009) (xy 371.54694 -217.664122)
			(xy 371.58355 -217.627512) (xy 371.625437 -217.59708) (xy 371.671569 -217.573574) (xy 371.720809 -217.557575)
			(xy 371.771947 -217.549476) (xy 371.823721 -217.549476) (xy 371.874859 -217.557575) (xy 371.924099 -217.573574)
			(xy 371.970231 -217.59708) (xy 372.012118 -217.627512) (xy 372.048728 -217.664122) (xy 372.07916 -217.706009)
			(xy 372.102666 -217.752141) (xy 372.118665 -217.801381) (xy 372.126764 -217.852519) (xy 372.127272 -217.878406)
			(xy 372.126825 -217.903782) (xy 372.119055 -217.953934) (xy 372.103685 -218.002302) (xy 372.081077 -218.047739)
			(xy 372.051767 -218.089171) (xy 372.01645 -218.125617) (xy 371.97596 -218.156215) (xy 371.931256 -218.18024)
			(xy 371.883396 -218.197124) (xy 371.85854 -218.202256) (xy 371.83568 -218.206574) (xy 371.630956 -218.561412)
			(xy 371.63883 -218.583256) (xy 371.647481 -218.609663) (xy 371.656798 -218.66444) (xy 371.657372 -218.692222)
			(xy 372.877588 -218.692222) (xy 372.878139 -218.66688) (xy 372.885907 -218.616793) (xy 372.901248 -218.568485)
			(xy 372.923801 -218.523094) (xy 372.953034 -218.481689) (xy 372.988259 -218.445245) (xy 373.028646 -218.41462)
			(xy 373.073244 -218.390537) (xy 373.121002 -218.373561) (xy 373.145812 -218.368372) (xy 373.168672 -218.364054)
			(xy 373.373904 -218.008708) (xy 373.36603 -217.98661) (xy 373.357561 -217.960367) (xy 373.348492 -217.905977)
			(xy 373.347996 -217.878406) (xy 373.348504 -217.852519) (xy 373.356603 -217.801381) (xy 373.372602 -217.752141)
			(xy 373.396108 -217.706009) (xy 373.42654 -217.664122) (xy 373.46315 -217.627512) (xy 373.505037 -217.59708)
			(xy 373.551169 -217.573574) (xy 373.600409 -217.557575) (xy 373.651547 -217.549476) (xy 373.703321 -217.549476)
			(xy 373.754459 -217.557575) (xy 373.803699 -217.573574) (xy 373.849831 -217.59708) (xy 373.891718 -217.627512)
			(xy 373.928328 -217.664122) (xy 373.95876 -217.706009) (xy 373.982266 -217.752141) (xy 373.998265 -217.801381)
			(xy 374.006364 -217.852519) (xy 374.006872 -217.878406) (xy 374.006425 -217.903782) (xy 373.998655 -217.953934)
			(xy 373.983285 -218.002302) (xy 373.960677 -218.047739) (xy 373.931367 -218.089171) (xy 373.89605 -218.125617)
			(xy 373.85556 -218.156215) (xy 373.810856 -218.18024) (xy 373.762996 -218.197124) (xy 373.73814 -218.202256)
			(xy 373.71528 -218.206574) (xy 373.510556 -218.561412) (xy 373.51843 -218.583256) (xy 373.527081 -218.609663)
			(xy 373.536398 -218.66444) (xy 373.536972 -218.692222) (xy 373.536464 -218.718129) (xy 373.528358 -218.769306)
			(xy 373.512346 -218.818585) (xy 373.488823 -218.864752) (xy 373.458367 -218.906671) (xy 373.421729 -218.943309)
			(xy 373.37981 -218.973765) (xy 373.333643 -218.997288) (xy 373.284364 -219.0133) (xy 373.233187 -219.021406)
			(xy 373.181373 -219.021406) (xy 373.130196 -219.0133) (xy 373.080917 -218.997288) (xy 373.03475 -218.973765)
			(xy 372.992831 -218.943309) (xy 372.956193 -218.906671) (xy 372.925737 -218.864752) (xy 372.902214 -218.818585)
			(xy 372.886202 -218.769306) (xy 372.878096 -218.718129) (xy 372.877588 -218.692222) (xy 371.657372 -218.692222)
			(xy 371.656864 -218.718129) (xy 371.648758 -218.769306) (xy 371.632746 -218.818585) (xy 371.609223 -218.864752)
			(xy 371.578767 -218.906671) (xy 371.542129 -218.943309) (xy 371.50021 -218.973765) (xy 371.454043 -218.997288)
			(xy 371.404764 -219.0133) (xy 371.353587 -219.021406) (xy 371.301773 -219.021406) (xy 371.250596 -219.0133)
			(xy 371.201317 -218.997288) (xy 371.15515 -218.973765) (xy 371.113231 -218.943309) (xy 371.076593 -218.906671)
			(xy 371.046137 -218.864752) (xy 371.022614 -218.818585) (xy 371.006602 -218.769306) (xy 370.998496 -218.718129)
			(xy 370.997988 -218.692222) (xy 369.777772 -218.692222) (xy 369.777264 -218.718129) (xy 369.769158 -218.769306)
			(xy 369.753146 -218.818585) (xy 369.729623 -218.864752) (xy 369.699167 -218.906671) (xy 369.662529 -218.943309)
			(xy 369.62061 -218.973765) (xy 369.574443 -218.997288) (xy 369.525164 -219.0133) (xy 369.473987 -219.021406)
			(xy 369.422173 -219.021406) (xy 369.370996 -219.0133) (xy 369.321717 -218.997288) (xy 369.27555 -218.973765)
			(xy 369.233631 -218.943309) (xy 369.196993 -218.906671) (xy 369.166537 -218.864752) (xy 369.143014 -218.818585)
			(xy 369.127002 -218.769306) (xy 369.118896 -218.718129) (xy 369.118388 -218.692222) (xy 367.898172 -218.692222)
			(xy 367.897664 -218.718129) (xy 367.889558 -218.769306) (xy 367.873546 -218.818585) (xy 367.850023 -218.864752)
			(xy 367.819567 -218.906671) (xy 367.782929 -218.943309) (xy 367.74101 -218.973765) (xy 367.694843 -218.997288)
			(xy 367.645564 -219.0133) (xy 367.594387 -219.021406) (xy 367.542573 -219.021406) (xy 367.491396 -219.0133)
			(xy 367.442117 -218.997288) (xy 367.39595 -218.973765) (xy 367.354031 -218.943309) (xy 367.317393 -218.906671)
			(xy 367.286937 -218.864752) (xy 367.263414 -218.818585) (xy 367.247402 -218.769306) (xy 367.239296 -218.718129)
			(xy 367.238788 -218.692222) (xy 366.018572 -218.692222) (xy 366.018064 -218.718129) (xy 366.009958 -218.769306)
			(xy 365.993946 -218.818585) (xy 365.970423 -218.864752) (xy 365.939967 -218.906671) (xy 365.903329 -218.943309)
			(xy 365.86141 -218.973765) (xy 365.815243 -218.997288) (xy 365.765964 -219.0133) (xy 365.714787 -219.021406)
			(xy 365.662973 -219.021406) (xy 365.611796 -219.0133) (xy 365.562517 -218.997288) (xy 365.51635 -218.973765)
			(xy 365.474431 -218.943309) (xy 365.437793 -218.906671) (xy 365.407337 -218.864752) (xy 365.383814 -218.818585)
			(xy 365.367802 -218.769306) (xy 365.359696 -218.718129) (xy 365.359188 -218.692222) (xy 364.138972 -218.692222)
			(xy 364.138488 -218.718124) (xy 364.130378 -218.769289) (xy 364.11436 -218.818555) (xy 364.09083 -218.864707)
			(xy 364.060368 -218.906608) (xy 364.023723 -218.943225) (xy 363.9818 -218.973657) (xy 363.935631 -218.997153)
			(xy 363.886353 -219.013134) (xy 363.835182 -219.021207) (xy 363.80928 -219.02166) (xy 363.779199 -219.021012)
			(xy 363.720029 -219.010145) (xy 363.691678 -219.00007) (xy 363.678357 -218.995448) (xy 363.650285 -218.992933)
			(xy 363.622595 -218.99819) (xy 363.597398 -219.010818) (xy 363.576613 -219.029855) (xy 363.561827 -219.05385)
			(xy 363.554164 -219.080973) (xy 363.553756 -219.095066) (xy 363.553756 -219.257372) (xy 363.572877 -219.274496)
			(xy 363.606076 -219.31364) (xy 363.632776 -219.357475) (xy 363.652326 -219.404932) (xy 363.664248 -219.454855)
			(xy 363.668252 -219.506025) (xy 363.66424 -219.557194) (xy 363.65231 -219.607115) (xy 363.632754 -219.65457)
			(xy 363.606047 -219.698401) (xy 363.572842 -219.737539) (xy 363.553756 -219.754704) (xy 363.553756 -220.319854)
			(xy 364.419388 -220.319854) (xy 364.419896 -220.293947) (xy 364.428002 -220.24277) (xy 364.444014 -220.193491)
			(xy 364.467537 -220.147324) (xy 364.497993 -220.105405) (xy 364.534631 -220.068767) (xy 364.57655 -220.038311)
			(xy 364.622717 -220.014788) (xy 364.671996 -219.998776) (xy 364.723173 -219.99067) (xy 364.774987 -219.99067)
			(xy 364.826164 -219.998776) (xy 364.875443 -220.014788) (xy 364.92161 -220.038311) (xy 364.963529 -220.068767)
			(xy 365.000167 -220.105405) (xy 365.030623 -220.147324) (xy 365.054146 -220.193491) (xy 365.070158 -220.24277)
			(xy 365.078264 -220.293947) (xy 365.078772 -220.319854) (xy 366.298988 -220.319854) (xy 366.299496 -220.293947)
			(xy 366.307602 -220.24277) (xy 366.323614 -220.193491) (xy 366.347137 -220.147324) (xy 366.377593 -220.105405)
			(xy 366.414231 -220.068767) (xy 366.45615 -220.038311) (xy 366.502317 -220.014788) (xy 366.551596 -219.998776)
			(xy 366.602773 -219.99067) (xy 366.654587 -219.99067) (xy 366.705764 -219.998776) (xy 366.755043 -220.014788)
			(xy 366.80121 -220.038311) (xy 366.843129 -220.068767) (xy 366.879767 -220.105405) (xy 366.910223 -220.147324)
			(xy 366.933746 -220.193491) (xy 366.949758 -220.24277) (xy 366.957864 -220.293947) (xy 366.958372 -220.319854)
			(xy 368.178588 -220.319854) (xy 368.179096 -220.293947) (xy 368.187202 -220.24277) (xy 368.203214 -220.193491)
			(xy 368.226737 -220.147324) (xy 368.257193 -220.105405) (xy 368.293831 -220.068767) (xy 368.33575 -220.038311)
			(xy 368.381917 -220.014788) (xy 368.431196 -219.998776) (xy 368.482373 -219.99067) (xy 368.534187 -219.99067)
			(xy 368.585364 -219.998776) (xy 368.634643 -220.014788) (xy 368.68081 -220.038311) (xy 368.722729 -220.068767)
			(xy 368.759367 -220.105405) (xy 368.789823 -220.147324) (xy 368.813346 -220.193491) (xy 368.829358 -220.24277)
			(xy 368.837464 -220.293947) (xy 368.837972 -220.319854) (xy 370.058188 -220.319854) (xy 370.058696 -220.293947)
			(xy 370.066802 -220.24277) (xy 370.082814 -220.193491) (xy 370.106337 -220.147324) (xy 370.136793 -220.105405)
			(xy 370.173431 -220.068767) (xy 370.21535 -220.038311) (xy 370.261517 -220.014788) (xy 370.310796 -219.998776)
			(xy 370.361973 -219.99067) (xy 370.413787 -219.99067) (xy 370.464964 -219.998776) (xy 370.514243 -220.014788)
			(xy 370.56041 -220.038311) (xy 370.602329 -220.068767) (xy 370.638967 -220.105405) (xy 370.669423 -220.147324)
			(xy 370.692946 -220.193491) (xy 370.708958 -220.24277) (xy 370.717064 -220.293947) (xy 370.717572 -220.319854)
			(xy 371.937788 -220.319854) (xy 371.938296 -220.293947) (xy 371.946402 -220.24277) (xy 371.962414 -220.193491)
			(xy 371.985937 -220.147324) (xy 372.016393 -220.105405) (xy 372.053031 -220.068767) (xy 372.09495 -220.038311)
			(xy 372.141117 -220.014788) (xy 372.190396 -219.998776) (xy 372.241573 -219.99067) (xy 372.293387 -219.99067)
			(xy 372.344564 -219.998776) (xy 372.393843 -220.014788) (xy 372.44001 -220.038311) (xy 372.481929 -220.068767)
			(xy 372.518567 -220.105405) (xy 372.549023 -220.147324) (xy 372.572546 -220.193491) (xy 372.588558 -220.24277)
			(xy 372.596664 -220.293947) (xy 372.597172 -220.319854) (xy 373.817388 -220.319854) (xy 373.817896 -220.293947)
			(xy 373.826002 -220.24277) (xy 373.842014 -220.193491) (xy 373.865537 -220.147324) (xy 373.895993 -220.105405)
			(xy 373.932631 -220.068767) (xy 373.97455 -220.038311) (xy 374.020717 -220.014788) (xy 374.069996 -219.998776)
			(xy 374.121173 -219.99067) (xy 374.172987 -219.99067) (xy 374.224164 -219.998776) (xy 374.273443 -220.014788)
			(xy 374.31961 -220.038311) (xy 374.361529 -220.068767) (xy 374.398167 -220.105405) (xy 374.428623 -220.147324)
			(xy 374.452146 -220.193491) (xy 374.468158 -220.24277) (xy 374.476264 -220.293947) (xy 374.476772 -220.319854)
			(xy 374.476163 -220.347508) (xy 374.466839 -220.402026) (xy 374.45823 -220.428312) (xy 374.45061 -220.45041)
			(xy 374.655842 -220.805756) (xy 374.678702 -220.810074) (xy 374.703508 -220.815252) (xy 374.751247 -220.832242)
			(xy 374.795825 -220.856337) (xy 374.836191 -220.886969) (xy 374.871395 -220.923417) (xy 374.900606 -220.964822)
			(xy 374.923138 -221.01021) (xy 374.93846 -221.058511) (xy 374.94621 -221.108588) (xy 374.946672 -221.133924)
			(xy 374.946164 -221.159811) (xy 374.938065 -221.210949) (xy 374.922066 -221.260189) (xy 374.89856 -221.306321)
			(xy 374.868128 -221.348208) (xy 374.831518 -221.384818) (xy 374.789631 -221.41525) (xy 374.743499 -221.438756)
			(xy 374.694259 -221.454755) (xy 374.643121 -221.462854) (xy 374.591347 -221.462854) (xy 374.540209 -221.454755)
			(xy 374.490969 -221.438756) (xy 374.444837 -221.41525) (xy 374.40295 -221.384818) (xy 374.36634 -221.348208)
			(xy 374.335908 -221.306321) (xy 374.312402 -221.260189) (xy 374.296403 -221.210949) (xy 374.288304 -221.159811)
			(xy 374.287796 -221.133924) (xy 374.288332 -221.106216) (xy 374.297523 -221.051569) (xy 374.306084 -221.025212)
			(xy 374.313958 -221.003114) (xy 374.10898 -220.648022) (xy 374.08612 -220.643704) (xy 374.061279 -220.638521)
			(xy 374.013432 -220.621628) (xy 373.96874 -220.5976) (xy 373.928259 -220.567005) (xy 373.892948 -220.530566)
			(xy 373.863639 -220.489145) (xy 373.841027 -220.44372) (xy 373.825646 -220.395365) (xy 373.817859 -220.345225)
			(xy 373.817388 -220.319854) (xy 372.597172 -220.319854) (xy 372.596563 -220.347508) (xy 372.587239 -220.402026)
			(xy 372.57863 -220.428312) (xy 372.57101 -220.45041) (xy 372.776242 -220.805756) (xy 372.799102 -220.810074)
			(xy 372.823908 -220.815252) (xy 372.871647 -220.832242) (xy 372.916225 -220.856337) (xy 372.956591 -220.886969)
			(xy 372.991795 -220.923417) (xy 373.021006 -220.964822) (xy 373.043538 -221.01021) (xy 373.05886 -221.058511)
			(xy 373.06661 -221.108588) (xy 373.067072 -221.133924) (xy 373.066564 -221.159811) (xy 373.058465 -221.210949)
			(xy 373.042466 -221.260189) (xy 373.01896 -221.306321) (xy 372.988528 -221.348208) (xy 372.951918 -221.384818)
			(xy 372.910031 -221.41525) (xy 372.863899 -221.438756) (xy 372.814659 -221.454755) (xy 372.763521 -221.462854)
			(xy 372.711747 -221.462854) (xy 372.660609 -221.454755) (xy 372.611369 -221.438756) (xy 372.565237 -221.41525)
			(xy 372.52335 -221.384818) (xy 372.48674 -221.348208) (xy 372.456308 -221.306321) (xy 372.432802 -221.260189)
			(xy 372.416803 -221.210949) (xy 372.408704 -221.159811) (xy 372.408196 -221.133924) (xy 372.408732 -221.106216)
			(xy 372.417923 -221.051569) (xy 372.426484 -221.025212) (xy 372.434358 -221.003114) (xy 372.22938 -220.648022)
			(xy 372.20652 -220.643704) (xy 372.181679 -220.638521) (xy 372.133832 -220.621628) (xy 372.08914 -220.5976)
			(xy 372.048659 -220.567005) (xy 372.013348 -220.530566) (xy 371.984039 -220.489145) (xy 371.961427 -220.44372)
			(xy 371.946046 -220.395365) (xy 371.938259 -220.345225) (xy 371.937788 -220.319854) (xy 370.717572 -220.319854)
			(xy 370.716963 -220.347508) (xy 370.707639 -220.402026) (xy 370.69903 -220.428312) (xy 370.69141 -220.45041)
			(xy 370.896642 -220.805756) (xy 370.919502 -220.810074) (xy 370.944308 -220.815252) (xy 370.992047 -220.832242)
			(xy 371.036625 -220.856337) (xy 371.076991 -220.886969) (xy 371.112195 -220.923417) (xy 371.141406 -220.964822)
			(xy 371.163938 -221.01021) (xy 371.17926 -221.058511) (xy 371.18701 -221.108588) (xy 371.187472 -221.133924)
			(xy 371.186964 -221.159811) (xy 371.178865 -221.210949) (xy 371.162866 -221.260189) (xy 371.13936 -221.306321)
			(xy 371.108928 -221.348208) (xy 371.072318 -221.384818) (xy 371.030431 -221.41525) (xy 370.984299 -221.438756)
			(xy 370.935059 -221.454755) (xy 370.883921 -221.462854) (xy 370.832147 -221.462854) (xy 370.781009 -221.454755)
			(xy 370.731769 -221.438756) (xy 370.685637 -221.41525) (xy 370.64375 -221.384818) (xy 370.60714 -221.348208)
			(xy 370.576708 -221.306321) (xy 370.553202 -221.260189) (xy 370.537203 -221.210949) (xy 370.529104 -221.159811)
			(xy 370.528596 -221.133924) (xy 370.529132 -221.106216) (xy 370.538323 -221.051569) (xy 370.546884 -221.025212)
			(xy 370.554758 -221.003114) (xy 370.34978 -220.648022) (xy 370.32692 -220.643704) (xy 370.302079 -220.638521)
			(xy 370.254232 -220.621628) (xy 370.20954 -220.5976) (xy 370.169059 -220.567005) (xy 370.133748 -220.530566)
			(xy 370.104439 -220.489145) (xy 370.081827 -220.44372) (xy 370.066446 -220.395365) (xy 370.058659 -220.345225)
			(xy 370.058188 -220.319854) (xy 368.837972 -220.319854) (xy 368.837363 -220.347508) (xy 368.828039 -220.402026)
			(xy 368.81943 -220.428312) (xy 368.81181 -220.45041) (xy 369.017042 -220.805756) (xy 369.039902 -220.810074)
			(xy 369.064708 -220.815252) (xy 369.112447 -220.832242) (xy 369.157025 -220.856337) (xy 369.197391 -220.886969)
			(xy 369.232595 -220.923417) (xy 369.261806 -220.964822) (xy 369.284338 -221.01021) (xy 369.29966 -221.058511)
			(xy 369.30741 -221.108588) (xy 369.307872 -221.133924) (xy 369.307364 -221.159811) (xy 369.299265 -221.210949)
			(xy 369.283266 -221.260189) (xy 369.25976 -221.306321) (xy 369.229328 -221.348208) (xy 369.192718 -221.384818)
			(xy 369.150831 -221.41525) (xy 369.104699 -221.438756) (xy 369.055459 -221.454755) (xy 369.004321 -221.462854)
			(xy 368.952547 -221.462854) (xy 368.901409 -221.454755) (xy 368.852169 -221.438756) (xy 368.806037 -221.41525)
			(xy 368.76415 -221.384818) (xy 368.72754 -221.348208) (xy 368.697108 -221.306321) (xy 368.673602 -221.260189)
			(xy 368.657603 -221.210949) (xy 368.649504 -221.159811) (xy 368.648996 -221.133924) (xy 368.649532 -221.106216)
			(xy 368.658723 -221.051569) (xy 368.667284 -221.025212) (xy 368.675158 -221.003114) (xy 368.47018 -220.648022)
			(xy 368.44732 -220.643704) (xy 368.422479 -220.638521) (xy 368.374632 -220.621628) (xy 368.32994 -220.5976)
			(xy 368.289459 -220.567005) (xy 368.254148 -220.530566) (xy 368.224839 -220.489145) (xy 368.202227 -220.44372)
			(xy 368.186846 -220.395365) (xy 368.179059 -220.345225) (xy 368.178588 -220.319854) (xy 366.958372 -220.319854)
			(xy 366.957763 -220.347508) (xy 366.948439 -220.402026) (xy 366.93983 -220.428312) (xy 366.93221 -220.45041)
			(xy 367.137442 -220.805756) (xy 367.160302 -220.810074) (xy 367.185108 -220.815252) (xy 367.232847 -220.832242)
			(xy 367.277425 -220.856337) (xy 367.317791 -220.886969) (xy 367.352995 -220.923417) (xy 367.382206 -220.964822)
			(xy 367.404738 -221.01021) (xy 367.42006 -221.058511) (xy 367.42781 -221.108588) (xy 367.428272 -221.133924)
			(xy 367.427764 -221.159811) (xy 367.419665 -221.210949) (xy 367.403666 -221.260189) (xy 367.38016 -221.306321)
			(xy 367.349728 -221.348208) (xy 367.313118 -221.384818) (xy 367.271231 -221.41525) (xy 367.225099 -221.438756)
			(xy 367.175859 -221.454755) (xy 367.124721 -221.462854) (xy 367.072947 -221.462854) (xy 367.021809 -221.454755)
			(xy 366.972569 -221.438756) (xy 366.926437 -221.41525) (xy 366.88455 -221.384818) (xy 366.84794 -221.348208)
			(xy 366.817508 -221.306321) (xy 366.794002 -221.260189) (xy 366.778003 -221.210949) (xy 366.769904 -221.159811)
			(xy 366.769396 -221.133924) (xy 366.769932 -221.106216) (xy 366.779123 -221.051569) (xy 366.787684 -221.025212)
			(xy 366.795558 -221.003114) (xy 366.59058 -220.648022) (xy 366.56772 -220.643704) (xy 366.542879 -220.638521)
			(xy 366.495032 -220.621628) (xy 366.45034 -220.5976) (xy 366.409859 -220.567005) (xy 366.374548 -220.530566)
			(xy 366.345239 -220.489145) (xy 366.322627 -220.44372) (xy 366.307246 -220.395365) (xy 366.299459 -220.345225)
			(xy 366.298988 -220.319854) (xy 365.078772 -220.319854) (xy 365.078163 -220.347508) (xy 365.068839 -220.402026)
			(xy 365.06023 -220.428312) (xy 365.05261 -220.45041) (xy 365.257842 -220.805756) (xy 365.280702 -220.810074)
			(xy 365.305508 -220.815252) (xy 365.353247 -220.832242) (xy 365.397825 -220.856337) (xy 365.438191 -220.886969)
			(xy 365.473395 -220.923417) (xy 365.502606 -220.964822) (xy 365.525138 -221.01021) (xy 365.54046 -221.058511)
			(xy 365.54821 -221.108588) (xy 365.548672 -221.133924) (xy 365.548164 -221.159811) (xy 365.540065 -221.210949)
			(xy 365.524066 -221.260189) (xy 365.50056 -221.306321) (xy 365.470128 -221.348208) (xy 365.433518 -221.384818)
			(xy 365.391631 -221.41525) (xy 365.345499 -221.438756) (xy 365.296259 -221.454755) (xy 365.245121 -221.462854)
			(xy 365.193347 -221.462854) (xy 365.142209 -221.454755) (xy 365.092969 -221.438756) (xy 365.046837 -221.41525)
			(xy 365.00495 -221.384818) (xy 364.96834 -221.348208) (xy 364.937908 -221.306321) (xy 364.914402 -221.260189)
			(xy 364.898403 -221.210949) (xy 364.890304 -221.159811) (xy 364.889796 -221.133924) (xy 364.890332 -221.106216)
			(xy 364.899523 -221.051569) (xy 364.908084 -221.025212) (xy 364.915958 -221.003114) (xy 364.71098 -220.648022)
			(xy 364.68812 -220.643704) (xy 364.663279 -220.638521) (xy 364.615432 -220.621628) (xy 364.57074 -220.5976)
			(xy 364.530259 -220.567005) (xy 364.494948 -220.530566) (xy 364.465639 -220.489145) (xy 364.443027 -220.44372)
			(xy 364.427646 -220.395365) (xy 364.419859 -220.345225) (xy 364.419388 -220.319854) (xy 363.553756 -220.319854)
			(xy 363.553756 -220.88348) (xy 363.573081 -220.900688) (xy 363.60665 -220.940064) (xy 363.633653 -220.984201)
			(xy 363.653429 -221.032015) (xy 363.665491 -221.082332) (xy 363.669544 -221.133916) (xy 363.665486 -221.185499)
			(xy 363.653419 -221.235815) (xy 363.633639 -221.283627) (xy 363.606631 -221.327762) (xy 363.573059 -221.367134)
			(xy 363.553756 -221.384368) (xy 363.553756 -221.544896) (xy 363.55422 -221.558974) (xy 363.561924 -221.586056)
			(xy 363.576721 -221.61001) (xy 363.59749 -221.629022) (xy 363.622656 -221.641649) (xy 363.650312 -221.646935)
			(xy 363.678361 -221.644479) (xy 363.691678 -221.639892) (xy 363.705378 -221.634803) (xy 363.733488 -221.626795)
			(xy 363.747812 -221.62389) (xy 363.770672 -221.619572) (xy 363.975904 -221.264226) (xy 363.96803 -221.242128)
			(xy 363.959567 -221.215884) (xy 363.950503 -221.161494) (xy 363.949996 -221.133924) (xy 363.950504 -221.108037)
			(xy 363.958603 -221.056899) (xy 363.974602 -221.007659) (xy 363.998108 -220.961527) (xy 364.02854 -220.91964)
			(xy 364.06515 -220.88303) (xy 364.107037 -220.852598) (xy 364.153169 -220.829092) (xy 364.202409 -220.813093)
			(xy 364.253547 -220.804994) (xy 364.305321 -220.804994) (xy 364.356459 -220.813093) (xy 364.405699 -220.829092)
			(xy 364.451831 -220.852598) (xy 364.493718 -220.88303) (xy 364.530328 -220.91964) (xy 364.56076 -220.961527)
			(xy 364.584266 -221.007659) (xy 364.600265 -221.056899) (xy 364.608364 -221.108037) (xy 364.608872 -221.133924)
			(xy 364.608403 -221.159298) (xy 364.60062 -221.209444) (xy 364.585243 -221.257806) (xy 364.562634 -221.303238)
			(xy 364.533329 -221.344668) (xy 364.498019 -221.381116) (xy 364.457539 -221.411721) (xy 364.412846 -221.435759)
			(xy 364.364997 -221.452663) (xy 364.34014 -221.457774) (xy 364.31728 -221.462092) (xy 364.112556 -221.81693)
			(xy 364.12043 -221.838774) (xy 364.129074 -221.865183) (xy 364.138391 -221.919959) (xy 364.138972 -221.94774)
			(xy 365.359188 -221.94774) (xy 365.359665 -221.922395) (xy 365.367445 -221.872306) (xy 365.382797 -221.823996)
			(xy 365.40536 -221.778605) (xy 365.434603 -221.7372) (xy 365.469837 -221.700757) (xy 365.510231 -221.670134)
			(xy 365.554836 -221.646052) (xy 365.602599 -221.629078) (xy 365.627412 -221.62389) (xy 365.650272 -221.619572)
			(xy 365.855504 -221.264226) (xy 365.84763 -221.242128) (xy 365.839165 -221.215883) (xy 365.830093 -221.161495)
			(xy 365.829596 -221.133924) (xy 365.830104 -221.108037) (xy 365.838203 -221.056899) (xy 365.854202 -221.007659)
			(xy 365.877708 -220.961527) (xy 365.90814 -220.91964) (xy 365.94475 -220.88303) (xy 365.986637 -220.852598)
			(xy 366.032769 -220.829092) (xy 366.082009 -220.813093) (xy 366.133147 -220.804994) (xy 366.184921 -220.804994)
			(xy 366.236059 -220.813093) (xy 366.285299 -220.829092) (xy 366.331431 -220.852598) (xy 366.373318 -220.88303)
			(xy 366.409928 -220.91964) (xy 366.44036 -220.961527) (xy 366.463866 -221.007659) (xy 366.479865 -221.056899)
			(xy 366.487964 -221.108037) (xy 366.488472 -221.133924) (xy 366.488042 -221.1593) (xy 366.480269 -221.209454)
			(xy 366.464896 -221.257821) (xy 366.442286 -221.303259) (xy 366.412974 -221.344691) (xy 366.377655 -221.381137)
			(xy 366.337163 -221.411734) (xy 366.292458 -221.435759) (xy 366.244596 -221.452643) (xy 366.21974 -221.457774)
			(xy 366.19688 -221.462092) (xy 365.992156 -221.81693) (xy 366.00003 -221.838774) (xy 366.008686 -221.865179)
			(xy 366.018 -221.919958) (xy 366.018572 -221.94774) (xy 369.118388 -221.94774) (xy 369.118865 -221.922395)
			(xy 369.126645 -221.872306) (xy 369.141997 -221.823996) (xy 369.16456 -221.778605) (xy 369.193803 -221.7372)
			(xy 369.229037 -221.700757) (xy 369.269431 -221.670134) (xy 369.314036 -221.646052) (xy 369.361799 -221.629078)
			(xy 369.386612 -221.62389) (xy 369.409472 -221.619572) (xy 369.614704 -221.264226) (xy 369.60683 -221.242128)
			(xy 369.598365 -221.215883) (xy 369.589293 -221.161495) (xy 369.588796 -221.133924) (xy 369.589304 -221.108037)
			(xy 369.597403 -221.056899) (xy 369.613402 -221.007659) (xy 369.636908 -220.961527) (xy 369.66734 -220.91964)
			(xy 369.70395 -220.88303) (xy 369.745837 -220.852598) (xy 369.791969 -220.829092) (xy 369.841209 -220.813093)
			(xy 369.892347 -220.804994) (xy 369.944121 -220.804994) (xy 369.995259 -220.813093) (xy 370.044499 -220.829092)
			(xy 370.090631 -220.852598) (xy 370.132518 -220.88303) (xy 370.169128 -220.91964) (xy 370.19956 -220.961527)
			(xy 370.223066 -221.007659) (xy 370.239065 -221.056899) (xy 370.247164 -221.108037) (xy 370.247672 -221.133924)
			(xy 370.247242 -221.1593) (xy 370.239469 -221.209454) (xy 370.224096 -221.257821) (xy 370.201486 -221.303259)
			(xy 370.172174 -221.344691) (xy 370.136855 -221.381137) (xy 370.096363 -221.411734) (xy 370.051658 -221.435759)
			(xy 370.003796 -221.452643) (xy 369.97894 -221.457774) (xy 369.95608 -221.462092) (xy 369.751356 -221.81693)
			(xy 369.75923 -221.838774) (xy 369.767886 -221.865179) (xy 369.7772 -221.919958) (xy 369.777772 -221.94774)
			(xy 370.997988 -221.94774) (xy 370.998465 -221.922395) (xy 371.006245 -221.872306) (xy 371.021597 -221.823996)
			(xy 371.04416 -221.778605) (xy 371.073403 -221.7372) (xy 371.108637 -221.700757) (xy 371.149031 -221.670134)
			(xy 371.193636 -221.646052) (xy 371.241399 -221.629078) (xy 371.266212 -221.62389) (xy 371.289072 -221.619572)
			(xy 371.494304 -221.264226) (xy 371.48643 -221.242128) (xy 371.477965 -221.215883) (xy 371.468893 -221.161495)
			(xy 371.468396 -221.133924) (xy 371.468904 -221.108037) (xy 371.477003 -221.056899) (xy 371.493002 -221.007659)
			(xy 371.516508 -220.961527) (xy 371.54694 -220.91964) (xy 371.58355 -220.88303) (xy 371.625437 -220.852598)
			(xy 371.671569 -220.829092) (xy 371.720809 -220.813093) (xy 371.771947 -220.804994) (xy 371.823721 -220.804994)
			(xy 371.874859 -220.813093) (xy 371.924099 -220.829092) (xy 371.970231 -220.852598) (xy 372.012118 -220.88303)
			(xy 372.048728 -220.91964) (xy 372.07916 -220.961527) (xy 372.102666 -221.007659) (xy 372.118665 -221.056899)
			(xy 372.126764 -221.108037) (xy 372.127272 -221.133924) (xy 372.126842 -221.1593) (xy 372.119069 -221.209454)
			(xy 372.103696 -221.257821) (xy 372.081086 -221.303259) (xy 372.051774 -221.344691) (xy 372.016455 -221.381137)
			(xy 371.975963 -221.411734) (xy 371.931258 -221.435759) (xy 371.883396 -221.452643) (xy 371.85854 -221.457774)
			(xy 371.83568 -221.462092) (xy 371.630956 -221.81693) (xy 371.63883 -221.838774) (xy 371.647486 -221.865179)
			(xy 371.6568 -221.919958) (xy 371.657372 -221.94774) (xy 372.877588 -221.94774) (xy 372.878065 -221.922395)
			(xy 372.885845 -221.872306) (xy 372.901197 -221.823996) (xy 372.92376 -221.778605) (xy 372.953003 -221.7372)
			(xy 372.988237 -221.700757) (xy 373.028631 -221.670134) (xy 373.073236 -221.646052) (xy 373.120999 -221.629078)
			(xy 373.145812 -221.62389) (xy 373.168672 -221.619572) (xy 373.373904 -221.264226) (xy 373.36603 -221.242128)
			(xy 373.357565 -221.215883) (xy 373.348493 -221.161495) (xy 373.347996 -221.133924) (xy 373.348504 -221.108037)
			(xy 373.356603 -221.056899) (xy 373.372602 -221.007659) (xy 373.396108 -220.961527) (xy 373.42654 -220.91964)
			(xy 373.46315 -220.88303) (xy 373.505037 -220.852598) (xy 373.551169 -220.829092) (xy 373.600409 -220.813093)
			(xy 373.651547 -220.804994) (xy 373.703321 -220.804994) (xy 373.754459 -220.813093) (xy 373.803699 -220.829092)
			(xy 373.849831 -220.852598) (xy 373.891718 -220.88303) (xy 373.928328 -220.91964) (xy 373.95876 -220.961527)
			(xy 373.982266 -221.007659) (xy 373.998265 -221.056899) (xy 374.006364 -221.108037) (xy 374.006872 -221.133924)
			(xy 374.006442 -221.1593) (xy 373.998669 -221.209454) (xy 373.983296 -221.257821) (xy 373.960686 -221.303259)
			(xy 373.931374 -221.344691) (xy 373.896055 -221.381137) (xy 373.855563 -221.411734) (xy 373.810858 -221.435759)
			(xy 373.762996 -221.452643) (xy 373.73814 -221.457774) (xy 373.71528 -221.462092) (xy 373.510556 -221.81693)
			(xy 373.51843 -221.838774) (xy 373.527086 -221.865179) (xy 373.5364 -221.919958) (xy 373.536972 -221.94774)
			(xy 373.536464 -221.973647) (xy 373.528358 -222.024824) (xy 373.512346 -222.074103) (xy 373.488823 -222.12027)
			(xy 373.458367 -222.162189) (xy 373.421729 -222.198827) (xy 373.37981 -222.229283) (xy 373.333643 -222.252806)
			(xy 373.284364 -222.268818) (xy 373.233187 -222.276924) (xy 373.181373 -222.276924) (xy 373.130196 -222.268818)
			(xy 373.080917 -222.252806) (xy 373.03475 -222.229283) (xy 372.992831 -222.198827) (xy 372.956193 -222.162189)
			(xy 372.925737 -222.12027) (xy 372.902214 -222.074103) (xy 372.886202 -222.024824) (xy 372.878096 -221.973647)
			(xy 372.877588 -221.94774) (xy 371.657372 -221.94774) (xy 371.656864 -221.973647) (xy 371.648758 -222.024824)
			(xy 371.632746 -222.074103) (xy 371.609223 -222.12027) (xy 371.578767 -222.162189) (xy 371.542129 -222.198827)
			(xy 371.50021 -222.229283) (xy 371.454043 -222.252806) (xy 371.404764 -222.268818) (xy 371.353587 -222.276924)
			(xy 371.301773 -222.276924) (xy 371.250596 -222.268818) (xy 371.201317 -222.252806) (xy 371.15515 -222.229283)
			(xy 371.113231 -222.198827) (xy 371.076593 -222.162189) (xy 371.046137 -222.12027) (xy 371.022614 -222.074103)
			(xy 371.006602 -222.024824) (xy 370.998496 -221.973647) (xy 370.997988 -221.94774) (xy 369.777772 -221.94774)
			(xy 369.777264 -221.973647) (xy 369.769158 -222.024824) (xy 369.753146 -222.074103) (xy 369.729623 -222.12027)
			(xy 369.699167 -222.162189) (xy 369.662529 -222.198827) (xy 369.62061 -222.229283) (xy 369.574443 -222.252806)
			(xy 369.525164 -222.268818) (xy 369.473987 -222.276924) (xy 369.422173 -222.276924) (xy 369.370996 -222.268818)
			(xy 369.321717 -222.252806) (xy 369.27555 -222.229283) (xy 369.233631 -222.198827) (xy 369.196993 -222.162189)
			(xy 369.166537 -222.12027) (xy 369.143014 -222.074103) (xy 369.127002 -222.024824) (xy 369.118896 -221.973647)
			(xy 369.118388 -221.94774) (xy 366.018572 -221.94774) (xy 366.018064 -221.973647) (xy 366.009958 -222.024824)
			(xy 365.993946 -222.074103) (xy 365.970423 -222.12027) (xy 365.939967 -222.162189) (xy 365.903329 -222.198827)
			(xy 365.86141 -222.229283) (xy 365.815243 -222.252806) (xy 365.765964 -222.268818) (xy 365.714787 -222.276924)
			(xy 365.662973 -222.276924) (xy 365.611796 -222.268818) (xy 365.562517 -222.252806) (xy 365.51635 -222.229283)
			(xy 365.474431 -222.198827) (xy 365.437793 -222.162189) (xy 365.407337 -222.12027) (xy 365.383814 -222.074103)
			(xy 365.367802 -222.024824) (xy 365.359696 -221.973647) (xy 365.359188 -221.94774) (xy 364.138972 -221.94774)
			(xy 364.138461 -221.973645) (xy 364.13035 -222.024815) (xy 364.114335 -222.074087) (xy 364.090809 -222.120248)
			(xy 364.060352 -222.162159) (xy 364.023714 -222.198791) (xy 363.981796 -222.22924) (xy 363.935632 -222.252758)
			(xy 363.886357 -222.268764) (xy 363.835185 -222.276865) (xy 363.80928 -222.277432) (xy 363.77919 -222.276715)
			(xy 363.72002 -222.265721) (xy 363.691678 -222.255588) (xy 363.678354 -222.250968) (xy 363.650276 -222.248456)
			(xy 363.62258 -222.253714) (xy 363.597376 -222.26634) (xy 363.576581 -222.285373) (xy 363.56178 -222.309365)
			(xy 363.554098 -222.336489) (xy 363.553756 -222.350584) (xy 363.553756 -222.51289) (xy 363.572883 -222.530015)
			(xy 363.606095 -222.56916) (xy 363.632807 -222.612999) (xy 363.652368 -222.660462) (xy 363.664301 -222.710392)
			(xy 363.668314 -222.761571) (xy 363.66431 -222.812751) (xy 363.652386 -222.862683) (xy 363.632833 -222.91015)
			(xy 363.606129 -222.953993) (xy 363.572924 -222.993145) (xy 363.553756 -223.010222) (xy 363.553756 -224.138998)
			(xy 363.571504 -224.154734) (xy 363.602743 -224.190424) (xy 363.628547 -224.230221) (xy 363.648383 -224.273305)
			(xy 363.661842 -224.318786) (xy 363.668646 -224.365727) (xy 363.669072 -224.389442) (xy 363.949996 -224.389442)
			(xy 363.950429 -224.364106) (xy 363.95819 -224.314032) (xy 363.97352 -224.265734) (xy 363.996059 -224.22035)
			(xy 364.025275 -224.178949) (xy 364.060481 -224.142504) (xy 364.100848 -224.111874) (xy 364.145426 -224.087781)
			(xy 364.193165 -224.070791) (xy 364.217966 -224.065592) (xy 364.240826 -224.061274) (xy 364.44555 -223.706436)
			(xy 364.43793 -223.684338) (xy 364.429302 -223.657991) (xy 364.419979 -223.603344) (xy 364.419388 -223.575626)
			(xy 364.419896 -223.549719) (xy 364.428002 -223.498542) (xy 364.444014 -223.449263) (xy 364.467537 -223.403096)
			(xy 364.497993 -223.361177) (xy 364.534631 -223.324539) (xy 364.57655 -223.294083) (xy 364.622717 -223.27056)
			(xy 364.671996 -223.254548) (xy 364.723173 -223.246442) (xy 364.774987 -223.246442) (xy 364.826164 -223.254548)
			(xy 364.875443 -223.27056) (xy 364.92161 -223.294083) (xy 364.963529 -223.324539) (xy 365.000167 -223.361177)
			(xy 365.030623 -223.403096) (xy 365.054146 -223.449263) (xy 365.070158 -223.498542) (xy 365.078264 -223.549719)
			(xy 365.078772 -223.575626) (xy 365.078381 -223.600993) (xy 365.070628 -223.651131) (xy 365.055277 -223.699486)
			(xy 365.032692 -223.744915) (xy 365.003407 -223.786344) (xy 364.968116 -223.822791) (xy 364.927652 -223.853396)
			(xy 364.882974 -223.877433) (xy 364.835139 -223.894334) (xy 364.810294 -223.899476) (xy 364.787434 -223.903794)
			(xy 364.58271 -224.258632) (xy 364.590584 -224.280476) (xy 364.599157 -224.306897) (xy 364.608358 -224.36167)
			(xy 364.608872 -224.389442) (xy 364.889796 -224.389442) (xy 364.890304 -224.363555) (xy 364.898403 -224.312417)
			(xy 364.914402 -224.263177) (xy 364.937908 -224.217045) (xy 364.96834 -224.175158) (xy 365.00495 -224.138548)
			(xy 365.046837 -224.108116) (xy 365.092969 -224.08461) (xy 365.142209 -224.068611) (xy 365.193347 -224.060512)
			(xy 365.245121 -224.060512) (xy 365.296259 -224.068611) (xy 365.345499 -224.08461) (xy 365.391631 -224.108116)
			(xy 365.433518 -224.138548) (xy 365.470128 -224.175158) (xy 365.50056 -224.217045) (xy 365.524066 -224.263177)
			(xy 365.540065 -224.312417) (xy 365.548164 -224.363555) (xy 365.548672 -224.389442) (xy 365.829596 -224.389442)
			(xy 365.830029 -224.364106) (xy 365.83779 -224.314032) (xy 365.85312 -224.265734) (xy 365.875659 -224.22035)
			(xy 365.904875 -224.178949) (xy 365.940081 -224.142504) (xy 365.980448 -224.111874) (xy 366.025026 -224.087781)
			(xy 366.072765 -224.070791) (xy 366.097566 -224.065592) (xy 366.120426 -224.061274) (xy 366.32515 -223.706436)
			(xy 366.31753 -223.684338) (xy 366.308902 -223.657991) (xy 366.299579 -223.603344) (xy 366.298988 -223.575626)
			(xy 366.299496 -223.549719) (xy 366.307602 -223.498542) (xy 366.323614 -223.449263) (xy 366.347137 -223.403096)
			(xy 366.377593 -223.361177) (xy 366.414231 -223.324539) (xy 366.45615 -223.294083) (xy 366.502317 -223.27056)
			(xy 366.551596 -223.254548) (xy 366.602773 -223.246442) (xy 366.654587 -223.246442) (xy 366.705764 -223.254548)
			(xy 366.755043 -223.27056) (xy 366.80121 -223.294083) (xy 366.843129 -223.324539) (xy 366.879767 -223.361177)
			(xy 366.910223 -223.403096) (xy 366.933746 -223.449263) (xy 366.949758 -223.498542) (xy 366.957864 -223.549719)
			(xy 366.958372 -223.575626) (xy 366.957981 -223.600993) (xy 366.950228 -223.651131) (xy 366.934877 -223.699486)
			(xy 366.912292 -223.744915) (xy 366.883007 -223.786344) (xy 366.847716 -223.822791) (xy 366.807252 -223.853396)
			(xy 366.762574 -223.877433) (xy 366.714739 -223.894334) (xy 366.689894 -223.899476) (xy 366.667034 -223.903794)
			(xy 366.46231 -224.258632) (xy 366.470184 -224.280476) (xy 366.478757 -224.306897) (xy 366.487958 -224.36167)
			(xy 366.488472 -224.389442) (xy 366.769396 -224.389442) (xy 366.769904 -224.363555) (xy 366.778003 -224.312417)
			(xy 366.794002 -224.263177) (xy 366.817508 -224.217045) (xy 366.84794 -224.175158) (xy 366.88455 -224.138548)
			(xy 366.926437 -224.108116) (xy 366.972569 -224.08461) (xy 367.021809 -224.068611) (xy 367.072947 -224.060512)
			(xy 367.124721 -224.060512) (xy 367.175859 -224.068611) (xy 367.225099 -224.08461) (xy 367.271231 -224.108116)
			(xy 367.313118 -224.138548) (xy 367.349728 -224.175158) (xy 367.38016 -224.217045) (xy 367.403666 -224.263177)
			(xy 367.419665 -224.312417) (xy 367.427764 -224.363555) (xy 367.428272 -224.389442) (xy 367.709196 -224.389442)
			(xy 367.709629 -224.364106) (xy 367.71739 -224.314032) (xy 367.73272 -224.265734) (xy 367.755259 -224.22035)
			(xy 367.784475 -224.178949) (xy 367.819681 -224.142504) (xy 367.860048 -224.111874) (xy 367.904626 -224.087781)
			(xy 367.952365 -224.070791) (xy 367.977166 -224.065592) (xy 368.000026 -224.061274) (xy 368.20475 -223.706436)
			(xy 368.19713 -223.684338) (xy 368.188502 -223.657991) (xy 368.179179 -223.603344) (xy 368.178588 -223.575626)
			(xy 368.179096 -223.549719) (xy 368.187202 -223.498542) (xy 368.203214 -223.449263) (xy 368.226737 -223.403096)
			(xy 368.257193 -223.361177) (xy 368.293831 -223.324539) (xy 368.33575 -223.294083) (xy 368.381917 -223.27056)
			(xy 368.431196 -223.254548) (xy 368.482373 -223.246442) (xy 368.534187 -223.246442) (xy 368.585364 -223.254548)
			(xy 368.634643 -223.27056) (xy 368.68081 -223.294083) (xy 368.722729 -223.324539) (xy 368.759367 -223.361177)
			(xy 368.789823 -223.403096) (xy 368.813346 -223.449263) (xy 368.829358 -223.498542) (xy 368.837464 -223.549719)
			(xy 368.837972 -223.575626) (xy 368.837581 -223.600993) (xy 368.829828 -223.651131) (xy 368.814477 -223.699486)
			(xy 368.791892 -223.744915) (xy 368.762607 -223.786344) (xy 368.727316 -223.822791) (xy 368.686852 -223.853396)
			(xy 368.642174 -223.877433) (xy 368.594339 -223.894334) (xy 368.569494 -223.899476) (xy 368.546634 -223.903794)
			(xy 368.34191 -224.258632) (xy 368.349784 -224.280476) (xy 368.358357 -224.306897) (xy 368.367558 -224.36167)
			(xy 368.368072 -224.389442) (xy 368.648996 -224.389442) (xy 368.649504 -224.363555) (xy 368.657603 -224.312417)
			(xy 368.673602 -224.263177) (xy 368.697108 -224.217045) (xy 368.72754 -224.175158) (xy 368.76415 -224.138548)
			(xy 368.806037 -224.108116) (xy 368.852169 -224.08461) (xy 368.901409 -224.068611) (xy 368.952547 -224.060512)
			(xy 369.004321 -224.060512) (xy 369.055459 -224.068611) (xy 369.104699 -224.08461) (xy 369.150831 -224.108116)
			(xy 369.192718 -224.138548) (xy 369.229328 -224.175158) (xy 369.25976 -224.217045) (xy 369.283266 -224.263177)
			(xy 369.299265 -224.312417) (xy 369.307364 -224.363555) (xy 369.307872 -224.389442) (xy 369.588796 -224.389442)
			(xy 369.589229 -224.364106) (xy 369.59699 -224.314032) (xy 369.61232 -224.265734) (xy 369.634859 -224.22035)
			(xy 369.664075 -224.178949) (xy 369.699281 -224.142504) (xy 369.739648 -224.111874) (xy 369.784226 -224.087781)
			(xy 369.831965 -224.070791) (xy 369.856766 -224.065592) (xy 369.879626 -224.061274) (xy 370.08435 -223.706436)
			(xy 370.07673 -223.684338) (xy 370.068102 -223.657991) (xy 370.058779 -223.603344) (xy 370.058188 -223.575626)
			(xy 370.058696 -223.549719) (xy 370.066802 -223.498542) (xy 370.082814 -223.449263) (xy 370.106337 -223.403096)
			(xy 370.136793 -223.361177) (xy 370.173431 -223.324539) (xy 370.21535 -223.294083) (xy 370.261517 -223.27056)
			(xy 370.310796 -223.254548) (xy 370.361973 -223.246442) (xy 370.413787 -223.246442) (xy 370.464964 -223.254548)
			(xy 370.514243 -223.27056) (xy 370.56041 -223.294083) (xy 370.602329 -223.324539) (xy 370.638967 -223.361177)
			(xy 370.669423 -223.403096) (xy 370.692946 -223.449263) (xy 370.708958 -223.498542) (xy 370.717064 -223.549719)
			(xy 370.717572 -223.575626) (xy 370.717181 -223.600993) (xy 370.709428 -223.651131) (xy 370.694077 -223.699486)
			(xy 370.671492 -223.744915) (xy 370.642207 -223.786344) (xy 370.606916 -223.822791) (xy 370.566452 -223.853396)
			(xy 370.521774 -223.877433) (xy 370.473939 -223.894334) (xy 370.449094 -223.899476) (xy 370.426234 -223.903794)
			(xy 370.22151 -224.258632) (xy 370.229384 -224.280476) (xy 370.237957 -224.306897) (xy 370.247158 -224.36167)
			(xy 370.247672 -224.389442) (xy 370.528596 -224.389442) (xy 370.529104 -224.363555) (xy 370.537203 -224.312417)
			(xy 370.553202 -224.263177) (xy 370.576708 -224.217045) (xy 370.60714 -224.175158) (xy 370.64375 -224.138548)
			(xy 370.685637 -224.108116) (xy 370.731769 -224.08461) (xy 370.781009 -224.068611) (xy 370.832147 -224.060512)
			(xy 370.883921 -224.060512) (xy 370.935059 -224.068611) (xy 370.984299 -224.08461) (xy 371.030431 -224.108116)
			(xy 371.072318 -224.138548) (xy 371.108928 -224.175158) (xy 371.13936 -224.217045) (xy 371.162866 -224.263177)
			(xy 371.178865 -224.312417) (xy 371.186964 -224.363555) (xy 371.187472 -224.389442) (xy 371.468396 -224.389442)
			(xy 371.468829 -224.364106) (xy 371.47659 -224.314032) (xy 371.49192 -224.265734) (xy 371.514459 -224.22035)
			(xy 371.543675 -224.178949) (xy 371.578881 -224.142504) (xy 371.619248 -224.111874) (xy 371.663826 -224.087781)
			(xy 371.711565 -224.070791) (xy 371.736366 -224.065592) (xy 371.759226 -224.061274) (xy 371.96395 -223.706436)
			(xy 371.95633 -223.684338) (xy 371.947702 -223.657991) (xy 371.938379 -223.603344) (xy 371.937788 -223.575626)
			(xy 371.938296 -223.549719) (xy 371.946402 -223.498542) (xy 371.962414 -223.449263) (xy 371.985937 -223.403096)
			(xy 372.016393 -223.361177) (xy 372.053031 -223.324539) (xy 372.09495 -223.294083) (xy 372.141117 -223.27056)
			(xy 372.190396 -223.254548) (xy 372.241573 -223.246442) (xy 372.293387 -223.246442) (xy 372.344564 -223.254548)
			(xy 372.393843 -223.27056) (xy 372.44001 -223.294083) (xy 372.481929 -223.324539) (xy 372.518567 -223.361177)
			(xy 372.549023 -223.403096) (xy 372.572546 -223.449263) (xy 372.588558 -223.498542) (xy 372.596664 -223.549719)
			(xy 372.597172 -223.575626) (xy 372.596781 -223.600993) (xy 372.589028 -223.651131) (xy 372.573677 -223.699486)
			(xy 372.551092 -223.744915) (xy 372.521807 -223.786344) (xy 372.486516 -223.822791) (xy 372.446052 -223.853396)
			(xy 372.401374 -223.877433) (xy 372.353539 -223.894334) (xy 372.328694 -223.899476) (xy 372.305834 -223.903794)
			(xy 372.10111 -224.258632) (xy 372.108984 -224.280476) (xy 372.117557 -224.306897) (xy 372.126758 -224.36167)
			(xy 372.127272 -224.389442) (xy 372.408196 -224.389442) (xy 372.408704 -224.363555) (xy 372.416803 -224.312417)
			(xy 372.432802 -224.263177) (xy 372.456308 -224.217045) (xy 372.48674 -224.175158) (xy 372.52335 -224.138548)
			(xy 372.565237 -224.108116) (xy 372.611369 -224.08461) (xy 372.660609 -224.068611) (xy 372.711747 -224.060512)
			(xy 372.763521 -224.060512) (xy 372.814659 -224.068611) (xy 372.863899 -224.08461) (xy 372.910031 -224.108116)
			(xy 372.951918 -224.138548) (xy 372.988528 -224.175158) (xy 373.01896 -224.217045) (xy 373.042466 -224.263177)
			(xy 373.058465 -224.312417) (xy 373.066564 -224.363555) (xy 373.067072 -224.389442) (xy 373.347996 -224.389442)
			(xy 373.348429 -224.364106) (xy 373.35619 -224.314032) (xy 373.37152 -224.265734) (xy 373.394059 -224.22035)
			(xy 373.423275 -224.178949) (xy 373.458481 -224.142504) (xy 373.498848 -224.111874) (xy 373.543426 -224.087781)
			(xy 373.591165 -224.070791) (xy 373.615966 -224.065592) (xy 373.638826 -224.061274) (xy 373.84355 -223.706436)
			(xy 373.83593 -223.684338) (xy 373.827302 -223.657991) (xy 373.817979 -223.603344) (xy 373.817388 -223.575626)
			(xy 373.817896 -223.549719) (xy 373.826002 -223.498542) (xy 373.842014 -223.449263) (xy 373.865537 -223.403096)
			(xy 373.895993 -223.361177) (xy 373.932631 -223.324539) (xy 373.97455 -223.294083) (xy 374.020717 -223.27056)
			(xy 374.069996 -223.254548) (xy 374.121173 -223.246442) (xy 374.172987 -223.246442) (xy 374.224164 -223.254548)
			(xy 374.273443 -223.27056) (xy 374.31961 -223.294083) (xy 374.361529 -223.324539) (xy 374.398167 -223.361177)
			(xy 374.428623 -223.403096) (xy 374.452146 -223.449263) (xy 374.468158 -223.498542) (xy 374.476264 -223.549719)
			(xy 374.476772 -223.575626) (xy 374.476381 -223.600993) (xy 374.468628 -223.651131) (xy 374.453277 -223.699486)
			(xy 374.430692 -223.744915) (xy 374.401407 -223.786344) (xy 374.366116 -223.822791) (xy 374.325652 -223.853396)
			(xy 374.280974 -223.877433) (xy 374.233139 -223.894334) (xy 374.208294 -223.899476) (xy 374.185434 -223.903794)
			(xy 373.98071 -224.258632) (xy 373.988584 -224.280476) (xy 373.997157 -224.306897) (xy 374.006358 -224.36167)
			(xy 374.006872 -224.389442) (xy 374.006364 -224.415329) (xy 373.998265 -224.466467) (xy 373.982266 -224.515707)
			(xy 373.95876 -224.561839) (xy 373.928328 -224.603726) (xy 373.891718 -224.640336) (xy 373.849831 -224.670768)
			(xy 373.803699 -224.694274) (xy 373.754459 -224.710273) (xy 373.703321 -224.718372) (xy 373.651547 -224.718372)
			(xy 373.600409 -224.710273) (xy 373.551169 -224.694274) (xy 373.505037 -224.670768) (xy 373.46315 -224.640336)
			(xy 373.42654 -224.603726) (xy 373.396108 -224.561839) (xy 373.372602 -224.515707) (xy 373.356603 -224.466467)
			(xy 373.348504 -224.415329) (xy 373.347996 -224.389442) (xy 373.067072 -224.389442) (xy 373.066525 -224.417149)
			(xy 373.057341 -224.471796) (xy 373.048784 -224.498154) (xy 373.04091 -224.520252) (xy 373.245888 -224.87509)
			(xy 373.268748 -224.879408) (xy 373.293571 -224.884565) (xy 373.341351 -224.90152) (xy 373.385971 -224.925592)
			(xy 373.426378 -224.956214) (xy 373.461619 -224.992662) (xy 373.490863 -225.034077) (xy 373.513419 -225.079482)
			(xy 373.528756 -225.127806) (xy 373.536511 -225.177908) (xy 373.536972 -225.203258) (xy 373.536464 -225.229165)
			(xy 373.528358 -225.280342) (xy 373.512346 -225.329621) (xy 373.488823 -225.375788) (xy 373.458367 -225.417707)
			(xy 373.421729 -225.454345) (xy 373.37981 -225.484801) (xy 373.333643 -225.508324) (xy 373.284364 -225.524336)
			(xy 373.233187 -225.532442) (xy 373.181373 -225.532442) (xy 373.130196 -225.524336) (xy 373.080917 -225.508324)
			(xy 373.03475 -225.484801) (xy 372.992831 -225.454345) (xy 372.956193 -225.417707) (xy 372.925737 -225.375788)
			(xy 372.902214 -225.329621) (xy 372.886202 -225.280342) (xy 372.878096 -225.229165) (xy 372.877588 -225.203258)
			(xy 372.878197 -225.175541) (xy 372.88751 -225.120895) (xy 372.89613 -225.094546) (xy 372.904004 -225.072448)
			(xy 372.699026 -224.71761) (xy 372.676166 -224.713292) (xy 372.651348 -224.708169) (xy 372.603605 -224.691172)
			(xy 372.559026 -224.667071) (xy 372.51866 -224.636431) (xy 372.483457 -224.599976) (xy 372.454248 -224.558564)
			(xy 372.431719 -224.51317) (xy 372.416401 -224.464863) (xy 372.408655 -224.414781) (xy 372.408196 -224.389442)
			(xy 372.127272 -224.389442) (xy 372.126764 -224.415329) (xy 372.118665 -224.466467) (xy 372.102666 -224.515707)
			(xy 372.07916 -224.561839) (xy 372.048728 -224.603726) (xy 372.012118 -224.640336) (xy 371.970231 -224.670768)
			(xy 371.924099 -224.694274) (xy 371.874859 -224.710273) (xy 371.823721 -224.718372) (xy 371.771947 -224.718372)
			(xy 371.720809 -224.710273) (xy 371.671569 -224.694274) (xy 371.625437 -224.670768) (xy 371.58355 -224.640336)
			(xy 371.54694 -224.603726) (xy 371.516508 -224.561839) (xy 371.493002 -224.515707) (xy 371.477003 -224.466467)
			(xy 371.468904 -224.415329) (xy 371.468396 -224.389442) (xy 371.187472 -224.389442) (xy 371.186925 -224.417149)
			(xy 371.177741 -224.471796) (xy 371.169184 -224.498154) (xy 371.16131 -224.520252) (xy 371.366288 -224.87509)
			(xy 371.389148 -224.879408) (xy 371.413971 -224.884565) (xy 371.461751 -224.90152) (xy 371.506371 -224.925592)
			(xy 371.546778 -224.956214) (xy 371.582019 -224.992662) (xy 371.611263 -225.034077) (xy 371.633819 -225.079482)
			(xy 371.649156 -225.127806) (xy 371.656911 -225.177908) (xy 371.657372 -225.203258) (xy 371.656864 -225.229165)
			(xy 371.648758 -225.280342) (xy 371.632746 -225.329621) (xy 371.609223 -225.375788) (xy 371.578767 -225.417707)
			(xy 371.542129 -225.454345) (xy 371.50021 -225.484801) (xy 371.454043 -225.508324) (xy 371.404764 -225.524336)
			(xy 371.353587 -225.532442) (xy 371.301773 -225.532442) (xy 371.250596 -225.524336) (xy 371.201317 -225.508324)
			(xy 371.15515 -225.484801) (xy 371.113231 -225.454345) (xy 371.076593 -225.417707) (xy 371.046137 -225.375788)
			(xy 371.022614 -225.329621) (xy 371.006602 -225.280342) (xy 370.998496 -225.229165) (xy 370.997988 -225.203258)
			(xy 370.998597 -225.175541) (xy 371.00791 -225.120895) (xy 371.01653 -225.094546) (xy 371.024404 -225.072448)
			(xy 370.819426 -224.71761) (xy 370.796566 -224.713292) (xy 370.771748 -224.708169) (xy 370.724005 -224.691172)
			(xy 370.679426 -224.667071) (xy 370.63906 -224.636431) (xy 370.603857 -224.599976) (xy 370.574648 -224.558564)
			(xy 370.552119 -224.51317) (xy 370.536801 -224.464863) (xy 370.529055 -224.414781) (xy 370.528596 -224.389442)
			(xy 370.247672 -224.389442) (xy 370.247164 -224.415329) (xy 370.239065 -224.466467) (xy 370.223066 -224.515707)
			(xy 370.19956 -224.561839) (xy 370.169128 -224.603726) (xy 370.132518 -224.640336) (xy 370.090631 -224.670768)
			(xy 370.044499 -224.694274) (xy 369.995259 -224.710273) (xy 369.944121 -224.718372) (xy 369.892347 -224.718372)
			(xy 369.841209 -224.710273) (xy 369.791969 -224.694274) (xy 369.745837 -224.670768) (xy 369.70395 -224.640336)
			(xy 369.66734 -224.603726) (xy 369.636908 -224.561839) (xy 369.613402 -224.515707) (xy 369.597403 -224.466467)
			(xy 369.589304 -224.415329) (xy 369.588796 -224.389442) (xy 369.307872 -224.389442) (xy 369.307325 -224.417149)
			(xy 369.298141 -224.471796) (xy 369.289584 -224.498154) (xy 369.28171 -224.520252) (xy 369.486688 -224.87509)
			(xy 369.509548 -224.879408) (xy 369.534371 -224.884565) (xy 369.582151 -224.90152) (xy 369.626771 -224.925592)
			(xy 369.667178 -224.956214) (xy 369.702419 -224.992662) (xy 369.731663 -225.034077) (xy 369.754219 -225.079482)
			(xy 369.769556 -225.127806) (xy 369.777311 -225.177908) (xy 369.777772 -225.203258) (xy 369.777264 -225.229165)
			(xy 369.769158 -225.280342) (xy 369.753146 -225.329621) (xy 369.729623 -225.375788) (xy 369.699167 -225.417707)
			(xy 369.662529 -225.454345) (xy 369.62061 -225.484801) (xy 369.574443 -225.508324) (xy 369.525164 -225.524336)
			(xy 369.473987 -225.532442) (xy 369.422173 -225.532442) (xy 369.370996 -225.524336) (xy 369.321717 -225.508324)
			(xy 369.27555 -225.484801) (xy 369.233631 -225.454345) (xy 369.196993 -225.417707) (xy 369.166537 -225.375788)
			(xy 369.143014 -225.329621) (xy 369.127002 -225.280342) (xy 369.118896 -225.229165) (xy 369.118388 -225.203258)
			(xy 369.118997 -225.175541) (xy 369.12831 -225.120895) (xy 369.13693 -225.094546) (xy 369.144804 -225.072448)
			(xy 368.939826 -224.71761) (xy 368.916966 -224.713292) (xy 368.892148 -224.708169) (xy 368.844405 -224.691172)
			(xy 368.799826 -224.667071) (xy 368.75946 -224.636431) (xy 368.724257 -224.599976) (xy 368.695048 -224.558564)
			(xy 368.672519 -224.51317) (xy 368.657201 -224.464863) (xy 368.649455 -224.414781) (xy 368.648996 -224.389442)
			(xy 368.368072 -224.389442) (xy 368.367564 -224.415329) (xy 368.359465 -224.466467) (xy 368.343466 -224.515707)
			(xy 368.31996 -224.561839) (xy 368.289528 -224.603726) (xy 368.252918 -224.640336) (xy 368.211031 -224.670768)
			(xy 368.164899 -224.694274) (xy 368.115659 -224.710273) (xy 368.064521 -224.718372) (xy 368.012747 -224.718372)
			(xy 367.961609 -224.710273) (xy 367.912369 -224.694274) (xy 367.866237 -224.670768) (xy 367.82435 -224.640336)
			(xy 367.78774 -224.603726) (xy 367.757308 -224.561839) (xy 367.733802 -224.515707) (xy 367.717803 -224.466467)
			(xy 367.709704 -224.415329) (xy 367.709196 -224.389442) (xy 367.428272 -224.389442) (xy 367.427725 -224.417149)
			(xy 367.418541 -224.471796) (xy 367.409984 -224.498154) (xy 367.40211 -224.520252) (xy 367.607088 -224.87509)
			(xy 367.629948 -224.879408) (xy 367.654771 -224.884565) (xy 367.702551 -224.90152) (xy 367.747171 -224.925592)
			(xy 367.787578 -224.956214) (xy 367.822819 -224.992662) (xy 367.852063 -225.034077) (xy 367.874619 -225.079482)
			(xy 367.889956 -225.127806) (xy 367.897711 -225.177908) (xy 367.898172 -225.203258) (xy 367.897664 -225.229165)
			(xy 367.889558 -225.280342) (xy 367.873546 -225.329621) (xy 367.850023 -225.375788) (xy 367.819567 -225.417707)
			(xy 367.782929 -225.454345) (xy 367.74101 -225.484801) (xy 367.694843 -225.508324) (xy 367.645564 -225.524336)
			(xy 367.594387 -225.532442) (xy 367.542573 -225.532442) (xy 367.491396 -225.524336) (xy 367.442117 -225.508324)
			(xy 367.39595 -225.484801) (xy 367.354031 -225.454345) (xy 367.317393 -225.417707) (xy 367.286937 -225.375788)
			(xy 367.263414 -225.329621) (xy 367.247402 -225.280342) (xy 367.239296 -225.229165) (xy 367.238788 -225.203258)
			(xy 367.239397 -225.175541) (xy 367.24871 -225.120895) (xy 367.25733 -225.094546) (xy 367.265204 -225.072448)
			(xy 367.060226 -224.71761) (xy 367.037366 -224.713292) (xy 367.012548 -224.708169) (xy 366.964805 -224.691172)
			(xy 366.920226 -224.667071) (xy 366.87986 -224.636431) (xy 366.844657 -224.599976) (xy 366.815448 -224.558564)
			(xy 366.792919 -224.51317) (xy 366.777601 -224.464863) (xy 366.769855 -224.414781) (xy 366.769396 -224.389442)
			(xy 366.488472 -224.389442) (xy 366.487964 -224.415329) (xy 366.479865 -224.466467) (xy 366.463866 -224.515707)
			(xy 366.44036 -224.561839) (xy 366.409928 -224.603726) (xy 366.373318 -224.640336) (xy 366.331431 -224.670768)
			(xy 366.285299 -224.694274) (xy 366.236059 -224.710273) (xy 366.184921 -224.718372) (xy 366.133147 -224.718372)
			(xy 366.082009 -224.710273) (xy 366.032769 -224.694274) (xy 365.986637 -224.670768) (xy 365.94475 -224.640336)
			(xy 365.90814 -224.603726) (xy 365.877708 -224.561839) (xy 365.854202 -224.515707) (xy 365.838203 -224.466467)
			(xy 365.830104 -224.415329) (xy 365.829596 -224.389442) (xy 365.548672 -224.389442) (xy 365.548125 -224.417149)
			(xy 365.538941 -224.471796) (xy 365.530384 -224.498154) (xy 365.52251 -224.520252) (xy 365.727488 -224.87509)
			(xy 365.750348 -224.879408) (xy 365.775171 -224.884565) (xy 365.822951 -224.90152) (xy 365.867571 -224.925592)
			(xy 365.907978 -224.956214) (xy 365.943219 -224.992662) (xy 365.972463 -225.034077) (xy 365.995019 -225.079482)
			(xy 366.010356 -225.127806) (xy 366.018111 -225.177908) (xy 366.018572 -225.203258) (xy 366.018064 -225.229165)
			(xy 366.009958 -225.280342) (xy 365.993946 -225.329621) (xy 365.970423 -225.375788) (xy 365.939967 -225.417707)
			(xy 365.903329 -225.454345) (xy 365.86141 -225.484801) (xy 365.815243 -225.508324) (xy 365.765964 -225.524336)
			(xy 365.714787 -225.532442) (xy 365.662973 -225.532442) (xy 365.611796 -225.524336) (xy 365.562517 -225.508324)
			(xy 365.51635 -225.484801) (xy 365.474431 -225.454345) (xy 365.437793 -225.417707) (xy 365.407337 -225.375788)
			(xy 365.383814 -225.329621) (xy 365.367802 -225.280342) (xy 365.359696 -225.229165) (xy 365.359188 -225.203258)
			(xy 365.359797 -225.175541) (xy 365.36911 -225.120895) (xy 365.37773 -225.094546) (xy 365.385604 -225.072448)
			(xy 365.180626 -224.71761) (xy 365.157766 -224.713292) (xy 365.132948 -224.708169) (xy 365.085205 -224.691172)
			(xy 365.040626 -224.667071) (xy 365.00026 -224.636431) (xy 364.965057 -224.599976) (xy 364.935848 -224.558564)
			(xy 364.913319 -224.51317) (xy 364.898001 -224.464863) (xy 364.890255 -224.414781) (xy 364.889796 -224.389442)
			(xy 364.608872 -224.389442) (xy 364.608364 -224.415329) (xy 364.600265 -224.466467) (xy 364.584266 -224.515707)
			(xy 364.56076 -224.561839) (xy 364.530328 -224.603726) (xy 364.493718 -224.640336) (xy 364.451831 -224.670768)
			(xy 364.405699 -224.694274) (xy 364.356459 -224.710273) (xy 364.305321 -224.718372) (xy 364.253547 -224.718372)
			(xy 364.202409 -224.710273) (xy 364.153169 -224.694274) (xy 364.107037 -224.670768) (xy 364.06515 -224.640336)
			(xy 364.02854 -224.603726) (xy 363.998108 -224.561839) (xy 363.974602 -224.515707) (xy 363.958603 -224.466467)
			(xy 363.950504 -224.415329) (xy 363.949996 -224.389442) (xy 363.669072 -224.389442) (xy 363.668548 -224.417151)
			(xy 363.659358 -224.4718) (xy 363.650784 -224.498154) (xy 363.64291 -224.520252) (xy 363.847888 -224.87509)
			(xy 363.870748 -224.879408) (xy 363.895562 -224.884594) (xy 363.94333 -224.901564) (xy 363.987938 -224.925644)
			(xy 364.028335 -224.956266) (xy 364.063572 -224.992709) (xy 364.092816 -225.034115) (xy 364.115381 -225.079509)
			(xy 364.130733 -225.12782) (xy 364.138511 -225.177912) (xy 364.138972 -225.203258) (xy 364.138493 -225.229163)
			(xy 364.13039 -225.280336) (xy 364.114379 -225.32961) (xy 364.090852 -225.375771) (xy 364.060391 -225.417681)
			(xy 364.023745 -225.454306) (xy 363.981819 -225.484745) (xy 363.935646 -225.508247) (xy 363.886363 -225.524232)
			(xy 363.835185 -225.532307) (xy 363.80928 -225.532696) (xy 363.779199 -225.532049) (xy 363.720028 -225.521182)
			(xy 363.691678 -225.511106) (xy 363.678355 -225.506485) (xy 363.650278 -225.503973) (xy 363.622583 -225.509231)
			(xy 363.59738 -225.521857) (xy 363.576588 -225.540891) (xy 363.56179 -225.564884) (xy 363.554113 -225.592007)
			(xy 363.553756 -225.606102) (xy 363.553756 -225.768662) (xy 363.572878 -225.785786) (xy 363.606078 -225.82493)
			(xy 363.63278 -225.868765) (xy 363.652331 -225.916224) (xy 363.664254 -225.966147) (xy 363.668259 -226.017318)
			(xy 363.664249 -226.068489) (xy 363.65232 -226.118411) (xy 363.632763 -226.165867) (xy 363.606057 -226.2097)
			(xy 363.572852 -226.24884) (xy 363.553756 -226.265994) (xy 363.553756 -227.396294) (xy 363.57132 -227.411952)
			(xy 363.602226 -227.447432) (xy 363.627749 -227.486961) (xy 363.647364 -227.529731) (xy 363.660671 -227.574863)
			(xy 363.667396 -227.621433) (xy 363.667802 -227.64496) (xy 363.66764 -227.659001) (xy 363.665219 -227.686978)
			(xy 363.662976 -227.70084) (xy 363.658404 -227.726748) (xy 365.689642 -229.757986) (xy 365.708692 -229.759002)
			(xy 365.735071 -229.761128) (xy 365.786699 -229.772751) (xy 365.835793 -229.792504) (xy 365.881083 -229.819877)
			(xy 365.921396 -229.854161) (xy 365.955687 -229.894467) (xy 365.983068 -229.939752) (xy 366.002831 -229.988843)
			(xy 366.014463 -230.040468) (xy 366.01654 -230.06685) (xy 366.017556 -230.0859) (xy 367.377218 -231.445562)
			(xy 367.410746 -231.42702) (xy 367.435145 -231.414243) (xy 367.487152 -231.396127) (xy 367.541452 -231.386939)
			(xy 367.568988 -231.38638) (xy 367.594777 -231.386859) (xy 367.64572 -231.394927) (xy 367.694773 -231.410865)
			(xy 367.740729 -231.434282) (xy 367.782455 -231.4646) (xy 367.818924 -231.501073) (xy 367.849237 -231.542802)
			(xy 367.872649 -231.58876) (xy 367.888582 -231.637815) (xy 367.896644 -231.688759) (xy 367.897156 -231.714548)
			(xy 367.896599 -231.742085) (xy 367.88742 -231.796388) (xy 367.869309 -231.848399) (xy 367.856516 -231.87279)
			(xy 367.837974 -231.906318) (xy 368.151918 -232.220262) (xy 368.16157 -232.224072) (xy 368.185777 -232.234432)
			(xy 368.230805 -232.261721) (xy 368.270901 -232.295848) (xy 368.305036 -232.335935) (xy 368.332335 -232.380957)
			(xy 368.342672 -232.405174) (xy 368.346482 -232.414826) (xy 369.7859 -233.854244) (xy 369.815618 -233.844592)
			(xy 369.84057 -233.836888) (xy 369.892125 -233.828598) (xy 369.918234 -233.828082) (xy 369.94402 -233.828564)
			(xy 369.994958 -233.836638) (xy 370.044005 -233.85258) (xy 370.089954 -233.875999) (xy 370.131673 -233.906318)
			(xy 370.168136 -233.942791) (xy 370.198445 -233.984518) (xy 370.221852 -234.030473) (xy 370.237782 -234.079524)
			(xy 370.245842 -234.130463) (xy 370.246402 -234.15625) (xy 370.245875 -234.182357) (xy 370.23758 -234.23391)
			(xy 370.229892 -234.258866) (xy 370.22024 -234.288584) (xy 372.206266 -236.27461) (xy 372.23065 -236.271816)
			(xy 372.239827 -236.27085) (xy 372.258253 -236.269833) (xy 372.26748 -236.269784) (xy 372.29327 -236.270288)
			(xy 372.344215 -236.278353) (xy 372.393272 -236.294289) (xy 372.439232 -236.317702) (xy 372.480964 -236.348015)
			(xy 372.51744 -236.384484) (xy 372.547763 -236.42621) (xy 372.571185 -236.472165) (xy 372.587131 -236.521218)
			(xy 372.595206 -236.572162) (xy 372.595648 -236.597952) (xy 372.595588 -236.607179) (xy 372.594571 -236.625604)
			(xy 372.593616 -236.634782) (xy 372.590822 -236.659166) (xy 373.918226 -237.98657) (xy 373.953278 -237.960916)
			(xy 373.974512 -237.94596) (xy 374.020713 -237.922235) (xy 374.070075 -237.906089) (xy 374.121366 -237.897924)
			(xy 374.147334 -237.897416) (xy 374.17312 -237.897924) (xy 374.224057 -237.905996) (xy 374.273105 -237.921937)
			(xy 374.319055 -237.945353) (xy 374.360777 -237.975669) (xy 374.397243 -238.012137) (xy 374.427556 -238.05386)
			(xy 374.45097 -238.099812) (xy 374.466908 -238.14886) (xy 374.474977 -238.199798) (xy 374.475502 -238.225584)
			(xy 374.475027 -238.250671) (xy 374.467393 -238.300261) (xy 374.4523 -238.348111) (xy 374.430099 -238.393106)
			(xy 374.401309 -238.434198) (xy 374.384316 -238.45266) (xy 374.643396 -238.71174) (xy 374.660414 -238.714026)
			(xy 374.686935 -238.718087) (xy 374.738262 -238.733705) (xy 374.786365 -238.757463) (xy 374.829964 -238.788727)
			(xy 374.867898 -238.826666) (xy 374.899157 -238.870268) (xy 374.922909 -238.918374) (xy 374.938521 -238.969702)
			(xy 374.942608 -238.99622) (xy 374.944894 -239.013238) (xy 375.36247 -239.430814) (xy 375.37973 -239.448855)
			(xy 375.40749 -239.490349) (xy 375.426606 -239.536466) (xy 375.436343 -239.58543) (xy 375.436892 -239.610392)
			(xy 375.436892 -254.509778) (xy 375.453374 -254.528099) (xy 375.481219 -254.568759) (xy 375.50267 -254.613125)
			(xy 375.517247 -254.6602) (xy 375.524621 -254.708925) (xy 375.524626 -254.758205) (xy 375.517263 -254.806932)
			(xy 375.502696 -254.85401) (xy 375.481254 -254.89838) (xy 375.453418 -254.939046) (xy 375.436892 -254.957326)
			(xy 375.436892 -256.137664) (xy 375.453368 -256.155985) (xy 375.481199 -256.196643) (xy 375.502639 -256.241005)
			(xy 375.517204 -256.288074) (xy 375.524567 -256.336792) (xy 375.524563 -256.386063) (xy 375.517191 -256.43478)
			(xy 375.502618 -256.481847) (xy 375.481172 -256.526205) (xy 375.453333 -256.566859) (xy 375.436892 -256.585212)
			(xy 375.436892 -257.765042) (xy 375.453412 -257.783374) (xy 375.481325 -257.824067) (xy 375.50283 -257.868482)
			(xy 375.517443 -257.915615) (xy 375.524834 -257.964405) (xy 375.524837 -258.013751) (xy 375.517452 -258.062542)
			(xy 375.502846 -258.109678) (xy 375.481347 -258.154095) (xy 375.45344 -258.194792) (xy 375.436892 -258.213098)
			(xy 375.436892 -259.393182) (xy 375.453374 -259.411503) (xy 375.481218 -259.452163) (xy 375.502669 -259.496529)
			(xy 375.517245 -259.543603) (xy 375.524618 -259.592328) (xy 375.524623 -259.641608) (xy 375.517259 -259.690334)
			(xy 375.502692 -259.737411) (xy 375.48125 -259.781782) (xy 375.453414 -259.822447) (xy 375.436892 -259.84073)
			(xy 375.436892 -261.021068) (xy 375.45337 -261.03939) (xy 375.481206 -261.08005) (xy 375.502652 -261.124413)
			(xy 375.517225 -261.171484) (xy 375.524599 -261.220204) (xy 375.52503 -261.244842) (xy 375.524521 -261.270626)
			(xy 375.516448 -261.321559) (xy 375.500506 -261.370602) (xy 375.477088 -261.416547) (xy 375.446772 -261.458264)
			(xy 375.410303 -261.494724) (xy 375.368579 -261.52503) (xy 375.322628 -261.548436) (xy 375.273581 -261.564366)
			(xy 375.222646 -261.572427) (xy 375.196862 -261.57301) (xy 375.172756 -261.572602) (xy 375.125058 -261.565577)
			(xy 375.078905 -261.551638) (xy 375.056908 -261.541768) (xy 375.02465 -261.526274) (xy 374.32869 -262.222234)
			(xy 374.31065 -262.239497) (xy 374.269158 -262.267261) (xy 374.22304 -262.286381) (xy 374.174074 -262.29612)
			(xy 374.149112 -262.296656) (xy 374.013222 -262.296656) (xy 373.994807 -262.31349) (xy 373.953837 -262.34196)
			(xy 373.909033 -262.363907) (xy 373.861424 -262.378825) (xy 373.812107 -262.386371) (xy 373.762217 -262.386371)
			(xy 373.7129 -262.378825) (xy 373.665291 -262.363907) (xy 373.620487 -262.34196) (xy 373.579517 -262.31349)
			(xy 373.561102 -262.296656) (xy 373.073676 -262.296656) (xy 373.055261 -262.31349) (xy 373.014291 -262.34196)
			(xy 372.969487 -262.363907) (xy 372.921878 -262.378825) (xy 372.872561 -262.386371) (xy 372.822671 -262.386371)
			(xy 372.773354 -262.378825) (xy 372.725745 -262.363907) (xy 372.680941 -262.34196) (xy 372.639971 -262.31349)
			(xy 372.621556 -262.296656) (xy 372.133876 -262.296656) (xy 372.115461 -262.31349) (xy 372.074491 -262.34196)
			(xy 372.029687 -262.363907) (xy 371.982078 -262.378825) (xy 371.932761 -262.386371) (xy 371.882871 -262.386371)
			(xy 371.833554 -262.378825) (xy 371.785945 -262.363907) (xy 371.741141 -262.34196) (xy 371.700171 -262.31349)
			(xy 371.681756 -262.296656) (xy 371.193822 -262.296656) (xy 371.175407 -262.31349) (xy 371.134437 -262.34196)
			(xy 371.089633 -262.363907) (xy 371.042024 -262.378825) (xy 370.992707 -262.386371) (xy 370.942817 -262.386371)
			(xy 370.8935 -262.378825) (xy 370.845891 -262.363907) (xy 370.801087 -262.34196) (xy 370.760117 -262.31349)
			(xy 370.741702 -262.296656) (xy 370.254276 -262.296656) (xy 370.235861 -262.313489) (xy 370.194892 -262.341957)
			(xy 370.150087 -262.363899) (xy 370.102478 -262.37881) (xy 370.053161 -262.386346) (xy 370.028216 -262.386826)
			(xy 370.003047 -262.386369) (xy 369.9533 -262.378681) (xy 369.905311 -262.363484) (xy 369.860207 -262.341134)
			(xy 369.819047 -262.312155) (xy 369.782797 -262.277229) (xy 369.752308 -262.237175) (xy 369.728296 -262.192933)
			(xy 369.719352 -262.169402) (xy 369.703844 -262.168181) (xy 369.674081 -262.159165) (xy 369.64738 -262.14322)
			(xy 369.63604 -262.132572) (xy 369.546632 -262.043164) (xy 369.546124 -262.043164) (xy 369.293648 -261.790688)
			(xy 369.293648 -261.582154) (xy 369.270459 -261.563305) (xy 369.22902 -261.520249) (xy 369.193961 -261.471857)
			(xy 369.165961 -261.419064) (xy 369.145564 -261.362896) (xy 369.133164 -261.304439) (xy 369.129001 -261.244826)
			(xy 369.133157 -261.185213) (xy 369.14555 -261.126754) (xy 369.16594 -261.070583) (xy 369.193933 -261.017788)
			(xy 369.228987 -260.969391) (xy 369.270421 -260.92633) (xy 369.293648 -260.90753) (xy 369.293648 -260.520434)
			(xy 369.205764 -260.43255) (xy 369.053618 -260.43255) (xy 368.787934 -260.698234) (xy 368.769893 -260.715493)
			(xy 368.728399 -260.743247) (xy 368.68228 -260.762357) (xy 368.633317 -260.772086) (xy 368.608356 -260.772656)
			(xy 366.874044 -260.772656) (xy 366.728756 -260.917944) (xy 366.728756 -263.053322) (xy 366.763554 -263.065006)
			(xy 366.78768 -263.073599) (xy 366.833129 -263.097199) (xy 366.87436 -263.127573) (xy 366.910373 -263.163984)
			(xy 366.940292 -263.205546) (xy 366.963392 -263.251252) (xy 366.979111 -263.299991) (xy 366.987069 -263.35058)
			(xy 366.987071 -263.401792) (xy 366.979118 -263.452382) (xy 366.963402 -263.501122) (xy 366.940307 -263.54683)
			(xy 366.910391 -263.588395) (xy 366.874381 -263.624808) (xy 366.833153 -263.655186) (xy 366.787706 -263.67879)
			(xy 366.763554 -263.687306) (xy 366.728756 -263.69899) (xy 366.728756 -270.016478) (xy 367.416334 -270.704056)
			(xy 367.563146 -270.704056)
		)
		(stroke
			(width 0)
			(type solid)
		)
		(fill yes)
		(layer "In9.Cu")
		(net "PVCCINFAON_CPU0")
	)
	(gr_poly
		(pts
			(xy 429.35144 -351.388172) (xy 429.334781 -351.368584) (xy 429.306689 -351.325514) (xy 429.285089 -351.27885)
			(xy 429.270431 -351.229562) (xy 429.26302 -351.178678) (xy 429.26254 -351.152968) (xy 429.263011 -351.125641)
			(xy 429.271316 -351.071622) (xy 429.287787 -351.01951) (xy 429.312036 -350.97053) (xy 429.343492 -350.925837)
			(xy 429.362108 -350.905826) (xy 429.372503 -350.894206) (xy 429.386324 -350.866275) (xy 429.391074 -350.835477)
			(xy 429.38631 -350.80468) (xy 429.372477 -350.776756) (xy 429.362108 -350.76511) (xy 429.343545 -350.745058)
			(xy 429.312118 -350.700359) (xy 429.287882 -350.651387) (xy 429.271404 -350.59929) (xy 429.26307 -350.545288)
			(xy 429.26254 -350.517968) (xy 429.263011 -350.490641) (xy 429.271316 -350.436622) (xy 429.287787 -350.38451)
			(xy 429.312036 -350.33553) (xy 429.343492 -350.290837) (xy 429.362108 -350.270826) (xy 429.372503 -350.259206)
			(xy 429.386324 -350.231275) (xy 429.391074 -350.200477) (xy 429.38631 -350.16968) (xy 429.372477 -350.141756)
			(xy 429.362108 -350.13011) (xy 429.343545 -350.110058) (xy 429.312118 -350.065359) (xy 429.287882 -350.016387)
			(xy 429.271404 -349.96429) (xy 429.26307 -349.910288) (xy 429.26254 -349.882968) (xy 429.263011 -349.855641)
			(xy 429.271316 -349.801622) (xy 429.287787 -349.74951) (xy 429.312036 -349.70053) (xy 429.343492 -349.655837)
			(xy 429.362108 -349.635826) (xy 429.372503 -349.624206) (xy 429.386324 -349.596275) (xy 429.391074 -349.565477)
			(xy 429.38631 -349.53468) (xy 429.372477 -349.506756) (xy 429.362108 -349.49511) (xy 429.343545 -349.475058)
			(xy 429.312118 -349.430359) (xy 429.287882 -349.381387) (xy 429.271404 -349.32929) (xy 429.26307 -349.275288)
			(xy 429.26254 -349.247968) (xy 429.263011 -349.220641) (xy 429.271316 -349.166622) (xy 429.287787 -349.11451)
			(xy 429.312036 -349.06553) (xy 429.343492 -349.020837) (xy 429.362108 -349.000826) (xy 429.372503 -348.989206)
			(xy 429.386324 -348.961275) (xy 429.391074 -348.930477) (xy 429.38631 -348.89968) (xy 429.372477 -348.871756)
			(xy 429.362108 -348.86011) (xy 429.343545 -348.840058) (xy 429.312118 -348.795359) (xy 429.287882 -348.746387)
			(xy 429.271404 -348.69429) (xy 429.26307 -348.640288) (xy 429.26254 -348.612968) (xy 429.263011 -348.585641)
			(xy 429.271316 -348.531622) (xy 429.287787 -348.47951) (xy 429.312036 -348.43053) (xy 429.343492 -348.385837)
			(xy 429.362108 -348.365826) (xy 429.372503 -348.354206) (xy 429.386324 -348.326275) (xy 429.391074 -348.295477)
			(xy 429.38631 -348.26468) (xy 429.372477 -348.236756) (xy 429.362108 -348.22511) (xy 429.343545 -348.205058)
			(xy 429.312118 -348.160359) (xy 429.287882 -348.111387) (xy 429.271404 -348.05929) (xy 429.26307 -348.005288)
			(xy 429.26254 -347.977968) (xy 429.263011 -347.950641) (xy 429.271316 -347.896622) (xy 429.287787 -347.84451)
			(xy 429.312036 -347.79553) (xy 429.343492 -347.750837) (xy 429.362108 -347.730826) (xy 429.372503 -347.719206)
			(xy 429.386324 -347.691275) (xy 429.391074 -347.660477) (xy 429.38631 -347.62968) (xy 429.372477 -347.601756)
			(xy 429.362108 -347.59011) (xy 429.343545 -347.570058) (xy 429.312118 -347.525359) (xy 429.287882 -347.476387)
			(xy 429.271404 -347.42429) (xy 429.26307 -347.370288) (xy 429.26254 -347.342968) (xy 429.262995 -347.316935)
			(xy 429.270585 -347.265424) (xy 429.285597 -347.215569) (xy 429.307712 -347.168432) (xy 429.336458 -347.12502)
			(xy 429.371221 -347.086258) (xy 429.41126 -347.052975) (xy 429.455721 -347.025879) (xy 429.503655 -347.005548)
			(xy 429.528732 -346.998544) (xy 429.566578 -346.988384) (xy 429.566578 -329.811634) (xy 428.931578 -329.176634)
			(xy 428.914319 -329.158593) (xy 428.886563 -329.117099) (xy 428.867452 -329.070981) (xy 428.857723 -329.022017)
			(xy 428.857156 -328.997056) (xy 428.857156 -323.726302) (xy 428.834906 -323.710964) (xy 428.794878 -323.67466)
			(xy 428.760794 -323.632724) (xy 428.733438 -323.586121) (xy 428.713437 -323.535919) (xy 428.701251 -323.483271)
			(xy 428.697159 -323.429387) (xy 428.701255 -323.375503) (xy 428.713445 -323.322856) (xy 428.73345 -323.272656)
			(xy 428.760809 -323.226054) (xy 428.794896 -323.184121) (xy 428.834927 -323.147819) (xy 428.857156 -323.13245)
			(xy 428.857156 -215.524334) (xy 428.385478 -215.052656) (xy 376.155712 -215.052656) (xy 375.821956 -215.386412)
			(xy 375.821956 -216.056718) (xy 375.836875 -216.07793) (xy 375.860534 -216.124076) (xy 375.876625 -216.173374)
			(xy 375.884747 -216.224591) (xy 375.885202 -216.25052) (xy 375.884706 -216.276444) (xy 375.876552 -216.327648)
			(xy 375.860466 -216.376938) (xy 375.836845 -216.423094) (xy 375.821956 -216.444322) (xy 375.821956 -216.645744)
			(xy 375.82248 -216.661136) (xy 375.831633 -216.690528) (xy 375.849124 -216.715859) (xy 375.873366 -216.734832)
			(xy 375.902158 -216.745723) (xy 375.932888 -216.747545) (xy 375.94794 -216.744296) (xy 375.967313 -216.739794)
			(xy 376.006793 -216.734957) (xy 376.02668 -216.734644) (xy 376.052589 -216.735125) (xy 376.10377 -216.743229)
			(xy 376.153053 -216.75924) (xy 376.199225 -216.782765) (xy 376.241147 -216.813223) (xy 376.277787 -216.849866)
			(xy 376.308244 -216.891789) (xy 376.331766 -216.937961) (xy 376.347775 -216.987245) (xy 376.355877 -217.038427)
			(xy 376.356372 -217.064336) (xy 377.576588 -217.064336) (xy 377.577096 -217.038429) (xy 377.585202 -216.987252)
			(xy 377.601214 -216.937973) (xy 377.624737 -216.891806) (xy 377.655193 -216.849887) (xy 377.691831 -216.813249)
			(xy 377.73375 -216.782793) (xy 377.779917 -216.75927) (xy 377.829196 -216.743258) (xy 377.880373 -216.735152)
			(xy 377.932187 -216.735152) (xy 377.983364 -216.743258) (xy 378.032643 -216.75927) (xy 378.07881 -216.782793)
			(xy 378.120729 -216.813249) (xy 378.157367 -216.849887) (xy 378.187823 -216.891806) (xy 378.211346 -216.937973)
			(xy 378.227358 -216.987252) (xy 378.235464 -217.038429) (xy 378.235972 -217.064336) (xy 379.456188 -217.064336)
			(xy 379.456696 -217.038429) (xy 379.464802 -216.987252) (xy 379.480814 -216.937973) (xy 379.504337 -216.891806)
			(xy 379.534793 -216.849887) (xy 379.571431 -216.813249) (xy 379.61335 -216.782793) (xy 379.659517 -216.75927)
			(xy 379.708796 -216.743258) (xy 379.759973 -216.735152) (xy 379.811787 -216.735152) (xy 379.862964 -216.743258)
			(xy 379.912243 -216.75927) (xy 379.95841 -216.782793) (xy 380.000329 -216.813249) (xy 380.036967 -216.849887)
			(xy 380.067423 -216.891806) (xy 380.090946 -216.937973) (xy 380.106958 -216.987252) (xy 380.115064 -217.038429)
			(xy 380.115572 -217.064336) (xy 381.335788 -217.064336) (xy 381.336296 -217.038429) (xy 381.344402 -216.987252)
			(xy 381.360414 -216.937973) (xy 381.383937 -216.891806) (xy 381.414393 -216.849887) (xy 381.451031 -216.813249)
			(xy 381.49295 -216.782793) (xy 381.539117 -216.75927) (xy 381.588396 -216.743258) (xy 381.639573 -216.735152)
			(xy 381.691387 -216.735152) (xy 381.742564 -216.743258) (xy 381.791843 -216.75927) (xy 381.83801 -216.782793)
			(xy 381.879929 -216.813249) (xy 381.916567 -216.849887) (xy 381.947023 -216.891806) (xy 381.970546 -216.937973)
			(xy 381.986558 -216.987252) (xy 381.994664 -217.038429) (xy 381.995172 -217.064336) (xy 381.994559 -217.091989)
			(xy 381.985238 -217.146507) (xy 381.97663 -217.172794) (xy 381.96901 -217.194892) (xy 382.174242 -217.550238)
			(xy 382.197102 -217.554556) (xy 382.221903 -217.559751) (xy 382.269642 -217.57674) (xy 382.314219 -217.600833)
			(xy 382.354584 -217.631463) (xy 382.389788 -217.667908) (xy 382.419 -217.709312) (xy 382.441533 -217.754697)
			(xy 382.456856 -217.802996) (xy 382.464608 -217.85307) (xy 382.465072 -217.878406) (xy 382.464564 -217.904293)
			(xy 382.456465 -217.955431) (xy 382.440466 -218.004671) (xy 382.41696 -218.050803) (xy 382.386528 -218.09269)
			(xy 382.349918 -218.1293) (xy 382.308031 -218.159732) (xy 382.261899 -218.183238) (xy 382.212659 -218.199237)
			(xy 382.161521 -218.207336) (xy 382.109747 -218.207336) (xy 382.058609 -218.199237) (xy 382.009369 -218.183238)
			(xy 381.963237 -218.159732) (xy 381.92135 -218.1293) (xy 381.88474 -218.09269) (xy 381.854308 -218.050803)
			(xy 381.830802 -218.004671) (xy 381.814803 -217.955431) (xy 381.806704 -217.904293) (xy 381.806196 -217.878406)
			(xy 381.806727 -217.850698) (xy 381.815921 -217.796051) (xy 381.824484 -217.769694) (xy 381.832358 -217.747596)
			(xy 381.62738 -217.392504) (xy 381.60452 -217.388186) (xy 381.579675 -217.38302) (xy 381.531826 -217.366126)
			(xy 381.487133 -217.342096) (xy 381.446653 -217.311499) (xy 381.411341 -217.275058) (xy 381.382033 -217.233634)
			(xy 381.359422 -217.188207) (xy 381.344043 -217.13985) (xy 381.336258 -217.089708) (xy 381.335788 -217.064336)
			(xy 380.115572 -217.064336) (xy 380.114959 -217.091989) (xy 380.105638 -217.146507) (xy 380.09703 -217.172794)
			(xy 380.08941 -217.194892) (xy 380.294642 -217.550238) (xy 380.317502 -217.554556) (xy 380.342303 -217.559751)
			(xy 380.390042 -217.57674) (xy 380.434619 -217.600833) (xy 380.474984 -217.631463) (xy 380.510188 -217.667908)
			(xy 380.5394 -217.709312) (xy 380.561933 -217.754697) (xy 380.577256 -217.802996) (xy 380.585008 -217.85307)
			(xy 380.585472 -217.878406) (xy 380.584964 -217.904293) (xy 380.576865 -217.955431) (xy 380.560866 -218.004671)
			(xy 380.53736 -218.050803) (xy 380.506928 -218.09269) (xy 380.470318 -218.1293) (xy 380.428431 -218.159732)
			(xy 380.382299 -218.183238) (xy 380.333059 -218.199237) (xy 380.281921 -218.207336) (xy 380.230147 -218.207336)
			(xy 380.179009 -218.199237) (xy 380.129769 -218.183238) (xy 380.083637 -218.159732) (xy 380.04175 -218.1293)
			(xy 380.00514 -218.09269) (xy 379.974708 -218.050803) (xy 379.951202 -218.004671) (xy 379.935203 -217.955431)
			(xy 379.927104 -217.904293) (xy 379.926596 -217.878406) (xy 379.927127 -217.850698) (xy 379.936321 -217.796051)
			(xy 379.944884 -217.769694) (xy 379.952758 -217.747596) (xy 379.74778 -217.392504) (xy 379.72492 -217.388186)
			(xy 379.700075 -217.38302) (xy 379.652226 -217.366126) (xy 379.607533 -217.342096) (xy 379.567053 -217.311499)
			(xy 379.531741 -217.275058) (xy 379.502433 -217.233634) (xy 379.479822 -217.188207) (xy 379.464443 -217.13985)
			(xy 379.456658 -217.089708) (xy 379.456188 -217.064336) (xy 378.235972 -217.064336) (xy 378.235359 -217.091989)
			(xy 378.226038 -217.146507) (xy 378.21743 -217.172794) (xy 378.20981 -217.194892) (xy 378.415042 -217.550238)
			(xy 378.437902 -217.554556) (xy 378.462703 -217.559751) (xy 378.510442 -217.57674) (xy 378.555019 -217.600833)
			(xy 378.595384 -217.631463) (xy 378.630588 -217.667908) (xy 378.6598 -217.709312) (xy 378.682333 -217.754697)
			(xy 378.697656 -217.802996) (xy 378.705408 -217.85307) (xy 378.705872 -217.878406) (xy 378.705364 -217.904293)
			(xy 378.697265 -217.955431) (xy 378.681266 -218.004671) (xy 378.65776 -218.050803) (xy 378.627328 -218.09269)
			(xy 378.590718 -218.1293) (xy 378.548831 -218.159732) (xy 378.502699 -218.183238) (xy 378.453459 -218.199237)
			(xy 378.402321 -218.207336) (xy 378.350547 -218.207336) (xy 378.299409 -218.199237) (xy 378.250169 -218.183238)
			(xy 378.204037 -218.159732) (xy 378.16215 -218.1293) (xy 378.12554 -218.09269) (xy 378.095108 -218.050803)
			(xy 378.071602 -218.004671) (xy 378.055603 -217.955431) (xy 378.047504 -217.904293) (xy 378.046996 -217.878406)
			(xy 378.047527 -217.850698) (xy 378.056721 -217.796051) (xy 378.065284 -217.769694) (xy 378.073158 -217.747596)
			(xy 377.86818 -217.392504) (xy 377.84532 -217.388186) (xy 377.820475 -217.38302) (xy 377.772626 -217.366126)
			(xy 377.727933 -217.342096) (xy 377.687453 -217.311499) (xy 377.652141 -217.275058) (xy 377.622833 -217.233634)
			(xy 377.600222 -217.188207) (xy 377.584843 -217.13985) (xy 377.577058 -217.089708) (xy 377.576588 -217.064336)
			(xy 376.356372 -217.064336) (xy 376.355769 -217.091991) (xy 376.346452 -217.146511) (xy 376.33783 -217.172794)
			(xy 376.33021 -217.194892) (xy 376.535442 -217.550238) (xy 376.558302 -217.554556) (xy 376.583103 -217.559754)
			(xy 376.630841 -217.576742) (xy 376.675418 -217.600835) (xy 376.715783 -217.631464) (xy 376.750986 -217.66791)
			(xy 376.780198 -217.709313) (xy 376.802731 -217.754698) (xy 376.818054 -217.802996) (xy 376.825806 -217.853071)
			(xy 376.826272 -217.878406) (xy 376.825764 -217.904293) (xy 376.817665 -217.955431) (xy 376.801666 -218.004671)
			(xy 376.77816 -218.050803) (xy 376.747728 -218.09269) (xy 376.711118 -218.1293) (xy 376.669231 -218.159732)
			(xy 376.623099 -218.183238) (xy 376.573859 -218.199237) (xy 376.522721 -218.207336) (xy 376.470947 -218.207336)
			(xy 376.419809 -218.199237) (xy 376.370569 -218.183238) (xy 376.324437 -218.159732) (xy 376.28255 -218.1293)
			(xy 376.24594 -218.09269) (xy 376.215508 -218.050803) (xy 376.192002 -218.004671) (xy 376.176003 -217.955431)
			(xy 376.167904 -217.904293) (xy 376.167396 -217.878406) (xy 376.167925 -217.850698) (xy 376.177125 -217.796052)
			(xy 376.185684 -217.769694) (xy 376.193558 -217.747596) (xy 375.98858 -217.392504) (xy 375.96572 -217.388186)
			(xy 375.94794 -217.384376) (xy 375.932884 -217.381206) (xy 375.902187 -217.383052) (xy 375.873428 -217.393945)
			(xy 375.84921 -217.412898) (xy 375.831726 -217.438197) (xy 375.822558 -217.467552) (xy 375.821956 -217.482928)
			(xy 375.821956 -217.682318) (xy 375.837155 -217.703739) (xy 375.861276 -217.750393) (xy 375.877688 -217.800283)
			(xy 375.885975 -217.852145) (xy 375.886472 -217.878406) (xy 375.885977 -217.904665) (xy 375.877676 -217.956523)
			(xy 375.861254 -218.006407) (xy 375.837127 -218.053054) (xy 375.821956 -218.074494) (xy 375.821956 -218.692222)
			(xy 376.636788 -218.692222) (xy 376.637339 -218.66688) (xy 376.645107 -218.616793) (xy 376.660448 -218.568485)
			(xy 376.683001 -218.523094) (xy 376.712234 -218.481689) (xy 376.747459 -218.445245) (xy 376.787846 -218.41462)
			(xy 376.832444 -218.390537) (xy 376.880202 -218.373561) (xy 376.905012 -218.368372) (xy 376.927872 -218.364054)
			(xy 377.133104 -218.008708) (xy 377.12523 -217.98661) (xy 377.116761 -217.960367) (xy 377.107692 -217.905977)
			(xy 377.107196 -217.878406) (xy 377.107704 -217.852519) (xy 377.115803 -217.801381) (xy 377.131802 -217.752141)
			(xy 377.155308 -217.706009) (xy 377.18574 -217.664122) (xy 377.22235 -217.627512) (xy 377.264237 -217.59708)
			(xy 377.310369 -217.573574) (xy 377.359609 -217.557575) (xy 377.410747 -217.549476) (xy 377.462521 -217.549476)
			(xy 377.513659 -217.557575) (xy 377.562899 -217.573574) (xy 377.609031 -217.59708) (xy 377.650918 -217.627512)
			(xy 377.687528 -217.664122) (xy 377.71796 -217.706009) (xy 377.741466 -217.752141) (xy 377.757465 -217.801381)
			(xy 377.765564 -217.852519) (xy 377.766072 -217.878406) (xy 377.765625 -217.903782) (xy 377.757855 -217.953934)
			(xy 377.742485 -218.002302) (xy 377.719877 -218.047739) (xy 377.690567 -218.089171) (xy 377.65525 -218.125617)
			(xy 377.61476 -218.156215) (xy 377.570056 -218.18024) (xy 377.522196 -218.197124) (xy 377.49734 -218.202256)
			(xy 377.47448 -218.206574) (xy 377.269756 -218.561412) (xy 377.27763 -218.583256) (xy 377.286281 -218.609663)
			(xy 377.295598 -218.66444) (xy 377.296172 -218.692222) (xy 378.516388 -218.692222) (xy 378.516939 -218.66688)
			(xy 378.524707 -218.616793) (xy 378.540048 -218.568485) (xy 378.562601 -218.523094) (xy 378.591834 -218.481689)
			(xy 378.627059 -218.445245) (xy 378.667446 -218.41462) (xy 378.712044 -218.390537) (xy 378.759802 -218.373561)
			(xy 378.784612 -218.368372) (xy 378.807472 -218.364054) (xy 379.012704 -218.008708) (xy 379.00483 -217.98661)
			(xy 378.996361 -217.960367) (xy 378.987292 -217.905977) (xy 378.986796 -217.878406) (xy 378.987304 -217.852519)
			(xy 378.995403 -217.801381) (xy 379.011402 -217.752141) (xy 379.034908 -217.706009) (xy 379.06534 -217.664122)
			(xy 379.10195 -217.627512) (xy 379.143837 -217.59708) (xy 379.189969 -217.573574) (xy 379.239209 -217.557575)
			(xy 379.290347 -217.549476) (xy 379.342121 -217.549476) (xy 379.393259 -217.557575) (xy 379.442499 -217.573574)
			(xy 379.488631 -217.59708) (xy 379.530518 -217.627512) (xy 379.567128 -217.664122) (xy 379.59756 -217.706009)
			(xy 379.621066 -217.752141) (xy 379.637065 -217.801381) (xy 379.645164 -217.852519) (xy 379.645672 -217.878406)
			(xy 379.645225 -217.903782) (xy 379.637455 -217.953934) (xy 379.622085 -218.002302) (xy 379.599477 -218.047739)
			(xy 379.570167 -218.089171) (xy 379.53485 -218.125617) (xy 379.49436 -218.156215) (xy 379.449656 -218.18024)
			(xy 379.401796 -218.197124) (xy 379.37694 -218.202256) (xy 379.35408 -218.206574) (xy 379.149356 -218.561412)
			(xy 379.15723 -218.583256) (xy 379.165881 -218.609663) (xy 379.175198 -218.66444) (xy 379.175772 -218.692222)
			(xy 380.395988 -218.692222) (xy 380.396539 -218.66688) (xy 380.404307 -218.616793) (xy 380.419648 -218.568485)
			(xy 380.442201 -218.523094) (xy 380.471434 -218.481689) (xy 380.506659 -218.445245) (xy 380.547046 -218.41462)
			(xy 380.591644 -218.390537) (xy 380.639402 -218.373561) (xy 380.664212 -218.368372) (xy 380.687072 -218.364054)
			(xy 380.892304 -218.008708) (xy 380.88443 -217.98661) (xy 380.875961 -217.960367) (xy 380.866892 -217.905977)
			(xy 380.866396 -217.878406) (xy 380.866904 -217.852519) (xy 380.875003 -217.801381) (xy 380.891002 -217.752141)
			(xy 380.914508 -217.706009) (xy 380.94494 -217.664122) (xy 380.98155 -217.627512) (xy 381.023437 -217.59708)
			(xy 381.069569 -217.573574) (xy 381.118809 -217.557575) (xy 381.169947 -217.549476) (xy 381.221721 -217.549476)
			(xy 381.272859 -217.557575) (xy 381.322099 -217.573574) (xy 381.368231 -217.59708) (xy 381.410118 -217.627512)
			(xy 381.446728 -217.664122) (xy 381.47716 -217.706009) (xy 381.500666 -217.752141) (xy 381.516665 -217.801381)
			(xy 381.524764 -217.852519) (xy 381.525272 -217.878406) (xy 381.524825 -217.903782) (xy 381.517055 -217.953934)
			(xy 381.501685 -218.002302) (xy 381.479077 -218.047739) (xy 381.449767 -218.089171) (xy 381.41445 -218.125617)
			(xy 381.37396 -218.156215) (xy 381.329256 -218.18024) (xy 381.281396 -218.197124) (xy 381.25654 -218.202256)
			(xy 381.23368 -218.206574) (xy 381.028956 -218.561412) (xy 381.03683 -218.583256) (xy 381.045481 -218.609663)
			(xy 381.054798 -218.66444) (xy 381.055372 -218.692222) (xy 381.054864 -218.718129) (xy 381.046758 -218.769306)
			(xy 381.030746 -218.818585) (xy 381.007223 -218.864752) (xy 380.976767 -218.906671) (xy 380.940129 -218.943309)
			(xy 380.89821 -218.973765) (xy 380.852043 -218.997288) (xy 380.802764 -219.0133) (xy 380.751587 -219.021406)
			(xy 380.699773 -219.021406) (xy 380.648596 -219.0133) (xy 380.599317 -218.997288) (xy 380.55315 -218.973765)
			(xy 380.511231 -218.943309) (xy 380.474593 -218.906671) (xy 380.444137 -218.864752) (xy 380.420614 -218.818585)
			(xy 380.404602 -218.769306) (xy 380.396496 -218.718129) (xy 380.395988 -218.692222) (xy 379.175772 -218.692222)
			(xy 379.175264 -218.718129) (xy 379.167158 -218.769306) (xy 379.151146 -218.818585) (xy 379.127623 -218.864752)
			(xy 379.097167 -218.906671) (xy 379.060529 -218.943309) (xy 379.01861 -218.973765) (xy 378.972443 -218.997288)
			(xy 378.923164 -219.0133) (xy 378.871987 -219.021406) (xy 378.820173 -219.021406) (xy 378.768996 -219.0133)
			(xy 378.719717 -218.997288) (xy 378.67355 -218.973765) (xy 378.631631 -218.943309) (xy 378.594993 -218.906671)
			(xy 378.564537 -218.864752) (xy 378.541014 -218.818585) (xy 378.525002 -218.769306) (xy 378.516896 -218.718129)
			(xy 378.516388 -218.692222) (xy 377.296172 -218.692222) (xy 377.295664 -218.718129) (xy 377.287558 -218.769306)
			(xy 377.271546 -218.818585) (xy 377.248023 -218.864752) (xy 377.217567 -218.906671) (xy 377.180929 -218.943309)
			(xy 377.13901 -218.973765) (xy 377.092843 -218.997288) (xy 377.043564 -219.0133) (xy 376.992387 -219.021406)
			(xy 376.940573 -219.021406) (xy 376.889396 -219.0133) (xy 376.840117 -218.997288) (xy 376.79395 -218.973765)
			(xy 376.752031 -218.943309) (xy 376.715393 -218.906671) (xy 376.684937 -218.864752) (xy 376.661414 -218.818585)
			(xy 376.645402 -218.769306) (xy 376.637296 -218.718129) (xy 376.636788 -218.692222) (xy 375.821956 -218.692222)
			(xy 375.821956 -219.312236) (xy 375.836874 -219.333449) (xy 375.86053 -219.379595) (xy 375.876619 -219.428892)
			(xy 375.884738 -219.480109) (xy 375.885202 -219.506038) (xy 375.884705 -219.531962) (xy 375.876548 -219.583164)
			(xy 375.86046 -219.632453) (xy 375.836837 -219.678607) (xy 375.821956 -219.69984) (xy 375.821956 -219.901262)
			(xy 375.822483 -219.916652) (xy 375.831638 -219.946039) (xy 375.84913 -219.971366) (xy 375.87337 -219.990334)
			(xy 375.902159 -220.001224) (xy 375.932885 -220.003045) (xy 375.94794 -219.999814) (xy 375.967319 -219.995369)
			(xy 376.006799 -219.990653) (xy 376.02668 -219.990416) (xy 376.052575 -219.990922) (xy 376.10373 -219.999017)
			(xy 376.152989 -220.015012) (xy 376.199141 -220.038512) (xy 376.241051 -220.06894) (xy 376.277687 -220.105547)
			(xy 376.308149 -220.147432) (xy 376.331686 -220.193565) (xy 376.347721 -220.242811) (xy 376.355857 -220.293959)
			(xy 376.356372 -220.319854) (xy 377.576588 -220.319854) (xy 377.577096 -220.293947) (xy 377.585202 -220.24277)
			(xy 377.601214 -220.193491) (xy 377.624737 -220.147324) (xy 377.655193 -220.105405) (xy 377.691831 -220.068767)
			(xy 377.73375 -220.038311) (xy 377.779917 -220.014788) (xy 377.829196 -219.998776) (xy 377.880373 -219.99067)
			(xy 377.932187 -219.99067) (xy 377.983364 -219.998776) (xy 378.032643 -220.014788) (xy 378.07881 -220.038311)
			(xy 378.120729 -220.068767) (xy 378.157367 -220.105405) (xy 378.187823 -220.147324) (xy 378.211346 -220.193491)
			(xy 378.227358 -220.24277) (xy 378.235464 -220.293947) (xy 378.235972 -220.319854) (xy 379.456188 -220.319854)
			(xy 379.456696 -220.293947) (xy 379.464802 -220.24277) (xy 379.480814 -220.193491) (xy 379.504337 -220.147324)
			(xy 379.534793 -220.105405) (xy 379.571431 -220.068767) (xy 379.61335 -220.038311) (xy 379.659517 -220.014788)
			(xy 379.708796 -219.998776) (xy 379.759973 -219.99067) (xy 379.811787 -219.99067) (xy 379.862964 -219.998776)
			(xy 379.912243 -220.014788) (xy 379.95841 -220.038311) (xy 380.000329 -220.068767) (xy 380.036967 -220.105405)
			(xy 380.067423 -220.147324) (xy 380.090946 -220.193491) (xy 380.106958 -220.24277) (xy 380.115064 -220.293947)
			(xy 380.115572 -220.319854) (xy 381.336296 -220.319854) (xy 381.336804 -220.293967) (xy 381.344903 -220.242829)
			(xy 381.360902 -220.193589) (xy 381.384408 -220.147457) (xy 381.41484 -220.10557) (xy 381.45145 -220.06896)
			(xy 381.493337 -220.038528) (xy 381.539469 -220.015022) (xy 381.588709 -219.999023) (xy 381.639847 -219.990924)
			(xy 381.691621 -219.990924) (xy 381.742759 -219.999023) (xy 381.791999 -220.015022) (xy 381.838131 -220.038528)
			(xy 381.880018 -220.06896) (xy 381.916628 -220.10557) (xy 381.94706 -220.147457) (xy 381.970566 -220.193589)
			(xy 381.986565 -220.242829) (xy 381.994664 -220.293967) (xy 381.995172 -220.319854) (xy 381.994628 -220.347561)
			(xy 381.985442 -220.402208) (xy 381.976884 -220.428566) (xy 381.969264 -220.450664) (xy 382.174242 -220.805756)
			(xy 382.197102 -220.810074) (xy 382.221908 -220.815252) (xy 382.269647 -220.832242) (xy 382.314225 -220.856337)
			(xy 382.354591 -220.886969) (xy 382.389795 -220.923417) (xy 382.419006 -220.964822) (xy 382.441538 -221.01021)
			(xy 382.45686 -221.058511) (xy 382.46461 -221.108588) (xy 382.465072 -221.133924) (xy 382.464564 -221.159811)
			(xy 382.456465 -221.210949) (xy 382.440466 -221.260189) (xy 382.41696 -221.306321) (xy 382.386528 -221.348208)
			(xy 382.349918 -221.384818) (xy 382.308031 -221.41525) (xy 382.261899 -221.438756) (xy 382.212659 -221.454755)
			(xy 382.161521 -221.462854) (xy 382.109747 -221.462854) (xy 382.058609 -221.454755) (xy 382.009369 -221.438756)
			(xy 381.963237 -221.41525) (xy 381.92135 -221.384818) (xy 381.88474 -221.348208) (xy 381.854308 -221.306321)
			(xy 381.830802 -221.260189) (xy 381.814803 -221.210949) (xy 381.806704 -221.159811) (xy 381.806196 -221.133924)
			(xy 381.806732 -221.106216) (xy 381.815923 -221.051569) (xy 381.824484 -221.025212) (xy 381.832358 -221.003114)
			(xy 381.62738 -220.648022) (xy 381.60452 -220.643704) (xy 381.579694 -220.638559) (xy 381.531915 -220.6216)
			(xy 381.487296 -220.597525) (xy 381.446891 -220.566902) (xy 381.41165 -220.530452) (xy 381.382408 -220.489036)
			(xy 381.359851 -220.44363) (xy 381.344514 -220.395306) (xy 381.336758 -220.345204) (xy 381.336296 -220.319854)
			(xy 380.115572 -220.319854) (xy 380.114963 -220.347508) (xy 380.105639 -220.402026) (xy 380.09703 -220.428312)
			(xy 380.08941 -220.45041) (xy 380.294642 -220.805756) (xy 380.317502 -220.810074) (xy 380.342308 -220.815252)
			(xy 380.390047 -220.832242) (xy 380.434625 -220.856337) (xy 380.474991 -220.886969) (xy 380.510195 -220.923417)
			(xy 380.539406 -220.964822) (xy 380.561938 -221.01021) (xy 380.57726 -221.058511) (xy 380.58501 -221.108588)
			(xy 380.585472 -221.133924) (xy 380.584964 -221.159811) (xy 380.576865 -221.210949) (xy 380.560866 -221.260189)
			(xy 380.53736 -221.306321) (xy 380.506928 -221.348208) (xy 380.470318 -221.384818) (xy 380.428431 -221.41525)
			(xy 380.382299 -221.438756) (xy 380.333059 -221.454755) (xy 380.281921 -221.462854) (xy 380.230147 -221.462854)
			(xy 380.179009 -221.454755) (xy 380.129769 -221.438756) (xy 380.083637 -221.41525) (xy 380.04175 -221.384818)
			(xy 380.00514 -221.348208) (xy 379.974708 -221.306321) (xy 379.951202 -221.260189) (xy 379.935203 -221.210949)
			(xy 379.927104 -221.159811) (xy 379.926596 -221.133924) (xy 379.927132 -221.106216) (xy 379.936323 -221.051569)
			(xy 379.944884 -221.025212) (xy 379.952758 -221.003114) (xy 379.74778 -220.648022) (xy 379.72492 -220.643704)
			(xy 379.700079 -220.638521) (xy 379.652232 -220.621628) (xy 379.60754 -220.5976) (xy 379.567059 -220.567005)
			(xy 379.531748 -220.530566) (xy 379.502439 -220.489145) (xy 379.479827 -220.44372) (xy 379.464446 -220.395365)
			(xy 379.456659 -220.345225) (xy 379.456188 -220.319854) (xy 378.235972 -220.319854) (xy 378.235363 -220.347508)
			(xy 378.226039 -220.402026) (xy 378.21743 -220.428312) (xy 378.20981 -220.45041) (xy 378.415042 -220.805756)
			(xy 378.437902 -220.810074) (xy 378.462708 -220.815252) (xy 378.510447 -220.832242) (xy 378.555025 -220.856337)
			(xy 378.595391 -220.886969) (xy 378.630595 -220.923417) (xy 378.659806 -220.964822) (xy 378.682338 -221.01021)
			(xy 378.69766 -221.058511) (xy 378.70541 -221.108588) (xy 378.705872 -221.133924) (xy 378.705364 -221.159811)
			(xy 378.697265 -221.210949) (xy 378.681266 -221.260189) (xy 378.65776 -221.306321) (xy 378.627328 -221.348208)
			(xy 378.590718 -221.384818) (xy 378.548831 -221.41525) (xy 378.502699 -221.438756) (xy 378.453459 -221.454755)
			(xy 378.402321 -221.462854) (xy 378.350547 -221.462854) (xy 378.299409 -221.454755) (xy 378.250169 -221.438756)
			(xy 378.204037 -221.41525) (xy 378.16215 -221.384818) (xy 378.12554 -221.348208) (xy 378.095108 -221.306321)
			(xy 378.071602 -221.260189) (xy 378.055603 -221.210949) (xy 378.047504 -221.159811) (xy 378.046996 -221.133924)
			(xy 378.047532 -221.106216) (xy 378.056723 -221.051569) (xy 378.065284 -221.025212) (xy 378.073158 -221.003114)
			(xy 377.86818 -220.648022) (xy 377.84532 -220.643704) (xy 377.820479 -220.638521) (xy 377.772632 -220.621628)
			(xy 377.72794 -220.5976) (xy 377.687459 -220.567005) (xy 377.652148 -220.530566) (xy 377.622839 -220.489145)
			(xy 377.600227 -220.44372) (xy 377.584846 -220.395365) (xy 377.577059 -220.345225) (xy 377.576588 -220.319854)
			(xy 376.356372 -220.319854) (xy 376.355767 -220.347508) (xy 376.346448 -220.402028) (xy 376.33783 -220.428312)
			(xy 376.33021 -220.45041) (xy 376.535442 -220.805756) (xy 376.558302 -220.810074) (xy 376.583102 -220.815272)
			(xy 376.630839 -220.83226) (xy 376.675414 -220.856354) (xy 376.715778 -220.886984) (xy 376.750979 -220.923429)
			(xy 376.780189 -220.964832) (xy 376.80272 -221.010217) (xy 376.81804 -221.058515) (xy 376.82579 -221.108589)
			(xy 376.826272 -221.133924) (xy 376.825764 -221.159811) (xy 376.817665 -221.210949) (xy 376.801666 -221.260189)
			(xy 376.77816 -221.306321) (xy 376.747728 -221.348208) (xy 376.711118 -221.384818) (xy 376.669231 -221.41525)
			(xy 376.623099 -221.438756) (xy 376.573859 -221.454755) (xy 376.522721 -221.462854) (xy 376.470947 -221.462854)
			(xy 376.419809 -221.454755) (xy 376.370569 -221.438756) (xy 376.324437 -221.41525) (xy 376.28255 -221.384818)
			(xy 376.24594 -221.348208) (xy 376.215508 -221.306321) (xy 376.192002 -221.260189) (xy 376.176003 -221.210949)
			(xy 376.167904 -221.159811) (xy 376.167396 -221.133924) (xy 376.167924 -221.106216) (xy 376.17712 -221.051569)
			(xy 376.185684 -221.025212) (xy 376.193558 -221.003114) (xy 375.98858 -220.648022) (xy 375.96572 -220.643704)
			(xy 375.94794 -220.639894) (xy 375.932881 -220.636726) (xy 375.902176 -220.638572) (xy 375.873408 -220.649464)
			(xy 375.849179 -220.668414) (xy 375.831679 -220.693711) (xy 375.82249 -220.723067) (xy 375.821956 -220.738446)
			(xy 375.821956 -220.937836) (xy 375.837153 -220.959257) (xy 375.861272 -221.005911) (xy 375.877682 -221.055802)
			(xy 375.885966 -221.107664) (xy 375.886472 -221.133924) (xy 375.885983 -221.160185) (xy 375.877694 -221.212049)
			(xy 375.861282 -221.26194) (xy 375.837163 -221.308596) (xy 375.821956 -221.330012) (xy 375.821956 -221.94774)
			(xy 376.636788 -221.94774) (xy 376.637265 -221.922395) (xy 376.645045 -221.872306) (xy 376.660397 -221.823996)
			(xy 376.68296 -221.778605) (xy 376.712203 -221.7372) (xy 376.747437 -221.700757) (xy 376.787831 -221.670134)
			(xy 376.832436 -221.646052) (xy 376.880199 -221.629078) (xy 376.905012 -221.62389) (xy 376.927872 -221.619572)
			(xy 377.133104 -221.264226) (xy 377.12523 -221.242128) (xy 377.116765 -221.215883) (xy 377.107693 -221.161495)
			(xy 377.107196 -221.133924) (xy 377.107704 -221.108037) (xy 377.115803 -221.056899) (xy 377.131802 -221.007659)
			(xy 377.155308 -220.961527) (xy 377.18574 -220.91964) (xy 377.22235 -220.88303) (xy 377.264237 -220.852598)
			(xy 377.310369 -220.829092) (xy 377.359609 -220.813093) (xy 377.410747 -220.804994) (xy 377.462521 -220.804994)
			(xy 377.513659 -220.813093) (xy 377.562899 -220.829092) (xy 377.609031 -220.852598) (xy 377.650918 -220.88303)
			(xy 377.687528 -220.91964) (xy 377.71796 -220.961527) (xy 377.741466 -221.007659) (xy 377.757465 -221.056899)
			(xy 377.765564 -221.108037) (xy 377.766072 -221.133924) (xy 377.765642 -221.1593) (xy 377.757869 -221.209454)
			(xy 377.742496 -221.257821) (xy 377.719886 -221.303259) (xy 377.690574 -221.344691) (xy 377.655255 -221.381137)
			(xy 377.614763 -221.411734) (xy 377.570058 -221.435759) (xy 377.522196 -221.452643) (xy 377.49734 -221.457774)
			(xy 377.47448 -221.462092) (xy 377.269756 -221.81693) (xy 377.27763 -221.838774) (xy 377.286286 -221.865179)
			(xy 377.2956 -221.919958) (xy 377.296172 -221.94774) (xy 378.516388 -221.94774) (xy 378.516865 -221.922395)
			(xy 378.524645 -221.872306) (xy 378.539997 -221.823996) (xy 378.56256 -221.778605) (xy 378.591803 -221.7372)
			(xy 378.627037 -221.700757) (xy 378.667431 -221.670134) (xy 378.712036 -221.646052) (xy 378.759799 -221.629078)
			(xy 378.784612 -221.62389) (xy 378.807472 -221.619572) (xy 379.012704 -221.264226) (xy 379.00483 -221.242128)
			(xy 378.996365 -221.215883) (xy 378.987293 -221.161495) (xy 378.986796 -221.133924) (xy 378.987304 -221.108037)
			(xy 378.995403 -221.056899) (xy 379.011402 -221.007659) (xy 379.034908 -220.961527) (xy 379.06534 -220.91964)
			(xy 379.10195 -220.88303) (xy 379.143837 -220.852598) (xy 379.189969 -220.829092) (xy 379.239209 -220.813093)
			(xy 379.290347 -220.804994) (xy 379.342121 -220.804994) (xy 379.393259 -220.813093) (xy 379.442499 -220.829092)
			(xy 379.488631 -220.852598) (xy 379.530518 -220.88303) (xy 379.567128 -220.91964) (xy 379.59756 -220.961527)
			(xy 379.621066 -221.007659) (xy 379.637065 -221.056899) (xy 379.645164 -221.108037) (xy 379.645672 -221.133924)
			(xy 379.645242 -221.1593) (xy 379.637469 -221.209454) (xy 379.622096 -221.257821) (xy 379.599486 -221.303259)
			(xy 379.570174 -221.344691) (xy 379.534855 -221.381137) (xy 379.494363 -221.411734) (xy 379.449658 -221.435759)
			(xy 379.401796 -221.452643) (xy 379.37694 -221.457774) (xy 379.35408 -221.462092) (xy 379.149356 -221.81693)
			(xy 379.15723 -221.838774) (xy 379.165886 -221.865179) (xy 379.1752 -221.919958) (xy 379.175772 -221.94774)
			(xy 380.395988 -221.94774) (xy 380.396465 -221.922395) (xy 380.404245 -221.872306) (xy 380.419597 -221.823996)
			(xy 380.44216 -221.778605) (xy 380.471403 -221.7372) (xy 380.506637 -221.700757) (xy 380.547031 -221.670134)
			(xy 380.591636 -221.646052) (xy 380.639399 -221.629078) (xy 380.664212 -221.62389) (xy 380.687072 -221.619572)
			(xy 380.89205 -221.263972) (xy 380.88443 -221.242128) (xy 380.875981 -221.215945) (xy 380.866909 -221.161685)
			(xy 380.866396 -221.134178) (xy 380.866396 -221.133924) (xy 380.866904 -221.108037) (xy 380.875003 -221.056899)
			(xy 380.891002 -221.007659) (xy 380.914508 -220.961527) (xy 380.94494 -220.91964) (xy 380.98155 -220.88303)
			(xy 381.023437 -220.852598) (xy 381.069569 -220.829092) (xy 381.118809 -220.813093) (xy 381.169947 -220.804994)
			(xy 381.221721 -220.804994) (xy 381.272859 -220.813093) (xy 381.322099 -220.829092) (xy 381.368231 -220.852598)
			(xy 381.410118 -220.88303) (xy 381.446728 -220.91964) (xy 381.47716 -220.961527) (xy 381.500666 -221.007659)
			(xy 381.516665 -221.056899) (xy 381.524764 -221.108037) (xy 381.525272 -221.133924) (xy 381.524879 -221.159291)
			(xy 381.517126 -221.209429) (xy 381.501775 -221.257784) (xy 381.479191 -221.303213) (xy 381.449906 -221.344642)
			(xy 381.414615 -221.381089) (xy 381.374152 -221.411694) (xy 381.329474 -221.435731) (xy 381.281638 -221.452632)
			(xy 381.256794 -221.457774) (xy 381.233934 -221.462092) (xy 381.02921 -221.81693) (xy 381.03683 -221.838774)
			(xy 381.045444 -221.865059) (xy 381.054766 -221.919578) (xy 381.055372 -221.947232) (xy 381.055372 -221.94774)
			(xy 382.275588 -221.94774) (xy 382.276065 -221.922395) (xy 382.283845 -221.872306) (xy 382.299197 -221.823996)
			(xy 382.32176 -221.778605) (xy 382.351003 -221.7372) (xy 382.386237 -221.700757) (xy 382.426631 -221.670134)
			(xy 382.471236 -221.646052) (xy 382.518999 -221.629078) (xy 382.543812 -221.62389) (xy 382.566672 -221.619572)
			(xy 382.77165 -221.263972) (xy 382.76403 -221.242128) (xy 382.755581 -221.215945) (xy 382.746509 -221.161685)
			(xy 382.745996 -221.134178) (xy 382.745996 -221.133924) (xy 382.746504 -221.108037) (xy 382.754603 -221.056899)
			(xy 382.770602 -221.007659) (xy 382.794108 -220.961527) (xy 382.82454 -220.91964) (xy 382.86115 -220.88303)
			(xy 382.903037 -220.852598) (xy 382.949169 -220.829092) (xy 382.998409 -220.813093) (xy 383.049547 -220.804994)
			(xy 383.101321 -220.804994) (xy 383.152459 -220.813093) (xy 383.201699 -220.829092) (xy 383.247831 -220.852598)
			(xy 383.289718 -220.88303) (xy 383.326328 -220.91964) (xy 383.35676 -220.961527) (xy 383.380266 -221.007659)
			(xy 383.396265 -221.056899) (xy 383.404364 -221.108037) (xy 383.404872 -221.133924) (xy 383.404479 -221.159291)
			(xy 383.396726 -221.209429) (xy 383.381375 -221.257784) (xy 383.358791 -221.303213) (xy 383.329506 -221.344642)
			(xy 383.294215 -221.381089) (xy 383.253752 -221.411694) (xy 383.209074 -221.435731) (xy 383.161238 -221.452632)
			(xy 383.136394 -221.457774) (xy 383.113534 -221.462092) (xy 382.90881 -221.81693) (xy 382.91643 -221.838774)
			(xy 382.925044 -221.865059) (xy 382.934366 -221.919578) (xy 382.934972 -221.947232) (xy 382.934972 -221.94774)
			(xy 382.934464 -221.973647) (xy 382.926358 -222.024824) (xy 382.910346 -222.074103) (xy 382.886823 -222.12027)
			(xy 382.856367 -222.162189) (xy 382.819729 -222.198827) (xy 382.77781 -222.229283) (xy 382.731643 -222.252806)
			(xy 382.682364 -222.268818) (xy 382.631187 -222.276924) (xy 382.579373 -222.276924) (xy 382.528196 -222.268818)
			(xy 382.478917 -222.252806) (xy 382.43275 -222.229283) (xy 382.390831 -222.198827) (xy 382.354193 -222.162189)
			(xy 382.323737 -222.12027) (xy 382.300214 -222.074103) (xy 382.284202 -222.024824) (xy 382.276096 -221.973647)
			(xy 382.275588 -221.94774) (xy 381.055372 -221.94774) (xy 381.054864 -221.973647) (xy 381.046758 -222.024824)
			(xy 381.030746 -222.074103) (xy 381.007223 -222.12027) (xy 380.976767 -222.162189) (xy 380.940129 -222.198827)
			(xy 380.89821 -222.229283) (xy 380.852043 -222.252806) (xy 380.802764 -222.268818) (xy 380.751587 -222.276924)
			(xy 380.699773 -222.276924) (xy 380.648596 -222.268818) (xy 380.599317 -222.252806) (xy 380.55315 -222.229283)
			(xy 380.511231 -222.198827) (xy 380.474593 -222.162189) (xy 380.444137 -222.12027) (xy 380.420614 -222.074103)
			(xy 380.404602 -222.024824) (xy 380.396496 -221.973647) (xy 380.395988 -221.94774) (xy 379.175772 -221.94774)
			(xy 379.175264 -221.973647) (xy 379.167158 -222.024824) (xy 379.151146 -222.074103) (xy 379.127623 -222.12027)
			(xy 379.097167 -222.162189) (xy 379.060529 -222.198827) (xy 379.01861 -222.229283) (xy 378.972443 -222.252806)
			(xy 378.923164 -222.268818) (xy 378.871987 -222.276924) (xy 378.820173 -222.276924) (xy 378.768996 -222.268818)
			(xy 378.719717 -222.252806) (xy 378.67355 -222.229283) (xy 378.631631 -222.198827) (xy 378.594993 -222.162189)
			(xy 378.564537 -222.12027) (xy 378.541014 -222.074103) (xy 378.525002 -222.024824) (xy 378.516896 -221.973647)
			(xy 378.516388 -221.94774) (xy 377.296172 -221.94774) (xy 377.295664 -221.973647) (xy 377.287558 -222.024824)
			(xy 377.271546 -222.074103) (xy 377.248023 -222.12027) (xy 377.217567 -222.162189) (xy 377.180929 -222.198827)
			(xy 377.13901 -222.229283) (xy 377.092843 -222.252806) (xy 377.043564 -222.268818) (xy 376.992387 -222.276924)
			(xy 376.940573 -222.276924) (xy 376.889396 -222.268818) (xy 376.840117 -222.252806) (xy 376.79395 -222.229283)
			(xy 376.752031 -222.198827) (xy 376.715393 -222.162189) (xy 376.684937 -222.12027) (xy 376.661414 -222.074103)
			(xy 376.645402 -222.024824) (xy 376.637296 -221.973647) (xy 376.636788 -221.94774) (xy 375.821956 -221.94774)
			(xy 375.821956 -222.567754) (xy 375.836873 -222.588967) (xy 375.860526 -222.635114) (xy 375.876612 -222.684411)
			(xy 375.884729 -222.735628) (xy 375.885202 -222.761556) (xy 375.884703 -222.787479) (xy 375.876544 -222.83868)
			(xy 375.860454 -222.887967) (xy 375.836829 -222.934119) (xy 375.821956 -222.955358) (xy 375.821956 -223.157034)
			(xy 375.822479 -223.172427) (xy 375.83163 -223.201821) (xy 375.84912 -223.227156) (xy 375.873363 -223.246131)
			(xy 375.902157 -223.257023) (xy 375.932889 -223.258845) (xy 375.94794 -223.255586) (xy 375.967319 -223.251141)
			(xy 376.006799 -223.246426) (xy 376.02668 -223.246188) (xy 376.052576 -223.246693) (xy 376.103732 -223.254788)
			(xy 376.152993 -223.270783) (xy 376.199148 -223.294282) (xy 376.24106 -223.32471) (xy 376.277699 -223.361316)
			(xy 376.308164 -223.403201) (xy 376.331705 -223.449335) (xy 376.347743 -223.498581) (xy 376.355883 -223.54973)
			(xy 376.356372 -223.575626) (xy 376.355897 -223.600983) (xy 376.348111 -223.651097) (xy 376.332743 -223.699427)
			(xy 376.310154 -223.744833) (xy 376.280878 -223.786244) (xy 376.245606 -223.822684) (xy 376.205169 -223.853292)
			(xy 376.160522 -223.877347) (xy 376.112718 -223.89428) (xy 376.087894 -223.899476) (xy 376.065034 -223.903794)
			(xy 375.86031 -224.258632) (xy 375.868184 -224.280476) (xy 375.876763 -224.306895) (xy 375.885958 -224.36167)
			(xy 375.886472 -224.389442) (xy 376.167396 -224.389442) (xy 376.167904 -224.363555) (xy 376.176003 -224.312417)
			(xy 376.192002 -224.263177) (xy 376.215508 -224.217045) (xy 376.24594 -224.175158) (xy 376.28255 -224.138548)
			(xy 376.324437 -224.108116) (xy 376.370569 -224.08461) (xy 376.419809 -224.068611) (xy 376.470947 -224.060512)
			(xy 376.522721 -224.060512) (xy 376.573859 -224.068611) (xy 376.623099 -224.08461) (xy 376.669231 -224.108116)
			(xy 376.711118 -224.138548) (xy 376.747728 -224.175158) (xy 376.77816 -224.217045) (xy 376.801666 -224.263177)
			(xy 376.817665 -224.312417) (xy 376.825764 -224.363555) (xy 376.826272 -224.389442) (xy 377.107196 -224.389442)
			(xy 377.107629 -224.364106) (xy 377.11539 -224.314032) (xy 377.13072 -224.265734) (xy 377.153259 -224.22035)
			(xy 377.182475 -224.178949) (xy 377.217681 -224.142504) (xy 377.258048 -224.111874) (xy 377.302626 -224.087781)
			(xy 377.350365 -224.070791) (xy 377.375166 -224.065592) (xy 377.398026 -224.061274) (xy 377.60275 -223.706436)
			(xy 377.59513 -223.684338) (xy 377.586502 -223.657991) (xy 377.577179 -223.603344) (xy 377.576588 -223.575626)
			(xy 377.577096 -223.549719) (xy 377.585202 -223.498542) (xy 377.601214 -223.449263) (xy 377.624737 -223.403096)
			(xy 377.655193 -223.361177) (xy 377.691831 -223.324539) (xy 377.73375 -223.294083) (xy 377.779917 -223.27056)
			(xy 377.829196 -223.254548) (xy 377.880373 -223.246442) (xy 377.932187 -223.246442) (xy 377.983364 -223.254548)
			(xy 378.032643 -223.27056) (xy 378.07881 -223.294083) (xy 378.120729 -223.324539) (xy 378.157367 -223.361177)
			(xy 378.187823 -223.403096) (xy 378.211346 -223.449263) (xy 378.227358 -223.498542) (xy 378.235464 -223.549719)
			(xy 378.235972 -223.575626) (xy 378.235581 -223.600993) (xy 378.227828 -223.651131) (xy 378.212477 -223.699486)
			(xy 378.189892 -223.744915) (xy 378.160607 -223.786344) (xy 378.125316 -223.822791) (xy 378.084852 -223.853396)
			(xy 378.040174 -223.877433) (xy 377.992339 -223.894334) (xy 377.967494 -223.899476) (xy 377.944634 -223.903794)
			(xy 377.73991 -224.258632) (xy 377.747784 -224.280476) (xy 377.756357 -224.306897) (xy 377.765558 -224.36167)
			(xy 377.766072 -224.389442) (xy 378.046996 -224.389442) (xy 378.047504 -224.363555) (xy 378.055603 -224.312417)
			(xy 378.071602 -224.263177) (xy 378.095108 -224.217045) (xy 378.12554 -224.175158) (xy 378.16215 -224.138548)
			(xy 378.204037 -224.108116) (xy 378.250169 -224.08461) (xy 378.299409 -224.068611) (xy 378.350547 -224.060512)
			(xy 378.402321 -224.060512) (xy 378.453459 -224.068611) (xy 378.502699 -224.08461) (xy 378.548831 -224.108116)
			(xy 378.590718 -224.138548) (xy 378.627328 -224.175158) (xy 378.65776 -224.217045) (xy 378.681266 -224.263177)
			(xy 378.697265 -224.312417) (xy 378.705364 -224.363555) (xy 378.705872 -224.389442) (xy 378.986796 -224.389442)
			(xy 378.987229 -224.364106) (xy 378.99499 -224.314032) (xy 379.01032 -224.265734) (xy 379.032859 -224.22035)
			(xy 379.062075 -224.178949) (xy 379.097281 -224.142504) (xy 379.137648 -224.111874) (xy 379.182226 -224.087781)
			(xy 379.229965 -224.070791) (xy 379.254766 -224.065592) (xy 379.277626 -224.061274) (xy 379.48235 -223.706182)
			(xy 379.47473 -223.684338) (xy 379.466087 -223.657995) (xy 379.456772 -223.603345) (xy 379.456188 -223.575626)
			(xy 379.456696 -223.549719) (xy 379.464802 -223.498542) (xy 379.480814 -223.449263) (xy 379.504337 -223.403096)
			(xy 379.534793 -223.361177) (xy 379.571431 -223.324539) (xy 379.61335 -223.294083) (xy 379.659517 -223.27056)
			(xy 379.708796 -223.254548) (xy 379.759973 -223.246442) (xy 379.811787 -223.246442) (xy 379.862964 -223.254548)
			(xy 379.912243 -223.27056) (xy 379.95841 -223.294083) (xy 380.000329 -223.324539) (xy 380.036967 -223.361177)
			(xy 380.067423 -223.403096) (xy 380.090946 -223.449263) (xy 380.106958 -223.498542) (xy 380.115064 -223.549719)
			(xy 380.115572 -223.575626) (xy 380.115097 -223.600971) (xy 380.107321 -223.651063) (xy 380.091971 -223.699374)
			(xy 380.069408 -223.744767) (xy 380.040166 -223.786173) (xy 380.004931 -223.822617) (xy 379.964535 -223.853239)
			(xy 379.919928 -223.877319) (xy 379.872162 -223.89429) (xy 379.847348 -223.899476) (xy 379.824488 -223.903794)
			(xy 379.619764 -224.258632) (xy 379.627384 -224.280476) (xy 379.635939 -224.306769) (xy 379.645132 -224.361289)
			(xy 379.645672 -224.388934) (xy 379.645672 -224.389442) (xy 379.926596 -224.389442) (xy 379.927104 -224.363555)
			(xy 379.935203 -224.312417) (xy 379.951202 -224.263177) (xy 379.974708 -224.217045) (xy 380.00514 -224.175158)
			(xy 380.04175 -224.138548) (xy 380.083637 -224.108116) (xy 380.129769 -224.08461) (xy 380.179009 -224.068611)
			(xy 380.230147 -224.060512) (xy 380.281921 -224.060512) (xy 380.333059 -224.068611) (xy 380.382299 -224.08461)
			(xy 380.428431 -224.108116) (xy 380.470318 -224.138548) (xy 380.506928 -224.175158) (xy 380.53736 -224.217045)
			(xy 380.560866 -224.263177) (xy 380.576865 -224.312417) (xy 380.584964 -224.363555) (xy 380.585472 -224.389442)
			(xy 380.866396 -224.389442) (xy 380.866829 -224.364106) (xy 380.87459 -224.314032) (xy 380.88992 -224.265734)
			(xy 380.912459 -224.22035) (xy 380.941675 -224.178949) (xy 380.976881 -224.142504) (xy 381.017248 -224.111874)
			(xy 381.061826 -224.087781) (xy 381.109565 -224.070791) (xy 381.134366 -224.065592) (xy 381.157226 -224.061274)
			(xy 381.362204 -223.705928) (xy 381.354584 -223.684084) (xy 381.346035 -223.657789) (xy 381.336839 -223.603271)
			(xy 381.336296 -223.575626) (xy 381.336804 -223.549739) (xy 381.344903 -223.498601) (xy 381.360902 -223.449361)
			(xy 381.384408 -223.403229) (xy 381.41484 -223.361342) (xy 381.45145 -223.324732) (xy 381.493337 -223.2943)
			(xy 381.539469 -223.270794) (xy 381.588709 -223.254795) (xy 381.639847 -223.246696) (xy 381.691621 -223.246696)
			(xy 381.742759 -223.254795) (xy 381.791999 -223.270794) (xy 381.838131 -223.2943) (xy 381.880018 -223.324732)
			(xy 381.916628 -223.361342) (xy 381.94706 -223.403229) (xy 381.970566 -223.449361) (xy 381.986565 -223.498601)
			(xy 381.994664 -223.549739) (xy 381.995172 -223.575626) (xy 381.994697 -223.600971) (xy 381.986921 -223.651063)
			(xy 381.971571 -223.699374) (xy 381.949008 -223.744767) (xy 381.919766 -223.786173) (xy 381.884531 -223.822617)
			(xy 381.844135 -223.853239) (xy 381.799528 -223.877319) (xy 381.751762 -223.89429) (xy 381.726948 -223.899476)
			(xy 381.704088 -223.903794) (xy 381.499364 -224.258632) (xy 381.506984 -224.280476) (xy 381.515539 -224.306769)
			(xy 381.524732 -224.361289) (xy 381.525272 -224.388934) (xy 381.525272 -224.389442) (xy 381.806196 -224.389442)
			(xy 381.806704 -224.363555) (xy 381.814803 -224.312417) (xy 381.830802 -224.263177) (xy 381.854308 -224.217045)
			(xy 381.88474 -224.175158) (xy 381.92135 -224.138548) (xy 381.963237 -224.108116) (xy 382.009369 -224.08461)
			(xy 382.058609 -224.068611) (xy 382.109747 -224.060512) (xy 382.161521 -224.060512) (xy 382.212659 -224.068611)
			(xy 382.261899 -224.08461) (xy 382.308031 -224.108116) (xy 382.349918 -224.138548) (xy 382.386528 -224.175158)
			(xy 382.41696 -224.217045) (xy 382.440466 -224.263177) (xy 382.456465 -224.312417) (xy 382.464564 -224.363555)
			(xy 382.465072 -224.389442) (xy 382.464539 -224.41715) (xy 382.455342 -224.471795) (xy 382.446784 -224.498154)
			(xy 382.439164 -224.519998) (xy 382.644142 -224.87509) (xy 382.667002 -224.879408) (xy 382.691815 -224.884555)
			(xy 382.739557 -224.901547) (xy 382.784137 -224.925644) (xy 382.824504 -224.95628) (xy 382.859707 -224.992732)
			(xy 382.888918 -225.034142) (xy 382.911448 -225.079534) (xy 382.926766 -225.12784) (xy 382.934512 -225.17792)
			(xy 382.934972 -225.203258) (xy 382.934464 -225.229145) (xy 382.926365 -225.280283) (xy 382.910366 -225.329523)
			(xy 382.88686 -225.375655) (xy 382.856428 -225.417542) (xy 382.819818 -225.454152) (xy 382.777931 -225.484584)
			(xy 382.731799 -225.50809) (xy 382.682559 -225.524089) (xy 382.631421 -225.532188) (xy 382.579647 -225.532188)
			(xy 382.528509 -225.524089) (xy 382.479269 -225.50809) (xy 382.433137 -225.484584) (xy 382.39125 -225.454152)
			(xy 382.35464 -225.417542) (xy 382.324208 -225.375655) (xy 382.300702 -225.329523) (xy 382.284703 -225.280283)
			(xy 382.276604 -225.229145) (xy 382.276096 -225.203258) (xy 382.276096 -225.20275) (xy 382.276653 -225.175107)
			(xy 382.285844 -225.120589) (xy 382.294384 -225.094292) (xy 382.302004 -225.072448) (xy 382.09728 -224.71761)
			(xy 382.07442 -224.713292) (xy 382.049591 -224.708158) (xy 382.001812 -224.691199) (xy 381.957192 -224.667122)
			(xy 381.916786 -224.636498) (xy 381.881546 -224.600046) (xy 381.852303 -224.558629) (xy 381.829748 -224.513222)
			(xy 381.814412 -224.464896) (xy 381.806657 -224.414792) (xy 381.806196 -224.389442) (xy 381.525272 -224.389442)
			(xy 381.524764 -224.415329) (xy 381.516665 -224.466467) (xy 381.500666 -224.515707) (xy 381.47716 -224.561839)
			(xy 381.446728 -224.603726) (xy 381.410118 -224.640336) (xy 381.368231 -224.670768) (xy 381.322099 -224.694274)
			(xy 381.272859 -224.710273) (xy 381.221721 -224.718372) (xy 381.169947 -224.718372) (xy 381.118809 -224.710273)
			(xy 381.069569 -224.694274) (xy 381.023437 -224.670768) (xy 380.98155 -224.640336) (xy 380.94494 -224.603726)
			(xy 380.914508 -224.561839) (xy 380.891002 -224.515707) (xy 380.875003 -224.466467) (xy 380.866904 -224.415329)
			(xy 380.866396 -224.389442) (xy 380.585472 -224.389442) (xy 380.584925 -224.417149) (xy 380.575741 -224.471796)
			(xy 380.567184 -224.498154) (xy 380.55931 -224.520252) (xy 380.764288 -224.87509) (xy 380.787148 -224.879408)
			(xy 380.811971 -224.884565) (xy 380.859751 -224.90152) (xy 380.904371 -224.925592) (xy 380.944778 -224.956214)
			(xy 380.980019 -224.992662) (xy 381.009263 -225.034077) (xy 381.031819 -225.079482) (xy 381.047156 -225.127806)
			(xy 381.054911 -225.177908) (xy 381.055372 -225.203258) (xy 381.054864 -225.229165) (xy 381.046758 -225.280342)
			(xy 381.030746 -225.329621) (xy 381.007223 -225.375788) (xy 380.976767 -225.417707) (xy 380.940129 -225.454345)
			(xy 380.89821 -225.484801) (xy 380.852043 -225.508324) (xy 380.802764 -225.524336) (xy 380.751587 -225.532442)
			(xy 380.699773 -225.532442) (xy 380.648596 -225.524336) (xy 380.599317 -225.508324) (xy 380.55315 -225.484801)
			(xy 380.511231 -225.454345) (xy 380.474593 -225.417707) (xy 380.444137 -225.375788) (xy 380.420614 -225.329621)
			(xy 380.404602 -225.280342) (xy 380.396496 -225.229165) (xy 380.395988 -225.203258) (xy 380.396597 -225.175541)
			(xy 380.40591 -225.120895) (xy 380.41453 -225.094546) (xy 380.422404 -225.072448) (xy 380.217426 -224.71761)
			(xy 380.194566 -224.713292) (xy 380.169748 -224.708169) (xy 380.122005 -224.691172) (xy 380.077426 -224.667071)
			(xy 380.03706 -224.636431) (xy 380.001857 -224.599976) (xy 379.972648 -224.558564) (xy 379.950119 -224.51317)
			(xy 379.934801 -224.464863) (xy 379.927055 -224.414781) (xy 379.926596 -224.389442) (xy 379.645672 -224.389442)
			(xy 379.645164 -224.415329) (xy 379.637065 -224.466467) (xy 379.621066 -224.515707) (xy 379.59756 -224.561839)
			(xy 379.567128 -224.603726) (xy 379.530518 -224.640336) (xy 379.488631 -224.670768) (xy 379.442499 -224.694274)
			(xy 379.393259 -224.710273) (xy 379.342121 -224.718372) (xy 379.290347 -224.718372) (xy 379.239209 -224.710273)
			(xy 379.189969 -224.694274) (xy 379.143837 -224.670768) (xy 379.10195 -224.640336) (xy 379.06534 -224.603726)
			(xy 379.034908 -224.561839) (xy 379.011402 -224.515707) (xy 378.995403 -224.466467) (xy 378.987304 -224.415329)
			(xy 378.986796 -224.389442) (xy 378.705872 -224.389442) (xy 378.705325 -224.417149) (xy 378.696141 -224.471796)
			(xy 378.687584 -224.498154) (xy 378.67971 -224.520252) (xy 378.884688 -224.87509) (xy 378.907548 -224.879408)
			(xy 378.932371 -224.884565) (xy 378.980151 -224.90152) (xy 379.024771 -224.925592) (xy 379.065178 -224.956214)
			(xy 379.100419 -224.992662) (xy 379.129663 -225.034077) (xy 379.152219 -225.079482) (xy 379.167556 -225.127806)
			(xy 379.175311 -225.177908) (xy 379.175772 -225.203258) (xy 379.175264 -225.229165) (xy 379.167158 -225.280342)
			(xy 379.151146 -225.329621) (xy 379.127623 -225.375788) (xy 379.097167 -225.417707) (xy 379.060529 -225.454345)
			(xy 379.01861 -225.484801) (xy 378.972443 -225.508324) (xy 378.923164 -225.524336) (xy 378.871987 -225.532442)
			(xy 378.820173 -225.532442) (xy 378.768996 -225.524336) (xy 378.719717 -225.508324) (xy 378.67355 -225.484801)
			(xy 378.631631 -225.454345) (xy 378.594993 -225.417707) (xy 378.564537 -225.375788) (xy 378.541014 -225.329621)
			(xy 378.525002 -225.280342) (xy 378.516896 -225.229165) (xy 378.516388 -225.203258) (xy 378.516997 -225.175541)
			(xy 378.52631 -225.120895) (xy 378.53493 -225.094546) (xy 378.542804 -225.072448) (xy 378.337826 -224.71761)
			(xy 378.314966 -224.713292) (xy 378.290148 -224.708169) (xy 378.242405 -224.691172) (xy 378.197826 -224.667071)
			(xy 378.15746 -224.636431) (xy 378.122257 -224.599976) (xy 378.093048 -224.558564) (xy 378.070519 -224.51317)
			(xy 378.055201 -224.464863) (xy 378.047455 -224.414781) (xy 378.046996 -224.389442) (xy 377.766072 -224.389442)
			(xy 377.765564 -224.415329) (xy 377.757465 -224.466467) (xy 377.741466 -224.515707) (xy 377.71796 -224.561839)
			(xy 377.687528 -224.603726) (xy 377.650918 -224.640336) (xy 377.609031 -224.670768) (xy 377.562899 -224.694274)
			(xy 377.513659 -224.710273) (xy 377.462521 -224.718372) (xy 377.410747 -224.718372) (xy 377.359609 -224.710273)
			(xy 377.310369 -224.694274) (xy 377.264237 -224.670768) (xy 377.22235 -224.640336) (xy 377.18574 -224.603726)
			(xy 377.155308 -224.561839) (xy 377.131802 -224.515707) (xy 377.115803 -224.466467) (xy 377.107704 -224.415329)
			(xy 377.107196 -224.389442) (xy 376.826272 -224.389442) (xy 376.825725 -224.417149) (xy 376.816541 -224.471796)
			(xy 376.807984 -224.498154) (xy 376.80011 -224.520252) (xy 377.005088 -224.87509) (xy 377.027948 -224.879408)
			(xy 377.052771 -224.884565) (xy 377.100551 -224.90152) (xy 377.145171 -224.925592) (xy 377.185578 -224.956214)
			(xy 377.220819 -224.992662) (xy 377.250063 -225.034077) (xy 377.272619 -225.079482) (xy 377.287956 -225.127806)
			(xy 377.295711 -225.177908) (xy 377.296172 -225.203258) (xy 377.295664 -225.229165) (xy 377.287558 -225.280342)
			(xy 377.271546 -225.329621) (xy 377.248023 -225.375788) (xy 377.217567 -225.417707) (xy 377.180929 -225.454345)
			(xy 377.13901 -225.484801) (xy 377.092843 -225.508324) (xy 377.043564 -225.524336) (xy 376.992387 -225.532442)
			(xy 376.940573 -225.532442) (xy 376.889396 -225.524336) (xy 376.840117 -225.508324) (xy 376.79395 -225.484801)
			(xy 376.752031 -225.454345) (xy 376.715393 -225.417707) (xy 376.684937 -225.375788) (xy 376.661414 -225.329621)
			(xy 376.645402 -225.280342) (xy 376.637296 -225.229165) (xy 376.636788 -225.203258) (xy 376.637397 -225.175541)
			(xy 376.64671 -225.120895) (xy 376.65533 -225.094546) (xy 376.663204 -225.072448) (xy 376.458226 -224.71761)
			(xy 376.435366 -224.713292) (xy 376.410548 -224.708169) (xy 376.362805 -224.691172) (xy 376.318226 -224.667071)
			(xy 376.27786 -224.636431) (xy 376.242657 -224.599976) (xy 376.213448 -224.558564) (xy 376.190919 -224.51317)
			(xy 376.175601 -224.464863) (xy 376.167855 -224.414781) (xy 376.167396 -224.389442) (xy 375.886472 -224.389442)
			(xy 375.885982 -224.415703) (xy 375.87769 -224.467565) (xy 375.861276 -224.517455) (xy 375.837155 -224.564109)
			(xy 375.821956 -224.58553) (xy 375.821956 -225.3361) (xy 376.265948 -225.780092) (xy 376.301 -225.75393)
			(xy 376.322374 -225.738698) (xy 376.368949 -225.714508) (xy 376.418778 -225.698033) (xy 376.470593 -225.689692)
			(xy 376.496834 -225.68916) (xy 376.522619 -225.689668) (xy 376.573553 -225.697741) (xy 376.622598 -225.713682)
			(xy 376.668545 -225.737099) (xy 376.710263 -225.767415) (xy 376.746725 -225.803884) (xy 376.777034 -225.845608)
			(xy 376.800442 -225.891559) (xy 376.816374 -225.940607) (xy 376.824437 -225.991543) (xy 376.825002 -226.017328)
			(xy 376.824485 -226.043569) (xy 376.816134 -226.095382) (xy 376.799649 -226.145207) (xy 376.775449 -226.191777)
			(xy 376.760232 -226.213162) (xy 376.73407 -226.248214) (xy 376.989086 -226.50323) (xy 377.006612 -226.505516)
			(xy 377.030915 -226.508971) (xy 377.078196 -226.522161) (xy 377.122985 -226.542248) (xy 377.164282 -226.568782)
			(xy 377.201166 -226.601171) (xy 377.232813 -226.638694) (xy 377.258518 -226.680512) (xy 377.277706 -226.725693)
			(xy 377.284234 -226.749356) (xy 377.29414 -226.787456) (xy 377.57862 -226.787456) (xy 377.588526 -226.749356)
			(xy 377.59534 -226.724811) (xy 377.615508 -226.678036) (xy 377.642663 -226.63494) (xy 377.676151 -226.596557)
			(xy 377.715169 -226.563812) (xy 377.758778 -226.537489) (xy 377.805931 -226.518222) (xy 377.855495 -226.506473)
			(xy 377.90628 -226.502525) (xy 377.957065 -226.506473) (xy 378.006629 -226.518222) (xy 378.053782 -226.537489)
			(xy 378.097391 -226.563812) (xy 378.136409 -226.596557) (xy 378.169897 -226.63494) (xy 378.197052 -226.678036)
			(xy 378.21722 -226.724811) (xy 378.224034 -226.749356) (xy 378.23394 -226.787456) (xy 378.518674 -226.787456)
			(xy 378.52858 -226.749356) (xy 378.535394 -226.724811) (xy 378.555562 -226.678036) (xy 378.582717 -226.63494)
			(xy 378.616205 -226.596557) (xy 378.655223 -226.563812) (xy 378.698832 -226.537489) (xy 378.745985 -226.518222)
			(xy 378.795549 -226.506473) (xy 378.846334 -226.502525) (xy 378.897119 -226.506473) (xy 378.946683 -226.518222)
			(xy 378.993836 -226.537489) (xy 379.037445 -226.563812) (xy 379.076463 -226.596557) (xy 379.109951 -226.63494)
			(xy 379.137106 -226.678036) (xy 379.157274 -226.724811) (xy 379.164088 -226.749356) (xy 379.173994 -226.787456)
			(xy 379.45822 -226.787456) (xy 379.468126 -226.749356) (xy 379.47494 -226.724811) (xy 379.495108 -226.678036)
			(xy 379.522263 -226.63494) (xy 379.555751 -226.596557) (xy 379.594769 -226.563812) (xy 379.638378 -226.537489)
			(xy 379.685531 -226.518222) (xy 379.735095 -226.506473) (xy 379.78588 -226.502525) (xy 379.836665 -226.506473)
			(xy 379.886229 -226.518222) (xy 379.933382 -226.537489) (xy 379.976991 -226.563812) (xy 380.016009 -226.596557)
			(xy 380.049497 -226.63494) (xy 380.076652 -226.678036) (xy 380.09682 -226.724811) (xy 380.103634 -226.749356)
			(xy 380.11354 -226.787456) (xy 380.546356 -226.787456) (xy 380.571314 -226.788033) (xy 380.620268 -226.797783)
			(xy 380.666379 -226.816897) (xy 380.707875 -226.844641) (xy 380.725934 -226.861878) (xy 381.180594 -227.316538)
			(xy 381.201168 -227.316792) (xy 381.226415 -227.317669) (xy 381.276201 -227.326224) (xy 381.324089 -227.342304)
			(xy 381.368948 -227.365532) (xy 381.409719 -227.395357) (xy 381.445439 -227.431077) (xy 381.475265 -227.471847)
			(xy 381.498493 -227.516706) (xy 381.514575 -227.564593) (xy 381.52313 -227.614379) (xy 381.524002 -227.639626)
			(xy 381.524256 -227.6602) (xy 382.87452 -229.010464) (xy 382.908302 -228.990398) (xy 382.933802 -228.976067)
			(xy 382.988626 -228.955686) (xy 383.04619 -228.945327) (xy 383.075434 -228.944678) (xy 383.101221 -228.94516)
			(xy 383.152158 -228.953234) (xy 383.201205 -228.969176) (xy 383.247155 -228.992595) (xy 383.288875 -229.022914)
			(xy 383.325338 -229.059386) (xy 383.355647 -229.101114) (xy 383.379055 -229.147069) (xy 383.394985 -229.19612)
			(xy 383.403046 -229.247059) (xy 383.403602 -229.272846) (xy 383.402968 -229.302092) (xy 383.392618 -229.359662)
			(xy 383.372236 -229.414489) (xy 383.357882 -229.439978) (xy 383.337816 -229.47376) (xy 383.634742 -229.770686)
			(xy 383.646426 -229.774496) (xy 383.670859 -229.782918) (xy 383.71692 -229.806352) (xy 383.758739 -229.836715)
			(xy 383.795282 -229.873257) (xy 383.825646 -229.915076) (xy 383.84908 -229.961136) (xy 383.8575 -229.98557)
			(xy 383.86131 -229.997254) (xy 387.813296 -233.94924) (xy 387.830559 -233.96728) (xy 387.858322 -234.008772)
			(xy 387.877439 -234.05489) (xy 387.887174 -234.103856) (xy 387.887718 -234.128818) (xy 387.887718 -244.381528)
			(xy 387.888988 -244.387116) (xy 387.892671 -244.404794) (xy 387.896612 -244.440689) (xy 387.896862 -244.458744)
			(xy 387.89664 -244.476801) (xy 387.892696 -244.512698) (xy 387.888988 -244.530372) (xy 387.887718 -244.53596)
			(xy 387.887718 -246.719598) (xy 387.922262 -246.731282) (xy 387.946381 -246.739875) (xy 387.991818 -246.763474)
			(xy 388.033037 -246.793845) (xy 388.069038 -246.83025) (xy 388.098947 -246.871806) (xy 388.122038 -246.917503)
			(xy 388.13775 -246.966232) (xy 388.145701 -247.01681) (xy 388.1457 -247.06801) (xy 388.137745 -247.118588)
			(xy 388.12203 -247.167316) (xy 388.098936 -247.213012) (xy 388.069025 -247.254565) (xy 388.033022 -247.290968)
			(xy 387.991801 -247.321336) (xy 387.946363 -247.344933) (xy 387.922262 -247.353582) (xy 387.887718 -247.365266)
			(xy 387.887718 -251.76988) (xy 391.655564 -251.76988) (xy 391.659545 -251.63686) (xy 391.671474 -251.504315)
			(xy 391.691309 -251.372722) (xy 391.718978 -251.24255) (xy 391.754382 -251.114265) (xy 391.797395 -250.988328)
			(xy 391.847862 -250.865189) (xy 391.905603 -250.745288) (xy 391.970412 -250.629055) (xy 392.042056 -250.516905)
			(xy 392.120278 -250.409241) (xy 392.204799 -250.306448) (xy 392.295317 -250.208893) (xy 392.391506 -250.116927)
			(xy 392.493024 -250.030877) (xy 392.599505 -249.951053) (xy 392.71057 -249.87774) (xy 392.825821 -249.8112)
			(xy 392.944845 -249.751671) (xy 393.067216 -249.699367) (xy 393.192495 -249.654475) (xy 393.320236 -249.617156)
			(xy 393.449979 -249.587543) (xy 393.581261 -249.565742) (xy 393.713612 -249.551832) (xy 393.846558 -249.545861)
			(xy 393.979623 -249.547852) (xy 394.112331 -249.557797) (xy 394.244207 -249.575661) (xy 394.374778 -249.601379)
			(xy 394.503578 -249.63486) (xy 394.630144 -249.675984) (xy 394.754025 -249.724604) (xy 394.874776 -249.780545)
			(xy 394.991966 -249.843607) (xy 395.105175 -249.913565) (xy 395.213997 -249.990169) (xy 395.318043 -250.073143)
			(xy 395.416941 -250.162191) (xy 395.510336 -250.256994) (xy 395.597894 -250.357212) (xy 395.679303 -250.462488)
			(xy 395.754269 -250.572444) (xy 395.822526 -250.686686) (xy 395.883828 -250.804806) (xy 395.937957 -250.926381)
			(xy 395.984718 -251.050975) (xy 396.023944 -251.178143) (xy 396.055494 -251.307429) (xy 396.079257 -251.43837)
			(xy 396.095146 -251.570498) (xy 396.103104 -251.70334) (xy 396.103602 -251.76988) (xy 396.103104 -251.83642)
			(xy 396.095146 -251.969262) (xy 396.079257 -252.10139) (xy 396.055494 -252.232331) (xy 396.023944 -252.361617)
			(xy 395.984718 -252.488785) (xy 395.937957 -252.613379) (xy 395.883828 -252.734954) (xy 395.822526 -252.853074)
			(xy 395.754269 -252.967316) (xy 395.679303 -253.077272) (xy 395.597894 -253.182548) (xy 395.510336 -253.282766)
			(xy 395.416941 -253.377569) (xy 395.318043 -253.466617) (xy 395.213997 -253.549591) (xy 395.105175 -253.626195)
			(xy 394.991966 -253.696153) (xy 394.874776 -253.759215) (xy 394.754025 -253.815156) (xy 394.630144 -253.863776)
			(xy 394.503578 -253.9049) (xy 394.374778 -253.938381) (xy 394.244207 -253.964099) (xy 394.112331 -253.981963)
			(xy 393.979623 -253.991908) (xy 393.846558 -253.993899) (xy 393.713612 -253.987928) (xy 393.581261 -253.974018)
			(xy 393.449979 -253.952217) (xy 393.320236 -253.922604) (xy 393.192495 -253.885285) (xy 393.067216 -253.840393)
			(xy 392.944845 -253.788089) (xy 392.825821 -253.72856) (xy 392.71057 -253.66202) (xy 392.599505 -253.588707)
			(xy 392.493024 -253.508883) (xy 392.391506 -253.422833) (xy 392.295317 -253.330867) (xy 392.204799 -253.233312)
			(xy 392.120278 -253.130519) (xy 392.042056 -253.022855) (xy 391.970412 -252.910705) (xy 391.905603 -252.794472)
			(xy 391.847862 -252.674571) (xy 391.797395 -252.551432) (xy 391.754382 -252.425495) (xy 391.718978 -252.29721)
			(xy 391.691309 -252.167038) (xy 391.671474 -252.035445) (xy 391.659545 -251.9029) (xy 391.655564 -251.76988)
			(xy 387.887718 -251.76988) (xy 387.887718 -261.727442) (xy 387.931152 -261.733538) (xy 387.956855 -261.737757)
			(xy 388.006579 -261.753254) (xy 388.053232 -261.776409) (xy 388.095644 -261.806642) (xy 388.132748 -261.843192)
			(xy 388.163615 -261.885144) (xy 388.18747 -261.931443) (xy 388.203713 -261.980929) (xy 388.211938 -262.032359)
			(xy 388.211938 -262.084442) (xy 388.203713 -262.135872) (xy 388.187469 -262.185358) (xy 388.163615 -262.231657)
			(xy 388.132747 -262.273609) (xy 388.095643 -262.310159) (xy 388.053231 -262.340391) (xy 388.006578 -262.363546)
			(xy 387.956853 -262.379043) (xy 387.931152 -262.38327) (xy 387.887718 -262.389366) (xy 387.887718 -263.184894)
			(xy 387.887098 -263.209847) (xy 387.877345 -263.258792) (xy 387.858233 -263.304894) (xy 387.830496 -263.346383)
			(xy 387.813296 -263.364472) (xy 384.407156 -266.770612) (xy 384.422142 -266.80287) (xy 384.431896 -266.824722)
			(xy 384.445682 -266.870544) (xy 384.452671 -266.917883) (xy 384.45313 -266.941808) (xy 384.45265 -266.967596)
			(xy 384.44458 -267.018537) (xy 384.42864 -267.067588) (xy 384.405222 -267.113542) (xy 384.374904 -267.155266)
			(xy 384.338431 -267.191734) (xy 384.296703 -267.222046) (xy 384.250746 -267.245457) (xy 384.201692 -267.26139)
			(xy 384.15075 -267.269453) (xy 384.124962 -267.269976) (xy 384.101036 -267.269525) (xy 384.053696 -267.262539)
			(xy 384.007873 -267.248749) (xy 383.986024 -267.238988) (xy 383.953766 -267.224002) (xy 382.57226 -268.605508)
			(xy 382.56972 -268.621764) (xy 382.565151 -268.647064) (xy 382.549185 -268.695931) (xy 382.525796 -268.741712)
			(xy 382.495557 -268.783287) (xy 382.459206 -268.81964) (xy 382.417633 -268.849883) (xy 382.371854 -268.873275)
			(xy 382.322989 -268.889245) (xy 382.297686 -268.893798) (xy 382.28143 -268.896338) (xy 382.016762 -269.161006)
			(xy 382.033 -269.179301) (xy 382.060436 -269.219797) (xy 382.081562 -269.263915) (xy 382.095911 -269.310678)
			(xy 382.103165 -269.359052) (xy 382.10363 -269.38351) (xy 382.103149 -269.409298) (xy 382.095079 -269.460239)
			(xy 382.079139 -269.50929) (xy 382.055721 -269.555243) (xy 382.025403 -269.596967) (xy 381.988931 -269.633434)
			(xy 381.947202 -269.663746) (xy 381.901245 -269.687157) (xy 381.852192 -269.70309) (xy 381.80125 -269.711153)
			(xy 381.775462 -269.711678) (xy 381.751005 -269.711225) (xy 381.702633 -269.703964) (xy 381.655873 -269.689607)
			(xy 381.611759 -269.668473) (xy 381.571269 -269.64103) (xy 381.552958 -269.62481) (xy 380.220474 -270.957294)
			(xy 380.222506 -270.98117) (xy 380.22403 -271.011396) (xy 380.22355 -271.037185) (xy 380.215482 -271.088127)
			(xy 380.199543 -271.13718) (xy 380.176126 -271.183135) (xy 380.145808 -271.224861) (xy 380.109335 -271.26133)
			(xy 380.067606 -271.291644) (xy 380.021649 -271.315056) (xy 379.972594 -271.33099) (xy 379.921651 -271.339053)
			(xy 379.895862 -271.339564) (xy 379.870494 -271.339087) (xy 379.820364 -271.331271) (xy 379.772035 -271.31583)
			(xy 379.72666 -271.293132) (xy 379.68532 -271.26372) (xy 379.649 -271.228294) (xy 379.618568 -271.187698)
			(xy 379.594748 -271.142902) (xy 379.585982 -271.119092) (xy 379.574044 -271.085056) (xy 379.27788 -271.085056)
			(xy 379.265942 -271.119092) (xy 379.257182 -271.142908) (xy 379.233374 -271.187719) (xy 379.202948 -271.228329)
			(xy 379.16663 -271.263768) (xy 379.125288 -271.29319) (xy 379.079907 -271.315894) (xy 379.031571 -271.331338)
			(xy 378.981434 -271.339153) (xy 378.93069 -271.339153) (xy 378.880553 -271.331338) (xy 378.832217 -271.315894)
			(xy 378.786836 -271.29319) (xy 378.745494 -271.263768) (xy 378.709176 -271.228329) (xy 378.67875 -271.187719)
			(xy 378.654942 -271.142908) (xy 378.646182 -271.119092) (xy 378.634244 -271.085056) (xy 378.33808 -271.085056)
			(xy 378.326142 -271.119092) (xy 378.317382 -271.142908) (xy 378.293574 -271.187719) (xy 378.263148 -271.228329)
			(xy 378.22683 -271.263768) (xy 378.185488 -271.29319) (xy 378.140107 -271.315894) (xy 378.091771 -271.331338)
			(xy 378.041634 -271.339153) (xy 377.99089 -271.339153) (xy 377.940753 -271.331338) (xy 377.892417 -271.315894)
			(xy 377.847036 -271.29319) (xy 377.805694 -271.263768) (xy 377.769376 -271.228329) (xy 377.73895 -271.187719)
			(xy 377.715142 -271.142908) (xy 377.706382 -271.119092) (xy 377.694444 -271.085056) (xy 377.39828 -271.085056)
			(xy 377.386342 -271.119092) (xy 377.377582 -271.142908) (xy 377.353774 -271.187719) (xy 377.323348 -271.228329)
			(xy 377.28703 -271.263768) (xy 377.245688 -271.29319) (xy 377.200307 -271.315894) (xy 377.151971 -271.331338)
			(xy 377.101834 -271.339153) (xy 377.05109 -271.339153) (xy 377.000953 -271.331338) (xy 376.952617 -271.315894)
			(xy 376.907236 -271.29319) (xy 376.865894 -271.263768) (xy 376.829576 -271.228329) (xy 376.79915 -271.187719)
			(xy 376.775342 -271.142908) (xy 376.766582 -271.119092) (xy 376.754644 -271.085056) (xy 376.45848 -271.085056)
			(xy 376.446542 -271.119092) (xy 376.437782 -271.142908) (xy 376.413974 -271.187719) (xy 376.383548 -271.228329)
			(xy 376.34723 -271.263768) (xy 376.305888 -271.29319) (xy 376.260507 -271.315894) (xy 376.212171 -271.331338)
			(xy 376.162034 -271.339153) (xy 376.11129 -271.339153) (xy 376.061153 -271.331338) (xy 376.012817 -271.315894)
			(xy 375.967436 -271.29319) (xy 375.926094 -271.263768) (xy 375.889776 -271.228329) (xy 375.85935 -271.187719)
			(xy 375.835542 -271.142908) (xy 375.826782 -271.119092) (xy 375.814844 -271.085056) (xy 375.51868 -271.085056)
			(xy 375.506742 -271.119092) (xy 375.497982 -271.142908) (xy 375.474174 -271.187719) (xy 375.443748 -271.228329)
			(xy 375.40743 -271.263768) (xy 375.366088 -271.29319) (xy 375.320707 -271.315894) (xy 375.272371 -271.331338)
			(xy 375.222234 -271.339153) (xy 375.17149 -271.339153) (xy 375.121353 -271.331338) (xy 375.073017 -271.315894)
			(xy 375.027636 -271.29319) (xy 374.986294 -271.263768) (xy 374.949976 -271.228329) (xy 374.91955 -271.187719)
			(xy 374.895742 -271.142908) (xy 374.886982 -271.119092) (xy 374.875044 -271.085056) (xy 374.57888 -271.085056)
			(xy 374.566942 -271.119092) (xy 374.558182 -271.142908) (xy 374.534374 -271.187719) (xy 374.503948 -271.228329)
			(xy 374.46763 -271.263768) (xy 374.426288 -271.29319) (xy 374.380907 -271.315894) (xy 374.332571 -271.331338)
			(xy 374.282434 -271.339153) (xy 374.23169 -271.339153) (xy 374.181553 -271.331338) (xy 374.133217 -271.315894)
			(xy 374.087836 -271.29319) (xy 374.046494 -271.263768) (xy 374.010176 -271.228329) (xy 373.97975 -271.187719)
			(xy 373.955942 -271.142908) (xy 373.947182 -271.119092) (xy 373.935244 -271.085056) (xy 373.63908 -271.085056)
			(xy 373.627142 -271.119092) (xy 373.618382 -271.142908) (xy 373.594574 -271.187719) (xy 373.564148 -271.228329)
			(xy 373.52783 -271.263768) (xy 373.486488 -271.29319) (xy 373.441107 -271.315894) (xy 373.392771 -271.331338)
			(xy 373.342634 -271.339153) (xy 373.29189 -271.339153) (xy 373.241753 -271.331338) (xy 373.193417 -271.315894)
			(xy 373.148036 -271.29319) (xy 373.106694 -271.263768) (xy 373.070376 -271.228329) (xy 373.03995 -271.187719)
			(xy 373.016142 -271.142908) (xy 373.007382 -271.119092) (xy 372.995444 -271.085056) (xy 372.69928 -271.085056)
			(xy 372.687342 -271.119092) (xy 372.678582 -271.142908) (xy 372.654774 -271.187719) (xy 372.624348 -271.228329)
			(xy 372.58803 -271.263768) (xy 372.546688 -271.29319) (xy 372.501307 -271.315894) (xy 372.452971 -271.331338)
			(xy 372.402834 -271.339153) (xy 372.35209 -271.339153) (xy 372.301953 -271.331338) (xy 372.253617 -271.315894)
			(xy 372.208236 -271.29319) (xy 372.166894 -271.263768) (xy 372.130576 -271.228329) (xy 372.10015 -271.187719)
			(xy 372.076342 -271.142908) (xy 372.067582 -271.119092) (xy 372.055644 -271.085056) (xy 371.75948 -271.085056)
			(xy 371.747542 -271.119092) (xy 371.738782 -271.142908) (xy 371.714974 -271.187719) (xy 371.684548 -271.228329)
			(xy 371.64823 -271.263768) (xy 371.606888 -271.29319) (xy 371.561507 -271.315894) (xy 371.513171 -271.331338)
			(xy 371.463034 -271.339153) (xy 371.41229 -271.339153) (xy 371.362153 -271.331338) (xy 371.313817 -271.315894)
			(xy 371.268436 -271.29319) (xy 371.227094 -271.263768) (xy 371.190776 -271.228329) (xy 371.16035 -271.187719)
			(xy 371.136542 -271.142908) (xy 371.127782 -271.119092) (xy 371.115844 -271.085056) (xy 370.819934 -271.085056)
			(xy 370.807996 -271.119092) (xy 370.799236 -271.142908) (xy 370.775428 -271.187719) (xy 370.745002 -271.228329)
			(xy 370.708684 -271.263768) (xy 370.667342 -271.29319) (xy 370.621961 -271.315894) (xy 370.573625 -271.331338)
			(xy 370.523488 -271.339153) (xy 370.472744 -271.339153) (xy 370.422607 -271.331338) (xy 370.374271 -271.315894)
			(xy 370.32889 -271.29319) (xy 370.287548 -271.263768) (xy 370.25123 -271.228329) (xy 370.220804 -271.187719)
			(xy 370.196996 -271.142908) (xy 370.188236 -271.119092) (xy 370.176298 -271.085056) (xy 369.87988 -271.085056)
			(xy 369.867942 -271.119092) (xy 369.859182 -271.142908) (xy 369.835374 -271.187719) (xy 369.804948 -271.228329)
			(xy 369.76863 -271.263768) (xy 369.727288 -271.29319) (xy 369.681907 -271.315894) (xy 369.633571 -271.331338)
			(xy 369.583434 -271.339153) (xy 369.53269 -271.339153) (xy 369.482553 -271.331338) (xy 369.434217 -271.315894)
			(xy 369.388836 -271.29319) (xy 369.347494 -271.263768) (xy 369.311176 -271.228329) (xy 369.28075 -271.187719)
			(xy 369.256942 -271.142908) (xy 369.248182 -271.119092) (xy 369.236244 -271.085056) (xy 368.94008 -271.085056)
			(xy 368.928142 -271.119092) (xy 368.919389 -271.142911) (xy 368.895588 -271.187729) (xy 368.865166 -271.228343)
			(xy 368.828848 -271.263784) (xy 368.787503 -271.293205) (xy 368.742118 -271.315902) (xy 368.693776 -271.331335)
			(xy 368.643635 -271.339134) (xy 368.618262 -271.339564) (xy 368.593693 -271.339103) (xy 368.545105 -271.331775)
			(xy 368.498151 -271.317288) (xy 368.45388 -271.295966) (xy 368.413281 -271.268285) (xy 368.37726 -271.234863)
			(xy 368.346622 -271.196447) (xy 368.32205 -271.153894) (xy 368.304094 -271.108154) (xy 368.298222 -271.084294)
			(xy 368.274442 -271.085634) (xy 368.227099 -271.08048) (xy 368.181545 -271.066599) (xy 368.139373 -271.044475)
			(xy 368.10206 -271.014884) (xy 368.070911 -270.978861) (xy 368.058446 -270.958564) (xy 367.310924 -270.958564)
			(xy 366.474248 -270.121888) (xy 366.474248 -269.720568) (xy 366.451102 -269.701719) (xy 366.409744 -269.658676)
			(xy 366.374756 -269.610313) (xy 366.346816 -269.557564) (xy 366.326463 -269.501449) (xy 366.314092 -269.443054)
			(xy 366.309941 -269.383506) (xy 366.31409 -269.323959) (xy 366.32646 -269.265563) (xy 366.346811 -269.209447)
			(xy 366.37475 -269.156697) (xy 366.409736 -269.108333) (xy 366.451093 -269.06529) (xy 366.474248 -269.046452)
			(xy 366.474248 -268.092936) (xy 366.451104 -268.074087) (xy 366.40975 -268.031045) (xy 366.374767 -267.982683)
			(xy 366.346831 -267.929936) (xy 366.326482 -267.873823) (xy 366.314114 -267.81543) (xy 366.309966 -267.755886)
			(xy 366.314118 -267.696343) (xy 366.32649 -267.63795) (xy 366.346842 -267.581839) (xy 366.374781 -267.529094)
			(xy 366.409768 -267.480734) (xy 366.451124 -267.437695) (xy 366.474248 -267.41882) (xy 366.474248 -266.323064)
			(xy 366.459233 -266.301782) (xy 366.435411 -266.255467) (xy 366.419196 -266.205973) (xy 366.410993 -266.154541)
			(xy 366.410494 -266.1285) (xy 366.410972 -266.102457) (xy 366.419161 -266.051019) (xy 366.435382 -266.001523)
			(xy 366.459225 -265.955215) (xy 366.474248 -265.933936) (xy 366.474248 -264.694924) (xy 366.459236 -264.673641)
			(xy 366.43542 -264.627325) (xy 366.41921 -264.577832) (xy 366.411014 -264.5264) (xy 366.410494 -264.50036)
			(xy 366.410967 -264.474315) (xy 366.419148 -264.422873) (xy 366.435361 -264.373372) (xy 366.459199 -264.327058)
			(xy 366.474248 -264.305796) (xy 366.474248 -263.647174) (xy 366.452605 -263.63174) (xy 366.414147 -263.595044)
			(xy 366.382102 -263.552633) (xy 366.357308 -263.505614) (xy 366.340411 -263.455216) (xy 366.331852 -263.402753)
			(xy 366.331856 -263.349597) (xy 366.340423 -263.297136) (xy 366.357327 -263.24674) (xy 366.382129 -263.199725)
			(xy 366.41418 -263.157319) (xy 366.452643 -263.120629) (xy 366.474248 -263.105138) (xy 366.474248 -260.90118)
			(xy 366.345978 -260.772656) (xy 364.725712 -260.772656) (xy 364.214156 -261.284212) (xy 364.214156 -264.356088)
			(xy 364.218728 -264.365994) (xy 364.227798 -264.38722) (xy 364.240576 -264.431575) (xy 364.247032 -264.477281)
			(xy 364.24743 -264.50036) (xy 364.247058 -264.523442) (xy 364.240618 -264.569153) (xy 364.227817 -264.613506)
			(xy 364.218728 -264.634726) (xy 364.214156 -264.644632) (xy 364.214156 -265.983974) (xy 364.218728 -265.99388)
			(xy 364.227799 -266.015106) (xy 364.240579 -266.059461) (xy 364.247036 -266.105166) (xy 364.24743 -266.128246)
			(xy 364.247059 -266.151328) (xy 364.24062 -266.19704) (xy 364.227821 -266.241393) (xy 364.218728 -266.262612)
			(xy 364.214156 -266.272518) (xy 364.214156 -267.611606) (xy 364.218728 -267.621512) (xy 364.227797 -267.642738)
			(xy 364.240573 -267.687094) (xy 364.247025 -267.732799) (xy 364.24743 -267.755878) (xy 364.247057 -267.77896)
			(xy 364.240614 -267.82467) (xy 364.227811 -267.869021) (xy 364.218728 -267.890244) (xy 364.214156 -267.90015)
			(xy 364.214156 -269.239238) (xy 364.218728 -269.249144) (xy 364.227802 -269.270369) (xy 364.240586 -269.314724)
			(xy 364.247048 -269.36043) (xy 364.24743 -269.38351) (xy 364.247061 -269.406593) (xy 364.240628 -269.452306)
			(xy 364.227833 -269.496662) (xy 364.218728 -269.517876) (xy 364.214156 -269.527782) (xy 364.214156 -270.867124)
			(xy 364.218728 -270.87703) (xy 364.227796 -270.898256) (xy 364.240569 -270.942612) (xy 364.247019 -270.988317)
			(xy 364.24743 -271.011396) (xy 364.247062 -271.034479) (xy 364.240631 -271.080193) (xy 364.227837 -271.12455)
			(xy 364.218728 -271.145762) (xy 364.214156 -271.155668) (xy 364.214156 -272.49501) (xy 364.218728 -272.504916)
			(xy 364.227797 -272.526142) (xy 364.240572 -272.570498) (xy 364.247024 -272.616203) (xy 364.24743 -272.639282)
			(xy 364.247056 -272.662363) (xy 364.240613 -272.708074) (xy 364.22781 -272.752425) (xy 364.218728 -272.773648)
			(xy 364.214156 -272.783554) (xy 364.214156 -274.12188) (xy 364.218728 -274.13204) (xy 364.227893 -274.15333)
			(xy 364.240808 -274.197846) (xy 364.247316 -274.243738) (xy 364.247684 -274.266914) (xy 364.24728 -274.290087)
			(xy 364.240759 -274.335972) (xy 364.227864 -274.380488) (xy 364.218728 -274.401788) (xy 364.214156 -274.411948)
			(xy 364.214156 -275.750528) (xy 364.218728 -275.760434) (xy 364.227796 -275.781661) (xy 364.240568 -275.826016)
			(xy 364.247018 -275.871721) (xy 364.24743 -275.8948) (xy 364.247062 -275.917883) (xy 364.24063 -275.963597)
			(xy 364.227836 -276.007953) (xy 364.218728 -276.029166) (xy 364.214156 -276.039072) (xy 364.214156 -277.377144)
			(xy 364.218728 -277.387304) (xy 364.227889 -277.408595) (xy 364.240795 -277.453111) (xy 364.247294 -277.499003)
			(xy 364.247684 -277.522178) (xy 364.247282 -277.545351) (xy 364.240767 -277.591238) (xy 364.227875 -277.635756)
			(xy 364.218728 -277.657052) (xy 364.214156 -277.667212) (xy 364.214156 -279.006046) (xy 364.218728 -279.015952)
			(xy 364.22965 -279.043638) (xy 364.231174 -279.04821) (xy 364.62589 -279.73655) (xy 364.629954 -279.740868)
			(xy 364.646567 -279.759445) (xy 364.674556 -279.800676) (xy 364.695985 -279.845667) (xy 364.703614 -279.869392)
			(xy 364.705392 -279.87498) (xy 365.088424 -280.543254) (xy 365.092996 -280.547826) (xy 365.112339 -280.568331)
			(xy 365.144425 -280.614673) (xy 365.168148 -280.665802) (xy 365.176054 -280.69286) (xy 365.177832 -280.69921)
			(xy 365.551212 -281.350212) (xy 365.556546 -281.355292) (xy 365.57311 -281.371794) (xy 365.601873 -281.408656)
			(xy 365.625116 -281.449224) (xy 365.642372 -281.492679) (xy 365.64824 -281.515312) (xy 365.650018 -281.522424)
			(xy 366.014508 -282.158186) (xy 366.02035 -282.16352) (xy 366.038854 -282.181025) (xy 366.070754 -282.220733)
			(xy 366.096129 -282.264897) (xy 366.114368 -282.312454) (xy 366.120172 -282.337256) (xy 366.121696 -282.34513)
			(xy 366.478312 -282.966922) (xy 366.484916 -282.972764) (xy 366.505095 -282.991111) (xy 366.539664 -283.033289)
			(xy 366.566778 -283.080606) (xy 366.58569 -283.131757) (xy 366.591342 -283.158438) (xy 366.59312 -283.16682)
			(xy 366.94237 -283.77642) (xy 366.949482 -283.782262) (xy 366.966963 -283.797444) (xy 366.997906 -283.831884)
			(xy 367.023711 -283.870325) (xy 367.043867 -283.912007) (xy 367.057974 -283.956105) (xy 367.062258 -283.978858)
			(xy 367.063782 -283.987748) (xy 367.40465 -284.582108) (xy 367.41227 -284.588204) (xy 367.431947 -284.604242)
			(xy 367.466607 -284.641329) (xy 367.495182 -284.683285) (xy 367.516999 -284.729119) (xy 367.531543 -284.777753)
			(xy 367.53546 -284.802834) (xy 367.53673 -284.81274) (xy 367.556676 -284.847538) (xy 368.758724 -284.847538)
			(xy 368.759232 -284.821631) (xy 368.767338 -284.770454) (xy 368.78335 -284.721175) (xy 368.806873 -284.675008)
			(xy 368.837329 -284.633089) (xy 368.873967 -284.596451) (xy 368.915886 -284.565995) (xy 368.962053 -284.542472)
			(xy 369.011332 -284.52646) (xy 369.062509 -284.518354) (xy 369.114323 -284.518354) (xy 369.1655 -284.52646)
			(xy 369.214779 -284.542472) (xy 369.260946 -284.565995) (xy 369.302865 -284.596451) (xy 369.339503 -284.633089)
			(xy 369.369959 -284.675008) (xy 369.393482 -284.721175) (xy 369.409494 -284.770454) (xy 369.4176 -284.821631)
			(xy 369.418108 -284.847538) (xy 370.638324 -284.847538) (xy 370.638832 -284.821631) (xy 370.646938 -284.770454)
			(xy 370.66295 -284.721175) (xy 370.686473 -284.675008) (xy 370.716929 -284.633089) (xy 370.753567 -284.596451)
			(xy 370.795486 -284.565995) (xy 370.841653 -284.542472) (xy 370.890932 -284.52646) (xy 370.942109 -284.518354)
			(xy 370.993923 -284.518354) (xy 371.0451 -284.52646) (xy 371.094379 -284.542472) (xy 371.140546 -284.565995)
			(xy 371.182465 -284.596451) (xy 371.219103 -284.633089) (xy 371.249559 -284.675008) (xy 371.273082 -284.721175)
			(xy 371.289094 -284.770454) (xy 371.2972 -284.821631) (xy 371.297708 -284.847538) (xy 372.517924 -284.847538)
			(xy 372.518432 -284.821631) (xy 372.526538 -284.770454) (xy 372.54255 -284.721175) (xy 372.566073 -284.675008)
			(xy 372.596529 -284.633089) (xy 372.633167 -284.596451) (xy 372.675086 -284.565995) (xy 372.721253 -284.542472)
			(xy 372.770532 -284.52646) (xy 372.821709 -284.518354) (xy 372.873523 -284.518354) (xy 372.9247 -284.52646)
			(xy 372.973979 -284.542472) (xy 373.020146 -284.565995) (xy 373.062065 -284.596451) (xy 373.098703 -284.633089)
			(xy 373.129159 -284.675008) (xy 373.152682 -284.721175) (xy 373.168694 -284.770454) (xy 373.1768 -284.821631)
			(xy 373.177308 -284.847538) (xy 374.397524 -284.847538) (xy 374.398032 -284.821631) (xy 374.406138 -284.770454)
			(xy 374.42215 -284.721175) (xy 374.445673 -284.675008) (xy 374.476129 -284.633089) (xy 374.512767 -284.596451)
			(xy 374.554686 -284.565995) (xy 374.600853 -284.542472) (xy 374.650132 -284.52646) (xy 374.701309 -284.518354)
			(xy 374.753123 -284.518354) (xy 374.8043 -284.52646) (xy 374.853579 -284.542472) (xy 374.899746 -284.565995)
			(xy 374.941665 -284.596451) (xy 374.978303 -284.633089) (xy 375.008759 -284.675008) (xy 375.032282 -284.721175)
			(xy 375.048294 -284.770454) (xy 375.0564 -284.821631) (xy 375.056908 -284.847538) (xy 376.277124 -284.847538)
			(xy 376.277632 -284.821631) (xy 376.285738 -284.770454) (xy 376.30175 -284.721175) (xy 376.325273 -284.675008)
			(xy 376.355729 -284.633089) (xy 376.392367 -284.596451) (xy 376.434286 -284.565995) (xy 376.480453 -284.542472)
			(xy 376.529732 -284.52646) (xy 376.580909 -284.518354) (xy 376.632723 -284.518354) (xy 376.6839 -284.52646)
			(xy 376.733179 -284.542472) (xy 376.779346 -284.565995) (xy 376.821265 -284.596451) (xy 376.857903 -284.633089)
			(xy 376.888359 -284.675008) (xy 376.911882 -284.721175) (xy 376.927894 -284.770454) (xy 376.936 -284.821631)
			(xy 376.936508 -284.847538) (xy 378.156724 -284.847538) (xy 378.157232 -284.821631) (xy 378.165338 -284.770454)
			(xy 378.18135 -284.721175) (xy 378.204873 -284.675008) (xy 378.235329 -284.633089) (xy 378.271967 -284.596451)
			(xy 378.313886 -284.565995) (xy 378.360053 -284.542472) (xy 378.409332 -284.52646) (xy 378.460509 -284.518354)
			(xy 378.512323 -284.518354) (xy 378.5635 -284.52646) (xy 378.612779 -284.542472) (xy 378.658946 -284.565995)
			(xy 378.700865 -284.596451) (xy 378.737503 -284.633089) (xy 378.767959 -284.675008) (xy 378.791482 -284.721175)
			(xy 378.807494 -284.770454) (xy 378.8156 -284.821631) (xy 378.816108 -284.847538) (xy 380.036324 -284.847538)
			(xy 380.036832 -284.821631) (xy 380.044938 -284.770454) (xy 380.06095 -284.721175) (xy 380.084473 -284.675008)
			(xy 380.114929 -284.633089) (xy 380.151567 -284.596451) (xy 380.193486 -284.565995) (xy 380.239653 -284.542472)
			(xy 380.288932 -284.52646) (xy 380.340109 -284.518354) (xy 380.391923 -284.518354) (xy 380.4431 -284.52646)
			(xy 380.492379 -284.542472) (xy 380.538546 -284.565995) (xy 380.580465 -284.596451) (xy 380.617103 -284.633089)
			(xy 380.647559 -284.675008) (xy 380.671082 -284.721175) (xy 380.687094 -284.770454) (xy 380.6952 -284.821631)
			(xy 380.695708 -284.847538) (xy 380.695098 -284.875255) (xy 380.685785 -284.929901) (xy 380.677166 -284.95625)
			(xy 380.669292 -284.978348) (xy 380.87427 -285.333186) (xy 380.89713 -285.337504) (xy 380.921947 -285.342634)
			(xy 380.969689 -285.35963) (xy 381.014267 -285.383731) (xy 381.054634 -285.414369) (xy 381.089836 -285.450823)
			(xy 381.119046 -285.492235) (xy 381.141576 -285.537628) (xy 381.156894 -285.585934) (xy 381.16464 -285.636016)
			(xy 381.1651 -285.661354) (xy 381.164592 -285.687241) (xy 381.156493 -285.738379) (xy 381.140494 -285.787619)
			(xy 381.116988 -285.833751) (xy 381.086556 -285.875638) (xy 381.049946 -285.912248) (xy 381.008059 -285.94268)
			(xy 380.961927 -285.966186) (xy 380.912687 -285.982185) (xy 380.861549 -285.990284) (xy 380.809775 -285.990284)
			(xy 380.758637 -285.982185) (xy 380.709397 -285.966186) (xy 380.663265 -285.94268) (xy 380.621378 -285.912248)
			(xy 380.584768 -285.875638) (xy 380.554336 -285.833751) (xy 380.53083 -285.787619) (xy 380.514831 -285.738379)
			(xy 380.506732 -285.687241) (xy 380.506224 -285.661354) (xy 380.506766 -285.633646) (xy 380.515953 -285.579)
			(xy 380.524512 -285.552642) (xy 380.532386 -285.530544) (xy 380.327408 -285.175706) (xy 380.304548 -285.171388)
			(xy 380.279723 -285.166238) (xy 380.231943 -285.149282) (xy 380.187323 -285.125209) (xy 380.146916 -285.094586)
			(xy 380.111675 -285.058137) (xy 380.082431 -285.016721) (xy 380.059876 -284.971315) (xy 380.044539 -284.922991)
			(xy 380.036785 -284.872888) (xy 380.036324 -284.847538) (xy 378.816108 -284.847538) (xy 378.815498 -284.875255)
			(xy 378.806185 -284.929901) (xy 378.797566 -284.95625) (xy 378.789692 -284.978348) (xy 378.99467 -285.333186)
			(xy 379.01753 -285.337504) (xy 379.042347 -285.342634) (xy 379.090089 -285.35963) (xy 379.134667 -285.383731)
			(xy 379.175034 -285.414369) (xy 379.210236 -285.450823) (xy 379.239446 -285.492235) (xy 379.261976 -285.537628)
			(xy 379.277294 -285.585934) (xy 379.28504 -285.636016) (xy 379.2855 -285.661354) (xy 379.284992 -285.687241)
			(xy 379.276893 -285.738379) (xy 379.260894 -285.787619) (xy 379.237388 -285.833751) (xy 379.206956 -285.875638)
			(xy 379.170346 -285.912248) (xy 379.128459 -285.94268) (xy 379.082327 -285.966186) (xy 379.033087 -285.982185)
			(xy 378.981949 -285.990284) (xy 378.930175 -285.990284) (xy 378.879037 -285.982185) (xy 378.829797 -285.966186)
			(xy 378.783665 -285.94268) (xy 378.741778 -285.912248) (xy 378.705168 -285.875638) (xy 378.674736 -285.833751)
			(xy 378.65123 -285.787619) (xy 378.635231 -285.738379) (xy 378.627132 -285.687241) (xy 378.626624 -285.661354)
			(xy 378.627166 -285.633646) (xy 378.636353 -285.579) (xy 378.644912 -285.552642) (xy 378.652786 -285.530544)
			(xy 378.447808 -285.175706) (xy 378.424948 -285.171388) (xy 378.400123 -285.166238) (xy 378.352343 -285.149282)
			(xy 378.307723 -285.125209) (xy 378.267316 -285.094586) (xy 378.232075 -285.058137) (xy 378.202831 -285.016721)
			(xy 378.180276 -284.971315) (xy 378.164939 -284.922991) (xy 378.157185 -284.872888) (xy 378.156724 -284.847538)
			(xy 376.936508 -284.847538) (xy 376.935898 -284.875255) (xy 376.926585 -284.929901) (xy 376.917966 -284.95625)
			(xy 376.910092 -284.978348) (xy 377.11507 -285.333186) (xy 377.13793 -285.337504) (xy 377.162747 -285.342634)
			(xy 377.210489 -285.35963) (xy 377.255067 -285.383731) (xy 377.295434 -285.414369) (xy 377.330636 -285.450823)
			(xy 377.359846 -285.492235) (xy 377.382376 -285.537628) (xy 377.397694 -285.585934) (xy 377.40544 -285.636016)
			(xy 377.4059 -285.661354) (xy 377.405392 -285.687241) (xy 377.397293 -285.738379) (xy 377.381294 -285.787619)
			(xy 377.357788 -285.833751) (xy 377.327356 -285.875638) (xy 377.290746 -285.912248) (xy 377.248859 -285.94268)
			(xy 377.202727 -285.966186) (xy 377.153487 -285.982185) (xy 377.102349 -285.990284) (xy 377.050575 -285.990284)
			(xy 376.999437 -285.982185) (xy 376.950197 -285.966186) (xy 376.904065 -285.94268) (xy 376.862178 -285.912248)
			(xy 376.825568 -285.875638) (xy 376.795136 -285.833751) (xy 376.77163 -285.787619) (xy 376.755631 -285.738379)
			(xy 376.747532 -285.687241) (xy 376.747024 -285.661354) (xy 376.747566 -285.633646) (xy 376.756753 -285.579)
			(xy 376.765312 -285.552642) (xy 376.773186 -285.530544) (xy 376.568208 -285.175706) (xy 376.545348 -285.171388)
			(xy 376.520523 -285.166238) (xy 376.472743 -285.149282) (xy 376.428123 -285.125209) (xy 376.387716 -285.094586)
			(xy 376.352475 -285.058137) (xy 376.323231 -285.016721) (xy 376.300676 -284.971315) (xy 376.285339 -284.922991)
			(xy 376.277585 -284.872888) (xy 376.277124 -284.847538) (xy 375.056908 -284.847538) (xy 375.056298 -284.875255)
			(xy 375.046985 -284.929901) (xy 375.038366 -284.95625) (xy 375.030492 -284.978348) (xy 375.23547 -285.333186)
			(xy 375.25833 -285.337504) (xy 375.283147 -285.342634) (xy 375.330889 -285.35963) (xy 375.375467 -285.383731)
			(xy 375.415834 -285.414369) (xy 375.451036 -285.450823) (xy 375.480246 -285.492235) (xy 375.502776 -285.537628)
			(xy 375.518094 -285.585934) (xy 375.52584 -285.636016) (xy 375.5263 -285.661354) (xy 375.525792 -285.687241)
			(xy 375.517693 -285.738379) (xy 375.501694 -285.787619) (xy 375.478188 -285.833751) (xy 375.447756 -285.875638)
			(xy 375.411146 -285.912248) (xy 375.369259 -285.94268) (xy 375.323127 -285.966186) (xy 375.273887 -285.982185)
			(xy 375.222749 -285.990284) (xy 375.170975 -285.990284) (xy 375.119837 -285.982185) (xy 375.070597 -285.966186)
			(xy 375.024465 -285.94268) (xy 374.982578 -285.912248) (xy 374.945968 -285.875638) (xy 374.915536 -285.833751)
			(xy 374.89203 -285.787619) (xy 374.876031 -285.738379) (xy 374.867932 -285.687241) (xy 374.867424 -285.661354)
			(xy 374.867966 -285.633646) (xy 374.877153 -285.579) (xy 374.885712 -285.552642) (xy 374.893586 -285.530544)
			(xy 374.688608 -285.175706) (xy 374.665748 -285.171388) (xy 374.640923 -285.166238) (xy 374.593143 -285.149282)
			(xy 374.548523 -285.125209) (xy 374.508116 -285.094586) (xy 374.472875 -285.058137) (xy 374.443631 -285.016721)
			(xy 374.421076 -284.971315) (xy 374.405739 -284.922991) (xy 374.397985 -284.872888) (xy 374.397524 -284.847538)
			(xy 373.177308 -284.847538) (xy 373.176698 -284.875255) (xy 373.167385 -284.929901) (xy 373.158766 -284.95625)
			(xy 373.150892 -284.978348) (xy 373.35587 -285.333186) (xy 373.37873 -285.337504) (xy 373.403547 -285.342634)
			(xy 373.451289 -285.35963) (xy 373.495867 -285.383731) (xy 373.536234 -285.414369) (xy 373.571436 -285.450823)
			(xy 373.600646 -285.492235) (xy 373.623176 -285.537628) (xy 373.638494 -285.585934) (xy 373.64624 -285.636016)
			(xy 373.6467 -285.661354) (xy 373.646192 -285.687241) (xy 373.638093 -285.738379) (xy 373.622094 -285.787619)
			(xy 373.598588 -285.833751) (xy 373.568156 -285.875638) (xy 373.531546 -285.912248) (xy 373.489659 -285.94268)
			(xy 373.443527 -285.966186) (xy 373.394287 -285.982185) (xy 373.343149 -285.990284) (xy 373.291375 -285.990284)
			(xy 373.240237 -285.982185) (xy 373.190997 -285.966186) (xy 373.144865 -285.94268) (xy 373.102978 -285.912248)
			(xy 373.066368 -285.875638) (xy 373.035936 -285.833751) (xy 373.01243 -285.787619) (xy 372.996431 -285.738379)
			(xy 372.988332 -285.687241) (xy 372.987824 -285.661354) (xy 372.988366 -285.633646) (xy 372.997553 -285.579)
			(xy 373.006112 -285.552642) (xy 373.013986 -285.530544) (xy 372.809008 -285.175706) (xy 372.786148 -285.171388)
			(xy 372.761323 -285.166238) (xy 372.713543 -285.149282) (xy 372.668923 -285.125209) (xy 372.628516 -285.094586)
			(xy 372.593275 -285.058137) (xy 372.564031 -285.016721) (xy 372.541476 -284.971315) (xy 372.526139 -284.922991)
			(xy 372.518385 -284.872888) (xy 372.517924 -284.847538) (xy 371.297708 -284.847538) (xy 371.297098 -284.875255)
			(xy 371.287785 -284.929901) (xy 371.279166 -284.95625) (xy 371.271292 -284.978348) (xy 371.47627 -285.333186)
			(xy 371.49913 -285.337504) (xy 371.523947 -285.342634) (xy 371.571689 -285.35963) (xy 371.616267 -285.383731)
			(xy 371.656634 -285.414369) (xy 371.691836 -285.450823) (xy 371.721046 -285.492235) (xy 371.743576 -285.537628)
			(xy 371.758894 -285.585934) (xy 371.76664 -285.636016) (xy 371.7671 -285.661354) (xy 371.766592 -285.687241)
			(xy 371.758493 -285.738379) (xy 371.742494 -285.787619) (xy 371.718988 -285.833751) (xy 371.688556 -285.875638)
			(xy 371.651946 -285.912248) (xy 371.610059 -285.94268) (xy 371.563927 -285.966186) (xy 371.514687 -285.982185)
			(xy 371.463549 -285.990284) (xy 371.411775 -285.990284) (xy 371.360637 -285.982185) (xy 371.311397 -285.966186)
			(xy 371.265265 -285.94268) (xy 371.223378 -285.912248) (xy 371.186768 -285.875638) (xy 371.156336 -285.833751)
			(xy 371.13283 -285.787619) (xy 371.116831 -285.738379) (xy 371.108732 -285.687241) (xy 371.108224 -285.661354)
			(xy 371.108766 -285.633646) (xy 371.117953 -285.579) (xy 371.126512 -285.552642) (xy 371.134386 -285.530544)
			(xy 370.929408 -285.175706) (xy 370.906548 -285.171388) (xy 370.881723 -285.166238) (xy 370.833943 -285.149282)
			(xy 370.789323 -285.125209) (xy 370.748916 -285.094586) (xy 370.713675 -285.058137) (xy 370.684431 -285.016721)
			(xy 370.661876 -284.971315) (xy 370.646539 -284.922991) (xy 370.638785 -284.872888) (xy 370.638324 -284.847538)
			(xy 369.418108 -284.847538) (xy 369.417498 -284.875255) (xy 369.408185 -284.929901) (xy 369.399566 -284.95625)
			(xy 369.391692 -284.978348) (xy 369.59667 -285.333186) (xy 369.61953 -285.337504) (xy 369.644347 -285.342634)
			(xy 369.692089 -285.35963) (xy 369.736667 -285.383731) (xy 369.777034 -285.414369) (xy 369.812236 -285.450823)
			(xy 369.841446 -285.492235) (xy 369.863976 -285.537628) (xy 369.879294 -285.585934) (xy 369.88704 -285.636016)
			(xy 369.8875 -285.661354) (xy 369.886992 -285.687241) (xy 369.878893 -285.738379) (xy 369.862894 -285.787619)
			(xy 369.839388 -285.833751) (xy 369.808956 -285.875638) (xy 369.772346 -285.912248) (xy 369.730459 -285.94268)
			(xy 369.684327 -285.966186) (xy 369.635087 -285.982185) (xy 369.583949 -285.990284) (xy 369.532175 -285.990284)
			(xy 369.481037 -285.982185) (xy 369.431797 -285.966186) (xy 369.385665 -285.94268) (xy 369.343778 -285.912248)
			(xy 369.307168 -285.875638) (xy 369.276736 -285.833751) (xy 369.25323 -285.787619) (xy 369.237231 -285.738379)
			(xy 369.229132 -285.687241) (xy 369.228624 -285.661354) (xy 369.229166 -285.633646) (xy 369.238353 -285.579)
			(xy 369.246912 -285.552642) (xy 369.254786 -285.530544) (xy 369.049808 -285.175706) (xy 369.026948 -285.171388)
			(xy 369.002123 -285.166238) (xy 368.954343 -285.149282) (xy 368.909723 -285.125209) (xy 368.869316 -285.094586)
			(xy 368.834075 -285.058137) (xy 368.804831 -285.016721) (xy 368.782276 -284.971315) (xy 368.766939 -284.922991)
			(xy 368.759185 -284.872888) (xy 368.758724 -284.847538) (xy 367.556676 -284.847538) (xy 367.868962 -285.392368)
			(xy 367.877344 -285.398464) (xy 367.898162 -285.414928) (xy 367.93476 -285.453362) (xy 367.964736 -285.497158)
			(xy 367.987319 -285.545185) (xy 368.001926 -285.596207) (xy 368.005614 -285.622492) (xy 368.006884 -285.632652)
			(xy 368.11839 -285.827216) (xy 368.126441 -285.840195) (xy 368.148786 -285.860999) (xy 368.176271 -285.874289)
			(xy 368.206453 -285.878884) (xy 368.236648 -285.874376) (xy 368.264172 -285.861164) (xy 368.286576 -285.840425)
			(xy 368.294666 -285.82747) (xy 368.314986 -285.792164) (xy 368.307112 -285.77032) (xy 368.298534 -285.743901)
			(xy 368.289339 -285.689126) (xy 368.288824 -285.661354) (xy 368.289332 -285.635467) (xy 368.297431 -285.584329)
			(xy 368.31343 -285.535089) (xy 368.336936 -285.488957) (xy 368.367368 -285.44707) (xy 368.403978 -285.41046)
			(xy 368.445865 -285.380028) (xy 368.491997 -285.356522) (xy 368.541237 -285.340523) (xy 368.592375 -285.332424)
			(xy 368.644149 -285.332424) (xy 368.695287 -285.340523) (xy 368.744527 -285.356522) (xy 368.790659 -285.380028)
			(xy 368.832546 -285.41046) (xy 368.869156 -285.44707) (xy 368.899588 -285.488957) (xy 368.923094 -285.535089)
			(xy 368.939093 -285.584329) (xy 368.947192 -285.635467) (xy 368.9477 -285.661354) (xy 368.947239 -285.686692)
			(xy 368.939492 -285.736772) (xy 368.924173 -285.785078) (xy 368.901644 -285.83047) (xy 368.872433 -285.87188)
			(xy 368.837231 -285.908334) (xy 368.796865 -285.938971) (xy 368.752286 -285.963071) (xy 368.704545 -285.980066)
			(xy 368.67973 -285.985204) (xy 368.65687 -285.989522) (xy 368.451892 -286.344614) (xy 368.459766 -286.366458)
			(xy 368.465943 -286.385017) (xy 368.474352 -286.423219) (xy 368.47653 -286.442658) (xy 368.477546 -286.45358)
			(xy 368.490082 -286.475424) (xy 369.698524 -286.475424) (xy 369.699048 -286.45008) (xy 369.706816 -286.399991)
			(xy 369.722159 -286.351681) (xy 369.744715 -286.306288) (xy 369.773951 -286.264882) (xy 369.80918 -286.228438)
			(xy 369.849572 -286.197814) (xy 369.894174 -286.173733) (xy 369.941936 -286.156761) (xy 369.966748 -286.151574)
			(xy 369.989608 -286.147256) (xy 370.194586 -285.792164) (xy 370.186712 -285.77032) (xy 370.178138 -285.7439)
			(xy 370.168938 -285.689126) (xy 370.168424 -285.661354) (xy 370.168932 -285.635467) (xy 370.177031 -285.584329)
			(xy 370.19303 -285.535089) (xy 370.216536 -285.488957) (xy 370.246968 -285.44707) (xy 370.283578 -285.41046)
			(xy 370.325465 -285.380028) (xy 370.371597 -285.356522) (xy 370.420837 -285.340523) (xy 370.471975 -285.332424)
			(xy 370.523749 -285.332424) (xy 370.574887 -285.340523) (xy 370.624127 -285.356522) (xy 370.670259 -285.380028)
			(xy 370.712146 -285.41046) (xy 370.748756 -285.44707) (xy 370.779188 -285.488957) (xy 370.802694 -285.535089)
			(xy 370.818693 -285.584329) (xy 370.826792 -285.635467) (xy 370.8273 -285.661354) (xy 370.826866 -285.68669)
			(xy 370.819106 -285.736765) (xy 370.803776 -285.785062) (xy 370.781238 -285.830446) (xy 370.752022 -285.871848)
			(xy 370.716816 -285.908293) (xy 370.676449 -285.938922) (xy 370.631871 -285.963016) (xy 370.584131 -285.980006)
			(xy 370.55933 -285.985204) (xy 370.53647 -285.989522) (xy 370.331492 -286.344614) (xy 370.339366 -286.366458)
			(xy 370.348019 -286.392864) (xy 370.357334 -286.447642) (xy 370.357908 -286.475424) (xy 371.578124 -286.475424)
			(xy 371.578648 -286.45008) (xy 371.586416 -286.399991) (xy 371.601759 -286.351681) (xy 371.624315 -286.306288)
			(xy 371.653551 -286.264882) (xy 371.68878 -286.228438) (xy 371.729172 -286.197814) (xy 371.773774 -286.173733)
			(xy 371.821536 -286.156761) (xy 371.846348 -286.151574) (xy 371.869208 -286.147256) (xy 372.074186 -285.792164)
			(xy 372.066312 -285.77032) (xy 372.057738 -285.7439) (xy 372.048538 -285.689126) (xy 372.048024 -285.661354)
			(xy 372.048532 -285.635467) (xy 372.056631 -285.584329) (xy 372.07263 -285.535089) (xy 372.096136 -285.488957)
			(xy 372.126568 -285.44707) (xy 372.163178 -285.41046) (xy 372.205065 -285.380028) (xy 372.251197 -285.356522)
			(xy 372.300437 -285.340523) (xy 372.351575 -285.332424) (xy 372.403349 -285.332424) (xy 372.454487 -285.340523)
			(xy 372.503727 -285.356522) (xy 372.549859 -285.380028) (xy 372.591746 -285.41046) (xy 372.628356 -285.44707)
			(xy 372.658788 -285.488957) (xy 372.682294 -285.535089) (xy 372.698293 -285.584329) (xy 372.706392 -285.635467)
			(xy 372.7069 -285.661354) (xy 372.706466 -285.68669) (xy 372.698706 -285.736765) (xy 372.683376 -285.785062)
			(xy 372.660838 -285.830446) (xy 372.631622 -285.871848) (xy 372.596416 -285.908293) (xy 372.556049 -285.938922)
			(xy 372.511471 -285.963016) (xy 372.463731 -285.980006) (xy 372.43893 -285.985204) (xy 372.41607 -285.989522)
			(xy 372.211092 -286.344614) (xy 372.218966 -286.366458) (xy 372.227619 -286.392864) (xy 372.236934 -286.447642)
			(xy 372.237508 -286.475424) (xy 373.457724 -286.475424) (xy 373.458248 -286.45008) (xy 373.466016 -286.399991)
			(xy 373.481359 -286.351681) (xy 373.503915 -286.306288) (xy 373.533151 -286.264882) (xy 373.56838 -286.228438)
			(xy 373.608772 -286.197814) (xy 373.653374 -286.173733) (xy 373.701136 -286.156761) (xy 373.725948 -286.151574)
			(xy 373.748808 -286.147256) (xy 373.953786 -285.792164) (xy 373.945912 -285.77032) (xy 373.937338 -285.7439)
			(xy 373.928138 -285.689126) (xy 373.927624 -285.661354) (xy 373.928132 -285.635467) (xy 373.936231 -285.584329)
			(xy 373.95223 -285.535089) (xy 373.975736 -285.488957) (xy 374.006168 -285.44707) (xy 374.042778 -285.41046)
			(xy 374.084665 -285.380028) (xy 374.130797 -285.356522) (xy 374.180037 -285.340523) (xy 374.231175 -285.332424)
			(xy 374.282949 -285.332424) (xy 374.334087 -285.340523) (xy 374.383327 -285.356522) (xy 374.429459 -285.380028)
			(xy 374.471346 -285.41046) (xy 374.507956 -285.44707) (xy 374.538388 -285.488957) (xy 374.561894 -285.535089)
			(xy 374.577893 -285.584329) (xy 374.585992 -285.635467) (xy 374.5865 -285.661354) (xy 374.586066 -285.68669)
			(xy 374.578306 -285.736765) (xy 374.562976 -285.785062) (xy 374.540438 -285.830446) (xy 374.511222 -285.871848)
			(xy 374.476016 -285.908293) (xy 374.435649 -285.938922) (xy 374.391071 -285.963016) (xy 374.343331 -285.980006)
			(xy 374.31853 -285.985204) (xy 374.29567 -285.989522) (xy 374.090692 -286.344614) (xy 374.098566 -286.366458)
			(xy 374.107219 -286.392864) (xy 374.116534 -286.447642) (xy 374.117108 -286.475424) (xy 375.337324 -286.475424)
			(xy 375.337848 -286.45008) (xy 375.345616 -286.399991) (xy 375.360959 -286.351681) (xy 375.383515 -286.306288)
			(xy 375.412751 -286.264882) (xy 375.44798 -286.228438) (xy 375.488372 -286.197814) (xy 375.532974 -286.173733)
			(xy 375.580736 -286.156761) (xy 375.605548 -286.151574) (xy 375.628408 -286.147256) (xy 375.833386 -285.792164)
			(xy 375.825512 -285.77032) (xy 375.816938 -285.7439) (xy 375.807738 -285.689126) (xy 375.807224 -285.661354)
			(xy 375.807732 -285.635467) (xy 375.815831 -285.584329) (xy 375.83183 -285.535089) (xy 375.855336 -285.488957)
			(xy 375.885768 -285.44707) (xy 375.922378 -285.41046) (xy 375.964265 -285.380028) (xy 376.010397 -285.356522)
			(xy 376.059637 -285.340523) (xy 376.110775 -285.332424) (xy 376.162549 -285.332424) (xy 376.213687 -285.340523)
			(xy 376.262927 -285.356522) (xy 376.309059 -285.380028) (xy 376.350946 -285.41046) (xy 376.387556 -285.44707)
			(xy 376.417988 -285.488957) (xy 376.441494 -285.535089) (xy 376.457493 -285.584329) (xy 376.465592 -285.635467)
			(xy 376.4661 -285.661354) (xy 376.465666 -285.68669) (xy 376.457906 -285.736765) (xy 376.442576 -285.785062)
			(xy 376.420038 -285.830446) (xy 376.390822 -285.871848) (xy 376.355616 -285.908293) (xy 376.315249 -285.938922)
			(xy 376.270671 -285.963016) (xy 376.222931 -285.980006) (xy 376.19813 -285.985204) (xy 376.17527 -285.989522)
			(xy 375.970292 -286.344614) (xy 375.978166 -286.366458) (xy 375.986819 -286.392864) (xy 375.996134 -286.447642)
			(xy 375.996708 -286.475424) (xy 377.216924 -286.475424) (xy 377.217448 -286.45008) (xy 377.225216 -286.399991)
			(xy 377.240559 -286.351681) (xy 377.263115 -286.306288) (xy 377.292351 -286.264882) (xy 377.32758 -286.228438)
			(xy 377.367972 -286.197814) (xy 377.412574 -286.173733) (xy 377.460336 -286.156761) (xy 377.485148 -286.151574)
			(xy 377.508008 -286.147256) (xy 377.712986 -285.792164) (xy 377.705112 -285.77032) (xy 377.696538 -285.7439)
			(xy 377.687338 -285.689126) (xy 377.686824 -285.661354) (xy 377.687332 -285.635467) (xy 377.695431 -285.584329)
			(xy 377.71143 -285.535089) (xy 377.734936 -285.488957) (xy 377.765368 -285.44707) (xy 377.801978 -285.41046)
			(xy 377.843865 -285.380028) (xy 377.889997 -285.356522) (xy 377.939237 -285.340523) (xy 377.990375 -285.332424)
			(xy 378.042149 -285.332424) (xy 378.093287 -285.340523) (xy 378.142527 -285.356522) (xy 378.188659 -285.380028)
			(xy 378.230546 -285.41046) (xy 378.267156 -285.44707) (xy 378.297588 -285.488957) (xy 378.321094 -285.535089)
			(xy 378.337093 -285.584329) (xy 378.345192 -285.635467) (xy 378.3457 -285.661354) (xy 378.345266 -285.68669)
			(xy 378.337506 -285.736765) (xy 378.322176 -285.785062) (xy 378.299638 -285.830446) (xy 378.270422 -285.871848)
			(xy 378.235216 -285.908293) (xy 378.194849 -285.938922) (xy 378.150271 -285.963016) (xy 378.102531 -285.980006)
			(xy 378.07773 -285.985204) (xy 378.05487 -285.989522) (xy 377.849892 -286.344614) (xy 377.857766 -286.366458)
			(xy 377.866419 -286.392864) (xy 377.875734 -286.447642) (xy 377.876308 -286.475424) (xy 379.096524 -286.475424)
			(xy 379.097048 -286.45008) (xy 379.104816 -286.399991) (xy 379.120159 -286.351681) (xy 379.142715 -286.306288)
			(xy 379.171951 -286.264882) (xy 379.20718 -286.228438) (xy 379.247572 -286.197814) (xy 379.292174 -286.173733)
			(xy 379.339936 -286.156761) (xy 379.364748 -286.151574) (xy 379.387608 -286.147256) (xy 379.592586 -285.792164)
			(xy 379.584712 -285.77032) (xy 379.576138 -285.7439) (xy 379.566938 -285.689126) (xy 379.566424 -285.661354)
			(xy 379.566932 -285.635467) (xy 379.575031 -285.584329) (xy 379.59103 -285.535089) (xy 379.614536 -285.488957)
			(xy 379.644968 -285.44707) (xy 379.681578 -285.41046) (xy 379.723465 -285.380028) (xy 379.769597 -285.356522)
			(xy 379.818837 -285.340523) (xy 379.869975 -285.332424) (xy 379.921749 -285.332424) (xy 379.972887 -285.340523)
			(xy 380.022127 -285.356522) (xy 380.068259 -285.380028) (xy 380.110146 -285.41046) (xy 380.146756 -285.44707)
			(xy 380.177188 -285.488957) (xy 380.200694 -285.535089) (xy 380.216693 -285.584329) (xy 380.224792 -285.635467)
			(xy 380.2253 -285.661354) (xy 380.224866 -285.68669) (xy 380.217106 -285.736765) (xy 380.201776 -285.785062)
			(xy 380.179238 -285.830446) (xy 380.150022 -285.871848) (xy 380.114816 -285.908293) (xy 380.074449 -285.938922)
			(xy 380.029871 -285.963016) (xy 379.982131 -285.980006) (xy 379.95733 -285.985204) (xy 379.93447 -285.989522)
			(xy 379.729492 -286.344614) (xy 379.737366 -286.366458) (xy 379.746019 -286.392864) (xy 379.755334 -286.447642)
			(xy 379.755908 -286.475424) (xy 380.976124 -286.475424) (xy 380.976648 -286.45008) (xy 380.984416 -286.399991)
			(xy 380.999759 -286.351681) (xy 381.022315 -286.306288) (xy 381.051551 -286.264882) (xy 381.08678 -286.228438)
			(xy 381.127172 -286.197814) (xy 381.171774 -286.173733) (xy 381.219536 -286.156761) (xy 381.244348 -286.151574)
			(xy 381.267208 -286.147256) (xy 381.472186 -285.792164) (xy 381.464312 -285.77032) (xy 381.455738 -285.7439)
			(xy 381.446538 -285.689126) (xy 381.446024 -285.661354) (xy 381.446532 -285.635467) (xy 381.454631 -285.584329)
			(xy 381.47063 -285.535089) (xy 381.494136 -285.488957) (xy 381.524568 -285.44707) (xy 381.561178 -285.41046)
			(xy 381.603065 -285.380028) (xy 381.649197 -285.356522) (xy 381.698437 -285.340523) (xy 381.749575 -285.332424)
			(xy 381.801349 -285.332424) (xy 381.852487 -285.340523) (xy 381.901727 -285.356522) (xy 381.947859 -285.380028)
			(xy 381.989746 -285.41046) (xy 382.026356 -285.44707) (xy 382.056788 -285.488957) (xy 382.080294 -285.535089)
			(xy 382.096293 -285.584329) (xy 382.104392 -285.635467) (xy 382.1049 -285.661354) (xy 382.104466 -285.68669)
			(xy 382.096706 -285.736765) (xy 382.081376 -285.785062) (xy 382.058838 -285.830446) (xy 382.029622 -285.871848)
			(xy 381.994416 -285.908293) (xy 381.954049 -285.938922) (xy 381.909471 -285.963016) (xy 381.861731 -285.980006)
			(xy 381.83693 -285.985204) (xy 381.81407 -285.989522) (xy 381.609092 -286.344614) (xy 381.616966 -286.366458)
			(xy 381.625619 -286.392864) (xy 381.634934 -286.447642) (xy 381.635508 -286.475424) (xy 381.635 -286.501331)
			(xy 381.626894 -286.552508) (xy 381.610882 -286.601787) (xy 381.587359 -286.647954) (xy 381.556903 -286.689873)
			(xy 381.520265 -286.726511) (xy 381.478346 -286.756967) (xy 381.432179 -286.78049) (xy 381.3829 -286.796502)
			(xy 381.331723 -286.804608) (xy 381.279909 -286.804608) (xy 381.228732 -286.796502) (xy 381.179453 -286.78049)
			(xy 381.133286 -286.756967) (xy 381.091367 -286.726511) (xy 381.054729 -286.689873) (xy 381.024273 -286.647954)
			(xy 381.00075 -286.601787) (xy 380.984738 -286.552508) (xy 380.976632 -286.501331) (xy 380.976124 -286.475424)
			(xy 379.755908 -286.475424) (xy 379.7554 -286.501331) (xy 379.747294 -286.552508) (xy 379.731282 -286.601787)
			(xy 379.707759 -286.647954) (xy 379.677303 -286.689873) (xy 379.640665 -286.726511) (xy 379.598746 -286.756967)
			(xy 379.552579 -286.78049) (xy 379.5033 -286.796502) (xy 379.452123 -286.804608) (xy 379.400309 -286.804608)
			(xy 379.349132 -286.796502) (xy 379.299853 -286.78049) (xy 379.253686 -286.756967) (xy 379.211767 -286.726511)
			(xy 379.175129 -286.689873) (xy 379.144673 -286.647954) (xy 379.12115 -286.601787) (xy 379.105138 -286.552508)
			(xy 379.097032 -286.501331) (xy 379.096524 -286.475424) (xy 377.876308 -286.475424) (xy 377.8758 -286.501331)
			(xy 377.867694 -286.552508) (xy 377.851682 -286.601787) (xy 377.828159 -286.647954) (xy 377.797703 -286.689873)
			(xy 377.761065 -286.726511) (xy 377.719146 -286.756967) (xy 377.672979 -286.78049) (xy 377.6237 -286.796502)
			(xy 377.572523 -286.804608) (xy 377.520709 -286.804608) (xy 377.469532 -286.796502) (xy 377.420253 -286.78049)
			(xy 377.374086 -286.756967) (xy 377.332167 -286.726511) (xy 377.295529 -286.689873) (xy 377.265073 -286.647954)
			(xy 377.24155 -286.601787) (xy 377.225538 -286.552508) (xy 377.217432 -286.501331) (xy 377.216924 -286.475424)
			(xy 375.996708 -286.475424) (xy 375.9962 -286.501331) (xy 375.988094 -286.552508) (xy 375.972082 -286.601787)
			(xy 375.948559 -286.647954) (xy 375.918103 -286.689873) (xy 375.881465 -286.726511) (xy 375.839546 -286.756967)
			(xy 375.793379 -286.78049) (xy 375.7441 -286.796502) (xy 375.692923 -286.804608) (xy 375.641109 -286.804608)
			(xy 375.589932 -286.796502) (xy 375.540653 -286.78049) (xy 375.494486 -286.756967) (xy 375.452567 -286.726511)
			(xy 375.415929 -286.689873) (xy 375.385473 -286.647954) (xy 375.36195 -286.601787) (xy 375.345938 -286.552508)
			(xy 375.337832 -286.501331) (xy 375.337324 -286.475424) (xy 374.117108 -286.475424) (xy 374.1166 -286.501331)
			(xy 374.108494 -286.552508) (xy 374.092482 -286.601787) (xy 374.068959 -286.647954) (xy 374.038503 -286.689873)
			(xy 374.001865 -286.726511) (xy 373.959946 -286.756967) (xy 373.913779 -286.78049) (xy 373.8645 -286.796502)
			(xy 373.813323 -286.804608) (xy 373.761509 -286.804608) (xy 373.710332 -286.796502) (xy 373.661053 -286.78049)
			(xy 373.614886 -286.756967) (xy 373.572967 -286.726511) (xy 373.536329 -286.689873) (xy 373.505873 -286.647954)
			(xy 373.48235 -286.601787) (xy 373.466338 -286.552508) (xy 373.458232 -286.501331) (xy 373.457724 -286.475424)
			(xy 372.237508 -286.475424) (xy 372.237 -286.501331) (xy 372.228894 -286.552508) (xy 372.212882 -286.601787)
			(xy 372.189359 -286.647954) (xy 372.158903 -286.689873) (xy 372.122265 -286.726511) (xy 372.080346 -286.756967)
			(xy 372.034179 -286.78049) (xy 371.9849 -286.796502) (xy 371.933723 -286.804608) (xy 371.881909 -286.804608)
			(xy 371.830732 -286.796502) (xy 371.781453 -286.78049) (xy 371.735286 -286.756967) (xy 371.693367 -286.726511)
			(xy 371.656729 -286.689873) (xy 371.626273 -286.647954) (xy 371.60275 -286.601787) (xy 371.586738 -286.552508)
			(xy 371.578632 -286.501331) (xy 371.578124 -286.475424) (xy 370.357908 -286.475424) (xy 370.3574 -286.501331)
			(xy 370.349294 -286.552508) (xy 370.333282 -286.601787) (xy 370.309759 -286.647954) (xy 370.279303 -286.689873)
			(xy 370.242665 -286.726511) (xy 370.200746 -286.756967) (xy 370.154579 -286.78049) (xy 370.1053 -286.796502)
			(xy 370.054123 -286.804608) (xy 370.002309 -286.804608) (xy 369.951132 -286.796502) (xy 369.901853 -286.78049)
			(xy 369.855686 -286.756967) (xy 369.813767 -286.726511) (xy 369.777129 -286.689873) (xy 369.746673 -286.647954)
			(xy 369.72315 -286.601787) (xy 369.707138 -286.552508) (xy 369.699032 -286.501331) (xy 369.698524 -286.475424)
			(xy 368.490082 -286.475424) (xy 368.800126 -287.015682) (xy 368.809016 -287.022286) (xy 368.827925 -287.036281)
			(xy 368.861916 -287.068802) (xy 368.890913 -287.105845) (xy 368.914323 -287.14665) (xy 368.931663 -287.19038)
			(xy 368.942581 -287.236138) (xy 368.94516 -287.259522) (xy 368.946176 -287.270444) (xy 369.263168 -287.823402)
			(xy 369.27282 -287.830006) (xy 369.293333 -287.844408) (xy 369.330157 -287.878407) (xy 369.361406 -287.917591)
			(xy 369.386359 -287.961057) (xy 369.40444 -288.007801) (xy 369.415231 -288.056745) (xy 369.417346 -288.08172)
			(xy 369.418108 -288.093658) (xy 369.728242 -288.634424) (xy 369.738402 -288.641028) (xy 369.758297 -288.654557)
			(xy 369.794312 -288.686455) (xy 369.825311 -288.723247) (xy 369.850637 -288.764152) (xy 369.860576 -288.786062)
			(xy 369.874038 -288.816542) (xy 370.182394 -288.816542) (xy 370.195856 -288.786062) (xy 370.206452 -288.762832)
			(xy 370.233746 -288.719684) (xy 370.26737 -288.681264) (xy 370.306518 -288.648491) (xy 370.350254 -288.622149)
			(xy 370.397529 -288.60287) (xy 370.447213 -288.591115) (xy 370.498116 -288.587165) (xy 370.549019 -288.591115)
			(xy 370.598703 -288.60287) (xy 370.645978 -288.622149) (xy 370.689714 -288.648491) (xy 370.728862 -288.681264)
			(xy 370.762486 -288.719684) (xy 370.78978 -288.762832) (xy 370.800376 -288.786062) (xy 370.813838 -288.816542)
			(xy 370.976144 -288.816542) (xy 370.991386 -288.81604) (xy 371.020518 -288.807064) (xy 371.045704 -288.789892)
			(xy 371.064705 -288.766055) (xy 371.075828 -288.737673) (xy 371.078082 -288.707274) (xy 371.071269 -288.677562)
			(xy 371.064028 -288.664142) (xy 370.929662 -288.431224) (xy 370.906802 -288.426906) (xy 370.88196 -288.421763)
			(xy 370.83413 -288.40486) (xy 370.789458 -288.380821) (xy 370.749001 -288.350216) (xy 370.713717 -288.313767)
			(xy 370.684441 -288.272338) (xy 370.661866 -288.226909) (xy 370.646525 -288.178556) (xy 370.638781 -288.128421)
			(xy 370.638324 -288.103056) (xy 370.638832 -288.077149) (xy 370.646938 -288.025972) (xy 370.66295 -287.976693)
			(xy 370.686473 -287.930526) (xy 370.716929 -287.888607) (xy 370.753567 -287.851969) (xy 370.795486 -287.821513)
			(xy 370.841653 -287.79799) (xy 370.890932 -287.781978) (xy 370.942109 -287.773872) (xy 370.993923 -287.773872)
			(xy 371.0451 -287.781978) (xy 371.094379 -287.79799) (xy 371.140546 -287.821513) (xy 371.182465 -287.851969)
			(xy 371.219103 -287.888607) (xy 371.249559 -287.930526) (xy 371.273082 -287.976693) (xy 371.289094 -288.025972)
			(xy 371.2972 -288.077149) (xy 371.297708 -288.103056) (xy 371.297115 -288.130773) (xy 371.287787 -288.185419)
			(xy 371.279166 -288.211768) (xy 371.271546 -288.233866) (xy 371.476524 -288.588958) (xy 371.499384 -288.593276)
			(xy 371.525582 -288.598796) (xy 371.575864 -288.617174) (xy 371.622517 -288.643435) (xy 371.664315 -288.676887)
			(xy 371.700159 -288.716652) (xy 371.72911 -288.761684) (xy 371.740176 -288.786062) (xy 371.753638 -288.816542)
			(xy 372.061994 -288.816542) (xy 372.075456 -288.786062) (xy 372.086052 -288.762832) (xy 372.113346 -288.719684)
			(xy 372.14697 -288.681264) (xy 372.186118 -288.648491) (xy 372.229854 -288.622149) (xy 372.277129 -288.60287)
			(xy 372.326813 -288.591115) (xy 372.377716 -288.587165) (xy 372.428619 -288.591115) (xy 372.478303 -288.60287)
			(xy 372.525578 -288.622149) (xy 372.569314 -288.648491) (xy 372.608462 -288.681264) (xy 372.642086 -288.719684)
			(xy 372.66938 -288.762832) (xy 372.679976 -288.786062) (xy 372.693438 -288.816542) (xy 372.855744 -288.816542)
			(xy 372.870986 -288.81604) (xy 372.900118 -288.807064) (xy 372.925304 -288.789892) (xy 372.944305 -288.766055)
			(xy 372.955428 -288.737673) (xy 372.957682 -288.707274) (xy 372.950869 -288.677562) (xy 372.943628 -288.664142)
			(xy 372.809262 -288.431224) (xy 372.786402 -288.426906) (xy 372.76156 -288.421763) (xy 372.71373 -288.40486)
			(xy 372.669058 -288.380821) (xy 372.628601 -288.350216) (xy 372.593317 -288.313767) (xy 372.564041 -288.272338)
			(xy 372.541466 -288.226909) (xy 372.526125 -288.178556) (xy 372.518381 -288.128421) (xy 372.517924 -288.103056)
			(xy 372.518432 -288.077149) (xy 372.526538 -288.025972) (xy 372.54255 -287.976693) (xy 372.566073 -287.930526)
			(xy 372.596529 -287.888607) (xy 372.633167 -287.851969) (xy 372.675086 -287.821513) (xy 372.721253 -287.79799)
			(xy 372.770532 -287.781978) (xy 372.821709 -287.773872) (xy 372.873523 -287.773872) (xy 372.9247 -287.781978)
			(xy 372.973979 -287.79799) (xy 373.020146 -287.821513) (xy 373.062065 -287.851969) (xy 373.098703 -287.888607)
			(xy 373.129159 -287.930526) (xy 373.152682 -287.976693) (xy 373.168694 -288.025972) (xy 373.1768 -288.077149)
			(xy 373.177308 -288.103056) (xy 373.176715 -288.130773) (xy 373.167387 -288.185419) (xy 373.158766 -288.211768)
			(xy 373.151146 -288.233866) (xy 373.356124 -288.588958) (xy 373.378984 -288.593276) (xy 373.405182 -288.598796)
			(xy 373.455464 -288.617174) (xy 373.502117 -288.643435) (xy 373.543915 -288.676887) (xy 373.579759 -288.716652)
			(xy 373.60871 -288.761684) (xy 373.619776 -288.786062) (xy 373.633238 -288.816542) (xy 373.941594 -288.816542)
			(xy 373.955056 -288.786062) (xy 373.965652 -288.762832) (xy 373.992946 -288.719684) (xy 374.02657 -288.681264)
			(xy 374.065718 -288.648491) (xy 374.109454 -288.622149) (xy 374.156729 -288.60287) (xy 374.206413 -288.591115)
			(xy 374.257316 -288.587165) (xy 374.308219 -288.591115) (xy 374.357903 -288.60287) (xy 374.405178 -288.622149)
			(xy 374.448914 -288.648491) (xy 374.488062 -288.681264) (xy 374.521686 -288.719684) (xy 374.54898 -288.762832)
			(xy 374.559576 -288.786062) (xy 374.573038 -288.816542) (xy 374.735344 -288.816542) (xy 374.750586 -288.81604)
			(xy 374.779718 -288.807064) (xy 374.804904 -288.789892) (xy 374.823905 -288.766055) (xy 374.835028 -288.737673)
			(xy 374.837282 -288.707274) (xy 374.830469 -288.677562) (xy 374.823228 -288.664142) (xy 374.688862 -288.431224)
			(xy 374.666002 -288.426906) (xy 374.64116 -288.421763) (xy 374.59333 -288.40486) (xy 374.548658 -288.380821)
			(xy 374.508201 -288.350216) (xy 374.472917 -288.313767) (xy 374.443641 -288.272338) (xy 374.421066 -288.226909)
			(xy 374.405725 -288.178556) (xy 374.397981 -288.128421) (xy 374.397524 -288.103056) (xy 374.398032 -288.077149)
			(xy 374.406138 -288.025972) (xy 374.42215 -287.976693) (xy 374.445673 -287.930526) (xy 374.476129 -287.888607)
			(xy 374.512767 -287.851969) (xy 374.554686 -287.821513) (xy 374.600853 -287.79799) (xy 374.650132 -287.781978)
			(xy 374.701309 -287.773872) (xy 374.753123 -287.773872) (xy 374.8043 -287.781978) (xy 374.853579 -287.79799)
			(xy 374.899746 -287.821513) (xy 374.941665 -287.851969) (xy 374.978303 -287.888607) (xy 375.008759 -287.930526)
			(xy 375.032282 -287.976693) (xy 375.048294 -288.025972) (xy 375.0564 -288.077149) (xy 375.056908 -288.103056)
			(xy 375.056315 -288.130773) (xy 375.046987 -288.185419) (xy 375.038366 -288.211768) (xy 375.030746 -288.233866)
			(xy 375.235724 -288.588958) (xy 375.258584 -288.593276) (xy 375.284782 -288.598796) (xy 375.335064 -288.617174)
			(xy 375.381717 -288.643435) (xy 375.423515 -288.676887) (xy 375.459359 -288.716652) (xy 375.48831 -288.761684)
			(xy 375.499376 -288.786062) (xy 375.512838 -288.816542) (xy 375.821194 -288.816542) (xy 375.834656 -288.786062)
			(xy 375.845252 -288.762832) (xy 375.872546 -288.719684) (xy 375.90617 -288.681264) (xy 375.945318 -288.648491)
			(xy 375.989054 -288.622149) (xy 376.036329 -288.60287) (xy 376.086013 -288.591115) (xy 376.136916 -288.587165)
			(xy 376.187819 -288.591115) (xy 376.237503 -288.60287) (xy 376.284778 -288.622149) (xy 376.328514 -288.648491)
			(xy 376.367662 -288.681264) (xy 376.401286 -288.719684) (xy 376.42858 -288.762832) (xy 376.439176 -288.786062)
			(xy 376.452638 -288.816542) (xy 376.614944 -288.816542) (xy 376.630186 -288.81604) (xy 376.659318 -288.807064)
			(xy 376.684504 -288.789892) (xy 376.703505 -288.766055) (xy 376.714628 -288.737673) (xy 376.716882 -288.707274)
			(xy 376.710069 -288.677562) (xy 376.702828 -288.664142) (xy 376.568462 -288.431224) (xy 376.545602 -288.426906)
			(xy 376.52076 -288.421763) (xy 376.47293 -288.40486) (xy 376.428258 -288.380821) (xy 376.387801 -288.350216)
			(xy 376.352517 -288.313767) (xy 376.323241 -288.272338) (xy 376.300666 -288.226909) (xy 376.285325 -288.178556)
			(xy 376.277581 -288.128421) (xy 376.277124 -288.103056) (xy 376.277632 -288.077149) (xy 376.285738 -288.025972)
			(xy 376.30175 -287.976693) (xy 376.325273 -287.930526) (xy 376.355729 -287.888607) (xy 376.392367 -287.851969)
			(xy 376.434286 -287.821513) (xy 376.480453 -287.79799) (xy 376.529732 -287.781978) (xy 376.580909 -287.773872)
			(xy 376.632723 -287.773872) (xy 376.6839 -287.781978) (xy 376.733179 -287.79799) (xy 376.779346 -287.821513)
			(xy 376.821265 -287.851969) (xy 376.857903 -287.888607) (xy 376.888359 -287.930526) (xy 376.911882 -287.976693)
			(xy 376.927894 -288.025972) (xy 376.936 -288.077149) (xy 376.936508 -288.103056) (xy 376.935915 -288.130773)
			(xy 376.926587 -288.185419) (xy 376.917966 -288.211768) (xy 376.910346 -288.233866) (xy 377.115324 -288.588958)
			(xy 377.138184 -288.593276) (xy 377.164382 -288.598796) (xy 377.214664 -288.617174) (xy 377.261317 -288.643435)
			(xy 377.303115 -288.676887) (xy 377.338959 -288.716652) (xy 377.36791 -288.761684) (xy 377.378976 -288.786062)
			(xy 377.392438 -288.816542) (xy 377.700794 -288.816542) (xy 377.714256 -288.786062) (xy 377.724852 -288.762832)
			(xy 377.752146 -288.719684) (xy 377.78577 -288.681264) (xy 377.824918 -288.648491) (xy 377.868654 -288.622149)
			(xy 377.915929 -288.60287) (xy 377.965613 -288.591115) (xy 378.016516 -288.587165) (xy 378.067419 -288.591115)
			(xy 378.117103 -288.60287) (xy 378.164378 -288.622149) (xy 378.208114 -288.648491) (xy 378.247262 -288.681264)
			(xy 378.280886 -288.719684) (xy 378.30818 -288.762832) (xy 378.318776 -288.786062) (xy 378.332238 -288.816542)
			(xy 378.494544 -288.816542) (xy 378.509786 -288.81604) (xy 378.538918 -288.807064) (xy 378.564104 -288.789892)
			(xy 378.583105 -288.766055) (xy 378.594228 -288.737673) (xy 378.596482 -288.707274) (xy 378.589669 -288.677562)
			(xy 378.582428 -288.664142) (xy 378.448062 -288.431224) (xy 378.425202 -288.426906) (xy 378.40036 -288.421763)
			(xy 378.35253 -288.40486) (xy 378.307858 -288.380821) (xy 378.267401 -288.350216) (xy 378.232117 -288.313767)
			(xy 378.202841 -288.272338) (xy 378.180266 -288.226909) (xy 378.164925 -288.178556) (xy 378.157181 -288.128421)
			(xy 378.156724 -288.103056) (xy 378.157232 -288.077149) (xy 378.165338 -288.025972) (xy 378.18135 -287.976693)
			(xy 378.204873 -287.930526) (xy 378.235329 -287.888607) (xy 378.271967 -287.851969) (xy 378.313886 -287.821513)
			(xy 378.360053 -287.79799) (xy 378.409332 -287.781978) (xy 378.460509 -287.773872) (xy 378.512323 -287.773872)
			(xy 378.5635 -287.781978) (xy 378.612779 -287.79799) (xy 378.658946 -287.821513) (xy 378.700865 -287.851969)
			(xy 378.737503 -287.888607) (xy 378.767959 -287.930526) (xy 378.791482 -287.976693) (xy 378.807494 -288.025972)
			(xy 378.8156 -288.077149) (xy 378.816108 -288.103056) (xy 378.815515 -288.130773) (xy 378.806187 -288.185419)
			(xy 378.797566 -288.211768) (xy 378.789946 -288.233866) (xy 378.994924 -288.588958) (xy 379.017784 -288.593276)
			(xy 379.043982 -288.598796) (xy 379.094264 -288.617174) (xy 379.140917 -288.643435) (xy 379.182715 -288.676887)
			(xy 379.218559 -288.716652) (xy 379.24751 -288.761684) (xy 379.258576 -288.786062) (xy 379.272038 -288.816542)
			(xy 379.580394 -288.816542) (xy 379.593856 -288.786062) (xy 379.604452 -288.762832) (xy 379.631746 -288.719684)
			(xy 379.66537 -288.681264) (xy 379.704518 -288.648491) (xy 379.748254 -288.622149) (xy 379.795529 -288.60287)
			(xy 379.845213 -288.591115) (xy 379.896116 -288.587165) (xy 379.947019 -288.591115) (xy 379.996703 -288.60287)
			(xy 380.043978 -288.622149) (xy 380.087714 -288.648491) (xy 380.126862 -288.681264) (xy 380.160486 -288.719684)
			(xy 380.18778 -288.762832) (xy 380.198376 -288.786062) (xy 380.211838 -288.816542) (xy 380.374144 -288.816542)
			(xy 380.389386 -288.81604) (xy 380.418518 -288.807064) (xy 380.443704 -288.789892) (xy 380.462705 -288.766055)
			(xy 380.473828 -288.737673) (xy 380.476082 -288.707274) (xy 380.469269 -288.677562) (xy 380.462028 -288.664142)
			(xy 380.327662 -288.431224) (xy 380.304802 -288.426906) (xy 380.27996 -288.421763) (xy 380.23213 -288.40486)
			(xy 380.187458 -288.380821) (xy 380.147001 -288.350216) (xy 380.111717 -288.313767) (xy 380.082441 -288.272338)
			(xy 380.059866 -288.226909) (xy 380.044525 -288.178556) (xy 380.036781 -288.128421) (xy 380.036324 -288.103056)
			(xy 380.036832 -288.077149) (xy 380.044938 -288.025972) (xy 380.06095 -287.976693) (xy 380.084473 -287.930526)
			(xy 380.114929 -287.888607) (xy 380.151567 -287.851969) (xy 380.193486 -287.821513) (xy 380.239653 -287.79799)
			(xy 380.288932 -287.781978) (xy 380.340109 -287.773872) (xy 380.391923 -287.773872) (xy 380.4431 -287.781978)
			(xy 380.492379 -287.79799) (xy 380.538546 -287.821513) (xy 380.580465 -287.851969) (xy 380.617103 -287.888607)
			(xy 380.647559 -287.930526) (xy 380.671082 -287.976693) (xy 380.687094 -288.025972) (xy 380.6952 -288.077149)
			(xy 380.695708 -288.103056) (xy 380.695115 -288.130773) (xy 380.685787 -288.185419) (xy 380.677166 -288.211768)
			(xy 380.669546 -288.233866) (xy 380.874524 -288.588958) (xy 380.897384 -288.593276) (xy 380.923582 -288.598796)
			(xy 380.973864 -288.617174) (xy 381.020517 -288.643435) (xy 381.062315 -288.676887) (xy 381.098159 -288.716652)
			(xy 381.12711 -288.761684) (xy 381.138176 -288.786062) (xy 381.151638 -288.816542) (xy 381.459994 -288.816542)
			(xy 381.473456 -288.786062) (xy 381.484052 -288.762832) (xy 381.511346 -288.719684) (xy 381.54497 -288.681264)
			(xy 381.584118 -288.648491) (xy 381.627854 -288.622149) (xy 381.675129 -288.60287) (xy 381.724813 -288.591115)
			(xy 381.775716 -288.587165) (xy 381.826619 -288.591115) (xy 381.876303 -288.60287) (xy 381.923578 -288.622149)
			(xy 381.967314 -288.648491) (xy 382.006462 -288.681264) (xy 382.040086 -288.719684) (xy 382.06738 -288.762832)
			(xy 382.077976 -288.786062) (xy 382.091438 -288.816542) (xy 382.401318 -288.816542) (xy 382.41478 -288.786062)
			(xy 382.425342 -288.762972) (xy 382.452528 -288.720089) (xy 382.485998 -288.681909) (xy 382.524952 -288.649344)
			(xy 382.56846 -288.623171) (xy 382.615482 -288.604016) (xy 382.664894 -288.592337) (xy 382.715516 -288.588412)
			(xy 382.766138 -288.592337) (xy 382.81555 -288.604016) (xy 382.862572 -288.623171) (xy 382.90608 -288.649344)
			(xy 382.945034 -288.681909) (xy 382.978504 -288.720089) (xy 383.00569 -288.762972) (xy 383.016252 -288.786062)
			(xy 383.029714 -288.816542) (xy 383.19329 -288.816542) (xy 383.208551 -288.816076) (xy 383.237737 -288.807151)
			(xy 383.262984 -288.790004) (xy 383.282041 -288.766166) (xy 383.293208 -288.737763) (xy 383.295487 -288.707328)
			(xy 383.288676 -288.677578) (xy 383.281428 -288.664142) (xy 383.146808 -288.431224) (xy 383.123948 -288.426906)
			(xy 383.099134 -288.42172) (xy 383.051366 -288.40475) (xy 383.006757 -288.38067) (xy 382.966358 -288.350048)
			(xy 382.931121 -288.313605) (xy 382.901875 -288.272199) (xy 382.87931 -288.226806) (xy 382.863956 -288.178494)
			(xy 382.856175 -288.128402) (xy 382.855724 -288.103056) (xy 382.856232 -288.077149) (xy 382.864338 -288.025972)
			(xy 382.88035 -287.976693) (xy 382.903873 -287.930526) (xy 382.934329 -287.888607) (xy 382.970967 -287.851969)
			(xy 383.012886 -287.821513) (xy 383.059053 -287.79799) (xy 383.108332 -287.781978) (xy 383.159509 -287.773872)
			(xy 383.211323 -287.773872) (xy 383.2625 -287.781978) (xy 383.311779 -287.79799) (xy 383.357946 -287.821513)
			(xy 383.399865 -287.851969) (xy 383.436503 -287.888607) (xy 383.466959 -287.930526) (xy 383.490482 -287.976693)
			(xy 383.506494 -288.025972) (xy 383.5146 -288.077149) (xy 383.515108 -288.103056) (xy 383.514515 -288.130773)
			(xy 383.505187 -288.185419) (xy 383.496566 -288.211768) (xy 383.488692 -288.233866) (xy 383.693924 -288.588958)
			(xy 383.716784 -288.593276) (xy 383.742982 -288.598796) (xy 383.793264 -288.617174) (xy 383.839917 -288.643435)
			(xy 383.881715 -288.676887) (xy 383.917559 -288.716652) (xy 383.94651 -288.761684) (xy 383.957576 -288.786062)
			(xy 383.971038 -288.816542) (xy 385.71805 -288.816542) (xy 385.743008 -288.817118) (xy 385.791964 -288.826867)
			(xy 385.838076 -288.845979) (xy 385.879574 -288.873722) (xy 385.897628 -288.890964) (xy 393.043156 -296.036492)
			(xy 393.060411 -296.054535) (xy 393.088159 -296.09603) (xy 393.107263 -296.142148) (xy 393.116985 -296.191111)
			(xy 393.117578 -296.21607) (xy 393.117578 -329.804014) (xy 393.466574 -330.15301) (xy 396.150338 -330.15301)
			(xy 396.175293 -330.153625) (xy 396.224243 -330.163369) (xy 396.270351 -330.182476) (xy 396.311846 -330.21021)
			(xy 396.329916 -330.227432) (xy 396.74419 -330.641706) (xy 396.761448 -330.659747) (xy 396.789201 -330.701241)
			(xy 396.808307 -330.74736) (xy 396.818029 -330.796324) (xy 396.818612 -330.821284) (xy 396.818612 -339.91931)
			(xy 408.390852 -351.49155) (xy 429.248062 -351.49155)
		)
		(stroke
			(width 0)
			(type solid)
		)
		(fill yes)
		(layer "In9.Cu")
		(net "PVCCFA_EHV_FIVRA_CPU0")
	)
	(gr_poly
		(pts
			(xy 350.434656 -267.735304) (xy 350.436665 -267.710632) (xy 350.447167 -267.662259) (xy 350.464812 -267.61601)
			(xy 350.4892 -267.572935) (xy 350.519779 -267.53401) (xy 350.555854 -267.500116) (xy 350.59661 -267.472023)
			(xy 350.641121 -267.450366) (xy 350.688379 -267.435638) (xy 350.737312 -267.428171) (xy 350.762062 -267.42771)
			(xy 350.784712 -267.428087) (xy 350.829579 -267.434329) (xy 350.85147 -267.440156) (xy 350.880172 -267.448284)
			(xy 352.098356 -266.2301) (xy 352.098356 -265.635994) (xy 352.06432 -265.624056) (xy 352.040508 -265.615294)
			(xy 351.995705 -265.591483) (xy 351.955104 -265.561057) (xy 351.919672 -265.52474) (xy 351.890256 -265.4834)
			(xy 351.867558 -265.438024) (xy 351.852118 -265.389693) (xy 351.844306 -265.339561) (xy 351.844307 -265.288824)
			(xy 351.852122 -265.238692) (xy 351.867564 -265.190362) (xy 351.890265 -265.144986) (xy 351.919682 -265.103648)
			(xy 351.955115 -265.067333) (xy 351.995718 -265.036908) (xy 352.040522 -265.013099) (xy 352.06432 -265.004296)
			(xy 352.098356 -264.992358) (xy 352.098356 -262.017256) (xy 352.098815 -261.995077) (xy 352.106526 -261.951393)
			(xy 352.121706 -261.909713) (xy 352.143894 -261.871302) (xy 352.172415 -261.837328) (xy 352.206403 -261.808823)
			(xy 352.225356 -261.797292) (xy 352.225356 -261.572502) (xy 352.207424 -261.545507) (xy 352.179033 -261.487253)
			(xy 352.159741 -261.425386) (xy 352.149991 -261.361319) (xy 352.14941 -261.328916) (xy 352.149918 -261.299177)
			(xy 352.158144 -261.240271) (xy 352.174439 -261.183069) (xy 352.198491 -261.128672) (xy 352.229837 -261.078124)
			(xy 352.267875 -261.032399) (xy 352.311871 -260.992376) (xy 352.360982 -260.958824) (xy 352.414262 -260.932388)
			(xy 352.470687 -260.913577) (xy 352.529171 -260.902753) (xy 352.558858 -260.900926) (xy 352.57867 -260.89991)
			(xy 352.79584 -260.68274) (xy 352.804222 -260.675374) (xy 352.806254 -260.673596) (xy 352.939604 -260.539992)
			(xy 352.937572 -260.51637) (xy 352.936556 -260.493256) (xy 352.936556 -257.093212) (xy 352.5774 -256.734056)
			(xy 351.611946 -256.734056) (xy 351.605088 -256.741168) (xy 351.285556 -257.0607) (xy 351.285556 -260.518656)
			(xy 351.284979 -260.543614) (xy 351.27523 -260.592569) (xy 351.256116 -260.63868) (xy 351.228373 -260.680177)
			(xy 351.211134 -260.698234) (xy 351.136204 -260.773164) (xy 351.13722 -260.79577) (xy 351.137728 -260.812534)
			(xy 351.137246 -260.838321) (xy 351.129172 -260.889258) (xy 351.11323 -260.938306) (xy 351.089811 -260.984256)
			(xy 351.059492 -261.025977) (xy 351.02302 -261.06244) (xy 350.981293 -261.09275) (xy 350.935338 -261.116158)
			(xy 350.886286 -261.13209) (xy 350.835347 -261.140151) (xy 350.80956 -261.140702) (xy 350.792796 -261.140194)
			(xy 350.77019 -261.139178) (xy 350.652334 -261.257034) (xy 350.634293 -261.274293) (xy 350.592799 -261.302047)
			(xy 350.54668 -261.321157) (xy 350.497717 -261.330886) (xy 350.472756 -261.331456) (xy 350.140778 -261.331456)
			(xy 350.128078 -261.363714) (xy 350.11808 -261.388007) (xy 350.091491 -261.43331) (xy 350.058024 -261.473798)
			(xy 350.018534 -261.508436) (xy 349.974029 -261.536341) (xy 349.925647 -261.556798) (xy 349.874623 -261.569285)
			(xy 349.822262 -261.573483) (xy 349.769901 -261.569285) (xy 349.718877 -261.556798) (xy 349.670495 -261.536341)
			(xy 349.62599 -261.508436) (xy 349.5865 -261.473798) (xy 349.553033 -261.43331) (xy 349.526444 -261.388007)
			(xy 349.516446 -261.363714) (xy 349.503746 -261.331456) (xy 349.200978 -261.331456) (xy 349.188278 -261.363714)
			(xy 349.17828 -261.388007) (xy 349.151691 -261.43331) (xy 349.118224 -261.473798) (xy 349.078734 -261.508436)
			(xy 349.034229 -261.536341) (xy 348.985847 -261.556798) (xy 348.934823 -261.569285) (xy 348.882462 -261.573483)
			(xy 348.830101 -261.569285) (xy 348.779077 -261.556798) (xy 348.730695 -261.536341) (xy 348.68619 -261.508436)
			(xy 348.6467 -261.473798) (xy 348.613233 -261.43331) (xy 348.586644 -261.388007) (xy 348.576646 -261.363714)
			(xy 348.563946 -261.331456) (xy 348.261178 -261.331456) (xy 348.248478 -261.363714) (xy 348.23848 -261.388007)
			(xy 348.211891 -261.43331) (xy 348.178424 -261.473798) (xy 348.138934 -261.508436) (xy 348.094429 -261.536341)
			(xy 348.046047 -261.556798) (xy 347.995023 -261.569285) (xy 347.942662 -261.573483) (xy 347.890301 -261.569285)
			(xy 347.839277 -261.556798) (xy 347.790895 -261.536341) (xy 347.74639 -261.508436) (xy 347.7069 -261.473798)
			(xy 347.673433 -261.43331) (xy 347.646844 -261.388007) (xy 347.636846 -261.363714) (xy 347.624146 -261.331456)
			(xy 347.321378 -261.331456) (xy 347.308678 -261.363714) (xy 347.29868 -261.388007) (xy 347.272091 -261.43331)
			(xy 347.238624 -261.473798) (xy 347.199134 -261.508436) (xy 347.154629 -261.536341) (xy 347.106247 -261.556798)
			(xy 347.055223 -261.569285) (xy 347.002862 -261.573483) (xy 346.950501 -261.569285) (xy 346.899477 -261.556798)
			(xy 346.851095 -261.536341) (xy 346.80659 -261.508436) (xy 346.7671 -261.473798) (xy 346.733633 -261.43331)
			(xy 346.707044 -261.388007) (xy 346.697046 -261.363714) (xy 346.684346 -261.331456) (xy 346.381578 -261.331456)
			(xy 346.368878 -261.363714) (xy 346.35888 -261.388007) (xy 346.332291 -261.43331) (xy 346.298824 -261.473798)
			(xy 346.259334 -261.508436) (xy 346.214829 -261.536341) (xy 346.166447 -261.556798) (xy 346.115423 -261.569285)
			(xy 346.063062 -261.573483) (xy 346.010701 -261.569285) (xy 345.959677 -261.556798) (xy 345.911295 -261.536341)
			(xy 345.86679 -261.508436) (xy 345.8273 -261.473798) (xy 345.793833 -261.43331) (xy 345.767244 -261.388007)
			(xy 345.757246 -261.363714) (xy 345.744546 -261.331456) (xy 345.441778 -261.331456) (xy 345.429078 -261.363714)
			(xy 345.419742 -261.386503) (xy 345.395235 -261.429218) (xy 345.364624 -261.467793) (xy 345.328594 -261.501364)
			(xy 345.287954 -261.529177) (xy 345.243616 -261.550609) (xy 345.196575 -261.565177) (xy 345.147885 -261.572557)
			(xy 345.123262 -261.57301) (xy 345.097475 -261.572502) (xy 345.046537 -261.564429) (xy 344.997489 -261.548488)
			(xy 344.951537 -261.525073) (xy 344.909814 -261.494757) (xy 344.873345 -261.45829) (xy 344.84303 -261.416566)
			(xy 344.819613 -261.370615) (xy 344.803672 -261.321567) (xy 344.795599 -261.270629) (xy 344.795094 -261.244842)
			(xy 344.795601 -261.218517) (xy 344.803963 -261.166535) (xy 344.820498 -261.116548) (xy 344.832178 -261.09295)
			(xy 344.84945 -261.05993) (xy 344.520774 -260.731254) (xy 344.512646 -260.727444) (xy 344.48896 -260.715616)
			(xy 344.44539 -260.685547) (xy 344.407205 -260.648881) (xy 344.375393 -260.606566) (xy 344.350777 -260.559699)
			(xy 344.333994 -260.509491) (xy 344.325479 -260.457241) (xy 344.32494 -260.430772) (xy 344.325418 -260.405362)
			(xy 344.333257 -260.35515) (xy 344.348743 -260.306747) (xy 344.371506 -260.261309) (xy 344.401001 -260.219924)
			(xy 344.418412 -260.20141) (xy 344.418412 -259.031994) (xy 344.401075 -259.013505) (xy 344.37173 -258.972181)
			(xy 344.349087 -258.926837) (xy 344.333684 -258.878551) (xy 344.325887 -258.82847) (xy 344.325883 -258.777787)
			(xy 344.333671 -258.727705) (xy 344.349065 -258.679416) (xy 344.3717 -258.634068) (xy 344.401038 -258.592739)
			(xy 344.418412 -258.574286) (xy 344.418412 -257.404108) (xy 344.401081 -257.385619) (xy 344.371749 -257.344297)
			(xy 344.349119 -257.298957) (xy 344.333728 -257.250677) (xy 344.325942 -257.200604) (xy 344.325947 -257.14993)
			(xy 344.333743 -257.099859) (xy 344.349144 -257.051582) (xy 344.371783 -257.006246) (xy 344.401124 -256.96493)
			(xy 344.418412 -256.9464) (xy 344.418412 -255.776476) (xy 344.401076 -255.757987) (xy 344.371734 -255.716663)
			(xy 344.349093 -255.67132) (xy 344.333693 -255.623035) (xy 344.325899 -255.572956) (xy 344.325896 -255.522275)
			(xy 344.333686 -255.472196) (xy 344.349081 -255.423909) (xy 344.371718 -255.378564) (xy 344.401056 -255.337237)
			(xy 344.418412 -255.318768) (xy 344.418412 -254.14859) (xy 344.401075 -254.130101) (xy 344.371731 -254.088777)
			(xy 344.349088 -254.043433) (xy 344.333686 -253.995147) (xy 344.32589 -253.945067) (xy 344.325886 -253.894384)
			(xy 344.333674 -253.844303) (xy 344.349069 -253.796015) (xy 344.371704 -253.750667) (xy 344.401042 -253.709339)
			(xy 344.418412 -253.690882) (xy 344.418412 -249.111008) (xy 344.391234 -249.096784) (xy 344.368867 -249.08451)
			(xy 344.327895 -249.05411) (xy 344.292123 -249.017735) (xy 344.262412 -248.976261) (xy 344.239478 -248.930689)
			(xy 344.223874 -248.882116) (xy 344.215977 -248.831713) (xy 344.215976 -248.780695) (xy 344.223872 -248.730292)
			(xy 344.239475 -248.681718) (xy 344.262408 -248.636145) (xy 344.292118 -248.594671) (xy 344.32789 -248.558295)
			(xy 344.368861 -248.527894) (xy 344.391234 -248.515632) (xy 344.418412 -248.501408) (xy 344.418412 -247.483376)
			(xy 344.391234 -247.469152) (xy 344.368828 -247.456881) (xy 344.327781 -247.426476) (xy 344.291939 -247.390078)
			(xy 344.262168 -247.348568) (xy 344.239186 -247.302947) (xy 344.22355 -247.254317) (xy 344.215635 -247.203851)
			(xy 344.215633 -247.152769) (xy 344.223545 -247.102303) (xy 344.239179 -247.053672) (xy 344.262157 -247.008049)
			(xy 344.291926 -246.966537) (xy 344.327765 -246.930138) (xy 344.368811 -246.89973) (xy 344.391234 -246.887492)
			(xy 344.418412 -246.873268) (xy 344.418412 -245.85549) (xy 344.391234 -245.841266) (xy 344.368869 -245.828992)
			(xy 344.3279 -245.798592) (xy 344.29213 -245.762218) (xy 344.262421 -245.720746) (xy 344.239489 -245.675175)
			(xy 344.223888 -245.626604) (xy 344.215992 -245.576203) (xy 344.215993 -245.525188) (xy 344.22389 -245.474787)
			(xy 344.239493 -245.426217) (xy 344.262426 -245.380646) (xy 344.292136 -245.339175) (xy 344.327907 -245.302802)
			(xy 344.368876 -245.272404) (xy 344.391234 -245.260114) (xy 344.418412 -245.24589) (xy 344.418412 -244.227604)
			(xy 344.391234 -244.21338) (xy 344.368867 -244.201106) (xy 344.327896 -244.170706) (xy 344.292124 -244.134331)
			(xy 344.262414 -244.092858) (xy 344.23948 -244.047286) (xy 344.223877 -243.998713) (xy 344.21598 -243.94831)
			(xy 344.21598 -243.897293) (xy 344.223876 -243.846891) (xy 344.239479 -243.798318) (xy 344.262412 -243.752745)
			(xy 344.292122 -243.711272) (xy 344.327894 -243.674896) (xy 344.368864 -243.644496) (xy 344.391234 -243.632228)
			(xy 344.418412 -243.618004) (xy 344.418412 -242.599718) (xy 344.391234 -242.585494) (xy 344.368866 -242.573219)
			(xy 344.327893 -242.54282) (xy 344.292119 -242.506444) (xy 344.262406 -242.46497) (xy 344.239471 -242.419396)
			(xy 344.223867 -242.370822) (xy 344.215968 -242.320418) (xy 344.215967 -242.269399) (xy 344.223863 -242.218994)
			(xy 344.239465 -242.170419) (xy 344.262398 -242.124845) (xy 344.292108 -242.083369) (xy 344.327881 -242.046991)
			(xy 344.368852 -242.016589) (xy 344.391234 -242.004342) (xy 344.418412 -241.990118) (xy 344.418412 -240.972086)
			(xy 344.391234 -240.957862) (xy 344.368869 -240.945588) (xy 344.327901 -240.915188) (xy 344.292131 -240.878814)
			(xy 344.262423 -240.837342) (xy 344.239492 -240.791772) (xy 344.223891 -240.743201) (xy 344.215996 -240.692801)
			(xy 344.215997 -240.641786) (xy 344.223894 -240.591386) (xy 344.239497 -240.542816) (xy 344.26243 -240.497246)
			(xy 344.29214 -240.455776) (xy 344.32791 -240.419403) (xy 344.36888 -240.389006) (xy 344.391234 -240.37671)
			(xy 344.418412 -240.362486) (xy 344.418412 -239.3442) (xy 344.391234 -239.329976) (xy 344.368868 -239.317702)
			(xy 344.327897 -239.287302) (xy 344.292126 -239.250927) (xy 344.262416 -239.209454) (xy 344.239483 -239.163883)
			(xy 344.22388 -239.11531) (xy 344.215984 -239.064908) (xy 344.215984 -239.013892) (xy 344.22388 -238.96349)
			(xy 344.239483 -238.914917) (xy 344.262416 -238.869346) (xy 344.292126 -238.827873) (xy 344.327897 -238.791498)
			(xy 344.368868 -238.761098) (xy 344.391234 -238.748824) (xy 344.418412 -238.7346) (xy 344.418412 -237.716314)
			(xy 344.391234 -237.70209) (xy 344.368867 -237.689815) (xy 344.327894 -237.659416) (xy 344.292121 -237.62304)
			(xy 344.262408 -237.581566) (xy 344.239474 -237.535993) (xy 344.22387 -237.487419) (xy 344.215972 -237.437016)
			(xy 344.215971 -237.385997) (xy 344.223867 -237.335593) (xy 344.239469 -237.287019) (xy 344.262402 -237.241445)
			(xy 344.292112 -237.19997) (xy 344.327884 -237.163593) (xy 344.368856 -237.133191) (xy 344.391234 -237.120938)
			(xy 344.418412 -237.106714) (xy 344.418412 -236.088682) (xy 344.391234 -236.074458) (xy 344.368869 -236.062184)
			(xy 344.327901 -236.031785) (xy 344.292133 -235.995411) (xy 344.262425 -235.953939) (xy 344.239495 -235.908369)
			(xy 344.223894 -235.859798) (xy 344.215999 -235.809399) (xy 344.216 -235.758385) (xy 344.223898 -235.707985)
			(xy 344.239501 -235.659416) (xy 344.262434 -235.613847) (xy 344.292143 -235.572376) (xy 344.327914 -235.536004)
			(xy 344.368883 -235.505608) (xy 344.391234 -235.493306) (xy 344.418412 -235.479082) (xy 344.418412 -234.938316)
			(xy 344.419032 -234.913363) (xy 344.428783 -234.864418) (xy 344.447896 -234.818316) (xy 344.475634 -234.776828)
			(xy 344.492834 -234.758738) (xy 345.16187 -234.089702) (xy 345.165172 -234.07624) (xy 345.171787 -234.051828)
			(xy 345.191494 -234.005247) (xy 345.218114 -233.962243) (xy 345.251018 -233.923832) (xy 345.289427 -233.890926)
			(xy 345.33243 -233.864303) (xy 345.379009 -233.844594) (xy 345.403424 -233.837988) (xy 345.416886 -233.834686)
			(xy 345.698572 -233.553) (xy 345.676728 -233.51871) (xy 345.664523 -233.498845) (xy 345.645241 -233.456396)
			(xy 345.632167 -233.411644) (xy 345.625564 -233.365491) (xy 345.625166 -233.34218) (xy 345.625647 -233.316392)
			(xy 345.633719 -233.265453) (xy 345.64966 -233.216403) (xy 345.673078 -233.17045) (xy 345.703396 -233.128728)
			(xy 345.739869 -233.092261) (xy 345.781597 -233.06195) (xy 345.827553 -233.038539) (xy 345.876605 -233.022606)
			(xy 345.927546 -233.014543) (xy 345.953334 -233.014012) (xy 345.976644 -233.014424) (xy 346.022794 -233.02103)
			(xy 346.067544 -233.034105) (xy 346.109991 -233.053384) (xy 346.129864 -233.065574) (xy 346.164154 -233.087418)
			(xy 347.505274 -231.746298) (xy 347.504766 -231.724454) (xy 347.504512 -231.714548) (xy 347.504988 -231.688755)
			(xy 347.51305 -231.637804) (xy 347.528985 -231.588741) (xy 347.552398 -231.542776) (xy 347.582715 -231.501039)
			(xy 347.619187 -231.464559) (xy 347.660918 -231.434234) (xy 347.706879 -231.410811) (xy 347.755938 -231.394866)
			(xy 347.806887 -231.386793) (xy 347.83268 -231.38638) (xy 347.842586 -231.386634) (xy 347.86443 -231.387142)
			(xy 349.87103 -229.380542) (xy 349.864172 -229.352602) (xy 349.859555 -229.332986) (xy 349.854582 -229.292995)
			(xy 349.854266 -229.272846) (xy 349.854742 -229.247055) (xy 349.862806 -229.196107) (xy 349.878741 -229.147048)
			(xy 349.902155 -229.101087) (xy 349.932473 -229.059355) (xy 349.968946 -229.022881) (xy 350.010677 -228.992562)
			(xy 350.056637 -228.969145) (xy 350.105696 -228.953208) (xy 350.156643 -228.945143) (xy 350.182434 -228.944678)
			(xy 350.202583 -228.945) (xy 350.242575 -228.949965) (xy 350.26219 -228.954584) (xy 350.29013 -228.961442)
			(xy 351.782634 -227.468938) (xy 351.782634 -226.190048) (xy 351.77603 -226.178364) (xy 351.762751 -226.153625)
			(xy 351.74393 -226.10073) (xy 351.734404 -226.0454) (xy 351.733866 -226.017328) (xy 351.734441 -225.989259)
			(xy 351.743978 -225.933936) (xy 351.762764 -225.881034) (xy 351.77603 -225.856292) (xy 351.782634 -225.844608)
			(xy 351.782634 -224.564702) (xy 351.77603 -224.553018) (xy 351.764276 -224.531557) (xy 351.746541 -224.485954)
			(xy 351.735739 -224.438232) (xy 351.732108 -224.389437) (xy 351.735728 -224.340641) (xy 351.746519 -224.292916)
			(xy 351.764245 -224.247309) (xy 351.77603 -224.225866) (xy 351.782634 -224.214182) (xy 351.782634 -223.99752)
			(xy 351.782129 -223.982395) (xy 351.773359 -223.953448) (xy 351.756494 -223.92834) (xy 351.733013 -223.909274)
			(xy 351.704977 -223.897923) (xy 351.674846 -223.895284) (xy 351.659952 -223.897952) (xy 351.653094 -223.899476)
			(xy 351.630234 -223.903794) (xy 351.42551 -224.258632) (xy 351.433384 -224.280476) (xy 351.441963 -224.306895)
			(xy 351.451158 -224.36167) (xy 351.451672 -224.389442) (xy 351.451164 -224.415329) (xy 351.443065 -224.466467)
			(xy 351.427066 -224.515707) (xy 351.40356 -224.561839) (xy 351.373128 -224.603726) (xy 351.336518 -224.640336)
			(xy 351.294631 -224.670768) (xy 351.248499 -224.694274) (xy 351.199259 -224.710273) (xy 351.148121 -224.718372)
			(xy 351.096347 -224.718372) (xy 351.045209 -224.710273) (xy 350.995969 -224.694274) (xy 350.949837 -224.670768)
			(xy 350.90795 -224.640336) (xy 350.87134 -224.603726) (xy 350.840908 -224.561839) (xy 350.817402 -224.515707)
			(xy 350.801403 -224.466467) (xy 350.793304 -224.415329) (xy 350.792796 -224.389442) (xy 350.793256 -224.364104)
			(xy 350.801004 -224.314024) (xy 350.816323 -224.265719) (xy 350.838853 -224.220327) (xy 350.868064 -224.178916)
			(xy 350.903266 -224.142463) (xy 350.943632 -224.111826) (xy 350.98821 -224.087725) (xy 351.035951 -224.07073)
			(xy 351.060766 -224.065592) (xy 351.083626 -224.061274) (xy 351.28835 -223.706436) (xy 351.28073 -223.684338)
			(xy 351.272104 -223.65799) (xy 351.262776 -223.603344) (xy 351.262188 -223.575626) (xy 351.262668 -223.549723)
			(xy 351.270773 -223.498556) (xy 351.286787 -223.449288) (xy 351.310316 -223.403133) (xy 351.340778 -223.361231)
			(xy 351.377424 -223.324613) (xy 351.41935 -223.294183) (xy 351.465523 -223.27069) (xy 351.514803 -223.254714)
			(xy 351.565977 -223.246648) (xy 351.59188 -223.246188) (xy 351.609026 -223.246407) (xy 351.643131 -223.24997)
			(xy 351.659952 -223.2533) (xy 351.674848 -223.255893) (xy 351.704952 -223.253231) (xy 351.732959 -223.24188)
			(xy 351.756422 -223.222834) (xy 351.773287 -223.197757) (xy 351.782079 -223.168843) (xy 351.782634 -223.153732)
			(xy 351.782634 -222.934276) (xy 351.77603 -222.922592) (xy 351.762757 -222.897851) (xy 351.743947 -222.844955)
			(xy 351.734433 -222.789627) (xy 351.733866 -222.761556) (xy 351.734447 -222.733489) (xy 351.743995 -222.678171)
			(xy 351.76279 -222.625276) (xy 351.77603 -222.60052) (xy 351.782634 -222.588836) (xy 351.782634 -222.088202)
			(xy 351.156778 -221.462346) (xy 351.13468 -221.463362) (xy 351.122234 -221.463616) (xy 351.096331 -221.463136)
			(xy 351.045162 -221.455032) (xy 350.995893 -221.439019) (xy 350.949737 -221.415491) (xy 350.907833 -221.385029)
			(xy 350.871214 -221.348383) (xy 350.840782 -221.306456) (xy 350.817288 -221.260283) (xy 350.801311 -221.211002)
			(xy 350.793245 -221.159828) (xy 350.792796 -221.133924) (xy 350.792796 -221.121478) (xy 350.793812 -221.09938)
			(xy 350.157796 -220.463364) (xy 350.148087 -220.454209) (xy 350.124986 -220.440865) (xy 350.099217 -220.43396)
			(xy 350.072539 -220.433966) (xy 350.046773 -220.440882) (xy 350.023678 -220.454235) (xy 350.00483 -220.473116)
			(xy 349.997776 -220.484446) (xy 349.985613 -220.504717) (xy 349.956387 -220.541873) (xy 349.922159 -220.57448)
			(xy 349.88363 -220.60187) (xy 349.841586 -220.623482) (xy 349.79689 -220.638875) (xy 349.773748 -220.643704)
			(xy 349.750888 -220.648022) (xy 349.54591 -221.003114) (xy 349.553784 -221.024958) (xy 349.562364 -221.051377)
			(xy 349.571562 -221.106152) (xy 349.572072 -221.133924) (xy 349.852996 -221.133924) (xy 349.853504 -221.108037)
			(xy 349.861603 -221.056899) (xy 349.877602 -221.007659) (xy 349.901108 -220.961527) (xy 349.93154 -220.91964)
			(xy 349.96815 -220.88303) (xy 350.010037 -220.852598) (xy 350.056169 -220.829092) (xy 350.105409 -220.813093)
			(xy 350.156547 -220.804994) (xy 350.208321 -220.804994) (xy 350.259459 -220.813093) (xy 350.308699 -220.829092)
			(xy 350.354831 -220.852598) (xy 350.396718 -220.88303) (xy 350.433328 -220.91964) (xy 350.46376 -220.961527)
			(xy 350.487266 -221.007659) (xy 350.503265 -221.056899) (xy 350.511364 -221.108037) (xy 350.511872 -221.133924)
			(xy 350.511345 -221.161632) (xy 350.502148 -221.216279) (xy 350.493584 -221.242636) (xy 350.48571 -221.264734)
			(xy 350.690688 -221.619572) (xy 350.713548 -221.62389) (xy 350.738367 -221.629064) (xy 350.786146 -221.646018)
			(xy 350.830765 -221.670088) (xy 350.871172 -221.700708) (xy 350.906413 -221.737154) (xy 350.935657 -221.778566)
			(xy 350.958214 -221.823969) (xy 350.973552 -221.872291) (xy 350.98131 -221.922391) (xy 350.981772 -221.94774)
			(xy 350.981264 -221.973647) (xy 350.973158 -222.024824) (xy 350.957146 -222.074103) (xy 350.933623 -222.12027)
			(xy 350.903167 -222.162189) (xy 350.866529 -222.198827) (xy 350.82461 -222.229283) (xy 350.778443 -222.252806)
			(xy 350.729164 -222.268818) (xy 350.677987 -222.276924) (xy 350.626173 -222.276924) (xy 350.574996 -222.268818)
			(xy 350.525717 -222.252806) (xy 350.47955 -222.229283) (xy 350.437631 -222.198827) (xy 350.400993 -222.162189)
			(xy 350.370537 -222.12027) (xy 350.347014 -222.074103) (xy 350.331002 -222.024824) (xy 350.322896 -221.973647)
			(xy 350.322388 -221.94774) (xy 350.322992 -221.920023) (xy 350.332309 -221.865377) (xy 350.34093 -221.839028)
			(xy 350.348804 -221.81693) (xy 350.143826 -221.462092) (xy 350.120966 -221.457774) (xy 350.096166 -221.452574)
			(xy 350.04843 -221.435583) (xy 350.003855 -221.411489) (xy 349.963491 -221.380859) (xy 349.928289 -221.344414)
			(xy 349.899076 -221.303012) (xy 349.876542 -221.257629) (xy 349.861217 -221.209332) (xy 349.853461 -221.159259)
			(xy 349.852996 -221.133924) (xy 349.572072 -221.133924) (xy 349.571564 -221.159811) (xy 349.563465 -221.210949)
			(xy 349.547466 -221.260189) (xy 349.52396 -221.306321) (xy 349.493528 -221.348208) (xy 349.456918 -221.384818)
			(xy 349.415031 -221.41525) (xy 349.368899 -221.438756) (xy 349.319659 -221.454755) (xy 349.268521 -221.462854)
			(xy 349.216747 -221.462854) (xy 349.165609 -221.454755) (xy 349.116369 -221.438756) (xy 349.070237 -221.41525)
			(xy 349.02835 -221.384818) (xy 348.99174 -221.348208) (xy 348.961308 -221.306321) (xy 348.937802 -221.260189)
			(xy 348.921803 -221.210949) (xy 348.913704 -221.159811) (xy 348.913196 -221.133924) (xy 348.913658 -221.108587)
			(xy 348.921408 -221.058509) (xy 348.936728 -221.010206) (xy 348.95926 -220.964816) (xy 348.98847 -220.923408)
			(xy 349.023673 -220.886957) (xy 349.064038 -220.856322) (xy 349.108616 -220.832223) (xy 349.156355 -220.815229)
			(xy 349.181166 -220.810074) (xy 349.204026 -220.805756) (xy 349.409004 -220.450664) (xy 349.40113 -220.42882)
			(xy 349.392487 -220.402411) (xy 349.383173 -220.347635) (xy 349.382588 -220.319854) (xy 349.383025 -220.295168)
			(xy 349.390387 -220.246348) (xy 349.404955 -220.199175) (xy 349.426402 -220.154704) (xy 349.454247 -220.113934)
			(xy 349.487867 -220.077778) (xy 349.526507 -220.047045) (xy 349.547688 -220.034358) (xy 349.559082 -220.027375)
			(xy 349.578025 -220.008538) (xy 349.591424 -219.985426) (xy 349.598357 -219.959627) (xy 349.598349 -219.932912)
			(xy 349.5914 -219.907116) (xy 349.577987 -219.884013) (xy 349.56877 -219.874338) (xy 349.45447 -219.760038)
			(xy 349.419926 -219.782136) (xy 349.399994 -219.794449) (xy 349.35738 -219.813911) (xy 349.312429 -219.827111)
			(xy 349.266058 -219.833782) (xy 349.242634 -219.834206) (xy 349.216844 -219.833703) (xy 349.165897 -219.825639)
			(xy 349.116839 -219.809705) (xy 349.070878 -219.786293) (xy 349.029145 -219.755979) (xy 348.992668 -219.71951)
			(xy 348.962345 -219.677784) (xy 348.938923 -219.631827) (xy 348.922978 -219.582773) (xy 348.914903 -219.531828)
			(xy 348.914466 -219.506038) (xy 348.914862 -219.482611) (xy 348.921527 -219.436234) (xy 348.934726 -219.391278)
			(xy 348.954191 -219.34866) (xy 348.966536 -219.328746) (xy 348.988634 -219.294202) (xy 348.95409 -219.259658)
			(xy 348.936828 -219.241618) (xy 348.909067 -219.200125) (xy 348.889951 -219.154007) (xy 348.880217 -219.105042)
			(xy 348.879668 -219.08008) (xy 348.879668 -219.017596) (xy 348.825058 -219.017596) (xy 348.821248 -219.018104)
			(xy 348.809127 -219.019787) (xy 348.784717 -219.02157) (xy 348.77248 -219.02166) (xy 348.746587 -219.021151)
			(xy 348.695439 -219.013051) (xy 348.646187 -218.997052) (xy 348.600042 -218.97355) (xy 348.55814 -218.943121)
			(xy 348.521511 -218.906514) (xy 348.491056 -218.86463) (xy 348.467525 -218.8185) (xy 348.451497 -218.769257)
			(xy 348.443365 -218.718114) (xy 348.442788 -218.692222) (xy 348.443375 -218.664503) (xy 348.45269 -218.609854)
			(xy 348.46133 -218.58351) (xy 348.469204 -218.561412) (xy 348.264226 -218.206574) (xy 348.241366 -218.202256)
			(xy 348.216566 -218.197056) (xy 348.168831 -218.180065) (xy 348.124258 -218.155971) (xy 348.083896 -218.12534)
			(xy 348.048695 -218.088895) (xy 348.019485 -218.047493) (xy 347.996953 -218.002109) (xy 347.98163 -217.953813)
			(xy 347.973877 -217.90374) (xy 347.973396 -217.878406) (xy 347.973904 -217.852519) (xy 347.982003 -217.801381)
			(xy 347.998002 -217.752141) (xy 348.021508 -217.706009) (xy 348.05194 -217.664122) (xy 348.08855 -217.627512)
			(xy 348.130437 -217.59708) (xy 348.176569 -217.573574) (xy 348.225809 -217.557575) (xy 348.276947 -217.549476)
			(xy 348.328721 -217.549476) (xy 348.379859 -217.557575) (xy 348.429099 -217.573574) (xy 348.475231 -217.59708)
			(xy 348.517118 -217.627512) (xy 348.553728 -217.664122) (xy 348.58416 -217.706009) (xy 348.607666 -217.752141)
			(xy 348.623665 -217.801381) (xy 348.631764 -217.852519) (xy 348.632272 -217.878406) (xy 348.631742 -217.906114)
			(xy 348.622542 -217.960759) (xy 348.613984 -217.987118) (xy 348.60611 -218.009216) (xy 348.690184 -218.154504)
			(xy 348.698032 -218.167055) (xy 348.719574 -218.187338) (xy 348.746025 -218.200597) (xy 348.775165 -218.205721)
			(xy 348.804552 -218.202279) (xy 348.831721 -218.19056) (xy 348.854392 -218.171548) (xy 348.870663 -218.146836)
			(xy 348.879171 -218.118497) (xy 348.879668 -218.103704) (xy 348.879668 -215.867742) (xy 348.879263 -215.854311)
			(xy 348.872264 -215.828376) (xy 348.85874 -215.805167) (xy 348.839628 -215.78629) (xy 348.816253 -215.773055)
			(xy 348.790233 -215.766378) (xy 348.776798 -215.766142) (xy 348.77248 -215.766396) (xy 348.746574 -215.765886)
			(xy 348.695399 -215.757778) (xy 348.646123 -215.741765) (xy 348.599958 -215.71824) (xy 348.558042 -215.687784)
			(xy 348.521405 -215.651146) (xy 348.490951 -215.609228) (xy 348.467429 -215.563062) (xy 348.451418 -215.513785)
			(xy 348.443313 -215.46261) (xy 348.442788 -215.436704) (xy 348.443253 -215.411358) (xy 348.451016 -215.361265)
			(xy 348.466358 -215.312951) (xy 348.488919 -215.267556) (xy 348.518166 -215.226153) (xy 348.553409 -215.189717)
			(xy 348.593816 -215.159108) (xy 348.638434 -215.135048) (xy 348.68621 -215.118105) (xy 348.711012 -215.112854)
			(xy 348.733872 -215.108536) (xy 348.879668 -214.855806) (xy 348.879668 -189.34938) (xy 348.880281 -189.324424)
			(xy 348.890021 -189.275471) (xy 348.909123 -189.229359) (xy 348.936852 -189.187858) (xy 348.95409 -189.169802)
			(xy 349.522542 -188.60135) (xy 349.540583 -188.584091) (xy 349.582077 -188.556334) (xy 349.628195 -188.537221)
			(xy 349.677159 -188.527488) (xy 349.70212 -188.526928) (xy 355.093524 -188.526928) (xy 355.58476 -188.035692)
			(xy 355.58476 -174.508668) (xy 355.585334 -174.483709) (xy 355.595081 -174.434752) (xy 355.614192 -174.388638)
			(xy 355.641934 -174.347139) (xy 355.659182 -174.32909) (xy 372.891304 -157.096968) (xy 372.909347 -157.079712)
			(xy 372.950842 -157.051964) (xy 372.99696 -157.032861) (xy 373.045922 -157.023139) (xy 373.070882 -157.022546)
			(xy 409.505912 -157.022546) (xy 409.966668 -156.56179) (xy 409.966668 -149.101302) (xy 409.53309 -148.667724)
			(xy 409.521526 -148.655773) (xy 409.501268 -148.629401) (xy 409.492704 -148.615146) (xy 408.43708 -148.615146)
			(xy 408.414203 -148.630996) (xy 408.364557 -148.656147) (xy 408.311601 -148.673263) (xy 408.256627 -148.681927)
			(xy 408.200973 -148.681927) (xy 408.145999 -148.673263) (xy 408.093043 -148.656147) (xy 408.043397 -148.630996)
			(xy 408.02052 -148.615146) (xy 396.941294 -148.615146) (xy 396.926195 -148.637975) (xy 396.890496 -148.679464)
			(xy 396.849236 -148.715427) (xy 396.80326 -148.745125) (xy 396.753513 -148.767948) (xy 396.701014 -148.783429)
			(xy 396.646843 -148.79125) (xy 396.592109 -148.79125) (xy 396.537938 -148.783429) (xy 396.485439 -148.767948)
			(xy 396.435692 -148.745125) (xy 396.389716 -148.715427) (xy 396.348456 -148.679464) (xy 396.312757 -148.637975)
			(xy 396.297658 -148.615146) (xy 356.031038 -148.615146) (xy 337.080352 -167.565832) (xy 348.657164 -167.565832)
			(xy 348.657658 -167.532531) (xy 348.666337 -167.466499) (xy 348.683566 -167.402165) (xy 348.709048 -167.340632)
			(xy 348.742347 -167.282953) (xy 348.782893 -167.230117) (xy 348.829992 -167.183027) (xy 348.882836 -167.142492)
			(xy 348.911418 -167.125396) (xy 349.83547 -166.591742) (xy 349.864533 -166.575642) (xy 349.925937 -166.550271)
			(xy 349.990123 -166.533114) (xy 350.055996 -166.524463) (xy 350.089216 -166.523924) (xy 350.089724 -166.523924)
			(xy 350.120458 -166.524315) (xy 350.181477 -166.531727) (xy 350.241158 -166.54644) (xy 350.29863 -166.56824)
			(xy 350.353056 -166.596808) (xy 350.403641 -166.631729) (xy 350.449648 -166.672492) (xy 350.490406 -166.718503)
			(xy 350.525321 -166.769092) (xy 350.553883 -166.823521) (xy 350.575676 -166.880996) (xy 350.590383 -166.940678)
			(xy 350.597788 -167.001698) (xy 350.598232 -167.032432) (xy 350.597712 -167.065732) (xy 350.589036 -167.131763)
			(xy 350.571812 -167.196097) (xy 350.546334 -167.25763) (xy 350.513038 -167.315309) (xy 350.472496 -167.368145)
			(xy 350.4254 -167.415235) (xy 350.372559 -167.455772) (xy 350.343978 -167.472868) (xy 349.419926 -168.006522)
			(xy 349.390862 -168.02262) (xy 349.329459 -168.047992) (xy 349.265273 -168.06515) (xy 349.1994 -168.073802)
			(xy 349.16618 -168.07434) (xy 349.165672 -168.07434) (xy 349.134942 -168.07387) (xy 349.073929 -168.066459)
			(xy 349.014255 -168.051748) (xy 348.956789 -168.029953) (xy 348.902369 -168.001389) (xy 348.851788 -167.966475)
			(xy 348.805784 -167.925719) (xy 348.765027 -167.879715) (xy 348.730113 -167.829135) (xy 348.701549 -167.774715)
			(xy 348.679753 -167.717249) (xy 348.665041 -167.657575) (xy 348.65763 -167.596562) (xy 348.657164 -167.565832)
			(xy 337.080352 -167.565832) (xy 336.343752 -168.302432) (xy 352.441764 -168.302432) (xy 352.442268 -168.271702)
			(xy 352.449672 -168.210689) (xy 352.464377 -168.151013) (xy 352.486168 -168.093545) (xy 352.514727 -168.039122)
			(xy 352.549637 -167.988539) (xy 352.59039 -167.942533) (xy 352.636392 -167.901774) (xy 352.686971 -167.866858)
			(xy 352.74139 -167.838292) (xy 352.798856 -167.816495) (xy 352.85853 -167.801783) (xy 352.919542 -167.794371)
			(xy 352.950272 -167.793924) (xy 352.95078 -167.793924) (xy 352.983998 -167.794489) (xy 353.049869 -167.803142)
			(xy 353.114055 -167.820291) (xy 353.175463 -167.845645) (xy 353.204526 -167.861742) (xy 354.128578 -168.395396)
			(xy 354.157139 -168.412518) (xy 354.209962 -168.453067) (xy 354.257042 -168.500162) (xy 354.297574 -168.552998)
			(xy 354.330866 -168.61067) (xy 354.356349 -168.672193) (xy 354.373586 -168.736515) (xy 354.382284 -168.802536)
			(xy 354.382832 -168.835832) (xy 354.382374 -168.866563) (xy 354.374962 -168.927576) (xy 354.360251 -168.987251)
			(xy 354.338454 -169.044717) (xy 354.30989 -169.099138) (xy 354.274975 -169.149719) (xy 354.234218 -169.195723)
			(xy 354.188213 -169.23648) (xy 354.137631 -169.271394) (xy 354.08321 -169.299957) (xy 354.025743 -169.321753)
			(xy 353.966068 -169.336464) (xy 353.905055 -169.343875) (xy 353.874324 -169.34434) (xy 353.873816 -169.34434)
			(xy 353.840597 -169.343782) (xy 353.774726 -169.335127) (xy 353.710541 -169.317976) (xy 353.649132 -169.292621)
			(xy 353.62007 -169.276522) (xy 352.696018 -168.742868) (xy 352.667463 -168.725735) (xy 352.614637 -168.685191)
			(xy 352.567553 -168.638099) (xy 352.527018 -168.585266) (xy 352.493724 -168.527595) (xy 352.468241 -168.466072)
			(xy 352.451005 -168.40175) (xy 352.44231 -168.335728) (xy 352.441764 -168.302432) (xy 336.343752 -168.302432)
			(xy 334.032352 -170.613832) (xy 348.657164 -170.613832) (xy 348.657658 -170.580531) (xy 348.666337 -170.514499)
			(xy 348.683566 -170.450165) (xy 348.709048 -170.388632) (xy 348.742347 -170.330953) (xy 348.782893 -170.278117)
			(xy 348.829992 -170.231027) (xy 348.882836 -170.190492) (xy 348.911418 -170.173396) (xy 349.83547 -169.639742)
			(xy 349.864533 -169.623642) (xy 349.925937 -169.598271) (xy 349.990123 -169.581114) (xy 350.055996 -169.572463)
			(xy 350.089216 -169.571924) (xy 350.089724 -169.571924) (xy 350.120458 -169.572315) (xy 350.181477 -169.579727)
			(xy 350.241158 -169.59444) (xy 350.29863 -169.61624) (xy 350.353056 -169.644808) (xy 350.403641 -169.679729)
			(xy 350.449648 -169.720492) (xy 350.490406 -169.766503) (xy 350.525321 -169.817092) (xy 350.553883 -169.871521)
			(xy 350.575676 -169.928996) (xy 350.590383 -169.988678) (xy 350.597788 -170.049698) (xy 350.598232 -170.080432)
			(xy 350.597712 -170.113732) (xy 350.589036 -170.179763) (xy 350.571812 -170.244097) (xy 350.546334 -170.30563)
			(xy 350.513038 -170.363309) (xy 350.472496 -170.416145) (xy 350.4254 -170.463235) (xy 350.372559 -170.503772)
			(xy 350.343978 -170.520868) (xy 349.419926 -171.054522) (xy 349.390862 -171.07062) (xy 349.329459 -171.095992)
			(xy 349.265273 -171.11315) (xy 349.1994 -171.121802) (xy 349.16618 -171.12234) (xy 349.165672 -171.12234)
			(xy 349.134942 -171.12187) (xy 349.073929 -171.114459) (xy 349.014255 -171.099748) (xy 348.956789 -171.077953)
			(xy 348.902369 -171.049389) (xy 348.851788 -171.014475) (xy 348.805784 -170.973719) (xy 348.765027 -170.927715)
			(xy 348.730113 -170.877135) (xy 348.701549 -170.822715) (xy 348.679753 -170.765249) (xy 348.665041 -170.705575)
			(xy 348.65763 -170.644562) (xy 348.657164 -170.613832) (xy 334.032352 -170.613832) (xy 332.660752 -171.985432)
			(xy 352.441764 -171.985432) (xy 352.442268 -171.954702) (xy 352.449672 -171.893689) (xy 352.464377 -171.834013)
			(xy 352.486168 -171.776545) (xy 352.514727 -171.722122) (xy 352.549637 -171.671539) (xy 352.59039 -171.625533)
			(xy 352.636392 -171.584774) (xy 352.686971 -171.549858) (xy 352.74139 -171.521292) (xy 352.798856 -171.499495)
			(xy 352.85853 -171.484783) (xy 352.919542 -171.477371) (xy 352.950272 -171.476924) (xy 352.95078 -171.476924)
			(xy 352.983998 -171.477489) (xy 353.049869 -171.486142) (xy 353.114055 -171.503291) (xy 353.175463 -171.528645)
			(xy 353.204526 -171.544742) (xy 354.128578 -172.078396) (xy 354.157139 -172.095518) (xy 354.209962 -172.136067)
			(xy 354.257042 -172.183162) (xy 354.297574 -172.235998) (xy 354.330866 -172.29367) (xy 354.356349 -172.355193)
			(xy 354.373586 -172.419515) (xy 354.382284 -172.485536) (xy 354.382832 -172.518832) (xy 354.382374 -172.549563)
			(xy 354.374962 -172.610576) (xy 354.360251 -172.670251) (xy 354.338454 -172.727717) (xy 354.30989 -172.782138)
			(xy 354.274975 -172.832719) (xy 354.234218 -172.878723) (xy 354.188213 -172.91948) (xy 354.137631 -172.954394)
			(xy 354.08321 -172.982957) (xy 354.025743 -173.004753) (xy 353.966068 -173.019464) (xy 353.905055 -173.026875)
			(xy 353.874324 -173.02734) (xy 353.873816 -173.02734) (xy 353.840597 -173.026782) (xy 353.774726 -173.018127)
			(xy 353.710541 -173.000976) (xy 353.649132 -172.975621) (xy 353.62007 -172.959522) (xy 352.696018 -172.425868)
			(xy 352.667463 -172.408735) (xy 352.614637 -172.368191) (xy 352.567553 -172.321099) (xy 352.527018 -172.268266)
			(xy 352.493724 -172.210595) (xy 352.468241 -172.149072) (xy 352.451005 -172.08475) (xy 352.44231 -172.018728)
			(xy 352.441764 -171.985432) (xy 332.660752 -171.985432) (xy 330.984352 -173.661832) (xy 348.657164 -173.661832)
			(xy 348.657658 -173.628531) (xy 348.666337 -173.562499) (xy 348.683566 -173.498165) (xy 348.709048 -173.436632)
			(xy 348.742347 -173.378953) (xy 348.782893 -173.326117) (xy 348.829992 -173.279027) (xy 348.882836 -173.238492)
			(xy 348.911418 -173.221396) (xy 349.83547 -172.687742) (xy 349.864533 -172.671642) (xy 349.925937 -172.646271)
			(xy 349.990123 -172.629114) (xy 350.055996 -172.620463) (xy 350.089216 -172.619924) (xy 350.089724 -172.619924)
			(xy 350.120458 -172.620315) (xy 350.181477 -172.627727) (xy 350.241158 -172.64244) (xy 350.29863 -172.66424)
			(xy 350.353056 -172.692808) (xy 350.403641 -172.727729) (xy 350.449648 -172.768492) (xy 350.490406 -172.814503)
			(xy 350.525321 -172.865092) (xy 350.553883 -172.919521) (xy 350.575676 -172.976996) (xy 350.590383 -173.036678)
			(xy 350.597788 -173.097698) (xy 350.598232 -173.128432) (xy 350.597712 -173.161732) (xy 350.589036 -173.227763)
			(xy 350.571812 -173.292097) (xy 350.546334 -173.35363) (xy 350.513038 -173.411309) (xy 350.472496 -173.464145)
			(xy 350.4254 -173.511235) (xy 350.372559 -173.551772) (xy 350.343978 -173.568868) (xy 349.419926 -174.102522)
			(xy 349.390862 -174.11862) (xy 349.329459 -174.143992) (xy 349.265273 -174.16115) (xy 349.1994 -174.169802)
			(xy 349.16618 -174.17034) (xy 349.165672 -174.17034) (xy 349.134942 -174.16987) (xy 349.073929 -174.162459)
			(xy 349.014255 -174.147748) (xy 348.956789 -174.125953) (xy 348.902369 -174.097389) (xy 348.851788 -174.062475)
			(xy 348.805784 -174.021719) (xy 348.765027 -173.975715) (xy 348.730113 -173.925135) (xy 348.701549 -173.870715)
			(xy 348.679753 -173.813249) (xy 348.665041 -173.753575) (xy 348.65763 -173.692562) (xy 348.657164 -173.661832)
			(xy 330.984352 -173.661832) (xy 327.936352 -176.709832) (xy 348.657164 -176.709832) (xy 348.657658 -176.676531)
			(xy 348.666337 -176.610499) (xy 348.683566 -176.546165) (xy 348.709048 -176.484632) (xy 348.742347 -176.426953)
			(xy 348.782893 -176.374117) (xy 348.829992 -176.327027) (xy 348.882836 -176.286492) (xy 348.911418 -176.269396)
			(xy 349.83547 -175.735742) (xy 349.864533 -175.719642) (xy 349.925937 -175.694271) (xy 349.990123 -175.677114)
			(xy 350.055996 -175.668463) (xy 350.089216 -175.667924) (xy 350.089724 -175.667924) (xy 350.120458 -175.668315)
			(xy 350.121421 -175.668432) (xy 352.441764 -175.668432) (xy 352.442268 -175.637702) (xy 352.449672 -175.576689)
			(xy 352.464377 -175.517013) (xy 352.486168 -175.459545) (xy 352.514727 -175.405122) (xy 352.549637 -175.354539)
			(xy 352.59039 -175.308533) (xy 352.636392 -175.267774) (xy 352.686971 -175.232858) (xy 352.74139 -175.204292)
			(xy 352.798856 -175.182495) (xy 352.85853 -175.167783) (xy 352.919542 -175.160371) (xy 352.950272 -175.159924)
			(xy 352.95078 -175.159924) (xy 352.983998 -175.160489) (xy 353.049869 -175.169142) (xy 353.114055 -175.186291)
			(xy 353.175463 -175.211645) (xy 353.204526 -175.227742) (xy 354.128578 -175.761396) (xy 354.157139 -175.778518)
			(xy 354.209962 -175.819067) (xy 354.257042 -175.866162) (xy 354.297574 -175.918998) (xy 354.330866 -175.97667)
			(xy 354.356349 -176.038193) (xy 354.373586 -176.102515) (xy 354.382284 -176.168536) (xy 354.382832 -176.201832)
			(xy 354.382374 -176.232563) (xy 354.374962 -176.293576) (xy 354.360251 -176.353251) (xy 354.338454 -176.410717)
			(xy 354.30989 -176.465138) (xy 354.274975 -176.515719) (xy 354.234218 -176.561723) (xy 354.188213 -176.60248)
			(xy 354.137631 -176.637394) (xy 354.08321 -176.665957) (xy 354.025743 -176.687753) (xy 353.966068 -176.702464)
			(xy 353.905055 -176.709875) (xy 353.874324 -176.71034) (xy 353.873816 -176.71034) (xy 353.840597 -176.709782)
			(xy 353.774726 -176.701127) (xy 353.710541 -176.683976) (xy 353.649132 -176.658621) (xy 353.62007 -176.642522)
			(xy 352.696018 -176.108868) (xy 352.667463 -176.091735) (xy 352.614637 -176.051191) (xy 352.567553 -176.004099)
			(xy 352.527018 -175.951266) (xy 352.493724 -175.893595) (xy 352.468241 -175.832072) (xy 352.451005 -175.76775)
			(xy 352.44231 -175.701728) (xy 352.441764 -175.668432) (xy 350.121421 -175.668432) (xy 350.181477 -175.675727)
			(xy 350.241158 -175.69044) (xy 350.29863 -175.71224) (xy 350.353056 -175.740808) (xy 350.403641 -175.775729)
			(xy 350.449648 -175.816492) (xy 350.490406 -175.862503) (xy 350.525321 -175.913092) (xy 350.553883 -175.967521)
			(xy 350.575676 -176.024996) (xy 350.590383 -176.084678) (xy 350.597788 -176.145698) (xy 350.598232 -176.176432)
			(xy 350.597712 -176.209732) (xy 350.589036 -176.275763) (xy 350.571812 -176.340097) (xy 350.546334 -176.40163)
			(xy 350.513038 -176.459309) (xy 350.472496 -176.512145) (xy 350.4254 -176.559235) (xy 350.372559 -176.599772)
			(xy 350.343978 -176.616868) (xy 349.419926 -177.150522) (xy 349.390862 -177.16662) (xy 349.329459 -177.191992)
			(xy 349.265273 -177.20915) (xy 349.1994 -177.217802) (xy 349.16618 -177.21834) (xy 349.165672 -177.21834)
			(xy 349.134942 -177.21787) (xy 349.073929 -177.210459) (xy 349.014255 -177.195748) (xy 348.956789 -177.173953)
			(xy 348.902369 -177.145389) (xy 348.851788 -177.110475) (xy 348.805784 -177.069719) (xy 348.765027 -177.023715)
			(xy 348.730113 -176.973135) (xy 348.701549 -176.918715) (xy 348.679753 -176.861249) (xy 348.665041 -176.801575)
			(xy 348.65763 -176.740562) (xy 348.657164 -176.709832) (xy 327.936352 -176.709832) (xy 324.888352 -179.757832)
			(xy 348.657164 -179.757832) (xy 348.657658 -179.724531) (xy 348.666337 -179.658499) (xy 348.683566 -179.594165)
			(xy 348.709048 -179.532632) (xy 348.742347 -179.474953) (xy 348.782893 -179.422117) (xy 348.829992 -179.375027)
			(xy 348.882836 -179.334492) (xy 348.911418 -179.317396) (xy 349.83547 -178.783742) (xy 349.864533 -178.767642)
			(xy 349.925937 -178.742271) (xy 349.990123 -178.725114) (xy 350.055996 -178.716463) (xy 350.089216 -178.715924)
			(xy 350.089724 -178.715924) (xy 350.120458 -178.716315) (xy 350.181477 -178.723727) (xy 350.241158 -178.73844)
			(xy 350.29863 -178.76024) (xy 350.353056 -178.788808) (xy 350.403641 -178.823729) (xy 350.449648 -178.864492)
			(xy 350.490406 -178.910503) (xy 350.525321 -178.961092) (xy 350.553883 -179.015521) (xy 350.575676 -179.072996)
			(xy 350.590383 -179.132678) (xy 350.597788 -179.193698) (xy 350.598232 -179.224432) (xy 350.597712 -179.257732)
			(xy 350.589036 -179.323763) (xy 350.581628 -179.351432) (xy 352.441764 -179.351432) (xy 352.442268 -179.320702)
			(xy 352.449672 -179.259689) (xy 352.464377 -179.200013) (xy 352.486168 -179.142545) (xy 352.514727 -179.088122)
			(xy 352.549637 -179.037539) (xy 352.59039 -178.991533) (xy 352.636392 -178.950774) (xy 352.686971 -178.915858)
			(xy 352.74139 -178.887292) (xy 352.798856 -178.865495) (xy 352.85853 -178.850783) (xy 352.919542 -178.843371)
			(xy 352.950272 -178.842924) (xy 352.95078 -178.842924) (xy 352.983998 -178.843489) (xy 353.049869 -178.852142)
			(xy 353.114055 -178.869291) (xy 353.175463 -178.894645) (xy 353.204526 -178.910742) (xy 354.128578 -179.444396)
			(xy 354.157139 -179.461518) (xy 354.209962 -179.502067) (xy 354.257042 -179.549162) (xy 354.297574 -179.601998)
			(xy 354.330866 -179.65967) (xy 354.356349 -179.721193) (xy 354.373586 -179.785515) (xy 354.382284 -179.851536)
			(xy 354.382832 -179.884832) (xy 354.382374 -179.915563) (xy 354.374962 -179.976576) (xy 354.360251 -180.036251)
			(xy 354.338454 -180.093717) (xy 354.30989 -180.148138) (xy 354.274975 -180.198719) (xy 354.234218 -180.244723)
			(xy 354.188213 -180.28548) (xy 354.137631 -180.320394) (xy 354.08321 -180.348957) (xy 354.025743 -180.370753)
			(xy 353.966068 -180.385464) (xy 353.905055 -180.392875) (xy 353.874324 -180.39334) (xy 353.873816 -180.39334)
			(xy 353.840597 -180.392782) (xy 353.774726 -180.384127) (xy 353.710541 -180.366976) (xy 353.649132 -180.341621)
			(xy 353.62007 -180.325522) (xy 352.696018 -179.791868) (xy 352.667463 -179.774735) (xy 352.614637 -179.734191)
			(xy 352.567553 -179.687099) (xy 352.527018 -179.634266) (xy 352.493724 -179.576595) (xy 352.468241 -179.515072)
			(xy 352.451005 -179.45075) (xy 352.44231 -179.384728) (xy 352.441764 -179.351432) (xy 350.581628 -179.351432)
			(xy 350.571812 -179.388097) (xy 350.546334 -179.44963) (xy 350.513038 -179.507309) (xy 350.472496 -179.560145)
			(xy 350.4254 -179.607235) (xy 350.372559 -179.647772) (xy 350.343978 -179.664868) (xy 349.419926 -180.198522)
			(xy 349.390862 -180.21462) (xy 349.329459 -180.239992) (xy 349.265273 -180.25715) (xy 349.1994 -180.265802)
			(xy 349.16618 -180.26634) (xy 349.165672 -180.26634) (xy 349.134942 -180.26587) (xy 349.073929 -180.258459)
			(xy 349.014255 -180.243748) (xy 348.956789 -180.221953) (xy 348.902369 -180.193389) (xy 348.851788 -180.158475)
			(xy 348.805784 -180.117719) (xy 348.765027 -180.071715) (xy 348.730113 -180.021135) (xy 348.701549 -179.966715)
			(xy 348.679753 -179.909249) (xy 348.665041 -179.849575) (xy 348.65763 -179.788562) (xy 348.657164 -179.757832)
			(xy 324.888352 -179.757832) (xy 321.840352 -182.805832) (xy 348.657164 -182.805832) (xy 348.657658 -182.772531)
			(xy 348.666337 -182.706499) (xy 348.683566 -182.642165) (xy 348.709048 -182.580632) (xy 348.742347 -182.522953)
			(xy 348.782893 -182.470117) (xy 348.829992 -182.423027) (xy 348.882836 -182.382492) (xy 348.911418 -182.365396)
			(xy 349.83547 -181.831742) (xy 349.864533 -181.815642) (xy 349.925937 -181.790271) (xy 349.990123 -181.773114)
			(xy 350.055996 -181.764463) (xy 350.089216 -181.763924) (xy 350.089724 -181.763924) (xy 350.120458 -181.764315)
			(xy 350.181477 -181.771727) (xy 350.241158 -181.78644) (xy 350.29863 -181.80824) (xy 350.353056 -181.836808)
			(xy 350.403641 -181.871729) (xy 350.449648 -181.912492) (xy 350.490406 -181.958503) (xy 350.525321 -182.009092)
			(xy 350.553883 -182.063521) (xy 350.575676 -182.120996) (xy 350.590383 -182.180678) (xy 350.597788 -182.241698)
			(xy 350.598232 -182.272432) (xy 350.597712 -182.305732) (xy 350.589036 -182.371763) (xy 350.571812 -182.436097)
			(xy 350.546334 -182.49763) (xy 350.513038 -182.555309) (xy 350.472496 -182.608145) (xy 350.4254 -182.655235)
			(xy 350.372559 -182.695772) (xy 350.343978 -182.712868) (xy 349.775297 -183.04129) (xy 352.441764 -183.04129)
			(xy 352.442192 -183.010552) (xy 352.449601 -182.949525) (xy 352.46431 -182.889835) (xy 352.486105 -182.832352)
			(xy 352.514667 -182.777914) (xy 352.549581 -182.727315) (xy 352.590338 -182.681292) (xy 352.636344 -182.640516)
			(xy 352.686928 -182.60558) (xy 352.741353 -182.576994) (xy 352.798826 -182.555175) (xy 352.85851 -182.540441)
			(xy 352.919534 -182.533005) (xy 352.950272 -182.532528) (xy 352.95078 -182.532528) (xy 352.984007 -182.533118)
			(xy 353.049889 -182.541823) (xy 353.114077 -182.559036) (xy 353.175475 -182.584464) (xy 353.204526 -182.6006)
			(xy 354.128578 -183.134254) (xy 354.157165 -183.151335) (xy 354.209988 -183.19189) (xy 354.257067 -183.238991)
			(xy 354.297597 -183.291832) (xy 354.330886 -183.34951) (xy 354.356365 -183.411039) (xy 354.373597 -183.475367)
			(xy 354.382288 -183.541392) (xy 354.382832 -183.57469) (xy 354.382389 -183.605428) (xy 354.374982 -183.666455)
			(xy 354.360275 -183.726145) (xy 354.338483 -183.783627) (xy 354.309922 -183.838065) (xy 354.275009 -183.888665)
			(xy 354.234254 -183.934688) (xy 354.188249 -183.975465) (xy 354.137666 -184.010401) (xy 354.083241 -184.038987)
			(xy 354.025768 -184.060806) (xy 353.966085 -184.07554) (xy 353.905061 -184.082975) (xy 353.874324 -184.083452)
			(xy 353.873816 -184.083452) (xy 353.840589 -184.082867) (xy 353.774706 -184.07416) (xy 353.710519 -184.056946)
			(xy 353.649121 -184.031517) (xy 353.62007 -184.01538) (xy 352.696018 -183.481726) (xy 352.667489 -183.464552)
			(xy 352.614663 -183.424014) (xy 352.567578 -183.376928) (xy 352.527041 -183.324101) (xy 352.493744 -183.266436)
			(xy 352.468257 -183.204918) (xy 352.451015 -183.140601) (xy 352.442314 -183.074584) (xy 352.441764 -183.04129)
			(xy 349.775297 -183.04129) (xy 349.419926 -183.246522) (xy 349.390862 -183.26262) (xy 349.329459 -183.287992)
			(xy 349.265273 -183.30515) (xy 349.1994 -183.313802) (xy 349.16618 -183.31434) (xy 349.165672 -183.31434)
			(xy 349.134942 -183.31387) (xy 349.073929 -183.306459) (xy 349.014255 -183.291748) (xy 348.956789 -183.269953)
			(xy 348.902369 -183.241389) (xy 348.851788 -183.206475) (xy 348.805784 -183.165719) (xy 348.765027 -183.119715)
			(xy 348.730113 -183.069135) (xy 348.701549 -183.014715) (xy 348.679753 -182.957249) (xy 348.665041 -182.897575)
			(xy 348.65763 -182.836562) (xy 348.657164 -182.805832) (xy 321.840352 -182.805832) (xy 318.57188 -186.074304)
			(xy 318.57188 -186.714892) (xy 351.367344 -186.714892) (xy 351.367848 -186.684163) (xy 351.375257 -186.623152)
			(xy 351.389965 -186.563479) (xy 351.411758 -186.506014) (xy 351.440318 -186.451595) (xy 351.475229 -186.401014)
			(xy 351.515982 -186.355011) (xy 351.561983 -186.314254) (xy 351.612561 -186.279339) (xy 351.666978 -186.250774)
			(xy 351.724441 -186.228977) (xy 351.784113 -186.214264) (xy 351.845123 -186.206851) (xy 351.875852 -186.206384)
			(xy 351.87636 -186.206384) (xy 351.90958 -186.206906) (xy 351.975453 -186.215571) (xy 352.039638 -186.232732)
			(xy 352.101045 -186.258098) (xy 352.130106 -186.274202) (xy 353.054158 -186.807856) (xy 353.082741 -186.824943)
			(xy 353.135565 -186.865496) (xy 353.182645 -186.912596) (xy 353.223176 -186.965436) (xy 353.256466 -187.023114)
			(xy 353.281945 -187.084642) (xy 353.299177 -187.148969) (xy 353.307868 -187.214995) (xy 353.308412 -187.248292)
			(xy 353.307955 -187.279024) (xy 353.300547 -187.340039) (xy 353.285839 -187.399717) (xy 353.264044 -187.457187)
			(xy 353.235482 -187.51161) (xy 353.200567 -187.562194) (xy 353.15981 -187.608201) (xy 353.113804 -187.648959)
			(xy 353.063221 -187.683875) (xy 353.008798 -187.712439) (xy 352.951329 -187.734235) (xy 352.891651 -187.748945)
			(xy 352.830636 -187.756354) (xy 352.799904 -187.7568) (xy 352.799396 -187.7568) (xy 352.766177 -187.756256)
			(xy 352.700305 -187.747598) (xy 352.636119 -187.730443) (xy 352.574711 -187.705083) (xy 352.54565 -187.688982)
			(xy 351.621598 -187.155328) (xy 351.593065 -187.13816) (xy 351.54024 -187.09762) (xy 351.493156 -187.050533)
			(xy 351.45262 -186.997705) (xy 351.419323 -186.940039) (xy 351.393837 -186.878521) (xy 351.376595 -186.814204)
			(xy 351.367894 -186.748186) (xy 351.367344 -186.714892) (xy 318.57188 -186.714892) (xy 318.57188 -193.87947)
			(xy 318.817498 -193.87947) (xy 318.839683 -193.879925) (xy 318.883379 -193.887629) (xy 318.925073 -193.902805)
			(xy 318.963499 -193.924989) (xy 318.997489 -193.95351) (xy 319.026009 -193.987499) (xy 319.048195 -194.025925)
			(xy 319.06337 -194.067619) (xy 319.071075 -194.111315) (xy 319.071075 -194.155685) (xy 319.06337 -194.199381)
			(xy 319.048195 -194.241075) (xy 319.026009 -194.279501) (xy 318.997489 -194.31349) (xy 318.963499 -194.342011)
			(xy 318.925073 -194.364195) (xy 318.883379 -194.379371) (xy 318.839683 -194.387075) (xy 318.817498 -194.38747)
			(xy 318.57188 -194.38747) (xy 318.57188 -194.718432) (xy 318.57188 -194.720972) (xy 318.57188 -194.723512)
			(xy 318.57188 -206.024988) (xy 334.640692 -206.024988) (xy 334.644673 -205.891968) (xy 334.656602 -205.759423)
			(xy 334.676437 -205.62783) (xy 334.704106 -205.497658) (xy 334.73951 -205.369373) (xy 334.782523 -205.243436)
			(xy 334.83299 -205.120297) (xy 334.890731 -205.000396) (xy 334.95554 -204.884163) (xy 335.027184 -204.772013)
			(xy 335.105406 -204.664349) (xy 335.189927 -204.561556) (xy 335.280445 -204.464001) (xy 335.376634 -204.372035)
			(xy 335.478152 -204.285985) (xy 335.584633 -204.206161) (xy 335.695698 -204.132848) (xy 335.810949 -204.066308)
			(xy 335.929973 -204.006779) (xy 336.052344 -203.954475) (xy 336.177623 -203.909583) (xy 336.305364 -203.872264)
			(xy 336.435107 -203.842651) (xy 336.566389 -203.82085) (xy 336.69874 -203.80694) (xy 336.831686 -203.800969)
			(xy 336.964751 -203.80296) (xy 337.097459 -203.812905) (xy 337.229335 -203.830769) (xy 337.359906 -203.856487)
			(xy 337.488706 -203.889968) (xy 337.615272 -203.931092) (xy 337.739153 -203.979712) (xy 337.859904 -204.035653)
			(xy 337.977094 -204.098715) (xy 338.090303 -204.168673) (xy 338.199125 -204.245277) (xy 338.303171 -204.328251)
			(xy 338.402069 -204.417299) (xy 338.495464 -204.512102) (xy 338.583022 -204.61232) (xy 338.664431 -204.717596)
			(xy 338.739397 -204.827552) (xy 338.807654 -204.941794) (xy 338.868956 -205.059914) (xy 338.923085 -205.181489)
			(xy 338.969846 -205.306083) (xy 339.009072 -205.433251) (xy 339.040622 -205.562537) (xy 339.064385 -205.693478)
			(xy 339.080274 -205.825606) (xy 339.088232 -205.958448) (xy 339.08873 -206.024988) (xy 339.088232 -206.091528)
			(xy 339.080274 -206.22437) (xy 339.064385 -206.356498) (xy 339.040622 -206.487439) (xy 339.009072 -206.616725)
			(xy 338.969846 -206.743893) (xy 338.923085 -206.868487) (xy 338.868956 -206.990062) (xy 338.807654 -207.108182)
			(xy 338.739397 -207.222424) (xy 338.664431 -207.33238) (xy 338.583022 -207.437656) (xy 338.495464 -207.537874)
			(xy 338.402069 -207.632677) (xy 338.303171 -207.721725) (xy 338.199125 -207.804699) (xy 338.090303 -207.881303)
			(xy 337.977094 -207.951261) (xy 337.859904 -208.014323) (xy 337.739153 -208.070264) (xy 337.615272 -208.118884)
			(xy 337.488706 -208.160008) (xy 337.359906 -208.193489) (xy 337.229335 -208.219207) (xy 337.097459 -208.237071)
			(xy 336.964751 -208.247016) (xy 336.831686 -208.249007) (xy 336.69874 -208.243036) (xy 336.566389 -208.229126)
			(xy 336.435107 -208.207325) (xy 336.305364 -208.177712) (xy 336.177623 -208.140393) (xy 336.052344 -208.095501)
			(xy 335.929973 -208.043197) (xy 335.810949 -207.983668) (xy 335.695698 -207.917128) (xy 335.584633 -207.843815)
			(xy 335.478152 -207.763991) (xy 335.376634 -207.677941) (xy 335.280445 -207.585975) (xy 335.189927 -207.48842)
			(xy 335.105406 -207.385627) (xy 335.027184 -207.277963) (xy 334.95554 -207.165813) (xy 334.890731 -207.04958)
			(xy 334.83299 -206.929679) (xy 334.782523 -206.80654) (xy 334.73951 -206.680603) (xy 334.704106 -206.552318)
			(xy 334.676437 -206.422146) (xy 334.656602 -206.290553) (xy 334.644673 -206.158008) (xy 334.640692 -206.024988)
			(xy 318.57188 -206.024988) (xy 318.57188 -213.732618) (xy 338.105496 -213.732618) (xy 338.106004 -213.706731)
			(xy 338.114103 -213.655593) (xy 338.130102 -213.606353) (xy 338.153608 -213.560221) (xy 338.18404 -213.518334)
			(xy 338.22065 -213.481724) (xy 338.262537 -213.451292) (xy 338.308669 -213.427786) (xy 338.357909 -213.411787)
			(xy 338.409047 -213.403688) (xy 338.460821 -213.403688) (xy 338.511959 -213.411787) (xy 338.561199 -213.427786)
			(xy 338.607331 -213.451292) (xy 338.649218 -213.481724) (xy 338.685828 -213.518334) (xy 338.71626 -213.560221)
			(xy 338.739766 -213.606353) (xy 338.755765 -213.655593) (xy 338.763864 -213.706731) (xy 338.764372 -213.732618)
			(xy 339.985096 -213.732618) (xy 339.985604 -213.706731) (xy 339.993703 -213.655593) (xy 340.009702 -213.606353)
			(xy 340.033208 -213.560221) (xy 340.06364 -213.518334) (xy 340.10025 -213.481724) (xy 340.142137 -213.451292)
			(xy 340.188269 -213.427786) (xy 340.237509 -213.411787) (xy 340.288647 -213.403688) (xy 340.340421 -213.403688)
			(xy 340.391559 -213.411787) (xy 340.440799 -213.427786) (xy 340.486931 -213.451292) (xy 340.528818 -213.481724)
			(xy 340.565428 -213.518334) (xy 340.59586 -213.560221) (xy 340.619366 -213.606353) (xy 340.635365 -213.655593)
			(xy 340.643464 -213.706731) (xy 340.643972 -213.732618) (xy 341.864696 -213.732618) (xy 341.865204 -213.706731)
			(xy 341.873303 -213.655593) (xy 341.889302 -213.606353) (xy 341.912808 -213.560221) (xy 341.94324 -213.518334)
			(xy 341.97985 -213.481724) (xy 342.021737 -213.451292) (xy 342.067869 -213.427786) (xy 342.117109 -213.411787)
			(xy 342.168247 -213.403688) (xy 342.220021 -213.403688) (xy 342.271159 -213.411787) (xy 342.320399 -213.427786)
			(xy 342.366531 -213.451292) (xy 342.408418 -213.481724) (xy 342.445028 -213.518334) (xy 342.47546 -213.560221)
			(xy 342.498966 -213.606353) (xy 342.514965 -213.655593) (xy 342.523064 -213.706731) (xy 342.523572 -213.732618)
			(xy 343.744296 -213.732618) (xy 343.744804 -213.706731) (xy 343.752903 -213.655593) (xy 343.768902 -213.606353)
			(xy 343.792408 -213.560221) (xy 343.82284 -213.518334) (xy 343.85945 -213.481724) (xy 343.901337 -213.451292)
			(xy 343.947469 -213.427786) (xy 343.996709 -213.411787) (xy 344.047847 -213.403688) (xy 344.099621 -213.403688)
			(xy 344.150759 -213.411787) (xy 344.199999 -213.427786) (xy 344.246131 -213.451292) (xy 344.288018 -213.481724)
			(xy 344.324628 -213.518334) (xy 344.35506 -213.560221) (xy 344.378566 -213.606353) (xy 344.394565 -213.655593)
			(xy 344.402664 -213.706731) (xy 344.403172 -213.732618) (xy 345.623896 -213.732618) (xy 345.624404 -213.706731)
			(xy 345.632503 -213.655593) (xy 345.648502 -213.606353) (xy 345.672008 -213.560221) (xy 345.70244 -213.518334)
			(xy 345.73905 -213.481724) (xy 345.780937 -213.451292) (xy 345.827069 -213.427786) (xy 345.876309 -213.411787)
			(xy 345.927447 -213.403688) (xy 345.979221 -213.403688) (xy 346.030359 -213.411787) (xy 346.079599 -213.427786)
			(xy 346.125731 -213.451292) (xy 346.167618 -213.481724) (xy 346.204228 -213.518334) (xy 346.23466 -213.560221)
			(xy 346.258166 -213.606353) (xy 346.274165 -213.655593) (xy 346.282264 -213.706731) (xy 346.282772 -213.732618)
			(xy 347.503496 -213.732618) (xy 347.504004 -213.706731) (xy 347.512103 -213.655593) (xy 347.528102 -213.606353)
			(xy 347.551608 -213.560221) (xy 347.58204 -213.518334) (xy 347.61865 -213.481724) (xy 347.660537 -213.451292)
			(xy 347.706669 -213.427786) (xy 347.755909 -213.411787) (xy 347.807047 -213.403688) (xy 347.858821 -213.403688)
			(xy 347.909959 -213.411787) (xy 347.959199 -213.427786) (xy 348.005331 -213.451292) (xy 348.047218 -213.481724)
			(xy 348.083828 -213.518334) (xy 348.11426 -213.560221) (xy 348.137766 -213.606353) (xy 348.153765 -213.655593)
			(xy 348.161864 -213.706731) (xy 348.162372 -213.732618) (xy 348.162023 -213.755595) (xy 348.155702 -213.801111)
			(xy 348.143116 -213.845306) (xy 348.134178 -213.866476) (xy 348.124272 -213.888828) (xy 348.337886 -214.293958)
			(xy 348.362016 -214.29853) (xy 348.38693 -214.303664) (xy 348.43494 -214.320459) (xy 348.479799 -214.344434)
			(xy 348.520441 -214.375017) (xy 348.555899 -214.411484) (xy 348.585332 -214.452967) (xy 348.60804 -214.49848)
			(xy 348.623483 -214.546942) (xy 348.631295 -214.597202) (xy 348.631764 -214.622634) (xy 348.631256 -214.648521)
			(xy 348.623157 -214.699659) (xy 348.607158 -214.748899) (xy 348.583652 -214.795031) (xy 348.55322 -214.836918)
			(xy 348.51661 -214.873528) (xy 348.474723 -214.90396) (xy 348.428591 -214.927466) (xy 348.379351 -214.943465)
			(xy 348.328213 -214.951564) (xy 348.276439 -214.951564) (xy 348.225301 -214.943465) (xy 348.176061 -214.927466)
			(xy 348.129929 -214.90396) (xy 348.088042 -214.873528) (xy 348.051432 -214.836918) (xy 348.021 -214.795031)
			(xy 347.997494 -214.748899) (xy 347.981495 -214.699659) (xy 347.973396 -214.648521) (xy 347.972888 -214.622634)
			(xy 347.973258 -214.599658) (xy 347.97957 -214.554143) (xy 347.992148 -214.509947) (xy 348.001082 -214.488776)
			(xy 348.010988 -214.466424) (xy 347.797374 -214.061294) (xy 347.773244 -214.056722) (xy 347.748313 -214.051663)
			(xy 347.700299 -214.034858) (xy 347.655439 -214.010874) (xy 347.614797 -213.980281) (xy 347.579339 -213.943805)
			(xy 347.549909 -213.902313) (xy 347.527205 -213.856791) (xy 347.511767 -213.80832) (xy 347.503962 -213.758053)
			(xy 347.503496 -213.732618) (xy 346.282772 -213.732618) (xy 346.282423 -213.755595) (xy 346.276102 -213.801111)
			(xy 346.263516 -213.845306) (xy 346.254578 -213.866476) (xy 346.244672 -213.888828) (xy 346.458286 -214.293958)
			(xy 346.482416 -214.29853) (xy 346.50733 -214.303664) (xy 346.55534 -214.320459) (xy 346.600199 -214.344434)
			(xy 346.640841 -214.375017) (xy 346.676299 -214.411484) (xy 346.705732 -214.452967) (xy 346.72844 -214.49848)
			(xy 346.743883 -214.546942) (xy 346.751695 -214.597202) (xy 346.752164 -214.622634) (xy 346.751656 -214.648521)
			(xy 346.743557 -214.699659) (xy 346.727558 -214.748899) (xy 346.704052 -214.795031) (xy 346.67362 -214.836918)
			(xy 346.63701 -214.873528) (xy 346.595123 -214.90396) (xy 346.548991 -214.927466) (xy 346.499751 -214.943465)
			(xy 346.448613 -214.951564) (xy 346.396839 -214.951564) (xy 346.345701 -214.943465) (xy 346.296461 -214.927466)
			(xy 346.250329 -214.90396) (xy 346.208442 -214.873528) (xy 346.171832 -214.836918) (xy 346.1414 -214.795031)
			(xy 346.117894 -214.748899) (xy 346.101895 -214.699659) (xy 346.093796 -214.648521) (xy 346.093288 -214.622634)
			(xy 346.093658 -214.599658) (xy 346.09997 -214.554143) (xy 346.112548 -214.509947) (xy 346.121482 -214.488776)
			(xy 346.131388 -214.466424) (xy 345.917774 -214.061294) (xy 345.893644 -214.056722) (xy 345.868713 -214.051663)
			(xy 345.820699 -214.034858) (xy 345.775839 -214.010874) (xy 345.735197 -213.980281) (xy 345.699739 -213.943805)
			(xy 345.670309 -213.902313) (xy 345.647605 -213.856791) (xy 345.632167 -213.80832) (xy 345.624362 -213.758053)
			(xy 345.623896 -213.732618) (xy 344.403172 -213.732618) (xy 344.402823 -213.755595) (xy 344.396502 -213.801111)
			(xy 344.383916 -213.845306) (xy 344.374978 -213.866476) (xy 344.365072 -213.888828) (xy 344.578686 -214.293958)
			(xy 344.602816 -214.29853) (xy 344.62773 -214.303664) (xy 344.67574 -214.320459) (xy 344.720599 -214.344434)
			(xy 344.761241 -214.375017) (xy 344.796699 -214.411484) (xy 344.826132 -214.452967) (xy 344.84884 -214.49848)
			(xy 344.864283 -214.546942) (xy 344.872095 -214.597202) (xy 344.872564 -214.622634) (xy 344.872056 -214.648521)
			(xy 344.863957 -214.699659) (xy 344.847958 -214.748899) (xy 344.824452 -214.795031) (xy 344.79402 -214.836918)
			(xy 344.75741 -214.873528) (xy 344.715523 -214.90396) (xy 344.669391 -214.927466) (xy 344.620151 -214.943465)
			(xy 344.569013 -214.951564) (xy 344.517239 -214.951564) (xy 344.466101 -214.943465) (xy 344.416861 -214.927466)
			(xy 344.370729 -214.90396) (xy 344.328842 -214.873528) (xy 344.292232 -214.836918) (xy 344.2618 -214.795031)
			(xy 344.238294 -214.748899) (xy 344.222295 -214.699659) (xy 344.214196 -214.648521) (xy 344.213688 -214.622634)
			(xy 344.214058 -214.599658) (xy 344.22037 -214.554143) (xy 344.232948 -214.509947) (xy 344.241882 -214.488776)
			(xy 344.251788 -214.466424) (xy 344.038174 -214.061294) (xy 344.014044 -214.056722) (xy 343.989113 -214.051663)
			(xy 343.941099 -214.034858) (xy 343.896239 -214.010874) (xy 343.855597 -213.980281) (xy 343.820139 -213.943805)
			(xy 343.790709 -213.902313) (xy 343.768005 -213.856791) (xy 343.752567 -213.80832) (xy 343.744762 -213.758053)
			(xy 343.744296 -213.732618) (xy 342.523572 -213.732618) (xy 342.523223 -213.755595) (xy 342.516902 -213.801111)
			(xy 342.504316 -213.845306) (xy 342.495378 -213.866476) (xy 342.485472 -213.888828) (xy 342.699086 -214.293958)
			(xy 342.723216 -214.29853) (xy 342.74813 -214.303664) (xy 342.79614 -214.320459) (xy 342.840999 -214.344434)
			(xy 342.881641 -214.375017) (xy 342.917099 -214.411484) (xy 342.946532 -214.452967) (xy 342.96924 -214.49848)
			(xy 342.984683 -214.546942) (xy 342.992495 -214.597202) (xy 342.992964 -214.622634) (xy 342.992456 -214.648521)
			(xy 342.984357 -214.699659) (xy 342.968358 -214.748899) (xy 342.944852 -214.795031) (xy 342.91442 -214.836918)
			(xy 342.87781 -214.873528) (xy 342.835923 -214.90396) (xy 342.789791 -214.927466) (xy 342.740551 -214.943465)
			(xy 342.689413 -214.951564) (xy 342.637639 -214.951564) (xy 342.586501 -214.943465) (xy 342.537261 -214.927466)
			(xy 342.491129 -214.90396) (xy 342.449242 -214.873528) (xy 342.412632 -214.836918) (xy 342.3822 -214.795031)
			(xy 342.358694 -214.748899) (xy 342.342695 -214.699659) (xy 342.334596 -214.648521) (xy 342.334088 -214.622634)
			(xy 342.334458 -214.599658) (xy 342.34077 -214.554143) (xy 342.353348 -214.509947) (xy 342.362282 -214.488776)
			(xy 342.372188 -214.466424) (xy 342.158574 -214.061294) (xy 342.134444 -214.056722) (xy 342.109513 -214.051663)
			(xy 342.061499 -214.034858) (xy 342.016639 -214.010874) (xy 341.975997 -213.980281) (xy 341.940539 -213.943805)
			(xy 341.911109 -213.902313) (xy 341.888405 -213.856791) (xy 341.872967 -213.80832) (xy 341.865162 -213.758053)
			(xy 341.864696 -213.732618) (xy 340.643972 -213.732618) (xy 340.643623 -213.755595) (xy 340.637302 -213.801111)
			(xy 340.624716 -213.845306) (xy 340.615778 -213.866476) (xy 340.605872 -213.888828) (xy 340.819486 -214.293958)
			(xy 340.843616 -214.29853) (xy 340.86853 -214.303664) (xy 340.91654 -214.320459) (xy 340.961399 -214.344434)
			(xy 341.002041 -214.375017) (xy 341.037499 -214.411484) (xy 341.066932 -214.452967) (xy 341.08964 -214.49848)
			(xy 341.105083 -214.546942) (xy 341.112895 -214.597202) (xy 341.113364 -214.622634) (xy 341.112856 -214.648521)
			(xy 341.104757 -214.699659) (xy 341.088758 -214.748899) (xy 341.065252 -214.795031) (xy 341.03482 -214.836918)
			(xy 340.99821 -214.873528) (xy 340.956323 -214.90396) (xy 340.910191 -214.927466) (xy 340.860951 -214.943465)
			(xy 340.809813 -214.951564) (xy 340.758039 -214.951564) (xy 340.706901 -214.943465) (xy 340.657661 -214.927466)
			(xy 340.611529 -214.90396) (xy 340.569642 -214.873528) (xy 340.533032 -214.836918) (xy 340.5026 -214.795031)
			(xy 340.479094 -214.748899) (xy 340.463095 -214.699659) (xy 340.454996 -214.648521) (xy 340.454488 -214.622634)
			(xy 340.454858 -214.599658) (xy 340.46117 -214.554143) (xy 340.473748 -214.509947) (xy 340.482682 -214.488776)
			(xy 340.492588 -214.466424) (xy 340.278974 -214.061294) (xy 340.254844 -214.056722) (xy 340.229913 -214.051663)
			(xy 340.181899 -214.034858) (xy 340.137039 -214.010874) (xy 340.096397 -213.980281) (xy 340.060939 -213.943805)
			(xy 340.031509 -213.902313) (xy 340.008805 -213.856791) (xy 339.993367 -213.80832) (xy 339.985562 -213.758053)
			(xy 339.985096 -213.732618) (xy 338.764372 -213.732618) (xy 338.764023 -213.755595) (xy 338.757702 -213.801111)
			(xy 338.745116 -213.845306) (xy 338.736178 -213.866476) (xy 338.726272 -213.888828) (xy 338.939886 -214.293958)
			(xy 338.964016 -214.29853) (xy 338.98893 -214.303664) (xy 339.03694 -214.320459) (xy 339.081799 -214.344434)
			(xy 339.122441 -214.375017) (xy 339.157899 -214.411484) (xy 339.187332 -214.452967) (xy 339.21004 -214.49848)
			(xy 339.225483 -214.546942) (xy 339.233295 -214.597202) (xy 339.233764 -214.622634) (xy 339.233256 -214.648521)
			(xy 339.225157 -214.699659) (xy 339.209158 -214.748899) (xy 339.185652 -214.795031) (xy 339.15522 -214.836918)
			(xy 339.11861 -214.873528) (xy 339.076723 -214.90396) (xy 339.030591 -214.927466) (xy 338.981351 -214.943465)
			(xy 338.930213 -214.951564) (xy 338.878439 -214.951564) (xy 338.827301 -214.943465) (xy 338.778061 -214.927466)
			(xy 338.731929 -214.90396) (xy 338.690042 -214.873528) (xy 338.653432 -214.836918) (xy 338.623 -214.795031)
			(xy 338.599494 -214.748899) (xy 338.583495 -214.699659) (xy 338.575396 -214.648521) (xy 338.574888 -214.622634)
			(xy 338.575258 -214.599658) (xy 338.58157 -214.554143) (xy 338.594148 -214.509947) (xy 338.603082 -214.488776)
			(xy 338.612988 -214.466424) (xy 338.399374 -214.061294) (xy 338.375244 -214.056722) (xy 338.350313 -214.051663)
			(xy 338.302299 -214.034858) (xy 338.257439 -214.010874) (xy 338.216797 -213.980281) (xy 338.181339 -213.943805)
			(xy 338.151909 -213.902313) (xy 338.129205 -213.856791) (xy 338.113767 -213.80832) (xy 338.105962 -213.758053)
			(xy 338.105496 -213.732618) (xy 318.57188 -213.732618) (xy 318.57188 -215.436704) (xy 336.225388 -215.436704)
			(xy 336.225896 -215.410797) (xy 336.234002 -215.35962) (xy 336.250014 -215.310341) (xy 336.273537 -215.264174)
			(xy 336.303993 -215.222255) (xy 336.340631 -215.185617) (xy 336.38255 -215.155161) (xy 336.428717 -215.131638)
			(xy 336.477996 -215.115626) (xy 336.529173 -215.10752) (xy 336.580987 -215.10752) (xy 336.632164 -215.115626)
			(xy 336.681443 -215.131638) (xy 336.72761 -215.155161) (xy 336.769529 -215.185617) (xy 336.806167 -215.222255)
			(xy 336.836623 -215.264174) (xy 336.860146 -215.310341) (xy 336.876158 -215.35962) (xy 336.884264 -215.410797)
			(xy 336.884772 -215.436704) (xy 337.165188 -215.436704) (xy 337.165723 -215.411361) (xy 337.173493 -215.361274)
			(xy 337.188837 -215.312966) (xy 337.211392 -215.267575) (xy 337.240627 -215.226169) (xy 337.275854 -215.189725)
			(xy 337.316243 -215.159101) (xy 337.360842 -215.135018) (xy 337.408601 -215.118043) (xy 337.433412 -215.112854)
			(xy 337.456272 -215.108536) (xy 337.66125 -214.753444) (xy 337.653376 -214.7316) (xy 337.644799 -214.705181)
			(xy 337.6356 -214.650406) (xy 337.635088 -214.622634) (xy 337.635596 -214.596747) (xy 337.643695 -214.545609)
			(xy 337.659694 -214.496369) (xy 337.6832 -214.450237) (xy 337.713632 -214.40835) (xy 337.750242 -214.37174)
			(xy 337.792129 -214.341308) (xy 337.838261 -214.317802) (xy 337.887501 -214.301803) (xy 337.938639 -214.293704)
			(xy 337.990413 -214.293704) (xy 338.041551 -214.301803) (xy 338.090791 -214.317802) (xy 338.136923 -214.341308)
			(xy 338.17881 -214.37174) (xy 338.21542 -214.40835) (xy 338.245852 -214.450237) (xy 338.269358 -214.496369)
			(xy 338.285357 -214.545609) (xy 338.293456 -214.596747) (xy 338.293964 -214.622634) (xy 338.293541 -214.647971)
			(xy 338.285783 -214.698047) (xy 338.270454 -214.746347) (xy 338.247915 -214.791733) (xy 338.218698 -214.833136)
			(xy 338.18349 -214.869581) (xy 338.14312 -214.90021) (xy 338.098539 -214.924301) (xy 338.050797 -214.941288)
			(xy 338.025994 -214.946484) (xy 338.003134 -214.950802) (xy 337.798156 -215.305894) (xy 337.80603 -215.327738)
			(xy 337.814677 -215.354146) (xy 337.823997 -215.408922) (xy 337.824572 -215.436704) (xy 339.044788 -215.436704)
			(xy 339.045323 -215.411361) (xy 339.053093 -215.361274) (xy 339.068437 -215.312966) (xy 339.090992 -215.267575)
			(xy 339.120227 -215.226169) (xy 339.155454 -215.189725) (xy 339.195843 -215.159101) (xy 339.240442 -215.135018)
			(xy 339.288201 -215.118043) (xy 339.313012 -215.112854) (xy 339.335872 -215.108536) (xy 339.54085 -214.753444)
			(xy 339.532976 -214.7316) (xy 339.524399 -214.705181) (xy 339.5152 -214.650406) (xy 339.514688 -214.622634)
			(xy 339.515196 -214.596747) (xy 339.523295 -214.545609) (xy 339.539294 -214.496369) (xy 339.5628 -214.450237)
			(xy 339.593232 -214.40835) (xy 339.629842 -214.37174) (xy 339.671729 -214.341308) (xy 339.717861 -214.317802)
			(xy 339.767101 -214.301803) (xy 339.818239 -214.293704) (xy 339.870013 -214.293704) (xy 339.921151 -214.301803)
			(xy 339.970391 -214.317802) (xy 340.016523 -214.341308) (xy 340.05841 -214.37174) (xy 340.09502 -214.40835)
			(xy 340.125452 -214.450237) (xy 340.148958 -214.496369) (xy 340.164957 -214.545609) (xy 340.173056 -214.596747)
			(xy 340.173564 -214.622634) (xy 340.173141 -214.647971) (xy 340.165383 -214.698047) (xy 340.150054 -214.746347)
			(xy 340.127515 -214.791733) (xy 340.098298 -214.833136) (xy 340.06309 -214.869581) (xy 340.02272 -214.90021)
			(xy 339.978139 -214.924301) (xy 339.930397 -214.941288) (xy 339.905594 -214.946484) (xy 339.882734 -214.950802)
			(xy 339.677756 -215.305894) (xy 339.68563 -215.327738) (xy 339.694277 -215.354146) (xy 339.703597 -215.408922)
			(xy 339.704172 -215.436704) (xy 340.924388 -215.436704) (xy 340.924923 -215.411361) (xy 340.932693 -215.361274)
			(xy 340.948037 -215.312966) (xy 340.970592 -215.267575) (xy 340.999827 -215.226169) (xy 341.035054 -215.189725)
			(xy 341.075443 -215.159101) (xy 341.120042 -215.135018) (xy 341.167801 -215.118043) (xy 341.192612 -215.112854)
			(xy 341.215472 -215.108536) (xy 341.42045 -214.753444) (xy 341.412576 -214.7316) (xy 341.403999 -214.705181)
			(xy 341.3948 -214.650406) (xy 341.394288 -214.622634) (xy 341.394796 -214.596747) (xy 341.402895 -214.545609)
			(xy 341.418894 -214.496369) (xy 341.4424 -214.450237) (xy 341.472832 -214.40835) (xy 341.509442 -214.37174)
			(xy 341.551329 -214.341308) (xy 341.597461 -214.317802) (xy 341.646701 -214.301803) (xy 341.697839 -214.293704)
			(xy 341.749613 -214.293704) (xy 341.800751 -214.301803) (xy 341.849991 -214.317802) (xy 341.896123 -214.341308)
			(xy 341.93801 -214.37174) (xy 341.97462 -214.40835) (xy 342.005052 -214.450237) (xy 342.028558 -214.496369)
			(xy 342.044557 -214.545609) (xy 342.052656 -214.596747) (xy 342.053164 -214.622634) (xy 342.052741 -214.647971)
			(xy 342.044983 -214.698047) (xy 342.029654 -214.746347) (xy 342.007115 -214.791733) (xy 341.977898 -214.833136)
			(xy 341.94269 -214.869581) (xy 341.90232 -214.90021) (xy 341.857739 -214.924301) (xy 341.809997 -214.941288)
			(xy 341.785194 -214.946484) (xy 341.762334 -214.950802) (xy 341.557356 -215.305894) (xy 341.56523 -215.327738)
			(xy 341.573877 -215.354146) (xy 341.583197 -215.408922) (xy 341.583772 -215.436704) (xy 342.803988 -215.436704)
			(xy 342.804523 -215.411361) (xy 342.812293 -215.361274) (xy 342.827637 -215.312966) (xy 342.850192 -215.267575)
			(xy 342.879427 -215.226169) (xy 342.914654 -215.189725) (xy 342.955043 -215.159101) (xy 342.999642 -215.135018)
			(xy 343.047401 -215.118043) (xy 343.072212 -215.112854) (xy 343.095072 -215.108536) (xy 343.30005 -214.753444)
			(xy 343.292176 -214.7316) (xy 343.283599 -214.705181) (xy 343.2744 -214.650406) (xy 343.273888 -214.622634)
			(xy 343.274396 -214.596747) (xy 343.282495 -214.545609) (xy 343.298494 -214.496369) (xy 343.322 -214.450237)
			(xy 343.352432 -214.40835) (xy 343.389042 -214.37174) (xy 343.430929 -214.341308) (xy 343.477061 -214.317802)
			(xy 343.526301 -214.301803) (xy 343.577439 -214.293704) (xy 343.629213 -214.293704) (xy 343.680351 -214.301803)
			(xy 343.729591 -214.317802) (xy 343.775723 -214.341308) (xy 343.81761 -214.37174) (xy 343.85422 -214.40835)
			(xy 343.884652 -214.450237) (xy 343.908158 -214.496369) (xy 343.924157 -214.545609) (xy 343.932256 -214.596747)
			(xy 343.932764 -214.622634) (xy 343.932341 -214.647971) (xy 343.924583 -214.698047) (xy 343.909254 -214.746347)
			(xy 343.886715 -214.791733) (xy 343.857498 -214.833136) (xy 343.82229 -214.869581) (xy 343.78192 -214.90021)
			(xy 343.737339 -214.924301) (xy 343.689597 -214.941288) (xy 343.664794 -214.946484) (xy 343.641934 -214.950802)
			(xy 343.436956 -215.305894) (xy 343.44483 -215.327738) (xy 343.453477 -215.354146) (xy 343.462797 -215.408922)
			(xy 343.463372 -215.436704) (xy 344.683588 -215.436704) (xy 344.684123 -215.411361) (xy 344.691893 -215.361274)
			(xy 344.707237 -215.312966) (xy 344.729792 -215.267575) (xy 344.759027 -215.226169) (xy 344.794254 -215.189725)
			(xy 344.834643 -215.159101) (xy 344.879242 -215.135018) (xy 344.927001 -215.118043) (xy 344.951812 -215.112854)
			(xy 344.974672 -215.108536) (xy 345.17965 -214.753444) (xy 345.171776 -214.7316) (xy 345.163199 -214.705181)
			(xy 345.154 -214.650406) (xy 345.153488 -214.622634) (xy 345.153996 -214.596747) (xy 345.162095 -214.545609)
			(xy 345.178094 -214.496369) (xy 345.2016 -214.450237) (xy 345.232032 -214.40835) (xy 345.268642 -214.37174)
			(xy 345.310529 -214.341308) (xy 345.356661 -214.317802) (xy 345.405901 -214.301803) (xy 345.457039 -214.293704)
			(xy 345.508813 -214.293704) (xy 345.559951 -214.301803) (xy 345.609191 -214.317802) (xy 345.655323 -214.341308)
			(xy 345.69721 -214.37174) (xy 345.73382 -214.40835) (xy 345.764252 -214.450237) (xy 345.787758 -214.496369)
			(xy 345.803757 -214.545609) (xy 345.811856 -214.596747) (xy 345.812364 -214.622634) (xy 345.811941 -214.647971)
			(xy 345.804183 -214.698047) (xy 345.788854 -214.746347) (xy 345.766315 -214.791733) (xy 345.737098 -214.833136)
			(xy 345.70189 -214.869581) (xy 345.66152 -214.90021) (xy 345.616939 -214.924301) (xy 345.569197 -214.941288)
			(xy 345.544394 -214.946484) (xy 345.521534 -214.950802) (xy 345.316556 -215.305894) (xy 345.32443 -215.327738)
			(xy 345.333077 -215.354146) (xy 345.342397 -215.408922) (xy 345.342972 -215.436704) (xy 346.563188 -215.436704)
			(xy 346.563723 -215.411361) (xy 346.571493 -215.361274) (xy 346.586837 -215.312966) (xy 346.609392 -215.267575)
			(xy 346.638627 -215.226169) (xy 346.673854 -215.189725) (xy 346.714243 -215.159101) (xy 346.758842 -215.135018)
			(xy 346.806601 -215.118043) (xy 346.831412 -215.112854) (xy 346.854272 -215.108536) (xy 347.05925 -214.753444)
			(xy 347.051376 -214.7316) (xy 347.042799 -214.705181) (xy 347.0336 -214.650406) (xy 347.033088 -214.622634)
			(xy 347.033596 -214.596747) (xy 347.041695 -214.545609) (xy 347.057694 -214.496369) (xy 347.0812 -214.450237)
			(xy 347.111632 -214.40835) (xy 347.148242 -214.37174) (xy 347.190129 -214.341308) (xy 347.236261 -214.317802)
			(xy 347.285501 -214.301803) (xy 347.336639 -214.293704) (xy 347.388413 -214.293704) (xy 347.439551 -214.301803)
			(xy 347.488791 -214.317802) (xy 347.534923 -214.341308) (xy 347.57681 -214.37174) (xy 347.61342 -214.40835)
			(xy 347.643852 -214.450237) (xy 347.667358 -214.496369) (xy 347.683357 -214.545609) (xy 347.691456 -214.596747)
			(xy 347.691964 -214.622634) (xy 347.691541 -214.647971) (xy 347.683783 -214.698047) (xy 347.668454 -214.746347)
			(xy 347.645915 -214.791733) (xy 347.616698 -214.833136) (xy 347.58149 -214.869581) (xy 347.54112 -214.90021)
			(xy 347.496539 -214.924301) (xy 347.448797 -214.941288) (xy 347.423994 -214.946484) (xy 347.401134 -214.950802)
			(xy 347.196156 -215.305894) (xy 347.20403 -215.327738) (xy 347.212677 -215.354146) (xy 347.221997 -215.408922)
			(xy 347.222572 -215.436704) (xy 347.222064 -215.462611) (xy 347.213958 -215.513788) (xy 347.197946 -215.563067)
			(xy 347.174423 -215.609234) (xy 347.143967 -215.651153) (xy 347.107329 -215.687791) (xy 347.06541 -215.718247)
			(xy 347.019243 -215.74177) (xy 346.969964 -215.757782) (xy 346.918787 -215.765888) (xy 346.866973 -215.765888)
			(xy 346.815796 -215.757782) (xy 346.766517 -215.74177) (xy 346.72035 -215.718247) (xy 346.678431 -215.687791)
			(xy 346.641793 -215.651153) (xy 346.611337 -215.609234) (xy 346.587814 -215.563067) (xy 346.571802 -215.513788)
			(xy 346.563696 -215.462611) (xy 346.563188 -215.436704) (xy 345.342972 -215.436704) (xy 345.342464 -215.462611)
			(xy 345.334358 -215.513788) (xy 345.318346 -215.563067) (xy 345.294823 -215.609234) (xy 345.264367 -215.651153)
			(xy 345.227729 -215.687791) (xy 345.18581 -215.718247) (xy 345.139643 -215.74177) (xy 345.090364 -215.757782)
			(xy 345.039187 -215.765888) (xy 344.987373 -215.765888) (xy 344.936196 -215.757782) (xy 344.886917 -215.74177)
			(xy 344.84075 -215.718247) (xy 344.798831 -215.687791) (xy 344.762193 -215.651153) (xy 344.731737 -215.609234)
			(xy 344.708214 -215.563067) (xy 344.692202 -215.513788) (xy 344.684096 -215.462611) (xy 344.683588 -215.436704)
			(xy 343.463372 -215.436704) (xy 343.462864 -215.462611) (xy 343.454758 -215.513788) (xy 343.438746 -215.563067)
			(xy 343.415223 -215.609234) (xy 343.384767 -215.651153) (xy 343.348129 -215.687791) (xy 343.30621 -215.718247)
			(xy 343.260043 -215.74177) (xy 343.210764 -215.757782) (xy 343.159587 -215.765888) (xy 343.107773 -215.765888)
			(xy 343.056596 -215.757782) (xy 343.007317 -215.74177) (xy 342.96115 -215.718247) (xy 342.919231 -215.687791)
			(xy 342.882593 -215.651153) (xy 342.852137 -215.609234) (xy 342.828614 -215.563067) (xy 342.812602 -215.513788)
			(xy 342.804496 -215.462611) (xy 342.803988 -215.436704) (xy 341.583772 -215.436704) (xy 341.583264 -215.462611)
			(xy 341.575158 -215.513788) (xy 341.559146 -215.563067) (xy 341.535623 -215.609234) (xy 341.505167 -215.651153)
			(xy 341.468529 -215.687791) (xy 341.42661 -215.718247) (xy 341.380443 -215.74177) (xy 341.331164 -215.757782)
			(xy 341.279987 -215.765888) (xy 341.228173 -215.765888) (xy 341.176996 -215.757782) (xy 341.127717 -215.74177)
			(xy 341.08155 -215.718247) (xy 341.039631 -215.687791) (xy 341.002993 -215.651153) (xy 340.972537 -215.609234)
			(xy 340.949014 -215.563067) (xy 340.933002 -215.513788) (xy 340.924896 -215.462611) (xy 340.924388 -215.436704)
			(xy 339.704172 -215.436704) (xy 339.703664 -215.462611) (xy 339.695558 -215.513788) (xy 339.679546 -215.563067)
			(xy 339.656023 -215.609234) (xy 339.625567 -215.651153) (xy 339.588929 -215.687791) (xy 339.54701 -215.718247)
			(xy 339.500843 -215.74177) (xy 339.451564 -215.757782) (xy 339.400387 -215.765888) (xy 339.348573 -215.765888)
			(xy 339.297396 -215.757782) (xy 339.248117 -215.74177) (xy 339.20195 -215.718247) (xy 339.160031 -215.687791)
			(xy 339.123393 -215.651153) (xy 339.092937 -215.609234) (xy 339.069414 -215.563067) (xy 339.053402 -215.513788)
			(xy 339.045296 -215.462611) (xy 339.044788 -215.436704) (xy 337.824572 -215.436704) (xy 337.824064 -215.462611)
			(xy 337.815958 -215.513788) (xy 337.799946 -215.563067) (xy 337.776423 -215.609234) (xy 337.745967 -215.651153)
			(xy 337.709329 -215.687791) (xy 337.66741 -215.718247) (xy 337.621243 -215.74177) (xy 337.571964 -215.757782)
			(xy 337.520787 -215.765888) (xy 337.468973 -215.765888) (xy 337.417796 -215.757782) (xy 337.368517 -215.74177)
			(xy 337.32235 -215.718247) (xy 337.280431 -215.687791) (xy 337.243793 -215.651153) (xy 337.213337 -215.609234)
			(xy 337.189814 -215.563067) (xy 337.173802 -215.513788) (xy 337.165696 -215.462611) (xy 337.165188 -215.436704)
			(xy 336.884772 -215.436704) (xy 336.884181 -215.464421) (xy 336.874856 -215.519068) (xy 336.86623 -215.545416)
			(xy 336.858356 -215.567514) (xy 337.063334 -215.922352) (xy 337.086194 -215.92667) (xy 337.110997 -215.931858)
			(xy 337.158737 -215.948846) (xy 337.203315 -215.972939) (xy 337.243681 -216.00357) (xy 337.278884 -216.040017)
			(xy 337.308096 -216.081421) (xy 337.330629 -216.126808) (xy 337.345951 -216.175108) (xy 337.353702 -216.225184)
			(xy 337.354164 -216.25052) (xy 337.353656 -216.276407) (xy 337.345557 -216.327545) (xy 337.329558 -216.376785)
			(xy 337.306052 -216.422917) (xy 337.27562 -216.464804) (xy 337.23901 -216.501414) (xy 337.197123 -216.531846)
			(xy 337.150991 -216.555352) (xy 337.101751 -216.571351) (xy 337.050613 -216.57945) (xy 336.998839 -216.57945)
			(xy 336.947701 -216.571351) (xy 336.898461 -216.555352) (xy 336.852329 -216.531846) (xy 336.810442 -216.501414)
			(xy 336.773832 -216.464804) (xy 336.7434 -216.422917) (xy 336.719894 -216.376785) (xy 336.703895 -216.327545)
			(xy 336.695796 -216.276407) (xy 336.695288 -216.25052) (xy 336.695823 -216.222812) (xy 336.705015 -216.168165)
			(xy 336.713576 -216.141808) (xy 336.72145 -216.11971) (xy 336.516472 -215.764872) (xy 336.493612 -215.760554)
			(xy 336.46879 -215.755389) (xy 336.421007 -215.73844) (xy 336.376384 -215.714372) (xy 336.335974 -215.683753)
			(xy 336.300731 -215.647305) (xy 336.271487 -215.60589) (xy 336.248932 -215.560483) (xy 336.233597 -215.512158)
			(xy 336.225846 -215.462054) (xy 336.225388 -215.436704) (xy 318.57188 -215.436704) (xy 318.57188 -217.425016)
			(xy 319.078102 -217.931238) (xy 336.695796 -217.931238) (xy 336.695796 -217.880184) (xy 336.695796 -217.878406)
			(xy 336.696304 -217.852519) (xy 336.704403 -217.801381) (xy 336.720402 -217.752141) (xy 336.743908 -217.706009)
			(xy 336.77434 -217.664122) (xy 336.81095 -217.627512) (xy 336.852837 -217.59708) (xy 336.898969 -217.573574)
			(xy 336.948209 -217.557575) (xy 336.999347 -217.549476) (xy 337.051121 -217.549476) (xy 337.102259 -217.557575)
			(xy 337.151499 -217.573574) (xy 337.197631 -217.59708) (xy 337.239518 -217.627512) (xy 337.276128 -217.664122)
			(xy 337.30656 -217.706009) (xy 337.330066 -217.752141) (xy 337.346065 -217.801381) (xy 337.354164 -217.852519)
			(xy 337.354672 -217.878406) (xy 337.354672 -217.880184) (xy 337.354672 -217.931238) (xy 337.635596 -217.931238)
			(xy 337.635596 -217.880184) (xy 337.635596 -217.878406) (xy 337.636059 -217.85307) (xy 337.643811 -217.802993)
			(xy 337.659134 -217.754693) (xy 337.681666 -217.709305) (xy 337.710877 -217.6679) (xy 337.74608 -217.631451)
			(xy 337.786444 -217.600818) (xy 337.831021 -217.576721) (xy 337.878759 -217.559728) (xy 337.903566 -217.554556)
			(xy 337.926426 -217.550238) (xy 338.131404 -217.195146) (xy 338.12353 -217.173302) (xy 338.114881 -217.146894)
			(xy 338.105553 -217.092118) (xy 338.104988 -217.064336) (xy 338.105496 -217.038429) (xy 338.113602 -216.987252)
			(xy 338.129614 -216.937973) (xy 338.153137 -216.891806) (xy 338.183593 -216.849887) (xy 338.220231 -216.813249)
			(xy 338.26215 -216.782793) (xy 338.308317 -216.75927) (xy 338.357596 -216.743258) (xy 338.408773 -216.735152)
			(xy 338.460587 -216.735152) (xy 338.511764 -216.743258) (xy 338.561043 -216.75927) (xy 338.60721 -216.782793)
			(xy 338.649129 -216.813249) (xy 338.685767 -216.849887) (xy 338.716223 -216.891806) (xy 338.739746 -216.937973)
			(xy 338.755758 -216.987252) (xy 338.763864 -217.038429) (xy 338.764372 -217.064336) (xy 338.763912 -217.089686)
			(xy 338.756157 -217.139789) (xy 338.740821 -217.188114) (xy 338.718265 -217.233519) (xy 338.689022 -217.274935)
			(xy 338.653781 -217.311384) (xy 338.613373 -217.342006) (xy 338.568753 -217.366079) (xy 338.520973 -217.383035)
			(xy 338.496148 -217.388186) (xy 338.473288 -217.392504) (xy 338.26831 -217.747596) (xy 338.276184 -217.76944)
			(xy 338.284758 -217.79586) (xy 338.293942 -217.850635) (xy 338.294472 -217.878406) (xy 338.294472 -217.880184)
			(xy 338.294472 -217.931238) (xy 338.575396 -217.931238) (xy 338.575396 -217.880184) (xy 338.575396 -217.878406)
			(xy 338.575904 -217.852519) (xy 338.584003 -217.801381) (xy 338.600002 -217.752141) (xy 338.623508 -217.706009)
			(xy 338.65394 -217.664122) (xy 338.69055 -217.627512) (xy 338.732437 -217.59708) (xy 338.778569 -217.573574)
			(xy 338.827809 -217.557575) (xy 338.878947 -217.549476) (xy 338.930721 -217.549476) (xy 338.981859 -217.557575)
			(xy 339.031099 -217.573574) (xy 339.077231 -217.59708) (xy 339.119118 -217.627512) (xy 339.155728 -217.664122)
			(xy 339.18616 -217.706009) (xy 339.209666 -217.752141) (xy 339.225665 -217.801381) (xy 339.233764 -217.852519)
			(xy 339.234272 -217.878406) (xy 339.234272 -217.880184) (xy 339.234272 -217.931238) (xy 339.515196 -217.931238)
			(xy 339.515196 -217.880184) (xy 339.515196 -217.878406) (xy 339.515659 -217.85307) (xy 339.523411 -217.802993)
			(xy 339.538734 -217.754693) (xy 339.561266 -217.709305) (xy 339.590477 -217.6679) (xy 339.62568 -217.631451)
			(xy 339.666044 -217.600818) (xy 339.710621 -217.576721) (xy 339.758359 -217.559728) (xy 339.783166 -217.554556)
			(xy 339.806026 -217.550238) (xy 340.011004 -217.195146) (xy 340.00313 -217.173302) (xy 339.994481 -217.146894)
			(xy 339.985153 -217.092118) (xy 339.984588 -217.064336) (xy 339.985096 -217.038429) (xy 339.993202 -216.987252)
			(xy 340.009214 -216.937973) (xy 340.032737 -216.891806) (xy 340.063193 -216.849887) (xy 340.099831 -216.813249)
			(xy 340.14175 -216.782793) (xy 340.187917 -216.75927) (xy 340.237196 -216.743258) (xy 340.288373 -216.735152)
			(xy 340.340187 -216.735152) (xy 340.391364 -216.743258) (xy 340.440643 -216.75927) (xy 340.48681 -216.782793)
			(xy 340.528729 -216.813249) (xy 340.565367 -216.849887) (xy 340.595823 -216.891806) (xy 340.619346 -216.937973)
			(xy 340.635358 -216.987252) (xy 340.643464 -217.038429) (xy 340.643972 -217.064336) (xy 340.643512 -217.089686)
			(xy 340.635757 -217.139789) (xy 340.620421 -217.188114) (xy 340.597865 -217.233519) (xy 340.568622 -217.274935)
			(xy 340.533381 -217.311384) (xy 340.492973 -217.342006) (xy 340.448353 -217.366079) (xy 340.400573 -217.383035)
			(xy 340.375748 -217.388186) (xy 340.352888 -217.392504) (xy 340.14791 -217.747596) (xy 340.155784 -217.76944)
			(xy 340.164358 -217.79586) (xy 340.173542 -217.850635) (xy 340.174072 -217.878406) (xy 340.174072 -217.880184)
			(xy 340.174072 -217.931238) (xy 340.454996 -217.931238) (xy 340.454996 -217.880184) (xy 340.454996 -217.878406)
			(xy 340.455504 -217.852519) (xy 340.463603 -217.801381) (xy 340.479602 -217.752141) (xy 340.503108 -217.706009)
			(xy 340.53354 -217.664122) (xy 340.57015 -217.627512) (xy 340.612037 -217.59708) (xy 340.658169 -217.573574)
			(xy 340.707409 -217.557575) (xy 340.758547 -217.549476) (xy 340.810321 -217.549476) (xy 340.861459 -217.557575)
			(xy 340.910699 -217.573574) (xy 340.956831 -217.59708) (xy 340.998718 -217.627512) (xy 341.035328 -217.664122)
			(xy 341.06576 -217.706009) (xy 341.089266 -217.752141) (xy 341.105265 -217.801381) (xy 341.113364 -217.852519)
			(xy 341.113872 -217.878406) (xy 341.113872 -217.880184) (xy 341.113872 -217.931238) (xy 341.394796 -217.931238)
			(xy 341.394796 -217.880184) (xy 341.394796 -217.878406) (xy 341.395259 -217.85307) (xy 341.403011 -217.802993)
			(xy 341.418334 -217.754693) (xy 341.440866 -217.709305) (xy 341.470077 -217.6679) (xy 341.50528 -217.631451)
			(xy 341.545644 -217.600818) (xy 341.590221 -217.576721) (xy 341.637959 -217.559728) (xy 341.662766 -217.554556)
			(xy 341.685626 -217.550238) (xy 341.890604 -217.195146) (xy 341.88273 -217.173302) (xy 341.874081 -217.146894)
			(xy 341.864753 -217.092118) (xy 341.864188 -217.064336) (xy 341.864696 -217.038429) (xy 341.872802 -216.987252)
			(xy 341.888814 -216.937973) (xy 341.912337 -216.891806) (xy 341.942793 -216.849887) (xy 341.979431 -216.813249)
			(xy 342.02135 -216.782793) (xy 342.067517 -216.75927) (xy 342.116796 -216.743258) (xy 342.167973 -216.735152)
			(xy 342.219787 -216.735152) (xy 342.270964 -216.743258) (xy 342.320243 -216.75927) (xy 342.36641 -216.782793)
			(xy 342.408329 -216.813249) (xy 342.444967 -216.849887) (xy 342.475423 -216.891806) (xy 342.498946 -216.937973)
			(xy 342.514958 -216.987252) (xy 342.523064 -217.038429) (xy 342.523572 -217.064336) (xy 342.523112 -217.089686)
			(xy 342.515357 -217.139789) (xy 342.500021 -217.188114) (xy 342.477465 -217.233519) (xy 342.448222 -217.274935)
			(xy 342.412981 -217.311384) (xy 342.372573 -217.342006) (xy 342.327953 -217.366079) (xy 342.280173 -217.383035)
			(xy 342.255348 -217.388186) (xy 342.232488 -217.392504) (xy 342.02751 -217.747596) (xy 342.035384 -217.76944)
			(xy 342.043958 -217.79586) (xy 342.053142 -217.850635) (xy 342.053672 -217.878406) (xy 342.053672 -217.880184)
			(xy 342.053672 -217.931238) (xy 342.334596 -217.931238) (xy 342.334596 -217.880184) (xy 342.334596 -217.878406)
			(xy 342.335104 -217.852519) (xy 342.343203 -217.801381) (xy 342.359202 -217.752141) (xy 342.382708 -217.706009)
			(xy 342.41314 -217.664122) (xy 342.44975 -217.627512) (xy 342.491637 -217.59708) (xy 342.537769 -217.573574)
			(xy 342.587009 -217.557575) (xy 342.638147 -217.549476) (xy 342.689921 -217.549476) (xy 342.741059 -217.557575)
			(xy 342.790299 -217.573574) (xy 342.836431 -217.59708) (xy 342.878318 -217.627512) (xy 342.914928 -217.664122)
			(xy 342.94536 -217.706009) (xy 342.968866 -217.752141) (xy 342.984865 -217.801381) (xy 342.992964 -217.852519)
			(xy 342.993472 -217.878406) (xy 343.274396 -217.878406) (xy 343.274888 -217.853072) (xy 343.282639 -217.803)
			(xy 343.29796 -217.754704) (xy 343.320491 -217.70932) (xy 343.349699 -217.667918) (xy 343.384899 -217.631473)
			(xy 343.42526 -217.600842) (xy 343.469833 -217.576747) (xy 343.517567 -217.559756) (xy 343.542366 -217.554556)
			(xy 343.565226 -217.550238) (xy 343.770204 -217.195146) (xy 343.76233 -217.173302) (xy 343.753691 -217.146892)
			(xy 343.744367 -217.092117) (xy 343.743788 -217.064336) (xy 343.744296 -217.038429) (xy 343.752402 -216.987252)
			(xy 343.768414 -216.937973) (xy 343.791937 -216.891806) (xy 343.822393 -216.849887) (xy 343.859031 -216.813249)
			(xy 343.90095 -216.782793) (xy 343.947117 -216.75927) (xy 343.996396 -216.743258) (xy 344.047573 -216.735152)
			(xy 344.099387 -216.735152) (xy 344.150564 -216.743258) (xy 344.199843 -216.75927) (xy 344.24601 -216.782793)
			(xy 344.287929 -216.813249) (xy 344.324567 -216.849887) (xy 344.355023 -216.891806) (xy 344.378546 -216.937973)
			(xy 344.394558 -216.987252) (xy 344.402664 -217.038429) (xy 344.403172 -217.064336) (xy 344.402706 -217.089682)
			(xy 344.394928 -217.139773) (xy 344.379577 -217.188085) (xy 344.357013 -217.233478) (xy 344.327769 -217.274884)
			(xy 344.292534 -217.311328) (xy 344.252136 -217.34195) (xy 344.207529 -217.36603) (xy 344.159762 -217.383)
			(xy 344.134948 -217.388186) (xy 344.112088 -217.392504) (xy 343.90711 -217.747596) (xy 343.914984 -217.76944)
			(xy 343.923573 -217.795856) (xy 343.932763 -217.850633) (xy 343.933272 -217.878406) (xy 344.214196 -217.878406)
			(xy 344.214704 -217.852519) (xy 344.222803 -217.801381) (xy 344.238802 -217.752141) (xy 344.262308 -217.706009)
			(xy 344.29274 -217.664122) (xy 344.32935 -217.627512) (xy 344.371237 -217.59708) (xy 344.417369 -217.573574)
			(xy 344.466609 -217.557575) (xy 344.517747 -217.549476) (xy 344.569521 -217.549476) (xy 344.620659 -217.557575)
			(xy 344.669899 -217.573574) (xy 344.716031 -217.59708) (xy 344.757918 -217.627512) (xy 344.794528 -217.664122)
			(xy 344.82496 -217.706009) (xy 344.848466 -217.752141) (xy 344.864465 -217.801381) (xy 344.872564 -217.852519)
			(xy 344.873072 -217.878406) (xy 345.153996 -217.878406) (xy 345.154488 -217.853072) (xy 345.162239 -217.803)
			(xy 345.17756 -217.754704) (xy 345.200091 -217.70932) (xy 345.229299 -217.667918) (xy 345.264499 -217.631473)
			(xy 345.30486 -217.600842) (xy 345.349433 -217.576747) (xy 345.397167 -217.559756) (xy 345.421966 -217.554556)
			(xy 345.444826 -217.550238) (xy 345.649804 -217.195146) (xy 345.64193 -217.173302) (xy 345.633291 -217.146892)
			(xy 345.623967 -217.092117) (xy 345.623388 -217.064336) (xy 345.623896 -217.038429) (xy 345.632002 -216.987252)
			(xy 345.648014 -216.937973) (xy 345.671537 -216.891806) (xy 345.701993 -216.849887) (xy 345.738631 -216.813249)
			(xy 345.78055 -216.782793) (xy 345.826717 -216.75927) (xy 345.875996 -216.743258) (xy 345.927173 -216.735152)
			(xy 345.978987 -216.735152) (xy 346.030164 -216.743258) (xy 346.079443 -216.75927) (xy 346.12561 -216.782793)
			(xy 346.167529 -216.813249) (xy 346.204167 -216.849887) (xy 346.234623 -216.891806) (xy 346.258146 -216.937973)
			(xy 346.274158 -216.987252) (xy 346.282264 -217.038429) (xy 346.282772 -217.064336) (xy 346.282306 -217.089682)
			(xy 346.274528 -217.139773) (xy 346.259177 -217.188085) (xy 346.236613 -217.233478) (xy 346.207369 -217.274884)
			(xy 346.172134 -217.311328) (xy 346.131736 -217.34195) (xy 346.087129 -217.36603) (xy 346.039362 -217.383)
			(xy 346.014548 -217.388186) (xy 345.991688 -217.392504) (xy 345.78671 -217.747596) (xy 345.794584 -217.76944)
			(xy 345.803173 -217.795856) (xy 345.812363 -217.850633) (xy 345.812872 -217.878406) (xy 346.093796 -217.878406)
			(xy 346.094304 -217.852519) (xy 346.102403 -217.801381) (xy 346.118402 -217.752141) (xy 346.141908 -217.706009)
			(xy 346.17234 -217.664122) (xy 346.20895 -217.627512) (xy 346.250837 -217.59708) (xy 346.296969 -217.573574)
			(xy 346.346209 -217.557575) (xy 346.397347 -217.549476) (xy 346.449121 -217.549476) (xy 346.500259 -217.557575)
			(xy 346.549499 -217.573574) (xy 346.595631 -217.59708) (xy 346.637518 -217.627512) (xy 346.674128 -217.664122)
			(xy 346.70456 -217.706009) (xy 346.728066 -217.752141) (xy 346.744065 -217.801381) (xy 346.752164 -217.852519)
			(xy 346.752672 -217.878406) (xy 347.033596 -217.878406) (xy 347.034088 -217.853072) (xy 347.041839 -217.803)
			(xy 347.05716 -217.754704) (xy 347.079691 -217.70932) (xy 347.108899 -217.667918) (xy 347.144099 -217.631473)
			(xy 347.18446 -217.600842) (xy 347.229033 -217.576747) (xy 347.276767 -217.559756) (xy 347.301566 -217.554556)
			(xy 347.324426 -217.550238) (xy 347.529404 -217.195146) (xy 347.52153 -217.173302) (xy 347.512891 -217.146892)
			(xy 347.503567 -217.092117) (xy 347.502988 -217.064336) (xy 347.503496 -217.038429) (xy 347.511602 -216.987252)
			(xy 347.527614 -216.937973) (xy 347.551137 -216.891806) (xy 347.581593 -216.849887) (xy 347.618231 -216.813249)
			(xy 347.66015 -216.782793) (xy 347.706317 -216.75927) (xy 347.755596 -216.743258) (xy 347.806773 -216.735152)
			(xy 347.858587 -216.735152) (xy 347.909764 -216.743258) (xy 347.959043 -216.75927) (xy 348.00521 -216.782793)
			(xy 348.047129 -216.813249) (xy 348.083767 -216.849887) (xy 348.114223 -216.891806) (xy 348.137746 -216.937973)
			(xy 348.153758 -216.987252) (xy 348.161864 -217.038429) (xy 348.162372 -217.064336) (xy 348.161906 -217.089682)
			(xy 348.154128 -217.139773) (xy 348.138777 -217.188085) (xy 348.116213 -217.233478) (xy 348.086969 -217.274884)
			(xy 348.051734 -217.311328) (xy 348.011336 -217.34195) (xy 347.966729 -217.36603) (xy 347.918962 -217.383)
			(xy 347.894148 -217.388186) (xy 347.871288 -217.392504) (xy 347.66631 -217.747596) (xy 347.674184 -217.76944)
			(xy 347.682773 -217.795856) (xy 347.691963 -217.850633) (xy 347.692472 -217.878406) (xy 347.691964 -217.904293)
			(xy 347.683865 -217.955431) (xy 347.667866 -218.004671) (xy 347.64436 -218.050803) (xy 347.613928 -218.09269)
			(xy 347.577318 -218.1293) (xy 347.535431 -218.159732) (xy 347.489299 -218.183238) (xy 347.440059 -218.199237)
			(xy 347.388921 -218.207336) (xy 347.337147 -218.207336) (xy 347.286009 -218.199237) (xy 347.236769 -218.183238)
			(xy 347.190637 -218.159732) (xy 347.14875 -218.1293) (xy 347.11214 -218.09269) (xy 347.081708 -218.050803)
			(xy 347.058202 -218.004671) (xy 347.042203 -217.955431) (xy 347.034104 -217.904293) (xy 347.033596 -217.878406)
			(xy 346.752672 -217.878406) (xy 346.752141 -217.906114) (xy 346.742946 -217.960761) (xy 346.734384 -217.987118)
			(xy 346.72651 -218.009216) (xy 346.931488 -218.364054) (xy 346.954348 -218.368372) (xy 346.979163 -218.373563)
			(xy 347.026941 -218.390515) (xy 347.071559 -218.414584) (xy 347.111965 -218.445202) (xy 347.147206 -218.481645)
			(xy 347.17645 -218.523056) (xy 347.199009 -218.568456) (xy 347.214349 -218.616776) (xy 347.222108 -218.666874)
			(xy 347.222572 -218.692222) (xy 347.222064 -218.718129) (xy 347.213958 -218.769306) (xy 347.197946 -218.818585)
			(xy 347.174423 -218.864752) (xy 347.143967 -218.906671) (xy 347.107329 -218.943309) (xy 347.06541 -218.973765)
			(xy 347.019243 -218.997288) (xy 346.969964 -219.0133) (xy 346.918787 -219.021406) (xy 346.866973 -219.021406)
			(xy 346.815796 -219.0133) (xy 346.766517 -218.997288) (xy 346.72035 -218.973765) (xy 346.678431 -218.943309)
			(xy 346.641793 -218.906671) (xy 346.611337 -218.864752) (xy 346.587814 -218.818585) (xy 346.571802 -218.769306)
			(xy 346.563696 -218.718129) (xy 346.563188 -218.692222) (xy 346.563788 -218.664505) (xy 346.573107 -218.609859)
			(xy 346.58173 -218.58351) (xy 346.589604 -218.561412) (xy 346.384626 -218.206574) (xy 346.361766 -218.202256)
			(xy 346.336962 -218.197073) (xy 346.289224 -218.180081) (xy 346.244649 -218.155985) (xy 346.204284 -218.125353)
			(xy 346.169082 -218.088906) (xy 346.13987 -218.047502) (xy 346.117337 -218.002116) (xy 346.102013 -217.953817)
			(xy 346.09426 -217.903742) (xy 346.093796 -217.878406) (xy 345.812872 -217.878406) (xy 345.812364 -217.904293)
			(xy 345.804265 -217.955431) (xy 345.788266 -218.004671) (xy 345.76476 -218.050803) (xy 345.734328 -218.09269)
			(xy 345.697718 -218.1293) (xy 345.655831 -218.159732) (xy 345.609699 -218.183238) (xy 345.560459 -218.199237)
			(xy 345.509321 -218.207336) (xy 345.457547 -218.207336) (xy 345.406409 -218.199237) (xy 345.357169 -218.183238)
			(xy 345.311037 -218.159732) (xy 345.26915 -218.1293) (xy 345.23254 -218.09269) (xy 345.202108 -218.050803)
			(xy 345.178602 -218.004671) (xy 345.162603 -217.955431) (xy 345.154504 -217.904293) (xy 345.153996 -217.878406)
			(xy 344.873072 -217.878406) (xy 344.872541 -217.906114) (xy 344.863346 -217.960761) (xy 344.854784 -217.987118)
			(xy 344.84691 -218.009216) (xy 345.051888 -218.364054) (xy 345.074748 -218.368372) (xy 345.099563 -218.373563)
			(xy 345.147341 -218.390515) (xy 345.191959 -218.414584) (xy 345.232365 -218.445202) (xy 345.267606 -218.481645)
			(xy 345.29685 -218.523056) (xy 345.319409 -218.568456) (xy 345.334749 -218.616776) (xy 345.342508 -218.666874)
			(xy 345.342972 -218.692222) (xy 345.342464 -218.718129) (xy 345.334358 -218.769306) (xy 345.318346 -218.818585)
			(xy 345.294823 -218.864752) (xy 345.264367 -218.906671) (xy 345.227729 -218.943309) (xy 345.18581 -218.973765)
			(xy 345.139643 -218.997288) (xy 345.090364 -219.0133) (xy 345.039187 -219.021406) (xy 344.987373 -219.021406)
			(xy 344.936196 -219.0133) (xy 344.886917 -218.997288) (xy 344.84075 -218.973765) (xy 344.798831 -218.943309)
			(xy 344.762193 -218.906671) (xy 344.731737 -218.864752) (xy 344.708214 -218.818585) (xy 344.692202 -218.769306)
			(xy 344.684096 -218.718129) (xy 344.683588 -218.692222) (xy 344.684188 -218.664505) (xy 344.693507 -218.609859)
			(xy 344.70213 -218.58351) (xy 344.710004 -218.561412) (xy 344.505026 -218.206574) (xy 344.482166 -218.202256)
			(xy 344.457362 -218.197073) (xy 344.409624 -218.180081) (xy 344.365049 -218.155985) (xy 344.324684 -218.125353)
			(xy 344.289482 -218.088906) (xy 344.26027 -218.047502) (xy 344.237737 -218.002116) (xy 344.222413 -217.953817)
			(xy 344.21466 -217.903742) (xy 344.214196 -217.878406) (xy 343.933272 -217.878406) (xy 343.932764 -217.904293)
			(xy 343.924665 -217.955431) (xy 343.908666 -218.004671) (xy 343.88516 -218.050803) (xy 343.854728 -218.09269)
			(xy 343.818118 -218.1293) (xy 343.776231 -218.159732) (xy 343.730099 -218.183238) (xy 343.680859 -218.199237)
			(xy 343.629721 -218.207336) (xy 343.577947 -218.207336) (xy 343.526809 -218.199237) (xy 343.477569 -218.183238)
			(xy 343.431437 -218.159732) (xy 343.38955 -218.1293) (xy 343.35294 -218.09269) (xy 343.322508 -218.050803)
			(xy 343.299002 -218.004671) (xy 343.283003 -217.955431) (xy 343.274904 -217.904293) (xy 343.274396 -217.878406)
			(xy 342.993472 -217.878406) (xy 342.992942 -217.906114) (xy 342.983742 -217.960759) (xy 342.975184 -217.987118)
			(xy 342.96731 -218.009216) (xy 343.172288 -218.364054) (xy 343.195148 -218.368372) (xy 343.21996 -218.373559)
			(xy 343.267723 -218.39053) (xy 343.312326 -218.414611) (xy 343.352718 -218.445234) (xy 343.387948 -218.481679)
			(xy 343.417185 -218.523085) (xy 343.439741 -218.568478) (xy 343.455084 -218.616789) (xy 343.462853 -218.666878)
			(xy 343.463372 -218.692222) (xy 343.46261 -218.712288) (xy 343.46134 -218.735148) (xy 344.796364 -220.070172)
			(xy 344.831162 -220.047058) (xy 344.851501 -220.033962) (xy 344.895215 -220.013251) (xy 344.941499 -219.99919)
			(xy 344.989348 -219.992085) (xy 345.013534 -219.991686) (xy 345.039321 -219.992194) (xy 345.09026 -220.000266)
			(xy 345.139309 -220.016206) (xy 345.185262 -220.039622) (xy 345.226986 -220.069937) (xy 345.263455 -220.106405)
			(xy 345.293772 -220.148128) (xy 345.317189 -220.19408) (xy 345.333131 -220.243128) (xy 345.341205 -220.294067)
			(xy 345.341702 -220.319854) (xy 345.341168 -220.347112) (xy 345.332173 -220.400882) (xy 345.314422 -220.452427)
			(xy 345.288403 -220.500334) (xy 345.25483 -220.543286) (xy 345.214625 -220.580104) (xy 345.168892 -220.609778)
			(xy 345.14409 -220.621098) (xy 345.113356 -220.634306) (xy 345.113356 -220.796612) (xy 345.113837 -220.810874)
			(xy 345.121733 -220.838283) (xy 345.136906 -220.862436) (xy 345.15817 -220.881448) (xy 345.183864 -220.893833)
			(xy 345.211983 -220.898624) (xy 345.240329 -220.895448) (xy 345.266689 -220.884551) (xy 345.278202 -220.876114)
			(xy 345.299356 -220.859905) (xy 345.345826 -220.833822) (xy 345.395886 -220.815553) (xy 345.421966 -220.810074)
			(xy 345.444826 -220.805756) (xy 345.649804 -220.450664) (xy 345.64193 -220.42882) (xy 345.633287 -220.402411)
			(xy 345.623973 -220.347635) (xy 345.623388 -220.319854) (xy 345.623896 -220.293947) (xy 345.632002 -220.24277)
			(xy 345.648014 -220.193491) (xy 345.671537 -220.147324) (xy 345.701993 -220.105405) (xy 345.738631 -220.068767)
			(xy 345.78055 -220.038311) (xy 345.826717 -220.014788) (xy 345.875996 -219.998776) (xy 345.927173 -219.99067)
			(xy 345.978987 -219.99067) (xy 346.030164 -219.998776) (xy 346.079443 -220.014788) (xy 346.12561 -220.038311)
			(xy 346.167529 -220.068767) (xy 346.204167 -220.105405) (xy 346.234623 -220.147324) (xy 346.258146 -220.193491)
			(xy 346.274158 -220.24277) (xy 346.282264 -220.293947) (xy 346.282772 -220.319854) (xy 346.28231 -220.345203)
			(xy 346.274553 -220.395304) (xy 346.259216 -220.443627) (xy 346.236659 -220.48903) (xy 346.207415 -220.530444)
			(xy 346.172174 -220.56689) (xy 346.131767 -220.59751) (xy 346.087148 -220.621582) (xy 346.039369 -220.638536)
			(xy 346.014548 -220.643704) (xy 345.991688 -220.648022) (xy 345.78671 -221.003114) (xy 345.794584 -221.024958)
			(xy 345.803164 -221.051377) (xy 345.812362 -221.106152) (xy 345.812872 -221.133924) (xy 346.093796 -221.133924)
			(xy 346.094304 -221.108037) (xy 346.102403 -221.056899) (xy 346.118402 -221.007659) (xy 346.141908 -220.961527)
			(xy 346.17234 -220.91964) (xy 346.20895 -220.88303) (xy 346.250837 -220.852598) (xy 346.296969 -220.829092)
			(xy 346.346209 -220.813093) (xy 346.397347 -220.804994) (xy 346.449121 -220.804994) (xy 346.500259 -220.813093)
			(xy 346.549499 -220.829092) (xy 346.595631 -220.852598) (xy 346.637518 -220.88303) (xy 346.674128 -220.91964)
			(xy 346.70456 -220.961527) (xy 346.728066 -221.007659) (xy 346.744065 -221.056899) (xy 346.752164 -221.108037)
			(xy 346.752672 -221.133924) (xy 347.033596 -221.133924) (xy 347.034104 -221.10859) (xy 347.041853 -221.058519)
			(xy 347.057172 -221.010223) (xy 347.0797 -220.96484) (xy 347.108906 -220.923438) (xy 347.144104 -220.886992)
			(xy 347.184463 -220.856361) (xy 347.229034 -220.832266) (xy 347.276767 -220.815274) (xy 347.301566 -220.810074)
			(xy 347.324426 -220.805756) (xy 347.529404 -220.450664) (xy 347.52153 -220.42882) (xy 347.512896 -220.402408)
			(xy 347.503568 -220.347635) (xy 347.502988 -220.319854) (xy 347.503496 -220.293947) (xy 347.511602 -220.24277)
			(xy 347.527614 -220.193491) (xy 347.551137 -220.147324) (xy 347.581593 -220.105405) (xy 347.618231 -220.068767)
			(xy 347.66015 -220.038311) (xy 347.706317 -220.014788) (xy 347.755596 -219.998776) (xy 347.806773 -219.99067)
			(xy 347.858587 -219.99067) (xy 347.909764 -219.998776) (xy 347.959043 -220.014788) (xy 348.00521 -220.038311)
			(xy 348.047129 -220.068767) (xy 348.083767 -220.105405) (xy 348.114223 -220.147324) (xy 348.137746 -220.193491)
			(xy 348.153758 -220.24277) (xy 348.161864 -220.293947) (xy 348.162372 -220.319854) (xy 348.161922 -220.3452)
			(xy 348.154142 -220.395293) (xy 348.138788 -220.443604) (xy 348.116222 -220.488998) (xy 348.086976 -220.530404)
			(xy 348.051739 -220.566847) (xy 348.01134 -220.597469) (xy 347.966731 -220.621548) (xy 347.918963 -220.638518)
			(xy 347.894148 -220.643704) (xy 347.871288 -220.648022) (xy 347.66631 -221.003114) (xy 347.674184 -221.024958)
			(xy 347.682777 -221.051373) (xy 347.691965 -221.106151) (xy 347.692472 -221.133924) (xy 347.973396 -221.133924)
			(xy 347.973904 -221.108037) (xy 347.982003 -221.056899) (xy 347.998002 -221.007659) (xy 348.021508 -220.961527)
			(xy 348.05194 -220.91964) (xy 348.08855 -220.88303) (xy 348.130437 -220.852598) (xy 348.176569 -220.829092)
			(xy 348.225809 -220.813093) (xy 348.276947 -220.804994) (xy 348.328721 -220.804994) (xy 348.379859 -220.813093)
			(xy 348.429099 -220.829092) (xy 348.475231 -220.852598) (xy 348.517118 -220.88303) (xy 348.553728 -220.91964)
			(xy 348.58416 -220.961527) (xy 348.607666 -221.007659) (xy 348.623665 -221.056899) (xy 348.631764 -221.108037)
			(xy 348.632272 -221.133924) (xy 348.631745 -221.161632) (xy 348.622548 -221.216279) (xy 348.613984 -221.242636)
			(xy 348.60611 -221.264734) (xy 348.811088 -221.619572) (xy 348.833948 -221.62389) (xy 348.858767 -221.629064)
			(xy 348.906546 -221.646018) (xy 348.951165 -221.670088) (xy 348.991572 -221.700708) (xy 349.026813 -221.737154)
			(xy 349.056057 -221.778566) (xy 349.078614 -221.823969) (xy 349.093952 -221.872291) (xy 349.10171 -221.922391)
			(xy 349.102172 -221.94774) (xy 349.101664 -221.973647) (xy 349.093558 -222.024824) (xy 349.077546 -222.074103)
			(xy 349.054023 -222.12027) (xy 349.023567 -222.162189) (xy 348.986929 -222.198827) (xy 348.94501 -222.229283)
			(xy 348.898843 -222.252806) (xy 348.849564 -222.268818) (xy 348.798387 -222.276924) (xy 348.746573 -222.276924)
			(xy 348.695396 -222.268818) (xy 348.646117 -222.252806) (xy 348.59995 -222.229283) (xy 348.558031 -222.198827)
			(xy 348.521393 -222.162189) (xy 348.490937 -222.12027) (xy 348.467414 -222.074103) (xy 348.451402 -222.024824)
			(xy 348.443296 -221.973647) (xy 348.442788 -221.94774) (xy 348.443392 -221.920023) (xy 348.452709 -221.865377)
			(xy 348.46133 -221.839028) (xy 348.469204 -221.81693) (xy 348.264226 -221.462092) (xy 348.241366 -221.457774)
			(xy 348.216566 -221.452574) (xy 348.16883 -221.435583) (xy 348.124255 -221.411489) (xy 348.083891 -221.380859)
			(xy 348.048689 -221.344414) (xy 348.019476 -221.303012) (xy 347.996942 -221.257629) (xy 347.981617 -221.209332)
			(xy 347.973861 -221.159259) (xy 347.973396 -221.133924) (xy 347.692472 -221.133924) (xy 347.691964 -221.159811)
			(xy 347.683865 -221.210949) (xy 347.667866 -221.260189) (xy 347.64436 -221.306321) (xy 347.613928 -221.348208)
			(xy 347.577318 -221.384818) (xy 347.535431 -221.41525) (xy 347.489299 -221.438756) (xy 347.440059 -221.454755)
			(xy 347.388921 -221.462854) (xy 347.337147 -221.462854) (xy 347.286009 -221.454755) (xy 347.236769 -221.438756)
			(xy 347.190637 -221.41525) (xy 347.14875 -221.384818) (xy 347.11214 -221.348208) (xy 347.081708 -221.306321)
			(xy 347.058202 -221.260189) (xy 347.042203 -221.210949) (xy 347.034104 -221.159811) (xy 347.033596 -221.133924)
			(xy 346.752672 -221.133924) (xy 346.752145 -221.161632) (xy 346.742948 -221.216279) (xy 346.734384 -221.242636)
			(xy 346.72651 -221.264734) (xy 346.931488 -221.619572) (xy 346.954348 -221.62389) (xy 346.979167 -221.629064)
			(xy 347.026946 -221.646018) (xy 347.071565 -221.670088) (xy 347.111972 -221.700708) (xy 347.147213 -221.737154)
			(xy 347.176457 -221.778566) (xy 347.199014 -221.823969) (xy 347.214352 -221.872291) (xy 347.22211 -221.922391)
			(xy 347.222572 -221.94774) (xy 347.222064 -221.973647) (xy 347.213958 -222.024824) (xy 347.197946 -222.074103)
			(xy 347.174423 -222.12027) (xy 347.143967 -222.162189) (xy 347.107329 -222.198827) (xy 347.06541 -222.229283)
			(xy 347.019243 -222.252806) (xy 346.969964 -222.268818) (xy 346.918787 -222.276924) (xy 346.866973 -222.276924)
			(xy 346.815796 -222.268818) (xy 346.766517 -222.252806) (xy 346.72035 -222.229283) (xy 346.678431 -222.198827)
			(xy 346.641793 -222.162189) (xy 346.611337 -222.12027) (xy 346.587814 -222.074103) (xy 346.571802 -222.024824)
			(xy 346.563696 -221.973647) (xy 346.563188 -221.94774) (xy 346.563792 -221.920023) (xy 346.573109 -221.865377)
			(xy 346.58173 -221.839028) (xy 346.589604 -221.81693) (xy 346.384626 -221.462092) (xy 346.361766 -221.457774)
			(xy 346.336966 -221.452574) (xy 346.28923 -221.435583) (xy 346.244655 -221.411489) (xy 346.204291 -221.380859)
			(xy 346.169089 -221.344414) (xy 346.139876 -221.303012) (xy 346.117342 -221.257629) (xy 346.102017 -221.209332)
			(xy 346.094261 -221.159259) (xy 346.093796 -221.133924) (xy 345.812872 -221.133924) (xy 345.812363 -221.159817)
			(xy 345.804262 -221.210965) (xy 345.788263 -221.260218) (xy 345.764761 -221.306363) (xy 345.734332 -221.348266)
			(xy 345.697725 -221.384895) (xy 345.655842 -221.415351) (xy 345.609712 -221.438883) (xy 345.560469 -221.454913)
			(xy 345.509326 -221.463046) (xy 345.483434 -221.463616) (xy 345.455717 -221.463024) (xy 345.40107 -221.453707)
			(xy 345.348753 -221.435379) (xy 345.300238 -221.408557) (xy 345.278202 -221.391734) (xy 345.266743 -221.383232)
			(xy 345.24038 -221.372349) (xy 345.212035 -221.369186) (xy 345.183921 -221.37399) (xy 345.158235 -221.386387)
			(xy 345.136982 -221.405407) (xy 345.121822 -221.429565) (xy 345.113939 -221.456975) (xy 345.113356 -221.471236)
			(xy 345.113356 -221.632018) (xy 345.14409 -221.645226) (xy 345.167369 -221.655802) (xy 345.210615 -221.683076)
			(xy 345.249129 -221.716704) (xy 345.281985 -221.755877) (xy 345.308395 -221.799656) (xy 345.327726 -221.84699)
			(xy 345.339511 -221.896741) (xy 345.34347 -221.947716) (xy 345.339506 -221.99869) (xy 345.327716 -222.048441)
			(xy 345.308381 -222.095772) (xy 345.281967 -222.139549) (xy 345.249106 -222.178719) (xy 345.21059 -222.212343)
			(xy 345.167341 -222.239613) (xy 345.14409 -222.250254) (xy 345.113356 -222.263462) (xy 345.113356 -223.261174)
			(xy 345.14409 -223.274382) (xy 345.167231 -223.28495) (xy 345.21021 -223.312164) (xy 345.248478 -223.34568)
			(xy 345.28112 -223.384696) (xy 345.307355 -223.42828) (xy 345.326556 -223.475387) (xy 345.338262 -223.524892)
			(xy 345.342195 -223.57561) (xy 345.338259 -223.626328) (xy 345.32655 -223.675832) (xy 345.307346 -223.722939)
			(xy 345.281108 -223.766521) (xy 345.248464 -223.805535) (xy 345.210193 -223.839048) (xy 345.167212 -223.866259)
			(xy 345.14409 -223.87687) (xy 345.113356 -223.890078) (xy 345.113356 -224.05213) (xy 345.113839 -224.06639)
			(xy 345.121738 -224.093794) (xy 345.136912 -224.117943) (xy 345.158174 -224.136951) (xy 345.183866 -224.149334)
			(xy 345.211981 -224.154124) (xy 345.240323 -224.150949) (xy 345.266681 -224.140056) (xy 345.278202 -224.131632)
			(xy 345.299355 -224.115422) (xy 345.345825 -224.089338) (xy 345.395885 -224.071068) (xy 345.421966 -224.065592)
			(xy 345.444826 -224.061274) (xy 345.64955 -223.706436) (xy 345.64193 -223.684338) (xy 345.633304 -223.65799)
			(xy 345.623976 -223.603344) (xy 345.623388 -223.575626) (xy 345.623896 -223.549719) (xy 345.632002 -223.498542)
			(xy 345.648014 -223.449263) (xy 345.671537 -223.403096) (xy 345.701993 -223.361177) (xy 345.738631 -223.324539)
			(xy 345.78055 -223.294083) (xy 345.826717 -223.27056) (xy 345.875996 -223.254548) (xy 345.927173 -223.246442)
			(xy 345.978987 -223.246442) (xy 346.030164 -223.254548) (xy 346.079443 -223.27056) (xy 346.12561 -223.294083)
			(xy 346.167529 -223.324539) (xy 346.204167 -223.361177) (xy 346.234623 -223.403096) (xy 346.258146 -223.449263)
			(xy 346.274158 -223.498542) (xy 346.282264 -223.549719) (xy 346.282772 -223.575626) (xy 346.282297 -223.600983)
			(xy 346.274511 -223.651097) (xy 346.259143 -223.699427) (xy 346.236554 -223.744833) (xy 346.207278 -223.786244)
			(xy 346.172006 -223.822684) (xy 346.131569 -223.853292) (xy 346.086922 -223.877347) (xy 346.039118 -223.89428)
			(xy 346.014294 -223.899476) (xy 345.991434 -223.903794) (xy 345.78671 -224.258632) (xy 345.794584 -224.280476)
			(xy 345.803163 -224.306895) (xy 345.812358 -224.36167) (xy 345.812872 -224.389442) (xy 346.093796 -224.389442)
			(xy 346.094304 -224.363555) (xy 346.102403 -224.312417) (xy 346.118402 -224.263177) (xy 346.141908 -224.217045)
			(xy 346.17234 -224.175158) (xy 346.20895 -224.138548) (xy 346.250837 -224.108116) (xy 346.296969 -224.08461)
			(xy 346.346209 -224.068611) (xy 346.397347 -224.060512) (xy 346.449121 -224.060512) (xy 346.500259 -224.068611)
			(xy 346.549499 -224.08461) (xy 346.595631 -224.108116) (xy 346.637518 -224.138548) (xy 346.674128 -224.175158)
			(xy 346.70456 -224.217045) (xy 346.728066 -224.263177) (xy 346.744065 -224.312417) (xy 346.752164 -224.363555)
			(xy 346.752672 -224.389442) (xy 347.033596 -224.389442) (xy 347.034029 -224.364106) (xy 347.04179 -224.314032)
			(xy 347.05712 -224.265734) (xy 347.079659 -224.22035) (xy 347.108875 -224.178949) (xy 347.144081 -224.142504)
			(xy 347.184448 -224.111874) (xy 347.229026 -224.087781) (xy 347.276765 -224.070791) (xy 347.301566 -224.065592)
			(xy 347.324426 -224.061274) (xy 347.52915 -223.706436) (xy 347.52153 -223.684338) (xy 347.512902 -223.657991)
			(xy 347.503579 -223.603344) (xy 347.502988 -223.575626) (xy 347.503496 -223.549719) (xy 347.511602 -223.498542)
			(xy 347.527614 -223.449263) (xy 347.551137 -223.403096) (xy 347.581593 -223.361177) (xy 347.618231 -223.324539)
			(xy 347.66015 -223.294083) (xy 347.706317 -223.27056) (xy 347.755596 -223.254548) (xy 347.806773 -223.246442)
			(xy 347.858587 -223.246442) (xy 347.909764 -223.254548) (xy 347.959043 -223.27056) (xy 348.00521 -223.294083)
			(xy 348.047129 -223.324539) (xy 348.083767 -223.361177) (xy 348.114223 -223.403096) (xy 348.137746 -223.449263)
			(xy 348.153758 -223.498542) (xy 348.161864 -223.549719) (xy 348.162372 -223.575626) (xy 348.161981 -223.600993)
			(xy 348.154228 -223.651131) (xy 348.138877 -223.699486) (xy 348.116292 -223.744915) (xy 348.087007 -223.786344)
			(xy 348.051716 -223.822791) (xy 348.011252 -223.853396) (xy 347.966574 -223.877433) (xy 347.918739 -223.894334)
			(xy 347.893894 -223.899476) (xy 347.871034 -223.903794) (xy 347.66631 -224.258632) (xy 347.674184 -224.280476)
			(xy 347.682757 -224.306897) (xy 347.691958 -224.36167) (xy 347.692472 -224.389442) (xy 347.973396 -224.389442)
			(xy 347.973904 -224.363555) (xy 347.982003 -224.312417) (xy 347.998002 -224.263177) (xy 348.021508 -224.217045)
			(xy 348.05194 -224.175158) (xy 348.08855 -224.138548) (xy 348.130437 -224.108116) (xy 348.176569 -224.08461)
			(xy 348.225809 -224.068611) (xy 348.276947 -224.060512) (xy 348.328721 -224.060512) (xy 348.379859 -224.068611)
			(xy 348.429099 -224.08461) (xy 348.475231 -224.108116) (xy 348.517118 -224.138548) (xy 348.553728 -224.175158)
			(xy 348.58416 -224.217045) (xy 348.607666 -224.263177) (xy 348.623665 -224.312417) (xy 348.631764 -224.363555)
			(xy 348.632272 -224.389442) (xy 348.913196 -224.389442) (xy 348.913629 -224.364106) (xy 348.92139 -224.314032)
			(xy 348.93672 -224.265734) (xy 348.959259 -224.22035) (xy 348.988475 -224.178949) (xy 349.023681 -224.142504)
			(xy 349.064048 -224.111874) (xy 349.108626 -224.087781) (xy 349.156365 -224.070791) (xy 349.181166 -224.065592)
			(xy 349.204026 -224.061274) (xy 349.40875 -223.706436) (xy 349.40113 -223.684338) (xy 349.392502 -223.657991)
			(xy 349.383179 -223.603344) (xy 349.382588 -223.575626) (xy 349.383096 -223.549719) (xy 349.391202 -223.498542)
			(xy 349.407214 -223.449263) (xy 349.430737 -223.403096) (xy 349.461193 -223.361177) (xy 349.497831 -223.324539)
			(xy 349.53975 -223.294083) (xy 349.585917 -223.27056) (xy 349.635196 -223.254548) (xy 349.686373 -223.246442)
			(xy 349.738187 -223.246442) (xy 349.789364 -223.254548) (xy 349.838643 -223.27056) (xy 349.88481 -223.294083)
			(xy 349.926729 -223.324539) (xy 349.963367 -223.361177) (xy 349.993823 -223.403096) (xy 350.017346 -223.449263)
			(xy 350.033358 -223.498542) (xy 350.041464 -223.549719) (xy 350.041972 -223.575626) (xy 350.041581 -223.600993)
			(xy 350.033828 -223.651131) (xy 350.018477 -223.699486) (xy 349.995892 -223.744915) (xy 349.966607 -223.786344)
			(xy 349.931316 -223.822791) (xy 349.890852 -223.853396) (xy 349.846174 -223.877433) (xy 349.798339 -223.894334)
			(xy 349.773494 -223.899476) (xy 349.750634 -223.903794) (xy 349.54591 -224.258632) (xy 349.553784 -224.280476)
			(xy 349.562357 -224.306897) (xy 349.571558 -224.36167) (xy 349.572072 -224.389442) (xy 349.852996 -224.389442)
			(xy 349.853504 -224.363555) (xy 349.861603 -224.312417) (xy 349.877602 -224.263177) (xy 349.901108 -224.217045)
			(xy 349.93154 -224.175158) (xy 349.96815 -224.138548) (xy 350.010037 -224.108116) (xy 350.056169 -224.08461)
			(xy 350.105409 -224.068611) (xy 350.156547 -224.060512) (xy 350.208321 -224.060512) (xy 350.259459 -224.068611)
			(xy 350.308699 -224.08461) (xy 350.354831 -224.108116) (xy 350.396718 -224.138548) (xy 350.433328 -224.175158)
			(xy 350.46376 -224.217045) (xy 350.487266 -224.263177) (xy 350.503265 -224.312417) (xy 350.511364 -224.363555)
			(xy 350.511872 -224.389442) (xy 350.511325 -224.417149) (xy 350.502141 -224.471796) (xy 350.493584 -224.498154)
			(xy 350.48571 -224.520252) (xy 350.690688 -224.87509) (xy 350.713548 -224.879408) (xy 350.738371 -224.884565)
			(xy 350.786151 -224.90152) (xy 350.830771 -224.925592) (xy 350.871178 -224.956214) (xy 350.906419 -224.992662)
			(xy 350.935663 -225.034077) (xy 350.958219 -225.079482) (xy 350.973556 -225.127806) (xy 350.981311 -225.177908)
			(xy 350.981772 -225.203258) (xy 350.981264 -225.229165) (xy 350.973158 -225.280342) (xy 350.957146 -225.329621)
			(xy 350.933623 -225.375788) (xy 350.903167 -225.417707) (xy 350.866529 -225.454345) (xy 350.82461 -225.484801)
			(xy 350.778443 -225.508324) (xy 350.729164 -225.524336) (xy 350.677987 -225.532442) (xy 350.626173 -225.532442)
			(xy 350.574996 -225.524336) (xy 350.525717 -225.508324) (xy 350.47955 -225.484801) (xy 350.437631 -225.454345)
			(xy 350.400993 -225.417707) (xy 350.370537 -225.375788) (xy 350.347014 -225.329621) (xy 350.331002 -225.280342)
			(xy 350.322896 -225.229165) (xy 350.322388 -225.203258) (xy 350.322997 -225.175541) (xy 350.33231 -225.120895)
			(xy 350.34093 -225.094546) (xy 350.348804 -225.072448) (xy 350.143826 -224.71761) (xy 350.120966 -224.713292)
			(xy 350.096148 -224.708169) (xy 350.048405 -224.691172) (xy 350.003826 -224.667071) (xy 349.96346 -224.636431)
			(xy 349.928257 -224.599976) (xy 349.899048 -224.558564) (xy 349.876519 -224.51317) (xy 349.861201 -224.464863)
			(xy 349.853455 -224.414781) (xy 349.852996 -224.389442) (xy 349.572072 -224.389442) (xy 349.571564 -224.415329)
			(xy 349.563465 -224.466467) (xy 349.547466 -224.515707) (xy 349.52396 -224.561839) (xy 349.493528 -224.603726)
			(xy 349.456918 -224.640336) (xy 349.415031 -224.670768) (xy 349.368899 -224.694274) (xy 349.319659 -224.710273)
			(xy 349.268521 -224.718372) (xy 349.216747 -224.718372) (xy 349.165609 -224.710273) (xy 349.116369 -224.694274)
			(xy 349.070237 -224.670768) (xy 349.02835 -224.640336) (xy 348.99174 -224.603726) (xy 348.961308 -224.561839)
			(xy 348.937802 -224.515707) (xy 348.921803 -224.466467) (xy 348.913704 -224.415329) (xy 348.913196 -224.389442)
			(xy 348.632272 -224.389442) (xy 348.631725 -224.417149) (xy 348.622541 -224.471796) (xy 348.613984 -224.498154)
			(xy 348.60611 -224.520252) (xy 348.811088 -224.87509) (xy 348.833948 -224.879408) (xy 348.858771 -224.884565)
			(xy 348.906551 -224.90152) (xy 348.951171 -224.925592) (xy 348.991578 -224.956214) (xy 349.026819 -224.992662)
			(xy 349.056063 -225.034077) (xy 349.078619 -225.079482) (xy 349.093956 -225.127806) (xy 349.101711 -225.177908)
			(xy 349.102172 -225.203258) (xy 349.101664 -225.229165) (xy 349.093558 -225.280342) (xy 349.077546 -225.329621)
			(xy 349.054023 -225.375788) (xy 349.023567 -225.417707) (xy 348.986929 -225.454345) (xy 348.94501 -225.484801)
			(xy 348.898843 -225.508324) (xy 348.849564 -225.524336) (xy 348.798387 -225.532442) (xy 348.746573 -225.532442)
			(xy 348.695396 -225.524336) (xy 348.646117 -225.508324) (xy 348.59995 -225.484801) (xy 348.558031 -225.454345)
			(xy 348.521393 -225.417707) (xy 348.490937 -225.375788) (xy 348.467414 -225.329621) (xy 348.451402 -225.280342)
			(xy 348.443296 -225.229165) (xy 348.442788 -225.203258) (xy 348.443397 -225.175541) (xy 348.45271 -225.120895)
			(xy 348.46133 -225.094546) (xy 348.469204 -225.072448) (xy 348.264226 -224.71761) (xy 348.241366 -224.713292)
			(xy 348.216548 -224.708169) (xy 348.168805 -224.691172) (xy 348.124226 -224.667071) (xy 348.08386 -224.636431)
			(xy 348.048657 -224.599976) (xy 348.019448 -224.558564) (xy 347.996919 -224.51317) (xy 347.981601 -224.464863)
			(xy 347.973855 -224.414781) (xy 347.973396 -224.389442) (xy 347.692472 -224.389442) (xy 347.691964 -224.415329)
			(xy 347.683865 -224.466467) (xy 347.667866 -224.515707) (xy 347.64436 -224.561839) (xy 347.613928 -224.603726)
			(xy 347.577318 -224.640336) (xy 347.535431 -224.670768) (xy 347.489299 -224.694274) (xy 347.440059 -224.710273)
			(xy 347.388921 -224.718372) (xy 347.337147 -224.718372) (xy 347.286009 -224.710273) (xy 347.236769 -224.694274)
			(xy 347.190637 -224.670768) (xy 347.14875 -224.640336) (xy 347.11214 -224.603726) (xy 347.081708 -224.561839)
			(xy 347.058202 -224.515707) (xy 347.042203 -224.466467) (xy 347.034104 -224.415329) (xy 347.033596 -224.389442)
			(xy 346.752672 -224.389442) (xy 346.752125 -224.417149) (xy 346.742941 -224.471796) (xy 346.734384 -224.498154)
			(xy 346.72651 -224.520252) (xy 346.931488 -224.87509) (xy 346.954348 -224.879408) (xy 346.979171 -224.884565)
			(xy 347.026951 -224.90152) (xy 347.071571 -224.925592) (xy 347.111978 -224.956214) (xy 347.147219 -224.992662)
			(xy 347.176463 -225.034077) (xy 347.199019 -225.079482) (xy 347.214356 -225.127806) (xy 347.222111 -225.177908)
			(xy 347.222572 -225.203258) (xy 347.222064 -225.229165) (xy 347.213958 -225.280342) (xy 347.197946 -225.329621)
			(xy 347.174423 -225.375788) (xy 347.143967 -225.417707) (xy 347.107329 -225.454345) (xy 347.06541 -225.484801)
			(xy 347.019243 -225.508324) (xy 346.969964 -225.524336) (xy 346.918787 -225.532442) (xy 346.866973 -225.532442)
			(xy 346.815796 -225.524336) (xy 346.766517 -225.508324) (xy 346.72035 -225.484801) (xy 346.678431 -225.454345)
			(xy 346.641793 -225.417707) (xy 346.611337 -225.375788) (xy 346.587814 -225.329621) (xy 346.571802 -225.280342)
			(xy 346.563696 -225.229165) (xy 346.563188 -225.203258) (xy 346.563797 -225.175541) (xy 346.57311 -225.120895)
			(xy 346.58173 -225.094546) (xy 346.589604 -225.072448) (xy 346.384626 -224.71761) (xy 346.361766 -224.713292)
			(xy 346.336948 -224.708169) (xy 346.289205 -224.691172) (xy 346.244626 -224.667071) (xy 346.20426 -224.636431)
			(xy 346.169057 -224.599976) (xy 346.139848 -224.558564) (xy 346.117319 -224.51317) (xy 346.102001 -224.464863)
			(xy 346.094255 -224.414781) (xy 346.093796 -224.389442) (xy 345.812872 -224.389442) (xy 345.812361 -224.415328)
			(xy 345.804257 -224.466462) (xy 345.788254 -224.5157) (xy 345.764747 -224.561828) (xy 345.734315 -224.603712)
			(xy 345.697706 -224.64032) (xy 345.655821 -224.670752) (xy 345.609692 -224.694257) (xy 345.560455 -224.710259)
			(xy 345.50932 -224.718362) (xy 345.483434 -224.71888) (xy 345.45573 -224.718301) (xy 345.401104 -224.709025)
			(xy 345.348792 -224.69076) (xy 345.300263 -224.66402) (xy 345.278202 -224.647252) (xy 345.266738 -224.638755)
			(xy 345.24037 -224.62788) (xy 345.212023 -224.624722) (xy 345.183908 -224.629527) (xy 345.158219 -224.64192)
			(xy 345.136958 -224.660934) (xy 345.121786 -224.685086) (xy 345.113886 -224.712493) (xy 345.113356 -224.726754)
			(xy 345.113356 -224.887536) (xy 345.14409 -224.900744) (xy 345.169026 -224.912098) (xy 345.215044 -224.941834)
			(xy 345.255505 -224.978776) (xy 345.289294 -225.021904) (xy 345.31548 -225.07003) (xy 345.33334 -225.121826)
			(xy 345.342382 -225.175863) (xy 345.342972 -225.203258) (xy 345.342493 -225.229163) (xy 345.33439 -225.280336)
			(xy 345.318379 -225.32961) (xy 345.294852 -225.375771) (xy 345.264391 -225.417681) (xy 345.227745 -225.454306)
			(xy 345.185819 -225.484745) (xy 345.139646 -225.508247) (xy 345.090363 -225.524232) (xy 345.039185 -225.532307)
			(xy 345.01328 -225.532696) (xy 344.990306 -225.532294) (xy 344.944804 -225.525916) (xy 344.922602 -225.519996)
			(xy 344.8939 -225.511868) (xy 343.426796 -226.978972) (xy 343.42324 -226.985576) (xy 343.411441 -227.006766)
			(xy 343.382562 -227.04573) (xy 343.348264 -227.080019) (xy 343.309292 -227.108887) (xy 343.288112 -227.120704)
			(xy 343.281508 -227.12426) (xy 342.940894 -227.464874) (xy 342.957404 -227.49764) (xy 342.968388 -227.520627)
			(xy 342.983903 -227.56915) (xy 342.991735 -227.619488) (xy 342.992202 -227.64496) (xy 342.991726 -227.670753)
			(xy 342.983662 -227.721704) (xy 342.967727 -227.770766) (xy 342.944313 -227.816732) (xy 342.913997 -227.858469)
			(xy 342.877525 -227.894949) (xy 342.835795 -227.925275) (xy 342.789835 -227.948699) (xy 342.740776 -227.964645)
			(xy 342.689827 -227.97272) (xy 342.664034 -227.973128) (xy 342.638562 -227.972665) (xy 342.588224 -227.96483)
			(xy 342.539702 -227.949312) (xy 342.516714 -227.93833) (xy 342.483948 -227.92182) (xy 341.112348 -229.29342)
			(xy 341.110316 -229.310946) (xy 341.107035 -229.335129) (xy 341.094247 -229.382223) (xy 341.074624 -229.426905)
			(xy 341.048601 -229.468187) (xy 341.016751 -229.505161) (xy 340.979777 -229.537009) (xy 340.938493 -229.563031)
			(xy 340.893811 -229.582651) (xy 340.846716 -229.595438) (xy 340.822534 -229.598728) (xy 340.805008 -229.60076)
			(xy 340.550754 -229.855014) (xy 340.57717 -229.890066) (xy 340.592514 -229.911502) (xy 340.616891 -229.958239)
			(xy 340.633495 -230.008268) (xy 340.6419 -230.060306) (xy 340.642448 -230.086662) (xy 340.641972 -230.112453)
			(xy 340.633907 -230.163401) (xy 340.617972 -230.212459) (xy 340.594557 -230.258421) (xy 340.564239 -230.300153)
			(xy 340.527767 -230.336628) (xy 340.486036 -230.366947) (xy 340.440076 -230.390365) (xy 340.391018 -230.406303)
			(xy 340.340071 -230.41437) (xy 340.31428 -230.41483) (xy 340.287918 -230.414333) (xy 340.235867 -230.405951)
			(xy 340.18583 -230.389341) (xy 340.139099 -230.364933) (xy 340.117684 -230.349552) (xy 340.082632 -230.323136)
			(xy 338.757006 -231.648762) (xy 338.760308 -231.6734) (xy 338.761504 -231.683645) (xy 338.762777 -231.704234)
			(xy 338.762848 -231.714548) (xy 338.762339 -231.740333) (xy 338.754264 -231.791266) (xy 338.738322 -231.840309)
			(xy 338.714905 -231.886255) (xy 338.684589 -231.927972) (xy 338.64812 -231.964433) (xy 338.606397 -231.99474)
			(xy 338.560446 -232.018148) (xy 338.5114 -232.03408) (xy 338.460465 -232.042144) (xy 338.43468 -232.042716)
			(xy 338.424366 -232.042654) (xy 338.403776 -232.041381) (xy 338.393532 -232.040176) (xy 338.368894 -232.036874)
			(xy 337.721956 -232.683812) (xy 337.721956 -233.105198) (xy 337.740724 -233.123902) (xy 337.772574 -233.166243)
			(xy 337.797216 -233.213147) (xy 337.814008 -233.263399) (xy 337.822515 -233.315695) (xy 337.822517 -233.368678)
			(xy 337.814014 -233.420974) (xy 337.797226 -233.471227) (xy 337.772589 -233.518134) (xy 337.740742 -233.560477)
			(xy 337.721956 -233.579162) (xy 337.721956 -234.733084) (xy 337.740725 -234.751788) (xy 337.772578 -234.794129)
			(xy 337.797221 -234.841034) (xy 337.814015 -234.891287) (xy 337.822524 -234.943584) (xy 337.822528 -234.996569)
			(xy 337.814026 -235.048867) (xy 337.79724 -235.099122) (xy 337.772603 -235.146031) (xy 337.740756 -235.188377)
			(xy 337.721956 -235.207048) (xy 337.721956 -236.36097) (xy 337.740726 -236.379674) (xy 337.772581 -236.422015)
			(xy 337.797227 -236.468921) (xy 337.814023 -236.519175) (xy 337.822534 -236.571474) (xy 337.822539 -236.62446)
			(xy 337.814039 -236.67676) (xy 337.797253 -236.727017) (xy 337.772617 -236.773928) (xy 337.74077 -236.816276)
			(xy 337.721956 -236.834934) (xy 337.721956 -237.988602) (xy 337.740723 -238.007306) (xy 337.772574 -238.049647)
			(xy 337.797214 -238.096551) (xy 337.814005 -238.146802) (xy 337.822512 -238.199098) (xy 337.822514 -238.25208)
			(xy 337.814011 -238.304376) (xy 337.797223 -238.354629) (xy 337.772585 -238.401535) (xy 337.740738 -238.443877)
			(xy 337.721956 -238.462566) (xy 337.721956 -239.616234) (xy 337.74072 -239.634938) (xy 337.772565 -239.677278)
			(xy 337.797201 -239.72418) (xy 337.813988 -239.77443) (xy 337.822491 -239.826722) (xy 337.822489 -239.879701)
			(xy 337.813983 -239.931992) (xy 337.797192 -239.98224) (xy 337.772554 -240.029141) (xy 337.740706 -240.071478)
			(xy 337.721956 -240.090198) (xy 337.721956 -241.24412) (xy 337.740722 -241.262824) (xy 337.772569 -241.305164)
			(xy 337.797207 -241.352067) (xy 337.813996 -241.402318) (xy 337.8225 -241.454611) (xy 337.8225 -241.507592)
			(xy 337.813995 -241.559885) (xy 337.797206 -241.610135) (xy 337.772568 -241.657038) (xy 337.74072 -241.699378)
			(xy 337.721956 -241.718084) (xy 337.721956 -242.872006) (xy 337.740723 -242.89071) (xy 337.772573 -242.93305)
			(xy 337.797212 -242.979955) (xy 337.814003 -243.030206) (xy 337.82251 -243.082501) (xy 337.822511 -243.135483)
			(xy 337.814007 -243.187778) (xy 337.797219 -243.23803) (xy 337.772581 -243.284936) (xy 337.740734 -243.327278)
			(xy 337.721956 -243.34597) (xy 337.721956 -244.499638) (xy 337.74072 -244.518342) (xy 337.772565 -244.560682)
			(xy 337.797199 -244.607584) (xy 337.813986 -244.657833) (xy 337.822488 -244.710125) (xy 337.822486 -244.763103)
			(xy 337.813979 -244.815394) (xy 337.797189 -244.865641) (xy 337.77255 -244.912542) (xy 337.740702 -244.954879)
			(xy 337.721956 -244.973602) (xy 337.721956 -246.127524) (xy 337.740721 -246.146228) (xy 337.772568 -246.188568)
			(xy 337.797205 -246.235471) (xy 337.813994 -246.285721) (xy 337.822498 -246.338014) (xy 337.822497 -246.390994)
			(xy 337.813992 -246.443287) (xy 337.797202 -246.493537) (xy 337.772564 -246.540439) (xy 337.740716 -246.582778)
			(xy 337.721956 -246.601488) (xy 337.721956 -247.754902) (xy 337.740766 -247.773612) (xy 337.772693 -247.81598)
			(xy 337.797393 -247.862929) (xy 337.814224 -247.913239) (xy 337.822749 -247.965601) (xy 337.822745 -248.018652)
			(xy 337.814212 -248.071012) (xy 337.797372 -248.121319) (xy 337.772664 -248.168265) (xy 337.740731 -248.210628)
			(xy 337.721956 -248.229374) (xy 337.721956 -249.383042) (xy 337.74072 -249.401746) (xy 337.772564 -249.444086)
			(xy 337.797198 -249.490988) (xy 337.813984 -249.541236) (xy 337.822485 -249.593528) (xy 337.822483 -249.646506)
			(xy 337.813976 -249.698796) (xy 337.797185 -249.749043) (xy 337.772546 -249.795942) (xy 337.740698 -249.838279)
			(xy 337.721956 -249.857006) (xy 337.721956 -254.42545) (xy 337.75015 -254.43942) (xy 337.773321 -254.451406)
			(xy 337.815866 -254.481589) (xy 337.853098 -254.518127) (xy 337.884077 -254.560096) (xy 337.908022 -254.60644)
			(xy 337.924331 -254.65599) (xy 337.932591 -254.707496) (xy 337.932594 -254.759661) (xy 337.924341 -254.811169)
			(xy 337.908039 -254.860721) (xy 337.884099 -254.907068) (xy 337.853126 -254.949041) (xy 337.815899 -254.985583)
			(xy 337.773357 -255.015772) (xy 337.75015 -255.027684) (xy 337.721956 -255.041654) (xy 337.721956 -256.053336)
			(xy 337.75015 -256.067306) (xy 337.773314 -256.079292) (xy 337.815846 -256.109473) (xy 337.853064 -256.146006)
			(xy 337.884031 -256.187969) (xy 337.907966 -256.234305) (xy 337.924265 -256.283845) (xy 337.932517 -256.335341)
			(xy 337.932514 -256.387493) (xy 337.924257 -256.438988) (xy 337.907953 -256.488526) (xy 337.884014 -256.534859)
			(xy 337.853042 -256.57682) (xy 337.81582 -256.613349) (xy 337.773285 -256.643525) (xy 337.75015 -256.65557)
			(xy 337.721956 -256.66954) (xy 337.721956 -257.680968) (xy 337.75015 -257.694938) (xy 337.773319 -257.706924)
			(xy 337.815862 -257.737107) (xy 337.853091 -257.773643) (xy 337.884067 -257.815611) (xy 337.908011 -257.861954)
			(xy 337.924317 -257.911501) (xy 337.932575 -257.963006) (xy 337.932577 -258.015168) (xy 337.924323 -258.066673)
			(xy 337.908021 -258.116222) (xy 337.884081 -258.162566) (xy 337.853108 -258.204537) (xy 337.815882 -258.241076)
			(xy 337.773342 -258.271262) (xy 337.75015 -258.283202) (xy 337.721956 -258.297172) (xy 337.721956 -259.308854)
			(xy 337.75015 -259.322824) (xy 337.77332 -259.33481) (xy 337.815865 -259.364993) (xy 337.853096 -259.40153)
			(xy 337.884075 -259.4435) (xy 337.90802 -259.489843) (xy 337.924328 -259.539392) (xy 337.932587 -259.590899)
			(xy 337.93259 -259.643063) (xy 337.924337 -259.69457) (xy 337.908035 -259.744121) (xy 337.884095 -259.790467)
			(xy 337.853122 -259.83244) (xy 337.815895 -259.868982) (xy 337.773354 -259.89917) (xy 337.75015 -259.911088)
			(xy 337.721956 -259.925058) (xy 337.721956 -260.8199) (xy 339.447632 -262.545576) (xy 339.469984 -262.54456)
			(xy 339.484462 -262.544306) (xy 339.510254 -262.544782) (xy 339.561205 -262.552846) (xy 339.610266 -262.568782)
			(xy 339.656231 -262.592196) (xy 339.697967 -262.622512) (xy 339.734446 -262.658984) (xy 339.764771 -262.700714)
			(xy 339.788194 -262.746674) (xy 339.804139 -262.795733) (xy 339.812213 -262.846682) (xy 339.81263 -262.872474)
			(xy 339.812376 -262.886952) (xy 339.81136 -262.909304) (xy 341.150194 -264.248138) (xy 341.184738 -264.225532)
			(xy 341.204838 -264.21292) (xy 341.247899 -264.192988) (xy 341.293381 -264.179462) (xy 341.340337 -264.172625)
			(xy 341.364062 -264.172192) (xy 341.389853 -264.172695) (xy 341.4408 -264.180758) (xy 341.489858 -264.196692)
			(xy 341.53582 -264.220104) (xy 341.577554 -264.250417) (xy 341.614032 -264.286887) (xy 341.644355 -264.328613)
			(xy 341.667778 -264.374569) (xy 341.683724 -264.423624) (xy 341.691799 -264.474569) (xy 341.69223 -264.50036)
			(xy 341.691813 -264.524087) (xy 341.684981 -264.571046) (xy 341.671455 -264.61653) (xy 341.651515 -264.659591)
			(xy 341.63889 -264.679684) (xy 341.616284 -264.714228) (xy 341.893144 -264.991088) (xy 341.907368 -264.994136)
			(xy 341.932901 -265.000507) (xy 341.981671 -265.020265) (xy 342.026665 -265.047549) (xy 342.066732 -265.081661)
			(xy 342.100845 -265.121727) (xy 342.128131 -265.16672) (xy 342.147891 -265.21549) (xy 342.154256 -265.241024)
			(xy 342.157304 -265.255248) (xy 343.554812 -266.652756) (xy 343.586308 -266.639548) (xy 343.606563 -266.631378)
			(xy 343.648693 -266.619857) (xy 343.691978 -266.61402) (xy 343.713816 -266.61364) (xy 343.739603 -266.614147)
			(xy 343.79054 -266.622217) (xy 343.839589 -266.638156) (xy 343.88554 -266.661572) (xy 343.927262 -266.691887)
			(xy 343.963728 -266.728356) (xy 343.994041 -266.770081) (xy 344.017453 -266.816034) (xy 344.033389 -266.865083)
			(xy 344.041455 -266.916021) (xy 344.041984 -266.941808) (xy 344.04161 -266.963647) (xy 344.035781 -267.006934)
			(xy 344.024256 -267.049064) (xy 344.016076 -267.069316) (xy 344.002868 -267.100812) (xy 344.685112 -267.783056)
			(xy 350.431608 -267.783056)
		)
		(stroke
			(width 0)
			(type solid)
		)
		(fill yes)
		(layer "In9.Cu")
		(net "PVCCFA_EHV_CPU0")
	)
	(gr_poly
		(pts
			(xy 168.62425 -341.767668) (xy 168.641221 -341.746414) (xy 168.680523 -341.708819) (xy 168.725085 -341.677639)
			(xy 168.773872 -341.653601) (xy 168.825747 -341.637263) (xy 168.879504 -341.629005) (xy 168.906698 -341.628476)
			(xy 168.932022 -341.628922) (xy 168.982159 -341.636102) (xy 169.030771 -341.650316) (xy 169.076878 -341.671278)
			(xy 169.119547 -341.698565) (xy 169.157917 -341.731624) (xy 169.174922 -341.750396) (xy 169.190162 -341.767668)
			(xy 169.258234 -341.767668) (xy 169.273474 -341.750396) (xy 169.292038 -341.729927) (xy 169.334373 -341.694417)
			(xy 169.381686 -341.665873) (xy 169.43284 -341.644981) (xy 169.486608 -341.632241) (xy 169.541698 -341.627961)
			(xy 169.596788 -341.632241) (xy 169.650556 -341.644981) (xy 169.70171 -341.665873) (xy 169.749023 -341.694417)
			(xy 169.791358 -341.729927) (xy 169.809922 -341.750396) (xy 169.825162 -341.767668) (xy 169.905934 -341.767668)
			(xy 169.921174 -341.750396) (xy 169.938166 -341.731614) (xy 169.976546 -341.698567) (xy 170.019221 -341.671289)
			(xy 170.065328 -341.650331) (xy 170.11394 -341.636114) (xy 170.164074 -341.628926) (xy 170.189398 -341.628476)
			(xy 170.216592 -341.62899) (xy 170.270349 -341.637257) (xy 170.322224 -341.6536) (xy 170.371012 -341.677639)
			(xy 170.415578 -341.708815) (xy 170.454888 -341.746403) (xy 170.471846 -341.767668) (xy 173.594522 -341.767668)
			(xy 173.611493 -341.746412) (xy 173.650793 -341.708814) (xy 173.695355 -341.677631) (xy 173.744142 -341.653589)
			(xy 173.796018 -341.637247) (xy 173.849775 -341.628985) (xy 173.87697 -341.628476) (xy 173.902295 -341.62892)
			(xy 173.952434 -341.636096) (xy 174.001049 -341.650308) (xy 174.047158 -341.671268) (xy 174.08983 -341.698552)
			(xy 174.128204 -341.731611) (xy 174.145194 -341.750396) (xy 174.160434 -341.767668) (xy 174.241206 -341.767668)
			(xy 174.256446 -341.750396) (xy 174.27501 -341.729927) (xy 174.317345 -341.694417) (xy 174.364658 -341.665873)
			(xy 174.415812 -341.644981) (xy 174.46958 -341.632241) (xy 174.52467 -341.627961) (xy 174.57976 -341.632241)
			(xy 174.633528 -341.644981) (xy 174.684682 -341.665873) (xy 174.731995 -341.694417) (xy 174.77433 -341.729927)
			(xy 174.792894 -341.750396) (xy 174.808134 -341.767668) (xy 174.876206 -341.767668) (xy 174.891446 -341.750396)
			(xy 174.908437 -341.731612) (xy 174.946817 -341.698562) (xy 174.989491 -341.671281) (xy 175.035598 -341.650319)
			(xy 175.08421 -341.636099) (xy 175.134346 -341.628907) (xy 175.15967 -341.628476) (xy 175.186862 -341.628995)
			(xy 175.240612 -341.637272) (xy 175.29248 -341.653623) (xy 175.34126 -341.677668) (xy 175.385818 -341.708847)
			(xy 175.425119 -341.746438) (xy 175.442118 -341.767668) (xy 178.30165 -341.767668) (xy 178.318621 -341.746414)
			(xy 178.357923 -341.708819) (xy 178.402485 -341.677639) (xy 178.451272 -341.653601) (xy 178.503147 -341.637263)
			(xy 178.556904 -341.629005) (xy 178.584098 -341.628476) (xy 178.609422 -341.628922) (xy 178.659559 -341.636102)
			(xy 178.708171 -341.650316) (xy 178.754278 -341.671278) (xy 178.796947 -341.698565) (xy 178.835317 -341.731624)
			(xy 178.852322 -341.750396) (xy 178.867562 -341.767668) (xy 178.935634 -341.767668) (xy 178.950874 -341.750396)
			(xy 178.969438 -341.729927) (xy 179.011773 -341.694417) (xy 179.059086 -341.665873) (xy 179.11024 -341.644981)
			(xy 179.164008 -341.632241) (xy 179.219098 -341.627961) (xy 179.274188 -341.632241) (xy 179.327956 -341.644981)
			(xy 179.37911 -341.665873) (xy 179.426423 -341.694417) (xy 179.468758 -341.729927) (xy 179.487322 -341.750396)
			(xy 179.502562 -341.767668) (xy 179.583334 -341.767668) (xy 179.598574 -341.750396) (xy 179.615566 -341.731614)
			(xy 179.653946 -341.698567) (xy 179.696621 -341.671289) (xy 179.742728 -341.650331) (xy 179.79134 -341.636114)
			(xy 179.841474 -341.628926) (xy 179.866798 -341.628476) (xy 179.893992 -341.62899) (xy 179.947749 -341.637257)
			(xy 179.999624 -341.6536) (xy 180.048412 -341.677639) (xy 180.092978 -341.708815) (xy 180.132288 -341.746403)
			(xy 180.149246 -341.767668) (xy 183.373268 -341.767668) (xy 183.390239 -341.746415) (xy 183.429542 -341.708822)
			(xy 183.474105 -341.677645) (xy 183.522891 -341.653608) (xy 183.574766 -341.637273) (xy 183.628523 -341.629018)
			(xy 183.655716 -341.628476) (xy 183.681042 -341.628917) (xy 183.731185 -341.636086) (xy 183.779805 -341.650292)
			(xy 183.82592 -341.671247) (xy 183.868598 -341.698528) (xy 183.906977 -341.731585) (xy 183.92394 -341.750396)
			(xy 183.93918 -341.767668) (xy 184.019952 -341.767668) (xy 184.035192 -341.750396) (xy 184.053756 -341.729927)
			(xy 184.096091 -341.694417) (xy 184.143404 -341.665873) (xy 184.194558 -341.644981) (xy 184.248326 -341.632241)
			(xy 184.303416 -341.627961) (xy 184.358506 -341.632241) (xy 184.412274 -341.644981) (xy 184.463428 -341.665873)
			(xy 184.510741 -341.694417) (xy 184.553076 -341.729927) (xy 184.57164 -341.750396) (xy 184.58688 -341.767668)
			(xy 184.654952 -341.767668) (xy 184.670192 -341.750396) (xy 184.687184 -341.731615) (xy 184.725565 -341.69857)
			(xy 184.76824 -341.671294) (xy 184.814347 -341.650338) (xy 184.862958 -341.636124) (xy 184.913093 -341.628938)
			(xy 184.938416 -341.628476) (xy 184.96766 -341.629049) (xy 185.02537 -341.638563) (xy 185.080753 -341.657366)
			(xy 185.106818 -341.67064) (xy 185.139838 -341.688674) (xy 186.0804 -340.748112) (xy 186.0804 -329.188064)
			(xy 185.495184 -328.602848) (xy 182.02148 -328.602848) (xy 181.996521 -328.602275) (xy 181.947562 -328.592531)
			(xy 181.901446 -328.573421) (xy 181.859945 -328.545681) (xy 181.841902 -328.528426) (xy 180.991764 -327.678288)
			(xy 180.974502 -327.660248) (xy 180.946738 -327.618755) (xy 180.927619 -327.572637) (xy 180.91788 -327.523672)
			(xy 180.917342 -327.49871) (xy 180.917342 -323.731636) (xy 180.895061 -323.716294) (xy 180.854975 -323.679972)
			(xy 180.820841 -323.638007) (xy 180.793444 -323.591363) (xy 180.773412 -323.541114) (xy 180.761208 -323.488415)
			(xy 180.757111 -323.434476) (xy 180.761215 -323.380537) (xy 180.773427 -323.327839) (xy 180.793465 -323.277593)
			(xy 180.820869 -323.230953) (xy 180.855009 -323.188993) (xy 180.8951 -323.152676) (xy 180.917342 -323.137276)
			(xy 180.917342 -215.48852) (xy 180.476652 -215.04783) (xy 152.668478 -215.04783) (xy 152.663906 -215.048592)
			(xy 152.652455 -215.050601) (xy 152.629304 -215.05276) (xy 152.617678 -215.05291) (xy 135.930894 -215.05291)
			(xy 135.916351 -215.053378) (xy 135.888444 -215.061576) (xy 135.863979 -215.077306) (xy 135.844937 -215.099293)
			(xy 135.832864 -215.125755) (xy 135.828737 -215.154546) (xy 135.83289 -215.183334) (xy 135.844988 -215.209785)
			(xy 135.854186 -215.221058) (xy 135.869275 -215.23911) (xy 135.894716 -215.278686) (xy 135.914271 -215.321477)
			(xy 135.927543 -215.366615) (xy 135.934261 -215.41318) (xy 135.934704 -215.436704) (xy 135.934196 -215.462611)
			(xy 135.92609 -215.513788) (xy 135.910078 -215.563067) (xy 135.886555 -215.609234) (xy 135.856099 -215.651153)
			(xy 135.819461 -215.687791) (xy 135.777542 -215.718247) (xy 135.731375 -215.74177) (xy 135.682096 -215.757782)
			(xy 135.630919 -215.765888) (xy 135.579105 -215.765888) (xy 135.527928 -215.757782) (xy 135.478649 -215.74177)
			(xy 135.432482 -215.718247) (xy 135.390563 -215.687791) (xy 135.353925 -215.651153) (xy 135.323469 -215.609234)
			(xy 135.299946 -215.563067) (xy 135.283934 -215.513788) (xy 135.275828 -215.462611) (xy 135.27532 -215.436704)
			(xy 135.276038 -215.405864) (xy 135.287546 -215.345266) (xy 135.29818 -215.316308) (xy 135.306816 -215.294464)
			(xy 135.179308 -215.05291) (xy 134.991094 -215.05291) (xy 134.976551 -215.053378) (xy 134.948644 -215.061576)
			(xy 134.924179 -215.077306) (xy 134.905137 -215.099293) (xy 134.893064 -215.125755) (xy 134.888937 -215.154546)
			(xy 134.89309 -215.183334) (xy 134.905188 -215.209785) (xy 134.914386 -215.221058) (xy 134.929475 -215.23911)
			(xy 134.954916 -215.278686) (xy 134.974471 -215.321477) (xy 134.987743 -215.366615) (xy 134.994461 -215.41318)
			(xy 134.994904 -215.436704) (xy 134.994396 -215.462611) (xy 134.98629 -215.513788) (xy 134.970278 -215.563067)
			(xy 134.946755 -215.609235) (xy 134.916299 -215.651154) (xy 134.87966 -215.687794) (xy 134.837742 -215.71825)
			(xy 134.791575 -215.741775) (xy 134.742296 -215.757788) (xy 134.691119 -215.765895) (xy 134.665212 -215.766396)
			(xy 134.6397 -215.765919) (xy 134.589284 -215.75806) (xy 134.540681 -215.742528) (xy 134.495051 -215.719693)
			(xy 134.453484 -215.6901) (xy 134.416972 -215.654458) (xy 134.401306 -215.634316) (xy 133.989318 -215.634316)
			(xy 133.973645 -215.654452) (xy 133.937135 -215.690096) (xy 133.89557 -215.719691) (xy 133.849941 -215.742528)
			(xy 133.801339 -215.758064) (xy 133.750924 -215.765926) (xy 133.725412 -215.766396) (xy 133.699502 -215.765915)
			(xy 133.648319 -215.757811) (xy 133.599035 -215.741799) (xy 133.552862 -215.718274) (xy 133.510938 -215.687816)
			(xy 133.474294 -215.651175) (xy 133.443834 -215.609252) (xy 133.420307 -215.56308) (xy 133.404293 -215.513796)
			(xy 133.396186 -215.462614) (xy 133.39572 -215.436704) (xy 133.396159 -215.413181) (xy 133.402887 -215.366618)
			(xy 133.416164 -215.321484) (xy 133.435721 -215.278694) (xy 133.46116 -215.239119) (xy 133.476238 -215.221058)
			(xy 133.485412 -215.209769) (xy 133.497504 -215.183324) (xy 133.501654 -215.154543) (xy 133.497528 -215.125759)
			(xy 133.485458 -215.099303) (xy 133.466424 -215.07732) (xy 133.441967 -215.061591) (xy 133.414069 -215.05339)
			(xy 133.39953 -215.05291) (xy 133.234938 -215.05291) (xy 133.088888 -215.305894) (xy 133.096762 -215.327738)
			(xy 133.105408 -215.354146) (xy 133.11473 -215.408922) (xy 133.115304 -215.436704) (xy 133.114796 -215.462611)
			(xy 133.10669 -215.513788) (xy 133.090678 -215.563067) (xy 133.067155 -215.609234) (xy 133.036699 -215.651153)
			(xy 133.000061 -215.687791) (xy 132.958142 -215.718247) (xy 132.911975 -215.74177) (xy 132.862696 -215.757782)
			(xy 132.811519 -215.765888) (xy 132.759705 -215.765888) (xy 132.708528 -215.757782) (xy 132.659249 -215.74177)
			(xy 132.613082 -215.718247) (xy 132.571163 -215.687791) (xy 132.534525 -215.651153) (xy 132.504069 -215.609234)
			(xy 132.480546 -215.563067) (xy 132.464534 -215.513788) (xy 132.456428 -215.462611) (xy 132.45592 -215.436704)
			(xy 132.456359 -215.413181) (xy 132.463087 -215.366618) (xy 132.476364 -215.321484) (xy 132.495921 -215.278694)
			(xy 132.52136 -215.239119) (xy 132.536438 -215.221058) (xy 132.545612 -215.209769) (xy 132.557704 -215.183324)
			(xy 132.561854 -215.154543) (xy 132.557728 -215.125759) (xy 132.545658 -215.099303) (xy 132.526624 -215.07732)
			(xy 132.502167 -215.061591) (xy 132.474269 -215.05339) (xy 132.45973 -215.05291) (xy 131.355338 -215.05291)
			(xy 131.209288 -215.305894) (xy 131.217162 -215.327738) (xy 131.225808 -215.354146) (xy 131.23513 -215.408922)
			(xy 131.235704 -215.436704) (xy 131.235196 -215.462611) (xy 131.22709 -215.513788) (xy 131.211078 -215.563067)
			(xy 131.187555 -215.609234) (xy 131.157099 -215.651153) (xy 131.120461 -215.687791) (xy 131.078542 -215.718247)
			(xy 131.032375 -215.74177) (xy 130.983096 -215.757782) (xy 130.931919 -215.765888) (xy 130.880105 -215.765888)
			(xy 130.828928 -215.757782) (xy 130.779649 -215.74177) (xy 130.733482 -215.718247) (xy 130.691563 -215.687791)
			(xy 130.654925 -215.651153) (xy 130.624469 -215.609234) (xy 130.600946 -215.563067) (xy 130.584934 -215.513788)
			(xy 130.576828 -215.462611) (xy 130.57632 -215.436704) (xy 130.576759 -215.413181) (xy 130.583487 -215.366618)
			(xy 130.596764 -215.321484) (xy 130.616321 -215.278694) (xy 130.64176 -215.239119) (xy 130.656838 -215.221058)
			(xy 130.666012 -215.209769) (xy 130.678104 -215.183324) (xy 130.682254 -215.154543) (xy 130.678128 -215.125759)
			(xy 130.666058 -215.099303) (xy 130.647024 -215.07732) (xy 130.622567 -215.061591) (xy 130.594669 -215.05339)
			(xy 130.58013 -215.05291) (xy 129.475738 -215.05291) (xy 129.329688 -215.305894) (xy 129.337562 -215.327738)
			(xy 129.346208 -215.354146) (xy 129.35553 -215.408922) (xy 129.356104 -215.436704) (xy 129.355596 -215.462611)
			(xy 129.34749 -215.513788) (xy 129.331478 -215.563067) (xy 129.307955 -215.609234) (xy 129.277499 -215.651153)
			(xy 129.240861 -215.687791) (xy 129.198942 -215.718247) (xy 129.152775 -215.74177) (xy 129.103496 -215.757782)
			(xy 129.052319 -215.765888) (xy 129.000505 -215.765888) (xy 128.949328 -215.757782) (xy 128.900049 -215.74177)
			(xy 128.853882 -215.718247) (xy 128.811963 -215.687791) (xy 128.775325 -215.651153) (xy 128.744869 -215.609234)
			(xy 128.721346 -215.563067) (xy 128.705334 -215.513788) (xy 128.697228 -215.462611) (xy 128.69672 -215.436704)
			(xy 128.697159 -215.413181) (xy 128.703887 -215.366618) (xy 128.717164 -215.321484) (xy 128.736721 -215.278694)
			(xy 128.76216 -215.239119) (xy 128.777238 -215.221058) (xy 128.786412 -215.209769) (xy 128.798504 -215.183324)
			(xy 128.802654 -215.154543) (xy 128.798528 -215.125759) (xy 128.786458 -215.099303) (xy 128.767424 -215.07732)
			(xy 128.742967 -215.061591) (xy 128.715069 -215.05339) (xy 128.70053 -215.05291) (xy 128.215898 -215.05291)
			(xy 127.882142 -215.386666) (xy 127.882142 -216.057226) (xy 127.896978 -216.078402) (xy 127.920504 -216.124442)
			(xy 127.936519 -216.173602) (xy 127.944625 -216.224665) (xy 127.944622 -216.276367) (xy 127.936511 -216.32743)
			(xy 127.920492 -216.376588) (xy 127.896961 -216.422626) (xy 127.882142 -216.443814) (xy 127.882142 -216.645744)
			(xy 127.882664 -216.66111) (xy 127.891793 -216.690453) (xy 127.90924 -216.71575) (xy 127.933425 -216.73471)
			(xy 127.962156 -216.745613) (xy 127.99283 -216.747472) (xy 128.007872 -216.744296) (xy 128.027245 -216.739796)
			(xy 128.066725 -216.734962) (xy 128.086612 -216.734644) (xy 128.11252 -216.735127) (xy 128.163697 -216.743235)
			(xy 128.212976 -216.759249) (xy 128.259142 -216.782776) (xy 128.30106 -216.813235) (xy 128.337696 -216.849877)
			(xy 128.368149 -216.891799) (xy 128.391669 -216.937969) (xy 128.407676 -216.98725) (xy 128.415777 -217.038428)
			(xy 128.416304 -217.064336) (xy 129.63652 -217.064336) (xy 129.637028 -217.038429) (xy 129.645134 -216.987252)
			(xy 129.661146 -216.937973) (xy 129.684669 -216.891806) (xy 129.715125 -216.849887) (xy 129.751763 -216.813249)
			(xy 129.793682 -216.782793) (xy 129.839849 -216.75927) (xy 129.889128 -216.743258) (xy 129.940305 -216.735152)
			(xy 129.992119 -216.735152) (xy 130.043296 -216.743258) (xy 130.092575 -216.75927) (xy 130.138742 -216.782793)
			(xy 130.180661 -216.813249) (xy 130.217299 -216.849887) (xy 130.247755 -216.891806) (xy 130.271278 -216.937973)
			(xy 130.28729 -216.987252) (xy 130.295396 -217.038429) (xy 130.295904 -217.064336) (xy 131.51612 -217.064336)
			(xy 131.516628 -217.038429) (xy 131.524734 -216.987252) (xy 131.540746 -216.937973) (xy 131.564269 -216.891806)
			(xy 131.594725 -216.849887) (xy 131.631363 -216.813249) (xy 131.673282 -216.782793) (xy 131.719449 -216.75927)
			(xy 131.768728 -216.743258) (xy 131.819905 -216.735152) (xy 131.871719 -216.735152) (xy 131.922896 -216.743258)
			(xy 131.972175 -216.75927) (xy 132.018342 -216.782793) (xy 132.060261 -216.813249) (xy 132.096899 -216.849887)
			(xy 132.127355 -216.891806) (xy 132.150878 -216.937973) (xy 132.16689 -216.987252) (xy 132.174996 -217.038429)
			(xy 132.175504 -217.064336) (xy 133.39572 -217.064336) (xy 133.396228 -217.038429) (xy 133.404334 -216.987252)
			(xy 133.420346 -216.937973) (xy 133.443869 -216.891806) (xy 133.474325 -216.849887) (xy 133.510963 -216.813249)
			(xy 133.552882 -216.782793) (xy 133.599049 -216.75927) (xy 133.648328 -216.743258) (xy 133.699505 -216.735152)
			(xy 133.751319 -216.735152) (xy 133.802496 -216.743258) (xy 133.851775 -216.75927) (xy 133.897942 -216.782793)
			(xy 133.939861 -216.813249) (xy 133.976499 -216.849887) (xy 134.006955 -216.891806) (xy 134.030478 -216.937973)
			(xy 134.04649 -216.987252) (xy 134.054596 -217.038429) (xy 134.055104 -217.064336) (xy 134.054489 -217.091989)
			(xy 134.045169 -217.146507) (xy 134.036562 -217.172794) (xy 134.028942 -217.194892) (xy 134.234174 -217.550238)
			(xy 134.257034 -217.554556) (xy 134.281841 -217.559728) (xy 134.329579 -217.576721) (xy 134.374156 -217.600818)
			(xy 134.41452 -217.631451) (xy 134.449723 -217.6679) (xy 134.478934 -217.709305) (xy 134.501466 -217.754693)
			(xy 134.516789 -217.802993) (xy 134.524541 -217.85307) (xy 134.525004 -217.878406) (xy 134.524496 -217.904293)
			(xy 134.516397 -217.955431) (xy 134.500398 -218.004671) (xy 134.476892 -218.050803) (xy 134.44646 -218.09269)
			(xy 134.40985 -218.1293) (xy 134.367963 -218.159732) (xy 134.321831 -218.183238) (xy 134.272591 -218.199237)
			(xy 134.221453 -218.207336) (xy 134.169679 -218.207336) (xy 134.118541 -218.199237) (xy 134.069301 -218.183238)
			(xy 134.023169 -218.159732) (xy 133.981282 -218.1293) (xy 133.944672 -218.09269) (xy 133.91424 -218.050803)
			(xy 133.890734 -218.004671) (xy 133.874735 -217.955431) (xy 133.866636 -217.904293) (xy 133.866128 -217.878406)
			(xy 133.866662 -217.850698) (xy 133.875855 -217.796051) (xy 133.884416 -217.769694) (xy 133.89229 -217.747596)
			(xy 133.687312 -217.392504) (xy 133.664452 -217.388186) (xy 133.639596 -217.383069) (xy 133.591748 -217.366166)
			(xy 133.547056 -217.342128) (xy 133.506577 -217.311523) (xy 133.471267 -217.275076) (xy 133.441961 -217.233647)
			(xy 133.419352 -217.188215) (xy 133.403974 -217.139855) (xy 133.39619 -217.089709) (xy 133.39572 -217.064336)
			(xy 132.175504 -217.064336) (xy 132.174889 -217.091989) (xy 132.165569 -217.146507) (xy 132.156962 -217.172794)
			(xy 132.149342 -217.194892) (xy 132.354574 -217.550238) (xy 132.377434 -217.554556) (xy 132.402241 -217.559728)
			(xy 132.449979 -217.576721) (xy 132.494556 -217.600818) (xy 132.53492 -217.631451) (xy 132.570123 -217.6679)
			(xy 132.599334 -217.709305) (xy 132.621866 -217.754693) (xy 132.637189 -217.802993) (xy 132.644941 -217.85307)
			(xy 132.645404 -217.878406) (xy 132.644896 -217.904293) (xy 132.636797 -217.955431) (xy 132.620798 -218.004671)
			(xy 132.597292 -218.050803) (xy 132.56686 -218.09269) (xy 132.53025 -218.1293) (xy 132.488363 -218.159732)
			(xy 132.442231 -218.183238) (xy 132.392991 -218.199237) (xy 132.341853 -218.207336) (xy 132.290079 -218.207336)
			(xy 132.238941 -218.199237) (xy 132.189701 -218.183238) (xy 132.143569 -218.159732) (xy 132.101682 -218.1293)
			(xy 132.065072 -218.09269) (xy 132.03464 -218.050803) (xy 132.011134 -218.004671) (xy 131.995135 -217.955431)
			(xy 131.987036 -217.904293) (xy 131.986528 -217.878406) (xy 131.987062 -217.850698) (xy 131.996255 -217.796051)
			(xy 132.004816 -217.769694) (xy 132.01269 -217.747596) (xy 131.807712 -217.392504) (xy 131.784852 -217.388186)
			(xy 131.759996 -217.383069) (xy 131.712148 -217.366166) (xy 131.667456 -217.342128) (xy 131.626977 -217.311523)
			(xy 131.591667 -217.275076) (xy 131.562361 -217.233647) (xy 131.539752 -217.188215) (xy 131.524374 -217.139855)
			(xy 131.51659 -217.089709) (xy 131.51612 -217.064336) (xy 130.295904 -217.064336) (xy 130.295289 -217.091989)
			(xy 130.285969 -217.146507) (xy 130.277362 -217.172794) (xy 130.269742 -217.194892) (xy 130.474974 -217.550238)
			(xy 130.497834 -217.554556) (xy 130.522641 -217.559728) (xy 130.570379 -217.576721) (xy 130.614956 -217.600818)
			(xy 130.65532 -217.631451) (xy 130.690523 -217.6679) (xy 130.719734 -217.709305) (xy 130.742266 -217.754693)
			(xy 130.757589 -217.802993) (xy 130.765341 -217.85307) (xy 130.765804 -217.878406) (xy 130.765296 -217.904293)
			(xy 130.757197 -217.955431) (xy 130.741198 -218.004671) (xy 130.717692 -218.050803) (xy 130.68726 -218.09269)
			(xy 130.65065 -218.1293) (xy 130.608763 -218.159732) (xy 130.562631 -218.183238) (xy 130.513391 -218.199237)
			(xy 130.462253 -218.207336) (xy 130.410479 -218.207336) (xy 130.359341 -218.199237) (xy 130.310101 -218.183238)
			(xy 130.263969 -218.159732) (xy 130.222082 -218.1293) (xy 130.185472 -218.09269) (xy 130.15504 -218.050803)
			(xy 130.131534 -218.004671) (xy 130.115535 -217.955431) (xy 130.107436 -217.904293) (xy 130.106928 -217.878406)
			(xy 130.107462 -217.850698) (xy 130.116655 -217.796051) (xy 130.125216 -217.769694) (xy 130.13309 -217.747596)
			(xy 129.928112 -217.392504) (xy 129.905252 -217.388186) (xy 129.880396 -217.383069) (xy 129.832548 -217.366166)
			(xy 129.787856 -217.342128) (xy 129.747377 -217.311523) (xy 129.712067 -217.275076) (xy 129.682761 -217.233647)
			(xy 129.660152 -217.188215) (xy 129.644774 -217.139855) (xy 129.63699 -217.089709) (xy 129.63652 -217.064336)
			(xy 128.416304 -217.064336) (xy 128.415701 -217.091991) (xy 128.406385 -217.146511) (xy 128.397762 -217.172794)
			(xy 128.390142 -217.194892) (xy 128.595374 -217.550238) (xy 128.618234 -217.554556) (xy 128.643033 -217.559756)
			(xy 128.690767 -217.576747) (xy 128.73534 -217.600842) (xy 128.775701 -217.631473) (xy 128.810901 -217.667918)
			(xy 128.840109 -217.70932) (xy 128.86264 -217.754704) (xy 128.877961 -217.803) (xy 128.885712 -217.853072)
			(xy 128.886204 -217.878406) (xy 128.885696 -217.904293) (xy 128.877597 -217.955431) (xy 128.861598 -218.004671)
			(xy 128.838092 -218.050803) (xy 128.80766 -218.09269) (xy 128.77105 -218.1293) (xy 128.729163 -218.159732)
			(xy 128.683031 -218.183238) (xy 128.633791 -218.199237) (xy 128.582653 -218.207336) (xy 128.530879 -218.207336)
			(xy 128.479741 -218.199237) (xy 128.430501 -218.183238) (xy 128.384369 -218.159732) (xy 128.342482 -218.1293)
			(xy 128.305872 -218.09269) (xy 128.27544 -218.050803) (xy 128.251934 -218.004671) (xy 128.235935 -217.955431)
			(xy 128.227836 -217.904293) (xy 128.227328 -217.878406) (xy 128.227857 -217.850698) (xy 128.237055 -217.796052)
			(xy 128.245616 -217.769694) (xy 128.25349 -217.747596) (xy 128.048512 -217.392504) (xy 128.025652 -217.388186)
			(xy 128.007872 -217.384376) (xy 127.992835 -217.38125) (xy 127.962195 -217.383159) (xy 127.933502 -217.394076)
			(xy 127.909344 -217.413019) (xy 127.891897 -217.438279) (xy 127.882735 -217.467579) (xy 127.882142 -217.482928)
			(xy 127.882142 -217.682826) (xy 127.89727 -217.704206) (xy 127.921279 -217.750751) (xy 127.937629 -217.800505)
			(xy 127.945907 -217.852219) (xy 127.945906 -217.904591) (xy 127.937626 -217.956304) (xy 127.921275 -218.006058)
			(xy 127.897264 -218.052602) (xy 127.882142 -218.073986) (xy 127.882142 -218.692222) (xy 128.69672 -218.692222)
			(xy 128.697245 -218.666878) (xy 128.705014 -218.616789) (xy 128.720357 -218.56848) (xy 128.742912 -218.523087)
			(xy 128.772149 -218.481681) (xy 128.807378 -218.445236) (xy 128.847769 -218.414613) (xy 128.89237 -218.390531)
			(xy 128.940132 -218.373559) (xy 128.964944 -218.368372) (xy 128.987804 -218.364054) (xy 129.193036 -218.008708)
			(xy 129.185162 -217.98661) (xy 129.176694 -217.960366) (xy 129.167624 -217.905977) (xy 129.167128 -217.878406)
			(xy 129.167636 -217.852519) (xy 129.175735 -217.801381) (xy 129.191734 -217.752141) (xy 129.21524 -217.706009)
			(xy 129.245672 -217.664122) (xy 129.282282 -217.627512) (xy 129.324169 -217.59708) (xy 129.370301 -217.573574)
			(xy 129.419541 -217.557575) (xy 129.470679 -217.549476) (xy 129.522453 -217.549476) (xy 129.573591 -217.557575)
			(xy 129.622831 -217.573574) (xy 129.668963 -217.59708) (xy 129.71085 -217.627512) (xy 129.74746 -217.664122)
			(xy 129.777892 -217.706009) (xy 129.801398 -217.752141) (xy 129.817397 -217.801381) (xy 129.825496 -217.852519)
			(xy 129.826004 -217.878406) (xy 129.825531 -217.90378) (xy 129.817762 -217.953931) (xy 129.802393 -218.002296)
			(xy 129.779788 -218.047732) (xy 129.750482 -218.089163) (xy 129.715168 -218.125609) (xy 129.674682 -218.156208)
			(xy 129.629982 -218.180235) (xy 129.582126 -218.197122) (xy 129.557272 -218.202256) (xy 129.534412 -218.206574)
			(xy 129.329688 -218.561412) (xy 129.337562 -218.583256) (xy 129.346214 -218.609662) (xy 129.35553 -218.66444)
			(xy 129.356104 -218.692222) (xy 130.57632 -218.692222) (xy 130.576845 -218.666878) (xy 130.584614 -218.616789)
			(xy 130.599957 -218.56848) (xy 130.622512 -218.523087) (xy 130.651749 -218.481681) (xy 130.686978 -218.445236)
			(xy 130.727369 -218.414613) (xy 130.77197 -218.390531) (xy 130.819732 -218.373559) (xy 130.844544 -218.368372)
			(xy 130.867404 -218.364054) (xy 131.072636 -218.008708) (xy 131.064762 -217.98661) (xy 131.056294 -217.960366)
			(xy 131.047224 -217.905977) (xy 131.046728 -217.878406) (xy 131.047236 -217.852519) (xy 131.055335 -217.801381)
			(xy 131.071334 -217.752141) (xy 131.09484 -217.706009) (xy 131.125272 -217.664122) (xy 131.161882 -217.627512)
			(xy 131.203769 -217.59708) (xy 131.249901 -217.573574) (xy 131.299141 -217.557575) (xy 131.350279 -217.549476)
			(xy 131.402053 -217.549476) (xy 131.453191 -217.557575) (xy 131.502431 -217.573574) (xy 131.548563 -217.59708)
			(xy 131.59045 -217.627512) (xy 131.62706 -217.664122) (xy 131.657492 -217.706009) (xy 131.680998 -217.752141)
			(xy 131.696997 -217.801381) (xy 131.705096 -217.852519) (xy 131.705604 -217.878406) (xy 131.705131 -217.90378)
			(xy 131.697362 -217.953931) (xy 131.681993 -218.002296) (xy 131.659388 -218.047732) (xy 131.630082 -218.089163)
			(xy 131.594768 -218.125609) (xy 131.554282 -218.156208) (xy 131.509582 -218.180235) (xy 131.461726 -218.197122)
			(xy 131.436872 -218.202256) (xy 131.414012 -218.206574) (xy 131.209288 -218.561412) (xy 131.217162 -218.583256)
			(xy 131.225814 -218.609662) (xy 131.23513 -218.66444) (xy 131.235704 -218.692222) (xy 132.45592 -218.692222)
			(xy 132.456445 -218.666878) (xy 132.464214 -218.616789) (xy 132.479557 -218.56848) (xy 132.502112 -218.523087)
			(xy 132.531349 -218.481681) (xy 132.566578 -218.445236) (xy 132.606969 -218.414613) (xy 132.65157 -218.390531)
			(xy 132.699332 -218.373559) (xy 132.724144 -218.368372) (xy 132.747004 -218.364054) (xy 132.952236 -218.008708)
			(xy 132.944362 -217.98661) (xy 132.935894 -217.960366) (xy 132.926824 -217.905977) (xy 132.926328 -217.878406)
			(xy 132.926836 -217.852519) (xy 132.934935 -217.801381) (xy 132.950934 -217.752141) (xy 132.97444 -217.706009)
			(xy 133.004872 -217.664122) (xy 133.041482 -217.627512) (xy 133.083369 -217.59708) (xy 133.129501 -217.573574)
			(xy 133.178741 -217.557575) (xy 133.229879 -217.549476) (xy 133.281653 -217.549476) (xy 133.332791 -217.557575)
			(xy 133.382031 -217.573574) (xy 133.428163 -217.59708) (xy 133.47005 -217.627512) (xy 133.50666 -217.664122)
			(xy 133.537092 -217.706009) (xy 133.560598 -217.752141) (xy 133.576597 -217.801381) (xy 133.584696 -217.852519)
			(xy 133.585204 -217.878406) (xy 133.584731 -217.90378) (xy 133.576962 -217.953931) (xy 133.561593 -218.002296)
			(xy 133.538988 -218.047732) (xy 133.509682 -218.089163) (xy 133.474368 -218.125609) (xy 133.433882 -218.156208)
			(xy 133.389182 -218.180235) (xy 133.341326 -218.197122) (xy 133.316472 -218.202256) (xy 133.293612 -218.206574)
			(xy 133.088888 -218.561412) (xy 133.096762 -218.583256) (xy 133.105414 -218.609662) (xy 133.11473 -218.66444)
			(xy 133.115304 -218.692222) (xy 133.114796 -218.718129) (xy 133.10669 -218.769306) (xy 133.090678 -218.818585)
			(xy 133.067155 -218.864752) (xy 133.036699 -218.906671) (xy 133.000061 -218.943309) (xy 132.958142 -218.973765)
			(xy 132.911975 -218.997288) (xy 132.862696 -219.0133) (xy 132.811519 -219.021406) (xy 132.759705 -219.021406)
			(xy 132.708528 -219.0133) (xy 132.659249 -218.997288) (xy 132.613082 -218.973765) (xy 132.571163 -218.943309)
			(xy 132.534525 -218.906671) (xy 132.504069 -218.864752) (xy 132.480546 -218.818585) (xy 132.464534 -218.769306)
			(xy 132.456428 -218.718129) (xy 132.45592 -218.692222) (xy 131.235704 -218.692222) (xy 131.235196 -218.718129)
			(xy 131.22709 -218.769306) (xy 131.211078 -218.818585) (xy 131.187555 -218.864752) (xy 131.157099 -218.906671)
			(xy 131.120461 -218.943309) (xy 131.078542 -218.973765) (xy 131.032375 -218.997288) (xy 130.983096 -219.0133)
			(xy 130.931919 -219.021406) (xy 130.880105 -219.021406) (xy 130.828928 -219.0133) (xy 130.779649 -218.997288)
			(xy 130.733482 -218.973765) (xy 130.691563 -218.943309) (xy 130.654925 -218.906671) (xy 130.624469 -218.864752)
			(xy 130.600946 -218.818585) (xy 130.584934 -218.769306) (xy 130.576828 -218.718129) (xy 130.57632 -218.692222)
			(xy 129.356104 -218.692222) (xy 129.355596 -218.718129) (xy 129.34749 -218.769306) (xy 129.331478 -218.818585)
			(xy 129.307955 -218.864752) (xy 129.277499 -218.906671) (xy 129.240861 -218.943309) (xy 129.198942 -218.973765)
			(xy 129.152775 -218.997288) (xy 129.103496 -219.0133) (xy 129.052319 -219.021406) (xy 129.000505 -219.021406)
			(xy 128.949328 -219.0133) (xy 128.900049 -218.997288) (xy 128.853882 -218.973765) (xy 128.811963 -218.943309)
			(xy 128.775325 -218.906671) (xy 128.744869 -218.864752) (xy 128.721346 -218.818585) (xy 128.705334 -218.769306)
			(xy 128.697228 -218.718129) (xy 128.69672 -218.692222) (xy 127.882142 -218.692222) (xy 127.882142 -219.312744)
			(xy 127.896977 -219.33392) (xy 127.9205 -219.379959) (xy 127.936512 -219.429118) (xy 127.944615 -219.48018)
			(xy 127.944611 -219.531881) (xy 127.936497 -219.582941) (xy 127.920476 -219.632098) (xy 127.896944 -219.678133)
			(xy 127.882142 -219.699332) (xy 127.882142 -219.901262) (xy 127.882666 -219.916626) (xy 127.891798 -219.945964)
			(xy 127.909246 -219.971257) (xy 127.933429 -219.990212) (xy 127.962157 -220.001113) (xy 127.992827 -220.002973)
			(xy 128.007872 -219.999814) (xy 128.027251 -219.995371) (xy 128.066731 -219.990659) (xy 128.086612 -219.990416)
			(xy 128.112506 -219.990924) (xy 128.163656 -219.999024) (xy 128.212911 -220.015021) (xy 128.259059 -220.038523)
			(xy 128.300964 -220.068951) (xy 128.337597 -220.105558) (xy 128.368055 -220.147441) (xy 128.391589 -220.193573)
			(xy 128.407622 -220.242816) (xy 128.415757 -220.293961) (xy 128.416304 -220.319854) (xy 129.63652 -220.319854)
			(xy 129.637028 -220.293947) (xy 129.645134 -220.24277) (xy 129.661146 -220.193491) (xy 129.684669 -220.147324)
			(xy 129.715125 -220.105405) (xy 129.751763 -220.068767) (xy 129.793682 -220.038311) (xy 129.839849 -220.014788)
			(xy 129.889128 -219.998776) (xy 129.940305 -219.99067) (xy 129.992119 -219.99067) (xy 130.043296 -219.998776)
			(xy 130.092575 -220.014788) (xy 130.138742 -220.038311) (xy 130.180661 -220.068767) (xy 130.217299 -220.105405)
			(xy 130.247755 -220.147324) (xy 130.271278 -220.193491) (xy 130.28729 -220.24277) (xy 130.295396 -220.293947)
			(xy 130.295904 -220.319854) (xy 131.51612 -220.319854) (xy 131.516628 -220.293947) (xy 131.524734 -220.24277)
			(xy 131.540746 -220.193491) (xy 131.564269 -220.147324) (xy 131.594725 -220.105405) (xy 131.631363 -220.068767)
			(xy 131.673282 -220.038311) (xy 131.719449 -220.014788) (xy 131.768728 -219.998776) (xy 131.819905 -219.99067)
			(xy 131.871719 -219.99067) (xy 131.922896 -219.998776) (xy 131.972175 -220.014788) (xy 132.018342 -220.038311)
			(xy 132.060261 -220.068767) (xy 132.096899 -220.105405) (xy 132.127355 -220.147324) (xy 132.150878 -220.193491)
			(xy 132.16689 -220.24277) (xy 132.174996 -220.293947) (xy 132.175504 -220.319854) (xy 133.396228 -220.319854)
			(xy 133.396736 -220.293967) (xy 133.404835 -220.242829) (xy 133.420834 -220.193589) (xy 133.44434 -220.147457)
			(xy 133.474772 -220.10557) (xy 133.511382 -220.06896) (xy 133.553269 -220.038528) (xy 133.599401 -220.015022)
			(xy 133.648641 -219.999023) (xy 133.699779 -219.990924) (xy 133.751553 -219.990924) (xy 133.802691 -219.999023)
			(xy 133.851931 -220.015022) (xy 133.898063 -220.038528) (xy 133.93995 -220.06896) (xy 133.97656 -220.10557)
			(xy 134.006992 -220.147457) (xy 134.030498 -220.193589) (xy 134.046497 -220.242829) (xy 134.054596 -220.293967)
			(xy 134.055104 -220.319854) (xy 134.054563 -220.347562) (xy 134.045375 -220.402208) (xy 134.036816 -220.428566)
			(xy 134.029196 -220.450664) (xy 134.234174 -220.805756) (xy 134.257034 -220.810074) (xy 134.281845 -220.815229)
			(xy 134.329584 -220.832223) (xy 134.374162 -220.856322) (xy 134.414527 -220.886957) (xy 134.44973 -220.923408)
			(xy 134.47894 -220.964816) (xy 134.501472 -221.010206) (xy 134.516792 -221.058509) (xy 134.524542 -221.108587)
			(xy 134.525004 -221.133924) (xy 134.524496 -221.159811) (xy 134.516397 -221.210949) (xy 134.500398 -221.260189)
			(xy 134.476892 -221.306321) (xy 134.44646 -221.348208) (xy 134.40985 -221.384818) (xy 134.367963 -221.41525)
			(xy 134.321831 -221.438756) (xy 134.272591 -221.454755) (xy 134.221453 -221.462854) (xy 134.169679 -221.462854)
			(xy 134.118541 -221.454755) (xy 134.069301 -221.438756) (xy 134.023169 -221.41525) (xy 133.981282 -221.384818)
			(xy 133.944672 -221.348208) (xy 133.91424 -221.306321) (xy 133.890734 -221.260189) (xy 133.874735 -221.210949)
			(xy 133.866636 -221.159811) (xy 133.866128 -221.133924) (xy 133.866667 -221.106216) (xy 133.875856 -221.05157)
			(xy 133.884416 -221.025212) (xy 133.89229 -221.003114) (xy 133.687312 -220.648022) (xy 133.664452 -220.643704)
			(xy 133.639631 -220.638536) (xy 133.591852 -220.621582) (xy 133.547233 -220.59751) (xy 133.506826 -220.56689)
			(xy 133.471585 -220.530444) (xy 133.442341 -220.48903) (xy 133.419784 -220.443627) (xy 133.404447 -220.395304)
			(xy 133.39669 -220.345203) (xy 133.396228 -220.319854) (xy 132.175504 -220.319854) (xy 132.174894 -220.347507)
			(xy 132.165571 -220.402025) (xy 132.156962 -220.428312) (xy 132.149342 -220.45041) (xy 132.354574 -220.805756)
			(xy 132.377434 -220.810074) (xy 132.402245 -220.815229) (xy 132.449984 -220.832223) (xy 132.494562 -220.856322)
			(xy 132.534927 -220.886957) (xy 132.57013 -220.923408) (xy 132.59934 -220.964816) (xy 132.621872 -221.010206)
			(xy 132.637192 -221.058509) (xy 132.644942 -221.108587) (xy 132.645404 -221.133924) (xy 132.644896 -221.159811)
			(xy 132.636797 -221.210949) (xy 132.620798 -221.260189) (xy 132.597292 -221.306321) (xy 132.56686 -221.348208)
			(xy 132.53025 -221.384818) (xy 132.488363 -221.41525) (xy 132.442231 -221.438756) (xy 132.392991 -221.454755)
			(xy 132.341853 -221.462854) (xy 132.290079 -221.462854) (xy 132.238941 -221.454755) (xy 132.189701 -221.438756)
			(xy 132.143569 -221.41525) (xy 132.101682 -221.384818) (xy 132.065072 -221.348208) (xy 132.03464 -221.306321)
			(xy 132.011134 -221.260189) (xy 131.995135 -221.210949) (xy 131.987036 -221.159811) (xy 131.986528 -221.133924)
			(xy 131.987067 -221.106216) (xy 131.996256 -221.05157) (xy 132.004816 -221.025212) (xy 132.01269 -221.003114)
			(xy 131.807712 -220.648022) (xy 131.784852 -220.643704) (xy 131.76 -220.63857) (xy 131.712153 -220.621668)
			(xy 131.667462 -220.597632) (xy 131.626984 -220.567029) (xy 131.591674 -220.530584) (xy 131.562368 -220.489157)
			(xy 131.539757 -220.443728) (xy 131.524377 -220.39537) (xy 131.516591 -220.345226) (xy 131.51612 -220.319854)
			(xy 130.295904 -220.319854) (xy 130.295294 -220.347507) (xy 130.285971 -220.402025) (xy 130.277362 -220.428312)
			(xy 130.269742 -220.45041) (xy 130.474974 -220.805756) (xy 130.497834 -220.810074) (xy 130.522645 -220.815229)
			(xy 130.570384 -220.832223) (xy 130.614962 -220.856322) (xy 130.655327 -220.886957) (xy 130.69053 -220.923408)
			(xy 130.71974 -220.964816) (xy 130.742272 -221.010206) (xy 130.757592 -221.058509) (xy 130.765342 -221.108587)
			(xy 130.765804 -221.133924) (xy 130.765296 -221.159811) (xy 130.757197 -221.210949) (xy 130.741198 -221.260189)
			(xy 130.717692 -221.306321) (xy 130.68726 -221.348208) (xy 130.65065 -221.384818) (xy 130.608763 -221.41525)
			(xy 130.562631 -221.438756) (xy 130.513391 -221.454755) (xy 130.462253 -221.462854) (xy 130.410479 -221.462854)
			(xy 130.359341 -221.454755) (xy 130.310101 -221.438756) (xy 130.263969 -221.41525) (xy 130.222082 -221.384818)
			(xy 130.185472 -221.348208) (xy 130.15504 -221.306321) (xy 130.131534 -221.260189) (xy 130.115535 -221.210949)
			(xy 130.107436 -221.159811) (xy 130.106928 -221.133924) (xy 130.107467 -221.106216) (xy 130.116656 -221.05157)
			(xy 130.125216 -221.025212) (xy 130.13309 -221.003114) (xy 129.928112 -220.648022) (xy 129.905252 -220.643704)
			(xy 129.8804 -220.63857) (xy 129.832553 -220.621668) (xy 129.787862 -220.597632) (xy 129.747384 -220.567029)
			(xy 129.712074 -220.530584) (xy 129.682768 -220.489157) (xy 129.660157 -220.443728) (xy 129.644777 -220.39537)
			(xy 129.636991 -220.345226) (xy 129.63652 -220.319854) (xy 128.416304 -220.319854) (xy 128.415699 -220.347508)
			(xy 128.406381 -220.402028) (xy 128.397762 -220.428312) (xy 128.390142 -220.45041) (xy 128.595374 -220.805756)
			(xy 128.618234 -220.810074) (xy 128.643033 -220.815274) (xy 128.690766 -220.832266) (xy 128.735337 -220.856361)
			(xy 128.775696 -220.886992) (xy 128.810894 -220.923438) (xy 128.8401 -220.96484) (xy 128.862628 -221.010223)
			(xy 128.877947 -221.058519) (xy 128.885696 -221.10859) (xy 128.886204 -221.133924) (xy 128.885696 -221.159811)
			(xy 128.877597 -221.210949) (xy 128.861598 -221.260189) (xy 128.838092 -221.306321) (xy 128.80766 -221.348208)
			(xy 128.77105 -221.384818) (xy 128.729163 -221.41525) (xy 128.683031 -221.438756) (xy 128.633791 -221.454755)
			(xy 128.582653 -221.462854) (xy 128.530879 -221.462854) (xy 128.479741 -221.454755) (xy 128.430501 -221.438756)
			(xy 128.384369 -221.41525) (xy 128.342482 -221.384818) (xy 128.305872 -221.348208) (xy 128.27544 -221.306321)
			(xy 128.251934 -221.260189) (xy 128.235935 -221.210949) (xy 128.227836 -221.159811) (xy 128.227328 -221.133924)
			(xy 128.227855 -221.106216) (xy 128.23705 -221.051569) (xy 128.245616 -221.025212) (xy 128.25349 -221.003114)
			(xy 128.048512 -220.648022) (xy 128.025652 -220.643704) (xy 128.007872 -220.639894) (xy 127.992836 -220.636768)
			(xy 127.962197 -220.638677) (xy 127.933507 -220.649595) (xy 127.909351 -220.668538) (xy 127.891908 -220.693798)
			(xy 127.88275 -220.723098) (xy 127.882142 -220.738446) (xy 127.882142 -220.938344) (xy 127.897268 -220.959724)
			(xy 127.921275 -221.006268) (xy 127.937622 -221.056022) (xy 127.945898 -221.107734) (xy 127.945894 -221.160104)
			(xy 127.937612 -221.211816) (xy 127.92126 -221.261568) (xy 127.897248 -221.308109) (xy 127.882142 -221.329504)
			(xy 127.882142 -221.94774) (xy 128.69672 -221.94774) (xy 128.697171 -221.922394) (xy 128.704952 -221.872302)
			(xy 128.720306 -221.82399) (xy 128.742872 -221.778597) (xy 128.772118 -221.737192) (xy 128.807355 -221.700749)
			(xy 128.847754 -221.670127) (xy 128.892362 -221.646047) (xy 128.94013 -221.629076) (xy 128.964944 -221.62389)
			(xy 128.987804 -221.619572) (xy 129.193036 -221.264226) (xy 129.185162 -221.242128) (xy 129.176698 -221.215883)
			(xy 129.167625 -221.161495) (xy 129.167128 -221.133924) (xy 129.167636 -221.108037) (xy 129.175735 -221.056899)
			(xy 129.191734 -221.007659) (xy 129.21524 -220.961527) (xy 129.245672 -220.91964) (xy 129.282282 -220.88303)
			(xy 129.324169 -220.852598) (xy 129.370301 -220.829092) (xy 129.419541 -220.813093) (xy 129.470679 -220.804994)
			(xy 129.522453 -220.804994) (xy 129.573591 -220.813093) (xy 129.622831 -220.829092) (xy 129.668963 -220.852598)
			(xy 129.71085 -220.88303) (xy 129.74746 -220.91964) (xy 129.777892 -220.961527) (xy 129.801398 -221.007659)
			(xy 129.817397 -221.056899) (xy 129.825496 -221.108037) (xy 129.826004 -221.133924) (xy 129.825548 -221.159299)
			(xy 129.817776 -221.20945) (xy 129.802404 -221.257815) (xy 129.779797 -221.303251) (xy 129.750489 -221.344682)
			(xy 129.715173 -221.381128) (xy 129.674685 -221.411727) (xy 129.629984 -221.435754) (xy 129.582126 -221.452641)
			(xy 129.557272 -221.457774) (xy 129.534412 -221.462092) (xy 129.329688 -221.81693) (xy 129.337562 -221.838774)
			(xy 129.346219 -221.865179) (xy 129.355532 -221.919958) (xy 129.356104 -221.94774) (xy 130.57632 -221.94774)
			(xy 130.576771 -221.922394) (xy 130.584552 -221.872302) (xy 130.599906 -221.82399) (xy 130.622472 -221.778597)
			(xy 130.651718 -221.737192) (xy 130.686955 -221.700749) (xy 130.727354 -221.670127) (xy 130.771962 -221.646047)
			(xy 130.81973 -221.629076) (xy 130.844544 -221.62389) (xy 130.867404 -221.619572) (xy 131.072636 -221.264226)
			(xy 131.064762 -221.242128) (xy 131.056298 -221.215883) (xy 131.047225 -221.161495) (xy 131.046728 -221.133924)
			(xy 131.047236 -221.108037) (xy 131.055335 -221.056899) (xy 131.071334 -221.007659) (xy 131.09484 -220.961527)
			(xy 131.125272 -220.91964) (xy 131.161882 -220.88303) (xy 131.203769 -220.852598) (xy 131.249901 -220.829092)
			(xy 131.299141 -220.813093) (xy 131.350279 -220.804994) (xy 131.402053 -220.804994) (xy 131.453191 -220.813093)
			(xy 131.502431 -220.829092) (xy 131.548563 -220.852598) (xy 131.59045 -220.88303) (xy 131.62706 -220.91964)
			(xy 131.657492 -220.961527) (xy 131.680998 -221.007659) (xy 131.696997 -221.056899) (xy 131.705096 -221.108037)
			(xy 131.705604 -221.133924) (xy 131.705148 -221.159299) (xy 131.697376 -221.20945) (xy 131.682004 -221.257815)
			(xy 131.659397 -221.303251) (xy 131.630089 -221.344682) (xy 131.594773 -221.381128) (xy 131.554285 -221.411727)
			(xy 131.509584 -221.435754) (xy 131.461726 -221.452641) (xy 131.436872 -221.457774) (xy 131.414012 -221.462092)
			(xy 131.209288 -221.81693) (xy 131.217162 -221.838774) (xy 131.225819 -221.865179) (xy 131.235132 -221.919958)
			(xy 131.235704 -221.94774) (xy 132.45592 -221.94774) (xy 132.456371 -221.922394) (xy 132.464152 -221.872302)
			(xy 132.479506 -221.82399) (xy 132.502072 -221.778597) (xy 132.531318 -221.737192) (xy 132.566555 -221.700749)
			(xy 132.606954 -221.670127) (xy 132.651562 -221.646047) (xy 132.69933 -221.629076) (xy 132.724144 -221.62389)
			(xy 132.747004 -221.619572) (xy 132.951982 -221.263972) (xy 132.944362 -221.242128) (xy 132.935911 -221.215946)
			(xy 132.92684 -221.161685) (xy 132.926328 -221.134178) (xy 132.926328 -221.133924) (xy 132.926836 -221.108037)
			(xy 132.934935 -221.056899) (xy 132.950934 -221.007659) (xy 132.97444 -220.961527) (xy 133.004872 -220.91964)
			(xy 133.041482 -220.88303) (xy 133.083369 -220.852598) (xy 133.129501 -220.829092) (xy 133.178741 -220.813093)
			(xy 133.229879 -220.804994) (xy 133.281653 -220.804994) (xy 133.332791 -220.813093) (xy 133.382031 -220.829092)
			(xy 133.428163 -220.852598) (xy 133.47005 -220.88303) (xy 133.50666 -220.91964) (xy 133.537092 -220.961527)
			(xy 133.560598 -221.007659) (xy 133.576597 -221.056899) (xy 133.584696 -221.108037) (xy 133.585204 -221.133924)
			(xy 133.584785 -221.15929) (xy 133.577033 -221.209425) (xy 133.561684 -221.257778) (xy 133.539102 -221.303206)
			(xy 133.509821 -221.344633) (xy 133.474533 -221.381081) (xy 133.434074 -221.411686) (xy 133.3894 -221.435725)
			(xy 133.341569 -221.45263) (xy 133.316726 -221.457774) (xy 133.293866 -221.462092) (xy 133.089142 -221.81693)
			(xy 133.096762 -221.838774) (xy 133.105377 -221.865059) (xy 133.114698 -221.919578) (xy 133.115304 -221.947232)
			(xy 133.115304 -221.94774) (xy 134.33552 -221.94774) (xy 134.335971 -221.922394) (xy 134.343752 -221.872302)
			(xy 134.359106 -221.82399) (xy 134.381672 -221.778597) (xy 134.410918 -221.737192) (xy 134.446155 -221.700749)
			(xy 134.486554 -221.670127) (xy 134.531162 -221.646047) (xy 134.57893 -221.629076) (xy 134.603744 -221.62389)
			(xy 134.626604 -221.619572) (xy 134.831582 -221.263972) (xy 134.823962 -221.242128) (xy 134.815511 -221.215946)
			(xy 134.80644 -221.161685) (xy 134.805928 -221.134178) (xy 134.805928 -221.133924) (xy 134.806436 -221.108037)
			(xy 134.814535 -221.056899) (xy 134.830534 -221.007659) (xy 134.85404 -220.961527) (xy 134.884472 -220.91964)
			(xy 134.921082 -220.88303) (xy 134.962969 -220.852598) (xy 135.009101 -220.829092) (xy 135.058341 -220.813093)
			(xy 135.109479 -220.804994) (xy 135.161253 -220.804994) (xy 135.212391 -220.813093) (xy 135.261631 -220.829092)
			(xy 135.307763 -220.852598) (xy 135.34965 -220.88303) (xy 135.38626 -220.91964) (xy 135.416692 -220.961527)
			(xy 135.440198 -221.007659) (xy 135.456197 -221.056899) (xy 135.464296 -221.108037) (xy 135.464804 -221.133924)
			(xy 135.464385 -221.15929) (xy 135.456633 -221.209425) (xy 135.441284 -221.257778) (xy 135.418702 -221.303206)
			(xy 135.389421 -221.344633) (xy 135.354133 -221.381081) (xy 135.313674 -221.411686) (xy 135.269 -221.435725)
			(xy 135.221169 -221.45263) (xy 135.196326 -221.457774) (xy 135.173466 -221.462092) (xy 134.968742 -221.81693)
			(xy 134.976362 -221.838774) (xy 134.984977 -221.865059) (xy 134.994298 -221.919578) (xy 134.994904 -221.947232)
			(xy 134.994904 -221.94774) (xy 134.994396 -221.973647) (xy 134.98629 -222.024824) (xy 134.970278 -222.074103)
			(xy 134.946755 -222.12027) (xy 134.916299 -222.162189) (xy 134.879661 -222.198827) (xy 134.837742 -222.229283)
			(xy 134.791575 -222.252806) (xy 134.742296 -222.268818) (xy 134.691119 -222.276924) (xy 134.639305 -222.276924)
			(xy 134.588128 -222.268818) (xy 134.538849 -222.252806) (xy 134.492682 -222.229283) (xy 134.450763 -222.198827)
			(xy 134.414125 -222.162189) (xy 134.383669 -222.12027) (xy 134.360146 -222.074103) (xy 134.344134 -222.024824)
			(xy 134.336028 -221.973647) (xy 134.33552 -221.94774) (xy 133.115304 -221.94774) (xy 133.114796 -221.973647)
			(xy 133.10669 -222.024824) (xy 133.090678 -222.074103) (xy 133.067155 -222.12027) (xy 133.036699 -222.162189)
			(xy 133.000061 -222.198827) (xy 132.958142 -222.229283) (xy 132.911975 -222.252806) (xy 132.862696 -222.268818)
			(xy 132.811519 -222.276924) (xy 132.759705 -222.276924) (xy 132.708528 -222.268818) (xy 132.659249 -222.252806)
			(xy 132.613082 -222.229283) (xy 132.571163 -222.198827) (xy 132.534525 -222.162189) (xy 132.504069 -222.12027)
			(xy 132.480546 -222.074103) (xy 132.464534 -222.024824) (xy 132.456428 -221.973647) (xy 132.45592 -221.94774)
			(xy 131.235704 -221.94774) (xy 131.235196 -221.973647) (xy 131.22709 -222.024824) (xy 131.211078 -222.074103)
			(xy 131.187555 -222.12027) (xy 131.157099 -222.162189) (xy 131.120461 -222.198827) (xy 131.078542 -222.229283)
			(xy 131.032375 -222.252806) (xy 130.983096 -222.268818) (xy 130.931919 -222.276924) (xy 130.880105 -222.276924)
			(xy 130.828928 -222.268818) (xy 130.779649 -222.252806) (xy 130.733482 -222.229283) (xy 130.691563 -222.198827)
			(xy 130.654925 -222.162189) (xy 130.624469 -222.12027) (xy 130.600946 -222.074103) (xy 130.584934 -222.024824)
			(xy 130.576828 -221.973647) (xy 130.57632 -221.94774) (xy 129.356104 -221.94774) (xy 129.355596 -221.973647)
			(xy 129.34749 -222.024824) (xy 129.331478 -222.074103) (xy 129.307955 -222.12027) (xy 129.277499 -222.162189)
			(xy 129.240861 -222.198827) (xy 129.198942 -222.229283) (xy 129.152775 -222.252806) (xy 129.103496 -222.268818)
			(xy 129.052319 -222.276924) (xy 129.000505 -222.276924) (xy 128.949328 -222.268818) (xy 128.900049 -222.252806)
			(xy 128.853882 -222.229283) (xy 128.811963 -222.198827) (xy 128.775325 -222.162189) (xy 128.744869 -222.12027)
			(xy 128.721346 -222.074103) (xy 128.705334 -222.024824) (xy 128.697228 -221.973647) (xy 128.69672 -221.94774)
			(xy 127.882142 -221.94774) (xy 127.882142 -222.568262) (xy 127.896983 -222.589438) (xy 127.92052 -222.635479)
			(xy 127.936544 -222.684642) (xy 127.944659 -222.73571) (xy 127.944664 -222.787419) (xy 127.93656 -222.838488)
			(xy 127.920547 -222.887655) (xy 127.897021 -222.933702) (xy 127.882142 -222.95485) (xy 127.882142 -223.157034)
			(xy 127.882663 -223.172401) (xy 127.89179 -223.201747) (xy 127.909236 -223.227047) (xy 127.933422 -223.246008)
			(xy 127.962155 -223.256913) (xy 127.992831 -223.258772) (xy 128.007872 -223.255586) (xy 128.027251 -223.251143)
			(xy 128.066731 -223.246432) (xy 128.086612 -223.246188) (xy 128.112507 -223.246696) (xy 128.163659 -223.254795)
			(xy 128.212915 -223.270792) (xy 128.259065 -223.294293) (xy 128.300973 -223.324721) (xy 128.337608 -223.361327)
			(xy 128.368069 -223.403211) (xy 128.391608 -223.449342) (xy 128.407644 -223.498586) (xy 128.415784 -223.549732)
			(xy 128.416304 -223.575626) (xy 128.415829 -223.600984) (xy 128.408044 -223.651099) (xy 128.392676 -223.699431)
			(xy 128.370088 -223.744839) (xy 128.340813 -223.786253) (xy 128.305542 -223.822696) (xy 128.265106 -223.853307)
			(xy 128.22046 -223.877366) (xy 128.172655 -223.894304) (xy 128.147826 -223.899476) (xy 128.124966 -223.903794)
			(xy 127.920242 -224.258632) (xy 127.928116 -224.280476) (xy 127.936696 -224.306895) (xy 127.945893 -224.36167)
			(xy 127.946404 -224.389442) (xy 128.227328 -224.389442) (xy 128.227836 -224.363555) (xy 128.235935 -224.312417)
			(xy 128.251934 -224.263177) (xy 128.27544 -224.217045) (xy 128.305872 -224.175158) (xy 128.342482 -224.138548)
			(xy 128.384369 -224.108116) (xy 128.430501 -224.08461) (xy 128.479741 -224.068611) (xy 128.530879 -224.060512)
			(xy 128.582653 -224.060512) (xy 128.633791 -224.068611) (xy 128.683031 -224.08461) (xy 128.729163 -224.108116)
			(xy 128.77105 -224.138548) (xy 128.80766 -224.175158) (xy 128.838092 -224.217045) (xy 128.861598 -224.263177)
			(xy 128.877597 -224.312417) (xy 128.885696 -224.363555) (xy 128.886204 -224.389442) (xy 129.167128 -224.389442)
			(xy 129.167535 -224.364105) (xy 129.175297 -224.314028) (xy 129.190629 -224.265728) (xy 129.21317 -224.220343)
			(xy 129.242389 -224.17894) (xy 129.277599 -224.142496) (xy 129.31797 -224.111867) (xy 129.362552 -224.087776)
			(xy 129.410295 -224.070789) (xy 129.435098 -224.065592) (xy 129.457958 -224.061274) (xy 129.662682 -223.706436)
			(xy 129.655062 -223.684338) (xy 129.646431 -223.657991) (xy 129.63711 -223.603344) (xy 129.63652 -223.575626)
			(xy 129.637028 -223.549719) (xy 129.645134 -223.498542) (xy 129.661146 -223.449263) (xy 129.684669 -223.403096)
			(xy 129.715125 -223.361177) (xy 129.751763 -223.324539) (xy 129.793682 -223.294083) (xy 129.839849 -223.27056)
			(xy 129.889128 -223.254548) (xy 129.940305 -223.246442) (xy 129.992119 -223.246442) (xy 130.043296 -223.254548)
			(xy 130.092575 -223.27056) (xy 130.138742 -223.294083) (xy 130.180661 -223.324539) (xy 130.217299 -223.361177)
			(xy 130.247755 -223.403096) (xy 130.271278 -223.449263) (xy 130.28729 -223.498542) (xy 130.295396 -223.549719)
			(xy 130.295904 -223.575626) (xy 130.295487 -223.600992) (xy 130.287734 -223.651127) (xy 130.272385 -223.69948)
			(xy 130.249803 -223.744908) (xy 130.220522 -223.786336) (xy 130.185234 -223.822783) (xy 130.144775 -223.853388)
			(xy 130.100101 -223.877427) (xy 130.052269 -223.894332) (xy 130.027426 -223.899476) (xy 130.004566 -223.903794)
			(xy 129.799842 -224.258632) (xy 129.807716 -224.280476) (xy 129.81629 -224.306896) (xy 129.82549 -224.36167)
			(xy 129.826004 -224.389442) (xy 130.106928 -224.389442) (xy 130.107436 -224.363555) (xy 130.115535 -224.312417)
			(xy 130.131534 -224.263177) (xy 130.15504 -224.217045) (xy 130.185472 -224.175158) (xy 130.222082 -224.138548)
			(xy 130.263969 -224.108116) (xy 130.310101 -224.08461) (xy 130.359341 -224.068611) (xy 130.410479 -224.060512)
			(xy 130.462253 -224.060512) (xy 130.513391 -224.068611) (xy 130.562631 -224.08461) (xy 130.608763 -224.108116)
			(xy 130.65065 -224.138548) (xy 130.68726 -224.175158) (xy 130.717692 -224.217045) (xy 130.741198 -224.263177)
			(xy 130.757197 -224.312417) (xy 130.765296 -224.363555) (xy 130.765804 -224.389442) (xy 131.046728 -224.389442)
			(xy 131.047135 -224.364105) (xy 131.054897 -224.314028) (xy 131.070229 -224.265728) (xy 131.09277 -224.220343)
			(xy 131.121989 -224.17894) (xy 131.157199 -224.142496) (xy 131.19757 -224.111867) (xy 131.242152 -224.087776)
			(xy 131.289895 -224.070789) (xy 131.314698 -224.065592) (xy 131.337558 -224.061274) (xy 131.542282 -223.706182)
			(xy 131.534662 -223.684338) (xy 131.526017 -223.657995) (xy 131.516704 -223.603345) (xy 131.51612 -223.575626)
			(xy 131.516628 -223.549719) (xy 131.524734 -223.498542) (xy 131.540746 -223.449263) (xy 131.564269 -223.403096)
			(xy 131.594725 -223.361177) (xy 131.631363 -223.324539) (xy 131.673282 -223.294083) (xy 131.719449 -223.27056)
			(xy 131.768728 -223.254548) (xy 131.819905 -223.246442) (xy 131.871719 -223.246442) (xy 131.922896 -223.254548)
			(xy 131.972175 -223.27056) (xy 132.018342 -223.294083) (xy 132.060261 -223.324539) (xy 132.096899 -223.361177)
			(xy 132.127355 -223.403096) (xy 132.150878 -223.449263) (xy 132.16689 -223.498542) (xy 132.174996 -223.549719)
			(xy 132.175504 -223.575626) (xy 132.175003 -223.60097) (xy 132.167228 -223.651059) (xy 132.151879 -223.699368)
			(xy 132.12932 -223.74476) (xy 132.10008 -223.786165) (xy 132.064849 -223.822609) (xy 132.024457 -223.853232)
			(xy 131.979854 -223.877314) (xy 131.932092 -223.894288) (xy 131.90728 -223.899476) (xy 131.88442 -223.903794)
			(xy 131.679696 -224.258632) (xy 131.687316 -224.280476) (xy 131.695872 -224.306769) (xy 131.705065 -224.361289)
			(xy 131.705604 -224.388934) (xy 131.705604 -224.389442) (xy 131.986528 -224.389442) (xy 131.987036 -224.363555)
			(xy 131.995135 -224.312417) (xy 132.011134 -224.263177) (xy 132.03464 -224.217045) (xy 132.065072 -224.175158)
			(xy 132.101682 -224.138548) (xy 132.143569 -224.108116) (xy 132.189701 -224.08461) (xy 132.238941 -224.068611)
			(xy 132.290079 -224.060512) (xy 132.341853 -224.060512) (xy 132.392991 -224.068611) (xy 132.442231 -224.08461)
			(xy 132.488363 -224.108116) (xy 132.53025 -224.138548) (xy 132.56686 -224.175158) (xy 132.597292 -224.217045)
			(xy 132.620798 -224.263177) (xy 132.636797 -224.312417) (xy 132.644896 -224.363555) (xy 132.645404 -224.389442)
			(xy 132.926328 -224.389442) (xy 132.926735 -224.364105) (xy 132.934497 -224.314028) (xy 132.949829 -224.265728)
			(xy 132.97237 -224.220343) (xy 133.001589 -224.17894) (xy 133.036799 -224.142496) (xy 133.07717 -224.111867)
			(xy 133.121752 -224.087776) (xy 133.169495 -224.070789) (xy 133.194298 -224.065592) (xy 133.217158 -224.061274)
			(xy 133.422136 -223.705928) (xy 133.414516 -223.684084) (xy 133.405965 -223.657789) (xy 133.396771 -223.603271)
			(xy 133.396228 -223.575626) (xy 133.396736 -223.549739) (xy 133.404835 -223.498601) (xy 133.420834 -223.449361)
			(xy 133.44434 -223.403229) (xy 133.474772 -223.361342) (xy 133.511382 -223.324732) (xy 133.553269 -223.2943)
			(xy 133.599401 -223.270794) (xy 133.648641 -223.254795) (xy 133.699779 -223.246696) (xy 133.751553 -223.246696)
			(xy 133.802691 -223.254795) (xy 133.851931 -223.270794) (xy 133.898063 -223.2943) (xy 133.93995 -223.324732)
			(xy 133.97656 -223.361342) (xy 134.006992 -223.403229) (xy 134.030498 -223.449361) (xy 134.046497 -223.498601)
			(xy 134.054596 -223.549739) (xy 134.055104 -223.575626) (xy 134.054603 -223.60097) (xy 134.046828 -223.651059)
			(xy 134.031479 -223.699368) (xy 134.00892 -223.74476) (xy 133.97968 -223.786165) (xy 133.944449 -223.822609)
			(xy 133.904057 -223.853232) (xy 133.859454 -223.877314) (xy 133.811692 -223.894288) (xy 133.78688 -223.899476)
			(xy 133.76402 -223.903794) (xy 133.559296 -224.258632) (xy 133.566916 -224.280476) (xy 133.575472 -224.306769)
			(xy 133.584665 -224.361289) (xy 133.585204 -224.388934) (xy 133.585204 -224.389442) (xy 133.866128 -224.389442)
			(xy 133.866636 -224.363555) (xy 133.874735 -224.312417) (xy 133.890734 -224.263177) (xy 133.91424 -224.217045)
			(xy 133.944672 -224.175158) (xy 133.981282 -224.138548) (xy 134.023169 -224.108116) (xy 134.069301 -224.08461)
			(xy 134.118541 -224.068611) (xy 134.169679 -224.060512) (xy 134.221453 -224.060512) (xy 134.272591 -224.068611)
			(xy 134.321831 -224.08461) (xy 134.367963 -224.108116) (xy 134.40985 -224.138548) (xy 134.44646 -224.175158)
			(xy 134.476892 -224.217045) (xy 134.500398 -224.263177) (xy 134.516397 -224.312417) (xy 134.524496 -224.363555)
			(xy 134.525004 -224.389442) (xy 134.524474 -224.41715) (xy 134.515275 -224.471796) (xy 134.506716 -224.498154)
			(xy 134.499096 -224.519998) (xy 134.704074 -224.87509) (xy 134.726934 -224.879408) (xy 134.751752 -224.884531)
			(xy 134.799495 -224.901528) (xy 134.844074 -224.925629) (xy 134.88444 -224.956269) (xy 134.919643 -224.992724)
			(xy 134.948852 -225.034136) (xy 134.971381 -225.07953) (xy 134.986699 -225.127837) (xy 134.994445 -225.177919)
			(xy 134.994904 -225.203258) (xy 134.994396 -225.229145) (xy 134.986297 -225.280283) (xy 134.970298 -225.329523)
			(xy 134.946792 -225.375655) (xy 134.91636 -225.417542) (xy 134.87975 -225.454152) (xy 134.837863 -225.484584)
			(xy 134.791731 -225.50809) (xy 134.742491 -225.524089) (xy 134.691353 -225.532188) (xy 134.639579 -225.532188)
			(xy 134.588441 -225.524089) (xy 134.539201 -225.50809) (xy 134.493069 -225.484584) (xy 134.451182 -225.454152)
			(xy 134.414572 -225.417542) (xy 134.38414 -225.375655) (xy 134.360634 -225.329523) (xy 134.344635 -225.280283)
			(xy 134.336536 -225.229145) (xy 134.336028 -225.203258) (xy 134.336028 -225.20275) (xy 134.336589 -225.175107)
			(xy 134.345778 -225.120589) (xy 134.354316 -225.094292) (xy 134.361936 -225.072448) (xy 134.157212 -224.71761)
			(xy 134.134352 -224.713292) (xy 134.109529 -224.708135) (xy 134.061749 -224.69118) (xy 134.017129 -224.667108)
			(xy 133.976722 -224.636486) (xy 133.941481 -224.600038) (xy 133.912237 -224.558623) (xy 133.889681 -224.513218)
			(xy 133.874344 -224.464894) (xy 133.866589 -224.414792) (xy 133.866128 -224.389442) (xy 133.585204 -224.389442)
			(xy 133.584696 -224.415329) (xy 133.576597 -224.466467) (xy 133.560598 -224.515707) (xy 133.537092 -224.561839)
			(xy 133.50666 -224.603726) (xy 133.47005 -224.640336) (xy 133.428163 -224.670768) (xy 133.382031 -224.694274)
			(xy 133.332791 -224.710273) (xy 133.281653 -224.718372) (xy 133.229879 -224.718372) (xy 133.178741 -224.710273)
			(xy 133.129501 -224.694274) (xy 133.083369 -224.670768) (xy 133.041482 -224.640336) (xy 133.004872 -224.603726)
			(xy 132.97444 -224.561839) (xy 132.950934 -224.515707) (xy 132.934935 -224.466467) (xy 132.926836 -224.415329)
			(xy 132.926328 -224.389442) (xy 132.645404 -224.389442) (xy 132.64486 -224.417149) (xy 132.635674 -224.471796)
			(xy 132.627116 -224.498154) (xy 132.619242 -224.520252) (xy 132.82422 -224.87509) (xy 132.84708 -224.879408)
			(xy 132.871909 -224.884542) (xy 132.919688 -224.901501) (xy 132.964308 -224.925578) (xy 133.004714 -224.956202)
			(xy 133.039954 -224.992654) (xy 133.069197 -225.034071) (xy 133.091752 -225.079478) (xy 133.107088 -225.127804)
			(xy 133.114843 -225.177908) (xy 133.115304 -225.203258) (xy 133.114796 -225.229165) (xy 133.10669 -225.280342)
			(xy 133.090678 -225.329621) (xy 133.067155 -225.375788) (xy 133.036699 -225.417707) (xy 133.000061 -225.454345)
			(xy 132.958142 -225.484801) (xy 132.911975 -225.508324) (xy 132.862696 -225.524336) (xy 132.811519 -225.532442)
			(xy 132.759705 -225.532442) (xy 132.708528 -225.524336) (xy 132.659249 -225.508324) (xy 132.613082 -225.484801)
			(xy 132.571163 -225.454345) (xy 132.534525 -225.417707) (xy 132.504069 -225.375788) (xy 132.480546 -225.329621)
			(xy 132.464534 -225.280342) (xy 132.456428 -225.229165) (xy 132.45592 -225.203258) (xy 132.456527 -225.175541)
			(xy 132.465842 -225.120895) (xy 132.474462 -225.094546) (xy 132.482336 -225.072448) (xy 132.277358 -224.71761)
			(xy 132.254498 -224.713292) (xy 132.229685 -224.708145) (xy 132.181943 -224.691153) (xy 132.137363 -224.667056)
			(xy 132.096996 -224.63642) (xy 132.061793 -224.599968) (xy 132.032582 -224.558558) (xy 132.010052 -224.513166)
			(xy 131.994734 -224.46486) (xy 131.986988 -224.41478) (xy 131.986528 -224.389442) (xy 131.705604 -224.389442)
			(xy 131.705096 -224.415329) (xy 131.696997 -224.466467) (xy 131.680998 -224.515707) (xy 131.657492 -224.561839)
			(xy 131.62706 -224.603726) (xy 131.59045 -224.640336) (xy 131.548563 -224.670768) (xy 131.502431 -224.694274)
			(xy 131.453191 -224.710273) (xy 131.402053 -224.718372) (xy 131.350279 -224.718372) (xy 131.299141 -224.710273)
			(xy 131.249901 -224.694274) (xy 131.203769 -224.670768) (xy 131.161882 -224.640336) (xy 131.125272 -224.603726)
			(xy 131.09484 -224.561839) (xy 131.071334 -224.515707) (xy 131.055335 -224.466467) (xy 131.047236 -224.415329)
			(xy 131.046728 -224.389442) (xy 130.765804 -224.389442) (xy 130.76526 -224.417149) (xy 130.756074 -224.471796)
			(xy 130.747516 -224.498154) (xy 130.739642 -224.520252) (xy 130.94462 -224.87509) (xy 130.96748 -224.879408)
			(xy 130.992309 -224.884542) (xy 131.040088 -224.901501) (xy 131.084708 -224.925578) (xy 131.125114 -224.956202)
			(xy 131.160354 -224.992654) (xy 131.189597 -225.034071) (xy 131.212152 -225.079478) (xy 131.227488 -225.127804)
			(xy 131.235243 -225.177908) (xy 131.235704 -225.203258) (xy 131.235196 -225.229165) (xy 131.22709 -225.280342)
			(xy 131.211078 -225.329621) (xy 131.187555 -225.375788) (xy 131.157099 -225.417707) (xy 131.120461 -225.454345)
			(xy 131.078542 -225.484801) (xy 131.032375 -225.508324) (xy 130.983096 -225.524336) (xy 130.931919 -225.532442)
			(xy 130.880105 -225.532442) (xy 130.828928 -225.524336) (xy 130.779649 -225.508324) (xy 130.733482 -225.484801)
			(xy 130.691563 -225.454345) (xy 130.654925 -225.417707) (xy 130.624469 -225.375788) (xy 130.600946 -225.329621)
			(xy 130.584934 -225.280342) (xy 130.576828 -225.229165) (xy 130.57632 -225.203258) (xy 130.576927 -225.175541)
			(xy 130.586242 -225.120895) (xy 130.594862 -225.094546) (xy 130.602736 -225.072448) (xy 130.397758 -224.71761)
			(xy 130.374898 -224.713292) (xy 130.350085 -224.708145) (xy 130.302343 -224.691153) (xy 130.257763 -224.667056)
			(xy 130.217396 -224.63642) (xy 130.182193 -224.599968) (xy 130.152982 -224.558558) (xy 130.130452 -224.513166)
			(xy 130.115134 -224.46486) (xy 130.107388 -224.41478) (xy 130.106928 -224.389442) (xy 129.826004 -224.389442)
			(xy 129.825496 -224.415329) (xy 129.817397 -224.466467) (xy 129.801398 -224.515707) (xy 129.777892 -224.561839)
			(xy 129.74746 -224.603726) (xy 129.71085 -224.640336) (xy 129.668963 -224.670768) (xy 129.622831 -224.694274)
			(xy 129.573591 -224.710273) (xy 129.522453 -224.718372) (xy 129.470679 -224.718372) (xy 129.419541 -224.710273)
			(xy 129.370301 -224.694274) (xy 129.324169 -224.670768) (xy 129.282282 -224.640336) (xy 129.245672 -224.603726)
			(xy 129.21524 -224.561839) (xy 129.191734 -224.515707) (xy 129.175735 -224.466467) (xy 129.167636 -224.415329)
			(xy 129.167128 -224.389442) (xy 128.886204 -224.389442) (xy 128.88566 -224.417149) (xy 128.876474 -224.471796)
			(xy 128.867916 -224.498154) (xy 128.860042 -224.520252) (xy 129.06502 -224.87509) (xy 129.08788 -224.879408)
			(xy 129.112709 -224.884542) (xy 129.160488 -224.901501) (xy 129.205108 -224.925578) (xy 129.245514 -224.956202)
			(xy 129.280754 -224.992654) (xy 129.309997 -225.034071) (xy 129.332552 -225.079478) (xy 129.347888 -225.127804)
			(xy 129.355643 -225.177908) (xy 129.356104 -225.203258) (xy 129.355596 -225.229165) (xy 129.34749 -225.280342)
			(xy 129.331478 -225.329621) (xy 129.307955 -225.375788) (xy 129.277499 -225.417707) (xy 129.240861 -225.454345)
			(xy 129.198942 -225.484801) (xy 129.152775 -225.508324) (xy 129.103496 -225.524336) (xy 129.052319 -225.532442)
			(xy 129.000505 -225.532442) (xy 128.949328 -225.524336) (xy 128.900049 -225.508324) (xy 128.853882 -225.484801)
			(xy 128.811963 -225.454345) (xy 128.775325 -225.417707) (xy 128.744869 -225.375788) (xy 128.721346 -225.329621)
			(xy 128.705334 -225.280342) (xy 128.697228 -225.229165) (xy 128.69672 -225.203258) (xy 128.697327 -225.175541)
			(xy 128.706642 -225.120895) (xy 128.715262 -225.094546) (xy 128.723136 -225.072448) (xy 128.518158 -224.71761)
			(xy 128.495298 -224.713292) (xy 128.470485 -224.708145) (xy 128.422743 -224.691153) (xy 128.378163 -224.667056)
			(xy 128.337796 -224.63642) (xy 128.302593 -224.599968) (xy 128.273382 -224.558558) (xy 128.250852 -224.513166)
			(xy 128.235534 -224.46486) (xy 128.227788 -224.41478) (xy 128.227328 -224.389442) (xy 127.946404 -224.389442)
			(xy 127.945898 -224.415627) (xy 127.937615 -224.467338) (xy 127.921264 -224.51709) (xy 127.897256 -224.563633)
			(xy 127.882142 -224.585022) (xy 127.882142 -225.336354) (xy 128.32588 -225.780092) (xy 128.360932 -225.75393)
			(xy 128.382307 -225.7387) (xy 128.428882 -225.714515) (xy 128.478711 -225.698044) (xy 128.530526 -225.689708)
			(xy 128.556766 -225.68916) (xy 128.582557 -225.689637) (xy 128.633503 -225.697702) (xy 128.682561 -225.713638)
			(xy 128.728521 -225.737053) (xy 128.770252 -225.76737) (xy 128.806726 -225.803843) (xy 128.837044 -225.845574)
			(xy 128.86046 -225.891533) (xy 128.876397 -225.940591) (xy 128.884463 -225.991537) (xy 128.884934 -226.017328)
			(xy 128.884417 -226.043569) (xy 128.876067 -226.095383) (xy 128.859583 -226.145209) (xy 128.835385 -226.19178)
			(xy 128.820164 -226.213162) (xy 128.794002 -226.248214) (xy 129.049018 -226.50323) (xy 129.066544 -226.505516)
			(xy 129.090865 -226.508949) (xy 129.138175 -226.522149) (xy 129.182988 -226.542258) (xy 129.2243 -226.568826)
			(xy 129.261188 -226.601257) (xy 129.292826 -226.638827) (xy 129.318508 -226.680695) (xy 129.337658 -226.725926)
			(xy 129.344166 -226.74961) (xy 129.354072 -226.78771) (xy 129.638552 -226.78771) (xy 129.648458 -226.74961)
			(xy 129.655243 -226.725037) (xy 129.675364 -226.6782) (xy 129.702489 -226.63504) (xy 129.735965 -226.596597)
			(xy 129.774986 -226.563796) (xy 129.818611 -226.537426) (xy 129.865791 -226.518124) (xy 129.91539 -226.506353)
			(xy 129.966212 -226.502398) (xy 130.017034 -226.506353) (xy 130.066633 -226.518124) (xy 130.113813 -226.537426)
			(xy 130.157438 -226.563796) (xy 130.196459 -226.596597) (xy 130.229935 -226.63504) (xy 130.25706 -226.6782)
			(xy 130.277181 -226.725037) (xy 130.283966 -226.74961) (xy 130.293872 -226.78771) (xy 130.578606 -226.78771)
			(xy 130.588512 -226.74961) (xy 130.595297 -226.725037) (xy 130.615418 -226.6782) (xy 130.642543 -226.63504)
			(xy 130.676019 -226.596597) (xy 130.71504 -226.563796) (xy 130.758665 -226.537426) (xy 130.805845 -226.518124)
			(xy 130.855444 -226.506353) (xy 130.906266 -226.502398) (xy 130.957088 -226.506353) (xy 131.006687 -226.518124)
			(xy 131.053867 -226.537426) (xy 131.097492 -226.563796) (xy 131.136513 -226.596597) (xy 131.169989 -226.63504)
			(xy 131.197114 -226.6782) (xy 131.217235 -226.725037) (xy 131.22402 -226.74961) (xy 131.233926 -226.78771)
			(xy 131.518152 -226.78771) (xy 131.528058 -226.74961) (xy 131.534843 -226.725037) (xy 131.554964 -226.6782)
			(xy 131.582089 -226.63504) (xy 131.615565 -226.596597) (xy 131.654586 -226.563796) (xy 131.698211 -226.537426)
			(xy 131.745391 -226.518124) (xy 131.79499 -226.506353) (xy 131.845812 -226.502398) (xy 131.896634 -226.506353)
			(xy 131.946233 -226.518124) (xy 131.993413 -226.537426) (xy 132.037038 -226.563796) (xy 132.076059 -226.596597)
			(xy 132.109535 -226.63504) (xy 132.13666 -226.6782) (xy 132.156781 -226.725037) (xy 132.163566 -226.74961)
			(xy 132.173472 -226.78771) (xy 132.606542 -226.78771) (xy 132.631497 -226.788326) (xy 132.680446 -226.79807)
			(xy 132.726554 -226.817177) (xy 132.768048 -226.844912) (xy 132.78612 -226.862132) (xy 133.240526 -227.316538)
			(xy 133.2611 -227.316792) (xy 133.28635 -227.317664) (xy 133.336144 -227.32621) (xy 133.384041 -227.342285)
			(xy 133.428909 -227.365509) (xy 133.469689 -227.395333) (xy 133.505418 -227.431054) (xy 133.535251 -227.471827)
			(xy 133.558485 -227.51669) (xy 133.574571 -227.564583) (xy 133.583129 -227.614375) (xy 133.583934 -227.639626)
			(xy 133.584188 -227.6602) (xy 134.934452 -229.010464) (xy 134.968234 -228.990398) (xy 134.993735 -228.97607)
			(xy 135.048559 -228.955694) (xy 135.106122 -228.94534) (xy 135.135366 -228.944678) (xy 135.161156 -228.945155)
			(xy 135.212102 -228.95322) (xy 135.261158 -228.969157) (xy 135.307117 -228.992572) (xy 135.348846 -229.02289)
			(xy 135.385318 -229.059363) (xy 135.415634 -229.101093) (xy 135.439048 -229.147053) (xy 135.454983 -229.19611)
			(xy 135.463046 -229.247056) (xy 135.463534 -229.272846) (xy 135.462899 -229.302092) (xy 135.452548 -229.359661)
			(xy 135.432162 -229.414486) (xy 135.417814 -229.439978) (xy 135.397748 -229.47376) (xy 135.694674 -229.770686)
			(xy 135.706358 -229.774496) (xy 135.730795 -229.782914) (xy 135.776863 -229.806342) (xy 135.81869 -229.836701)
			(xy 135.85524 -229.873241) (xy 135.885611 -229.915059) (xy 135.909051 -229.961121) (xy 135.917432 -229.98557)
			(xy 135.921242 -229.997254) (xy 135.987536 -230.063548) (xy 136.21512 -230.063548) (xy 136.223248 -230.022654)
			(xy 136.228603 -229.998161) (xy 136.24575 -229.951049) (xy 136.269864 -229.907094) (xy 136.300384 -229.867318)
			(xy 136.336599 -229.832649) (xy 136.377667 -229.803892) (xy 136.422632 -229.781718) (xy 136.470447 -229.766642)
			(xy 136.519998 -229.759015) (xy 136.570134 -229.759015) (xy 136.619685 -229.766642) (xy 136.6675 -229.781718)
			(xy 136.712465 -229.803892) (xy 136.753533 -229.832649) (xy 136.789748 -229.867318) (xy 136.820268 -229.907094)
			(xy 136.844382 -229.951049) (xy 136.861529 -229.998161) (xy 136.866884 -230.022654) (xy 136.875012 -230.063548)
			(xy 139.03452 -230.063548) (xy 139.042648 -230.022654) (xy 139.048003 -229.998161) (xy 139.06515 -229.951049)
			(xy 139.089264 -229.907094) (xy 139.119784 -229.867318) (xy 139.155999 -229.832649) (xy 139.197067 -229.803892)
			(xy 139.242032 -229.781718) (xy 139.289847 -229.766642) (xy 139.339398 -229.759015) (xy 139.389534 -229.759015)
			(xy 139.439085 -229.766642) (xy 139.4869 -229.781718) (xy 139.531865 -229.803892) (xy 139.572933 -229.832649)
			(xy 139.609148 -229.867318) (xy 139.639668 -229.907094) (xy 139.663782 -229.951049) (xy 139.680929 -229.998161)
			(xy 139.686284 -230.022654) (xy 139.694412 -230.063548) (xy 140.813536 -230.063548) (xy 140.838495 -230.064123)
			(xy 140.887451 -230.073869) (xy 140.933566 -230.092981) (xy 140.975065 -230.120722) (xy 140.993114 -230.13797)
			(xy 141.816836 -230.961692) (xy 141.834092 -230.979734) (xy 141.861842 -231.021229) (xy 141.880947 -231.067347)
			(xy 141.890671 -231.11631) (xy 141.891258 -231.14127) (xy 141.891258 -251.76988) (xy 143.715496 -251.76988)
			(xy 143.719477 -251.63686) (xy 143.731406 -251.504315) (xy 143.751241 -251.372722) (xy 143.77891 -251.24255)
			(xy 143.814314 -251.114265) (xy 143.857327 -250.988328) (xy 143.907794 -250.865189) (xy 143.965535 -250.745288)
			(xy 144.030344 -250.629055) (xy 144.101988 -250.516905) (xy 144.18021 -250.409241) (xy 144.264731 -250.306448)
			(xy 144.355249 -250.208893) (xy 144.451438 -250.116927) (xy 144.552956 -250.030877) (xy 144.659437 -249.951053)
			(xy 144.770502 -249.87774) (xy 144.885753 -249.8112) (xy 145.004777 -249.751671) (xy 145.127148 -249.699367)
			(xy 145.252427 -249.654475) (xy 145.380168 -249.617156) (xy 145.509911 -249.587543) (xy 145.641193 -249.565742)
			(xy 145.773544 -249.551832) (xy 145.90649 -249.545861) (xy 146.039555 -249.547852) (xy 146.172263 -249.557797)
			(xy 146.304139 -249.575661) (xy 146.43471 -249.601379) (xy 146.56351 -249.63486) (xy 146.690076 -249.675984)
			(xy 146.813957 -249.724604) (xy 146.934708 -249.780545) (xy 147.051898 -249.843607) (xy 147.165107 -249.913565)
			(xy 147.273929 -249.990169) (xy 147.377975 -250.073143) (xy 147.476873 -250.162191) (xy 147.570268 -250.256994)
			(xy 147.657826 -250.357212) (xy 147.739235 -250.462488) (xy 147.814201 -250.572444) (xy 147.882458 -250.686686)
			(xy 147.94376 -250.804806) (xy 147.997889 -250.926381) (xy 148.04465 -251.050975) (xy 148.083876 -251.178143)
			(xy 148.115426 -251.307429) (xy 148.139189 -251.43837) (xy 148.155078 -251.570498) (xy 148.163036 -251.70334)
			(xy 148.163534 -251.76988) (xy 148.163036 -251.83642) (xy 148.155078 -251.969262) (xy 148.139189 -252.10139)
			(xy 148.115426 -252.232331) (xy 148.083876 -252.361617) (xy 148.04465 -252.488785) (xy 147.997889 -252.613379)
			(xy 147.94376 -252.734954) (xy 147.882458 -252.853074) (xy 147.814201 -252.967316) (xy 147.739235 -253.077272)
			(xy 147.657826 -253.182548) (xy 147.570268 -253.282766) (xy 147.476873 -253.377569) (xy 147.377975 -253.466617)
			(xy 147.273929 -253.549591) (xy 147.165107 -253.626195) (xy 147.051898 -253.696153) (xy 146.934708 -253.759215)
			(xy 146.813957 -253.815156) (xy 146.690076 -253.863776) (xy 146.56351 -253.9049) (xy 146.43471 -253.938381)
			(xy 146.304139 -253.964099) (xy 146.172263 -253.981963) (xy 146.039555 -253.991908) (xy 145.90649 -253.993899)
			(xy 145.773544 -253.987928) (xy 145.641193 -253.974018) (xy 145.509911 -253.952217) (xy 145.380168 -253.922604)
			(xy 145.252427 -253.885285) (xy 145.127148 -253.840393) (xy 145.004777 -253.788089) (xy 144.885753 -253.72856)
			(xy 144.770502 -253.66202) (xy 144.659437 -253.588707) (xy 144.552956 -253.508883) (xy 144.451438 -253.422833)
			(xy 144.355249 -253.330867) (xy 144.264731 -253.233312) (xy 144.18021 -253.130519) (xy 144.101988 -253.022855)
			(xy 144.030344 -252.910705) (xy 143.965535 -252.794472) (xy 143.907794 -252.674571) (xy 143.857327 -252.551432)
			(xy 143.814314 -252.425495) (xy 143.77891 -252.29721) (xy 143.751241 -252.167038) (xy 143.731406 -252.035445)
			(xy 143.719477 -251.9029) (xy 143.715496 -251.76988) (xy 141.891258 -251.76988) (xy 141.891258 -265.97229)
			(xy 141.890678 -265.997247) (xy 141.880923 -266.046198) (xy 141.861805 -266.092305) (xy 141.834059 -266.133797)
			(xy 141.816836 -266.151868) (xy 140.683996 -267.284708) (xy 140.665954 -267.301965) (xy 140.62446 -267.329716)
			(xy 140.578341 -267.348821) (xy 140.529378 -267.358543) (xy 140.504418 -267.35913) (xy 135.879078 -267.35913)
			(xy 134.632192 -268.606016) (xy 134.629398 -268.622272) (xy 134.624806 -268.647487) (xy 134.60883 -268.696182)
			(xy 134.585479 -268.741802) (xy 134.555319 -268.783236) (xy 134.519083 -268.819478) (xy 134.477655 -268.849646)
			(xy 134.432039 -268.873007) (xy 134.383347 -268.888991) (xy 134.358126 -268.893544) (xy 134.34187 -268.896338)
			(xy 134.07898 -269.159228) (xy 134.103618 -269.19428) (xy 134.117759 -269.215166) (xy 134.14015 -269.260361)
			(xy 134.155376 -269.308445) (xy 134.163078 -269.358291) (xy 134.163562 -269.38351) (xy 134.163056 -269.409297)
			(xy 134.154986 -269.460236) (xy 134.139048 -269.509285) (xy 134.115632 -269.555237) (xy 134.085317 -269.59696)
			(xy 134.048848 -269.633427) (xy 134.007123 -269.663741) (xy 133.96117 -269.687154) (xy 133.91212 -269.70309)
			(xy 133.861181 -269.711157) (xy 133.835394 -269.711678) (xy 133.81017 -269.711244) (xy 133.760309 -269.70357)
			(xy 133.712215 -269.688342) (xy 133.667024 -269.665922) (xy 133.646164 -269.651734) (xy 133.611112 -269.627096)
			(xy 132.280406 -270.957802) (xy 132.282692 -270.981424) (xy 132.283962 -271.011396) (xy 132.283483 -271.037186)
			(xy 132.275415 -271.08813) (xy 132.259476 -271.137185) (xy 132.23606 -271.183143) (xy 132.205742 -271.224871)
			(xy 132.16927 -271.261343) (xy 132.127541 -271.291661) (xy 132.081583 -271.315077) (xy 132.032528 -271.331015)
			(xy 131.981584 -271.339083) (xy 131.955794 -271.339564) (xy 131.93044 -271.339091) (xy 131.880335 -271.331287)
			(xy 131.832028 -271.315867) (xy 131.786669 -271.293198) (xy 131.745339 -271.263819) (xy 131.709021 -271.228431)
			(xy 131.67858 -271.187875) (xy 131.654743 -271.143119) (xy 131.645914 -271.119346) (xy 131.633976 -271.08531)
			(xy 131.337812 -271.08531) (xy 131.325874 -271.119346) (xy 131.317087 -271.143134) (xy 131.293238 -271.187885)
			(xy 131.262788 -271.228434) (xy 131.226462 -271.263816) (xy 131.185126 -271.293188) (xy 131.139763 -271.315852)
			(xy 131.091454 -271.331268) (xy 131.041349 -271.339069) (xy 130.990639 -271.339069) (xy 130.940534 -271.331268)
			(xy 130.892225 -271.315852) (xy 130.846862 -271.293188) (xy 130.805526 -271.263816) (xy 130.7692 -271.228434)
			(xy 130.73875 -271.187885) (xy 130.714901 -271.143134) (xy 130.706114 -271.119346) (xy 130.694176 -271.08531)
			(xy 130.398012 -271.08531) (xy 130.386074 -271.119346) (xy 130.377287 -271.143134) (xy 130.353438 -271.187885)
			(xy 130.322988 -271.228434) (xy 130.286662 -271.263816) (xy 130.245326 -271.293188) (xy 130.199963 -271.315852)
			(xy 130.151654 -271.331268) (xy 130.101549 -271.339069) (xy 130.050839 -271.339069) (xy 130.000734 -271.331268)
			(xy 129.952425 -271.315852) (xy 129.907062 -271.293188) (xy 129.865726 -271.263816) (xy 129.8294 -271.228434)
			(xy 129.79895 -271.187885) (xy 129.775101 -271.143134) (xy 129.766314 -271.119346) (xy 129.754376 -271.08531)
			(xy 129.458212 -271.08531) (xy 129.446274 -271.119346) (xy 129.437487 -271.143134) (xy 129.413638 -271.187885)
			(xy 129.383188 -271.228434) (xy 129.346862 -271.263816) (xy 129.305526 -271.293188) (xy 129.260163 -271.315852)
			(xy 129.211854 -271.331268) (xy 129.161749 -271.339069) (xy 129.111039 -271.339069) (xy 129.060934 -271.331268)
			(xy 129.012625 -271.315852) (xy 128.967262 -271.293188) (xy 128.925926 -271.263816) (xy 128.8896 -271.228434)
			(xy 128.85915 -271.187885) (xy 128.835301 -271.143134) (xy 128.826514 -271.119346) (xy 128.814576 -271.08531)
			(xy 128.518412 -271.08531) (xy 128.506474 -271.119346) (xy 128.497687 -271.143134) (xy 128.473838 -271.187885)
			(xy 128.443388 -271.228434) (xy 128.407062 -271.263816) (xy 128.365726 -271.293188) (xy 128.320363 -271.315852)
			(xy 128.272054 -271.331268) (xy 128.221949 -271.339069) (xy 128.171239 -271.339069) (xy 128.121134 -271.331268)
			(xy 128.072825 -271.315852) (xy 128.027462 -271.293188) (xy 127.986126 -271.263816) (xy 127.9498 -271.228434)
			(xy 127.91935 -271.187885) (xy 127.895501 -271.143134) (xy 127.886714 -271.119346) (xy 127.874776 -271.08531)
			(xy 127.578612 -271.08531) (xy 127.566674 -271.119346) (xy 127.557887 -271.143134) (xy 127.534038 -271.187885)
			(xy 127.503588 -271.228434) (xy 127.467262 -271.263816) (xy 127.425926 -271.293188) (xy 127.380563 -271.315852)
			(xy 127.332254 -271.331268) (xy 127.282149 -271.339069) (xy 127.231439 -271.339069) (xy 127.181334 -271.331268)
			(xy 127.133025 -271.315852) (xy 127.087662 -271.293188) (xy 127.046326 -271.263816) (xy 127.01 -271.228434)
			(xy 126.97955 -271.187885) (xy 126.955701 -271.143134) (xy 126.946914 -271.119346) (xy 126.934976 -271.08531)
			(xy 126.638812 -271.08531) (xy 126.626874 -271.119346) (xy 126.618087 -271.143134) (xy 126.594238 -271.187885)
			(xy 126.563788 -271.228434) (xy 126.527462 -271.263816) (xy 126.486126 -271.293188) (xy 126.440763 -271.315852)
			(xy 126.392454 -271.331268) (xy 126.342349 -271.339069) (xy 126.291639 -271.339069) (xy 126.241534 -271.331268)
			(xy 126.193225 -271.315852) (xy 126.147862 -271.293188) (xy 126.106526 -271.263816) (xy 126.0702 -271.228434)
			(xy 126.03975 -271.187885) (xy 126.015901 -271.143134) (xy 126.007114 -271.119346) (xy 125.995176 -271.08531)
			(xy 125.699012 -271.08531) (xy 125.687074 -271.119346) (xy 125.678287 -271.143134) (xy 125.654438 -271.187885)
			(xy 125.623988 -271.228434) (xy 125.587662 -271.263816) (xy 125.546326 -271.293188) (xy 125.500963 -271.315852)
			(xy 125.452654 -271.331268) (xy 125.402549 -271.339069) (xy 125.351839 -271.339069) (xy 125.301734 -271.331268)
			(xy 125.253425 -271.315852) (xy 125.208062 -271.293188) (xy 125.166726 -271.263816) (xy 125.1304 -271.228434)
			(xy 125.09995 -271.187885) (xy 125.076101 -271.143134) (xy 125.067314 -271.119346) (xy 125.055376 -271.08531)
			(xy 124.759212 -271.08531) (xy 124.747274 -271.119346) (xy 124.738487 -271.143134) (xy 124.714638 -271.187885)
			(xy 124.684188 -271.228434) (xy 124.647862 -271.263816) (xy 124.606526 -271.293188) (xy 124.561163 -271.315852)
			(xy 124.512854 -271.331268) (xy 124.462749 -271.339069) (xy 124.412039 -271.339069) (xy 124.361934 -271.331268)
			(xy 124.313625 -271.315852) (xy 124.268262 -271.293188) (xy 124.226926 -271.263816) (xy 124.1906 -271.228434)
			(xy 124.16015 -271.187885) (xy 124.136301 -271.143134) (xy 124.127514 -271.119346) (xy 124.115576 -271.08531)
			(xy 123.819412 -271.08531) (xy 123.807474 -271.119346) (xy 123.798687 -271.143134) (xy 123.774838 -271.187885)
			(xy 123.744388 -271.228434) (xy 123.708062 -271.263816) (xy 123.666726 -271.293188) (xy 123.621363 -271.315852)
			(xy 123.573054 -271.331268) (xy 123.522949 -271.339069) (xy 123.472239 -271.339069) (xy 123.422134 -271.331268)
			(xy 123.373825 -271.315852) (xy 123.328462 -271.293188) (xy 123.287126 -271.263816) (xy 123.2508 -271.228434)
			(xy 123.22035 -271.187885) (xy 123.196501 -271.143134) (xy 123.187714 -271.119346) (xy 123.175776 -271.08531)
			(xy 122.879866 -271.08531) (xy 122.867928 -271.119346) (xy 122.859141 -271.143134) (xy 122.835292 -271.187885)
			(xy 122.804842 -271.228434) (xy 122.768516 -271.263816) (xy 122.72718 -271.293188) (xy 122.681817 -271.315852)
			(xy 122.633508 -271.331268) (xy 122.583403 -271.339069) (xy 122.532693 -271.339069) (xy 122.482588 -271.331268)
			(xy 122.434279 -271.315852) (xy 122.388916 -271.293188) (xy 122.34758 -271.263816) (xy 122.311254 -271.228434)
			(xy 122.280804 -271.187885) (xy 122.256955 -271.143134) (xy 122.248168 -271.119346) (xy 122.23623 -271.08531)
			(xy 121.939812 -271.08531) (xy 121.927874 -271.119346) (xy 121.919087 -271.143134) (xy 121.895238 -271.187885)
			(xy 121.864788 -271.228434) (xy 121.828462 -271.263816) (xy 121.787126 -271.293188) (xy 121.741763 -271.315852)
			(xy 121.693454 -271.331268) (xy 121.643349 -271.339069) (xy 121.592639 -271.339069) (xy 121.542534 -271.331268)
			(xy 121.494225 -271.315852) (xy 121.448862 -271.293188) (xy 121.407526 -271.263816) (xy 121.3712 -271.228434)
			(xy 121.34075 -271.187885) (xy 121.316901 -271.143134) (xy 121.308114 -271.119346) (xy 121.296176 -271.08531)
			(xy 121.000012 -271.08531) (xy 120.988074 -271.119346) (xy 120.979289 -271.143138) (xy 120.955442 -271.187897)
			(xy 120.924994 -271.228455) (xy 120.88867 -271.263847) (xy 120.847335 -271.293232) (xy 120.801972 -271.315908)
			(xy 120.753661 -271.331338) (xy 120.703552 -271.339153) (xy 120.678194 -271.339564) (xy 120.653635 -271.339112)
			(xy 120.605064 -271.331808) (xy 120.558123 -271.317347) (xy 120.513861 -271.296054) (xy 120.473266 -271.268404)
			(xy 120.437243 -271.235013) (xy 120.406599 -271.196628) (xy 120.382015 -271.154105) (xy 120.364042 -271.108394)
			(xy 120.358154 -271.084548) (xy 120.334379 -271.085873) (xy 120.287051 -271.080684) (xy 120.241522 -271.06676)
			(xy 120.199387 -271.044591) (xy 120.162125 -271.014953) (xy 120.131043 -270.978887) (xy 120.118632 -270.958564)
			(xy 119.37111 -270.958564) (xy 118.534688 -270.122142) (xy 118.534688 -269.720822) (xy 118.511467 -269.701994)
			(xy 118.469965 -269.658969) (xy 118.434849 -269.610589) (xy 118.406803 -269.557796) (xy 118.386371 -269.501616)
			(xy 118.373951 -269.443141) (xy 118.369783 -269.383506) (xy 118.373949 -269.323871) (xy 118.386368 -269.265395)
			(xy 118.406798 -269.209215) (xy 118.434843 -269.156421) (xy 118.469957 -269.108041) (xy 118.511458 -269.065014)
			(xy 118.534688 -269.046198) (xy 118.534688 -268.09319) (xy 118.511469 -268.074362) (xy 118.469972 -268.031337)
			(xy 118.43486 -267.982959) (xy 118.406818 -267.930168) (xy 118.38639 -267.87399) (xy 118.373973 -267.815518)
			(xy 118.369808 -267.755886) (xy 118.373977 -267.696255) (xy 118.386398 -267.637783) (xy 118.406829 -267.581607)
			(xy 118.434875 -267.528818) (xy 118.469989 -267.480442) (xy 118.51149 -267.437419) (xy 118.534688 -267.418566)
			(xy 118.534688 -266.323318) (xy 118.519582 -266.302034) (xy 118.495593 -266.255684) (xy 118.479246 -266.206121)
			(xy 118.470952 -266.154595) (xy 118.470426 -266.1285) (xy 118.470953 -266.102407) (xy 118.479257 -266.050884)
			(xy 118.495608 -266.001323) (xy 118.519595 -265.954974) (xy 118.534688 -265.933682) (xy 118.534688 -264.695178)
			(xy 118.519578 -264.673896) (xy 118.495581 -264.627547) (xy 118.479225 -264.577983) (xy 118.470921 -264.526456)
			(xy 118.470426 -264.50036) (xy 118.470948 -264.474265) (xy 118.479244 -264.422738) (xy 118.495588 -264.373172)
			(xy 118.519569 -264.326817) (xy 118.534688 -264.305542) (xy 118.534688 -263.64184) (xy 118.513745 -263.627791)
			(xy 118.476038 -263.594307) (xy 118.443897 -263.555449) (xy 118.418079 -263.512131) (xy 118.39919 -263.465374)
			(xy 118.387676 -263.416278) (xy 118.383808 -263.365998) (xy 118.387677 -263.315718) (xy 118.399192 -263.266622)
			(xy 118.418081 -263.219865) (xy 118.4439 -263.176548) (xy 118.476041 -263.13769) (xy 118.513749 -263.104206)
			(xy 118.534688 -263.090152) (xy 118.534688 -260.901434) (xy 118.406164 -260.77291) (xy 116.785898 -260.77291)
			(xy 116.274342 -261.284466) (xy 116.274342 -264.356596) (xy 116.27866 -264.366502) (xy 116.287702 -264.387648)
			(xy 116.300458 -264.431834) (xy 116.306937 -264.477366) (xy 116.307362 -264.50036) (xy 116.306961 -264.523357)
			(xy 116.300497 -264.568894) (xy 116.287718 -264.613077) (xy 116.27866 -264.634218) (xy 116.274342 -264.644124)
			(xy 116.274342 -265.984482) (xy 116.27866 -265.994388) (xy 116.287703 -266.015534) (xy 116.300461 -266.05972)
			(xy 116.306941 -266.105251) (xy 116.307362 -266.128246) (xy 116.306962 -266.151243) (xy 116.300499 -266.196781)
			(xy 116.287723 -266.240964) (xy 116.27866 -266.262104) (xy 116.274342 -266.27201) (xy 116.274342 -267.612114)
			(xy 116.27866 -267.62202) (xy 116.287701 -267.643166) (xy 116.300454 -267.687352) (xy 116.306931 -267.732884)
			(xy 116.307362 -267.755878) (xy 116.306959 -267.778874) (xy 116.300493 -267.824411) (xy 116.287713 -267.868592)
			(xy 116.27866 -267.889736) (xy 116.274342 -267.899642) (xy 116.274342 -269.239746) (xy 116.27866 -269.249652)
			(xy 116.287706 -269.270797) (xy 116.300468 -269.314983) (xy 116.306953 -269.360515) (xy 116.307362 -269.38351)
			(xy 116.306964 -269.406507) (xy 116.300507 -269.452047) (xy 116.287734 -269.496233) (xy 116.27866 -269.517368)
			(xy 116.274342 -269.527274) (xy 116.274342 -270.867632) (xy 116.27866 -270.877538) (xy 116.287707 -270.898683)
			(xy 116.300471 -270.942869) (xy 116.306958 -270.988401) (xy 116.307362 -271.011396) (xy 116.306958 -271.034392)
			(xy 116.300489 -271.079927) (xy 116.287707 -271.124108) (xy 116.27866 -271.145254) (xy 116.274342 -271.15516)
			(xy 116.274342 -272.495518) (xy 116.27866 -272.505424) (xy 116.287701 -272.52657) (xy 116.300454 -272.570756)
			(xy 116.306929 -272.616288) (xy 116.307362 -272.639282) (xy 116.306959 -272.662278) (xy 116.300492 -272.707814)
			(xy 116.287711 -272.751996) (xy 116.27866 -272.77314) (xy 116.274342 -272.783046) (xy 116.274342 -274.122642)
			(xy 116.278914 -274.132548) (xy 116.287988 -274.153773) (xy 116.300772 -274.198128) (xy 116.307234 -274.243834)
			(xy 116.307616 -274.266914) (xy 116.307247 -274.289997) (xy 116.300813 -274.33571) (xy 116.288017 -274.380065)
			(xy 116.278914 -274.40128) (xy 116.274342 -274.411186) (xy 116.274342 -275.751036) (xy 116.27866 -275.760942)
			(xy 116.287706 -275.782087) (xy 116.30047 -275.826273) (xy 116.306957 -275.871805) (xy 116.307362 -275.8948)
			(xy 116.306965 -275.917798) (xy 116.300509 -275.963338) (xy 116.287738 -276.007524) (xy 116.27866 -276.028658)
			(xy 116.274342 -276.038564) (xy 116.274342 -277.377906) (xy 116.278914 -277.387812) (xy 116.287984 -277.409038)
			(xy 116.30076 -277.453393) (xy 116.307213 -277.499099) (xy 116.307616 -277.522178) (xy 116.307243 -277.545259)
			(xy 116.3008 -277.59097) (xy 116.287996 -277.635321) (xy 116.278914 -277.656544) (xy 116.274342 -277.66645)
			(xy 116.274342 -279.006554) (xy 116.27866 -279.01646) (xy 116.289328 -279.04313) (xy 116.290852 -279.047702)
			(xy 116.686076 -279.736804) (xy 116.69014 -279.741122) (xy 116.706668 -279.759642) (xy 116.734534 -279.80072)
			(xy 116.755916 -279.845517) (xy 116.763546 -279.869138) (xy 116.76507 -279.874726) (xy 117.14861 -280.543508)
			(xy 117.153182 -280.54808) (xy 117.172444 -280.568478) (xy 117.204416 -280.614574) (xy 117.228094 -280.66543)
			(xy 117.235986 -280.692352) (xy 117.237764 -280.698702) (xy 117.611398 -281.350466) (xy 117.616732 -281.355546)
			(xy 117.633241 -281.372) (xy 117.661911 -281.408748) (xy 117.685089 -281.449187) (xy 117.702306 -281.4925)
			(xy 117.708172 -281.515058) (xy 117.70995 -281.52217) (xy 118.074694 -282.158186) (xy 118.080536 -282.163774)
			(xy 118.098939 -282.181253) (xy 118.130662 -282.22087) (xy 118.155909 -282.264897) (xy 118.174076 -282.312287)
			(xy 118.17985 -282.337002) (xy 118.181628 -282.344876) (xy 118.538498 -282.967176) (xy 118.544848 -282.972764)
			(xy 118.565031 -282.991108) (xy 118.599606 -283.033284) (xy 118.626726 -283.080601) (xy 118.645642 -283.131752)
			(xy 118.651274 -283.158438) (xy 118.652798 -283.166566) (xy 119.002556 -283.77642) (xy 119.009414 -283.782262)
			(xy 119.026893 -283.797414) (xy 119.057836 -283.831797) (xy 119.083642 -283.870186) (xy 119.103801 -283.911819)
			(xy 119.117911 -283.955871) (xy 119.12219 -283.978604) (xy 119.123714 -283.987494) (xy 119.464582 -284.582362)
			(xy 119.472456 -284.588458) (xy 119.492074 -284.604459) (xy 119.526623 -284.641461) (xy 119.555095 -284.683319)
			(xy 119.576816 -284.729046) (xy 119.591274 -284.777561) (xy 119.595138 -284.80258) (xy 119.596662 -284.812486)
			(xy 119.61676 -284.847538) (xy 120.818656 -284.847538) (xy 120.819164 -284.821631) (xy 120.82727 -284.770454)
			(xy 120.843282 -284.721175) (xy 120.866805 -284.675008) (xy 120.897261 -284.633089) (xy 120.933899 -284.596451)
			(xy 120.975818 -284.565995) (xy 121.021985 -284.542472) (xy 121.071264 -284.52646) (xy 121.122441 -284.518354)
			(xy 121.174255 -284.518354) (xy 121.225432 -284.52646) (xy 121.274711 -284.542472) (xy 121.320878 -284.565995)
			(xy 121.362797 -284.596451) (xy 121.399435 -284.633089) (xy 121.429891 -284.675008) (xy 121.453414 -284.721175)
			(xy 121.469426 -284.770454) (xy 121.477532 -284.821631) (xy 121.47804 -284.847538) (xy 122.698256 -284.847538)
			(xy 122.698764 -284.821631) (xy 122.70687 -284.770454) (xy 122.722882 -284.721175) (xy 122.746405 -284.675008)
			(xy 122.776861 -284.633089) (xy 122.813499 -284.596451) (xy 122.855418 -284.565995) (xy 122.901585 -284.542472)
			(xy 122.950864 -284.52646) (xy 123.002041 -284.518354) (xy 123.053855 -284.518354) (xy 123.105032 -284.52646)
			(xy 123.154311 -284.542472) (xy 123.200478 -284.565995) (xy 123.242397 -284.596451) (xy 123.279035 -284.633089)
			(xy 123.309491 -284.675008) (xy 123.333014 -284.721175) (xy 123.349026 -284.770454) (xy 123.357132 -284.821631)
			(xy 123.35764 -284.847538) (xy 124.577856 -284.847538) (xy 124.578364 -284.821631) (xy 124.58647 -284.770454)
			(xy 124.602482 -284.721175) (xy 124.626005 -284.675008) (xy 124.656461 -284.633089) (xy 124.693099 -284.596451)
			(xy 124.735018 -284.565995) (xy 124.781185 -284.542472) (xy 124.830464 -284.52646) (xy 124.881641 -284.518354)
			(xy 124.933455 -284.518354) (xy 124.984632 -284.52646) (xy 125.033911 -284.542472) (xy 125.080078 -284.565995)
			(xy 125.121997 -284.596451) (xy 125.158635 -284.633089) (xy 125.189091 -284.675008) (xy 125.212614 -284.721175)
			(xy 125.228626 -284.770454) (xy 125.236732 -284.821631) (xy 125.23724 -284.847538) (xy 126.457456 -284.847538)
			(xy 126.457964 -284.821631) (xy 126.46607 -284.770454) (xy 126.482082 -284.721175) (xy 126.505605 -284.675008)
			(xy 126.536061 -284.633089) (xy 126.572699 -284.596451) (xy 126.614618 -284.565995) (xy 126.660785 -284.542472)
			(xy 126.710064 -284.52646) (xy 126.761241 -284.518354) (xy 126.813055 -284.518354) (xy 126.864232 -284.52646)
			(xy 126.913511 -284.542472) (xy 126.959678 -284.565995) (xy 127.001597 -284.596451) (xy 127.038235 -284.633089)
			(xy 127.068691 -284.675008) (xy 127.092214 -284.721175) (xy 127.108226 -284.770454) (xy 127.116332 -284.821631)
			(xy 127.11684 -284.847538) (xy 128.337056 -284.847538) (xy 128.337564 -284.821631) (xy 128.34567 -284.770454)
			(xy 128.361682 -284.721175) (xy 128.385205 -284.675008) (xy 128.415661 -284.633089) (xy 128.452299 -284.596451)
			(xy 128.494218 -284.565995) (xy 128.540385 -284.542472) (xy 128.589664 -284.52646) (xy 128.640841 -284.518354)
			(xy 128.692655 -284.518354) (xy 128.743832 -284.52646) (xy 128.793111 -284.542472) (xy 128.839278 -284.565995)
			(xy 128.881197 -284.596451) (xy 128.917835 -284.633089) (xy 128.948291 -284.675008) (xy 128.971814 -284.721175)
			(xy 128.987826 -284.770454) (xy 128.995932 -284.821631) (xy 128.99644 -284.847538) (xy 130.216656 -284.847538)
			(xy 130.217164 -284.821631) (xy 130.22527 -284.770454) (xy 130.241282 -284.721175) (xy 130.264805 -284.675008)
			(xy 130.295261 -284.633089) (xy 130.331899 -284.596451) (xy 130.373818 -284.565995) (xy 130.419985 -284.542472)
			(xy 130.469264 -284.52646) (xy 130.520441 -284.518354) (xy 130.572255 -284.518354) (xy 130.623432 -284.52646)
			(xy 130.672711 -284.542472) (xy 130.718878 -284.565995) (xy 130.760797 -284.596451) (xy 130.797435 -284.633089)
			(xy 130.827891 -284.675008) (xy 130.851414 -284.721175) (xy 130.867426 -284.770454) (xy 130.875532 -284.821631)
			(xy 130.87604 -284.847538) (xy 132.096256 -284.847538) (xy 132.096764 -284.821631) (xy 132.10487 -284.770454)
			(xy 132.120882 -284.721175) (xy 132.144405 -284.675008) (xy 132.174861 -284.633089) (xy 132.211499 -284.596451)
			(xy 132.253418 -284.565995) (xy 132.299585 -284.542472) (xy 132.348864 -284.52646) (xy 132.400041 -284.518354)
			(xy 132.451855 -284.518354) (xy 132.503032 -284.52646) (xy 132.552311 -284.542472) (xy 132.598478 -284.565995)
			(xy 132.640397 -284.596451) (xy 132.677035 -284.633089) (xy 132.707491 -284.675008) (xy 132.731014 -284.721175)
			(xy 132.747026 -284.770454) (xy 132.755132 -284.821631) (xy 132.75564 -284.847538) (xy 132.755034 -284.875255)
			(xy 132.745719 -284.929901) (xy 132.737098 -284.95625) (xy 132.729224 -284.978348) (xy 132.934202 -285.333186)
			(xy 132.957062 -285.337504) (xy 132.981868 -285.342683) (xy 133.02961 -285.359669) (xy 133.07419 -285.383762)
			(xy 133.114558 -285.414393) (xy 133.149763 -285.450841) (xy 133.178975 -285.492247) (xy 133.201506 -285.537636)
			(xy 133.216825 -285.585939) (xy 133.224572 -285.636017) (xy 133.225032 -285.661354) (xy 133.224524 -285.687241)
			(xy 133.216425 -285.738379) (xy 133.200426 -285.787619) (xy 133.17692 -285.833751) (xy 133.146488 -285.875638)
			(xy 133.109878 -285.912248) (xy 133.067991 -285.94268) (xy 133.021859 -285.966186) (xy 132.972619 -285.982185)
			(xy 132.921481 -285.990284) (xy 132.869707 -285.990284) (xy 132.818569 -285.982185) (xy 132.769329 -285.966186)
			(xy 132.723197 -285.94268) (xy 132.68131 -285.912248) (xy 132.6447 -285.875638) (xy 132.614268 -285.833751)
			(xy 132.590762 -285.787619) (xy 132.574763 -285.738379) (xy 132.566664 -285.687241) (xy 132.566156 -285.661354)
			(xy 132.566701 -285.633647) (xy 132.575886 -285.579) (xy 132.584444 -285.552642) (xy 132.592318 -285.530544)
			(xy 132.38734 -285.175706) (xy 132.36448 -285.171388) (xy 132.33966 -285.166215) (xy 132.29188 -285.149263)
			(xy 132.247259 -285.125194) (xy 132.206851 -285.094575) (xy 132.171609 -285.058129) (xy 132.142365 -285.016715)
			(xy 132.119809 -284.971312) (xy 132.104472 -284.922989) (xy 132.096717 -284.872887) (xy 132.096256 -284.847538)
			(xy 130.87604 -284.847538) (xy 130.875434 -284.875255) (xy 130.866119 -284.929901) (xy 130.857498 -284.95625)
			(xy 130.849624 -284.978348) (xy 131.054602 -285.333186) (xy 131.077462 -285.337504) (xy 131.102268 -285.342683)
			(xy 131.15001 -285.359669) (xy 131.19459 -285.383762) (xy 131.234958 -285.414393) (xy 131.270163 -285.450841)
			(xy 131.299375 -285.492247) (xy 131.321906 -285.537636) (xy 131.337225 -285.585939) (xy 131.344972 -285.636017)
			(xy 131.345432 -285.661354) (xy 131.344924 -285.687241) (xy 131.336825 -285.738379) (xy 131.320826 -285.787619)
			(xy 131.29732 -285.833751) (xy 131.266888 -285.875638) (xy 131.230278 -285.912248) (xy 131.188391 -285.94268)
			(xy 131.142259 -285.966186) (xy 131.093019 -285.982185) (xy 131.041881 -285.990284) (xy 130.990107 -285.990284)
			(xy 130.938969 -285.982185) (xy 130.889729 -285.966186) (xy 130.843597 -285.94268) (xy 130.80171 -285.912248)
			(xy 130.7651 -285.875638) (xy 130.734668 -285.833751) (xy 130.711162 -285.787619) (xy 130.695163 -285.738379)
			(xy 130.687064 -285.687241) (xy 130.686556 -285.661354) (xy 130.687101 -285.633647) (xy 130.696286 -285.579)
			(xy 130.704844 -285.552642) (xy 130.712718 -285.530544) (xy 130.50774 -285.175706) (xy 130.48488 -285.171388)
			(xy 130.46006 -285.166215) (xy 130.41228 -285.149263) (xy 130.367659 -285.125194) (xy 130.327251 -285.094575)
			(xy 130.292009 -285.058129) (xy 130.262765 -285.016715) (xy 130.240209 -284.971312) (xy 130.224872 -284.922989)
			(xy 130.217117 -284.872887) (xy 130.216656 -284.847538) (xy 128.99644 -284.847538) (xy 128.995834 -284.875255)
			(xy 128.986519 -284.929901) (xy 128.977898 -284.95625) (xy 128.970024 -284.978348) (xy 129.175002 -285.333186)
			(xy 129.197862 -285.337504) (xy 129.222668 -285.342683) (xy 129.27041 -285.359669) (xy 129.31499 -285.383762)
			(xy 129.355358 -285.414393) (xy 129.390563 -285.450841) (xy 129.419775 -285.492247) (xy 129.442306 -285.537636)
			(xy 129.457625 -285.585939) (xy 129.465372 -285.636017) (xy 129.465832 -285.661354) (xy 129.465324 -285.687241)
			(xy 129.457225 -285.738379) (xy 129.441226 -285.787619) (xy 129.41772 -285.833751) (xy 129.387288 -285.875638)
			(xy 129.350678 -285.912248) (xy 129.308791 -285.94268) (xy 129.262659 -285.966186) (xy 129.213419 -285.982185)
			(xy 129.162281 -285.990284) (xy 129.110507 -285.990284) (xy 129.059369 -285.982185) (xy 129.010129 -285.966186)
			(xy 128.963997 -285.94268) (xy 128.92211 -285.912248) (xy 128.8855 -285.875638) (xy 128.855068 -285.833751)
			(xy 128.831562 -285.787619) (xy 128.815563 -285.738379) (xy 128.807464 -285.687241) (xy 128.806956 -285.661354)
			(xy 128.807501 -285.633647) (xy 128.816686 -285.579) (xy 128.825244 -285.552642) (xy 128.833118 -285.530544)
			(xy 128.62814 -285.175706) (xy 128.60528 -285.171388) (xy 128.58046 -285.166215) (xy 128.53268 -285.149263)
			(xy 128.488059 -285.125194) (xy 128.447651 -285.094575) (xy 128.412409 -285.058129) (xy 128.383165 -285.016715)
			(xy 128.360609 -284.971312) (xy 128.345272 -284.922989) (xy 128.337517 -284.872887) (xy 128.337056 -284.847538)
			(xy 127.11684 -284.847538) (xy 127.116234 -284.875255) (xy 127.106919 -284.929901) (xy 127.098298 -284.95625)
			(xy 127.090424 -284.978348) (xy 127.295402 -285.333186) (xy 127.318262 -285.337504) (xy 127.343068 -285.342683)
			(xy 127.39081 -285.359669) (xy 127.43539 -285.383762) (xy 127.475758 -285.414393) (xy 127.510963 -285.450841)
			(xy 127.540175 -285.492247) (xy 127.562706 -285.537636) (xy 127.578025 -285.585939) (xy 127.585772 -285.636017)
			(xy 127.586232 -285.661354) (xy 127.585724 -285.687241) (xy 127.577625 -285.738379) (xy 127.561626 -285.787619)
			(xy 127.53812 -285.833751) (xy 127.507688 -285.875638) (xy 127.471078 -285.912248) (xy 127.429191 -285.94268)
			(xy 127.383059 -285.966186) (xy 127.333819 -285.982185) (xy 127.282681 -285.990284) (xy 127.230907 -285.990284)
			(xy 127.179769 -285.982185) (xy 127.130529 -285.966186) (xy 127.084397 -285.94268) (xy 127.04251 -285.912248)
			(xy 127.0059 -285.875638) (xy 126.975468 -285.833751) (xy 126.951962 -285.787619) (xy 126.935963 -285.738379)
			(xy 126.927864 -285.687241) (xy 126.927356 -285.661354) (xy 126.927901 -285.633647) (xy 126.937086 -285.579)
			(xy 126.945644 -285.552642) (xy 126.953518 -285.530544) (xy 126.74854 -285.175706) (xy 126.72568 -285.171388)
			(xy 126.70086 -285.166215) (xy 126.65308 -285.149263) (xy 126.608459 -285.125194) (xy 126.568051 -285.094575)
			(xy 126.532809 -285.058129) (xy 126.503565 -285.016715) (xy 126.481009 -284.971312) (xy 126.465672 -284.922989)
			(xy 126.457917 -284.872887) (xy 126.457456 -284.847538) (xy 125.23724 -284.847538) (xy 125.236634 -284.875255)
			(xy 125.227319 -284.929901) (xy 125.218698 -284.95625) (xy 125.210824 -284.978348) (xy 125.415802 -285.333186)
			(xy 125.438662 -285.337504) (xy 125.463468 -285.342683) (xy 125.51121 -285.359669) (xy 125.55579 -285.383762)
			(xy 125.596158 -285.414393) (xy 125.631363 -285.450841) (xy 125.660575 -285.492247) (xy 125.683106 -285.537636)
			(xy 125.698425 -285.585939) (xy 125.706172 -285.636017) (xy 125.706632 -285.661354) (xy 125.706124 -285.687241)
			(xy 125.698025 -285.738379) (xy 125.682026 -285.787619) (xy 125.65852 -285.833751) (xy 125.628088 -285.875638)
			(xy 125.591478 -285.912248) (xy 125.549591 -285.94268) (xy 125.503459 -285.966186) (xy 125.454219 -285.982185)
			(xy 125.403081 -285.990284) (xy 125.351307 -285.990284) (xy 125.300169 -285.982185) (xy 125.250929 -285.966186)
			(xy 125.204797 -285.94268) (xy 125.16291 -285.912248) (xy 125.1263 -285.875638) (xy 125.095868 -285.833751)
			(xy 125.072362 -285.787619) (xy 125.056363 -285.738379) (xy 125.048264 -285.687241) (xy 125.047756 -285.661354)
			(xy 125.048301 -285.633647) (xy 125.057486 -285.579) (xy 125.066044 -285.552642) (xy 125.073918 -285.530544)
			(xy 124.86894 -285.175706) (xy 124.84608 -285.171388) (xy 124.82126 -285.166215) (xy 124.77348 -285.149263)
			(xy 124.728859 -285.125194) (xy 124.688451 -285.094575) (xy 124.653209 -285.058129) (xy 124.623965 -285.016715)
			(xy 124.601409 -284.971312) (xy 124.586072 -284.922989) (xy 124.578317 -284.872887) (xy 124.577856 -284.847538)
			(xy 123.35764 -284.847538) (xy 123.357034 -284.875255) (xy 123.347719 -284.929901) (xy 123.339098 -284.95625)
			(xy 123.331224 -284.978348) (xy 123.536202 -285.333186) (xy 123.559062 -285.337504) (xy 123.583868 -285.342683)
			(xy 123.63161 -285.359669) (xy 123.67619 -285.383762) (xy 123.716558 -285.414393) (xy 123.751763 -285.450841)
			(xy 123.780975 -285.492247) (xy 123.803506 -285.537636) (xy 123.818825 -285.585939) (xy 123.826572 -285.636017)
			(xy 123.827032 -285.661354) (xy 123.826524 -285.687241) (xy 123.818425 -285.738379) (xy 123.802426 -285.787619)
			(xy 123.77892 -285.833751) (xy 123.748488 -285.875638) (xy 123.711878 -285.912248) (xy 123.669991 -285.94268)
			(xy 123.623859 -285.966186) (xy 123.574619 -285.982185) (xy 123.523481 -285.990284) (xy 123.471707 -285.990284)
			(xy 123.420569 -285.982185) (xy 123.371329 -285.966186) (xy 123.325197 -285.94268) (xy 123.28331 -285.912248)
			(xy 123.2467 -285.875638) (xy 123.216268 -285.833751) (xy 123.192762 -285.787619) (xy 123.176763 -285.738379)
			(xy 123.168664 -285.687241) (xy 123.168156 -285.661354) (xy 123.168701 -285.633647) (xy 123.177886 -285.579)
			(xy 123.186444 -285.552642) (xy 123.194318 -285.530544) (xy 122.98934 -285.175706) (xy 122.96648 -285.171388)
			(xy 122.94166 -285.166215) (xy 122.89388 -285.149263) (xy 122.849259 -285.125194) (xy 122.808851 -285.094575)
			(xy 122.773609 -285.058129) (xy 122.744365 -285.016715) (xy 122.721809 -284.971312) (xy 122.706472 -284.922989)
			(xy 122.698717 -284.872887) (xy 122.698256 -284.847538) (xy 121.47804 -284.847538) (xy 121.477434 -284.875255)
			(xy 121.468119 -284.929901) (xy 121.459498 -284.95625) (xy 121.451624 -284.978348) (xy 121.656602 -285.333186)
			(xy 121.679462 -285.337504) (xy 121.704268 -285.342683) (xy 121.75201 -285.359669) (xy 121.79659 -285.383762)
			(xy 121.836958 -285.414393) (xy 121.872163 -285.450841) (xy 121.901375 -285.492247) (xy 121.923906 -285.537636)
			(xy 121.939225 -285.585939) (xy 121.946972 -285.636017) (xy 121.947432 -285.661354) (xy 121.946924 -285.687241)
			(xy 121.938825 -285.738379) (xy 121.922826 -285.787619) (xy 121.89932 -285.833751) (xy 121.868888 -285.875638)
			(xy 121.832278 -285.912248) (xy 121.790391 -285.94268) (xy 121.744259 -285.966186) (xy 121.695019 -285.982185)
			(xy 121.643881 -285.990284) (xy 121.592107 -285.990284) (xy 121.540969 -285.982185) (xy 121.491729 -285.966186)
			(xy 121.445597 -285.94268) (xy 121.40371 -285.912248) (xy 121.3671 -285.875638) (xy 121.336668 -285.833751)
			(xy 121.313162 -285.787619) (xy 121.297163 -285.738379) (xy 121.289064 -285.687241) (xy 121.288556 -285.661354)
			(xy 121.289101 -285.633647) (xy 121.298286 -285.579) (xy 121.306844 -285.552642) (xy 121.314718 -285.530544)
			(xy 121.10974 -285.175706) (xy 121.08688 -285.171388) (xy 121.06206 -285.166215) (xy 121.01428 -285.149263)
			(xy 120.969659 -285.125194) (xy 120.929251 -285.094575) (xy 120.894009 -285.058129) (xy 120.864765 -285.016715)
			(xy 120.842209 -284.971312) (xy 120.826872 -284.922989) (xy 120.819117 -284.872887) (xy 120.818656 -284.847538)
			(xy 119.61676 -284.847538) (xy 119.929148 -285.392368) (xy 119.93753 -285.398718) (xy 119.958317 -285.415132)
			(xy 119.994862 -285.453466) (xy 120.024793 -285.49716) (xy 120.047335 -285.545085) (xy 120.061908 -285.596003)
			(xy 120.065546 -285.622238) (xy 120.066816 -285.632398) (xy 120.178322 -285.827216) (xy 120.18637 -285.840214)
			(xy 120.208728 -285.861046) (xy 120.236244 -285.874339) (xy 120.26646 -285.878906) (xy 120.296676 -285.874339)
			(xy 120.324192 -285.861046) (xy 120.34655 -285.840214) (xy 120.354598 -285.827216) (xy 120.374918 -285.792164)
			(xy 120.367044 -285.77032) (xy 120.358465 -285.743901) (xy 120.34927 -285.689126) (xy 120.348756 -285.661354)
			(xy 120.349264 -285.635467) (xy 120.357363 -285.584329) (xy 120.373362 -285.535089) (xy 120.396868 -285.488957)
			(xy 120.4273 -285.44707) (xy 120.46391 -285.41046) (xy 120.505797 -285.380028) (xy 120.551929 -285.356522)
			(xy 120.601169 -285.340523) (xy 120.652307 -285.332424) (xy 120.704081 -285.332424) (xy 120.755219 -285.340523)
			(xy 120.804459 -285.356522) (xy 120.850591 -285.380028) (xy 120.892478 -285.41046) (xy 120.929088 -285.44707)
			(xy 120.95952 -285.488957) (xy 120.983026 -285.535089) (xy 120.999025 -285.584329) (xy 121.007124 -285.635467)
			(xy 121.007632 -285.661354) (xy 121.007171 -285.686691) (xy 120.999424 -285.736768) (xy 120.984103 -285.785069)
			(xy 120.961572 -285.830458) (xy 120.93236 -285.871863) (xy 120.897155 -285.90831) (xy 120.856787 -285.93894)
			(xy 120.812208 -285.963032) (xy 120.764466 -285.980017) (xy 120.739662 -285.985204) (xy 120.716802 -285.989522)
			(xy 120.511824 -286.344614) (xy 120.519698 -286.366458) (xy 120.525875 -286.385017) (xy 120.534286 -286.423219)
			(xy 120.536462 -286.442658) (xy 120.537478 -286.453326) (xy 120.550148 -286.475424) (xy 121.758456 -286.475424)
			(xy 121.758954 -286.450079) (xy 121.766723 -286.399987) (xy 121.782068 -286.351675) (xy 121.804626 -286.306281)
			(xy 121.833866 -286.264873) (xy 121.869099 -286.228429) (xy 121.909494 -286.197807) (xy 121.9541 -286.173728)
			(xy 122.001866 -286.156759) (xy 122.02668 -286.151574) (xy 122.04954 -286.147256) (xy 122.254518 -285.792164)
			(xy 122.246644 -285.77032) (xy 122.238071 -285.743899) (xy 122.22887 -285.689126) (xy 122.228356 -285.661354)
			(xy 122.228864 -285.635467) (xy 122.236963 -285.584329) (xy 122.252962 -285.535089) (xy 122.276468 -285.488957)
			(xy 122.3069 -285.44707) (xy 122.34351 -285.41046) (xy 122.385397 -285.380028) (xy 122.431529 -285.356522)
			(xy 122.480769 -285.340523) (xy 122.531907 -285.332424) (xy 122.583681 -285.332424) (xy 122.634819 -285.340523)
			(xy 122.684059 -285.356522) (xy 122.730191 -285.380028) (xy 122.772078 -285.41046) (xy 122.808688 -285.44707)
			(xy 122.83912 -285.488957) (xy 122.862626 -285.535089) (xy 122.878625 -285.584329) (xy 122.886724 -285.635467)
			(xy 122.887232 -285.661354) (xy 122.886772 -285.686689) (xy 122.879013 -285.736761) (xy 122.863685 -285.785057)
			(xy 122.841149 -285.830439) (xy 122.811936 -285.87184) (xy 122.776734 -285.908285) (xy 122.736371 -285.938915)
			(xy 122.691797 -285.963011) (xy 122.644062 -285.980004) (xy 122.619262 -285.985204) (xy 122.596402 -285.989522)
			(xy 122.391424 -286.344614) (xy 122.399298 -286.366458) (xy 122.407949 -286.392865) (xy 122.417266 -286.447642)
			(xy 122.41784 -286.475424) (xy 123.638056 -286.475424) (xy 123.638554 -286.450079) (xy 123.646323 -286.399987)
			(xy 123.661668 -286.351675) (xy 123.684226 -286.306281) (xy 123.713466 -286.264873) (xy 123.748699 -286.228429)
			(xy 123.789094 -286.197807) (xy 123.8337 -286.173728) (xy 123.881466 -286.156759) (xy 123.90628 -286.151574)
			(xy 123.92914 -286.147256) (xy 124.134118 -285.792164) (xy 124.126244 -285.77032) (xy 124.117671 -285.743899)
			(xy 124.10847 -285.689126) (xy 124.107956 -285.661354) (xy 124.108464 -285.635467) (xy 124.116563 -285.584329)
			(xy 124.132562 -285.535089) (xy 124.156068 -285.488957) (xy 124.1865 -285.44707) (xy 124.22311 -285.41046)
			(xy 124.264997 -285.380028) (xy 124.311129 -285.356522) (xy 124.360369 -285.340523) (xy 124.411507 -285.332424)
			(xy 124.463281 -285.332424) (xy 124.514419 -285.340523) (xy 124.563659 -285.356522) (xy 124.609791 -285.380028)
			(xy 124.651678 -285.41046) (xy 124.688288 -285.44707) (xy 124.71872 -285.488957) (xy 124.742226 -285.535089)
			(xy 124.758225 -285.584329) (xy 124.766324 -285.635467) (xy 124.766832 -285.661354) (xy 124.766372 -285.686689)
			(xy 124.758613 -285.736761) (xy 124.743285 -285.785057) (xy 124.720749 -285.830439) (xy 124.691536 -285.87184)
			(xy 124.656334 -285.908285) (xy 124.615971 -285.938915) (xy 124.571397 -285.963011) (xy 124.523662 -285.980004)
			(xy 124.498862 -285.985204) (xy 124.476002 -285.989522) (xy 124.271024 -286.344614) (xy 124.278898 -286.366458)
			(xy 124.287549 -286.392865) (xy 124.296866 -286.447642) (xy 124.29744 -286.475424) (xy 125.517656 -286.475424)
			(xy 125.518154 -286.450079) (xy 125.525923 -286.399987) (xy 125.541268 -286.351675) (xy 125.563826 -286.306281)
			(xy 125.593066 -286.264873) (xy 125.628299 -286.228429) (xy 125.668694 -286.197807) (xy 125.7133 -286.173728)
			(xy 125.761066 -286.156759) (xy 125.78588 -286.151574) (xy 125.80874 -286.147256) (xy 126.013718 -285.792164)
			(xy 126.005844 -285.77032) (xy 125.997271 -285.743899) (xy 125.98807 -285.689126) (xy 125.987556 -285.661354)
			(xy 125.988064 -285.635467) (xy 125.996163 -285.584329) (xy 126.012162 -285.535089) (xy 126.035668 -285.488957)
			(xy 126.0661 -285.44707) (xy 126.10271 -285.41046) (xy 126.144597 -285.380028) (xy 126.190729 -285.356522)
			(xy 126.239969 -285.340523) (xy 126.291107 -285.332424) (xy 126.342881 -285.332424) (xy 126.394019 -285.340523)
			(xy 126.443259 -285.356522) (xy 126.489391 -285.380028) (xy 126.531278 -285.41046) (xy 126.567888 -285.44707)
			(xy 126.59832 -285.488957) (xy 126.621826 -285.535089) (xy 126.637825 -285.584329) (xy 126.645924 -285.635467)
			(xy 126.646432 -285.661354) (xy 126.645972 -285.686689) (xy 126.638213 -285.736761) (xy 126.622885 -285.785057)
			(xy 126.600349 -285.830439) (xy 126.571136 -285.87184) (xy 126.535934 -285.908285) (xy 126.495571 -285.938915)
			(xy 126.450997 -285.963011) (xy 126.403262 -285.980004) (xy 126.378462 -285.985204) (xy 126.355602 -285.989522)
			(xy 126.150624 -286.344614) (xy 126.158498 -286.366458) (xy 126.167149 -286.392865) (xy 126.176466 -286.447642)
			(xy 126.17704 -286.475424) (xy 127.397256 -286.475424) (xy 127.397754 -286.450079) (xy 127.405523 -286.399987)
			(xy 127.420868 -286.351675) (xy 127.443426 -286.306281) (xy 127.472666 -286.264873) (xy 127.507899 -286.228429)
			(xy 127.548294 -286.197807) (xy 127.5929 -286.173728) (xy 127.640666 -286.156759) (xy 127.66548 -286.151574)
			(xy 127.68834 -286.147256) (xy 127.893318 -285.792164) (xy 127.885444 -285.77032) (xy 127.876871 -285.743899)
			(xy 127.86767 -285.689126) (xy 127.867156 -285.661354) (xy 127.867664 -285.635467) (xy 127.875763 -285.584329)
			(xy 127.891762 -285.535089) (xy 127.915268 -285.488957) (xy 127.9457 -285.44707) (xy 127.98231 -285.41046)
			(xy 128.024197 -285.380028) (xy 128.070329 -285.356522) (xy 128.119569 -285.340523) (xy 128.170707 -285.332424)
			(xy 128.222481 -285.332424) (xy 128.273619 -285.340523) (xy 128.322859 -285.356522) (xy 128.368991 -285.380028)
			(xy 128.410878 -285.41046) (xy 128.447488 -285.44707) (xy 128.47792 -285.488957) (xy 128.501426 -285.535089)
			(xy 128.517425 -285.584329) (xy 128.525524 -285.635467) (xy 128.526032 -285.661354) (xy 128.525572 -285.686689)
			(xy 128.517813 -285.736761) (xy 128.502485 -285.785057) (xy 128.479949 -285.830439) (xy 128.450736 -285.87184)
			(xy 128.415534 -285.908285) (xy 128.375171 -285.938915) (xy 128.330597 -285.963011) (xy 128.282862 -285.980004)
			(xy 128.258062 -285.985204) (xy 128.235202 -285.989522) (xy 128.030224 -286.344614) (xy 128.038098 -286.366458)
			(xy 128.046749 -286.392865) (xy 128.056066 -286.447642) (xy 128.05664 -286.475424) (xy 129.276856 -286.475424)
			(xy 129.277354 -286.450079) (xy 129.285123 -286.399987) (xy 129.300468 -286.351675) (xy 129.323026 -286.306281)
			(xy 129.352266 -286.264873) (xy 129.387499 -286.228429) (xy 129.427894 -286.197807) (xy 129.4725 -286.173728)
			(xy 129.520266 -286.156759) (xy 129.54508 -286.151574) (xy 129.56794 -286.147256) (xy 129.772918 -285.792164)
			(xy 129.765044 -285.77032) (xy 129.756471 -285.743899) (xy 129.74727 -285.689126) (xy 129.746756 -285.661354)
			(xy 129.747264 -285.635467) (xy 129.755363 -285.584329) (xy 129.771362 -285.535089) (xy 129.794868 -285.488957)
			(xy 129.8253 -285.44707) (xy 129.86191 -285.41046) (xy 129.903797 -285.380028) (xy 129.949929 -285.356522)
			(xy 129.999169 -285.340523) (xy 130.050307 -285.332424) (xy 130.102081 -285.332424) (xy 130.153219 -285.340523)
			(xy 130.202459 -285.356522) (xy 130.248591 -285.380028) (xy 130.290478 -285.41046) (xy 130.327088 -285.44707)
			(xy 130.35752 -285.488957) (xy 130.381026 -285.535089) (xy 130.397025 -285.584329) (xy 130.405124 -285.635467)
			(xy 130.405632 -285.661354) (xy 130.405172 -285.686689) (xy 130.397413 -285.736761) (xy 130.382085 -285.785057)
			(xy 130.359549 -285.830439) (xy 130.330336 -285.87184) (xy 130.295134 -285.908285) (xy 130.254771 -285.938915)
			(xy 130.210197 -285.963011) (xy 130.162462 -285.980004) (xy 130.137662 -285.985204) (xy 130.114802 -285.989522)
			(xy 129.909824 -286.344614) (xy 129.917698 -286.366458) (xy 129.926349 -286.392865) (xy 129.935666 -286.447642)
			(xy 129.93624 -286.475424) (xy 131.156456 -286.475424) (xy 131.156954 -286.450079) (xy 131.164723 -286.399987)
			(xy 131.180068 -286.351675) (xy 131.202626 -286.306281) (xy 131.231866 -286.264873) (xy 131.267099 -286.228429)
			(xy 131.307494 -286.197807) (xy 131.3521 -286.173728) (xy 131.399866 -286.156759) (xy 131.42468 -286.151574)
			(xy 131.44754 -286.147256) (xy 131.652518 -285.792164) (xy 131.644644 -285.77032) (xy 131.636071 -285.743899)
			(xy 131.62687 -285.689126) (xy 131.626356 -285.661354) (xy 131.626864 -285.635467) (xy 131.634963 -285.584329)
			(xy 131.650962 -285.535089) (xy 131.674468 -285.488957) (xy 131.7049 -285.44707) (xy 131.74151 -285.41046)
			(xy 131.783397 -285.380028) (xy 131.829529 -285.356522) (xy 131.878769 -285.340523) (xy 131.929907 -285.332424)
			(xy 131.981681 -285.332424) (xy 132.032819 -285.340523) (xy 132.082059 -285.356522) (xy 132.128191 -285.380028)
			(xy 132.170078 -285.41046) (xy 132.206688 -285.44707) (xy 132.23712 -285.488957) (xy 132.260626 -285.535089)
			(xy 132.276625 -285.584329) (xy 132.284724 -285.635467) (xy 132.285232 -285.661354) (xy 132.284772 -285.686689)
			(xy 132.277013 -285.736761) (xy 132.261685 -285.785057) (xy 132.239149 -285.830439) (xy 132.209936 -285.87184)
			(xy 132.174734 -285.908285) (xy 132.134371 -285.938915) (xy 132.089797 -285.963011) (xy 132.042062 -285.980004)
			(xy 132.017262 -285.985204) (xy 131.994402 -285.989522) (xy 131.789424 -286.344614) (xy 131.797298 -286.366458)
			(xy 131.805949 -286.392865) (xy 131.815266 -286.447642) (xy 131.81584 -286.475424) (xy 133.036056 -286.475424)
			(xy 133.036554 -286.450079) (xy 133.044323 -286.399987) (xy 133.059668 -286.351675) (xy 133.082226 -286.306281)
			(xy 133.111466 -286.264873) (xy 133.146699 -286.228429) (xy 133.187094 -286.197807) (xy 133.2317 -286.173728)
			(xy 133.279466 -286.156759) (xy 133.30428 -286.151574) (xy 133.32714 -286.147256) (xy 133.532118 -285.792164)
			(xy 133.524244 -285.77032) (xy 133.515671 -285.743899) (xy 133.50647 -285.689126) (xy 133.505956 -285.661354)
			(xy 133.506464 -285.635467) (xy 133.514563 -285.584329) (xy 133.530562 -285.535089) (xy 133.554068 -285.488957)
			(xy 133.5845 -285.44707) (xy 133.62111 -285.41046) (xy 133.662997 -285.380028) (xy 133.709129 -285.356522)
			(xy 133.758369 -285.340523) (xy 133.809507 -285.332424) (xy 133.861281 -285.332424) (xy 133.912419 -285.340523)
			(xy 133.961659 -285.356522) (xy 134.007791 -285.380028) (xy 134.049678 -285.41046) (xy 134.086288 -285.44707)
			(xy 134.11672 -285.488957) (xy 134.140226 -285.535089) (xy 134.156225 -285.584329) (xy 134.164324 -285.635467)
			(xy 134.164832 -285.661354) (xy 134.164372 -285.686689) (xy 134.156613 -285.736761) (xy 134.141285 -285.785057)
			(xy 134.118749 -285.830439) (xy 134.089536 -285.87184) (xy 134.054334 -285.908285) (xy 134.013971 -285.938915)
			(xy 133.969397 -285.963011) (xy 133.921662 -285.980004) (xy 133.896862 -285.985204) (xy 133.874002 -285.989522)
			(xy 133.669024 -286.344614) (xy 133.676898 -286.366458) (xy 133.685549 -286.392865) (xy 133.694866 -286.447642)
			(xy 133.69544 -286.475424) (xy 133.694932 -286.501331) (xy 133.686826 -286.552508) (xy 133.670814 -286.601787)
			(xy 133.647291 -286.647954) (xy 133.616835 -286.689873) (xy 133.580197 -286.726511) (xy 133.538278 -286.756967)
			(xy 133.492111 -286.78049) (xy 133.442832 -286.796502) (xy 133.391655 -286.804608) (xy 133.339841 -286.804608)
			(xy 133.288664 -286.796502) (xy 133.239385 -286.78049) (xy 133.193218 -286.756967) (xy 133.151299 -286.726511)
			(xy 133.114661 -286.689873) (xy 133.084205 -286.647954) (xy 133.060682 -286.601787) (xy 133.04467 -286.552508)
			(xy 133.036564 -286.501331) (xy 133.036056 -286.475424) (xy 131.81584 -286.475424) (xy 131.815332 -286.501331)
			(xy 131.807226 -286.552508) (xy 131.791214 -286.601787) (xy 131.767691 -286.647954) (xy 131.737235 -286.689873)
			(xy 131.700597 -286.726511) (xy 131.658678 -286.756967) (xy 131.612511 -286.78049) (xy 131.563232 -286.796502)
			(xy 131.512055 -286.804608) (xy 131.460241 -286.804608) (xy 131.409064 -286.796502) (xy 131.359785 -286.78049)
			(xy 131.313618 -286.756967) (xy 131.271699 -286.726511) (xy 131.235061 -286.689873) (xy 131.204605 -286.647954)
			(xy 131.181082 -286.601787) (xy 131.16507 -286.552508) (xy 131.156964 -286.501331) (xy 131.156456 -286.475424)
			(xy 129.93624 -286.475424) (xy 129.935732 -286.501331) (xy 129.927626 -286.552508) (xy 129.911614 -286.601787)
			(xy 129.888091 -286.647954) (xy 129.857635 -286.689873) (xy 129.820997 -286.726511) (xy 129.779078 -286.756967)
			(xy 129.732911 -286.78049) (xy 129.683632 -286.796502) (xy 129.632455 -286.804608) (xy 129.580641 -286.804608)
			(xy 129.529464 -286.796502) (xy 129.480185 -286.78049) (xy 129.434018 -286.756967) (xy 129.392099 -286.726511)
			(xy 129.355461 -286.689873) (xy 129.325005 -286.647954) (xy 129.301482 -286.601787) (xy 129.28547 -286.552508)
			(xy 129.277364 -286.501331) (xy 129.276856 -286.475424) (xy 128.05664 -286.475424) (xy 128.056132 -286.501331)
			(xy 128.048026 -286.552508) (xy 128.032014 -286.601787) (xy 128.008491 -286.647954) (xy 127.978035 -286.689873)
			(xy 127.941397 -286.726511) (xy 127.899478 -286.756967) (xy 127.853311 -286.78049) (xy 127.804032 -286.796502)
			(xy 127.752855 -286.804608) (xy 127.701041 -286.804608) (xy 127.649864 -286.796502) (xy 127.600585 -286.78049)
			(xy 127.554418 -286.756967) (xy 127.512499 -286.726511) (xy 127.475861 -286.689873) (xy 127.445405 -286.647954)
			(xy 127.421882 -286.601787) (xy 127.40587 -286.552508) (xy 127.397764 -286.501331) (xy 127.397256 -286.475424)
			(xy 126.17704 -286.475424) (xy 126.176532 -286.501331) (xy 126.168426 -286.552508) (xy 126.152414 -286.601787)
			(xy 126.128891 -286.647954) (xy 126.098435 -286.689873) (xy 126.061797 -286.726511) (xy 126.019878 -286.756967)
			(xy 125.973711 -286.78049) (xy 125.924432 -286.796502) (xy 125.873255 -286.804608) (xy 125.821441 -286.804608)
			(xy 125.770264 -286.796502) (xy 125.720985 -286.78049) (xy 125.674818 -286.756967) (xy 125.632899 -286.726511)
			(xy 125.596261 -286.689873) (xy 125.565805 -286.647954) (xy 125.542282 -286.601787) (xy 125.52627 -286.552508)
			(xy 125.518164 -286.501331) (xy 125.517656 -286.475424) (xy 124.29744 -286.475424) (xy 124.296932 -286.501331)
			(xy 124.288826 -286.552508) (xy 124.272814 -286.601787) (xy 124.249291 -286.647954) (xy 124.218835 -286.689873)
			(xy 124.182197 -286.726511) (xy 124.140278 -286.756967) (xy 124.094111 -286.78049) (xy 124.044832 -286.796502)
			(xy 123.993655 -286.804608) (xy 123.941841 -286.804608) (xy 123.890664 -286.796502) (xy 123.841385 -286.78049)
			(xy 123.795218 -286.756967) (xy 123.753299 -286.726511) (xy 123.716661 -286.689873) (xy 123.686205 -286.647954)
			(xy 123.662682 -286.601787) (xy 123.64667 -286.552508) (xy 123.638564 -286.501331) (xy 123.638056 -286.475424)
			(xy 122.41784 -286.475424) (xy 122.417332 -286.501331) (xy 122.409226 -286.552508) (xy 122.393214 -286.601787)
			(xy 122.369691 -286.647954) (xy 122.339235 -286.689873) (xy 122.302597 -286.726511) (xy 122.260678 -286.756967)
			(xy 122.214511 -286.78049) (xy 122.165232 -286.796502) (xy 122.114055 -286.804608) (xy 122.062241 -286.804608)
			(xy 122.011064 -286.796502) (xy 121.961785 -286.78049) (xy 121.915618 -286.756967) (xy 121.873699 -286.726511)
			(xy 121.837061 -286.689873) (xy 121.806605 -286.647954) (xy 121.783082 -286.601787) (xy 121.76707 -286.552508)
			(xy 121.758964 -286.501331) (xy 121.758456 -286.475424) (xy 120.550148 -286.475424) (xy 120.860058 -287.015936)
			(xy 120.869202 -287.022286) (xy 120.891789 -287.039168) (xy 120.931363 -287.079333) (xy 120.963498 -287.125665)
			(xy 120.987249 -287.176804) (xy 121.001919 -287.231248) (xy 121.005092 -287.259268) (xy 121.006108 -287.27019)
			(xy 121.3231 -287.823402) (xy 121.333006 -287.830006) (xy 121.353493 -287.844424) (xy 121.390266 -287.878443)
			(xy 121.421466 -287.917635) (xy 121.446375 -287.961098) (xy 121.464419 -288.007831) (xy 121.475182 -288.056756)
			(xy 121.477278 -288.08172) (xy 121.47804 -288.093404) (xy 121.788428 -288.634678) (xy 121.798588 -288.641282)
			(xy 121.818496 -288.654752) (xy 121.854515 -288.686579) (xy 121.885514 -288.723314) (xy 121.910831 -288.764173)
			(xy 121.920762 -288.786062) (xy 121.93397 -288.816796) (xy 122.242326 -288.816796) (xy 122.255534 -288.786062)
			(xy 122.266919 -288.761162) (xy 122.296698 -288.715223) (xy 122.333662 -288.674838) (xy 122.376793 -288.64112)
			(xy 122.424905 -288.614995) (xy 122.476673 -288.597183) (xy 122.530674 -288.588174) (xy 122.558048 -288.587688)
			(xy 122.585421 -288.588208) (xy 122.63942 -288.597215) (xy 122.691188 -288.615022) (xy 122.739301 -288.641139)
			(xy 122.782437 -288.674849) (xy 122.819407 -288.715225) (xy 122.849197 -288.761155) (xy 122.860562 -288.786062)
			(xy 122.87377 -288.816796) (xy 123.036076 -288.816796) (xy 123.051299 -288.81622) (xy 123.08039 -288.807235)
			(xy 123.105546 -288.790084) (xy 123.124539 -288.766287) (xy 123.135684 -288.737954) (xy 123.137995 -288.707595)
			(xy 123.131266 -288.677902) (xy 123.124214 -288.664396) (xy 122.989594 -288.431224) (xy 122.966734 -288.426906)
			(xy 122.941896 -288.421758) (xy 122.894074 -288.404849) (xy 122.84941 -288.380806) (xy 122.808962 -288.350198)
			(xy 122.773686 -288.313749) (xy 122.744417 -288.272322) (xy 122.721847 -288.226897) (xy 122.70651 -288.178548)
			(xy 122.698769 -288.128418) (xy 122.698256 -288.103056) (xy 122.698764 -288.077149) (xy 122.70687 -288.025972)
			(xy 122.722882 -287.976693) (xy 122.746405 -287.930526) (xy 122.776861 -287.888607) (xy 122.813499 -287.851969)
			(xy 122.855418 -287.821513) (xy 122.901585 -287.79799) (xy 122.950864 -287.781978) (xy 123.002041 -287.773872)
			(xy 123.053855 -287.773872) (xy 123.105032 -287.781978) (xy 123.154311 -287.79799) (xy 123.200478 -287.821513)
			(xy 123.242397 -287.851969) (xy 123.279035 -287.888607) (xy 123.309491 -287.930526) (xy 123.333014 -287.976693)
			(xy 123.349026 -288.025972) (xy 123.357132 -288.077149) (xy 123.35764 -288.103056) (xy 123.357047 -288.130773)
			(xy 123.34772 -288.185419) (xy 123.339098 -288.211768) (xy 123.331478 -288.233866) (xy 123.536456 -288.588958)
			(xy 123.559316 -288.593276) (xy 123.585527 -288.598792) (xy 123.635837 -288.617168) (xy 123.682517 -288.643432)
			(xy 123.72434 -288.676893) (xy 123.760206 -288.716672) (xy 123.789174 -288.761724) (xy 123.800362 -288.786062)
			(xy 123.81357 -288.816796) (xy 124.121926 -288.816796) (xy 124.135134 -288.786062) (xy 124.146519 -288.761162)
			(xy 124.176298 -288.715223) (xy 124.213262 -288.674838) (xy 124.256393 -288.64112) (xy 124.304505 -288.614995)
			(xy 124.356273 -288.597183) (xy 124.410274 -288.588174) (xy 124.437648 -288.587688) (xy 124.465021 -288.588208)
			(xy 124.51902 -288.597215) (xy 124.570788 -288.615022) (xy 124.618901 -288.641139) (xy 124.662037 -288.674849)
			(xy 124.699007 -288.715225) (xy 124.728797 -288.761155) (xy 124.740162 -288.786062) (xy 124.75337 -288.816796)
			(xy 124.915676 -288.816796) (xy 124.930899 -288.81622) (xy 124.95999 -288.807235) (xy 124.985146 -288.790084)
			(xy 125.004139 -288.766287) (xy 125.015284 -288.737954) (xy 125.017595 -288.707595) (xy 125.010866 -288.677902)
			(xy 125.003814 -288.664396) (xy 124.869194 -288.431224) (xy 124.846334 -288.426906) (xy 124.821496 -288.421758)
			(xy 124.773674 -288.404849) (xy 124.72901 -288.380806) (xy 124.688562 -288.350198) (xy 124.653286 -288.313749)
			(xy 124.624017 -288.272322) (xy 124.601447 -288.226897) (xy 124.58611 -288.178548) (xy 124.578369 -288.128418)
			(xy 124.577856 -288.103056) (xy 124.578364 -288.077149) (xy 124.58647 -288.025972) (xy 124.602482 -287.976693)
			(xy 124.626005 -287.930526) (xy 124.656461 -287.888607) (xy 124.693099 -287.851969) (xy 124.735018 -287.821513)
			(xy 124.781185 -287.79799) (xy 124.830464 -287.781978) (xy 124.881641 -287.773872) (xy 124.933455 -287.773872)
			(xy 124.984632 -287.781978) (xy 125.033911 -287.79799) (xy 125.080078 -287.821513) (xy 125.121997 -287.851969)
			(xy 125.158635 -287.888607) (xy 125.189091 -287.930526) (xy 125.212614 -287.976693) (xy 125.228626 -288.025972)
			(xy 125.236732 -288.077149) (xy 125.23724 -288.103056) (xy 125.236647 -288.130773) (xy 125.22732 -288.185419)
			(xy 125.218698 -288.211768) (xy 125.211078 -288.233866) (xy 125.416056 -288.588958) (xy 125.438916 -288.593276)
			(xy 125.465127 -288.598792) (xy 125.515437 -288.617168) (xy 125.562117 -288.643432) (xy 125.60394 -288.676893)
			(xy 125.639806 -288.716672) (xy 125.668774 -288.761724) (xy 125.679962 -288.786062) (xy 125.69317 -288.816796)
			(xy 126.001526 -288.816796) (xy 126.014734 -288.786062) (xy 126.026119 -288.761162) (xy 126.055898 -288.715223)
			(xy 126.092862 -288.674838) (xy 126.135993 -288.64112) (xy 126.184105 -288.614995) (xy 126.235873 -288.597183)
			(xy 126.289874 -288.588174) (xy 126.317248 -288.587688) (xy 126.344621 -288.588208) (xy 126.39862 -288.597215)
			(xy 126.450388 -288.615022) (xy 126.498501 -288.641139) (xy 126.541637 -288.674849) (xy 126.578607 -288.715225)
			(xy 126.608397 -288.761155) (xy 126.619762 -288.786062) (xy 126.63297 -288.816796) (xy 126.795276 -288.816796)
			(xy 126.810499 -288.81622) (xy 126.83959 -288.807235) (xy 126.864746 -288.790084) (xy 126.883739 -288.766287)
			(xy 126.894884 -288.737954) (xy 126.897195 -288.707595) (xy 126.890466 -288.677902) (xy 126.883414 -288.664396)
			(xy 126.748794 -288.431224) (xy 126.725934 -288.426906) (xy 126.701096 -288.421758) (xy 126.653274 -288.404849)
			(xy 126.60861 -288.380806) (xy 126.568162 -288.350198) (xy 126.532886 -288.313749) (xy 126.503617 -288.272322)
			(xy 126.481047 -288.226897) (xy 126.46571 -288.178548) (xy 126.457969 -288.128418) (xy 126.457456 -288.103056)
			(xy 126.457964 -288.077149) (xy 126.46607 -288.025972) (xy 126.482082 -287.976693) (xy 126.505605 -287.930526)
			(xy 126.536061 -287.888607) (xy 126.572699 -287.851969) (xy 126.614618 -287.821513) (xy 126.660785 -287.79799)
			(xy 126.710064 -287.781978) (xy 126.761241 -287.773872) (xy 126.813055 -287.773872) (xy 126.864232 -287.781978)
			(xy 126.913511 -287.79799) (xy 126.959678 -287.821513) (xy 127.001597 -287.851969) (xy 127.038235 -287.888607)
			(xy 127.068691 -287.930526) (xy 127.092214 -287.976693) (xy 127.108226 -288.025972) (xy 127.116332 -288.077149)
			(xy 127.11684 -288.103056) (xy 127.116247 -288.130773) (xy 127.10692 -288.185419) (xy 127.098298 -288.211768)
			(xy 127.090678 -288.233866) (xy 127.295656 -288.588958) (xy 127.318516 -288.593276) (xy 127.344727 -288.598792)
			(xy 127.395037 -288.617168) (xy 127.441717 -288.643432) (xy 127.48354 -288.676893) (xy 127.519406 -288.716672)
			(xy 127.548374 -288.761724) (xy 127.559562 -288.786062) (xy 127.57277 -288.816796) (xy 127.881126 -288.816796)
			(xy 127.894334 -288.786062) (xy 127.905719 -288.761162) (xy 127.935498 -288.715223) (xy 127.972462 -288.674838)
			(xy 128.015593 -288.64112) (xy 128.063705 -288.614995) (xy 128.115473 -288.597183) (xy 128.169474 -288.588174)
			(xy 128.196848 -288.587688) (xy 128.224221 -288.588208) (xy 128.27822 -288.597215) (xy 128.329988 -288.615022)
			(xy 128.378101 -288.641139) (xy 128.421237 -288.674849) (xy 128.458207 -288.715225) (xy 128.487997 -288.761155)
			(xy 128.499362 -288.786062) (xy 128.51257 -288.816796) (xy 128.674876 -288.816796) (xy 128.690099 -288.81622)
			(xy 128.71919 -288.807235) (xy 128.744346 -288.790084) (xy 128.763339 -288.766287) (xy 128.774484 -288.737954)
			(xy 128.776795 -288.707595) (xy 128.770066 -288.677902) (xy 128.763014 -288.664396) (xy 128.628394 -288.431224)
			(xy 128.605534 -288.426906) (xy 128.580696 -288.421758) (xy 128.532874 -288.404849) (xy 128.48821 -288.380806)
			(xy 128.447762 -288.350198) (xy 128.412486 -288.313749) (xy 128.383217 -288.272322) (xy 128.360647 -288.226897)
			(xy 128.34531 -288.178548) (xy 128.337569 -288.128418) (xy 128.337056 -288.103056) (xy 128.337564 -288.077149)
			(xy 128.34567 -288.025972) (xy 128.361682 -287.976693) (xy 128.385205 -287.930526) (xy 128.415661 -287.888607)
			(xy 128.452299 -287.851969) (xy 128.494218 -287.821513) (xy 128.540385 -287.79799) (xy 128.589664 -287.781978)
			(xy 128.640841 -287.773872) (xy 128.692655 -287.773872) (xy 128.743832 -287.781978) (xy 128.793111 -287.79799)
			(xy 128.839278 -287.821513) (xy 128.881197 -287.851969) (xy 128.917835 -287.888607) (xy 128.948291 -287.930526)
			(xy 128.971814 -287.976693) (xy 128.987826 -288.025972) (xy 128.995932 -288.077149) (xy 128.99644 -288.103056)
			(xy 128.995847 -288.130773) (xy 128.98652 -288.185419) (xy 128.977898 -288.211768) (xy 128.970278 -288.233866)
			(xy 129.175256 -288.588958) (xy 129.198116 -288.593276) (xy 129.224327 -288.598792) (xy 129.274637 -288.617168)
			(xy 129.321317 -288.643432) (xy 129.36314 -288.676893) (xy 129.399006 -288.716672) (xy 129.427974 -288.761724)
			(xy 129.439162 -288.786062) (xy 129.45237 -288.816796) (xy 129.760726 -288.816796) (xy 129.773934 -288.786062)
			(xy 129.785319 -288.761162) (xy 129.815098 -288.715223) (xy 129.852062 -288.674838) (xy 129.895193 -288.64112)
			(xy 129.943305 -288.614995) (xy 129.995073 -288.597183) (xy 130.049074 -288.588174) (xy 130.076448 -288.587688)
			(xy 130.103821 -288.588208) (xy 130.15782 -288.597215) (xy 130.209588 -288.615022) (xy 130.257701 -288.641139)
			(xy 130.300837 -288.674849) (xy 130.337807 -288.715225) (xy 130.367597 -288.761155) (xy 130.378962 -288.786062)
			(xy 130.39217 -288.816796) (xy 130.554476 -288.816796) (xy 130.569699 -288.81622) (xy 130.59879 -288.807235)
			(xy 130.623946 -288.790084) (xy 130.642939 -288.766287) (xy 130.654084 -288.737954) (xy 130.656395 -288.707595)
			(xy 130.649666 -288.677902) (xy 130.642614 -288.664396) (xy 130.507994 -288.431224) (xy 130.485134 -288.426906)
			(xy 130.460296 -288.421758) (xy 130.412474 -288.404849) (xy 130.36781 -288.380806) (xy 130.327362 -288.350198)
			(xy 130.292086 -288.313749) (xy 130.262817 -288.272322) (xy 130.240247 -288.226897) (xy 130.22491 -288.178548)
			(xy 130.217169 -288.128418) (xy 130.216656 -288.103056) (xy 130.217164 -288.077149) (xy 130.22527 -288.025972)
			(xy 130.241282 -287.976693) (xy 130.264805 -287.930526) (xy 130.295261 -287.888607) (xy 130.331899 -287.851969)
			(xy 130.373818 -287.821513) (xy 130.419985 -287.79799) (xy 130.469264 -287.781978) (xy 130.520441 -287.773872)
			(xy 130.572255 -287.773872) (xy 130.623432 -287.781978) (xy 130.672711 -287.79799) (xy 130.718878 -287.821513)
			(xy 130.760797 -287.851969) (xy 130.797435 -287.888607) (xy 130.827891 -287.930526) (xy 130.851414 -287.976693)
			(xy 130.867426 -288.025972) (xy 130.875532 -288.077149) (xy 130.87604 -288.103056) (xy 130.875447 -288.130773)
			(xy 130.86612 -288.185419) (xy 130.857498 -288.211768) (xy 130.849878 -288.233866) (xy 131.054856 -288.588958)
			(xy 131.077716 -288.593276) (xy 131.103927 -288.598792) (xy 131.154237 -288.617168) (xy 131.200917 -288.643432)
			(xy 131.24274 -288.676893) (xy 131.278606 -288.716672) (xy 131.307574 -288.761724) (xy 131.318762 -288.786062)
			(xy 131.33197 -288.816796) (xy 131.640326 -288.816796) (xy 131.653534 -288.786062) (xy 131.664919 -288.761162)
			(xy 131.694698 -288.715223) (xy 131.731662 -288.674838) (xy 131.774793 -288.64112) (xy 131.822905 -288.614995)
			(xy 131.874673 -288.597183) (xy 131.928674 -288.588174) (xy 131.956048 -288.587688) (xy 131.983421 -288.588208)
			(xy 132.03742 -288.597215) (xy 132.089188 -288.615022) (xy 132.137301 -288.641139) (xy 132.180437 -288.674849)
			(xy 132.217407 -288.715225) (xy 132.247197 -288.761155) (xy 132.258562 -288.786062) (xy 132.27177 -288.816796)
			(xy 132.434076 -288.816796) (xy 132.449299 -288.81622) (xy 132.47839 -288.807235) (xy 132.503546 -288.790084)
			(xy 132.522539 -288.766287) (xy 132.533684 -288.737954) (xy 132.535995 -288.707595) (xy 132.529266 -288.677902)
			(xy 132.522214 -288.664396) (xy 132.387594 -288.431224) (xy 132.364734 -288.426906) (xy 132.339896 -288.421758)
			(xy 132.292074 -288.404849) (xy 132.24741 -288.380806) (xy 132.206962 -288.350198) (xy 132.171686 -288.313749)
			(xy 132.142417 -288.272322) (xy 132.119847 -288.226897) (xy 132.10451 -288.178548) (xy 132.096769 -288.128418)
			(xy 132.096256 -288.103056) (xy 132.096764 -288.077149) (xy 132.10487 -288.025972) (xy 132.120882 -287.976693)
			(xy 132.144405 -287.930526) (xy 132.174861 -287.888607) (xy 132.211499 -287.851969) (xy 132.253418 -287.821513)
			(xy 132.299585 -287.79799) (xy 132.348864 -287.781978) (xy 132.400041 -287.773872) (xy 132.451855 -287.773872)
			(xy 132.503032 -287.781978) (xy 132.552311 -287.79799) (xy 132.598478 -287.821513) (xy 132.640397 -287.851969)
			(xy 132.677035 -287.888607) (xy 132.707491 -287.930526) (xy 132.731014 -287.976693) (xy 132.747026 -288.025972)
			(xy 132.755132 -288.077149) (xy 132.75564 -288.103056) (xy 132.755047 -288.130773) (xy 132.74572 -288.185419)
			(xy 132.737098 -288.211768) (xy 132.729478 -288.233866) (xy 132.934456 -288.588958) (xy 132.957316 -288.593276)
			(xy 132.983527 -288.598792) (xy 133.033837 -288.617168) (xy 133.080517 -288.643432) (xy 133.12234 -288.676893)
			(xy 133.158206 -288.716672) (xy 133.187174 -288.761724) (xy 133.198362 -288.786062) (xy 133.21157 -288.816796)
			(xy 133.519926 -288.816796) (xy 133.533134 -288.786062) (xy 133.544519 -288.761162) (xy 133.574298 -288.715223)
			(xy 133.611262 -288.674838) (xy 133.654393 -288.64112) (xy 133.702505 -288.614995) (xy 133.754273 -288.597183)
			(xy 133.808274 -288.588174) (xy 133.835648 -288.587688) (xy 133.863021 -288.588208) (xy 133.91702 -288.597215)
			(xy 133.968788 -288.615022) (xy 134.016901 -288.641139) (xy 134.060037 -288.674849) (xy 134.097007 -288.715225)
			(xy 134.126797 -288.761155) (xy 134.138162 -288.786062) (xy 134.15137 -288.816796) (xy 134.46125 -288.816796)
			(xy 134.474458 -288.786316) (xy 134.485023 -288.7632) (xy 134.512224 -288.720268) (xy 134.545718 -288.682043)
			(xy 134.584705 -288.649439) (xy 134.628251 -288.623234) (xy 134.675317 -288.604055) (xy 134.724777 -288.592361)
			(xy 134.775448 -288.588432) (xy 134.826119 -288.592361) (xy 134.875579 -288.604055) (xy 134.922645 -288.623234)
			(xy 134.966191 -288.649439) (xy 135.005178 -288.682043) (xy 135.038672 -288.720268) (xy 135.065873 -288.7632)
			(xy 135.076438 -288.786316) (xy 135.089646 -288.816796) (xy 135.253476 -288.816796) (xy 135.26871 -288.81629)
			(xy 135.297825 -288.807308) (xy 135.322994 -288.790138) (xy 135.341979 -288.766308) (xy 135.353088 -288.737937)
			(xy 135.355334 -288.707552) (xy 135.348517 -288.677856) (xy 135.34136 -288.664396) (xy 135.20674 -288.431224)
			(xy 135.18388 -288.426906) (xy 135.159064 -288.421722) (xy 135.111292 -288.404755) (xy 135.066679 -288.380677)
			(xy 135.026277 -288.350056) (xy 134.991036 -288.313613) (xy 134.961787 -288.272207) (xy 134.939218 -288.226812)
			(xy 134.923863 -288.178498) (xy 134.916081 -288.128403) (xy 134.915656 -288.103056) (xy 134.916164 -288.077149)
			(xy 134.92427 -288.025972) (xy 134.940282 -287.976693) (xy 134.963805 -287.930526) (xy 134.994261 -287.888607)
			(xy 135.030899 -287.851969) (xy 135.072818 -287.821513) (xy 135.118985 -287.79799) (xy 135.168264 -287.781978)
			(xy 135.219441 -287.773872) (xy 135.271255 -287.773872) (xy 135.322432 -287.781978) (xy 135.371711 -287.79799)
			(xy 135.417878 -287.821513) (xy 135.459797 -287.851969) (xy 135.496435 -287.888607) (xy 135.526891 -287.930526)
			(xy 135.550414 -287.976693) (xy 135.566426 -288.025972) (xy 135.574532 -288.077149) (xy 135.57504 -288.103056)
			(xy 135.574447 -288.130773) (xy 135.56512 -288.185419) (xy 135.556498 -288.211768) (xy 135.548624 -288.233866)
			(xy 135.753856 -288.588958) (xy 135.776716 -288.593276) (xy 135.802927 -288.598792) (xy 135.853237 -288.617168)
			(xy 135.899917 -288.643432) (xy 135.94174 -288.676893) (xy 135.977606 -288.716672) (xy 136.006574 -288.761724)
			(xy 136.017762 -288.786062) (xy 136.03097 -288.816796) (xy 137.448544 -288.816796) (xy 137.473499 -288.817412)
			(xy 137.522448 -288.827156) (xy 137.568557 -288.846263) (xy 137.610052 -288.873996) (xy 137.628122 -288.891218)
			(xy 145.060416 -296.323512) (xy 145.07768 -296.341551) (xy 145.105445 -296.383043) (xy 145.124566 -296.429162)
			(xy 145.134306 -296.478127) (xy 145.134838 -296.50309) (xy 145.134838 -331.043534) (xy 145.501614 -331.41031)
			(xy 148.007578 -331.41031) (xy 148.032531 -331.410929) (xy 148.081477 -331.42068) (xy 148.12758 -331.439791)
			(xy 148.169069 -331.467529) (xy 148.187156 -331.484732) (xy 148.804376 -332.101952) (xy 148.821639 -332.119992)
			(xy 148.849402 -332.161484) (xy 148.868519 -332.207602) (xy 148.878252 -332.256568) (xy 148.878798 -332.28153)
			(xy 148.878798 -340.70417) (xy 149.942296 -341.767668)
		)
		(stroke
			(width 0)
			(type solid)
		)
		(fill yes)
		(layer "In9.Cu")
		(net "PVCCFA_EHV_FIVRA_CPU1")
	)
	(gr_poly
		(pts
			(xy 119.630444 -270.701516) (xy 119.656615 -270.692994) (xy 119.710877 -270.683802) (xy 119.738394 -270.683228)
			(xy 119.765913 -270.683784) (xy 119.82018 -270.69297) (xy 119.846344 -270.701516) (xy 119.854472 -270.70431)
			(xy 120.118378 -270.70431) (xy 120.129885 -270.685341) (xy 120.158395 -270.651352) (xy 120.192374 -270.622831)
			(xy 120.230789 -270.600643) (xy 120.272474 -270.585462) (xy 120.316161 -270.577749) (xy 120.338342 -270.57731)
			(xy 131.942586 -270.57731) (xy 132.146548 -270.373348) (xy 132.1308 -270.340836) (xy 132.120393 -270.318404)
			(xy 132.105696 -270.27119) (xy 132.098257 -270.222304) (xy 132.09778 -270.19758) (xy 132.098261 -270.171793)
			(xy 132.106333 -270.120854) (xy 132.122274 -270.071805) (xy 132.145692 -270.025854) (xy 132.176011 -269.984132)
			(xy 132.212484 -269.947667) (xy 132.254212 -269.917357) (xy 132.300168 -269.893948) (xy 132.34922 -269.878017)
			(xy 132.400161 -269.869956) (xy 132.425948 -269.869412) (xy 132.450671 -269.869885) (xy 132.499552 -269.877346)
			(xy 132.546763 -269.892046) (xy 132.569204 -269.902432) (xy 132.601716 -269.91818) (xy 133.978142 -268.541754)
			(xy 133.980428 -268.524736) (xy 133.984583 -268.498458) (xy 134.000277 -268.447626) (xy 134.023965 -268.399991)
			(xy 134.055026 -268.356801) (xy 134.092647 -268.319187) (xy 134.135843 -268.288134) (xy 134.183482 -268.264455)
			(xy 134.234317 -268.24877) (xy 134.26059 -268.244574) (xy 134.277608 -268.242288) (xy 134.535672 -267.984224)
			(xy 134.510018 -267.949172) (xy 134.495185 -267.927994) (xy 134.471662 -267.881952) (xy 134.455645 -267.832792)
			(xy 134.44753 -267.781729) (xy 134.447026 -267.755878) (xy 134.447533 -267.730091) (xy 134.455604 -267.679153)
			(xy 134.471544 -267.630105) (xy 134.494959 -267.584154) (xy 134.525275 -267.542431) (xy 134.561743 -267.505964)
			(xy 134.603468 -267.475651) (xy 134.64942 -267.452238) (xy 134.698469 -267.4363) (xy 134.749407 -267.428232)
			(xy 134.775194 -267.42771) (xy 134.800185 -267.428199) (xy 134.849584 -267.435813) (xy 134.89726 -267.450821)
			(xy 134.942113 -267.472876) (xy 134.983109 -267.50147) (xy 135.001508 -267.518388) (xy 135.594344 -266.925552)
			(xy 135.612385 -266.908293) (xy 135.653879 -266.880536) (xy 135.699997 -266.861423) (xy 135.748961 -266.851691)
			(xy 135.773922 -266.85113) (xy 135.867648 -266.85113) (xy 135.880348 -266.81938) (xy 135.890516 -266.79542)
			(xy 135.917307 -266.750798) (xy 135.950804 -266.710963) (xy 135.990168 -266.676913) (xy 136.034412 -266.649502)
			(xy 136.082427 -266.629417) (xy 136.13301 -266.617161) (xy 136.184894 -266.613041) (xy 136.236778 -266.617161)
			(xy 136.287361 -266.629417) (xy 136.335376 -266.649502) (xy 136.37962 -266.676913) (xy 136.418984 -266.710963)
			(xy 136.452481 -266.750798) (xy 136.479272 -266.79542) (xy 136.48944 -266.81938) (xy 136.50214 -266.85113)
			(xy 140.399262 -266.85113) (xy 141.383258 -265.867134) (xy 141.383258 -231.246426) (xy 140.70838 -230.571548)
			(xy 135.88238 -230.571548) (xy 135.857421 -230.570975) (xy 135.808462 -230.561231) (xy 135.762346 -230.542121)
			(xy 135.720845 -230.514381) (xy 135.702802 -230.497126) (xy 135.62076 -230.415084) (xy 135.600186 -230.41483)
			(xy 135.574916 -230.41397) (xy 135.525079 -230.405437) (xy 135.477142 -230.389362) (xy 135.432236 -230.366124)
			(xy 135.391427 -230.336274) (xy 135.355679 -230.300518) (xy 135.325837 -230.259701) (xy 135.30261 -230.214791)
			(xy 135.286545 -230.16685) (xy 135.278023 -230.117011) (xy 135.277098 -230.091742) (xy 135.276844 -230.071168)
			(xy 133.92531 -228.719634) (xy 133.903669 -228.73551) (xy 133.856301 -228.760744) (xy 133.805461 -228.777942)
			(xy 133.752501 -228.786645) (xy 133.725666 -228.787198) (xy 133.699879 -228.78669) (xy 133.648941 -228.778618)
			(xy 133.599893 -228.762677) (xy 133.553942 -228.739261) (xy 133.512219 -228.708946) (xy 133.475751 -228.672478)
			(xy 133.445436 -228.630755) (xy 133.422021 -228.584803) (xy 133.406081 -228.535755) (xy 133.39801 -228.484817)
			(xy 133.397498 -228.45903) (xy 133.398008 -228.432191) (xy 133.4067 -228.379223) (xy 133.423905 -228.328378)
			(xy 133.449164 -228.281016) (xy 133.465062 -228.259386) (xy 133.166612 -227.960936) (xy 133.155182 -227.95738)
			(xy 133.130644 -227.94896) (xy 133.084383 -227.925486) (xy 133.042391 -227.895025) (xy 133.005714 -227.858338)
			(xy 132.975266 -227.816338) (xy 132.951804 -227.77007) (xy 132.943346 -227.745544) (xy 132.93979 -227.734114)
			(xy 132.501386 -227.29571) (xy 129.228342 -227.29571) (xy 129.203388 -227.295093) (xy 129.154439 -227.285346)
			(xy 129.108333 -227.266238) (xy 129.066839 -227.238504) (xy 129.048764 -227.221288) (xy 128.984502 -227.157026)
			(xy 128.968754 -227.154232) (xy 128.944235 -227.149382) (xy 128.896932 -227.133247) (xy 128.852622 -227.110127)
			(xy 128.81233 -227.080557) (xy 128.776986 -227.04522) (xy 128.747407 -227.004933) (xy 128.724279 -226.960627)
			(xy 128.708134 -226.913328) (xy 128.703324 -226.888802) (xy 128.70053 -226.873054) (xy 127.448564 -225.621088)
			(xy 127.4346 -225.606553) (xy 127.410999 -225.573881) (xy 127.401574 -225.556064) (xy 127.394213 -225.542764)
			(xy 127.373125 -225.520895) (xy 127.346534 -225.506199) (xy 127.316797 -225.49998) (xy 127.286546 -225.502787)
			(xy 127.272288 -225.508058) (xy 127.252305 -225.515878) (xy 127.210824 -225.526866) (xy 127.168268 -225.532382)
			(xy 127.146812 -225.532696) (xy 127.120917 -225.532189) (xy 127.069763 -225.524093) (xy 127.020504 -225.508098)
			(xy 126.974352 -225.484598) (xy 126.932442 -225.45417) (xy 126.895806 -225.417563) (xy 126.865344 -225.375679)
			(xy 126.841805 -225.329546) (xy 126.82577 -225.2803) (xy 126.817632 -225.229153) (xy 126.81712 -225.203258)
			(xy 126.817711 -225.17554) (xy 126.827035 -225.120894) (xy 126.835662 -225.094546) (xy 126.843536 -225.072448)
			(xy 126.638558 -224.71761) (xy 126.615698 -224.713292) (xy 126.590895 -224.708095) (xy 126.543154 -224.691108)
			(xy 126.498573 -224.667016) (xy 126.458204 -224.636387) (xy 126.422996 -224.599942) (xy 126.393778 -224.55854)
			(xy 126.371239 -224.513155) (xy 126.355909 -224.464855) (xy 126.34815 -224.414779) (xy 126.347728 -224.389442)
			(xy 126.348236 -224.363555) (xy 126.356335 -224.312417) (xy 126.372334 -224.263177) (xy 126.39584 -224.217045)
			(xy 126.426272 -224.175158) (xy 126.462882 -224.138548) (xy 126.504769 -224.108116) (xy 126.550901 -224.08461)
			(xy 126.600141 -224.068611) (xy 126.651279 -224.060512) (xy 126.703053 -224.060512) (xy 126.754191 -224.068611)
			(xy 126.803431 -224.08461) (xy 126.849563 -224.108116) (xy 126.89145 -224.138548) (xy 126.92806 -224.175158)
			(xy 126.958492 -224.217045) (xy 126.981998 -224.263177) (xy 126.997997 -224.312417) (xy 127.006096 -224.363555)
			(xy 127.006604 -224.389442) (xy 127.006079 -224.417151) (xy 126.996888 -224.471799) (xy 126.988316 -224.498154)
			(xy 126.980442 -224.520252) (xy 127.18542 -224.87509) (xy 127.20828 -224.879408) (xy 127.242824 -224.888044)
			(xy 127.255945 -224.891615) (xy 127.283116 -224.892439) (xy 127.309542 -224.886064) (xy 127.333347 -224.87294)
			(xy 127.352845 -224.853999) (xy 127.366653 -224.830584) (xy 127.373792 -224.804354) (xy 127.374142 -224.790762)
			(xy 127.374142 -224.6122) (xy 127.357934 -224.593859) (xy 127.330558 -224.553287) (xy 127.309481 -224.509113)
			(xy 127.295165 -224.462309) (xy 127.287925 -224.413903) (xy 127.287921 -224.364959) (xy 127.295151 -224.316551)
			(xy 127.309458 -224.269745) (xy 127.330528 -224.225567) (xy 127.357896 -224.18499) (xy 127.374142 -224.166684)
			(xy 127.374142 -222.982282) (xy 127.356443 -222.962) (xy 127.327232 -222.916791) (xy 127.305789 -222.867421)
			(xy 127.292692 -222.815213) (xy 127.28829 -222.761567) (xy 127.292703 -222.707923) (xy 127.30581 -222.655718)
			(xy 127.327262 -222.606351) (xy 127.356483 -222.561148) (xy 127.374142 -222.54083) (xy 127.374142 -222.360236)
			(xy 127.373706 -222.346658) (xy 127.366539 -222.320465) (xy 127.352729 -222.297084) (xy 127.333249 -222.278163)
			(xy 127.309475 -222.26504) (xy 127.283084 -222.258639) (xy 127.255939 -222.259414) (xy 127.242824 -222.262954)
			(xy 127.219389 -222.269667) (xy 127.171185 -222.276933) (xy 127.146812 -222.277432) (xy 127.120903 -222.276925)
			(xy 127.069722 -222.268821) (xy 127.020439 -222.252811) (xy 126.974268 -222.229289) (xy 126.932344 -222.198834)
			(xy 126.8957 -222.162196) (xy 126.865238 -222.120277) (xy 126.841709 -222.074109) (xy 126.825691 -222.024828)
			(xy 126.817579 -221.973649) (xy 126.81712 -221.94774) (xy 126.817582 -221.922391) (xy 126.82534 -221.87229)
			(xy 126.840678 -221.823968) (xy 126.863235 -221.778565) (xy 126.892479 -221.737152) (xy 126.927719 -221.700705)
			(xy 126.968126 -221.670085) (xy 127.012745 -221.646013) (xy 127.060523 -221.629058) (xy 127.085344 -221.62389)
			(xy 127.108204 -221.619572) (xy 127.313436 -221.264226) (xy 127.305562 -221.242128) (xy 127.297099 -221.215884)
			(xy 127.288034 -221.161495) (xy 127.287528 -221.133924) (xy 127.287972 -221.109454) (xy 127.295201 -221.061052)
			(xy 127.309504 -221.014249) (xy 127.330567 -220.970074) (xy 127.357927 -220.929497) (xy 127.374142 -220.911166)
			(xy 127.374142 -219.726764) (xy 127.356437 -219.706482) (xy 127.327212 -219.661271) (xy 127.305757 -219.611896)
			(xy 127.292647 -219.559682) (xy 127.288235 -219.506028) (xy 127.292638 -219.452374) (xy 127.305739 -219.400157)
			(xy 127.327185 -219.350779) (xy 127.356402 -219.305563) (xy 127.374142 -219.285312) (xy 127.374142 -219.104718)
			(xy 127.373704 -219.091142) (xy 127.366534 -219.064953) (xy 127.352723 -219.041576) (xy 127.333244 -219.022659)
			(xy 127.309472 -219.009539) (xy 127.283084 -219.003139) (xy 127.255943 -219.003913) (xy 127.242824 -219.007436)
			(xy 127.219382 -219.014095) (xy 127.171178 -219.021231) (xy 127.146812 -219.02166) (xy 127.120918 -219.021153)
			(xy 127.069766 -219.013057) (xy 127.020509 -218.997062) (xy 126.97436 -218.973561) (xy 126.932453 -218.943132)
			(xy 126.89582 -218.906525) (xy 126.865362 -218.86464) (xy 126.841828 -218.818507) (xy 126.825798 -218.769262)
			(xy 126.817665 -218.718116) (xy 126.81712 -218.692222) (xy 126.817584 -218.666874) (xy 126.825343 -218.616775)
			(xy 126.840683 -218.568455) (xy 126.863241 -218.523054) (xy 126.892486 -218.481643) (xy 126.927726 -218.445199)
			(xy 126.968132 -218.414581) (xy 127.01275 -218.390511) (xy 127.060527 -218.373557) (xy 127.085344 -218.368372)
			(xy 127.108204 -218.364054) (xy 127.313436 -218.008708) (xy 127.305562 -217.98661) (xy 127.2971 -217.960365)
			(xy 127.288038 -217.905976) (xy 127.287528 -217.878406) (xy 127.287973 -217.853937) (xy 127.295204 -217.805535)
			(xy 127.30951 -217.758734) (xy 127.330574 -217.714561) (xy 127.357936 -217.673986) (xy 127.374142 -217.655648)
			(xy 127.374142 -216.471246) (xy 127.356438 -216.450964) (xy 127.327216 -216.405753) (xy 127.305764 -216.356379)
			(xy 127.292657 -216.304167) (xy 127.288247 -216.250515) (xy 127.292652 -216.196863) (xy 127.305754 -216.144649)
			(xy 127.327202 -216.095273) (xy 127.35642 -216.050059) (xy 127.374142 -216.029794) (xy 127.374142 -215.8492)
			(xy 127.373702 -215.835626) (xy 127.366529 -215.809441) (xy 127.352717 -215.786068) (xy 127.333239 -215.767156)
			(xy 127.309469 -215.754038) (xy 127.283084 -215.747639) (xy 127.255946 -215.748412) (xy 127.242824 -215.751918)
			(xy 127.219389 -215.758632) (xy 127.171185 -215.765898) (xy 127.146812 -215.766396) (xy 127.120902 -215.765915)
			(xy 127.069719 -215.757811) (xy 127.020435 -215.741799) (xy 126.974262 -215.718274) (xy 126.932338 -215.687816)
			(xy 126.895694 -215.651175) (xy 126.865234 -215.609252) (xy 126.841707 -215.56308) (xy 126.825693 -215.513796)
			(xy 126.817586 -215.462614) (xy 126.81712 -215.436704) (xy 126.817585 -215.411357) (xy 126.825347 -215.36126)
			(xy 126.840688 -215.312942) (xy 126.863248 -215.267544) (xy 126.892492 -215.226135) (xy 126.927733 -215.189693)
			(xy 126.968138 -215.159077) (xy 127.012755 -215.135008) (xy 127.060531 -215.118056) (xy 127.085344 -215.112854)
			(xy 127.108204 -215.108536) (xy 127.313182 -214.753444) (xy 127.305308 -214.7316) (xy 127.296731 -214.705181)
			(xy 127.287541 -214.650406) (xy 127.28702 -214.622634) (xy 127.287525 -214.596744) (xy 127.29562 -214.5456)
			(xy 127.311616 -214.496352) (xy 127.335118 -214.450212) (xy 127.36555 -214.408318) (xy 127.40216 -214.371699)
			(xy 127.444047 -214.341258) (xy 127.490181 -214.317745) (xy 127.539426 -214.301738) (xy 127.590568 -214.293631)
			(xy 127.616458 -214.293196) (xy 127.640666 -214.293627) (xy 127.68856 -214.300718) (xy 127.734901 -214.31474)
			(xy 127.778693 -214.33539) (xy 127.818992 -214.362224) (xy 127.854933 -214.394665) (xy 127.885741 -214.432014)
			(xy 127.910753 -214.473469) (xy 127.920496 -214.495634) (xy 127.926655 -214.509067) (xy 127.945367 -214.531924)
			(xy 127.969832 -214.548477) (xy 127.998009 -214.557346) (xy 128.027545 -214.557791) (xy 128.041908 -214.554308)
			(xy 128.058776 -214.549913) (xy 128.093313 -214.5452) (xy 128.110742 -214.54491) (xy 128.233932 -214.54491)
			(xy 128.246124 -214.511382) (xy 128.255014 -214.488776) (xy 128.26492 -214.466424) (xy 128.051306 -214.061294)
			(xy 128.027176 -214.056722) (xy 128.002255 -214.051631) (xy 127.954254 -214.034807) (xy 127.909406 -214.010813)
			(xy 127.868773 -213.980218) (xy 127.833318 -213.943748) (xy 127.803882 -213.902268) (xy 127.781163 -213.856761)
			(xy 127.765699 -213.808305) (xy 127.757858 -213.758049) (xy 127.757428 -213.732618) (xy 127.757936 -213.706731)
			(xy 127.766035 -213.655593) (xy 127.782034 -213.606353) (xy 127.80554 -213.560221) (xy 127.835972 -213.518334)
			(xy 127.872582 -213.481724) (xy 127.914469 -213.451292) (xy 127.960601 -213.427786) (xy 128.009841 -213.411787)
			(xy 128.060979 -213.403688) (xy 128.112753 -213.403688) (xy 128.163891 -213.411787) (xy 128.213131 -213.427786)
			(xy 128.259263 -213.451292) (xy 128.30115 -213.481724) (xy 128.33776 -213.518334) (xy 128.368192 -213.560221)
			(xy 128.391698 -213.606353) (xy 128.407697 -213.655593) (xy 128.415796 -213.706731) (xy 128.416304 -213.732618)
			(xy 128.415939 -213.755594) (xy 128.409621 -213.801108) (xy 128.39704 -213.845303) (xy 128.38811 -213.866476)
			(xy 128.378204 -213.888828) (xy 128.591818 -214.293958) (xy 128.615948 -214.29853) (xy 128.640053 -214.303426)
			(xy 128.686567 -214.319417) (xy 128.730185 -214.342149) (xy 128.769936 -214.371115) (xy 128.804937 -214.405672)
			(xy 128.834409 -214.44505) (xy 128.857695 -214.488374) (xy 128.866392 -214.511382) (xy 128.878584 -214.54491)
			(xy 129.173732 -214.54491) (xy 129.185924 -214.511382) (xy 129.194888 -214.487752) (xy 129.219016 -214.443346)
			(xy 129.249642 -214.403145) (xy 129.286046 -214.368092) (xy 129.327377 -214.339009) (xy 129.372664 -214.316578)
			(xy 129.420844 -214.301325) (xy 129.470789 -214.293608) (xy 129.521327 -214.293608) (xy 129.571272 -214.301325)
			(xy 129.619452 -214.316578) (xy 129.664739 -214.339009) (xy 129.70607 -214.368092) (xy 129.742474 -214.403145)
			(xy 129.7731 -214.443346) (xy 129.797228 -214.487752) (xy 129.806192 -214.511382) (xy 129.818384 -214.54491)
			(xy 130.113532 -214.54491) (xy 130.125724 -214.511382) (xy 130.134614 -214.488776) (xy 130.14452 -214.466424)
			(xy 129.930906 -214.061294) (xy 129.906776 -214.056722) (xy 129.881855 -214.051631) (xy 129.833854 -214.034807)
			(xy 129.789006 -214.010813) (xy 129.748373 -213.980218) (xy 129.712918 -213.943748) (xy 129.683482 -213.902268)
			(xy 129.660763 -213.856761) (xy 129.645299 -213.808305) (xy 129.637458 -213.758049) (xy 129.637028 -213.732618)
			(xy 129.637536 -213.706731) (xy 129.645635 -213.655593) (xy 129.661634 -213.606353) (xy 129.68514 -213.560221)
			(xy 129.715572 -213.518334) (xy 129.752182 -213.481724) (xy 129.794069 -213.451292) (xy 129.840201 -213.427786)
			(xy 129.889441 -213.411787) (xy 129.940579 -213.403688) (xy 129.992353 -213.403688) (xy 130.043491 -213.411787)
			(xy 130.092731 -213.427786) (xy 130.138863 -213.451292) (xy 130.18075 -213.481724) (xy 130.21736 -213.518334)
			(xy 130.247792 -213.560221) (xy 130.271298 -213.606353) (xy 130.287297 -213.655593) (xy 130.295396 -213.706731)
			(xy 130.295904 -213.732618) (xy 130.295539 -213.755594) (xy 130.289221 -213.801108) (xy 130.27664 -213.845303)
			(xy 130.26771 -213.866476) (xy 130.257804 -213.888828) (xy 130.471418 -214.293958) (xy 130.495548 -214.29853)
			(xy 130.519653 -214.303426) (xy 130.566167 -214.319417) (xy 130.609785 -214.342149) (xy 130.649536 -214.371115)
			(xy 130.684537 -214.405672) (xy 130.714009 -214.44505) (xy 130.737295 -214.488374) (xy 130.745992 -214.511382)
			(xy 130.758184 -214.54491) (xy 131.053332 -214.54491) (xy 131.065524 -214.511382) (xy 131.074488 -214.487752)
			(xy 131.098616 -214.443346) (xy 131.129242 -214.403145) (xy 131.165646 -214.368092) (xy 131.206977 -214.339009)
			(xy 131.252264 -214.316578) (xy 131.300444 -214.301325) (xy 131.350389 -214.293608) (xy 131.400927 -214.293608)
			(xy 131.450872 -214.301325) (xy 131.499052 -214.316578) (xy 131.544339 -214.339009) (xy 131.58567 -214.368092)
			(xy 131.622074 -214.403145) (xy 131.6527 -214.443346) (xy 131.676828 -214.487752) (xy 131.685792 -214.511382)
			(xy 131.697984 -214.54491) (xy 131.993132 -214.54491) (xy 132.005324 -214.511382) (xy 132.014214 -214.488776)
			(xy 132.02412 -214.466424) (xy 131.810506 -214.061294) (xy 131.786376 -214.056722) (xy 131.761455 -214.051631)
			(xy 131.713454 -214.034807) (xy 131.668606 -214.010813) (xy 131.627973 -213.980218) (xy 131.592518 -213.943748)
			(xy 131.563082 -213.902268) (xy 131.540363 -213.856761) (xy 131.524899 -213.808305) (xy 131.517058 -213.758049)
			(xy 131.516628 -213.732618) (xy 131.517136 -213.706731) (xy 131.525235 -213.655593) (xy 131.541234 -213.606353)
			(xy 131.56474 -213.560221) (xy 131.595172 -213.518334) (xy 131.631782 -213.481724) (xy 131.673669 -213.451292)
			(xy 131.719801 -213.427786) (xy 131.769041 -213.411787) (xy 131.820179 -213.403688) (xy 131.871953 -213.403688)
			(xy 131.923091 -213.411787) (xy 131.972331 -213.427786) (xy 132.018463 -213.451292) (xy 132.06035 -213.481724)
			(xy 132.09696 -213.518334) (xy 132.127392 -213.560221) (xy 132.150898 -213.606353) (xy 132.166897 -213.655593)
			(xy 132.174996 -213.706731) (xy 132.175504 -213.732618) (xy 132.175139 -213.755594) (xy 132.168821 -213.801108)
			(xy 132.15624 -213.845303) (xy 132.14731 -213.866476) (xy 132.137404 -213.888828) (xy 132.351018 -214.293958)
			(xy 132.375148 -214.29853) (xy 132.399253 -214.303426) (xy 132.445767 -214.319417) (xy 132.489385 -214.342149)
			(xy 132.529136 -214.371115) (xy 132.564137 -214.405672) (xy 132.593609 -214.44505) (xy 132.616895 -214.488374)
			(xy 132.625592 -214.511382) (xy 132.637784 -214.54491) (xy 132.932932 -214.54491) (xy 132.945124 -214.511382)
			(xy 132.954088 -214.487752) (xy 132.978216 -214.443346) (xy 133.008842 -214.403145) (xy 133.045246 -214.368092)
			(xy 133.086577 -214.339009) (xy 133.131864 -214.316578) (xy 133.180044 -214.301325) (xy 133.229989 -214.293608)
			(xy 133.280527 -214.293608) (xy 133.330472 -214.301325) (xy 133.378652 -214.316578) (xy 133.423939 -214.339009)
			(xy 133.46527 -214.368092) (xy 133.501674 -214.403145) (xy 133.5323 -214.443346) (xy 133.556428 -214.487752)
			(xy 133.565392 -214.511382) (xy 133.577584 -214.54491) (xy 133.86435 -214.54491) (xy 133.870446 -214.501222)
			(xy 133.874548 -214.475401) (xy 133.889866 -214.425415) (xy 133.912914 -214.378489) (xy 133.943108 -214.335809)
			(xy 133.979685 -214.298455) (xy 134.021721 -214.267371) (xy 134.068153 -214.243343) (xy 134.117806 -214.226979)
			(xy 134.169426 -214.218692) (xy 134.221706 -214.218692) (xy 134.273326 -214.226979) (xy 134.322979 -214.243343)
			(xy 134.369411 -214.267371) (xy 134.411447 -214.298455) (xy 134.448024 -214.335809) (xy 134.478218 -214.378489)
			(xy 134.501266 -214.425415) (xy 134.516584 -214.475401) (xy 134.520686 -214.501222) (xy 134.526782 -214.54491)
			(xy 134.802626 -214.54491) (xy 134.808722 -214.501222) (xy 134.812828 -214.47529) (xy 134.828187 -214.425087)
			(xy 134.851312 -214.377954) (xy 134.881618 -214.335084) (xy 134.918338 -214.297562) (xy 134.960543 -214.266337)
			(xy 135.007166 -214.2422) (xy 135.057026 -214.225761) (xy 135.108862 -214.217436) (xy 135.161362 -214.217436)
			(xy 135.213198 -214.225761) (xy 135.263058 -214.2422) (xy 135.309681 -214.266337) (xy 135.351886 -214.297562)
			(xy 135.388606 -214.335084) (xy 135.418912 -214.377954) (xy 135.442037 -214.425087) (xy 135.457396 -214.47529)
			(xy 135.461502 -214.501222) (xy 135.467598 -214.54491) (xy 135.74395 -214.54491) (xy 135.750046 -214.501222)
			(xy 135.754148 -214.475401) (xy 135.769466 -214.425415) (xy 135.792514 -214.378489) (xy 135.822708 -214.335809)
			(xy 135.859285 -214.298455) (xy 135.901321 -214.267371) (xy 135.947753 -214.243343) (xy 135.997406 -214.226979)
			(xy 136.049026 -214.218692) (xy 136.101306 -214.218692) (xy 136.152926 -214.226979) (xy 136.202579 -214.243343)
			(xy 136.249011 -214.267371) (xy 136.291047 -214.298455) (xy 136.327624 -214.335809) (xy 136.357818 -214.378489)
			(xy 136.380866 -214.425415) (xy 136.396184 -214.475401) (xy 136.400286 -214.501222) (xy 136.406382 -214.54491)
			(xy 150.941278 -214.54491) (xy 150.94585 -214.544148) (xy 150.957301 -214.542136) (xy 150.980452 -214.539974)
			(xy 150.992078 -214.53983) (xy 151.246078 -214.53983) (xy 151.257703 -214.539987) (xy 151.280853 -214.542147)
			(xy 151.292306 -214.544148) (xy 151.296878 -214.54491) (xy 151.449278 -214.54491) (xy 151.45385 -214.544148)
			(xy 151.465301 -214.542136) (xy 151.488452 -214.539974) (xy 151.500078 -214.53983) (xy 153.741882 -214.53983)
			(xy 154.144218 -214.137494) (xy 154.144218 -196.352922) (xy 152.499822 -194.708526) (xy 152.482561 -194.690486)
			(xy 152.454802 -194.648993) (xy 152.435689 -194.602874) (xy 152.42596 -194.553909) (xy 152.4254 -194.528948)
			(xy 152.4254 -193.135504) (xy 97.990406 -138.70051) (xy 61.93282 -138.70051) (xy 61.39434 -139.23899)
			(xy 61.39434 -144.56918) (xy 61.418119 -144.582628) (xy 61.461913 -144.615281) (xy 61.500604 -144.653845)
			(xy 61.533399 -144.697533) (xy 61.55963 -144.745451) (xy 61.57876 -144.79662) (xy 61.590398 -144.849993)
			(xy 61.594305 -144.904481) (xy 61.590403 -144.958969) (xy 61.578771 -145.012344) (xy 61.559646 -145.063514)
			(xy 61.53342 -145.111435) (xy 61.500629 -145.155126) (xy 61.461942 -145.193694) (xy 61.418151 -145.226352)
			(xy 61.39434 -145.23974) (xy 61.39434 -150.5966) (xy 61.419803 -150.611035) (xy 61.466366 -150.646496)
			(xy 61.506966 -150.688655) (xy 61.54065 -150.73652) (xy 61.566626 -150.788969) (xy 61.584286 -150.844771)
			(xy 61.593215 -150.902615) (xy 61.59373 -150.93188) (xy 61.59321 -150.960619) (xy 61.584589 -151.017447)
			(xy 61.567538 -151.072338) (xy 61.542445 -151.12405) (xy 61.509877 -151.171411) (xy 61.490606 -151.192738)
			(xy 61.480533 -151.204273) (xy 61.467188 -151.231821) (xy 61.4626 -151.262085) (xy 61.46718 -151.292351)
			(xy 61.480517 -151.319903) (xy 61.490606 -151.331422) (xy 61.509877 -151.352749) (xy 61.542442 -151.400112)
			(xy 61.567534 -151.451823) (xy 61.584586 -151.506714) (xy 61.59321 -151.563541) (xy 61.59373 -151.59228)
			(xy 61.593192 -151.621541) (xy 61.584246 -151.679374) (xy 61.566576 -151.735164) (xy 61.540597 -151.787602)
			(xy 61.506916 -151.83546) (xy 61.466325 -151.877616) (xy 61.419773 -151.91308) (xy 61.39434 -151.92756)
			(xy 61.39434 -153.20518) (xy 61.418119 -153.218628) (xy 61.461913 -153.251281) (xy 61.500604 -153.289845)
			(xy 61.533399 -153.333533) (xy 61.55963 -153.381451) (xy 61.57876 -153.43262) (xy 61.590398 -153.485993)
			(xy 61.594305 -153.540481) (xy 61.590403 -153.594969) (xy 61.578771 -153.648344) (xy 61.559646 -153.699514)
			(xy 61.53342 -153.747435) (xy 61.500629 -153.791126) (xy 61.461942 -153.829694) (xy 61.418151 -153.862352)
			(xy 61.39434 -153.87574) (xy 61.39434 -159.2326) (xy 61.419803 -159.247035) (xy 61.466366 -159.282496)
			(xy 61.506966 -159.324655) (xy 61.54065 -159.37252) (xy 61.566626 -159.424969) (xy 61.584286 -159.480771)
			(xy 61.593215 -159.538615) (xy 61.59373 -159.56788) (xy 61.59321 -159.596619) (xy 61.584589 -159.653447)
			(xy 61.567538 -159.708338) (xy 61.542445 -159.76005) (xy 61.509877 -159.807411) (xy 61.490606 -159.828738)
			(xy 61.480533 -159.840273) (xy 61.467188 -159.867821) (xy 61.4626 -159.898085) (xy 61.46718 -159.928351)
			(xy 61.480517 -159.955903) (xy 61.490606 -159.967422) (xy 61.509877 -159.988749) (xy 61.542442 -160.036112)
			(xy 61.567534 -160.087823) (xy 61.584586 -160.142714) (xy 61.59321 -160.199541) (xy 61.59373 -160.22828)
			(xy 61.59324 -160.255522) (xy 61.585481 -160.309452) (xy 61.570134 -160.361731) (xy 61.547508 -160.411297)
			(xy 61.518065 -160.457141) (xy 61.482403 -160.498334) (xy 61.462158 -160.51657) (xy 61.45196 -160.526056)
			(xy 61.436646 -160.549307) (xy 61.428172 -160.575826) (xy 61.427165 -160.603648) (xy 61.4337 -160.63071)
			(xy 61.447293 -160.655006) (xy 61.456824 -160.66516) (xy 62.005972 -161.214308) (xy 70.633844 -161.214308)
			(xy 71.788782 -160.05937) (xy 71.806824 -160.042113) (xy 71.848318 -160.01436) (xy 71.894437 -159.995253)
			(xy 71.9434 -159.985527) (xy 71.96836 -159.984948) (xy 72.485504 -159.984948) (xy 72.502195 -159.963249)
			(xy 72.540767 -159.924404) (xy 72.584497 -159.891472) (xy 72.632485 -159.865129) (xy 72.683745 -159.845916)
			(xy 72.737226 -159.834229) (xy 72.791828 -159.830306) (xy 72.84643 -159.834229) (xy 72.899911 -159.845916)
			(xy 72.951171 -159.865129) (xy 72.999159 -159.891472) (xy 73.042889 -159.924404) (xy 73.081461 -159.963249)
			(xy 73.098152 -159.984948) (xy 74.975974 -159.984948) (xy 74.992571 -159.96242) (xy 75.031284 -159.92202)
			(xy 75.075485 -159.887711) (xy 75.124227 -159.860231) (xy 75.176461 -159.840169) (xy 75.231066 -159.827957)
			(xy 75.28687 -159.823857) (xy 75.342674 -159.827957) (xy 75.397279 -159.840169) (xy 75.449513 -159.860231)
			(xy 75.498255 -159.887711) (xy 75.542456 -159.92202) (xy 75.581169 -159.96242) (xy 75.597766 -159.984948)
			(xy 80.003904 -159.984948) (xy 80.028864 -159.98552) (xy 80.077824 -159.995261) (xy 80.123943 -160.014368)
			(xy 80.165446 -160.042107) (xy 80.183482 -160.05937) (xy 83.265518 -163.141406) (xy 83.271614 -163.147756)
			(xy 83.272122 -163.148264) (xy 115.53952 -195.415662) (xy 115.55678 -195.433703) (xy 115.584536 -195.475196)
			(xy 115.603648 -195.521315) (xy 115.613378 -195.570279) (xy 115.613942 -195.59524) (xy 115.613942 -206.024988)
			(xy 132.710692 -206.024988) (xy 132.714673 -205.891968) (xy 132.726602 -205.759423) (xy 132.746437 -205.62783)
			(xy 132.774106 -205.497658) (xy 132.80951 -205.369373) (xy 132.852523 -205.243436) (xy 132.90299 -205.120297)
			(xy 132.960731 -205.000396) (xy 133.02554 -204.884163) (xy 133.097184 -204.772013) (xy 133.175406 -204.664349)
			(xy 133.259927 -204.561556) (xy 133.350445 -204.464001) (xy 133.446634 -204.372035) (xy 133.548152 -204.285985)
			(xy 133.654633 -204.206161) (xy 133.765698 -204.132848) (xy 133.880949 -204.066308) (xy 133.999973 -204.006779)
			(xy 134.122344 -203.954475) (xy 134.247623 -203.909583) (xy 134.375364 -203.872264) (xy 134.505107 -203.842651)
			(xy 134.636389 -203.82085) (xy 134.76874 -203.80694) (xy 134.901686 -203.800969) (xy 135.034751 -203.80296)
			(xy 135.167459 -203.812905) (xy 135.299335 -203.830769) (xy 135.429906 -203.856487) (xy 135.558706 -203.889968)
			(xy 135.685272 -203.931092) (xy 135.809153 -203.979712) (xy 135.929904 -204.035653) (xy 136.047094 -204.098715)
			(xy 136.160303 -204.168673) (xy 136.269125 -204.245277) (xy 136.373171 -204.328251) (xy 136.472069 -204.417299)
			(xy 136.565464 -204.512102) (xy 136.653022 -204.61232) (xy 136.734431 -204.717596) (xy 136.809397 -204.827552)
			(xy 136.877654 -204.941794) (xy 136.938956 -205.059914) (xy 136.993085 -205.181489) (xy 137.039846 -205.306083)
			(xy 137.079072 -205.433251) (xy 137.110622 -205.562537) (xy 137.134385 -205.693478) (xy 137.150274 -205.825606)
			(xy 137.158232 -205.958448) (xy 137.15873 -206.024988) (xy 137.158232 -206.091528) (xy 137.150274 -206.22437)
			(xy 137.134385 -206.356498) (xy 137.110622 -206.487439) (xy 137.079072 -206.616725) (xy 137.039846 -206.743893)
			(xy 136.993085 -206.868487) (xy 136.938956 -206.990062) (xy 136.877654 -207.108182) (xy 136.809397 -207.222424)
			(xy 136.734431 -207.33238) (xy 136.653022 -207.437656) (xy 136.565464 -207.537874) (xy 136.472069 -207.632677)
			(xy 136.373171 -207.721725) (xy 136.269125 -207.804699) (xy 136.160303 -207.881303) (xy 136.047094 -207.951261)
			(xy 135.929904 -208.014323) (xy 135.809153 -208.070264) (xy 135.685272 -208.118884) (xy 135.558706 -208.160008)
			(xy 135.429906 -208.193489) (xy 135.299335 -208.219207) (xy 135.167459 -208.237071) (xy 135.034751 -208.247016)
			(xy 134.901686 -208.249007) (xy 134.76874 -208.243036) (xy 134.636389 -208.229126) (xy 134.505107 -208.207325)
			(xy 134.375364 -208.177712) (xy 134.247623 -208.140393) (xy 134.122344 -208.095501) (xy 133.999973 -208.043197)
			(xy 133.880949 -207.983668) (xy 133.765698 -207.917128) (xy 133.654633 -207.843815) (xy 133.548152 -207.763991)
			(xy 133.446634 -207.677941) (xy 133.350445 -207.585975) (xy 133.259927 -207.48842) (xy 133.175406 -207.385627)
			(xy 133.097184 -207.277963) (xy 133.02554 -207.165813) (xy 132.960731 -207.04958) (xy 132.90299 -206.929679)
			(xy 132.852523 -206.80654) (xy 132.80951 -206.680603) (xy 132.774106 -206.552318) (xy 132.746437 -206.422146)
			(xy 132.726602 -206.290553) (xy 132.714673 -206.158008) (xy 132.710692 -206.024988) (xy 115.613942 -206.024988)
			(xy 115.613942 -213.732618) (xy 116.479828 -213.732618) (xy 116.480336 -213.706731) (xy 116.488435 -213.655593)
			(xy 116.504434 -213.606353) (xy 116.52794 -213.560221) (xy 116.558372 -213.518334) (xy 116.594982 -213.481724)
			(xy 116.636869 -213.451292) (xy 116.683001 -213.427786) (xy 116.732241 -213.411787) (xy 116.783379 -213.403688)
			(xy 116.835153 -213.403688) (xy 116.886291 -213.411787) (xy 116.935531 -213.427786) (xy 116.981663 -213.451292)
			(xy 117.02355 -213.481724) (xy 117.06016 -213.518334) (xy 117.090592 -213.560221) (xy 117.114098 -213.606353)
			(xy 117.130097 -213.655593) (xy 117.138196 -213.706731) (xy 117.138704 -213.732618) (xy 118.359428 -213.732618)
			(xy 118.359936 -213.706731) (xy 118.368035 -213.655593) (xy 118.384034 -213.606353) (xy 118.40754 -213.560221)
			(xy 118.437972 -213.518334) (xy 118.474582 -213.481724) (xy 118.516469 -213.451292) (xy 118.562601 -213.427786)
			(xy 118.611841 -213.411787) (xy 118.662979 -213.403688) (xy 118.714753 -213.403688) (xy 118.765891 -213.411787)
			(xy 118.815131 -213.427786) (xy 118.861263 -213.451292) (xy 118.90315 -213.481724) (xy 118.93976 -213.518334)
			(xy 118.970192 -213.560221) (xy 118.993698 -213.606353) (xy 119.009697 -213.655593) (xy 119.017796 -213.706731)
			(xy 119.018304 -213.732618) (xy 120.239028 -213.732618) (xy 120.239536 -213.706731) (xy 120.247635 -213.655593)
			(xy 120.263634 -213.606353) (xy 120.28714 -213.560221) (xy 120.317572 -213.518334) (xy 120.354182 -213.481724)
			(xy 120.396069 -213.451292) (xy 120.442201 -213.427786) (xy 120.491441 -213.411787) (xy 120.542579 -213.403688)
			(xy 120.594353 -213.403688) (xy 120.645491 -213.411787) (xy 120.694731 -213.427786) (xy 120.740863 -213.451292)
			(xy 120.78275 -213.481724) (xy 120.81936 -213.518334) (xy 120.849792 -213.560221) (xy 120.873298 -213.606353)
			(xy 120.889297 -213.655593) (xy 120.897396 -213.706731) (xy 120.897904 -213.732618) (xy 122.118628 -213.732618)
			(xy 122.119136 -213.706731) (xy 122.127235 -213.655593) (xy 122.143234 -213.606353) (xy 122.16674 -213.560221)
			(xy 122.197172 -213.518334) (xy 122.233782 -213.481724) (xy 122.275669 -213.451292) (xy 122.321801 -213.427786)
			(xy 122.371041 -213.411787) (xy 122.422179 -213.403688) (xy 122.473953 -213.403688) (xy 122.525091 -213.411787)
			(xy 122.574331 -213.427786) (xy 122.620463 -213.451292) (xy 122.66235 -213.481724) (xy 122.69896 -213.518334)
			(xy 122.729392 -213.560221) (xy 122.752898 -213.606353) (xy 122.768897 -213.655593) (xy 122.776996 -213.706731)
			(xy 122.777504 -213.732618) (xy 123.99772 -213.732618) (xy 123.998228 -213.706711) (xy 124.006334 -213.655534)
			(xy 124.022346 -213.606255) (xy 124.045869 -213.560088) (xy 124.076325 -213.518169) (xy 124.112963 -213.481531)
			(xy 124.154882 -213.451075) (xy 124.201049 -213.427552) (xy 124.250328 -213.41154) (xy 124.301505 -213.403434)
			(xy 124.353319 -213.403434) (xy 124.404496 -213.41154) (xy 124.453775 -213.427552) (xy 124.499942 -213.451075)
			(xy 124.541861 -213.481531) (xy 124.578499 -213.518169) (xy 124.608955 -213.560088) (xy 124.632478 -213.606255)
			(xy 124.64849 -213.655534) (xy 124.656596 -213.706711) (xy 124.657104 -213.732618) (xy 125.87732 -213.732618)
			(xy 125.877828 -213.706711) (xy 125.885934 -213.655534) (xy 125.901946 -213.606255) (xy 125.925469 -213.560088)
			(xy 125.955925 -213.518169) (xy 125.992563 -213.481531) (xy 126.034482 -213.451075) (xy 126.080649 -213.427552)
			(xy 126.129928 -213.41154) (xy 126.181105 -213.403434) (xy 126.232919 -213.403434) (xy 126.284096 -213.41154)
			(xy 126.333375 -213.427552) (xy 126.379542 -213.451075) (xy 126.421461 -213.481531) (xy 126.458099 -213.518169)
			(xy 126.488555 -213.560088) (xy 126.512078 -213.606255) (xy 126.52809 -213.655534) (xy 126.536196 -213.706711)
			(xy 126.536704 -213.732618) (xy 126.536283 -213.755559) (xy 126.529855 -213.80099) (xy 126.517209 -213.845096)
			(xy 126.508256 -213.866222) (xy 126.49835 -213.888574) (xy 126.712218 -214.293958) (xy 126.736348 -214.29853)
			(xy 126.761267 -214.303641) (xy 126.809277 -214.320441) (xy 126.854136 -214.344419) (xy 126.894776 -214.375006)
			(xy 126.930234 -214.411476) (xy 126.959666 -214.452961) (xy 126.982373 -214.498476) (xy 126.997815 -214.54694)
			(xy 127.005627 -214.597201) (xy 127.006096 -214.622634) (xy 127.005588 -214.648521) (xy 126.997489 -214.699659)
			(xy 126.98149 -214.748899) (xy 126.957984 -214.795031) (xy 126.927552 -214.836918) (xy 126.890942 -214.873528)
			(xy 126.849055 -214.90396) (xy 126.802923 -214.927466) (xy 126.753683 -214.943465) (xy 126.702545 -214.951564)
			(xy 126.650771 -214.951564) (xy 126.599633 -214.943465) (xy 126.550393 -214.927466) (xy 126.504261 -214.90396)
			(xy 126.462374 -214.873528) (xy 126.425764 -214.836918) (xy 126.395332 -214.795031) (xy 126.371826 -214.748899)
			(xy 126.355827 -214.699659) (xy 126.347728 -214.648521) (xy 126.34722 -214.622634) (xy 126.347587 -214.599658)
			(xy 126.3539 -214.554143) (xy 126.366479 -214.509947) (xy 126.375414 -214.488776) (xy 126.38532 -214.466424)
			(xy 126.171706 -214.061294) (xy 126.147576 -214.056722) (xy 126.12262 -214.051672) (xy 126.074538 -214.034924)
			(xy 126.029605 -214.010979) (xy 125.98889 -213.980407) (xy 125.953363 -213.943936) (xy 125.92387 -213.902434)
			(xy 125.901111 -213.856888) (xy 125.88563 -213.808384) (xy 125.877795 -213.758075) (xy 125.87732 -213.732618)
			(xy 124.657104 -213.732618) (xy 124.656681 -213.756953) (xy 124.649527 -213.805095) (xy 124.635379 -213.851663)
			(xy 124.625354 -213.873842) (xy 124.614432 -213.896448) (xy 124.820172 -214.292942) (xy 124.845826 -214.296752)
			(xy 124.87151 -214.301109) (xy 124.921167 -214.316849) (xy 124.967731 -214.340204) (xy 125.010041 -214.370592)
			(xy 125.047044 -214.407258) (xy 125.077819 -214.449288) (xy 125.101599 -214.495635) (xy 125.117793 -214.545146)
			(xy 125.125998 -214.596588) (xy 125.126496 -214.622634) (xy 125.125988 -214.648521) (xy 125.117889 -214.699659)
			(xy 125.10189 -214.748899) (xy 125.078384 -214.795031) (xy 125.047952 -214.836918) (xy 125.011342 -214.873528)
			(xy 124.969455 -214.90396) (xy 124.923323 -214.927466) (xy 124.874083 -214.943465) (xy 124.822945 -214.951564)
			(xy 124.771171 -214.951564) (xy 124.720033 -214.943465) (xy 124.670793 -214.927466) (xy 124.624661 -214.90396)
			(xy 124.582774 -214.873528) (xy 124.546164 -214.836918) (xy 124.515732 -214.795031) (xy 124.492226 -214.748899)
			(xy 124.476227 -214.699659) (xy 124.468128 -214.648521) (xy 124.46762 -214.622634) (xy 124.468099 -214.597068)
			(xy 124.476002 -214.546552) (xy 124.491623 -214.497866) (xy 124.502672 -214.474806) (xy 124.514102 -214.451438)
			(xy 124.31268 -214.062818) (xy 124.28601 -214.059516) (xy 124.259814 -214.055663) (xy 124.20902 -214.04073)
			(xy 124.161267 -214.017866) (xy 124.117785 -213.987661) (xy 124.079693 -213.950891) (xy 124.047971 -213.908503)
			(xy 124.023436 -213.861587) (xy 124.006718 -213.811352) (xy 123.998249 -213.75909) (xy 123.99772 -213.732618)
			(xy 122.777504 -213.732618) (xy 122.777153 -213.755595) (xy 122.770832 -213.80111) (xy 122.758248 -213.845306)
			(xy 122.74931 -213.866476) (xy 122.739404 -213.888828) (xy 122.953018 -214.293958) (xy 122.977148 -214.29853)
			(xy 123.002067 -214.303641) (xy 123.050077 -214.320441) (xy 123.094936 -214.344419) (xy 123.135576 -214.375006)
			(xy 123.171034 -214.411476) (xy 123.200466 -214.452961) (xy 123.223173 -214.498476) (xy 123.238615 -214.54694)
			(xy 123.246427 -214.597201) (xy 123.246896 -214.622634) (xy 123.246388 -214.648521) (xy 123.238289 -214.699659)
			(xy 123.22229 -214.748899) (xy 123.198784 -214.795031) (xy 123.168352 -214.836918) (xy 123.131742 -214.873528)
			(xy 123.089855 -214.90396) (xy 123.043723 -214.927466) (xy 122.994483 -214.943465) (xy 122.943345 -214.951564)
			(xy 122.891571 -214.951564) (xy 122.840433 -214.943465) (xy 122.791193 -214.927466) (xy 122.745061 -214.90396)
			(xy 122.703174 -214.873528) (xy 122.666564 -214.836918) (xy 122.636132 -214.795031) (xy 122.612626 -214.748899)
			(xy 122.596627 -214.699659) (xy 122.588528 -214.648521) (xy 122.58802 -214.622634) (xy 122.588387 -214.599658)
			(xy 122.5947 -214.554143) (xy 122.607279 -214.509947) (xy 122.616214 -214.488776) (xy 122.62612 -214.466424)
			(xy 122.412506 -214.061294) (xy 122.388376 -214.056722) (xy 122.36345 -214.051639) (xy 122.315436 -214.034839)
			(xy 122.270575 -214.010859) (xy 122.229932 -213.980269) (xy 122.194474 -213.943796) (xy 122.165043 -213.902307)
			(xy 122.142338 -213.856787) (xy 122.1269 -213.808318) (xy 122.119094 -213.758052) (xy 122.118628 -213.732618)
			(xy 120.897904 -213.732618) (xy 120.897553 -213.755595) (xy 120.891232 -213.80111) (xy 120.878648 -213.845306)
			(xy 120.86971 -213.866476) (xy 120.859804 -213.888828) (xy 121.073418 -214.293958) (xy 121.097548 -214.29853)
			(xy 121.122467 -214.303641) (xy 121.170477 -214.320441) (xy 121.215336 -214.344419) (xy 121.255976 -214.375006)
			(xy 121.291434 -214.411476) (xy 121.320866 -214.452961) (xy 121.343573 -214.498476) (xy 121.359015 -214.54694)
			(xy 121.366827 -214.597201) (xy 121.367296 -214.622634) (xy 121.366788 -214.648521) (xy 121.358689 -214.699659)
			(xy 121.34269 -214.748899) (xy 121.319184 -214.795031) (xy 121.288752 -214.836918) (xy 121.252142 -214.873528)
			(xy 121.210255 -214.90396) (xy 121.164123 -214.927466) (xy 121.114883 -214.943465) (xy 121.063745 -214.951564)
			(xy 121.011971 -214.951564) (xy 120.960833 -214.943465) (xy 120.911593 -214.927466) (xy 120.865461 -214.90396)
			(xy 120.823574 -214.873528) (xy 120.786964 -214.836918) (xy 120.756532 -214.795031) (xy 120.733026 -214.748899)
			(xy 120.717027 -214.699659) (xy 120.708928 -214.648521) (xy 120.70842 -214.622634) (xy 120.708787 -214.599658)
			(xy 120.7151 -214.554143) (xy 120.727679 -214.509947) (xy 120.736614 -214.488776) (xy 120.74652 -214.466424)
			(xy 120.532906 -214.061294) (xy 120.508776 -214.056722) (xy 120.48385 -214.051639) (xy 120.435836 -214.034839)
			(xy 120.390975 -214.010859) (xy 120.350332 -213.980269) (xy 120.314874 -213.943796) (xy 120.285443 -213.902307)
			(xy 120.262738 -213.856787) (xy 120.2473 -213.808318) (xy 120.239494 -213.758052) (xy 120.239028 -213.732618)
			(xy 119.018304 -213.732618) (xy 119.017953 -213.755595) (xy 119.011632 -213.80111) (xy 118.999048 -213.845306)
			(xy 118.99011 -213.866476) (xy 118.980204 -213.888828) (xy 119.193818 -214.293958) (xy 119.217948 -214.29853)
			(xy 119.242867 -214.303641) (xy 119.290877 -214.320441) (xy 119.335736 -214.344419) (xy 119.376376 -214.375006)
			(xy 119.411834 -214.411476) (xy 119.441266 -214.452961) (xy 119.463973 -214.498476) (xy 119.479415 -214.54694)
			(xy 119.487227 -214.597201) (xy 119.487696 -214.622634) (xy 119.487188 -214.648521) (xy 119.479089 -214.699659)
			(xy 119.46309 -214.748899) (xy 119.439584 -214.795031) (xy 119.409152 -214.836918) (xy 119.372542 -214.873528)
			(xy 119.330655 -214.90396) (xy 119.284523 -214.927466) (xy 119.235283 -214.943465) (xy 119.184145 -214.951564)
			(xy 119.132371 -214.951564) (xy 119.081233 -214.943465) (xy 119.031993 -214.927466) (xy 118.985861 -214.90396)
			(xy 118.943974 -214.873528) (xy 118.907364 -214.836918) (xy 118.876932 -214.795031) (xy 118.853426 -214.748899)
			(xy 118.837427 -214.699659) (xy 118.829328 -214.648521) (xy 118.82882 -214.622634) (xy 118.829187 -214.599658)
			(xy 118.8355 -214.554143) (xy 118.848079 -214.509947) (xy 118.857014 -214.488776) (xy 118.86692 -214.466424)
			(xy 118.653306 -214.061294) (xy 118.629176 -214.056722) (xy 118.60425 -214.051639) (xy 118.556236 -214.034839)
			(xy 118.511375 -214.010859) (xy 118.470732 -213.980269) (xy 118.435274 -213.943796) (xy 118.405843 -213.902307)
			(xy 118.383138 -213.856787) (xy 118.3677 -213.808318) (xy 118.359894 -213.758052) (xy 118.359428 -213.732618)
			(xy 117.138704 -213.732618) (xy 117.138353 -213.755595) (xy 117.132032 -213.80111) (xy 117.119448 -213.845306)
			(xy 117.11051 -213.866476) (xy 117.100604 -213.888828) (xy 117.314218 -214.293958) (xy 117.338348 -214.29853)
			(xy 117.363267 -214.303641) (xy 117.411277 -214.320441) (xy 117.456136 -214.344419) (xy 117.496776 -214.375006)
			(xy 117.532234 -214.411476) (xy 117.561666 -214.452961) (xy 117.584373 -214.498476) (xy 117.599815 -214.54694)
			(xy 117.607627 -214.597201) (xy 117.608096 -214.622634) (xy 117.607588 -214.648521) (xy 117.599489 -214.699659)
			(xy 117.58349 -214.748899) (xy 117.559984 -214.795031) (xy 117.529552 -214.836918) (xy 117.492942 -214.873528)
			(xy 117.451055 -214.90396) (xy 117.404923 -214.927466) (xy 117.355683 -214.943465) (xy 117.304545 -214.951564)
			(xy 117.252771 -214.951564) (xy 117.201633 -214.943465) (xy 117.152393 -214.927466) (xy 117.106261 -214.90396)
			(xy 117.064374 -214.873528) (xy 117.027764 -214.836918) (xy 116.997332 -214.795031) (xy 116.973826 -214.748899)
			(xy 116.957827 -214.699659) (xy 116.949728 -214.648521) (xy 116.94922 -214.622634) (xy 116.949587 -214.599658)
			(xy 116.9559 -214.554143) (xy 116.968479 -214.509947) (xy 116.977414 -214.488776) (xy 116.98732 -214.466424)
			(xy 116.773706 -214.061294) (xy 116.749576 -214.056722) (xy 116.72465 -214.051639) (xy 116.676636 -214.034839)
			(xy 116.631775 -214.010859) (xy 116.591132 -213.980269) (xy 116.555674 -213.943796) (xy 116.526243 -213.902307)
			(xy 116.503538 -213.856787) (xy 116.4881 -213.808318) (xy 116.480294 -213.758052) (xy 116.479828 -213.732618)
			(xy 115.613942 -213.732618) (xy 115.613942 -214.372698) (xy 115.631596 -214.388433) (xy 115.662657 -214.424091)
			(xy 115.688301 -214.463824) (xy 115.708001 -214.506815) (xy 115.721352 -214.55218) (xy 115.72808 -214.598989)
			(xy 115.728496 -214.622634) (xy 115.728107 -214.64628) (xy 115.721379 -214.693091) (xy 115.708025 -214.738458)
			(xy 115.688317 -214.781447) (xy 115.662663 -214.821176) (xy 115.631589 -214.856826) (xy 115.613942 -214.87257)
			(xy 115.613942 -215.03386) (xy 115.614401 -215.047942) (xy 115.622099 -215.075035) (xy 115.636895 -215.099001)
			(xy 115.657667 -215.118023) (xy 115.682839 -215.130658) (xy 115.710503 -215.135949) (xy 115.738561 -215.133493)
			(xy 115.751864 -215.128856) (xy 115.765502 -215.123776) (xy 115.793484 -215.115766) (xy 115.807744 -215.112854)
			(xy 115.830604 -215.108536) (xy 116.035582 -214.753444) (xy 116.027708 -214.7316) (xy 116.019131 -214.705181)
			(xy 116.009941 -214.650406) (xy 116.00942 -214.622634) (xy 116.009928 -214.596747) (xy 116.018027 -214.545609)
			(xy 116.034026 -214.496369) (xy 116.057532 -214.450237) (xy 116.087964 -214.40835) (xy 116.124574 -214.37174)
			(xy 116.166461 -214.341308) (xy 116.212593 -214.317802) (xy 116.261833 -214.301803) (xy 116.312971 -214.293704)
			(xy 116.364745 -214.293704) (xy 116.415883 -214.301803) (xy 116.465123 -214.317802) (xy 116.511255 -214.341308)
			(xy 116.553142 -214.37174) (xy 116.589752 -214.40835) (xy 116.620184 -214.450237) (xy 116.64369 -214.496369)
			(xy 116.659689 -214.545609) (xy 116.667788 -214.596747) (xy 116.668296 -214.622634) (xy 116.66783 -214.647968)
			(xy 116.660072 -214.69804) (xy 116.644746 -214.746335) (xy 116.622211 -214.791716) (xy 116.592999 -214.833116)
			(xy 116.557796 -214.869559) (xy 116.517432 -214.900187) (xy 116.472858 -214.924279) (xy 116.425122 -214.941268)
			(xy 116.400326 -214.946484) (xy 116.377466 -214.950802) (xy 116.172488 -215.305894) (xy 116.180362 -215.327738)
			(xy 116.189008 -215.354146) (xy 116.19833 -215.408922) (xy 116.198904 -215.436704) (xy 117.41912 -215.436704)
			(xy 117.419629 -215.41136) (xy 117.4274 -215.36127) (xy 117.442746 -215.31296) (xy 117.465303 -215.267567)
			(xy 117.494542 -215.226161) (xy 117.529773 -215.189717) (xy 117.570165 -215.159094) (xy 117.614769 -215.135013)
			(xy 117.662532 -215.118041) (xy 117.687344 -215.112854) (xy 117.710204 -215.108536) (xy 117.915182 -214.753444)
			(xy 117.907308 -214.7316) (xy 117.898729 -214.705181) (xy 117.889532 -214.650406) (xy 117.88902 -214.622634)
			(xy 117.889528 -214.596747) (xy 117.897627 -214.545609) (xy 117.913626 -214.496369) (xy 117.937132 -214.450237)
			(xy 117.967564 -214.40835) (xy 118.004174 -214.37174) (xy 118.046061 -214.341308) (xy 118.092193 -214.317802)
			(xy 118.141433 -214.301803) (xy 118.192571 -214.293704) (xy 118.244345 -214.293704) (xy 118.295483 -214.301803)
			(xy 118.344723 -214.317802) (xy 118.390855 -214.341308) (xy 118.432742 -214.37174) (xy 118.469352 -214.40835)
			(xy 118.499784 -214.450237) (xy 118.52329 -214.496369) (xy 118.539289 -214.545609) (xy 118.547388 -214.596747)
			(xy 118.547896 -214.622634) (xy 118.547447 -214.64797) (xy 118.53969 -214.698044) (xy 118.524363 -214.746341)
			(xy 118.501827 -214.791726) (xy 118.472612 -214.833128) (xy 118.437408 -214.869572) (xy 118.397042 -214.900202)
			(xy 118.352465 -214.924296) (xy 118.304727 -214.941286) (xy 118.279926 -214.946484) (xy 118.257066 -214.950802)
			(xy 118.052088 -215.305894) (xy 118.059962 -215.327738) (xy 118.06861 -215.354146) (xy 118.077929 -215.408922)
			(xy 118.078504 -215.436704) (xy 119.29872 -215.436704) (xy 119.299229 -215.41136) (xy 119.307 -215.36127)
			(xy 119.322346 -215.31296) (xy 119.344903 -215.267567) (xy 119.374142 -215.226161) (xy 119.409373 -215.189717)
			(xy 119.449765 -215.159094) (xy 119.494369 -215.135013) (xy 119.542132 -215.118041) (xy 119.566944 -215.112854)
			(xy 119.589804 -215.108536) (xy 119.794782 -214.753444) (xy 119.786908 -214.7316) (xy 119.778329 -214.705181)
			(xy 119.769132 -214.650406) (xy 119.76862 -214.622634) (xy 119.769128 -214.596747) (xy 119.777227 -214.545609)
			(xy 119.793226 -214.496369) (xy 119.816732 -214.450237) (xy 119.847164 -214.40835) (xy 119.883774 -214.37174)
			(xy 119.925661 -214.341308) (xy 119.971793 -214.317802) (xy 120.021033 -214.301803) (xy 120.072171 -214.293704)
			(xy 120.123945 -214.293704) (xy 120.175083 -214.301803) (xy 120.224323 -214.317802) (xy 120.270455 -214.341308)
			(xy 120.312342 -214.37174) (xy 120.348952 -214.40835) (xy 120.379384 -214.450237) (xy 120.40289 -214.496369)
			(xy 120.418889 -214.545609) (xy 120.426988 -214.596747) (xy 120.427496 -214.622634) (xy 120.427047 -214.64797)
			(xy 120.41929 -214.698044) (xy 120.403963 -214.746341) (xy 120.381427 -214.791726) (xy 120.352212 -214.833128)
			(xy 120.317008 -214.869572) (xy 120.276642 -214.900202) (xy 120.232065 -214.924296) (xy 120.184327 -214.941286)
			(xy 120.159526 -214.946484) (xy 120.136666 -214.950802) (xy 119.931688 -215.305894) (xy 119.939562 -215.327738)
			(xy 119.94821 -215.354146) (xy 119.957529 -215.408922) (xy 119.958104 -215.436704) (xy 121.17832 -215.436704)
			(xy 121.178829 -215.41136) (xy 121.1866 -215.36127) (xy 121.201946 -215.31296) (xy 121.224503 -215.267567)
			(xy 121.253742 -215.226161) (xy 121.288973 -215.189717) (xy 121.329365 -215.159094) (xy 121.373969 -215.135013)
			(xy 121.421732 -215.118041) (xy 121.446544 -215.112854) (xy 121.469404 -215.108536) (xy 121.674382 -214.753444)
			(xy 121.666508 -214.7316) (xy 121.657929 -214.705181) (xy 121.648732 -214.650406) (xy 121.64822 -214.622634)
			(xy 121.648728 -214.596747) (xy 121.656827 -214.545609) (xy 121.672826 -214.496369) (xy 121.696332 -214.450237)
			(xy 121.726764 -214.40835) (xy 121.763374 -214.37174) (xy 121.805261 -214.341308) (xy 121.851393 -214.317802)
			(xy 121.900633 -214.301803) (xy 121.951771 -214.293704) (xy 122.003545 -214.293704) (xy 122.054683 -214.301803)
			(xy 122.103923 -214.317802) (xy 122.150055 -214.341308) (xy 122.191942 -214.37174) (xy 122.228552 -214.40835)
			(xy 122.258984 -214.450237) (xy 122.28249 -214.496369) (xy 122.298489 -214.545609) (xy 122.306588 -214.596747)
			(xy 122.307096 -214.622634) (xy 122.306647 -214.64797) (xy 122.29889 -214.698044) (xy 122.283563 -214.746341)
			(xy 122.261027 -214.791726) (xy 122.231812 -214.833128) (xy 122.196608 -214.869572) (xy 122.156242 -214.900202)
			(xy 122.111665 -214.924296) (xy 122.063927 -214.941286) (xy 122.039126 -214.946484) (xy 122.016266 -214.950802)
			(xy 121.811288 -215.305894) (xy 121.819162 -215.327738) (xy 121.82781 -215.354146) (xy 121.837129 -215.408922)
			(xy 121.837704 -215.436704) (xy 123.05792 -215.436704) (xy 123.058429 -215.41136) (xy 123.0662 -215.36127)
			(xy 123.081546 -215.31296) (xy 123.104103 -215.267567) (xy 123.133342 -215.226161) (xy 123.168573 -215.189717)
			(xy 123.208965 -215.159094) (xy 123.253569 -215.135013) (xy 123.301332 -215.118041) (xy 123.326144 -215.112854)
			(xy 123.349004 -215.108536) (xy 123.553982 -214.753444) (xy 123.546108 -214.7316) (xy 123.537529 -214.705181)
			(xy 123.528332 -214.650406) (xy 123.52782 -214.622634) (xy 123.528328 -214.596747) (xy 123.536427 -214.545609)
			(xy 123.552426 -214.496369) (xy 123.575932 -214.450237) (xy 123.606364 -214.40835) (xy 123.642974 -214.37174)
			(xy 123.684861 -214.341308) (xy 123.730993 -214.317802) (xy 123.780233 -214.301803) (xy 123.831371 -214.293704)
			(xy 123.883145 -214.293704) (xy 123.934283 -214.301803) (xy 123.983523 -214.317802) (xy 124.029655 -214.341308)
			(xy 124.071542 -214.37174) (xy 124.108152 -214.40835) (xy 124.138584 -214.450237) (xy 124.16209 -214.496369)
			(xy 124.178089 -214.545609) (xy 124.186188 -214.596747) (xy 124.186696 -214.622634) (xy 124.186247 -214.64797)
			(xy 124.17849 -214.698044) (xy 124.163163 -214.746341) (xy 124.140627 -214.791726) (xy 124.111412 -214.833128)
			(xy 124.076208 -214.869572) (xy 124.035842 -214.900202) (xy 123.991265 -214.924296) (xy 123.943527 -214.941286)
			(xy 123.918726 -214.946484) (xy 123.895866 -214.950802) (xy 123.690888 -215.305894) (xy 123.698762 -215.327738)
			(xy 123.70741 -215.354146) (xy 123.716729 -215.408922) (xy 123.717304 -215.436704) (xy 124.93752 -215.436704)
			(xy 124.938029 -215.41136) (xy 124.9458 -215.36127) (xy 124.961146 -215.31296) (xy 124.983703 -215.267567)
			(xy 125.012942 -215.226161) (xy 125.048173 -215.189717) (xy 125.088565 -215.159094) (xy 125.133169 -215.135013)
			(xy 125.180932 -215.118041) (xy 125.205744 -215.112854) (xy 125.228604 -215.108536) (xy 125.433582 -214.753444)
			(xy 125.425708 -214.7316) (xy 125.417129 -214.705181) (xy 125.407932 -214.650406) (xy 125.40742 -214.622634)
			(xy 125.407928 -214.596747) (xy 125.416027 -214.545609) (xy 125.432026 -214.496369) (xy 125.455532 -214.450237)
			(xy 125.485964 -214.40835) (xy 125.522574 -214.37174) (xy 125.564461 -214.341308) (xy 125.610593 -214.317802)
			(xy 125.659833 -214.301803) (xy 125.710971 -214.293704) (xy 125.762745 -214.293704) (xy 125.813883 -214.301803)
			(xy 125.863123 -214.317802) (xy 125.909255 -214.341308) (xy 125.951142 -214.37174) (xy 125.987752 -214.40835)
			(xy 126.018184 -214.450237) (xy 126.04169 -214.496369) (xy 126.057689 -214.545609) (xy 126.065788 -214.596747)
			(xy 126.066296 -214.622634) (xy 126.065847 -214.64797) (xy 126.05809 -214.698044) (xy 126.042763 -214.746341)
			(xy 126.020227 -214.791726) (xy 125.991012 -214.833128) (xy 125.955808 -214.869572) (xy 125.915442 -214.900202)
			(xy 125.870865 -214.924296) (xy 125.823127 -214.941286) (xy 125.798326 -214.946484) (xy 125.775466 -214.950802)
			(xy 125.570488 -215.305894) (xy 125.578362 -215.327738) (xy 125.58701 -215.354146) (xy 125.596329 -215.408922)
			(xy 125.596904 -215.436704) (xy 125.596396 -215.462611) (xy 125.58829 -215.513788) (xy 125.572278 -215.563067)
			(xy 125.548755 -215.609234) (xy 125.518299 -215.651153) (xy 125.481661 -215.687791) (xy 125.439742 -215.718247)
			(xy 125.393575 -215.74177) (xy 125.344296 -215.757782) (xy 125.293119 -215.765888) (xy 125.241305 -215.765888)
			(xy 125.190128 -215.757782) (xy 125.140849 -215.74177) (xy 125.094682 -215.718247) (xy 125.052763 -215.687791)
			(xy 125.016125 -215.651153) (xy 124.985669 -215.609234) (xy 124.962146 -215.563067) (xy 124.946134 -215.513788)
			(xy 124.938028 -215.462611) (xy 124.93752 -215.436704) (xy 123.717304 -215.436704) (xy 123.716796 -215.462611)
			(xy 123.70869 -215.513788) (xy 123.692678 -215.563067) (xy 123.669155 -215.609234) (xy 123.638699 -215.651153)
			(xy 123.602061 -215.687791) (xy 123.560142 -215.718247) (xy 123.513975 -215.74177) (xy 123.464696 -215.757782)
			(xy 123.413519 -215.765888) (xy 123.361705 -215.765888) (xy 123.310528 -215.757782) (xy 123.261249 -215.74177)
			(xy 123.215082 -215.718247) (xy 123.173163 -215.687791) (xy 123.136525 -215.651153) (xy 123.106069 -215.609234)
			(xy 123.082546 -215.563067) (xy 123.066534 -215.513788) (xy 123.058428 -215.462611) (xy 123.05792 -215.436704)
			(xy 121.837704 -215.436704) (xy 121.837196 -215.462611) (xy 121.82909 -215.513788) (xy 121.813078 -215.563067)
			(xy 121.789555 -215.609234) (xy 121.759099 -215.651153) (xy 121.722461 -215.687791) (xy 121.680542 -215.718247)
			(xy 121.634375 -215.74177) (xy 121.585096 -215.757782) (xy 121.533919 -215.765888) (xy 121.482105 -215.765888)
			(xy 121.430928 -215.757782) (xy 121.381649 -215.74177) (xy 121.335482 -215.718247) (xy 121.293563 -215.687791)
			(xy 121.256925 -215.651153) (xy 121.226469 -215.609234) (xy 121.202946 -215.563067) (xy 121.186934 -215.513788)
			(xy 121.178828 -215.462611) (xy 121.17832 -215.436704) (xy 119.958104 -215.436704) (xy 119.957596 -215.462611)
			(xy 119.94949 -215.513788) (xy 119.933478 -215.563067) (xy 119.909955 -215.609234) (xy 119.879499 -215.651153)
			(xy 119.842861 -215.687791) (xy 119.800942 -215.718247) (xy 119.754775 -215.74177) (xy 119.705496 -215.757782)
			(xy 119.654319 -215.765888) (xy 119.602505 -215.765888) (xy 119.551328 -215.757782) (xy 119.502049 -215.74177)
			(xy 119.455882 -215.718247) (xy 119.413963 -215.687791) (xy 119.377325 -215.651153) (xy 119.346869 -215.609234)
			(xy 119.323346 -215.563067) (xy 119.307334 -215.513788) (xy 119.299228 -215.462611) (xy 119.29872 -215.436704)
			(xy 118.078504 -215.436704) (xy 118.077996 -215.462611) (xy 118.06989 -215.513788) (xy 118.053878 -215.563067)
			(xy 118.030355 -215.609234) (xy 117.999899 -215.651153) (xy 117.963261 -215.687791) (xy 117.921342 -215.718247)
			(xy 117.875175 -215.74177) (xy 117.825896 -215.757782) (xy 117.774719 -215.765888) (xy 117.722905 -215.765888)
			(xy 117.671728 -215.757782) (xy 117.622449 -215.74177) (xy 117.576282 -215.718247) (xy 117.534363 -215.687791)
			(xy 117.497725 -215.651153) (xy 117.467269 -215.609234) (xy 117.443746 -215.563067) (xy 117.427734 -215.513788)
			(xy 117.419628 -215.462611) (xy 117.41912 -215.436704) (xy 116.198904 -215.436704) (xy 116.198396 -215.462611)
			(xy 116.19029 -215.513788) (xy 116.174278 -215.563067) (xy 116.150755 -215.609235) (xy 116.120299 -215.651154)
			(xy 116.08366 -215.687794) (xy 116.041742 -215.71825) (xy 115.995575 -215.741775) (xy 115.946296 -215.757788)
			(xy 115.895119 -215.765895) (xy 115.869212 -215.766396) (xy 115.839186 -215.765661) (xy 115.780146 -215.754664)
			(xy 115.751864 -215.744552) (xy 115.738544 -215.739932) (xy 115.710473 -215.737421) (xy 115.682785 -215.742681)
			(xy 115.65759 -215.755309) (xy 115.636807 -215.774344) (xy 115.622019 -215.798336) (xy 115.614354 -215.825456)
			(xy 115.613942 -215.839548) (xy 115.613942 -216.002362) (xy 115.632994 -216.01947) (xy 115.666068 -216.058556)
			(xy 115.692664 -216.102308) (xy 115.712137 -216.149662) (xy 115.724012 -216.199467) (xy 115.728002 -216.250513)
			(xy 115.724008 -216.301559) (xy 115.712129 -216.351363) (xy 115.692653 -216.398716) (xy 115.666052 -216.442466)
			(xy 115.632975 -216.481549) (xy 115.613942 -216.498678) (xy 115.613942 -217.064336) (xy 116.47932 -217.064336)
			(xy 116.479828 -217.038429) (xy 116.487934 -216.987252) (xy 116.503946 -216.937973) (xy 116.527469 -216.891806)
			(xy 116.557925 -216.849887) (xy 116.594563 -216.813249) (xy 116.636482 -216.782793) (xy 116.682649 -216.75927)
			(xy 116.731928 -216.743258) (xy 116.783105 -216.735152) (xy 116.834919 -216.735152) (xy 116.886096 -216.743258)
			(xy 116.935375 -216.75927) (xy 116.981542 -216.782793) (xy 117.023461 -216.813249) (xy 117.060099 -216.849887)
			(xy 117.090555 -216.891806) (xy 117.114078 -216.937973) (xy 117.13009 -216.987252) (xy 117.138196 -217.038429)
			(xy 117.138704 -217.064336) (xy 118.35892 -217.064336) (xy 118.359428 -217.038429) (xy 118.367534 -216.987252)
			(xy 118.383546 -216.937973) (xy 118.407069 -216.891806) (xy 118.437525 -216.849887) (xy 118.474163 -216.813249)
			(xy 118.516082 -216.782793) (xy 118.562249 -216.75927) (xy 118.611528 -216.743258) (xy 118.662705 -216.735152)
			(xy 118.714519 -216.735152) (xy 118.765696 -216.743258) (xy 118.814975 -216.75927) (xy 118.861142 -216.782793)
			(xy 118.903061 -216.813249) (xy 118.939699 -216.849887) (xy 118.970155 -216.891806) (xy 118.993678 -216.937973)
			(xy 119.00969 -216.987252) (xy 119.017796 -217.038429) (xy 119.018304 -217.064336) (xy 120.23852 -217.064336)
			(xy 120.239028 -217.038429) (xy 120.247134 -216.987252) (xy 120.263146 -216.937973) (xy 120.286669 -216.891806)
			(xy 120.317125 -216.849887) (xy 120.353763 -216.813249) (xy 120.395682 -216.782793) (xy 120.441849 -216.75927)
			(xy 120.491128 -216.743258) (xy 120.542305 -216.735152) (xy 120.594119 -216.735152) (xy 120.645296 -216.743258)
			(xy 120.694575 -216.75927) (xy 120.740742 -216.782793) (xy 120.782661 -216.813249) (xy 120.819299 -216.849887)
			(xy 120.849755 -216.891806) (xy 120.873278 -216.937973) (xy 120.88929 -216.987252) (xy 120.897396 -217.038429)
			(xy 120.897904 -217.064336) (xy 122.11812 -217.064336) (xy 122.118628 -217.038429) (xy 122.126734 -216.987252)
			(xy 122.142746 -216.937973) (xy 122.166269 -216.891806) (xy 122.196725 -216.849887) (xy 122.233363 -216.813249)
			(xy 122.275282 -216.782793) (xy 122.321449 -216.75927) (xy 122.370728 -216.743258) (xy 122.421905 -216.735152)
			(xy 122.473719 -216.735152) (xy 122.524896 -216.743258) (xy 122.574175 -216.75927) (xy 122.620342 -216.782793)
			(xy 122.662261 -216.813249) (xy 122.698899 -216.849887) (xy 122.729355 -216.891806) (xy 122.752878 -216.937973)
			(xy 122.76889 -216.987252) (xy 122.776996 -217.038429) (xy 122.777504 -217.064336) (xy 123.99772 -217.064336)
			(xy 123.998228 -217.038429) (xy 124.006334 -216.987252) (xy 124.022346 -216.937973) (xy 124.045869 -216.891806)
			(xy 124.076325 -216.849887) (xy 124.112963 -216.813249) (xy 124.154882 -216.782793) (xy 124.201049 -216.75927)
			(xy 124.250328 -216.743258) (xy 124.301505 -216.735152) (xy 124.353319 -216.735152) (xy 124.404496 -216.743258)
			(xy 124.453775 -216.75927) (xy 124.499942 -216.782793) (xy 124.541861 -216.813249) (xy 124.578499 -216.849887)
			(xy 124.608955 -216.891806) (xy 124.632478 -216.937973) (xy 124.64849 -216.987252) (xy 124.656596 -217.038429)
			(xy 124.657104 -217.064336) (xy 125.87732 -217.064336) (xy 125.877828 -217.038429) (xy 125.885934 -216.987252)
			(xy 125.901946 -216.937973) (xy 125.925469 -216.891806) (xy 125.955925 -216.849887) (xy 125.992563 -216.813249)
			(xy 126.034482 -216.782793) (xy 126.080649 -216.75927) (xy 126.129928 -216.743258) (xy 126.181105 -216.735152)
			(xy 126.232919 -216.735152) (xy 126.284096 -216.743258) (xy 126.333375 -216.75927) (xy 126.379542 -216.782793)
			(xy 126.421461 -216.813249) (xy 126.458099 -216.849887) (xy 126.488555 -216.891806) (xy 126.512078 -216.937973)
			(xy 126.52809 -216.987252) (xy 126.536196 -217.038429) (xy 126.536704 -217.064336) (xy 126.536089 -217.091989)
			(xy 126.526769 -217.146507) (xy 126.518162 -217.172794) (xy 126.510542 -217.194892) (xy 126.715774 -217.550238)
			(xy 126.738634 -217.554556) (xy 126.763441 -217.559728) (xy 126.811179 -217.576721) (xy 126.855756 -217.600818)
			(xy 126.89612 -217.631451) (xy 126.931323 -217.6679) (xy 126.960534 -217.709305) (xy 126.983066 -217.754693)
			(xy 126.998389 -217.802993) (xy 127.006141 -217.85307) (xy 127.006604 -217.878406) (xy 127.006096 -217.904293)
			(xy 126.997997 -217.955431) (xy 126.981998 -218.004671) (xy 126.958492 -218.050803) (xy 126.92806 -218.09269)
			(xy 126.89145 -218.1293) (xy 126.849563 -218.159732) (xy 126.803431 -218.183238) (xy 126.754191 -218.199237)
			(xy 126.703053 -218.207336) (xy 126.651279 -218.207336) (xy 126.600141 -218.199237) (xy 126.550901 -218.183238)
			(xy 126.504769 -218.159732) (xy 126.462882 -218.1293) (xy 126.426272 -218.09269) (xy 126.39584 -218.050803)
			(xy 126.372334 -218.004671) (xy 126.356335 -217.955431) (xy 126.348236 -217.904293) (xy 126.347728 -217.878406)
			(xy 126.348262 -217.850698) (xy 126.357455 -217.796051) (xy 126.366016 -217.769694) (xy 126.37389 -217.747596)
			(xy 126.168912 -217.392504) (xy 126.146052 -217.388186) (xy 126.121196 -217.383069) (xy 126.073348 -217.366166)
			(xy 126.028656 -217.342128) (xy 125.988177 -217.311523) (xy 125.952867 -217.275076) (xy 125.923561 -217.233647)
			(xy 125.900952 -217.188215) (xy 125.885574 -217.139855) (xy 125.87779 -217.089709) (xy 125.87732 -217.064336)
			(xy 124.657104 -217.064336) (xy 124.656489 -217.091989) (xy 124.647169 -217.146507) (xy 124.638562 -217.172794)
			(xy 124.630942 -217.194892) (xy 124.836174 -217.550238) (xy 124.859034 -217.554556) (xy 124.883841 -217.559728)
			(xy 124.931579 -217.576721) (xy 124.976156 -217.600818) (xy 125.01652 -217.631451) (xy 125.051723 -217.6679)
			(xy 125.080934 -217.709305) (xy 125.103466 -217.754693) (xy 125.118789 -217.802993) (xy 125.126541 -217.85307)
			(xy 125.127004 -217.878406) (xy 125.126496 -217.904293) (xy 125.118397 -217.955431) (xy 125.102398 -218.004671)
			(xy 125.078892 -218.050803) (xy 125.04846 -218.09269) (xy 125.01185 -218.1293) (xy 124.969963 -218.159732)
			(xy 124.923831 -218.183238) (xy 124.874591 -218.199237) (xy 124.823453 -218.207336) (xy 124.771679 -218.207336)
			(xy 124.720541 -218.199237) (xy 124.671301 -218.183238) (xy 124.625169 -218.159732) (xy 124.583282 -218.1293)
			(xy 124.546672 -218.09269) (xy 124.51624 -218.050803) (xy 124.492734 -218.004671) (xy 124.476735 -217.955431)
			(xy 124.468636 -217.904293) (xy 124.468128 -217.878406) (xy 124.468662 -217.850698) (xy 124.477855 -217.796051)
			(xy 124.486416 -217.769694) (xy 124.49429 -217.747596) (xy 124.289312 -217.392504) (xy 124.266452 -217.388186)
			(xy 124.241596 -217.383069) (xy 124.193748 -217.366166) (xy 124.149056 -217.342128) (xy 124.108577 -217.311523)
			(xy 124.073267 -217.275076) (xy 124.043961 -217.233647) (xy 124.021352 -217.188215) (xy 124.005974 -217.139855)
			(xy 123.99819 -217.089709) (xy 123.99772 -217.064336) (xy 122.777504 -217.064336) (xy 122.776889 -217.091989)
			(xy 122.767569 -217.146507) (xy 122.758962 -217.172794) (xy 122.751342 -217.194892) (xy 122.956574 -217.550238)
			(xy 122.979434 -217.554556) (xy 123.004241 -217.559728) (xy 123.051979 -217.576721) (xy 123.096556 -217.600818)
			(xy 123.13692 -217.631451) (xy 123.172123 -217.6679) (xy 123.201334 -217.709305) (xy 123.223866 -217.754693)
			(xy 123.239189 -217.802993) (xy 123.246941 -217.85307) (xy 123.247404 -217.878406) (xy 123.246896 -217.904293)
			(xy 123.238797 -217.955431) (xy 123.222798 -218.004671) (xy 123.199292 -218.050803) (xy 123.16886 -218.09269)
			(xy 123.13225 -218.1293) (xy 123.090363 -218.159732) (xy 123.044231 -218.183238) (xy 122.994991 -218.199237)
			(xy 122.943853 -218.207336) (xy 122.892079 -218.207336) (xy 122.840941 -218.199237) (xy 122.791701 -218.183238)
			(xy 122.745569 -218.159732) (xy 122.703682 -218.1293) (xy 122.667072 -218.09269) (xy 122.63664 -218.050803)
			(xy 122.613134 -218.004671) (xy 122.597135 -217.955431) (xy 122.589036 -217.904293) (xy 122.588528 -217.878406)
			(xy 122.589062 -217.850698) (xy 122.598255 -217.796051) (xy 122.606816 -217.769694) (xy 122.61469 -217.747596)
			(xy 122.409712 -217.392504) (xy 122.386852 -217.388186) (xy 122.361996 -217.383069) (xy 122.314148 -217.366166)
			(xy 122.269456 -217.342128) (xy 122.228977 -217.311523) (xy 122.193667 -217.275076) (xy 122.164361 -217.233647)
			(xy 122.141752 -217.188215) (xy 122.126374 -217.139855) (xy 122.11859 -217.089709) (xy 122.11812 -217.064336)
			(xy 120.897904 -217.064336) (xy 120.897289 -217.091989) (xy 120.887969 -217.146507) (xy 120.879362 -217.172794)
			(xy 120.871742 -217.194892) (xy 121.076974 -217.550238) (xy 121.099834 -217.554556) (xy 121.124641 -217.559728)
			(xy 121.172379 -217.576721) (xy 121.216956 -217.600818) (xy 121.25732 -217.631451) (xy 121.292523 -217.6679)
			(xy 121.321734 -217.709305) (xy 121.344266 -217.754693) (xy 121.359589 -217.802993) (xy 121.367341 -217.85307)
			(xy 121.367804 -217.878406) (xy 121.367296 -217.904293) (xy 121.359197 -217.955431) (xy 121.343198 -218.004671)
			(xy 121.319692 -218.050803) (xy 121.28926 -218.09269) (xy 121.25265 -218.1293) (xy 121.210763 -218.159732)
			(xy 121.164631 -218.183238) (xy 121.115391 -218.199237) (xy 121.064253 -218.207336) (xy 121.012479 -218.207336)
			(xy 120.961341 -218.199237) (xy 120.912101 -218.183238) (xy 120.865969 -218.159732) (xy 120.824082 -218.1293)
			(xy 120.787472 -218.09269) (xy 120.75704 -218.050803) (xy 120.733534 -218.004671) (xy 120.717535 -217.955431)
			(xy 120.709436 -217.904293) (xy 120.708928 -217.878406) (xy 120.709462 -217.850698) (xy 120.718655 -217.796051)
			(xy 120.727216 -217.769694) (xy 120.73509 -217.747596) (xy 120.530112 -217.392504) (xy 120.507252 -217.388186)
			(xy 120.482396 -217.383069) (xy 120.434548 -217.366166) (xy 120.389856 -217.342128) (xy 120.349377 -217.311523)
			(xy 120.314067 -217.275076) (xy 120.284761 -217.233647) (xy 120.262152 -217.188215) (xy 120.246774 -217.139855)
			(xy 120.23899 -217.089709) (xy 120.23852 -217.064336) (xy 119.018304 -217.064336) (xy 119.017689 -217.091989)
			(xy 119.008369 -217.146507) (xy 118.999762 -217.172794) (xy 118.992142 -217.194892) (xy 119.197374 -217.550238)
			(xy 119.220234 -217.554556) (xy 119.245041 -217.559728) (xy 119.292779 -217.576721) (xy 119.337356 -217.600818)
			(xy 119.37772 -217.631451) (xy 119.412923 -217.6679) (xy 119.442134 -217.709305) (xy 119.464666 -217.754693)
			(xy 119.479989 -217.802993) (xy 119.487741 -217.85307) (xy 119.488204 -217.878406) (xy 119.487696 -217.904293)
			(xy 119.479597 -217.955431) (xy 119.463598 -218.004671) (xy 119.440092 -218.050803) (xy 119.40966 -218.09269)
			(xy 119.37305 -218.1293) (xy 119.331163 -218.159732) (xy 119.285031 -218.183238) (xy 119.235791 -218.199237)
			(xy 119.184653 -218.207336) (xy 119.132879 -218.207336) (xy 119.081741 -218.199237) (xy 119.032501 -218.183238)
			(xy 118.986369 -218.159732) (xy 118.944482 -218.1293) (xy 118.907872 -218.09269) (xy 118.87744 -218.050803)
			(xy 118.853934 -218.004671) (xy 118.837935 -217.955431) (xy 118.829836 -217.904293) (xy 118.829328 -217.878406)
			(xy 118.829862 -217.850698) (xy 118.839055 -217.796051) (xy 118.847616 -217.769694) (xy 118.85549 -217.747596)
			(xy 118.650512 -217.392504) (xy 118.627652 -217.388186) (xy 118.602796 -217.383069) (xy 118.554948 -217.366166)
			(xy 118.510256 -217.342128) (xy 118.469777 -217.311523) (xy 118.434467 -217.275076) (xy 118.405161 -217.233647)
			(xy 118.382552 -217.188215) (xy 118.367174 -217.139855) (xy 118.35939 -217.089709) (xy 118.35892 -217.064336)
			(xy 117.138704 -217.064336) (xy 117.138089 -217.091989) (xy 117.128769 -217.146507) (xy 117.120162 -217.172794)
			(xy 117.112542 -217.194892) (xy 117.317774 -217.550238) (xy 117.340634 -217.554556) (xy 117.365441 -217.559728)
			(xy 117.413179 -217.576721) (xy 117.457756 -217.600818) (xy 117.49812 -217.631451) (xy 117.533323 -217.6679)
			(xy 117.562534 -217.709305) (xy 117.585066 -217.754693) (xy 117.600389 -217.802993) (xy 117.608141 -217.85307)
			(xy 117.608604 -217.878406) (xy 117.608096 -217.904293) (xy 117.599997 -217.955431) (xy 117.583998 -218.004671)
			(xy 117.560492 -218.050803) (xy 117.53006 -218.09269) (xy 117.49345 -218.1293) (xy 117.451563 -218.159732)
			(xy 117.405431 -218.183238) (xy 117.356191 -218.199237) (xy 117.305053 -218.207336) (xy 117.253279 -218.207336)
			(xy 117.202141 -218.199237) (xy 117.152901 -218.183238) (xy 117.106769 -218.159732) (xy 117.064882 -218.1293)
			(xy 117.028272 -218.09269) (xy 116.99784 -218.050803) (xy 116.974334 -218.004671) (xy 116.958335 -217.955431)
			(xy 116.950236 -217.904293) (xy 116.949728 -217.878406) (xy 116.950262 -217.850698) (xy 116.959455 -217.796051)
			(xy 116.968016 -217.769694) (xy 116.97589 -217.747596) (xy 116.770912 -217.392504) (xy 116.748052 -217.388186)
			(xy 116.723196 -217.383069) (xy 116.675348 -217.366166) (xy 116.630656 -217.342128) (xy 116.590177 -217.311523)
			(xy 116.554867 -217.275076) (xy 116.525561 -217.233647) (xy 116.502952 -217.188215) (xy 116.487574 -217.139855)
			(xy 116.47979 -217.089709) (xy 116.47932 -217.064336) (xy 115.613942 -217.064336) (xy 115.613942 -217.628216)
			(xy 115.633239 -217.645412) (xy 115.666756 -217.684756) (xy 115.693718 -217.728851) (xy 115.713464 -217.776616)
			(xy 115.725508 -217.826878) (xy 115.729555 -217.878404) (xy 115.725507 -217.92993) (xy 115.713461 -217.980192)
			(xy 115.693715 -218.027956) (xy 115.666752 -218.07205) (xy 115.633234 -218.111393) (xy 115.613942 -218.128596)
			(xy 115.613942 -218.289378) (xy 115.614404 -218.303459) (xy 115.622105 -218.330547) (xy 115.636901 -218.354509)
			(xy 115.657672 -218.373526) (xy 115.682841 -218.386159) (xy 115.710502 -218.391449) (xy 115.738556 -218.388995)
			(xy 115.751864 -218.384374) (xy 115.765502 -218.379294) (xy 115.793484 -218.371283) (xy 115.807744 -218.368372)
			(xy 115.830604 -218.364054) (xy 116.035836 -218.008708) (xy 116.027962 -217.98661) (xy 116.0195 -217.960365)
			(xy 116.010438 -217.905976) (xy 116.009928 -217.878406) (xy 116.010436 -217.852519) (xy 116.018535 -217.801381)
			(xy 116.034534 -217.752141) (xy 116.05804 -217.706009) (xy 116.088472 -217.664122) (xy 116.125082 -217.627512)
			(xy 116.166969 -217.59708) (xy 116.213101 -217.573574) (xy 116.262341 -217.557575) (xy 116.313479 -217.549476)
			(xy 116.365253 -217.549476) (xy 116.416391 -217.557575) (xy 116.465631 -217.573574) (xy 116.511763 -217.59708)
			(xy 116.55365 -217.627512) (xy 116.59026 -217.664122) (xy 116.620692 -217.706009) (xy 116.644198 -217.752141)
			(xy 116.660197 -217.801381) (xy 116.668296 -217.852519) (xy 116.668804 -217.878406) (xy 116.668336 -217.903779)
			(xy 116.660555 -217.953924) (xy 116.645178 -218.002284) (xy 116.622569 -218.047715) (xy 116.593262 -218.089142)
			(xy 116.55795 -218.125586) (xy 116.517468 -218.156186) (xy 116.472773 -218.180218) (xy 116.424923 -218.197113)
			(xy 116.400072 -218.202256) (xy 116.377212 -218.206574) (xy 116.172488 -218.561412) (xy 116.180362 -218.583256)
			(xy 116.189007 -218.609665) (xy 116.198325 -218.66444) (xy 116.198904 -218.692222) (xy 117.41912 -218.692222)
			(xy 117.419645 -218.666878) (xy 117.427414 -218.616789) (xy 117.442757 -218.56848) (xy 117.465312 -218.523087)
			(xy 117.494549 -218.481681) (xy 117.529778 -218.445236) (xy 117.570169 -218.414613) (xy 117.61477 -218.390531)
			(xy 117.662532 -218.373559) (xy 117.687344 -218.368372) (xy 117.710204 -218.364054) (xy 117.915436 -218.008708)
			(xy 117.907562 -217.98661) (xy 117.899094 -217.960366) (xy 117.890024 -217.905977) (xy 117.889528 -217.878406)
			(xy 117.890036 -217.852519) (xy 117.898135 -217.801381) (xy 117.914134 -217.752141) (xy 117.93764 -217.706009)
			(xy 117.968072 -217.664122) (xy 118.004682 -217.627512) (xy 118.046569 -217.59708) (xy 118.092701 -217.573574)
			(xy 118.141941 -217.557575) (xy 118.193079 -217.549476) (xy 118.244853 -217.549476) (xy 118.295991 -217.557575)
			(xy 118.345231 -217.573574) (xy 118.391363 -217.59708) (xy 118.43325 -217.627512) (xy 118.46986 -217.664122)
			(xy 118.500292 -217.706009) (xy 118.523798 -217.752141) (xy 118.539797 -217.801381) (xy 118.547896 -217.852519)
			(xy 118.548404 -217.878406) (xy 118.547931 -217.90378) (xy 118.540162 -217.953931) (xy 118.524793 -218.002296)
			(xy 118.502188 -218.047732) (xy 118.472882 -218.089163) (xy 118.437568 -218.125609) (xy 118.397082 -218.156208)
			(xy 118.352382 -218.180235) (xy 118.304526 -218.197122) (xy 118.279672 -218.202256) (xy 118.256812 -218.206574)
			(xy 118.052088 -218.561412) (xy 118.059962 -218.583256) (xy 118.068614 -218.609662) (xy 118.07793 -218.66444)
			(xy 118.078504 -218.692222) (xy 119.29872 -218.692222) (xy 119.299245 -218.666878) (xy 119.307014 -218.616789)
			(xy 119.322357 -218.56848) (xy 119.344912 -218.523087) (xy 119.374149 -218.481681) (xy 119.409378 -218.445236)
			(xy 119.449769 -218.414613) (xy 119.49437 -218.390531) (xy 119.542132 -218.373559) (xy 119.566944 -218.368372)
			(xy 119.589804 -218.364054) (xy 119.795036 -218.008708) (xy 119.787162 -217.98661) (xy 119.778694 -217.960366)
			(xy 119.769624 -217.905977) (xy 119.769128 -217.878406) (xy 119.769636 -217.852519) (xy 119.777735 -217.801381)
			(xy 119.793734 -217.752141) (xy 119.81724 -217.706009) (xy 119.847672 -217.664122) (xy 119.884282 -217.627512)
			(xy 119.926169 -217.59708) (xy 119.972301 -217.573574) (xy 120.021541 -217.557575) (xy 120.072679 -217.549476)
			(xy 120.124453 -217.549476) (xy 120.175591 -217.557575) (xy 120.224831 -217.573574) (xy 120.270963 -217.59708)
			(xy 120.31285 -217.627512) (xy 120.34946 -217.664122) (xy 120.379892 -217.706009) (xy 120.403398 -217.752141)
			(xy 120.419397 -217.801381) (xy 120.427496 -217.852519) (xy 120.428004 -217.878406) (xy 120.427531 -217.90378)
			(xy 120.419762 -217.953931) (xy 120.404393 -218.002296) (xy 120.381788 -218.047732) (xy 120.352482 -218.089163)
			(xy 120.317168 -218.125609) (xy 120.276682 -218.156208) (xy 120.231982 -218.180235) (xy 120.184126 -218.197122)
			(xy 120.159272 -218.202256) (xy 120.136412 -218.206574) (xy 119.931688 -218.561412) (xy 119.939562 -218.583256)
			(xy 119.948214 -218.609662) (xy 119.95753 -218.66444) (xy 119.958104 -218.692222) (xy 121.17832 -218.692222)
			(xy 121.178845 -218.666878) (xy 121.186614 -218.616789) (xy 121.201957 -218.56848) (xy 121.224512 -218.523087)
			(xy 121.253749 -218.481681) (xy 121.288978 -218.445236) (xy 121.329369 -218.414613) (xy 121.37397 -218.390531)
			(xy 121.421732 -218.373559) (xy 121.446544 -218.368372) (xy 121.469404 -218.364054) (xy 121.674636 -218.008708)
			(xy 121.666762 -217.98661) (xy 121.658294 -217.960366) (xy 121.649224 -217.905977) (xy 121.648728 -217.878406)
			(xy 121.649236 -217.852519) (xy 121.657335 -217.801381) (xy 121.673334 -217.752141) (xy 121.69684 -217.706009)
			(xy 121.727272 -217.664122) (xy 121.763882 -217.627512) (xy 121.805769 -217.59708) (xy 121.851901 -217.573574)
			(xy 121.901141 -217.557575) (xy 121.952279 -217.549476) (xy 122.004053 -217.549476) (xy 122.055191 -217.557575)
			(xy 122.104431 -217.573574) (xy 122.150563 -217.59708) (xy 122.19245 -217.627512) (xy 122.22906 -217.664122)
			(xy 122.259492 -217.706009) (xy 122.282998 -217.752141) (xy 122.298997 -217.801381) (xy 122.307096 -217.852519)
			(xy 122.307604 -217.878406) (xy 122.307131 -217.90378) (xy 122.299362 -217.953931) (xy 122.283993 -218.002296)
			(xy 122.261388 -218.047732) (xy 122.232082 -218.089163) (xy 122.196768 -218.125609) (xy 122.156282 -218.156208)
			(xy 122.111582 -218.180235) (xy 122.063726 -218.197122) (xy 122.038872 -218.202256) (xy 122.016012 -218.206574)
			(xy 121.811288 -218.561412) (xy 121.819162 -218.583256) (xy 121.827814 -218.609662) (xy 121.83713 -218.66444)
			(xy 121.837704 -218.692222) (xy 123.05792 -218.692222) (xy 123.058445 -218.666878) (xy 123.066214 -218.616789)
			(xy 123.081557 -218.56848) (xy 123.104112 -218.523087) (xy 123.133349 -218.481681) (xy 123.168578 -218.445236)
			(xy 123.208969 -218.414613) (xy 123.25357 -218.390531) (xy 123.301332 -218.373559) (xy 123.326144 -218.368372)
			(xy 123.349004 -218.364054) (xy 123.554236 -218.008708) (xy 123.546362 -217.98661) (xy 123.537894 -217.960366)
			(xy 123.528824 -217.905977) (xy 123.528328 -217.878406) (xy 123.528836 -217.852519) (xy 123.536935 -217.801381)
			(xy 123.552934 -217.752141) (xy 123.57644 -217.706009) (xy 123.606872 -217.664122) (xy 123.643482 -217.627512)
			(xy 123.685369 -217.59708) (xy 123.731501 -217.573574) (xy 123.780741 -217.557575) (xy 123.831879 -217.549476)
			(xy 123.883653 -217.549476) (xy 123.934791 -217.557575) (xy 123.984031 -217.573574) (xy 124.030163 -217.59708)
			(xy 124.07205 -217.627512) (xy 124.10866 -217.664122) (xy 124.139092 -217.706009) (xy 124.162598 -217.752141)
			(xy 124.178597 -217.801381) (xy 124.186696 -217.852519) (xy 124.187204 -217.878406) (xy 124.186731 -217.90378)
			(xy 124.178962 -217.953931) (xy 124.163593 -218.002296) (xy 124.140988 -218.047732) (xy 124.111682 -218.089163)
			(xy 124.076368 -218.125609) (xy 124.035882 -218.156208) (xy 123.991182 -218.180235) (xy 123.943326 -218.197122)
			(xy 123.918472 -218.202256) (xy 123.895612 -218.206574) (xy 123.690888 -218.561412) (xy 123.698762 -218.583256)
			(xy 123.707414 -218.609662) (xy 123.71673 -218.66444) (xy 123.717304 -218.692222) (xy 124.93752 -218.692222)
			(xy 124.938045 -218.666878) (xy 124.945814 -218.616789) (xy 124.961157 -218.56848) (xy 124.983712 -218.523087)
			(xy 125.012949 -218.481681) (xy 125.048178 -218.445236) (xy 125.088569 -218.414613) (xy 125.13317 -218.390531)
			(xy 125.180932 -218.373559) (xy 125.205744 -218.368372) (xy 125.228604 -218.364054) (xy 125.433836 -218.008708)
			(xy 125.425962 -217.98661) (xy 125.417494 -217.960366) (xy 125.408424 -217.905977) (xy 125.407928 -217.878406)
			(xy 125.408436 -217.852519) (xy 125.416535 -217.801381) (xy 125.432534 -217.752141) (xy 125.45604 -217.706009)
			(xy 125.486472 -217.664122) (xy 125.523082 -217.627512) (xy 125.564969 -217.59708) (xy 125.611101 -217.573574)
			(xy 125.660341 -217.557575) (xy 125.711479 -217.549476) (xy 125.763253 -217.549476) (xy 125.814391 -217.557575)
			(xy 125.863631 -217.573574) (xy 125.909763 -217.59708) (xy 125.95165 -217.627512) (xy 125.98826 -217.664122)
			(xy 126.018692 -217.706009) (xy 126.042198 -217.752141) (xy 126.058197 -217.801381) (xy 126.066296 -217.852519)
			(xy 126.066804 -217.878406) (xy 126.066331 -217.90378) (xy 126.058562 -217.953931) (xy 126.043193 -218.002296)
			(xy 126.020588 -218.047732) (xy 125.991282 -218.089163) (xy 125.955968 -218.125609) (xy 125.915482 -218.156208)
			(xy 125.870782 -218.180235) (xy 125.822926 -218.197122) (xy 125.798072 -218.202256) (xy 125.775212 -218.206574)
			(xy 125.570488 -218.561412) (xy 125.578362 -218.583256) (xy 125.587014 -218.609662) (xy 125.59633 -218.66444)
			(xy 125.596904 -218.692222) (xy 125.596396 -218.718129) (xy 125.58829 -218.769306) (xy 125.572278 -218.818585)
			(xy 125.548755 -218.864752) (xy 125.518299 -218.906671) (xy 125.481661 -218.943309) (xy 125.439742 -218.973765)
			(xy 125.393575 -218.997288) (xy 125.344296 -219.0133) (xy 125.293119 -219.021406) (xy 125.241305 -219.021406)
			(xy 125.190128 -219.0133) (xy 125.140849 -218.997288) (xy 125.094682 -218.973765) (xy 125.052763 -218.943309)
			(xy 125.016125 -218.906671) (xy 124.985669 -218.864752) (xy 124.962146 -218.818585) (xy 124.946134 -218.769306)
			(xy 124.938028 -218.718129) (xy 124.93752 -218.692222) (xy 123.717304 -218.692222) (xy 123.716796 -218.718129)
			(xy 123.70869 -218.769306) (xy 123.692678 -218.818585) (xy 123.669155 -218.864752) (xy 123.638699 -218.906671)
			(xy 123.602061 -218.943309) (xy 123.560142 -218.973765) (xy 123.513975 -218.997288) (xy 123.464696 -219.0133)
			(xy 123.413519 -219.021406) (xy 123.361705 -219.021406) (xy 123.310528 -219.0133) (xy 123.261249 -218.997288)
			(xy 123.215082 -218.973765) (xy 123.173163 -218.943309) (xy 123.136525 -218.906671) (xy 123.106069 -218.864752)
			(xy 123.082546 -218.818585) (xy 123.066534 -218.769306) (xy 123.058428 -218.718129) (xy 123.05792 -218.692222)
			(xy 121.837704 -218.692222) (xy 121.837196 -218.718129) (xy 121.82909 -218.769306) (xy 121.813078 -218.818585)
			(xy 121.789555 -218.864752) (xy 121.759099 -218.906671) (xy 121.722461 -218.943309) (xy 121.680542 -218.973765)
			(xy 121.634375 -218.997288) (xy 121.585096 -219.0133) (xy 121.533919 -219.021406) (xy 121.482105 -219.021406)
			(xy 121.430928 -219.0133) (xy 121.381649 -218.997288) (xy 121.335482 -218.973765) (xy 121.293563 -218.943309)
			(xy 121.256925 -218.906671) (xy 121.226469 -218.864752) (xy 121.202946 -218.818585) (xy 121.186934 -218.769306)
			(xy 121.178828 -218.718129) (xy 121.17832 -218.692222) (xy 119.958104 -218.692222) (xy 119.957596 -218.718129)
			(xy 119.94949 -218.769306) (xy 119.933478 -218.818585) (xy 119.909955 -218.864752) (xy 119.879499 -218.906671)
			(xy 119.842861 -218.943309) (xy 119.800942 -218.973765) (xy 119.754775 -218.997288) (xy 119.705496 -219.0133)
			(xy 119.654319 -219.021406) (xy 119.602505 -219.021406) (xy 119.551328 -219.0133) (xy 119.502049 -218.997288)
			(xy 119.455882 -218.973765) (xy 119.413963 -218.943309) (xy 119.377325 -218.906671) (xy 119.346869 -218.864752)
			(xy 119.323346 -218.818585) (xy 119.307334 -218.769306) (xy 119.299228 -218.718129) (xy 119.29872 -218.692222)
			(xy 118.078504 -218.692222) (xy 118.077996 -218.718129) (xy 118.06989 -218.769306) (xy 118.053878 -218.818585)
			(xy 118.030355 -218.864752) (xy 117.999899 -218.906671) (xy 117.963261 -218.943309) (xy 117.921342 -218.973765)
			(xy 117.875175 -218.997288) (xy 117.825896 -219.0133) (xy 117.774719 -219.021406) (xy 117.722905 -219.021406)
			(xy 117.671728 -219.0133) (xy 117.622449 -218.997288) (xy 117.576282 -218.973765) (xy 117.534363 -218.943309)
			(xy 117.497725 -218.906671) (xy 117.467269 -218.864752) (xy 117.443746 -218.818585) (xy 117.427734 -218.769306)
			(xy 117.419628 -218.718129) (xy 117.41912 -218.692222) (xy 116.198904 -218.692222) (xy 116.19842 -218.718122)
			(xy 116.190309 -218.769283) (xy 116.174291 -218.818544) (xy 116.15076 -218.864691) (xy 116.120296 -218.906587)
			(xy 116.083651 -218.943198) (xy 116.041727 -218.973622) (xy 115.995558 -218.99711) (xy 115.946281 -219.013082)
			(xy 115.895113 -219.021144) (xy 115.869212 -219.02166) (xy 115.839194 -219.021001) (xy 115.780149 -219.010142)
			(xy 115.751864 -219.00007) (xy 115.738544 -218.99545) (xy 115.710475 -218.992939) (xy 115.682789 -218.998198)
			(xy 115.657595 -219.010826) (xy 115.636814 -219.029862) (xy 115.62203 -219.053854) (xy 115.614369 -219.080975)
			(xy 115.613942 -219.095066) (xy 115.613942 -219.257626) (xy 115.633023 -219.274745) (xy 115.666149 -219.313863)
			(xy 115.692788 -219.357656) (xy 115.712292 -219.405061) (xy 115.724186 -219.454921) (xy 115.72818 -219.506025)
			(xy 115.724178 -219.557128) (xy 115.712277 -219.606987) (xy 115.692766 -219.654388) (xy 115.66612 -219.698178)
			(xy 115.632988 -219.73729) (xy 115.613942 -219.75445) (xy 115.613942 -220.319854) (xy 116.47932 -220.319854)
			(xy 116.479828 -220.293947) (xy 116.487934 -220.24277) (xy 116.503946 -220.193491) (xy 116.527469 -220.147324)
			(xy 116.557925 -220.105405) (xy 116.594563 -220.068767) (xy 116.636482 -220.038311) (xy 116.682649 -220.014788)
			(xy 116.731928 -219.998776) (xy 116.783105 -219.99067) (xy 116.834919 -219.99067) (xy 116.886096 -219.998776)
			(xy 116.935375 -220.014788) (xy 116.981542 -220.038311) (xy 117.023461 -220.068767) (xy 117.060099 -220.105405)
			(xy 117.090555 -220.147324) (xy 117.114078 -220.193491) (xy 117.13009 -220.24277) (xy 117.138196 -220.293947)
			(xy 117.138704 -220.319854) (xy 118.35892 -220.319854) (xy 118.359428 -220.293947) (xy 118.367534 -220.24277)
			(xy 118.383546 -220.193491) (xy 118.407069 -220.147324) (xy 118.437525 -220.105405) (xy 118.474163 -220.068767)
			(xy 118.516082 -220.038311) (xy 118.562249 -220.014788) (xy 118.611528 -219.998776) (xy 118.662705 -219.99067)
			(xy 118.714519 -219.99067) (xy 118.765696 -219.998776) (xy 118.814975 -220.014788) (xy 118.861142 -220.038311)
			(xy 118.903061 -220.068767) (xy 118.939699 -220.105405) (xy 118.970155 -220.147324) (xy 118.993678 -220.193491)
			(xy 119.00969 -220.24277) (xy 119.017796 -220.293947) (xy 119.018304 -220.319854) (xy 120.23852 -220.319854)
			(xy 120.239028 -220.293947) (xy 120.247134 -220.24277) (xy 120.263146 -220.193491) (xy 120.286669 -220.147324)
			(xy 120.317125 -220.105405) (xy 120.353763 -220.068767) (xy 120.395682 -220.038311) (xy 120.441849 -220.014788)
			(xy 120.491128 -219.998776) (xy 120.542305 -219.99067) (xy 120.594119 -219.99067) (xy 120.645296 -219.998776)
			(xy 120.694575 -220.014788) (xy 120.740742 -220.038311) (xy 120.782661 -220.068767) (xy 120.819299 -220.105405)
			(xy 120.849755 -220.147324) (xy 120.873278 -220.193491) (xy 120.88929 -220.24277) (xy 120.897396 -220.293947)
			(xy 120.897904 -220.319854) (xy 122.11812 -220.319854) (xy 122.118628 -220.293947) (xy 122.126734 -220.24277)
			(xy 122.142746 -220.193491) (xy 122.166269 -220.147324) (xy 122.196725 -220.105405) (xy 122.233363 -220.068767)
			(xy 122.275282 -220.038311) (xy 122.321449 -220.014788) (xy 122.370728 -219.998776) (xy 122.421905 -219.99067)
			(xy 122.473719 -219.99067) (xy 122.524896 -219.998776) (xy 122.574175 -220.014788) (xy 122.620342 -220.038311)
			(xy 122.662261 -220.068767) (xy 122.698899 -220.105405) (xy 122.729355 -220.147324) (xy 122.752878 -220.193491)
			(xy 122.76889 -220.24277) (xy 122.776996 -220.293947) (xy 122.777504 -220.319854) (xy 123.99772 -220.319854)
			(xy 123.998228 -220.293947) (xy 124.006334 -220.24277) (xy 124.022346 -220.193491) (xy 124.045869 -220.147324)
			(xy 124.076325 -220.105405) (xy 124.112963 -220.068767) (xy 124.154882 -220.038311) (xy 124.201049 -220.014788)
			(xy 124.250328 -219.998776) (xy 124.301505 -219.99067) (xy 124.353319 -219.99067) (xy 124.404496 -219.998776)
			(xy 124.453775 -220.014788) (xy 124.499942 -220.038311) (xy 124.541861 -220.068767) (xy 124.578499 -220.105405)
			(xy 124.608955 -220.147324) (xy 124.632478 -220.193491) (xy 124.64849 -220.24277) (xy 124.656596 -220.293947)
			(xy 124.657104 -220.319854) (xy 125.87732 -220.319854) (xy 125.877828 -220.293947) (xy 125.885934 -220.24277)
			(xy 125.901946 -220.193491) (xy 125.925469 -220.147324) (xy 125.955925 -220.105405) (xy 125.992563 -220.068767)
			(xy 126.034482 -220.038311) (xy 126.080649 -220.014788) (xy 126.129928 -219.998776) (xy 126.181105 -219.99067)
			(xy 126.232919 -219.99067) (xy 126.284096 -219.998776) (xy 126.333375 -220.014788) (xy 126.379542 -220.038311)
			(xy 126.421461 -220.068767) (xy 126.458099 -220.105405) (xy 126.488555 -220.147324) (xy 126.512078 -220.193491)
			(xy 126.52809 -220.24277) (xy 126.536196 -220.293947) (xy 126.536704 -220.319854) (xy 126.536094 -220.347507)
			(xy 126.526771 -220.402025) (xy 126.518162 -220.428312) (xy 126.510542 -220.45041) (xy 126.715774 -220.805756)
			(xy 126.738634 -220.810074) (xy 126.763445 -220.815229) (xy 126.811184 -220.832223) (xy 126.855762 -220.856322)
			(xy 126.896127 -220.886957) (xy 126.93133 -220.923408) (xy 126.96054 -220.964816) (xy 126.983072 -221.010206)
			(xy 126.998392 -221.058509) (xy 127.006142 -221.108587) (xy 127.006604 -221.133924) (xy 127.006096 -221.159811)
			(xy 126.997997 -221.210949) (xy 126.981998 -221.260189) (xy 126.958492 -221.306321) (xy 126.92806 -221.348208)
			(xy 126.89145 -221.384818) (xy 126.849563 -221.41525) (xy 126.803431 -221.438756) (xy 126.754191 -221.454755)
			(xy 126.703053 -221.462854) (xy 126.651279 -221.462854) (xy 126.600141 -221.454755) (xy 126.550901 -221.438756)
			(xy 126.504769 -221.41525) (xy 126.462882 -221.384818) (xy 126.426272 -221.348208) (xy 126.39584 -221.306321)
			(xy 126.372334 -221.260189) (xy 126.356335 -221.210949) (xy 126.348236 -221.159811) (xy 126.347728 -221.133924)
			(xy 126.348267 -221.106216) (xy 126.357456 -221.05157) (xy 126.366016 -221.025212) (xy 126.37389 -221.003114)
			(xy 126.168912 -220.648022) (xy 126.146052 -220.643704) (xy 126.1212 -220.63857) (xy 126.073353 -220.621668)
			(xy 126.028662 -220.597632) (xy 125.988184 -220.567029) (xy 125.952874 -220.530584) (xy 125.923568 -220.489157)
			(xy 125.900957 -220.443728) (xy 125.885577 -220.39537) (xy 125.877791 -220.345226) (xy 125.87732 -220.319854)
			(xy 124.657104 -220.319854) (xy 124.656494 -220.347507) (xy 124.647171 -220.402025) (xy 124.638562 -220.428312)
			(xy 124.630942 -220.45041) (xy 124.836174 -220.805756) (xy 124.859034 -220.810074) (xy 124.883845 -220.815229)
			(xy 124.931584 -220.832223) (xy 124.976162 -220.856322) (xy 125.016527 -220.886957) (xy 125.05173 -220.923408)
			(xy 125.08094 -220.964816) (xy 125.103472 -221.010206) (xy 125.118792 -221.058509) (xy 125.126542 -221.108587)
			(xy 125.127004 -221.133924) (xy 125.126496 -221.159811) (xy 125.118397 -221.210949) (xy 125.102398 -221.260189)
			(xy 125.078892 -221.306321) (xy 125.04846 -221.348208) (xy 125.01185 -221.384818) (xy 124.969963 -221.41525)
			(xy 124.923831 -221.438756) (xy 124.874591 -221.454755) (xy 124.823453 -221.462854) (xy 124.771679 -221.462854)
			(xy 124.720541 -221.454755) (xy 124.671301 -221.438756) (xy 124.625169 -221.41525) (xy 124.583282 -221.384818)
			(xy 124.546672 -221.348208) (xy 124.51624 -221.306321) (xy 124.492734 -221.260189) (xy 124.476735 -221.210949)
			(xy 124.468636 -221.159811) (xy 124.468128 -221.133924) (xy 124.468667 -221.106216) (xy 124.477856 -221.05157)
			(xy 124.486416 -221.025212) (xy 124.49429 -221.003114) (xy 124.289312 -220.648022) (xy 124.266452 -220.643704)
			(xy 124.2416 -220.63857) (xy 124.193753 -220.621668) (xy 124.149062 -220.597632) (xy 124.108584 -220.567029)
			(xy 124.073274 -220.530584) (xy 124.043968 -220.489157) (xy 124.021357 -220.443728) (xy 124.005977 -220.39537)
			(xy 123.998191 -220.345226) (xy 123.99772 -220.319854) (xy 122.777504 -220.319854) (xy 122.776894 -220.347507)
			(xy 122.767571 -220.402025) (xy 122.758962 -220.428312) (xy 122.751342 -220.45041) (xy 122.956574 -220.805756)
			(xy 122.979434 -220.810074) (xy 123.004245 -220.815229) (xy 123.051984 -220.832223) (xy 123.096562 -220.856322)
			(xy 123.136927 -220.886957) (xy 123.17213 -220.923408) (xy 123.20134 -220.964816) (xy 123.223872 -221.010206)
			(xy 123.239192 -221.058509) (xy 123.246942 -221.108587) (xy 123.247404 -221.133924) (xy 123.246896 -221.159811)
			(xy 123.238797 -221.210949) (xy 123.222798 -221.260189) (xy 123.199292 -221.306321) (xy 123.16886 -221.348208)
			(xy 123.13225 -221.384818) (xy 123.090363 -221.41525) (xy 123.044231 -221.438756) (xy 122.994991 -221.454755)
			(xy 122.943853 -221.462854) (xy 122.892079 -221.462854) (xy 122.840941 -221.454755) (xy 122.791701 -221.438756)
			(xy 122.745569 -221.41525) (xy 122.703682 -221.384818) (xy 122.667072 -221.348208) (xy 122.63664 -221.306321)
			(xy 122.613134 -221.260189) (xy 122.597135 -221.210949) (xy 122.589036 -221.159811) (xy 122.588528 -221.133924)
			(xy 122.589067 -221.106216) (xy 122.598256 -221.05157) (xy 122.606816 -221.025212) (xy 122.61469 -221.003114)
			(xy 122.409712 -220.648022) (xy 122.386852 -220.643704) (xy 122.362 -220.63857) (xy 122.314153 -220.621668)
			(xy 122.269462 -220.597632) (xy 122.228984 -220.567029) (xy 122.193674 -220.530584) (xy 122.164368 -220.489157)
			(xy 122.141757 -220.443728) (xy 122.126377 -220.39537) (xy 122.118591 -220.345226) (xy 122.11812 -220.319854)
			(xy 120.897904 -220.319854) (xy 120.897294 -220.347507) (xy 120.887971 -220.402025) (xy 120.879362 -220.428312)
			(xy 120.871742 -220.45041) (xy 121.076974 -220.805756) (xy 121.099834 -220.810074) (xy 121.124645 -220.815229)
			(xy 121.172384 -220.832223) (xy 121.216962 -220.856322) (xy 121.257327 -220.886957) (xy 121.29253 -220.923408)
			(xy 121.32174 -220.964816) (xy 121.344272 -221.010206) (xy 121.359592 -221.058509) (xy 121.367342 -221.108587)
			(xy 121.367804 -221.133924) (xy 121.367296 -221.159811) (xy 121.359197 -221.210949) (xy 121.343198 -221.260189)
			(xy 121.319692 -221.306321) (xy 121.28926 -221.348208) (xy 121.25265 -221.384818) (xy 121.210763 -221.41525)
			(xy 121.164631 -221.438756) (xy 121.115391 -221.454755) (xy 121.064253 -221.462854) (xy 121.012479 -221.462854)
			(xy 120.961341 -221.454755) (xy 120.912101 -221.438756) (xy 120.865969 -221.41525) (xy 120.824082 -221.384818)
			(xy 120.787472 -221.348208) (xy 120.75704 -221.306321) (xy 120.733534 -221.260189) (xy 120.717535 -221.210949)
			(xy 120.709436 -221.159811) (xy 120.708928 -221.133924) (xy 120.709467 -221.106216) (xy 120.718656 -221.05157)
			(xy 120.727216 -221.025212) (xy 120.73509 -221.003114) (xy 120.530112 -220.648022) (xy 120.507252 -220.643704)
			(xy 120.4824 -220.63857) (xy 120.434553 -220.621668) (xy 120.389862 -220.597632) (xy 120.349384 -220.567029)
			(xy 120.314074 -220.530584) (xy 120.284768 -220.489157) (xy 120.262157 -220.443728) (xy 120.246777 -220.39537)
			(xy 120.238991 -220.345226) (xy 120.23852 -220.319854) (xy 119.018304 -220.319854) (xy 119.017694 -220.347507)
			(xy 119.008371 -220.402025) (xy 118.999762 -220.428312) (xy 118.992142 -220.45041) (xy 119.197374 -220.805756)
			(xy 119.220234 -220.810074) (xy 119.245045 -220.815229) (xy 119.292784 -220.832223) (xy 119.337362 -220.856322)
			(xy 119.377727 -220.886957) (xy 119.41293 -220.923408) (xy 119.44214 -220.964816) (xy 119.464672 -221.010206)
			(xy 119.479992 -221.058509) (xy 119.487742 -221.108587) (xy 119.488204 -221.133924) (xy 119.487696 -221.159811)
			(xy 119.479597 -221.210949) (xy 119.463598 -221.260189) (xy 119.440092 -221.306321) (xy 119.40966 -221.348208)
			(xy 119.37305 -221.384818) (xy 119.331163 -221.41525) (xy 119.285031 -221.438756) (xy 119.235791 -221.454755)
			(xy 119.184653 -221.462854) (xy 119.132879 -221.462854) (xy 119.081741 -221.454755) (xy 119.032501 -221.438756)
			(xy 118.986369 -221.41525) (xy 118.944482 -221.384818) (xy 118.907872 -221.348208) (xy 118.87744 -221.306321)
			(xy 118.853934 -221.260189) (xy 118.837935 -221.210949) (xy 118.829836 -221.159811) (xy 118.829328 -221.133924)
			(xy 118.829867 -221.106216) (xy 118.839056 -221.05157) (xy 118.847616 -221.025212) (xy 118.85549 -221.003114)
			(xy 118.650512 -220.648022) (xy 118.627652 -220.643704) (xy 118.6028 -220.63857) (xy 118.554953 -220.621668)
			(xy 118.510262 -220.597632) (xy 118.469784 -220.567029) (xy 118.434474 -220.530584) (xy 118.405168 -220.489157)
			(xy 118.382557 -220.443728) (xy 118.367177 -220.39537) (xy 118.359391 -220.345226) (xy 118.35892 -220.319854)
			(xy 117.138704 -220.319854) (xy 117.138094 -220.347507) (xy 117.128771 -220.402025) (xy 117.120162 -220.428312)
			(xy 117.112542 -220.45041) (xy 117.317774 -220.805756) (xy 117.340634 -220.810074) (xy 117.365445 -220.815229)
			(xy 117.413184 -220.832223) (xy 117.457762 -220.856322) (xy 117.498127 -220.886957) (xy 117.53333 -220.923408)
			(xy 117.56254 -220.964816) (xy 117.585072 -221.010206) (xy 117.600392 -221.058509) (xy 117.608142 -221.108587)
			(xy 117.608604 -221.133924) (xy 117.608096 -221.159811) (xy 117.599997 -221.210949) (xy 117.583998 -221.260189)
			(xy 117.560492 -221.306321) (xy 117.53006 -221.348208) (xy 117.49345 -221.384818) (xy 117.451563 -221.41525)
			(xy 117.405431 -221.438756) (xy 117.356191 -221.454755) (xy 117.305053 -221.462854) (xy 117.253279 -221.462854)
			(xy 117.202141 -221.454755) (xy 117.152901 -221.438756) (xy 117.106769 -221.41525) (xy 117.064882 -221.384818)
			(xy 117.028272 -221.348208) (xy 116.99784 -221.306321) (xy 116.974334 -221.260189) (xy 116.958335 -221.210949)
			(xy 116.950236 -221.159811) (xy 116.949728 -221.133924) (xy 116.950267 -221.106216) (xy 116.959456 -221.05157)
			(xy 116.968016 -221.025212) (xy 116.97589 -221.003114) (xy 116.770912 -220.648022) (xy 116.748052 -220.643704)
			(xy 116.7232 -220.63857) (xy 116.675353 -220.621668) (xy 116.630662 -220.597632) (xy 116.590184 -220.567029)
			(xy 116.554874 -220.530584) (xy 116.525568 -220.489157) (xy 116.502957 -220.443728) (xy 116.487577 -220.39537)
			(xy 116.479791 -220.345226) (xy 116.47932 -220.319854) (xy 115.613942 -220.319854) (xy 115.613942 -220.883734)
			(xy 115.633238 -220.90093) (xy 115.666752 -220.940273) (xy 115.693712 -220.984368) (xy 115.713454 -221.032131)
			(xy 115.725496 -221.082391) (xy 115.729542 -221.133916) (xy 115.725491 -221.185439) (xy 115.713445 -221.235699)
			(xy 115.693697 -221.28346) (xy 115.666734 -221.327552) (xy 115.633216 -221.366892) (xy 115.613942 -221.384114)
			(xy 115.613942 -221.544896) (xy 115.614406 -221.558975) (xy 115.62211 -221.586059) (xy 115.636907 -221.610016)
			(xy 115.657676 -221.62903) (xy 115.682843 -221.64166) (xy 115.7105 -221.646949) (xy 115.738552 -221.644496)
			(xy 115.751864 -221.639892) (xy 115.765502 -221.634811) (xy 115.793484 -221.626801) (xy 115.807744 -221.62389)
			(xy 115.830604 -221.619572) (xy 116.035836 -221.264226) (xy 116.027962 -221.242128) (xy 116.019499 -221.215884)
			(xy 116.010434 -221.161495) (xy 116.009928 -221.133924) (xy 116.010436 -221.108037) (xy 116.018535 -221.056899)
			(xy 116.034534 -221.007659) (xy 116.05804 -220.961527) (xy 116.088472 -220.91964) (xy 116.125082 -220.88303)
			(xy 116.166969 -220.852598) (xy 116.213101 -220.829092) (xy 116.262341 -220.813093) (xy 116.313479 -220.804994)
			(xy 116.365253 -220.804994) (xy 116.416391 -220.813093) (xy 116.465631 -220.829092) (xy 116.511763 -220.852598)
			(xy 116.55365 -220.88303) (xy 116.59026 -220.91964) (xy 116.620692 -220.961527) (xy 116.644198 -221.007659)
			(xy 116.660197 -221.056899) (xy 116.668296 -221.108037) (xy 116.668804 -221.133924) (xy 116.668335 -221.159296)
			(xy 116.660552 -221.20944) (xy 116.645173 -221.257797) (xy 116.622563 -221.303226) (xy 116.593255 -221.34465)
			(xy 116.557943 -221.381092) (xy 116.517462 -221.41169) (xy 116.472768 -221.43572) (xy 116.424919 -221.452614)
			(xy 116.400072 -221.457774) (xy 116.377212 -221.462092) (xy 116.172488 -221.81693) (xy 116.180362 -221.838774)
			(xy 116.189005 -221.865183) (xy 116.198321 -221.919959) (xy 116.198904 -221.94774) (xy 117.41912 -221.94774)
			(xy 117.419571 -221.922394) (xy 117.427352 -221.872302) (xy 117.442706 -221.82399) (xy 117.465272 -221.778597)
			(xy 117.494518 -221.737192) (xy 117.529755 -221.700749) (xy 117.570154 -221.670127) (xy 117.614762 -221.646047)
			(xy 117.66253 -221.629076) (xy 117.687344 -221.62389) (xy 117.710204 -221.619572) (xy 117.915436 -221.264226)
			(xy 117.907562 -221.242128) (xy 117.899098 -221.215883) (xy 117.890025 -221.161495) (xy 117.889528 -221.133924)
			(xy 117.890036 -221.108037) (xy 117.898135 -221.056899) (xy 117.914134 -221.007659) (xy 117.93764 -220.961527)
			(xy 117.968072 -220.91964) (xy 118.004682 -220.88303) (xy 118.046569 -220.852598) (xy 118.092701 -220.829092)
			(xy 118.141941 -220.813093) (xy 118.193079 -220.804994) (xy 118.244853 -220.804994) (xy 118.295991 -220.813093)
			(xy 118.345231 -220.829092) (xy 118.391363 -220.852598) (xy 118.43325 -220.88303) (xy 118.46986 -220.91964)
			(xy 118.500292 -220.961527) (xy 118.523798 -221.007659) (xy 118.539797 -221.056899) (xy 118.547896 -221.108037)
			(xy 118.548404 -221.133924) (xy 118.547948 -221.159299) (xy 118.540176 -221.20945) (xy 118.524804 -221.257815)
			(xy 118.502197 -221.303251) (xy 118.472889 -221.344682) (xy 118.437573 -221.381128) (xy 118.397085 -221.411727)
			(xy 118.352384 -221.435754) (xy 118.304526 -221.452641) (xy 118.279672 -221.457774) (xy 118.256812 -221.462092)
			(xy 118.052088 -221.81693) (xy 118.059962 -221.838774) (xy 118.068619 -221.865179) (xy 118.077932 -221.919958)
			(xy 118.078504 -221.94774) (xy 121.17832 -221.94774) (xy 121.178771 -221.922394) (xy 121.186552 -221.872302)
			(xy 121.201906 -221.82399) (xy 121.224472 -221.778597) (xy 121.253718 -221.737192) (xy 121.288955 -221.700749)
			(xy 121.329354 -221.670127) (xy 121.373962 -221.646047) (xy 121.42173 -221.629076) (xy 121.446544 -221.62389)
			(xy 121.469404 -221.619572) (xy 121.674636 -221.264226) (xy 121.666762 -221.242128) (xy 121.658298 -221.215883)
			(xy 121.649225 -221.161495) (xy 121.648728 -221.133924) (xy 121.649236 -221.108037) (xy 121.657335 -221.056899)
			(xy 121.673334 -221.007659) (xy 121.69684 -220.961527) (xy 121.727272 -220.91964) (xy 121.763882 -220.88303)
			(xy 121.805769 -220.852598) (xy 121.851901 -220.829092) (xy 121.901141 -220.813093) (xy 121.952279 -220.804994)
			(xy 122.004053 -220.804994) (xy 122.055191 -220.813093) (xy 122.104431 -220.829092) (xy 122.150563 -220.852598)
			(xy 122.19245 -220.88303) (xy 122.22906 -220.91964) (xy 122.259492 -220.961527) (xy 122.282998 -221.007659)
			(xy 122.298997 -221.056899) (xy 122.307096 -221.108037) (xy 122.307604 -221.133924) (xy 122.307148 -221.159299)
			(xy 122.299376 -221.20945) (xy 122.284004 -221.257815) (xy 122.261397 -221.303251) (xy 122.232089 -221.344682)
			(xy 122.196773 -221.381128) (xy 122.156285 -221.411727) (xy 122.111584 -221.435754) (xy 122.063726 -221.452641)
			(xy 122.038872 -221.457774) (xy 122.016012 -221.462092) (xy 121.811288 -221.81693) (xy 121.819162 -221.838774)
			(xy 121.827819 -221.865179) (xy 121.837132 -221.919958) (xy 121.837704 -221.94774) (xy 123.05792 -221.94774)
			(xy 123.058371 -221.922394) (xy 123.066152 -221.872302) (xy 123.081506 -221.82399) (xy 123.104072 -221.778597)
			(xy 123.133318 -221.737192) (xy 123.168555 -221.700749) (xy 123.208954 -221.670127) (xy 123.253562 -221.646047)
			(xy 123.30133 -221.629076) (xy 123.326144 -221.62389) (xy 123.349004 -221.619572) (xy 123.554236 -221.264226)
			(xy 123.546362 -221.242128) (xy 123.537898 -221.215883) (xy 123.528825 -221.161495) (xy 123.528328 -221.133924)
			(xy 123.528836 -221.108037) (xy 123.536935 -221.056899) (xy 123.552934 -221.007659) (xy 123.57644 -220.961527)
			(xy 123.606872 -220.91964) (xy 123.643482 -220.88303) (xy 123.685369 -220.852598) (xy 123.731501 -220.829092)
			(xy 123.780741 -220.813093) (xy 123.831879 -220.804994) (xy 123.883653 -220.804994) (xy 123.934791 -220.813093)
			(xy 123.984031 -220.829092) (xy 124.030163 -220.852598) (xy 124.07205 -220.88303) (xy 124.10866 -220.91964)
			(xy 124.139092 -220.961527) (xy 124.162598 -221.007659) (xy 124.178597 -221.056899) (xy 124.186696 -221.108037)
			(xy 124.187204 -221.133924) (xy 124.186748 -221.159299) (xy 124.178976 -221.20945) (xy 124.163604 -221.257815)
			(xy 124.140997 -221.303251) (xy 124.111689 -221.344682) (xy 124.076373 -221.381128) (xy 124.035885 -221.411727)
			(xy 123.991184 -221.435754) (xy 123.943326 -221.452641) (xy 123.918472 -221.457774) (xy 123.895612 -221.462092)
			(xy 123.690888 -221.81693) (xy 123.698762 -221.838774) (xy 123.707419 -221.865179) (xy 123.716732 -221.919958)
			(xy 123.717304 -221.94774) (xy 124.93752 -221.94774) (xy 124.937971 -221.922394) (xy 124.945752 -221.872302)
			(xy 124.961106 -221.82399) (xy 124.983672 -221.778597) (xy 125.012918 -221.737192) (xy 125.048155 -221.700749)
			(xy 125.088554 -221.670127) (xy 125.133162 -221.646047) (xy 125.18093 -221.629076) (xy 125.205744 -221.62389)
			(xy 125.228604 -221.619572) (xy 125.433836 -221.264226) (xy 125.425962 -221.242128) (xy 125.417498 -221.215883)
			(xy 125.408425 -221.161495) (xy 125.407928 -221.133924) (xy 125.408436 -221.108037) (xy 125.416535 -221.056899)
			(xy 125.432534 -221.007659) (xy 125.45604 -220.961527) (xy 125.486472 -220.91964) (xy 125.523082 -220.88303)
			(xy 125.564969 -220.852598) (xy 125.611101 -220.829092) (xy 125.660341 -220.813093) (xy 125.711479 -220.804994)
			(xy 125.763253 -220.804994) (xy 125.814391 -220.813093) (xy 125.863631 -220.829092) (xy 125.909763 -220.852598)
			(xy 125.95165 -220.88303) (xy 125.98826 -220.91964) (xy 126.018692 -220.961527) (xy 126.042198 -221.007659)
			(xy 126.058197 -221.056899) (xy 126.066296 -221.108037) (xy 126.066804 -221.133924) (xy 126.066348 -221.159299)
			(xy 126.058576 -221.20945) (xy 126.043204 -221.257815) (xy 126.020597 -221.303251) (xy 125.991289 -221.344682)
			(xy 125.955973 -221.381128) (xy 125.915485 -221.411727) (xy 125.870784 -221.435754) (xy 125.822926 -221.452641)
			(xy 125.798072 -221.457774) (xy 125.775212 -221.462092) (xy 125.570488 -221.81693) (xy 125.578362 -221.838774)
			(xy 125.587019 -221.865179) (xy 125.596332 -221.919958) (xy 125.596904 -221.94774) (xy 125.596396 -221.973647)
			(xy 125.58829 -222.024824) (xy 125.572278 -222.074103) (xy 125.548755 -222.12027) (xy 125.518299 -222.162189)
			(xy 125.481661 -222.198827) (xy 125.439742 -222.229283) (xy 125.393575 -222.252806) (xy 125.344296 -222.268818)
			(xy 125.293119 -222.276924) (xy 125.241305 -222.276924) (xy 125.190128 -222.268818) (xy 125.140849 -222.252806)
			(xy 125.094682 -222.229283) (xy 125.052763 -222.198827) (xy 125.016125 -222.162189) (xy 124.985669 -222.12027)
			(xy 124.962146 -222.074103) (xy 124.946134 -222.024824) (xy 124.938028 -221.973647) (xy 124.93752 -221.94774)
			(xy 123.717304 -221.94774) (xy 123.716796 -221.973647) (xy 123.70869 -222.024824) (xy 123.692678 -222.074103)
			(xy 123.669155 -222.12027) (xy 123.638699 -222.162189) (xy 123.602061 -222.198827) (xy 123.560142 -222.229283)
			(xy 123.513975 -222.252806) (xy 123.464696 -222.268818) (xy 123.413519 -222.276924) (xy 123.361705 -222.276924)
			(xy 123.310528 -222.268818) (xy 123.261249 -222.252806) (xy 123.215082 -222.229283) (xy 123.173163 -222.198827)
			(xy 123.136525 -222.162189) (xy 123.106069 -222.12027) (xy 123.082546 -222.074103) (xy 123.066534 -222.024824)
			(xy 123.058428 -221.973647) (xy 123.05792 -221.94774) (xy 121.837704 -221.94774) (xy 121.837196 -221.973647)
			(xy 121.82909 -222.024824) (xy 121.813078 -222.074103) (xy 121.789555 -222.12027) (xy 121.759099 -222.162189)
			(xy 121.722461 -222.198827) (xy 121.680542 -222.229283) (xy 121.634375 -222.252806) (xy 121.585096 -222.268818)
			(xy 121.533919 -222.276924) (xy 121.482105 -222.276924) (xy 121.430928 -222.268818) (xy 121.381649 -222.252806)
			(xy 121.335482 -222.229283) (xy 121.293563 -222.198827) (xy 121.256925 -222.162189) (xy 121.226469 -222.12027)
			(xy 121.202946 -222.074103) (xy 121.186934 -222.024824) (xy 121.178828 -221.973647) (xy 121.17832 -221.94774)
			(xy 118.078504 -221.94774) (xy 118.077996 -221.973647) (xy 118.06989 -222.024824) (xy 118.053878 -222.074103)
			(xy 118.030355 -222.12027) (xy 117.999899 -222.162189) (xy 117.963261 -222.198827) (xy 117.921342 -222.229283)
			(xy 117.875175 -222.252806) (xy 117.825896 -222.268818) (xy 117.774719 -222.276924) (xy 117.722905 -222.276924)
			(xy 117.671728 -222.268818) (xy 117.622449 -222.252806) (xy 117.576282 -222.229283) (xy 117.534363 -222.198827)
			(xy 117.497725 -222.162189) (xy 117.467269 -222.12027) (xy 117.443746 -222.074103) (xy 117.427734 -222.024824)
			(xy 117.419628 -221.973647) (xy 117.41912 -221.94774) (xy 116.198904 -221.94774) (xy 116.198393 -221.973646)
			(xy 116.190283 -222.024818) (xy 116.174268 -222.074092) (xy 116.150742 -222.120255) (xy 116.120286 -222.162169)
			(xy 116.083648 -222.198804) (xy 116.041731 -222.229257) (xy 115.995567 -222.252778) (xy 115.946291 -222.268789)
			(xy 115.895118 -222.276895) (xy 115.869212 -222.277432) (xy 115.839186 -222.276697) (xy 115.780145 -222.265701)
			(xy 115.751864 -222.255588) (xy 115.738541 -222.25097) (xy 115.710466 -222.248462) (xy 115.682774 -222.253721)
			(xy 115.657573 -222.266348) (xy 115.636782 -222.28538) (xy 115.621983 -222.30937) (xy 115.614303 -222.33649)
			(xy 115.613942 -222.350584) (xy 115.613942 -222.513144) (xy 115.633029 -222.530263) (xy 115.666168 -222.569383)
			(xy 115.69282 -222.61318) (xy 115.712335 -222.66059) (xy 115.724239 -222.710458) (xy 115.728243 -222.761571)
			(xy 115.724248 -222.812685) (xy 115.712353 -222.862555) (xy 115.692846 -222.909968) (xy 115.666202 -222.953771)
			(xy 115.63307 -222.992896) (xy 115.613942 -223.009968) (xy 115.613942 -224.139252) (xy 115.631661 -224.154976)
			(xy 115.662847 -224.190635) (xy 115.6886 -224.230396) (xy 115.70839 -224.273437) (xy 115.721808 -224.318869)
			(xy 115.728576 -224.365756) (xy 115.729004 -224.389442) (xy 116.009928 -224.389442) (xy 116.010335 -224.364105)
			(xy 116.018097 -224.314028) (xy 116.033429 -224.265728) (xy 116.05597 -224.220343) (xy 116.085189 -224.17894)
			(xy 116.120399 -224.142496) (xy 116.16077 -224.111867) (xy 116.205352 -224.087776) (xy 116.253095 -224.070789)
			(xy 116.277898 -224.065592) (xy 116.300758 -224.061274) (xy 116.505482 -223.706436) (xy 116.497862 -223.684338)
			(xy 116.489231 -223.657991) (xy 116.47991 -223.603344) (xy 116.47932 -223.575626) (xy 116.479828 -223.549719)
			(xy 116.487934 -223.498542) (xy 116.503946 -223.449263) (xy 116.527469 -223.403096) (xy 116.557925 -223.361177)
			(xy 116.594563 -223.324539) (xy 116.636482 -223.294083) (xy 116.682649 -223.27056) (xy 116.731928 -223.254548)
			(xy 116.783105 -223.246442) (xy 116.834919 -223.246442) (xy 116.886096 -223.254548) (xy 116.935375 -223.27056)
			(xy 116.981542 -223.294083) (xy 117.023461 -223.324539) (xy 117.060099 -223.361177) (xy 117.090555 -223.403096)
			(xy 117.114078 -223.449263) (xy 117.13009 -223.498542) (xy 117.138196 -223.549719) (xy 117.138704 -223.575626)
			(xy 117.138287 -223.600992) (xy 117.130534 -223.651127) (xy 117.115185 -223.69948) (xy 117.092603 -223.744908)
			(xy 117.063322 -223.786336) (xy 117.028034 -223.822783) (xy 116.987575 -223.853388) (xy 116.942901 -223.877427)
			(xy 116.895069 -223.894332) (xy 116.870226 -223.899476) (xy 116.847366 -223.903794) (xy 116.642642 -224.258632)
			(xy 116.650516 -224.280476) (xy 116.65909 -224.306896) (xy 116.66829 -224.36167) (xy 116.668804 -224.389442)
			(xy 116.949728 -224.389442) (xy 116.950236 -224.363555) (xy 116.958335 -224.312417) (xy 116.974334 -224.263177)
			(xy 116.99784 -224.217045) (xy 117.028272 -224.175158) (xy 117.064882 -224.138548) (xy 117.106769 -224.108116)
			(xy 117.152901 -224.08461) (xy 117.202141 -224.068611) (xy 117.253279 -224.060512) (xy 117.305053 -224.060512)
			(xy 117.356191 -224.068611) (xy 117.405431 -224.08461) (xy 117.451563 -224.108116) (xy 117.49345 -224.138548)
			(xy 117.53006 -224.175158) (xy 117.560492 -224.217045) (xy 117.583998 -224.263177) (xy 117.599997 -224.312417)
			(xy 117.608096 -224.363555) (xy 117.608604 -224.389442) (xy 117.889528 -224.389442) (xy 117.889935 -224.364105)
			(xy 117.897697 -224.314028) (xy 117.913029 -224.265728) (xy 117.93557 -224.220343) (xy 117.964789 -224.17894)
			(xy 117.999999 -224.142496) (xy 118.04037 -224.111867) (xy 118.084952 -224.087776) (xy 118.132695 -224.070789)
			(xy 118.157498 -224.065592) (xy 118.180358 -224.061274) (xy 118.385082 -223.706436) (xy 118.377462 -223.684338)
			(xy 118.368831 -223.657991) (xy 118.35951 -223.603344) (xy 118.35892 -223.575626) (xy 118.359428 -223.549719)
			(xy 118.367534 -223.498542) (xy 118.383546 -223.449263) (xy 118.407069 -223.403096) (xy 118.437525 -223.361177)
			(xy 118.474163 -223.324539) (xy 118.516082 -223.294083) (xy 118.562249 -223.27056) (xy 118.611528 -223.254548)
			(xy 118.662705 -223.246442) (xy 118.714519 -223.246442) (xy 118.765696 -223.254548) (xy 118.814975 -223.27056)
			(xy 118.861142 -223.294083) (xy 118.903061 -223.324539) (xy 118.939699 -223.361177) (xy 118.970155 -223.403096)
			(xy 118.993678 -223.449263) (xy 119.00969 -223.498542) (xy 119.017796 -223.549719) (xy 119.018304 -223.575626)
			(xy 119.017887 -223.600992) (xy 119.010134 -223.651127) (xy 118.994785 -223.69948) (xy 118.972203 -223.744908)
			(xy 118.942922 -223.786336) (xy 118.907634 -223.822783) (xy 118.867175 -223.853388) (xy 118.822501 -223.877427)
			(xy 118.774669 -223.894332) (xy 118.749826 -223.899476) (xy 118.726966 -223.903794) (xy 118.522242 -224.258632)
			(xy 118.530116 -224.280476) (xy 118.53869 -224.306896) (xy 118.54789 -224.36167) (xy 118.548404 -224.389442)
			(xy 118.829328 -224.389442) (xy 118.829836 -224.363555) (xy 118.837935 -224.312417) (xy 118.853934 -224.263177)
			(xy 118.87744 -224.217045) (xy 118.907872 -224.175158) (xy 118.944482 -224.138548) (xy 118.986369 -224.108116)
			(xy 119.032501 -224.08461) (xy 119.081741 -224.068611) (xy 119.132879 -224.060512) (xy 119.184653 -224.060512)
			(xy 119.235791 -224.068611) (xy 119.285031 -224.08461) (xy 119.331163 -224.108116) (xy 119.37305 -224.138548)
			(xy 119.40966 -224.175158) (xy 119.440092 -224.217045) (xy 119.463598 -224.263177) (xy 119.479597 -224.312417)
			(xy 119.487696 -224.363555) (xy 119.488204 -224.389442) (xy 119.769128 -224.389442) (xy 119.769535 -224.364105)
			(xy 119.777297 -224.314028) (xy 119.792629 -224.265728) (xy 119.81517 -224.220343) (xy 119.844389 -224.17894)
			(xy 119.879599 -224.142496) (xy 119.91997 -224.111867) (xy 119.964552 -224.087776) (xy 120.012295 -224.070789)
			(xy 120.037098 -224.065592) (xy 120.059958 -224.061274) (xy 120.264682 -223.706436) (xy 120.257062 -223.684338)
			(xy 120.248431 -223.657991) (xy 120.23911 -223.603344) (xy 120.23852 -223.575626) (xy 120.239028 -223.549719)
			(xy 120.247134 -223.498542) (xy 120.263146 -223.449263) (xy 120.286669 -223.403096) (xy 120.317125 -223.361177)
			(xy 120.353763 -223.324539) (xy 120.395682 -223.294083) (xy 120.441849 -223.27056) (xy 120.491128 -223.254548)
			(xy 120.542305 -223.246442) (xy 120.594119 -223.246442) (xy 120.645296 -223.254548) (xy 120.694575 -223.27056)
			(xy 120.740742 -223.294083) (xy 120.782661 -223.324539) (xy 120.819299 -223.361177) (xy 120.849755 -223.403096)
			(xy 120.873278 -223.449263) (xy 120.88929 -223.498542) (xy 120.897396 -223.549719) (xy 120.897904 -223.575626)
			(xy 120.897487 -223.600992) (xy 120.889734 -223.651127) (xy 120.874385 -223.69948) (xy 120.851803 -223.744908)
			(xy 120.822522 -223.786336) (xy 120.787234 -223.822783) (xy 120.746775 -223.853388) (xy 120.702101 -223.877427)
			(xy 120.654269 -223.894332) (xy 120.629426 -223.899476) (xy 120.606566 -223.903794) (xy 120.401842 -224.258632)
			(xy 120.409716 -224.280476) (xy 120.41829 -224.306896) (xy 120.42749 -224.36167) (xy 120.428004 -224.389442)
			(xy 120.708928 -224.389442) (xy 120.709436 -224.363555) (xy 120.717535 -224.312417) (xy 120.733534 -224.263177)
			(xy 120.75704 -224.217045) (xy 120.787472 -224.175158) (xy 120.824082 -224.138548) (xy 120.865969 -224.108116)
			(xy 120.912101 -224.08461) (xy 120.961341 -224.068611) (xy 121.012479 -224.060512) (xy 121.064253 -224.060512)
			(xy 121.115391 -224.068611) (xy 121.164631 -224.08461) (xy 121.210763 -224.108116) (xy 121.25265 -224.138548)
			(xy 121.28926 -224.175158) (xy 121.319692 -224.217045) (xy 121.343198 -224.263177) (xy 121.359197 -224.312417)
			(xy 121.367296 -224.363555) (xy 121.367804 -224.389442) (xy 121.648728 -224.389442) (xy 121.649135 -224.364105)
			(xy 121.656897 -224.314028) (xy 121.672229 -224.265728) (xy 121.69477 -224.220343) (xy 121.723989 -224.17894)
			(xy 121.759199 -224.142496) (xy 121.79957 -224.111867) (xy 121.844152 -224.087776) (xy 121.891895 -224.070789)
			(xy 121.916698 -224.065592) (xy 121.939558 -224.061274) (xy 122.144282 -223.706436) (xy 122.136662 -223.684338)
			(xy 122.128031 -223.657991) (xy 122.11871 -223.603344) (xy 122.11812 -223.575626) (xy 122.118628 -223.549719)
			(xy 122.126734 -223.498542) (xy 122.142746 -223.449263) (xy 122.166269 -223.403096) (xy 122.196725 -223.361177)
			(xy 122.233363 -223.324539) (xy 122.275282 -223.294083) (xy 122.321449 -223.27056) (xy 122.370728 -223.254548)
			(xy 122.421905 -223.246442) (xy 122.473719 -223.246442) (xy 122.524896 -223.254548) (xy 122.574175 -223.27056)
			(xy 122.620342 -223.294083) (xy 122.662261 -223.324539) (xy 122.698899 -223.361177) (xy 122.729355 -223.403096)
			(xy 122.752878 -223.449263) (xy 122.76889 -223.498542) (xy 122.776996 -223.549719) (xy 122.777504 -223.575626)
			(xy 122.777087 -223.600992) (xy 122.769334 -223.651127) (xy 122.753985 -223.69948) (xy 122.731403 -223.744908)
			(xy 122.702122 -223.786336) (xy 122.666834 -223.822783) (xy 122.626375 -223.853388) (xy 122.581701 -223.877427)
			(xy 122.533869 -223.894332) (xy 122.509026 -223.899476) (xy 122.486166 -223.903794) (xy 122.281442 -224.258632)
			(xy 122.289316 -224.280476) (xy 122.29789 -224.306896) (xy 122.30709 -224.36167) (xy 122.307604 -224.389442)
			(xy 122.588528 -224.389442) (xy 122.589036 -224.363555) (xy 122.597135 -224.312417) (xy 122.613134 -224.263177)
			(xy 122.63664 -224.217045) (xy 122.667072 -224.175158) (xy 122.703682 -224.138548) (xy 122.745569 -224.108116)
			(xy 122.791701 -224.08461) (xy 122.840941 -224.068611) (xy 122.892079 -224.060512) (xy 122.943853 -224.060512)
			(xy 122.994991 -224.068611) (xy 123.044231 -224.08461) (xy 123.090363 -224.108116) (xy 123.13225 -224.138548)
			(xy 123.16886 -224.175158) (xy 123.199292 -224.217045) (xy 123.222798 -224.263177) (xy 123.238797 -224.312417)
			(xy 123.246896 -224.363555) (xy 123.247404 -224.389442) (xy 123.528328 -224.389442) (xy 123.528735 -224.364105)
			(xy 123.536497 -224.314028) (xy 123.551829 -224.265728) (xy 123.57437 -224.220343) (xy 123.603589 -224.17894)
			(xy 123.638799 -224.142496) (xy 123.67917 -224.111867) (xy 123.723752 -224.087776) (xy 123.771495 -224.070789)
			(xy 123.796298 -224.065592) (xy 123.819158 -224.061274) (xy 124.023882 -223.706436) (xy 124.016262 -223.684338)
			(xy 124.007631 -223.657991) (xy 123.99831 -223.603344) (xy 123.99772 -223.575626) (xy 123.998228 -223.549719)
			(xy 124.006334 -223.498542) (xy 124.022346 -223.449263) (xy 124.045869 -223.403096) (xy 124.076325 -223.361177)
			(xy 124.112963 -223.324539) (xy 124.154882 -223.294083) (xy 124.201049 -223.27056) (xy 124.250328 -223.254548)
			(xy 124.301505 -223.246442) (xy 124.353319 -223.246442) (xy 124.404496 -223.254548) (xy 124.453775 -223.27056)
			(xy 124.499942 -223.294083) (xy 124.541861 -223.324539) (xy 124.578499 -223.361177) (xy 124.608955 -223.403096)
			(xy 124.632478 -223.449263) (xy 124.64849 -223.498542) (xy 124.656596 -223.549719) (xy 124.657104 -223.575626)
			(xy 124.656687 -223.600992) (xy 124.648934 -223.651127) (xy 124.633585 -223.69948) (xy 124.611003 -223.744908)
			(xy 124.581722 -223.786336) (xy 124.546434 -223.822783) (xy 124.505975 -223.853388) (xy 124.461301 -223.877427)
			(xy 124.413469 -223.894332) (xy 124.388626 -223.899476) (xy 124.365766 -223.903794) (xy 124.161042 -224.258632)
			(xy 124.168916 -224.280476) (xy 124.17749 -224.306896) (xy 124.18669 -224.36167) (xy 124.187204 -224.389442)
			(xy 124.468128 -224.389442) (xy 124.468636 -224.363555) (xy 124.476735 -224.312417) (xy 124.492734 -224.263177)
			(xy 124.51624 -224.217045) (xy 124.546672 -224.175158) (xy 124.583282 -224.138548) (xy 124.625169 -224.108116)
			(xy 124.671301 -224.08461) (xy 124.720541 -224.068611) (xy 124.771679 -224.060512) (xy 124.823453 -224.060512)
			(xy 124.874591 -224.068611) (xy 124.923831 -224.08461) (xy 124.969963 -224.108116) (xy 125.01185 -224.138548)
			(xy 125.04846 -224.175158) (xy 125.078892 -224.217045) (xy 125.102398 -224.263177) (xy 125.118397 -224.312417)
			(xy 125.126496 -224.363555) (xy 125.127004 -224.389442) (xy 125.407928 -224.389442) (xy 125.408335 -224.364105)
			(xy 125.416097 -224.314028) (xy 125.431429 -224.265728) (xy 125.45397 -224.220343) (xy 125.483189 -224.17894)
			(xy 125.518399 -224.142496) (xy 125.55877 -224.111867) (xy 125.603352 -224.087776) (xy 125.651095 -224.070789)
			(xy 125.675898 -224.065592) (xy 125.698758 -224.061274) (xy 125.903482 -223.706436) (xy 125.895862 -223.684338)
			(xy 125.887231 -223.657991) (xy 125.87791 -223.603344) (xy 125.87732 -223.575626) (xy 125.877828 -223.549719)
			(xy 125.885934 -223.498542) (xy 125.901946 -223.449263) (xy 125.925469 -223.403096) (xy 125.955925 -223.361177)
			(xy 125.992563 -223.324539) (xy 126.034482 -223.294083) (xy 126.080649 -223.27056) (xy 126.129928 -223.254548)
			(xy 126.181105 -223.246442) (xy 126.232919 -223.246442) (xy 126.284096 -223.254548) (xy 126.333375 -223.27056)
			(xy 126.379542 -223.294083) (xy 126.421461 -223.324539) (xy 126.458099 -223.361177) (xy 126.488555 -223.403096)
			(xy 126.512078 -223.449263) (xy 126.52809 -223.498542) (xy 126.536196 -223.549719) (xy 126.536704 -223.575626)
			(xy 126.536287 -223.600992) (xy 126.528534 -223.651127) (xy 126.513185 -223.69948) (xy 126.490603 -223.744908)
			(xy 126.461322 -223.786336) (xy 126.426034 -223.822783) (xy 126.385575 -223.853388) (xy 126.340901 -223.877427)
			(xy 126.293069 -223.894332) (xy 126.268226 -223.899476) (xy 126.245366 -223.903794) (xy 126.040642 -224.258632)
			(xy 126.048516 -224.280476) (xy 126.05709 -224.306896) (xy 126.06629 -224.36167) (xy 126.066804 -224.389442)
			(xy 126.066296 -224.415329) (xy 126.058197 -224.466467) (xy 126.042198 -224.515707) (xy 126.018692 -224.561839)
			(xy 125.98826 -224.603726) (xy 125.95165 -224.640336) (xy 125.909763 -224.670768) (xy 125.863631 -224.694274)
			(xy 125.814391 -224.710273) (xy 125.763253 -224.718372) (xy 125.711479 -224.718372) (xy 125.660341 -224.710273)
			(xy 125.611101 -224.694274) (xy 125.564969 -224.670768) (xy 125.523082 -224.640336) (xy 125.486472 -224.603726)
			(xy 125.45604 -224.561839) (xy 125.432534 -224.515707) (xy 125.416535 -224.466467) (xy 125.408436 -224.415329)
			(xy 125.407928 -224.389442) (xy 125.127004 -224.389442) (xy 125.12646 -224.417149) (xy 125.117274 -224.471796)
			(xy 125.108716 -224.498154) (xy 125.100842 -224.520252) (xy 125.30582 -224.87509) (xy 125.32868 -224.879408)
			(xy 125.353509 -224.884542) (xy 125.401288 -224.901501) (xy 125.445908 -224.925578) (xy 125.486314 -224.956202)
			(xy 125.521554 -224.992654) (xy 125.550797 -225.034071) (xy 125.573352 -225.079478) (xy 125.588688 -225.127804)
			(xy 125.596443 -225.177908) (xy 125.596904 -225.203258) (xy 125.596396 -225.229165) (xy 125.58829 -225.280342)
			(xy 125.572278 -225.329621) (xy 125.548755 -225.375788) (xy 125.518299 -225.417707) (xy 125.481661 -225.454345)
			(xy 125.439742 -225.484801) (xy 125.393575 -225.508324) (xy 125.344296 -225.524336) (xy 125.293119 -225.532442)
			(xy 125.241305 -225.532442) (xy 125.190128 -225.524336) (xy 125.140849 -225.508324) (xy 125.094682 -225.484801)
			(xy 125.052763 -225.454345) (xy 125.016125 -225.417707) (xy 124.985669 -225.375788) (xy 124.962146 -225.329621)
			(xy 124.946134 -225.280342) (xy 124.938028 -225.229165) (xy 124.93752 -225.203258) (xy 124.938127 -225.175541)
			(xy 124.947442 -225.120895) (xy 124.956062 -225.094546) (xy 124.963936 -225.072448) (xy 124.758958 -224.71761)
			(xy 124.736098 -224.713292) (xy 124.711285 -224.708145) (xy 124.663543 -224.691153) (xy 124.618963 -224.667056)
			(xy 124.578596 -224.63642) (xy 124.543393 -224.599968) (xy 124.514182 -224.558558) (xy 124.491652 -224.513166)
			(xy 124.476334 -224.46486) (xy 124.468588 -224.41478) (xy 124.468128 -224.389442) (xy 124.187204 -224.389442)
			(xy 124.186696 -224.415329) (xy 124.178597 -224.466467) (xy 124.162598 -224.515707) (xy 124.139092 -224.561839)
			(xy 124.10866 -224.603726) (xy 124.07205 -224.640336) (xy 124.030163 -224.670768) (xy 123.984031 -224.694274)
			(xy 123.934791 -224.710273) (xy 123.883653 -224.718372) (xy 123.831879 -224.718372) (xy 123.780741 -224.710273)
			(xy 123.731501 -224.694274) (xy 123.685369 -224.670768) (xy 123.643482 -224.640336) (xy 123.606872 -224.603726)
			(xy 123.57644 -224.561839) (xy 123.552934 -224.515707) (xy 123.536935 -224.466467) (xy 123.528836 -224.415329)
			(xy 123.528328 -224.389442) (xy 123.247404 -224.389442) (xy 123.24686 -224.417149) (xy 123.237674 -224.471796)
			(xy 123.229116 -224.498154) (xy 123.221242 -224.520252) (xy 123.42622 -224.87509) (xy 123.44908 -224.879408)
			(xy 123.473909 -224.884542) (xy 123.521688 -224.901501) (xy 123.566308 -224.925578) (xy 123.606714 -224.956202)
			(xy 123.641954 -224.992654) (xy 123.671197 -225.034071) (xy 123.693752 -225.079478) (xy 123.709088 -225.127804)
			(xy 123.716843 -225.177908) (xy 123.717304 -225.203258) (xy 123.716796 -225.229165) (xy 123.70869 -225.280342)
			(xy 123.692678 -225.329621) (xy 123.669155 -225.375788) (xy 123.638699 -225.417707) (xy 123.602061 -225.454345)
			(xy 123.560142 -225.484801) (xy 123.513975 -225.508324) (xy 123.464696 -225.524336) (xy 123.413519 -225.532442)
			(xy 123.361705 -225.532442) (xy 123.310528 -225.524336) (xy 123.261249 -225.508324) (xy 123.215082 -225.484801)
			(xy 123.173163 -225.454345) (xy 123.136525 -225.417707) (xy 123.106069 -225.375788) (xy 123.082546 -225.329621)
			(xy 123.066534 -225.280342) (xy 123.058428 -225.229165) (xy 123.05792 -225.203258) (xy 123.058527 -225.175541)
			(xy 123.067842 -225.120895) (xy 123.076462 -225.094546) (xy 123.084336 -225.072448) (xy 122.879358 -224.71761)
			(xy 122.856498 -224.713292) (xy 122.831685 -224.708145) (xy 122.783943 -224.691153) (xy 122.739363 -224.667056)
			(xy 122.698996 -224.63642) (xy 122.663793 -224.599968) (xy 122.634582 -224.558558) (xy 122.612052 -224.513166)
			(xy 122.596734 -224.46486) (xy 122.588988 -224.41478) (xy 122.588528 -224.389442) (xy 122.307604 -224.389442)
			(xy 122.307096 -224.415329) (xy 122.298997 -224.466467) (xy 122.282998 -224.515707) (xy 122.259492 -224.561839)
			(xy 122.22906 -224.603726) (xy 122.19245 -224.640336) (xy 122.150563 -224.670768) (xy 122.104431 -224.694274)
			(xy 122.055191 -224.710273) (xy 122.004053 -224.718372) (xy 121.952279 -224.718372) (xy 121.901141 -224.710273)
			(xy 121.851901 -224.694274) (xy 121.805769 -224.670768) (xy 121.763882 -224.640336) (xy 121.727272 -224.603726)
			(xy 121.69684 -224.561839) (xy 121.673334 -224.515707) (xy 121.657335 -224.466467) (xy 121.649236 -224.415329)
			(xy 121.648728 -224.389442) (xy 121.367804 -224.389442) (xy 121.36726 -224.417149) (xy 121.358074 -224.471796)
			(xy 121.349516 -224.498154) (xy 121.341642 -224.520252) (xy 121.54662 -224.87509) (xy 121.56948 -224.879408)
			(xy 121.594309 -224.884542) (xy 121.642088 -224.901501) (xy 121.686708 -224.925578) (xy 121.727114 -224.956202)
			(xy 121.762354 -224.992654) (xy 121.791597 -225.034071) (xy 121.814152 -225.079478) (xy 121.829488 -225.127804)
			(xy 121.837243 -225.177908) (xy 121.837704 -225.203258) (xy 121.837196 -225.229165) (xy 121.82909 -225.280342)
			(xy 121.813078 -225.329621) (xy 121.789555 -225.375788) (xy 121.759099 -225.417707) (xy 121.722461 -225.454345)
			(xy 121.680542 -225.484801) (xy 121.634375 -225.508324) (xy 121.585096 -225.524336) (xy 121.533919 -225.532442)
			(xy 121.482105 -225.532442) (xy 121.430928 -225.524336) (xy 121.381649 -225.508324) (xy 121.335482 -225.484801)
			(xy 121.293563 -225.454345) (xy 121.256925 -225.417707) (xy 121.226469 -225.375788) (xy 121.202946 -225.329621)
			(xy 121.186934 -225.280342) (xy 121.178828 -225.229165) (xy 121.17832 -225.203258) (xy 121.178927 -225.175541)
			(xy 121.188242 -225.120895) (xy 121.196862 -225.094546) (xy 121.204736 -225.072448) (xy 120.999758 -224.71761)
			(xy 120.976898 -224.713292) (xy 120.952085 -224.708145) (xy 120.904343 -224.691153) (xy 120.859763 -224.667056)
			(xy 120.819396 -224.63642) (xy 120.784193 -224.599968) (xy 120.754982 -224.558558) (xy 120.732452 -224.513166)
			(xy 120.717134 -224.46486) (xy 120.709388 -224.41478) (xy 120.708928 -224.389442) (xy 120.428004 -224.389442)
			(xy 120.427496 -224.415329) (xy 120.419397 -224.466467) (xy 120.403398 -224.515707) (xy 120.379892 -224.561839)
			(xy 120.34946 -224.603726) (xy 120.31285 -224.640336) (xy 120.270963 -224.670768) (xy 120.224831 -224.694274)
			(xy 120.175591 -224.710273) (xy 120.124453 -224.718372) (xy 120.072679 -224.718372) (xy 120.021541 -224.710273)
			(xy 119.972301 -224.694274) (xy 119.926169 -224.670768) (xy 119.884282 -224.640336) (xy 119.847672 -224.603726)
			(xy 119.81724 -224.561839) (xy 119.793734 -224.515707) (xy 119.777735 -224.466467) (xy 119.769636 -224.415329)
			(xy 119.769128 -224.389442) (xy 119.488204 -224.389442) (xy 119.48766 -224.417149) (xy 119.478474 -224.471796)
			(xy 119.469916 -224.498154) (xy 119.462042 -224.520252) (xy 119.66702 -224.87509) (xy 119.68988 -224.879408)
			(xy 119.714709 -224.884542) (xy 119.762488 -224.901501) (xy 119.807108 -224.925578) (xy 119.847514 -224.956202)
			(xy 119.882754 -224.992654) (xy 119.911997 -225.034071) (xy 119.934552 -225.079478) (xy 119.949888 -225.127804)
			(xy 119.957643 -225.177908) (xy 119.958104 -225.203258) (xy 119.957596 -225.229165) (xy 119.94949 -225.280342)
			(xy 119.933478 -225.329621) (xy 119.909955 -225.375788) (xy 119.879499 -225.417707) (xy 119.842861 -225.454345)
			(xy 119.800942 -225.484801) (xy 119.754775 -225.508324) (xy 119.705496 -225.524336) (xy 119.654319 -225.532442)
			(xy 119.602505 -225.532442) (xy 119.551328 -225.524336) (xy 119.502049 -225.508324) (xy 119.455882 -225.484801)
			(xy 119.413963 -225.454345) (xy 119.377325 -225.417707) (xy 119.346869 -225.375788) (xy 119.323346 -225.329621)
			(xy 119.307334 -225.280342) (xy 119.299228 -225.229165) (xy 119.29872 -225.203258) (xy 119.299327 -225.175541)
			(xy 119.308642 -225.120895) (xy 119.317262 -225.094546) (xy 119.325136 -225.072448) (xy 119.120158 -224.71761)
			(xy 119.097298 -224.713292) (xy 119.072485 -224.708145) (xy 119.024743 -224.691153) (xy 118.980163 -224.667056)
			(xy 118.939796 -224.63642) (xy 118.904593 -224.599968) (xy 118.875382 -224.558558) (xy 118.852852 -224.513166)
			(xy 118.837534 -224.46486) (xy 118.829788 -224.41478) (xy 118.829328 -224.389442) (xy 118.548404 -224.389442)
			(xy 118.547896 -224.415329) (xy 118.539797 -224.466467) (xy 118.523798 -224.515707) (xy 118.500292 -224.561839)
			(xy 118.46986 -224.603726) (xy 118.43325 -224.640336) (xy 118.391363 -224.670768) (xy 118.345231 -224.694274)
			(xy 118.295991 -224.710273) (xy 118.244853 -224.718372) (xy 118.193079 -224.718372) (xy 118.141941 -224.710273)
			(xy 118.092701 -224.694274) (xy 118.046569 -224.670768) (xy 118.004682 -224.640336) (xy 117.968072 -224.603726)
			(xy 117.93764 -224.561839) (xy 117.914134 -224.515707) (xy 117.898135 -224.466467) (xy 117.890036 -224.415329)
			(xy 117.889528 -224.389442) (xy 117.608604 -224.389442) (xy 117.60806 -224.417149) (xy 117.598874 -224.471796)
			(xy 117.590316 -224.498154) (xy 117.582442 -224.520252) (xy 117.78742 -224.87509) (xy 117.81028 -224.879408)
			(xy 117.835109 -224.884542) (xy 117.882888 -224.901501) (xy 117.927508 -224.925578) (xy 117.967914 -224.956202)
			(xy 118.003154 -224.992654) (xy 118.032397 -225.034071) (xy 118.054952 -225.079478) (xy 118.070288 -225.127804)
			(xy 118.078043 -225.177908) (xy 118.078504 -225.203258) (xy 118.077996 -225.229165) (xy 118.06989 -225.280342)
			(xy 118.053878 -225.329621) (xy 118.030355 -225.375788) (xy 117.999899 -225.417707) (xy 117.963261 -225.454345)
			(xy 117.921342 -225.484801) (xy 117.875175 -225.508324) (xy 117.825896 -225.524336) (xy 117.774719 -225.532442)
			(xy 117.722905 -225.532442) (xy 117.671728 -225.524336) (xy 117.622449 -225.508324) (xy 117.576282 -225.484801)
			(xy 117.534363 -225.454345) (xy 117.497725 -225.417707) (xy 117.467269 -225.375788) (xy 117.443746 -225.329621)
			(xy 117.427734 -225.280342) (xy 117.419628 -225.229165) (xy 117.41912 -225.203258) (xy 117.419727 -225.175541)
			(xy 117.429042 -225.120895) (xy 117.437662 -225.094546) (xy 117.445536 -225.072448) (xy 117.240558 -224.71761)
			(xy 117.217698 -224.713292) (xy 117.192885 -224.708145) (xy 117.145143 -224.691153) (xy 117.100563 -224.667056)
			(xy 117.060196 -224.63642) (xy 117.024993 -224.599968) (xy 116.995782 -224.558558) (xy 116.973252 -224.513166)
			(xy 116.957934 -224.46486) (xy 116.950188 -224.41478) (xy 116.949728 -224.389442) (xy 116.668804 -224.389442)
			(xy 116.668296 -224.415329) (xy 116.660197 -224.466467) (xy 116.644198 -224.515707) (xy 116.620692 -224.561839)
			(xy 116.59026 -224.603726) (xy 116.55365 -224.640336) (xy 116.511763 -224.670768) (xy 116.465631 -224.694274)
			(xy 116.416391 -224.710273) (xy 116.365253 -224.718372) (xy 116.313479 -224.718372) (xy 116.262341 -224.710273)
			(xy 116.213101 -224.694274) (xy 116.166969 -224.670768) (xy 116.125082 -224.640336) (xy 116.088472 -224.603726)
			(xy 116.05804 -224.561839) (xy 116.034534 -224.515707) (xy 116.018535 -224.466467) (xy 116.010436 -224.415329)
			(xy 116.009928 -224.389442) (xy 115.729004 -224.389442) (xy 115.728479 -224.417151) (xy 115.719288 -224.471799)
			(xy 115.710716 -224.498154) (xy 115.702842 -224.520252) (xy 115.90782 -224.87509) (xy 115.93068 -224.879408)
			(xy 115.955492 -224.884596) (xy 116.003256 -224.901569) (xy 116.04786 -224.925651) (xy 116.088254 -224.956274)
			(xy 116.123486 -224.992717) (xy 116.152728 -225.034123) (xy 116.175289 -225.079514) (xy 116.19064 -225.127824)
			(xy 116.198417 -225.177913) (xy 116.198904 -225.203258) (xy 116.198425 -225.229161) (xy 116.190322 -225.28033)
			(xy 116.174309 -225.3296) (xy 116.150782 -225.375756) (xy 116.120319 -225.41766) (xy 116.083673 -225.454279)
			(xy 116.041746 -225.48471) (xy 115.995572 -225.508204) (xy 115.946291 -225.524179) (xy 115.895116 -225.532244)
			(xy 115.869212 -225.532696) (xy 115.839194 -225.532037) (xy 115.78015 -225.521175) (xy 115.751864 -225.511106)
			(xy 115.738542 -225.506487) (xy 115.710468 -225.503979) (xy 115.682777 -225.509238) (xy 115.657578 -225.521865)
			(xy 115.636789 -225.540898) (xy 115.621993 -225.564888) (xy 115.614317 -225.592009) (xy 115.613942 -225.606102)
			(xy 115.613942 -225.768916) (xy 115.633023 -225.786035) (xy 115.666151 -225.825153) (xy 115.692792 -225.868947)
			(xy 115.712297 -225.916352) (xy 115.724192 -225.966214) (xy 115.728188 -226.017318) (xy 115.724187 -226.068423)
			(xy 115.712286 -226.118283) (xy 115.692775 -226.165685) (xy 115.66613 -226.209477) (xy 115.632998 -226.248591)
			(xy 115.613942 -226.26574) (xy 115.613942 -227.396548) (xy 115.634908 -227.415416) (xy 115.67068 -227.45902)
			(xy 115.698478 -227.508093) (xy 115.717485 -227.561194) (xy 115.727143 -227.61676) (xy 115.727734 -227.64496)
			(xy 115.727572 -227.659001) (xy 115.725152 -227.686978) (xy 115.722908 -227.70084) (xy 115.718336 -227.726748)
			(xy 117.749574 -229.757986) (xy 117.768624 -229.759002) (xy 117.795002 -229.761131) (xy 117.846625 -229.772757)
			(xy 117.895715 -229.792513) (xy 117.941001 -229.819888) (xy 117.981309 -229.854172) (xy 118.015596 -229.894477)
			(xy 118.042974 -229.93976) (xy 118.062735 -229.988849) (xy 118.074365 -230.040471) (xy 118.076472 -230.06685)
			(xy 118.077488 -230.0859) (xy 119.43715 -231.445562) (xy 119.470678 -231.42702) (xy 119.495077 -231.414245)
			(xy 119.547085 -231.396134) (xy 119.601385 -231.386952) (xy 119.62892 -231.38638) (xy 119.654707 -231.386861)
			(xy 119.705646 -231.394933) (xy 119.754695 -231.410874) (xy 119.800646 -231.434292) (xy 119.842368 -231.464611)
			(xy 119.878833 -231.501084) (xy 119.909143 -231.542812) (xy 119.932552 -231.588768) (xy 119.948483 -231.63782)
			(xy 119.956544 -231.688761) (xy 119.957088 -231.714548) (xy 119.956531 -231.742085) (xy 119.947353 -231.796389)
			(xy 119.929243 -231.8484) (xy 119.916448 -231.87279) (xy 119.897906 -231.906318) (xy 120.21185 -232.220262)
			(xy 120.221502 -232.224072) (xy 120.245708 -232.234434) (xy 120.290732 -232.261726) (xy 120.330824 -232.295854)
			(xy 120.364956 -232.335942) (xy 120.392252 -232.380964) (xy 120.402604 -232.405174) (xy 120.406414 -232.414826)
			(xy 121.845832 -233.854244) (xy 121.87555 -233.844592) (xy 121.900501 -233.836883) (xy 121.952056 -233.828582)
			(xy 121.978166 -233.828082) (xy 122.003956 -233.828559) (xy 122.054901 -233.836624) (xy 122.103957 -233.852561)
			(xy 122.149916 -233.875976) (xy 122.191645 -233.906294) (xy 122.228116 -233.942767) (xy 122.258432 -233.984498)
			(xy 122.281846 -234.030457) (xy 122.29778 -234.079514) (xy 122.305842 -234.13046) (xy 122.306334 -234.15625)
			(xy 122.305807 -234.182358) (xy 122.297513 -234.233911) (xy 122.289824 -234.258866) (xy 122.280172 -234.288584)
			(xy 124.266198 -236.27461) (xy 124.290582 -236.271816) (xy 124.299759 -236.27085) (xy 124.318185 -236.269836)
			(xy 124.327412 -236.269784) (xy 124.3532 -236.270291) (xy 124.404142 -236.27836) (xy 124.453194 -236.294298)
			(xy 124.49915 -236.317712) (xy 124.540877 -236.348027) (xy 124.57735 -236.384495) (xy 124.607669 -236.426219)
			(xy 124.631088 -236.472172) (xy 124.647032 -236.521223) (xy 124.655107 -236.572164) (xy 124.65558 -236.597952)
			(xy 124.65552 -236.607179) (xy 124.654503 -236.625604) (xy 124.653548 -236.634782) (xy 124.650754 -236.659166)
			(xy 125.98019 -237.988602) (xy 125.998642 -237.971598) (xy 126.039743 -237.942819) (xy 126.084741 -237.920623)
			(xy 126.13259 -237.905526) (xy 126.182179 -237.897878) (xy 126.207266 -237.897416) (xy 126.233058 -237.897893)
			(xy 126.284007 -237.905957) (xy 126.333068 -237.921893) (xy 126.379031 -237.945307) (xy 126.420766 -237.975624)
			(xy 126.457243 -238.012096) (xy 126.487566 -238.053826) (xy 126.510988 -238.099786) (xy 126.526931 -238.148844)
			(xy 126.535003 -238.199792) (xy 126.535434 -238.225584) (xy 126.534942 -238.251553) (xy 126.526768 -238.302844)
			(xy 126.51062 -238.352208) (xy 126.486903 -238.398414) (xy 126.471934 -238.41964) (xy 126.44628 -238.454692)
			(xy 126.703328 -238.71174) (xy 126.720346 -238.714026) (xy 126.746871 -238.718082) (xy 126.798206 -238.733693)
			(xy 126.846318 -238.757445) (xy 126.889926 -238.788707) (xy 126.927868 -238.826645) (xy 126.959135 -238.870249)
			(xy 126.982893 -238.918359) (xy 126.99851 -238.969692) (xy 127.00254 -238.99622) (xy 127.004826 -239.013238)
			(xy 127.422656 -239.431068) (xy 127.439913 -239.44911) (xy 127.467665 -239.490605) (xy 127.486773 -239.536723)
			(xy 127.4965 -239.585686) (xy 127.497078 -239.610646) (xy 127.497078 -254.510032) (xy 127.513517 -254.528344)
			(xy 127.541284 -254.568972) (xy 127.562674 -254.613289) (xy 127.577208 -254.660303) (xy 127.58456 -254.70896)
			(xy 127.584565 -254.75817) (xy 127.577223 -254.806828) (xy 127.562699 -254.853845) (xy 127.541319 -254.898167)
			(xy 127.513561 -254.938801) (xy 127.497078 -254.957072) (xy 127.497078 -256.137918) (xy 127.513511 -256.15623)
			(xy 127.541265 -256.196856) (xy 127.562642 -256.241169) (xy 127.577165 -256.288178) (xy 127.584506 -256.336827)
			(xy 127.584502 -256.386028) (xy 127.577152 -256.434677) (xy 127.562622 -256.481683) (xy 127.541237 -256.525993)
			(xy 127.513476 -256.566613) (xy 127.497078 -256.584958) (xy 127.497078 -257.765296) (xy 127.513555 -257.783619)
			(xy 127.54139 -257.82428) (xy 127.562833 -257.868646) (xy 127.577403 -257.915718) (xy 127.584773 -257.96444)
			(xy 127.584776 -258.013716) (xy 127.577413 -258.062439) (xy 127.562849 -258.109513) (xy 127.541412 -258.153882)
			(xy 127.513583 -258.194547) (xy 127.497078 -258.212844) (xy 127.497078 -259.393436) (xy 127.513517 -259.411748)
			(xy 127.541283 -259.452376) (xy 127.562672 -259.496693) (xy 127.577206 -259.543707) (xy 127.584557 -259.592363)
			(xy 127.584562 -259.641572) (xy 127.57722 -259.69023) (xy 127.562696 -259.737247) (xy 127.541315 -259.781569)
			(xy 127.513557 -259.822201) (xy 127.497078 -259.840476) (xy 127.497078 -261.021322) (xy 127.513511 -261.039635)
			(xy 127.541265 -261.080262) (xy 127.562643 -261.124578) (xy 127.577164 -261.171589) (xy 127.584504 -261.220241)
			(xy 127.584962 -261.244842) (xy 127.584453 -261.270627) (xy 127.57638 -261.321562) (xy 127.560438 -261.370607)
			(xy 127.537021 -261.416554) (xy 127.506705 -261.458273) (xy 127.470237 -261.494737) (xy 127.428513 -261.525047)
			(xy 127.382562 -261.548457) (xy 127.333515 -261.564391) (xy 127.282579 -261.572457) (xy 127.256794 -261.57301)
			(xy 127.23273 -261.572587) (xy 127.185118 -261.565553) (xy 127.139045 -261.551637) (xy 127.117094 -261.541768)
			(xy 127.084836 -261.526528) (xy 126.388876 -262.222488) (xy 126.370837 -262.239752) (xy 126.329345 -262.267519)
			(xy 126.283227 -262.28664) (xy 126.234261 -262.296379) (xy 126.209298 -262.29691) (xy 126.072646 -262.29691)
			(xy 126.054266 -262.313693) (xy 126.013381 -262.342076) (xy 125.968676 -262.363954) (xy 125.921179 -262.378825)
			(xy 125.87198 -262.386347) (xy 125.822208 -262.386347) (xy 125.773009 -262.378825) (xy 125.725512 -262.363954)
			(xy 125.680807 -262.342076) (xy 125.639922 -262.313693) (xy 125.621542 -262.29691) (xy 125.1331 -262.29691)
			(xy 125.11472 -262.313693) (xy 125.073835 -262.342076) (xy 125.02913 -262.363954) (xy 124.981633 -262.378825)
			(xy 124.932434 -262.386347) (xy 124.882662 -262.386347) (xy 124.833463 -262.378825) (xy 124.785966 -262.363954)
			(xy 124.741261 -262.342076) (xy 124.700376 -262.313693) (xy 124.681996 -262.29691) (xy 124.1933 -262.29691)
			(xy 124.17492 -262.313693) (xy 124.134035 -262.342076) (xy 124.08933 -262.363954) (xy 124.041833 -262.378825)
			(xy 123.992634 -262.386347) (xy 123.942862 -262.386347) (xy 123.893663 -262.378825) (xy 123.846166 -262.363954)
			(xy 123.801461 -262.342076) (xy 123.760576 -262.313693) (xy 123.742196 -262.29691) (xy 123.253246 -262.29691)
			(xy 123.234866 -262.313693) (xy 123.193981 -262.342076) (xy 123.149276 -262.363954) (xy 123.101779 -262.378825)
			(xy 123.05258 -262.386347) (xy 123.002808 -262.386347) (xy 122.953609 -262.378825) (xy 122.906112 -262.363954)
			(xy 122.861407 -262.342076) (xy 122.820522 -262.313693) (xy 122.802142 -262.29691) (xy 122.3137 -262.29691)
			(xy 122.295318 -262.313691) (xy 122.254432 -262.342071) (xy 122.209728 -262.363948) (xy 122.162231 -262.37882)
			(xy 122.113033 -262.386347) (xy 122.088148 -262.386826) (xy 122.062995 -262.386341) (xy 122.01328 -262.378657)
			(xy 121.965319 -262.363477) (xy 121.920236 -262.341156) (xy 121.879087 -262.312217) (xy 121.842836 -262.277338)
			(xy 121.812332 -262.237336) (xy 121.788289 -262.193148) (xy 121.779284 -262.169656) (xy 121.76382 -262.168409)
			(xy 121.734151 -262.159372) (xy 121.707537 -262.143445) (xy 121.696226 -262.132826) (xy 121.606564 -262.043164)
			(xy 121.60631 -262.043164) (xy 121.354088 -261.790942) (xy 121.354088 -261.582408) (xy 121.330838 -261.563572)
			(xy 121.289282 -261.520521) (xy 121.25412 -261.472107) (xy 121.226035 -261.419272) (xy 121.205573 -261.363044)
			(xy 121.193134 -261.304516) (xy 121.188958 -261.244826) (xy 121.193127 -261.185136) (xy 121.205559 -261.126606)
			(xy 121.226014 -261.070375) (xy 121.254092 -261.017537) (xy 121.289249 -260.969119) (xy 121.3308 -260.926063)
			(xy 121.354088 -260.907276) (xy 121.354088 -260.520688) (xy 121.190004 -260.356858) (xy 120.84812 -260.698488)
			(xy 120.830079 -260.715748) (xy 120.788586 -260.743505) (xy 120.742468 -260.762616) (xy 120.693503 -260.772344)
			(xy 120.668542 -260.77291) (xy 118.966996 -260.77291) (xy 118.788942 -260.950964) (xy 118.788942 -263.04494)
			(xy 118.822724 -263.056878) (xy 118.846313 -263.065778) (xy 118.890653 -263.089774) (xy 118.930801 -263.120269)
			(xy 118.965813 -263.156544) (xy 118.994866 -263.197748) (xy 119.017275 -263.24291) (xy 119.032514 -263.290968)
			(xy 119.040225 -263.340791) (xy 119.040225 -263.391207) (xy 119.032515 -263.44103) (xy 119.017276 -263.489088)
			(xy 118.994867 -263.53425) (xy 118.965815 -263.575454) (xy 118.930803 -263.61173) (xy 118.890655 -263.642225)
			(xy 118.846316 -263.666221) (xy 118.822724 -263.675114) (xy 118.788942 -263.687052) (xy 118.788942 -270.016732)
			(xy 119.47652 -270.70431) (xy 119.622316 -270.70431)
		)
		(stroke
			(width 0)
			(type solid)
		)
		(fill yes)
		(layer "In9.Cu")
		(net "PVCCINFAON_CPU1")
	)
	(gr_poly
		(pts
			(xy 296.131996 -133.722618) (xy 296.141442 -133.696922) (xy 296.167119 -133.648571) (xy 296.199935 -133.604751)
			(xy 296.239108 -133.566507) (xy 296.283702 -133.534751) (xy 296.332655 -133.51024) (xy 296.384798 -133.493561)
			(xy 296.438887 -133.485109) (xy 296.46626 -133.48462) (xy 296.493576 -133.485127) (xy 296.547558 -133.493531)
			(xy 296.599603 -133.510145) (xy 296.648469 -133.534573) (xy 296.692993 -133.566232) (xy 296.712894 -133.58495)
			(xy 296.724569 -133.595489) (xy 296.752698 -133.609523) (xy 296.78376 -133.614352) (xy 296.814822 -133.609523)
			(xy 296.842951 -133.595489) (xy 296.854626 -133.58495) (xy 296.874538 -133.566243) (xy 296.919057 -133.534575)
			(xy 296.96792 -133.510138) (xy 297.019962 -133.493513) (xy 297.073943 -133.485097) (xy 297.10126 -133.48462)
			(xy 297.128634 -133.485129) (xy 297.18273 -133.49356) (xy 297.23488 -133.510225) (xy 297.283839 -133.534728)
			(xy 297.328438 -133.566482) (xy 297.367611 -133.60473) (xy 297.400422 -133.648557) (xy 297.426088 -133.696916)
			(xy 297.435524 -133.722618) (xy 297.447462 -133.756908) (xy 297.663108 -133.756908) (xy 297.686412 -133.742343)
			(xy 297.736319 -133.719339) (xy 297.789014 -133.703746) (xy 297.843403 -133.695889) (xy 297.87088 -133.69544)
			(xy 297.898354 -133.695922) (xy 297.952735 -133.703801) (xy 298.005427 -133.719386) (xy 298.055345 -133.742354)
			(xy 298.078652 -133.756908) (xy 333.803244 -133.756908) (xy 364.300262 -103.25989) (xy 364.318303 -103.24263)
			(xy 364.359796 -103.214872) (xy 364.405914 -103.19576) (xy 364.454879 -103.186029) (xy 364.47984 -103.185468)
			(xy 367.862866 -103.185468) (xy 367.884104 -103.166614) (xy 367.931118 -103.134758) (xy 367.982337 -103.110229)
			(xy 368.036628 -103.093567) (xy 368.092789 -103.085144) (xy 368.149579 -103.085144) (xy 368.20574 -103.093567)
			(xy 368.260031 -103.110229) (xy 368.31125 -103.134758) (xy 368.358264 -103.166614) (xy 368.379502 -103.185468)
			(xy 371.292374 -103.185468) (xy 371.301772 -103.146606) (xy 371.308974 -103.119314) (xy 371.33032 -103.067064)
			(xy 371.359131 -103.018529) (xy 371.394779 -102.974768) (xy 371.436485 -102.936737) (xy 371.483339 -102.905265)
			(xy 371.534318 -102.88104) (xy 371.58831 -102.86459) (xy 371.644137 -102.856274) (xy 371.700579 -102.856274)
			(xy 371.756406 -102.86459) (xy 371.810398 -102.88104) (xy 371.861377 -102.905265) (xy 371.908231 -102.936737)
			(xy 371.949937 -102.974768) (xy 371.985585 -103.018529) (xy 372.014396 -103.067064) (xy 372.035742 -103.119314)
			(xy 372.042944 -103.146606) (xy 372.052342 -103.185468) (xy 373.242332 -103.185468) (xy 373.25173 -103.146606)
			(xy 373.258932 -103.119314) (xy 373.280278 -103.067064) (xy 373.309089 -103.018529) (xy 373.344737 -102.974768)
			(xy 373.386443 -102.936737) (xy 373.433297 -102.905265) (xy 373.484276 -102.88104) (xy 373.538268 -102.86459)
			(xy 373.594095 -102.856274) (xy 373.650537 -102.856274) (xy 373.706364 -102.86459) (xy 373.760356 -102.88104)
			(xy 373.811335 -102.905265) (xy 373.858189 -102.936737) (xy 373.899895 -102.974768) (xy 373.935543 -103.018529)
			(xy 373.964354 -103.067064) (xy 373.9857 -103.119314) (xy 373.992902 -103.146606) (xy 374.0023 -103.185468)
			(xy 378.32538 -103.185468) (xy 378.344777 -103.16916) (xy 378.38736 -103.141684) (xy 378.433429 -103.12057)
			(xy 378.48204 -103.106249) (xy 378.532198 -103.099014) (xy 378.582874 -103.099014) (xy 378.633032 -103.106249)
			(xy 378.681643 -103.12057) (xy 378.727712 -103.141684) (xy 378.770295 -103.16916) (xy 378.789692 -103.185468)
			(xy 381.743204 -103.185468) (xy 390.62914 -94.299532) (xy 390.62914 -78.151228) (xy 390.629718 -78.126271)
			(xy 390.63947 -78.077318) (xy 390.658586 -78.031208) (xy 390.68633 -77.989713) (xy 390.703562 -77.97165)
			(xy 396.512542 -72.16267) (xy 396.530583 -72.145409) (xy 396.572076 -72.11765) (xy 396.618194 -72.098536)
			(xy 396.667159 -72.088803) (xy 396.69212 -72.088248) (xy 421.29456 -72.088248) (xy 421.29456 -66.06794)
			(xy 421.295065 -65.962416) (xy 421.303149 -65.751522) (xy 421.319305 -65.541093) (xy 421.343508 -65.331436)
			(xy 421.375725 -65.122861) (xy 421.415907 -64.915673) (xy 421.463995 -64.710176) (xy 421.519919 -64.506672)
			(xy 421.583596 -64.305459) (xy 421.654934 -64.106832) (xy 421.733828 -63.911084) (xy 421.820161 -63.718502)
			(xy 421.913808 -63.529367) (xy 422.01463 -63.343958) (xy 422.12248 -63.162547) (xy 422.237199 -62.9854)
			(xy 422.358619 -62.812778) (xy 422.486562 -62.644932) (xy 422.62084 -62.48211) (xy 422.761256 -62.324551)
			(xy 422.907604 -62.172486) (xy 423.059669 -62.026138) (xy 423.217228 -61.885722) (xy 423.38005 -61.751444)
			(xy 423.547896 -61.623501) (xy 423.720518 -61.502081) (xy 423.897665 -61.387362) (xy 424.079076 -61.279512)
			(xy 424.264485 -61.17869) (xy 424.45362 -61.085043) (xy 424.646202 -60.99871) (xy 424.84195 -60.919816)
			(xy 425.040577 -60.848478) (xy 425.24179 -60.784801) (xy 425.445294 -60.728877) (xy 425.650791 -60.680789)
			(xy 425.857979 -60.640607) (xy 426.066554 -60.60839) (xy 426.276211 -60.584187) (xy 426.48664 -60.568031)
			(xy 426.697534 -60.559947) (xy 426.908582 -60.559947) (xy 427.119476 -60.568031) (xy 427.329905 -60.584187)
			(xy 427.539562 -60.60839) (xy 427.748137 -60.640607) (xy 427.955325 -60.680789) (xy 428.160822 -60.728877)
			(xy 428.364326 -60.784801) (xy 428.565539 -60.848478) (xy 428.764166 -60.919816) (xy 428.959914 -60.99871)
			(xy 429.152496 -61.085043) (xy 429.341631 -61.17869) (xy 429.52704 -61.279512) (xy 429.708451 -61.387362)
			(xy 429.885598 -61.502081) (xy 430.05822 -61.623501) (xy 430.226066 -61.751444) (xy 430.388888 -61.885722)
			(xy 430.546447 -62.026138) (xy 430.698512 -62.172486) (xy 430.84486 -62.324551) (xy 430.985276 -62.48211)
			(xy 431.119554 -62.644932) (xy 431.247497 -62.812778) (xy 431.368917 -62.9854) (xy 431.483636 -63.162547)
			(xy 431.591486 -63.343958) (xy 431.692308 -63.529367) (xy 431.785955 -63.718502) (xy 431.872288 -63.911084)
			(xy 431.951182 -64.106832) (xy 432.02252 -64.305459) (xy 432.086197 -64.506672) (xy 432.142121 -64.710176)
			(xy 432.190209 -64.915673) (xy 432.230391 -65.122861) (xy 432.262608 -65.331436) (xy 432.286811 -65.541093)
			(xy 432.302967 -65.751522) (xy 432.311051 -65.962416) (xy 432.311556 -66.06794) (xy 432.311556 -72.088248)
			(xy 446.006474 -72.088248) (xy 446.01384 -72.046338) (xy 446.018968 -72.020223) (xy 446.035505 -71.969639)
			(xy 446.058915 -71.921845) (xy 446.088742 -71.87777) (xy 446.124408 -71.83827) (xy 446.165218 -71.804113)
			(xy 446.210382 -71.775961) (xy 446.259021 -71.754362) (xy 446.31019 -71.739735) (xy 446.362896 -71.732364)
			(xy 446.389506 -71.731886) (xy 446.417184 -71.732381) (xy 446.471956 -71.740388) (xy 446.524995 -71.756233)
			(xy 446.575185 -71.779582) (xy 446.62147 -71.809945) (xy 446.662877 -71.846682) (xy 446.681098 -71.867522)
			(xy 446.691282 -71.878741) (xy 446.716727 -71.895164) (xy 446.745863 -71.903422) (xy 446.776141 -71.902794)
			(xy 446.804909 -71.893333) (xy 446.82965 -71.875868) (xy 446.83934 -71.86422) (xy 446.857509 -71.841569)
			(xy 446.899546 -71.801514) (xy 446.947169 -71.768294) (xy 446.999278 -71.742679) (xy 447.054669 -71.72526)
			(xy 447.11206 -71.71644) (xy 447.141092 -71.715884) (xy 447.169951 -71.716421) (xy 447.227008 -71.725129)
			(xy 447.282102 -71.742332) (xy 447.333976 -71.767637) (xy 447.381447 -71.800468) (xy 447.423431 -71.840075)
			(xy 447.458969 -71.885554) (xy 447.473578 -71.910448) (xy 447.480606 -71.922093) (xy 447.4997 -71.94145)
			(xy 447.52323 -71.955072) (xy 447.549524 -71.961993) (xy 447.576712 -71.961719) (xy 447.602861 -71.95427)
			(xy 447.626112 -71.940176) (xy 447.644812 -71.920439) (xy 447.651632 -71.90867) (xy 447.666041 -71.883073)
			(xy 447.701499 -71.836245) (xy 447.743712 -71.795401) (xy 447.791683 -71.761504) (xy 447.844279 -71.735355)
			(xy 447.90026 -71.71757) (xy 447.958305 -71.708569) (xy 447.987674 -71.70801) (xy 448.015347 -71.708502)
			(xy 448.070112 -71.716496) (xy 448.123147 -71.732319) (xy 448.173338 -71.75564) (xy 448.219634 -71.785969)
			(xy 448.26106 -71.82267) (xy 448.296749 -71.864972) (xy 448.32595 -71.911987) (xy 448.348051 -71.962727)
			(xy 448.362588 -72.01613) (xy 448.366388 -72.043544) (xy 448.371722 -72.088248) (xy 450.861684 -72.088248)
			(xy 452.12254 -70.827392) (xy 452.12254 -45.486066) (xy 452.08698 -45.47489) (xy 452.060008 -45.465869)
			(xy 452.008879 -45.440962) (xy 451.962015 -45.408741) (xy 451.920453 -45.36992) (xy 451.885114 -45.325359)
			(xy 451.856782 -45.276047) (xy 451.836083 -45.223075) (xy 451.823478 -45.167617) (xy 451.819245 -45.110902)
			(xy 451.823477 -45.054188) (xy 451.836082 -44.99873) (xy 451.85678 -44.945758) (xy 451.885111 -44.896445)
			(xy 451.92045 -44.851884) (xy 451.962011 -44.813062) (xy 452.008875 -44.780841) (xy 452.060003 -44.755933)
			(xy 452.08698 -44.746926) (xy 452.12254 -44.73575) (xy 452.12254 -41.228264) (xy 448.047364 -37.153088)
			(xy 430.0601 -37.153088) (xy 430.051464 -37.192966) (xy 430.041964 -37.234056) (xy 430.016309 -37.314402)
			(xy 429.983267 -37.392004) (xy 429.943127 -37.466183) (xy 429.89624 -37.536292) (xy 429.843015 -37.601719)
			(xy 429.783916 -37.661894) (xy 429.719459 -37.716291) (xy 429.650207 -37.764435) (xy 429.576764 -37.805905)
			(xy 429.499771 -37.840341) (xy 429.419901 -37.867441) (xy 429.33785 -37.886969) (xy 429.254335 -37.898755)
			(xy 429.170084 -37.902695) (xy 429.085833 -37.898755) (xy 429.002318 -37.886969) (xy 428.920267 -37.867441)
			(xy 428.840397 -37.840341) (xy 428.763404 -37.805905) (xy 428.689961 -37.764435) (xy 428.620709 -37.716291)
			(xy 428.556252 -37.661894) (xy 428.497153 -37.601719) (xy 428.443928 -37.536292) (xy 428.397041 -37.466183)
			(xy 428.356901 -37.392004) (xy 428.323859 -37.314402) (xy 428.298204 -37.234056) (xy 428.288704 -37.192966)
			(xy 428.280068 -37.153088) (xy 427.5201 -37.153088) (xy 427.511464 -37.192966) (xy 427.501964 -37.234056)
			(xy 427.476309 -37.314402) (xy 427.443267 -37.392004) (xy 427.403127 -37.466183) (xy 427.35624 -37.536292)
			(xy 427.303015 -37.601719) (xy 427.243916 -37.661894) (xy 427.179459 -37.716291) (xy 427.110207 -37.764435)
			(xy 427.036764 -37.805905) (xy 426.959771 -37.840341) (xy 426.879901 -37.867441) (xy 426.79785 -37.886969)
			(xy 426.714335 -37.898755) (xy 426.630084 -37.902695) (xy 426.545833 -37.898755) (xy 426.462318 -37.886969)
			(xy 426.380267 -37.867441) (xy 426.300397 -37.840341) (xy 426.223404 -37.805905) (xy 426.149961 -37.764435)
			(xy 426.080709 -37.716291) (xy 426.016252 -37.661894) (xy 425.957153 -37.601719) (xy 425.903928 -37.536292)
			(xy 425.857041 -37.466183) (xy 425.816901 -37.392004) (xy 425.783859 -37.314402) (xy 425.758204 -37.234056)
			(xy 425.748704 -37.192966) (xy 425.740068 -37.153088) (xy 388.008876 -37.153088) (xy 388.002526 -37.196522)
			(xy 387.998101 -37.223359) (xy 387.982644 -37.275506) (xy 387.959936 -37.324929) (xy 387.930439 -37.370626)
			(xy 387.894751 -37.411669) (xy 387.853594 -37.447228) (xy 387.807805 -37.476581) (xy 387.758311 -37.499133)
			(xy 387.706115 -37.514427) (xy 387.652277 -37.522152) (xy 387.597887 -37.522152) (xy 387.544049 -37.514427)
			(xy 387.491853 -37.499133) (xy 387.442359 -37.476581) (xy 387.39657 -37.447228) (xy 387.355413 -37.411669)
			(xy 387.319725 -37.370626) (xy 387.290228 -37.324929) (xy 387.26752 -37.275506) (xy 387.252063 -37.223359)
			(xy 387.247638 -37.196522) (xy 387.241288 -37.153088) (xy 386.18668 -37.153088) (xy 386.16172 -37.152515)
			(xy 386.112761 -37.142772) (xy 386.066643 -37.123665) (xy 386.025139 -37.095928) (xy 386.007102 -37.078666)
			(xy 372.939564 -24.011128) (xy 354.18649 -24.011128) (xy 354.172598 -24.032795) (xy 354.139533 -24.072239)
			(xy 354.101098 -24.106471) (xy 354.058105 -24.134767) (xy 354.011464 -24.15653) (xy 353.962159 -24.1713)
			(xy 353.911234 -24.178763) (xy 353.859766 -24.178763) (xy 353.808841 -24.1713) (xy 353.759536 -24.15653)
			(xy 353.712895 -24.134767) (xy 353.669902 -24.106471) (xy 353.631467 -24.072239) (xy 353.598402 -24.032795)
			(xy 353.58451 -24.011128) (xy 336.364326 -24.011128) (xy 336.352388 -24.045418) (xy 336.342943 -24.071112)
			(xy 336.317267 -24.119458) (xy 336.28445 -24.163272) (xy 336.245276 -24.201507) (xy 336.20068 -24.233252)
			(xy 336.151725 -24.257749) (xy 336.099582 -24.274412) (xy 336.045495 -24.282844) (xy 335.990753 -24.282844)
			(xy 335.936666 -24.274412) (xy 335.884523 -24.257749) (xy 335.835568 -24.233252) (xy 335.790972 -24.201507)
			(xy 335.751798 -24.163272) (xy 335.718981 -24.119458) (xy 335.693305 -24.071112) (xy 335.68386 -24.045418)
			(xy 335.671922 -24.011128) (xy 334.114394 -24.011128) (xy 334.101482 -24.036529) (xy 334.069265 -24.083525)
			(xy 334.030419 -24.12521) (xy 333.985809 -24.160657) (xy 333.936425 -24.189078) (xy 333.883364 -24.209843)
			(xy 333.827806 -24.222489) (xy 333.770986 -24.226736) (xy 333.714166 -24.222489) (xy 333.658608 -24.209843)
			(xy 333.605547 -24.189078) (xy 333.556163 -24.160657) (xy 333.511553 -24.12521) (xy 333.472707 -24.083525)
			(xy 333.44049 -24.036529) (xy 333.427578 -24.011128) (xy 328.454766 -24.011128) (xy 328.450448 -24.01189)
			(xy 328.435824 -24.014172) (xy 328.406321 -24.016589) (xy 328.39152 -24.016716) (xy 328.376719 -24.016598)
			(xy 328.347215 -24.014182) (xy 328.332592 -24.01189) (xy 328.328274 -24.011128) (xy 287.480756 -24.011128)
			(xy 283.041852 -28.450032) (xy 354.840804 -28.450032) (xy 354.844787 -28.322014) (xy 354.856722 -28.194492)
			(xy 354.876561 -28.067958) (xy 354.904228 -27.942902) (xy 354.939617 -27.819809) (xy 354.98259 -27.699153)
			(xy 355.032981 -27.581403) (xy 355.090595 -27.467013) (xy 355.155209 -27.356426) (xy 355.226573 -27.25007)
			(xy 355.304411 -27.148357) (xy 355.388422 -27.051679) (xy 355.478281 -26.960412) (xy 355.57364 -26.874907)
			(xy 355.674131 -26.795497) (xy 355.779364 -26.722487) (xy 355.888933 -26.656161) (xy 356.002413 -26.596775)
			(xy 356.119365 -26.544559) (xy 356.239338 -26.499715) (xy 356.361866 -26.462417) (xy 356.486477 -26.432808)
			(xy 356.612686 -26.411003) (xy 356.740008 -26.397087) (xy 356.867948 -26.391113) (xy 356.996012 -26.393105)
			(xy 357.123705 -26.403055) (xy 357.250532 -26.420924) (xy 357.376003 -26.446643) (xy 357.499632 -26.480113)
			(xy 357.620941 -26.521204) (xy 357.739461 -26.569758) (xy 357.854733 -26.625586) (xy 357.966311 -26.688472)
			(xy 358.073764 -26.758174) (xy 358.176676 -26.834421) (xy 358.274648 -26.916918) (xy 358.367302 -27.005347)
			(xy 358.454279 -27.099365) (xy 358.535243 -27.198608) (xy 358.60988 -27.302693) (xy 358.677902 -27.411217)
			(xy 358.739046 -27.52376) (xy 358.793074 -27.639886) (xy 358.839779 -27.759147) (xy 358.878979 -27.88108)
			(xy 358.910522 -28.005215) (xy 358.934287 -28.131071) (xy 358.950181 -28.25816) (xy 358.958144 -28.385992)
			(xy 358.958642 -28.450032) (xy 358.958144 -28.514072) (xy 358.950181 -28.641904) (xy 358.934287 -28.768993)
			(xy 358.910522 -28.894849) (xy 358.878979 -29.018984) (xy 358.839779 -29.140917) (xy 358.793074 -29.260178)
			(xy 358.739046 -29.376304) (xy 358.677902 -29.488847) (xy 358.60988 -29.597371) (xy 358.535243 -29.701456)
			(xy 358.454279 -29.800699) (xy 358.367302 -29.894717) (xy 358.274648 -29.983146) (xy 358.176676 -30.065643)
			(xy 358.073764 -30.14189) (xy 357.966311 -30.211592) (xy 357.854733 -30.274478) (xy 357.739461 -30.330306)
			(xy 357.620941 -30.37886) (xy 357.499632 -30.419951) (xy 357.376003 -30.453421) (xy 357.250532 -30.47914)
			(xy 357.123705 -30.497009) (xy 356.996012 -30.506959) (xy 356.867948 -30.508951) (xy 356.740008 -30.502977)
			(xy 356.612686 -30.489061) (xy 356.486477 -30.467256) (xy 356.361866 -30.437647) (xy 356.239338 -30.400349)
			(xy 356.119365 -30.355505) (xy 356.002413 -30.303289) (xy 355.888933 -30.243903) (xy 355.779364 -30.177577)
			(xy 355.674131 -30.104567) (xy 355.57364 -30.025157) (xy 355.478281 -29.939652) (xy 355.388422 -29.848385)
			(xy 355.304411 -29.751707) (xy 355.226573 -29.649994) (xy 355.155209 -29.543638) (xy 355.090595 -29.433051)
			(xy 355.032981 -29.318661) (xy 354.98259 -29.200911) (xy 354.939617 -29.080255) (xy 354.904228 -28.957162)
			(xy 354.876561 -28.832106) (xy 354.856722 -28.705572) (xy 354.844787 -28.57805) (xy 354.840804 -28.450032)
			(xy 283.041852 -28.450032) (xy 276.224131 -35.267753) (xy 356.989346 -35.267753) (xy 356.989346 -35.213247)
			(xy 356.997102 -35.159297) (xy 357.012458 -35.106999) (xy 357.035099 -35.057419) (xy 357.064566 -35.011566)
			(xy 357.100259 -34.970373) (xy 357.14145 -34.934678) (xy 357.187302 -34.905209) (xy 357.236881 -34.882565)
			(xy 357.289177 -34.867207) (xy 357.343127 -34.859447) (xy 357.37038 -34.85896) (xy 358.23398 -34.85896)
			(xy 358.261232 -34.859486) (xy 358.31518 -34.86724) (xy 358.367476 -34.882593) (xy 358.417054 -34.905232)
			(xy 358.462906 -34.934697) (xy 358.504098 -34.970388) (xy 358.539791 -35.011578) (xy 358.569258 -35.057428)
			(xy 358.5919 -35.107005) (xy 358.607256 -35.1593) (xy 358.615013 -35.213249) (xy 358.615013 -35.267751)
			(xy 358.607256 -35.3217) (xy 358.5919 -35.373995) (xy 358.569258 -35.423572) (xy 358.539791 -35.469422)
			(xy 358.504098 -35.510612) (xy 358.462906 -35.546303) (xy 358.417054 -35.575768) (xy 358.367476 -35.598407)
			(xy 358.31518 -35.61376) (xy 358.261232 -35.621514) (xy 358.23398 -35.621976) (xy 357.37038 -35.621976)
			(xy 357.343127 -35.621553) (xy 357.289177 -35.613793) (xy 357.236881 -35.598435) (xy 357.187302 -35.575791)
			(xy 357.14145 -35.546322) (xy 357.100259 -35.510627) (xy 357.064566 -35.469434) (xy 357.035099 -35.423581)
			(xy 357.012458 -35.374001) (xy 356.997102 -35.321703) (xy 356.989346 -35.267753) (xy 276.224131 -35.267753)
			(xy 274.25396 -37.237924) (xy 274.25396 -39.657528) (xy 357.003604 -39.657528) (xy 357.003604 -38.793928)
			(xy 357.00409 -38.766659) (xy 357.011852 -38.712675) (xy 357.027217 -38.660345) (xy 357.049874 -38.610735)
			(xy 357.07936 -38.564854) (xy 357.115075 -38.523637) (xy 357.156292 -38.487922) (xy 357.202173 -38.458436)
			(xy 357.251783 -38.435779) (xy 357.304113 -38.420414) (xy 357.358097 -38.412652) (xy 357.412635 -38.412652)
			(xy 357.466619 -38.420414) (xy 357.518949 -38.435779) (xy 357.568559 -38.458436) (xy 357.61444 -38.487922)
			(xy 357.655657 -38.523637) (xy 357.691372 -38.564854) (xy 357.720858 -38.610735) (xy 357.743515 -38.660345)
			(xy 357.75888 -38.712675) (xy 357.766642 -38.766659) (xy 357.767128 -38.793928) (xy 357.767128 -39.657528)
			(xy 357.766642 -39.684797) (xy 357.75888 -39.738781) (xy 357.743515 -39.791111) (xy 357.720858 -39.840721)
			(xy 357.691372 -39.886602) (xy 357.655657 -39.927819) (xy 357.61444 -39.963534) (xy 357.568559 -39.99302)
			(xy 357.518949 -40.015677) (xy 357.466619 -40.031042) (xy 357.412635 -40.038804) (xy 357.358097 -40.038804)
			(xy 357.304113 -40.031042) (xy 357.251783 -40.015677) (xy 357.202173 -39.99302) (xy 357.156292 -39.963534)
			(xy 357.115075 -39.927819) (xy 357.07936 -39.886602) (xy 357.049874 -39.840721) (xy 357.027217 -39.791111)
			(xy 357.011852 -39.738781) (xy 357.00409 -39.684797) (xy 357.003604 -39.657528) (xy 274.25396 -39.657528)
			(xy 274.25396 -41.578276) (xy 274.270978 -41.59377) (xy 274.679156 -42.001948) (xy 322.633594 -42.001948)
			(xy 322.647818 -41.975024) (xy 322.66118 -41.950955) (xy 322.693766 -41.906585) (xy 322.73239 -41.867359)
			(xy 322.77625 -41.83409) (xy 322.824436 -41.80747) (xy 322.875947 -41.788051) (xy 322.929715 -41.776235)
			(xy 322.984622 -41.77227) (xy 323.039529 -41.776235) (xy 323.093297 -41.788051) (xy 323.144808 -41.80747)
			(xy 323.192994 -41.83409) (xy 323.236854 -41.867359) (xy 323.275478 -41.906585) (xy 323.308064 -41.950955)
			(xy 323.321426 -41.975024) (xy 323.33565 -42.001948) (xy 328.518266 -42.001948) (xy 328.525378 -41.999916)
			(xy 328.549906 -41.993146) (xy 328.600267 -41.985884) (xy 328.625708 -41.985438) (xy 328.651147 -41.98591)
			(xy 328.701504 -41.993174) (xy 328.726038 -41.999916) (xy 328.73315 -42.001948) (xy 330.146406 -42.001948)
			(xy 330.153518 -41.999916) (xy 330.178045 -41.993142) (xy 330.228406 -41.985871) (xy 330.253848 -41.985438)
			(xy 330.279286 -41.985913) (xy 330.329642 -41.993182) (xy 330.354178 -41.999916) (xy 330.36129 -42.001948)
			(xy 331.774546 -42.001948) (xy 331.781658 -41.999916) (xy 331.806186 -41.993145) (xy 331.856547 -41.98588)
			(xy 331.881988 -41.985438) (xy 331.907427 -41.985908) (xy 331.957785 -41.993169) (xy 331.982318 -41.999916)
			(xy 331.98943 -42.001948) (xy 333.40294 -42.001948) (xy 333.410052 -41.999916) (xy 333.434579 -41.993144)
			(xy 333.484941 -41.985878) (xy 333.510382 -41.985438) (xy 333.535821 -41.985908) (xy 333.58618 -41.993168)
			(xy 333.610712 -41.999916) (xy 333.617824 -42.001948) (xy 335.033366 -42.001948) (xy 335.040478 -41.999916)
			(xy 335.065006 -41.993146) (xy 335.115367 -41.985884) (xy 335.140808 -41.985438) (xy 335.166247 -41.98591)
			(xy 335.216604 -41.993174) (xy 335.241138 -41.999916) (xy 335.24825 -42.001948) (xy 338.28863 -42.001948)
			(xy 338.295742 -41.999916) (xy 338.320269 -41.993144) (xy 338.370631 -41.985876) (xy 338.396072 -41.985438)
			(xy 338.424447 -41.986011) (xy 338.480467 -41.995077) (xy 338.507578 -42.003472) (xy 338.528944 -42.006234)
			(xy 338.570381 -42.01801) (xy 338.609241 -42.036601) (xy 338.644411 -42.061477) (xy 338.659978 -42.07637)
			(xy 339.06714 -42.483532) (xy 339.097112 -42.473626) (xy 339.124451 -42.46507) (xy 339.180992 -42.455885)
			(xy 339.209634 -42.455338) (xy 339.209888 -42.455338) (xy 339.237873 -42.455858) (xy 339.293153 -42.464612)
			(xy 339.346383 -42.481908) (xy 339.396251 -42.507318) (xy 339.441531 -42.540217) (xy 339.481105 -42.579795)
			(xy 339.514 -42.625078) (xy 339.539405 -42.674949) (xy 339.556696 -42.72818) (xy 339.565445 -42.783461)
			(xy 339.565996 -42.811446) (xy 339.565471 -42.839074) (xy 339.556931 -42.893667) (xy 339.540063 -42.946286)
			(xy 339.515272 -42.995669) (xy 339.483152 -43.040631) (xy 339.444474 -43.080093) (xy 339.400166 -43.11311)
			(xy 339.351291 -43.138888) (xy 339.299022 -43.156809) (xy 339.244611 -43.166444) (xy 339.217 -43.167554)
			(xy 339.217 -43.395138) (xy 339.243299 -43.396135) (xy 339.295188 -43.404916) (xy 339.34522 -43.421238)
			(xy 339.392306 -43.444745) (xy 339.435419 -43.474925) (xy 339.473621 -43.511122) (xy 339.506081 -43.552546)
			(xy 339.506567 -43.5534) (xy 353.767583 -43.5534) (xy 353.771544 -43.500544) (xy 353.783339 -43.44887)
			(xy 353.802705 -43.39953) (xy 353.829208 -43.353628) (xy 353.862256 -43.312189) (xy 353.901112 -43.276139)
			(xy 353.944908 -43.246283) (xy 353.992664 -43.223289) (xy 354.043314 -43.207669) (xy 354.095726 -43.199773)
			(xy 354.122228 -43.199304) (xy 354.122736 -43.199304) (xy 354.153713 -43.199978) (xy 354.214715 -43.210807)
			(xy 354.272905 -43.232077) (xy 354.300028 -43.247056) (xy 354.328004 -43.238767) (xy 354.385663 -43.229845)
			(xy 354.414836 -43.229276) (xy 354.99548 -43.229276) (xy 355.004624 -43.225466) (xy 355.025917 -43.217194)
			(xy 355.070087 -43.205543) (xy 355.115388 -43.199665) (xy 355.138228 -43.199304) (xy 355.162681 -43.199729)
			(xy 355.211118 -43.206478) (xy 355.25817 -43.219815) (xy 355.280722 -43.229276) (xy 355.307866 -43.229907)
			(xy 355.361565 -43.237931) (xy 355.413585 -43.253486) (xy 355.462874 -43.276259) (xy 355.508436 -43.305789)
			(xy 355.549352 -43.341481) (xy 355.584795 -43.382612) (xy 355.61405 -43.428352) (xy 355.636524 -43.477777)
			(xy 355.651765 -43.52989) (xy 355.659465 -43.583636) (xy 355.659944 -43.610784) (xy 355.659468 -43.634951)
			(xy 356.178591 -43.634951) (xy 356.178591 -43.580449) (xy 356.186348 -43.526502) (xy 356.201703 -43.474208)
			(xy 356.224344 -43.424632) (xy 356.253811 -43.378783) (xy 356.289502 -43.337594) (xy 356.330692 -43.301903)
			(xy 356.376543 -43.272438) (xy 356.42612 -43.249799) (xy 356.478414 -43.234445) (xy 356.532361 -43.22669)
			(xy 356.559612 -43.226228) (xy 357.423212 -43.226228) (xy 357.450465 -43.226643) (xy 357.504417 -43.234401)
			(xy 357.556715 -43.249759) (xy 357.606295 -43.272403) (xy 357.652149 -43.301872) (xy 357.693341 -43.337567)
			(xy 357.729035 -43.378761) (xy 357.758503 -43.424615) (xy 357.781145 -43.474196) (xy 357.796501 -43.526495)
			(xy 357.804258 -43.580447) (xy 357.804258 -43.634953) (xy 357.803812 -43.638056) (xy 358.339039 -43.638056)
			(xy 358.339039 -43.583544) (xy 358.346797 -43.529588) (xy 358.362156 -43.477285) (xy 358.384802 -43.4277)
			(xy 358.414274 -43.381843) (xy 358.449974 -43.340648) (xy 358.491172 -43.304953) (xy 358.537032 -43.275485)
			(xy 358.586619 -43.252843) (xy 358.638923 -43.23749) (xy 358.69288 -43.229736) (xy 358.720136 -43.229276)
			(xy 359.583736 -43.229276) (xy 359.610984 -43.229797) (xy 359.664926 -43.237557) (xy 359.717214 -43.252915)
			(xy 359.766785 -43.275557) (xy 359.812629 -43.305023) (xy 359.853813 -43.340713) (xy 359.889499 -43.3819)
			(xy 359.91896 -43.427747) (xy 359.941598 -43.47732) (xy 359.956951 -43.529609) (xy 359.964706 -43.583552)
			(xy 359.964706 -43.638048) (xy 359.956951 -43.691991) (xy 359.941598 -43.74428) (xy 359.91896 -43.793853)
			(xy 359.889499 -43.8397) (xy 359.853813 -43.880887) (xy 359.812629 -43.916577) (xy 359.766785 -43.946043)
			(xy 359.717214 -43.968685) (xy 359.664926 -43.984043) (xy 359.610984 -43.991803) (xy 359.583736 -43.992292)
			(xy 358.720136 -43.992292) (xy 358.69288 -43.991864) (xy 358.638923 -43.98411) (xy 358.586619 -43.968757)
			(xy 358.537032 -43.946115) (xy 358.491172 -43.916647) (xy 358.449974 -43.880952) (xy 358.414274 -43.839757)
			(xy 358.384802 -43.7939) (xy 358.362156 -43.744315) (xy 358.346797 -43.692012) (xy 358.339039 -43.638056)
			(xy 357.803812 -43.638056) (xy 357.796501 -43.688905) (xy 357.781145 -43.741204) (xy 357.758503 -43.790785)
			(xy 357.729035 -43.836639) (xy 357.693341 -43.877833) (xy 357.652149 -43.913528) (xy 357.606295 -43.942997)
			(xy 357.556715 -43.965641) (xy 357.504417 -43.980999) (xy 357.450465 -43.988757) (xy 357.423212 -43.989244)
			(xy 356.559612 -43.989244) (xy 356.532361 -43.98871) (xy 356.478414 -43.980955) (xy 356.42612 -43.965601)
			(xy 356.376543 -43.942962) (xy 356.330692 -43.913497) (xy 356.289502 -43.877806) (xy 356.253811 -43.836617)
			(xy 356.224344 -43.790768) (xy 356.201703 -43.741192) (xy 356.186348 -43.688898) (xy 356.178591 -43.634951)
			(xy 355.659468 -43.634951) (xy 355.659407 -43.638033) (xy 355.651654 -43.691977) (xy 355.636302 -43.744269)
			(xy 355.613666 -43.793843) (xy 355.584204 -43.839692) (xy 355.548518 -43.880882) (xy 355.507334 -43.916573)
			(xy 355.461489 -43.946041) (xy 355.411917 -43.968684) (xy 355.359628 -43.984043) (xy 355.305685 -43.991803)
			(xy 355.278436 -43.992292) (xy 354.414836 -43.992292) (xy 354.388369 -43.991825) (xy 354.335944 -43.984518)
			(xy 354.285033 -43.970025) (xy 354.236619 -43.948625) (xy 354.191633 -43.920731) (xy 354.170996 -43.904154)
			(xy 354.158864 -43.905712) (xy 354.134459 -43.907367) (xy 354.122228 -43.907456) (xy 354.095726 -43.907027)
			(xy 354.043314 -43.899131) (xy 353.992664 -43.883511) (xy 353.944908 -43.860517) (xy 353.901112 -43.830661)
			(xy 353.862256 -43.794611) (xy 353.829208 -43.753172) (xy 353.802705 -43.70727) (xy 353.783339 -43.65793)
			(xy 353.771544 -43.606256) (xy 353.767583 -43.5534) (xy 339.506567 -43.5534) (xy 339.532091 -43.598297)
			(xy 339.551085 -43.647376) (xy 339.562649 -43.698717) (xy 339.566532 -43.751201) (xy 339.562649 -43.803685)
			(xy 339.551085 -43.855025) (xy 339.53209 -43.904105) (xy 339.50608 -43.949855) (xy 339.47362 -43.99128)
			(xy 339.435418 -44.027476) (xy 339.392304 -44.057656) (xy 339.345219 -44.081163) (xy 339.295186 -44.097484)
			(xy 339.243297 -44.106265) (xy 339.217 -44.107354) (xy 339.217 -44.687236) (xy 339.221826 -44.69765)
			(xy 339.232617 -44.721546) (xy 339.247844 -44.771718) (xy 339.255541 -44.823581) (xy 339.255541 -44.840452)
			(xy 348.511075 -44.840452) (xy 348.511075 -44.785948) (xy 348.518832 -44.731999) (xy 348.534188 -44.679702)
			(xy 348.556831 -44.630124) (xy 348.586298 -44.584273) (xy 348.621992 -44.543082) (xy 348.663184 -44.50739)
			(xy 348.709036 -44.477924) (xy 348.758616 -44.455283) (xy 348.810912 -44.439929) (xy 348.864862 -44.432174)
			(xy 348.892114 -44.431712) (xy 349.755714 -44.431712) (xy 349.782966 -44.432159) (xy 349.836915 -44.439917)
			(xy 349.889211 -44.455274) (xy 349.938789 -44.477918) (xy 349.98464 -44.507386) (xy 350.025831 -44.543079)
			(xy 350.061523 -44.584271) (xy 350.090989 -44.630123) (xy 350.11363 -44.679702) (xy 350.128986 -44.731999)
			(xy 350.136742 -44.785948) (xy 350.136742 -44.840452) (xy 350.128986 -44.894401) (xy 350.11363 -44.946698)
			(xy 350.090989 -44.996277) (xy 350.072098 -45.025673) (xy 355.559288 -45.025673) (xy 355.559288 -44.971127)
			(xy 355.56705 -44.917137) (xy 355.582418 -44.864802) (xy 355.605077 -44.815186) (xy 355.634567 -44.7693)
			(xy 355.670288 -44.728078) (xy 355.711511 -44.692359) (xy 355.757398 -44.662871) (xy 355.807015 -44.640213)
			(xy 355.859351 -44.624847) (xy 355.913341 -44.617087) (xy 355.940614 -44.616624) (xy 356.804214 -44.616624)
			(xy 356.831482 -44.617139) (xy 356.885462 -44.624902) (xy 356.937788 -44.640268) (xy 356.987394 -44.662925)
			(xy 357.033272 -44.69241) (xy 357.074486 -44.728124) (xy 357.110199 -44.769339) (xy 357.139682 -44.815218)
			(xy 357.162337 -44.864825) (xy 357.177701 -44.917152) (xy 357.185462 -44.971132) (xy 357.185462 -45.025668)
			(xy 357.177701 -45.079648) (xy 357.162337 -45.131975) (xy 357.139682 -45.181582) (xy 357.110199 -45.227461)
			(xy 357.074486 -45.268676) (xy 357.033272 -45.30439) (xy 356.987394 -45.333875) (xy 356.937788 -45.356532)
			(xy 356.885462 -45.371898) (xy 356.831482 -45.379661) (xy 356.804214 -45.380148) (xy 355.940614 -45.380148)
			(xy 355.913341 -45.379713) (xy 355.859351 -45.371953) (xy 355.807015 -45.356587) (xy 355.757398 -45.333929)
			(xy 355.711511 -45.304441) (xy 355.670288 -45.268722) (xy 355.634567 -45.2275) (xy 355.605077 -45.181614)
			(xy 355.582418 -45.131998) (xy 355.56705 -45.079663) (xy 355.559288 -45.025673) (xy 350.072098 -45.025673)
			(xy 350.061523 -45.042129) (xy 350.025831 -45.083321) (xy 349.98464 -45.119014) (xy 349.938789 -45.148482)
			(xy 349.889211 -45.171126) (xy 349.836915 -45.186483) (xy 349.782966 -45.194241) (xy 349.755714 -45.194728)
			(xy 348.892114 -45.194728) (xy 348.864862 -45.194226) (xy 348.810912 -45.186471) (xy 348.758616 -45.171117)
			(xy 348.709036 -45.148476) (xy 348.663184 -45.11901) (xy 348.621992 -45.083318) (xy 348.586298 -45.042127)
			(xy 348.556831 -44.996276) (xy 348.534188 -44.946698) (xy 348.518832 -44.894401) (xy 348.511075 -44.840452)
			(xy 339.255541 -44.840452) (xy 339.255541 -44.876012) (xy 339.247845 -44.927875) (xy 339.232619 -44.978047)
			(xy 339.221826 -45.001942) (xy 339.217 -45.012356) (xy 339.217 -46.830068) (xy 356.445326 -46.830068)
			(xy 356.445326 -46.775532) (xy 356.453087 -46.721552) (xy 356.468451 -46.669225) (xy 356.491104 -46.619618)
			(xy 356.520587 -46.573739) (xy 356.556298 -46.532522) (xy 356.597512 -46.496807) (xy 356.643388 -46.467321)
			(xy 356.692994 -46.444663) (xy 356.745319 -46.429294) (xy 356.799298 -46.421529) (xy 356.826566 -46.42104)
			(xy 357.690166 -46.42104) (xy 357.717439 -46.421497) (xy 357.77143 -46.429255) (xy 357.823767 -46.444619)
			(xy 357.873384 -46.467275) (xy 357.919272 -46.496761) (xy 357.960497 -46.532479) (xy 357.996218 -46.5737)
			(xy 358.025709 -46.619586) (xy 358.048369 -46.669202) (xy 358.063737 -46.721537) (xy 358.0715 -46.775527)
			(xy 358.0715 -46.830069) (xy 358.762026 -46.830069) (xy 358.762026 -46.775531) (xy 358.769788 -46.721547)
			(xy 358.785153 -46.669218) (xy 358.807809 -46.619608) (xy 358.837295 -46.573728) (xy 358.87301 -46.53251)
			(xy 358.914228 -46.496795) (xy 358.960108 -46.467309) (xy 359.009718 -46.444653) (xy 359.062047 -46.429288)
			(xy 359.116031 -46.421526) (xy 359.1433 -46.42104) (xy 360.0069 -46.42104) (xy 360.03417 -46.421522)
			(xy 360.088153 -46.429284) (xy 360.140483 -46.44465) (xy 360.190094 -46.467306) (xy 360.235975 -46.496792)
			(xy 360.277193 -46.532507) (xy 360.312908 -46.573725) (xy 360.342394 -46.619606) (xy 360.36505 -46.669217)
			(xy 360.380416 -46.721547) (xy 360.388178 -46.77553) (xy 360.388178 -46.83007) (xy 360.388178 -46.830073)
			(xy 361.088604 -46.830073) (xy 361.088604 -46.775527) (xy 361.096367 -46.721537) (xy 361.111735 -46.669202)
			(xy 361.134395 -46.619586) (xy 361.163887 -46.573701) (xy 361.199608 -46.53248) (xy 361.240833 -46.496763)
			(xy 361.286721 -46.467276) (xy 361.336339 -46.444621) (xy 361.388676 -46.429258) (xy 361.442667 -46.421501)
			(xy 361.46994 -46.42104) (xy 362.33354 -46.42104) (xy 362.360808 -46.421525) (xy 362.414787 -46.429291)
			(xy 362.467112 -46.44466) (xy 362.516718 -46.467319) (xy 362.562594 -46.496806) (xy 362.603807 -46.532522)
			(xy 362.639518 -46.573738) (xy 362.669 -46.619618) (xy 362.691654 -46.669225) (xy 362.707017 -46.721552)
			(xy 362.714778 -46.775532) (xy 362.714778 -46.830068) (xy 362.707017 -46.884048) (xy 362.691654 -46.936375)
			(xy 362.672751 -46.977768) (xy 396.642323 -46.977768) (xy 396.642323 -46.891996) (xy 396.650237 -46.806588)
			(xy 396.665998 -46.722276) (xy 396.689471 -46.639777) (xy 396.720456 -46.559796) (xy 396.758688 -46.483015)
			(xy 396.803842 -46.41009) (xy 396.855532 -46.341642) (xy 396.913317 -46.278255) (xy 396.976704 -46.22047)
			(xy 397.045152 -46.16878) (xy 397.118077 -46.123626) (xy 397.194858 -46.085394) (xy 397.274839 -46.054409)
			(xy 397.357338 -46.030936) (xy 397.44165 -46.015175) (xy 397.527058 -46.007261) (xy 397.61283 -46.007261)
			(xy 397.698238 -46.015175) (xy 397.78255 -46.030936) (xy 397.865049 -46.054409) (xy 397.94503 -46.085394)
			(xy 398.021811 -46.123626) (xy 398.094736 -46.16878) (xy 398.163184 -46.22047) (xy 398.226571 -46.278255)
			(xy 398.284356 -46.341642) (xy 398.336046 -46.41009) (xy 398.3812 -46.483015) (xy 398.419432 -46.559796)
			(xy 398.450417 -46.639777) (xy 398.47389 -46.722276) (xy 398.489651 -46.806588) (xy 398.497565 -46.891996)
			(xy 398.49806 -46.934882) (xy 398.497565 -46.977768) (xy 398.489651 -47.063176) (xy 398.47389 -47.147488)
			(xy 398.450417 -47.229987) (xy 398.419432 -47.309968) (xy 398.3812 -47.386749) (xy 398.336046 -47.459674)
			(xy 398.284356 -47.528122) (xy 398.226571 -47.591509) (xy 398.163184 -47.649294) (xy 398.094736 -47.700984)
			(xy 398.021811 -47.746138) (xy 397.94503 -47.78437) (xy 397.865049 -47.815355) (xy 397.78255 -47.838828)
			(xy 397.698238 -47.854589) (xy 397.61283 -47.862503) (xy 397.527058 -47.862503) (xy 397.44165 -47.854589)
			(xy 397.357338 -47.838828) (xy 397.274839 -47.815355) (xy 397.194858 -47.78437) (xy 397.118077 -47.746138)
			(xy 397.045152 -47.700984) (xy 396.976704 -47.649294) (xy 396.913317 -47.591509) (xy 396.855532 -47.528122)
			(xy 396.803842 -47.459674) (xy 396.758688 -47.386749) (xy 396.720456 -47.309968) (xy 396.689471 -47.229987)
			(xy 396.665998 -47.147488) (xy 396.650237 -47.063176) (xy 396.642323 -46.977768) (xy 362.672751 -46.977768)
			(xy 362.669 -46.985982) (xy 362.639518 -47.031862) (xy 362.603807 -47.073078) (xy 362.562594 -47.108794)
			(xy 362.516718 -47.138281) (xy 362.467112 -47.16094) (xy 362.414787 -47.176309) (xy 362.360808 -47.184075)
			(xy 362.33354 -47.184564) (xy 361.46994 -47.184564) (xy 361.442667 -47.184099) (xy 361.388676 -47.176342)
			(xy 361.336339 -47.160979) (xy 361.286721 -47.138324) (xy 361.240833 -47.108837) (xy 361.199608 -47.07312)
			(xy 361.163887 -47.031899) (xy 361.134395 -46.986014) (xy 361.111735 -46.936398) (xy 361.096367 -46.884063)
			(xy 361.088604 -46.830073) (xy 360.388178 -46.830073) (xy 360.380416 -46.884053) (xy 360.36505 -46.936383)
			(xy 360.342394 -46.985994) (xy 360.312908 -47.031875) (xy 360.277193 -47.073093) (xy 360.235975 -47.108808)
			(xy 360.190094 -47.138294) (xy 360.140483 -47.16095) (xy 360.088153 -47.176316) (xy 360.03417 -47.184078)
			(xy 360.0069 -47.184564) (xy 359.1433 -47.184564) (xy 359.116031 -47.184074) (xy 359.062047 -47.176312)
			(xy 359.009718 -47.160947) (xy 358.960108 -47.138291) (xy 358.914228 -47.108805) (xy 358.87301 -47.07309)
			(xy 358.837295 -47.031872) (xy 358.807809 -46.985992) (xy 358.785153 -46.936382) (xy 358.769788 -46.884053)
			(xy 358.762026 -46.830069) (xy 358.0715 -46.830069) (xy 358.0715 -46.830073) (xy 358.063737 -46.884063)
			(xy 358.048369 -46.936398) (xy 358.025709 -46.986014) (xy 357.996218 -47.0319) (xy 357.960497 -47.073121)
			(xy 357.919272 -47.108839) (xy 357.873384 -47.138325) (xy 357.823767 -47.160981) (xy 357.77143 -47.176345)
			(xy 357.717439 -47.184103) (xy 357.690166 -47.184564) (xy 356.826566 -47.184564) (xy 356.799298 -47.184071)
			(xy 356.745319 -47.176306) (xy 356.692994 -47.160937) (xy 356.643388 -47.138279) (xy 356.597512 -47.108793)
			(xy 356.556298 -47.073078) (xy 356.520587 -47.031861) (xy 356.491104 -46.985982) (xy 356.468451 -46.936375)
			(xy 356.453087 -46.884048) (xy 356.445326 -46.830068) (xy 339.217 -46.830068) (xy 339.217 -49.487836)
			(xy 339.221826 -49.49825) (xy 339.232617 -49.522146) (xy 339.247844 -49.572318) (xy 339.255541 -49.624181)
			(xy 339.255541 -49.676612) (xy 339.247845 -49.728475) (xy 339.232619 -49.778647) (xy 339.221826 -49.802542)
			(xy 339.217 -49.812956) (xy 339.217 -50.234955) (xy 350.291827 -50.234955) (xy 350.291827 -50.180445)
			(xy 350.299585 -50.126489) (xy 350.314942 -50.074187) (xy 350.337587 -50.024602) (xy 350.367058 -49.978745)
			(xy 350.402755 -49.937549) (xy 350.443952 -49.901853) (xy 350.489809 -49.872383) (xy 350.539394 -49.849739)
			(xy 350.591697 -49.834383) (xy 350.645653 -49.826626) (xy 350.672908 -49.826164) (xy 351.536508 -49.826164)
			(xy 351.563757 -49.826707) (xy 351.6177 -49.834464) (xy 351.66999 -49.849818) (xy 351.719562 -49.872458)
			(xy 351.765408 -49.901922) (xy 351.806594 -49.937611) (xy 351.842282 -49.978798) (xy 351.871746 -50.024645)
			(xy 351.894385 -50.074218) (xy 351.909738 -50.126508) (xy 351.917494 -50.180451) (xy 351.917494 -50.234949)
			(xy 351.917493 -50.234956) (xy 352.489927 -50.234956) (xy 352.489927 -50.180444) (xy 352.497685 -50.126487)
			(xy 352.513044 -50.074183) (xy 352.535689 -50.024598) (xy 352.565162 -49.97874) (xy 352.600861 -49.937544)
			(xy 352.642059 -49.901848) (xy 352.687919 -49.872378) (xy 352.737506 -49.849735) (xy 352.78981 -49.83438)
			(xy 352.843768 -49.826625) (xy 352.871024 -49.826164) (xy 353.734624 -49.826164) (xy 353.761872 -49.826708)
			(xy 353.815813 -49.834467) (xy 353.868101 -49.849823) (xy 353.917672 -49.872463) (xy 353.963516 -49.901928)
			(xy 354.0047 -49.937617) (xy 354.040386 -49.978804) (xy 354.069848 -50.024649) (xy 354.092486 -50.074221)
			(xy 354.107839 -50.12651) (xy 354.115594 -50.180452) (xy 354.115594 -50.234948) (xy 354.115593 -50.234956)
			(xy 354.712427 -50.234956) (xy 354.712427 -50.180444) (xy 354.720185 -50.126487) (xy 354.735544 -50.074183)
			(xy 354.758189 -50.024598) (xy 354.787662 -49.97874) (xy 354.823361 -49.937544) (xy 354.864559 -49.901848)
			(xy 354.910419 -49.872378) (xy 354.960006 -49.849735) (xy 355.01231 -49.83438) (xy 355.066268 -49.826625)
			(xy 355.093524 -49.826164) (xy 355.957124 -49.826164) (xy 355.984372 -49.826708) (xy 356.038313 -49.834467)
			(xy 356.090601 -49.849823) (xy 356.140172 -49.872463) (xy 356.186016 -49.901928) (xy 356.2272 -49.937617)
			(xy 356.262886 -49.978804) (xy 356.292348 -50.024649) (xy 356.314986 -50.074221) (xy 356.330339 -50.12651)
			(xy 356.338094 -50.180452) (xy 356.338094 -50.234948) (xy 356.338093 -50.234957) (xy 356.942527 -50.234957)
			(xy 356.942527 -50.180443) (xy 356.950286 -50.126484) (xy 356.965645 -50.074179) (xy 356.988293 -50.024592)
			(xy 357.017767 -49.978734) (xy 357.053468 -49.937537) (xy 357.094669 -49.90184) (xy 357.140531 -49.872371)
			(xy 357.19012 -49.84973) (xy 357.242427 -49.834376) (xy 357.296387 -49.826624) (xy 357.323644 -49.826164)
			(xy 358.187244 -49.826164) (xy 358.214491 -49.826709) (xy 358.26843 -49.83447) (xy 358.320716 -49.849828)
			(xy 358.370284 -49.87247) (xy 358.416125 -49.901935) (xy 358.457307 -49.937624) (xy 358.492991 -49.97881)
			(xy 358.522451 -50.024655) (xy 358.545087 -50.074226) (xy 358.560439 -50.126513) (xy 358.568194 -50.180453)
			(xy 358.568194 -50.234947) (xy 358.560439 -50.288887) (xy 358.545087 -50.341174) (xy 358.522451 -50.390745)
			(xy 358.492991 -50.43659) (xy 358.457307 -50.477776) (xy 358.416125 -50.513465) (xy 358.370284 -50.54293)
			(xy 358.320716 -50.565572) (xy 358.26843 -50.58093) (xy 358.214491 -50.588691) (xy 358.187244 -50.58918)
			(xy 357.323644 -50.58918) (xy 357.296387 -50.588776) (xy 357.242427 -50.581024) (xy 357.19012 -50.56567)
			(xy 357.140531 -50.543029) (xy 357.094669 -50.51356) (xy 357.053468 -50.477863) (xy 357.017767 -50.436666)
			(xy 356.988293 -50.390808) (xy 356.965645 -50.341221) (xy 356.950286 -50.288916) (xy 356.942527 -50.234957)
			(xy 356.338093 -50.234957) (xy 356.330339 -50.28889) (xy 356.314986 -50.341179) (xy 356.292348 -50.390751)
			(xy 356.262886 -50.436596) (xy 356.2272 -50.477783) (xy 356.186016 -50.513472) (xy 356.140172 -50.542937)
			(xy 356.090601 -50.565577) (xy 356.038313 -50.580933) (xy 355.984372 -50.588692) (xy 355.957124 -50.58918)
			(xy 355.093524 -50.58918) (xy 355.066268 -50.588775) (xy 355.01231 -50.58102) (xy 354.960006 -50.565665)
			(xy 354.910419 -50.543022) (xy 354.864559 -50.513552) (xy 354.823361 -50.477856) (xy 354.787662 -50.43666)
			(xy 354.758189 -50.390802) (xy 354.735544 -50.341217) (xy 354.720185 -50.288913) (xy 354.712427 -50.234956)
			(xy 354.115593 -50.234956) (xy 354.107839 -50.28889) (xy 354.092486 -50.341179) (xy 354.069848 -50.390751)
			(xy 354.040386 -50.436596) (xy 354.0047 -50.477783) (xy 353.963516 -50.513472) (xy 353.917672 -50.542937)
			(xy 353.868101 -50.565577) (xy 353.815813 -50.580933) (xy 353.761872 -50.588692) (xy 353.734624 -50.58918)
			(xy 352.871024 -50.58918) (xy 352.843768 -50.588775) (xy 352.78981 -50.58102) (xy 352.737506 -50.565665)
			(xy 352.687919 -50.543022) (xy 352.642059 -50.513552) (xy 352.600861 -50.477856) (xy 352.565162 -50.43666)
			(xy 352.535689 -50.390802) (xy 352.513044 -50.341217) (xy 352.497685 -50.288913) (xy 352.489927 -50.234956)
			(xy 351.917493 -50.234956) (xy 351.909738 -50.288892) (xy 351.894385 -50.341182) (xy 351.871746 -50.390755)
			(xy 351.842282 -50.436602) (xy 351.806594 -50.477789) (xy 351.765408 -50.513477) (xy 351.719562 -50.542942)
			(xy 351.66999 -50.565582) (xy 351.6177 -50.580936) (xy 351.563757 -50.588693) (xy 351.536508 -50.58918)
			(xy 350.672908 -50.58918) (xy 350.645653 -50.588774) (xy 350.591697 -50.581017) (xy 350.539394 -50.565661)
			(xy 350.489809 -50.543017) (xy 350.443952 -50.513547) (xy 350.402755 -50.477851) (xy 350.367058 -50.436655)
			(xy 350.337587 -50.390798) (xy 350.314942 -50.341213) (xy 350.299585 -50.288911) (xy 350.291827 -50.234955)
			(xy 339.217 -50.234955) (xy 339.217 -55.911852) (xy 357.10365 -55.911852) (xy 357.10365 -55.857348)
			(xy 357.111406 -55.803398) (xy 357.126762 -55.751101) (xy 357.149403 -55.701521) (xy 357.17887 -55.655668)
			(xy 357.214562 -55.614476) (xy 357.255752 -55.578782) (xy 357.301604 -55.549313) (xy 357.351182 -55.526669)
			(xy 357.403478 -55.511311) (xy 357.457428 -55.503551) (xy 357.48468 -55.503064) (xy 358.34828 -55.503064)
			(xy 358.375532 -55.503582) (xy 358.429481 -55.511336) (xy 358.481777 -55.526689) (xy 358.531356 -55.549329)
			(xy 358.577209 -55.578794) (xy 358.618401 -55.614485) (xy 358.654094 -55.655675) (xy 358.683562 -55.701526)
			(xy 358.706204 -55.751104) (xy 358.72156 -55.8034) (xy 358.729317 -55.857348) (xy 358.729317 -55.911852)
			(xy 358.729316 -55.911856) (xy 359.950927 -55.911856) (xy 359.950927 -55.857344) (xy 359.958685 -55.803388)
			(xy 359.974043 -55.751084) (xy 359.996689 -55.701499) (xy 360.026161 -55.655642) (xy 360.061859 -55.614445)
			(xy 360.103058 -55.578749) (xy 360.148917 -55.549279) (xy 360.198503 -55.526636) (xy 360.250807 -55.511281)
			(xy 360.304764 -55.503526) (xy 360.33202 -55.503064) (xy 361.19562 -55.503064) (xy 361.222868 -55.503608)
			(xy 361.27681 -55.511366) (xy 361.329098 -55.526722) (xy 361.378669 -55.549362) (xy 361.424514 -55.578827)
			(xy 361.465699 -55.614516) (xy 361.501385 -55.655702) (xy 361.530847 -55.701548) (xy 361.553485 -55.75112)
			(xy 361.568838 -55.80341) (xy 361.576594 -55.857352) (xy 361.576594 -55.911848) (xy 361.576593 -55.911857)
			(xy 363.514527 -55.911857) (xy 363.514527 -55.857343) (xy 363.522286 -55.803385) (xy 363.537645 -55.75108)
			(xy 363.560292 -55.701493) (xy 363.589766 -55.655635) (xy 363.625466 -55.614438) (xy 363.666667 -55.578742)
			(xy 363.712529 -55.549273) (xy 363.762117 -55.526631) (xy 363.814424 -55.511277) (xy 363.868383 -55.503524)
			(xy 363.89564 -55.503064) (xy 364.75924 -55.503064) (xy 364.786487 -55.503609) (xy 364.840427 -55.511369)
			(xy 364.892713 -55.526727) (xy 364.942281 -55.549369) (xy 364.988123 -55.578834) (xy 365.029306 -55.614523)
			(xy 365.06499 -55.655709) (xy 365.094451 -55.701554) (xy 365.117087 -55.751125) (xy 365.132439 -55.803412)
			(xy 365.140194 -55.857353) (xy 365.140194 -55.911847) (xy 365.132439 -55.965788) (xy 365.117087 -56.018075)
			(xy 365.094451 -56.067646) (xy 365.06499 -56.113491) (xy 365.029306 -56.154677) (xy 364.988123 -56.190366)
			(xy 364.942281 -56.219831) (xy 364.892713 -56.242473) (xy 364.840427 -56.257831) (xy 364.786487 -56.265591)
			(xy 364.75924 -56.26608) (xy 363.89564 -56.26608) (xy 363.868383 -56.265676) (xy 363.814424 -56.257923)
			(xy 363.762117 -56.242569) (xy 363.712529 -56.219927) (xy 363.666667 -56.190458) (xy 363.625466 -56.154762)
			(xy 363.589766 -56.113565) (xy 363.560292 -56.067707) (xy 363.537645 -56.01812) (xy 363.522286 -55.965815)
			(xy 363.514527 -55.911857) (xy 361.576593 -55.911857) (xy 361.568838 -55.96579) (xy 361.553485 -56.01808)
			(xy 361.530847 -56.067652) (xy 361.501385 -56.113498) (xy 361.465699 -56.154684) (xy 361.424514 -56.190373)
			(xy 361.378669 -56.219838) (xy 361.329098 -56.242478) (xy 361.27681 -56.257834) (xy 361.222868 -56.265592)
			(xy 361.19562 -56.26608) (xy 360.33202 -56.26608) (xy 360.304764 -56.265674) (xy 360.250807 -56.257919)
			(xy 360.198503 -56.242564) (xy 360.148917 -56.219921) (xy 360.103058 -56.190451) (xy 360.061859 -56.154755)
			(xy 360.026161 -56.113558) (xy 359.996689 -56.067701) (xy 359.974043 -56.018116) (xy 359.958685 -55.965812)
			(xy 359.950927 -55.911856) (xy 358.729316 -55.911856) (xy 358.72156 -55.9658) (xy 358.706204 -56.018096)
			(xy 358.683562 -56.067674) (xy 358.654094 -56.113525) (xy 358.618401 -56.154715) (xy 358.577209 -56.190406)
			(xy 358.531356 -56.219871) (xy 358.481777 -56.242511) (xy 358.429481 -56.257864) (xy 358.375532 -56.265618)
			(xy 358.34828 -56.26608) (xy 357.48468 -56.26608) (xy 357.457428 -56.265649) (xy 357.403478 -56.257889)
			(xy 357.351182 -56.242531) (xy 357.301604 -56.219887) (xy 357.255752 -56.190418) (xy 357.214562 -56.154724)
			(xy 357.17887 -56.113532) (xy 357.149403 -56.067679) (xy 357.126762 -56.018099) (xy 357.111406 -55.965802)
			(xy 357.10365 -55.911852) (xy 339.217 -55.911852) (xy 339.217 -56.200548) (xy 339.216384 -56.225503)
			(xy 339.206638 -56.274452) (xy 339.187531 -56.320559) (xy 339.159797 -56.362053) (xy 339.142578 -56.380126)
			(xy 338.405978 -57.116726) (xy 338.387938 -57.133988) (xy 338.346445 -57.161751) (xy 338.300327 -57.18087)
			(xy 338.251362 -57.190607) (xy 338.2264 -57.191148) (xy 337.798156 -57.191148) (xy 337.77732 -57.206519)
			(xy 337.732088 -57.231716) (xy 337.683687 -57.250103) (xy 337.633134 -57.261292) (xy 337.581494 -57.265048)
			(xy 337.529854 -57.261292) (xy 337.479301 -57.250103) (xy 337.4309 -57.231716) (xy 337.385668 -57.206519)
			(xy 337.364832 -57.191148) (xy 336.17027 -57.191148) (xy 336.149434 -57.206519) (xy 336.104202 -57.231716)
			(xy 336.055801 -57.250103) (xy 336.005248 -57.261292) (xy 335.953608 -57.265048) (xy 335.901968 -57.261292)
			(xy 335.851415 -57.250103) (xy 335.803014 -57.231716) (xy 335.757782 -57.206519) (xy 335.736946 -57.191148)
			(xy 332.912974 -57.191148) (xy 332.892138 -57.206519) (xy 332.846906 -57.231716) (xy 332.798505 -57.250103)
			(xy 332.747952 -57.261292) (xy 332.696312 -57.265048) (xy 332.644672 -57.261292) (xy 332.594119 -57.250103)
			(xy 332.545718 -57.231716) (xy 332.500486 -57.206519) (xy 332.47965 -57.191148) (xy 331.286612 -57.191148)
			(xy 331.265776 -57.206519) (xy 331.220544 -57.231716) (xy 331.172143 -57.250103) (xy 331.12159 -57.261292)
			(xy 331.06995 -57.265048) (xy 331.01831 -57.261292) (xy 330.967757 -57.250103) (xy 330.919356 -57.231716)
			(xy 330.874124 -57.206519) (xy 330.853288 -57.191148) (xy 330.076556 -57.191148) (xy 329.5142 -57.753504)
			(xy 329.5142 -61.480954) (xy 351.822512 -61.480954) (xy 351.822512 -60.617354) (xy 351.822998 -60.590103)
			(xy 351.830754 -60.536155) (xy 351.846109 -60.48386) (xy 351.868751 -60.434283) (xy 351.898217 -60.388433)
			(xy 351.933908 -60.347242) (xy 351.975099 -60.311551) (xy 352.020949 -60.282085) (xy 352.070526 -60.259443)
			(xy 352.122821 -60.244088) (xy 352.176769 -60.236332) (xy 352.231271 -60.236332) (xy 352.285219 -60.244088)
			(xy 352.337514 -60.259443) (xy 352.387091 -60.282085) (xy 352.432941 -60.311551) (xy 352.474132 -60.347242)
			(xy 352.509823 -60.388433) (xy 352.539289 -60.434283) (xy 352.561931 -60.48386) (xy 352.577286 -60.536155)
			(xy 352.585042 -60.590103) (xy 352.585528 -60.617354) (xy 352.585528 -61.223271) (xy 355.46889 -61.223271)
			(xy 355.46889 -61.168729) (xy 355.476653 -61.114741) (xy 355.492019 -61.062408) (xy 355.514676 -61.012794)
			(xy 355.544164 -60.966909) (xy 355.579881 -60.925688) (xy 355.621101 -60.88997) (xy 355.666985 -60.860481)
			(xy 355.716598 -60.837822) (xy 355.768931 -60.822455) (xy 355.822919 -60.814691) (xy 355.85019 -60.814204)
			(xy 356.71379 -60.814204) (xy 356.741059 -60.814735) (xy 356.795042 -60.822495) (xy 356.847371 -60.837859)
			(xy 356.896981 -60.860514) (xy 356.942862 -60.889999) (xy 356.98408 -60.925713) (xy 357.019795 -60.96693)
			(xy 357.049281 -61.01281) (xy 357.071937 -61.062419) (xy 357.087303 -61.114748) (xy 357.095065 -61.168731)
			(xy 357.095065 -61.223269) (xy 357.087303 -61.277252) (xy 357.071937 -61.329581) (xy 357.049281 -61.37919)
			(xy 357.019795 -61.42507) (xy 356.98408 -61.466287) (xy 356.942862 -61.502001) (xy 356.896981 -61.531486)
			(xy 356.847371 -61.554141) (xy 356.795042 -61.569505) (xy 356.741059 -61.577265) (xy 356.71379 -61.577728)
			(xy 355.85019 -61.577728) (xy 355.822919 -61.577309) (xy 355.768931 -61.569545) (xy 355.716598 -61.554178)
			(xy 355.666985 -61.531519) (xy 355.621101 -61.50203) (xy 355.579881 -61.466312) (xy 355.544164 -61.425091)
			(xy 355.514676 -61.379206) (xy 355.492019 -61.329592) (xy 355.476653 -61.277259) (xy 355.46889 -61.223271)
			(xy 352.585528 -61.223271) (xy 352.585528 -61.480954) (xy 352.585042 -61.508205) (xy 352.577286 -61.562153)
			(xy 352.561931 -61.614448) (xy 352.539289 -61.664025) (xy 352.509823 -61.709875) (xy 352.474132 -61.751066)
			(xy 352.432941 -61.786757) (xy 352.387091 -61.816223) (xy 352.337514 -61.838865) (xy 352.285219 -61.85422)
			(xy 352.231271 -61.861976) (xy 352.176769 -61.861976) (xy 352.122821 -61.85422) (xy 352.070526 -61.838865)
			(xy 352.020949 -61.816223) (xy 351.975099 -61.786757) (xy 351.933908 -61.751066) (xy 351.898217 -61.709875)
			(xy 351.868751 -61.664025) (xy 351.846109 -61.614448) (xy 351.830754 -61.562153) (xy 351.822998 -61.508205)
			(xy 351.822512 -61.480954) (xy 329.5142 -61.480954) (xy 329.5142 -63.269876) (xy 350.300544 -63.269876)
			(xy 350.300544 -62.406276) (xy 350.30103 -62.379025) (xy 350.308786 -62.325077) (xy 350.324141 -62.272782)
			(xy 350.346783 -62.223205) (xy 350.376249 -62.177355) (xy 350.41194 -62.136164) (xy 350.453131 -62.100473)
			(xy 350.498981 -62.071007) (xy 350.548558 -62.048365) (xy 350.600853 -62.03301) (xy 350.654801 -62.025254)
			(xy 350.709303 -62.025254) (xy 350.763251 -62.03301) (xy 350.815546 -62.048365) (xy 350.865123 -62.071007)
			(xy 350.910973 -62.100473) (xy 350.952164 -62.136164) (xy 350.987855 -62.177355) (xy 351.017321 -62.223205)
			(xy 351.039963 -62.272782) (xy 351.055318 -62.325077) (xy 351.063074 -62.379025) (xy 351.06356 -62.406276)
			(xy 351.06356 -63.269876) (xy 351.063074 -63.297127) (xy 351.055318 -63.351075) (xy 351.039963 -63.40337)
			(xy 351.017321 -63.452947) (xy 350.987855 -63.498797) (xy 350.952164 -63.539988) (xy 350.910973 -63.575679)
			(xy 350.865123 -63.605145) (xy 350.815546 -63.627787) (xy 350.763251 -63.643142) (xy 350.709303 -63.650898)
			(xy 350.654801 -63.650898) (xy 350.600853 -63.643142) (xy 350.548558 -63.627787) (xy 350.498981 -63.605145)
			(xy 350.453131 -63.575679) (xy 350.41194 -63.539988) (xy 350.376249 -63.498797) (xy 350.346783 -63.452947)
			(xy 350.324141 -63.40337) (xy 350.308786 -63.351075) (xy 350.30103 -63.297127) (xy 350.300544 -63.269876)
			(xy 329.5142 -63.269876) (xy 329.5142 -65.329562) (xy 352.362008 -65.329562) (xy 352.362008 -64.465962)
			(xy 352.362494 -64.438711) (xy 352.37025 -64.384763) (xy 352.385605 -64.332468) (xy 352.408247 -64.282891)
			(xy 352.437713 -64.237041) (xy 352.473404 -64.19585) (xy 352.514595 -64.160159) (xy 352.560445 -64.130693)
			(xy 352.610022 -64.108051) (xy 352.662317 -64.092696) (xy 352.716265 -64.08494) (xy 352.770767 -64.08494)
			(xy 352.824715 -64.092696) (xy 352.87701 -64.108051) (xy 352.926587 -64.130693) (xy 352.972437 -64.160159)
			(xy 353.013628 -64.19585) (xy 353.049319 -64.237041) (xy 353.078785 -64.282891) (xy 353.101427 -64.332468)
			(xy 353.116782 -64.384763) (xy 353.124538 -64.438711) (xy 353.125024 -64.465962) (xy 353.125024 -65.329562)
			(xy 353.124538 -65.356813) (xy 353.116782 -65.410761) (xy 353.101427 -65.463056) (xy 353.078785 -65.512633)
			(xy 353.049319 -65.558483) (xy 353.013628 -65.599674) (xy 352.972437 -65.635365) (xy 352.926587 -65.664831)
			(xy 352.87701 -65.687473) (xy 352.824715 -65.702828) (xy 352.770767 -65.710584) (xy 352.716265 -65.710584)
			(xy 352.662317 -65.702828) (xy 352.610022 -65.687473) (xy 352.560445 -65.664831) (xy 352.514595 -65.635365)
			(xy 352.473404 -65.599674) (xy 352.437713 -65.558483) (xy 352.408247 -65.512633) (xy 352.385605 -65.463056)
			(xy 352.37025 -65.410761) (xy 352.362494 -65.356813) (xy 352.362008 -65.329562) (xy 329.5142 -65.329562)
			(xy 329.5142 -66.963544) (xy 350.27108 -66.963544) (xy 350.27108 -66.099944) (xy 350.271566 -66.072693)
			(xy 350.279322 -66.018745) (xy 350.294677 -65.96645) (xy 350.317319 -65.916873) (xy 350.346785 -65.871023)
			(xy 350.382476 -65.829832) (xy 350.423667 -65.794141) (xy 350.469517 -65.764675) (xy 350.519094 -65.742033)
			(xy 350.571389 -65.726678) (xy 350.625337 -65.718922) (xy 350.679839 -65.718922) (xy 350.733787 -65.726678)
			(xy 350.786082 -65.742033) (xy 350.835659 -65.764675) (xy 350.881509 -65.794141) (xy 350.9227 -65.829832)
			(xy 350.958391 -65.871023) (xy 350.987857 -65.916873) (xy 351.010499 -65.96645) (xy 351.025854 -66.018745)
			(xy 351.03361 -66.072693) (xy 351.034096 -66.099944) (xy 351.034096 -66.963544) (xy 351.03361 -66.990795)
			(xy 351.025854 -67.044743) (xy 351.010499 -67.097038) (xy 351.005595 -67.107776) (xy 396.642323 -67.107776)
			(xy 396.642323 -67.022004) (xy 396.650237 -66.936596) (xy 396.665998 -66.852284) (xy 396.689471 -66.769785)
			(xy 396.720456 -66.689804) (xy 396.758688 -66.613023) (xy 396.803842 -66.540098) (xy 396.855532 -66.47165)
			(xy 396.913317 -66.408263) (xy 396.976704 -66.350478) (xy 397.045152 -66.298788) (xy 397.118077 -66.253634)
			(xy 397.194858 -66.215402) (xy 397.274839 -66.184417) (xy 397.357338 -66.160944) (xy 397.44165 -66.145183)
			(xy 397.527058 -66.137269) (xy 397.61283 -66.137269) (xy 397.698238 -66.145183) (xy 397.78255 -66.160944)
			(xy 397.865049 -66.184417) (xy 397.94503 -66.215402) (xy 398.021811 -66.253634) (xy 398.094736 -66.298788)
			(xy 398.163184 -66.350478) (xy 398.226571 -66.408263) (xy 398.284356 -66.47165) (xy 398.336046 -66.540098)
			(xy 398.3812 -66.613023) (xy 398.419432 -66.689804) (xy 398.450417 -66.769785) (xy 398.47389 -66.852284)
			(xy 398.489651 -66.936596) (xy 398.497565 -67.022004) (xy 398.49806 -67.06489) (xy 398.497565 -67.107776)
			(xy 398.489651 -67.193184) (xy 398.47389 -67.277496) (xy 398.450417 -67.359995) (xy 398.419432 -67.439976)
			(xy 398.3812 -67.516757) (xy 398.336046 -67.589682) (xy 398.284356 -67.65813) (xy 398.226571 -67.721517)
			(xy 398.163184 -67.779302) (xy 398.094736 -67.830992) (xy 398.021811 -67.876146) (xy 397.94503 -67.914378)
			(xy 397.865049 -67.945363) (xy 397.78255 -67.968836) (xy 397.698238 -67.984597) (xy 397.61283 -67.992511)
			(xy 397.527058 -67.992511) (xy 397.44165 -67.984597) (xy 397.357338 -67.968836) (xy 397.274839 -67.945363)
			(xy 397.194858 -67.914378) (xy 397.118077 -67.876146) (xy 397.045152 -67.830992) (xy 396.976704 -67.779302)
			(xy 396.913317 -67.721517) (xy 396.855532 -67.65813) (xy 396.803842 -67.589682) (xy 396.758688 -67.516757)
			(xy 396.720456 -67.439976) (xy 396.689471 -67.359995) (xy 396.665998 -67.277496) (xy 396.650237 -67.193184)
			(xy 396.642323 -67.107776) (xy 351.005595 -67.107776) (xy 350.987857 -67.146615) (xy 350.958391 -67.192465)
			(xy 350.9227 -67.233656) (xy 350.881509 -67.269347) (xy 350.835659 -67.298813) (xy 350.786082 -67.321455)
			(xy 350.733787 -67.33681) (xy 350.679839 -67.344566) (xy 350.625337 -67.344566) (xy 350.571389 -67.33681)
			(xy 350.519094 -67.321455) (xy 350.469517 -67.298813) (xy 350.423667 -67.269347) (xy 350.382476 -67.233656)
			(xy 350.346785 -67.192465) (xy 350.317319 -67.146615) (xy 350.294677 -67.097038) (xy 350.279322 -67.044743)
			(xy 350.271566 -66.990795) (xy 350.27108 -66.963544) (xy 329.5142 -66.963544) (xy 329.5142 -69.10578)
			(xy 351.73158 -69.10578) (xy 351.73158 -68.24218) (xy 351.732066 -68.214911) (xy 351.739828 -68.160927)
			(xy 351.755193 -68.108597) (xy 351.77785 -68.058987) (xy 351.807336 -68.013106) (xy 351.843051 -67.971889)
			(xy 351.884268 -67.936174) (xy 351.930149 -67.906688) (xy 351.979759 -67.884031) (xy 352.032089 -67.868666)
			(xy 352.086073 -67.860904) (xy 352.140611 -67.860904) (xy 352.194595 -67.868666) (xy 352.246925 -67.884031)
			(xy 352.296535 -67.906688) (xy 352.342416 -67.936174) (xy 352.383633 -67.971889) (xy 352.419348 -68.013106)
			(xy 352.448834 -68.058987) (xy 352.471491 -68.108597) (xy 352.486856 -68.160927) (xy 352.494618 -68.214911)
			(xy 352.495104 -68.24218) (xy 352.495104 -69.10578) (xy 352.494618 -69.133049) (xy 352.486856 -69.187033)
			(xy 352.471491 -69.239363) (xy 352.448834 -69.288973) (xy 352.419348 -69.334854) (xy 352.383633 -69.376071)
			(xy 352.342416 -69.411786) (xy 352.296535 -69.441272) (xy 352.246925 -69.463929) (xy 352.194595 -69.479294)
			(xy 352.140611 -69.487056) (xy 352.086073 -69.487056) (xy 352.032089 -69.479294) (xy 351.979759 -69.463929)
			(xy 351.930149 -69.441272) (xy 351.884268 -69.411786) (xy 351.843051 -69.376071) (xy 351.807336 -69.334854)
			(xy 351.77785 -69.288973) (xy 351.755193 -69.239363) (xy 351.739828 -69.187033) (xy 351.732066 -69.133049)
			(xy 351.73158 -69.10578) (xy 329.5142 -69.10578) (xy 329.5142 -71.213074) (xy 341.168388 -71.213074)
			(xy 341.168388 -71.158526) (xy 341.176151 -71.104534) (xy 341.19152 -71.052197) (xy 341.214181 -71.00258)
			(xy 341.243673 -70.956692) (xy 341.279395 -70.91547) (xy 341.320621 -70.879751) (xy 341.366511 -70.850263)
			(xy 341.416131 -70.827607) (xy 341.46847 -70.812243) (xy 341.522462 -70.804485) (xy 341.549736 -70.804024)
			(xy 342.413336 -70.804024) (xy 342.440603 -70.804541) (xy 342.49458 -70.812306) (xy 342.546904 -70.827674)
			(xy 342.596508 -70.850332) (xy 342.642382 -70.879817) (xy 342.683594 -70.915531) (xy 342.719304 -70.956747)
			(xy 342.748786 -71.002624) (xy 342.771438 -71.05223) (xy 342.786801 -71.104555) (xy 342.794562 -71.158533)
			(xy 342.794562 -71.213067) (xy 342.786801 -71.267045) (xy 342.771438 -71.31937) (xy 342.748786 -71.368976)
			(xy 342.719304 -71.414853) (xy 342.683594 -71.456069) (xy 342.642382 -71.491783) (xy 342.596508 -71.521268)
			(xy 342.546904 -71.543926) (xy 342.49458 -71.559294) (xy 342.440603 -71.567059) (xy 342.413336 -71.567548)
			(xy 341.549736 -71.567548) (xy 341.522462 -71.567115) (xy 341.46847 -71.559357) (xy 341.416131 -71.543993)
			(xy 341.366511 -71.521337) (xy 341.320621 -71.491849) (xy 341.279395 -71.45613) (xy 341.243673 -71.414908)
			(xy 341.214181 -71.36902) (xy 341.19152 -71.319403) (xy 341.176151 -71.267066) (xy 341.168388 -71.213074)
			(xy 329.5142 -71.213074) (xy 329.5142 -71.844253) (xy 346.360454 -71.844253) (xy 346.360454 -71.789747)
			(xy 346.368211 -71.735796) (xy 346.383567 -71.683499) (xy 346.406209 -71.633919) (xy 346.435677 -71.588066)
			(xy 346.47137 -71.546873) (xy 346.512562 -71.511179) (xy 346.558415 -71.481711) (xy 346.607995 -71.459068)
			(xy 346.660293 -71.443712) (xy 346.714243 -71.435954) (xy 346.741496 -71.435468) (xy 347.605096 -71.435468)
			(xy 347.632347 -71.435979) (xy 347.686295 -71.443735) (xy 347.73859 -71.45909) (xy 347.788168 -71.481731)
			(xy 347.834019 -71.511197) (xy 347.875209 -71.546888) (xy 347.910901 -71.588078) (xy 347.940367 -71.633929)
			(xy 347.963009 -71.683506) (xy 347.978364 -71.735801) (xy 347.986121 -71.789749) (xy 347.986121 -71.844251)
			(xy 347.978364 -71.898199) (xy 347.963009 -71.950494) (xy 347.940367 -72.000071) (xy 347.910901 -72.045922)
			(xy 347.875209 -72.087112) (xy 347.834019 -72.122803) (xy 347.788168 -72.152269) (xy 347.73859 -72.17491)
			(xy 347.686295 -72.190265) (xy 347.632347 -72.198021) (xy 347.605096 -72.198484) (xy 346.741496 -72.198484)
			(xy 346.714243 -72.198046) (xy 346.660293 -72.190288) (xy 346.607995 -72.174932) (xy 346.558415 -72.152289)
			(xy 346.512562 -72.122821) (xy 346.47137 -72.087127) (xy 346.435677 -72.045934) (xy 346.406209 -72.000081)
			(xy 346.383567 -71.950501) (xy 346.368211 -71.898204) (xy 346.360454 -71.844253) (xy 329.5142 -71.844253)
			(xy 329.5142 -72.404055) (xy 332.037847 -72.404055) (xy 332.037847 -72.349545) (xy 332.045606 -72.295589)
			(xy 332.060964 -72.243286) (xy 332.083611 -72.193702) (xy 332.113083 -72.147846) (xy 332.148782 -72.106651)
			(xy 332.189981 -72.070957) (xy 332.235841 -72.041489) (xy 332.285427 -72.018849) (xy 332.337732 -72.003496)
			(xy 332.391689 -71.995744) (xy 332.418944 -71.995284) (xy 333.282544 -71.995284) (xy 333.309793 -71.995789)
			(xy 333.363734 -72.00355) (xy 333.416023 -72.018909) (xy 333.465593 -72.041552) (xy 333.511437 -72.071019)
			(xy 333.552622 -72.10671) (xy 333.588308 -72.147898) (xy 333.617769 -72.193745) (xy 333.640407 -72.243318)
			(xy 333.655759 -72.295609) (xy 333.660251 -72.326853) (xy 343.845854 -72.326853) (xy 343.845854 -72.272347)
			(xy 343.853611 -72.218396) (xy 343.868967 -72.166099) (xy 343.891609 -72.116519) (xy 343.921077 -72.070666)
			(xy 343.95677 -72.029473) (xy 343.997962 -71.993779) (xy 344.043815 -71.964311) (xy 344.093395 -71.941668)
			(xy 344.145693 -71.926312) (xy 344.199643 -71.918554) (xy 344.226896 -71.918068) (xy 345.090496 -71.918068)
			(xy 345.117747 -71.918579) (xy 345.171695 -71.926335) (xy 345.22399 -71.94169) (xy 345.273568 -71.964331)
			(xy 345.319419 -71.993797) (xy 345.360609 -72.029488) (xy 345.396301 -72.070678) (xy 345.425767 -72.116529)
			(xy 345.448409 -72.166106) (xy 345.463764 -72.218401) (xy 345.471521 -72.272349) (xy 345.471521 -72.326851)
			(xy 345.463764 -72.380799) (xy 345.448409 -72.433094) (xy 345.425767 -72.482671) (xy 345.396301 -72.528522)
			(xy 345.360609 -72.569712) (xy 345.319419 -72.605403) (xy 345.273568 -72.634869) (xy 345.22399 -72.65751)
			(xy 345.171695 -72.672865) (xy 345.117747 -72.680621) (xy 345.090496 -72.681084) (xy 344.226896 -72.681084)
			(xy 344.199643 -72.680646) (xy 344.145693 -72.672888) (xy 344.093395 -72.657532) (xy 344.043815 -72.634889)
			(xy 343.997962 -72.605421) (xy 343.95677 -72.569727) (xy 343.921077 -72.528534) (xy 343.891609 -72.482681)
			(xy 343.868967 -72.433101) (xy 343.853611 -72.380804) (xy 343.845854 -72.326853) (xy 333.660251 -72.326853)
			(xy 333.663514 -72.349551) (xy 333.663514 -72.404049) (xy 333.655759 -72.457991) (xy 333.640407 -72.510282)
			(xy 333.617769 -72.559855) (xy 333.588308 -72.605702) (xy 333.552622 -72.64689) (xy 333.511437 -72.682581)
			(xy 333.465593 -72.712048) (xy 333.416023 -72.734691) (xy 333.363734 -72.75005) (xy 333.309793 -72.757811)
			(xy 333.282544 -72.7583) (xy 332.418944 -72.7583) (xy 332.391689 -72.757856) (xy 332.337732 -72.750104)
			(xy 332.285427 -72.734751) (xy 332.235841 -72.712111) (xy 332.189981 -72.682643) (xy 332.148782 -72.646949)
			(xy 332.113083 -72.605754) (xy 332.083611 -72.559898) (xy 332.060964 -72.510314) (xy 332.045606 -72.458011)
			(xy 332.037847 -72.404055) (xy 329.5142 -72.404055) (xy 329.5142 -74.356747) (xy 330.744122 -74.356747)
			(xy 330.744122 -74.302253) (xy 330.751877 -74.248315) (xy 330.767229 -74.196029) (xy 330.789865 -74.146459)
			(xy 330.819325 -74.100616) (xy 330.855009 -74.059431) (xy 330.89619 -74.023744) (xy 330.942031 -73.99428)
			(xy 330.991599 -73.97164) (xy 331.043883 -73.956284) (xy 331.097821 -73.948524) (xy 331.125068 -73.948036)
			(xy 331.988668 -73.948036) (xy 332.015926 -73.948409) (xy 332.069886 -73.956163) (xy 332.122194 -73.971518)
			(xy 332.171784 -73.994161) (xy 332.217646 -74.023632) (xy 332.258848 -74.05933) (xy 332.294549 -74.100528)
			(xy 332.324023 -74.146388) (xy 332.346671 -74.195976) (xy 332.36203 -74.248283) (xy 332.369789 -74.302243)
			(xy 332.369789 -74.356757) (xy 332.36203 -74.410717) (xy 332.346671 -74.463024) (xy 332.324023 -74.512612)
			(xy 332.294549 -74.558472) (xy 332.26684 -74.590448) (xy 336.274202 -74.590448) (xy 336.274202 -74.535953)
			(xy 336.281957 -74.482012) (xy 336.297309 -74.429724) (xy 336.319945 -74.380153) (xy 336.349406 -74.334308)
			(xy 336.38509 -74.293121) (xy 336.426272 -74.257432) (xy 336.472114 -74.227966) (xy 336.521683 -74.205324)
			(xy 336.573969 -74.189966) (xy 336.627909 -74.182205) (xy 336.655156 -74.181716) (xy 337.518756 -74.181716)
			(xy 337.546013 -74.182128) (xy 337.599972 -74.18988) (xy 337.652278 -74.205233) (xy 337.701867 -74.227875)
			(xy 337.747729 -74.257344) (xy 337.788929 -74.29304) (xy 337.82463 -74.334236) (xy 337.854104 -74.380094)
			(xy 337.876751 -74.42968) (xy 337.89211 -74.481985) (xy 337.899869 -74.535943) (xy 337.899869 -74.55185)
			(xy 339.156294 -74.55185) (xy 339.156294 -74.49735) (xy 339.16405 -74.443405) (xy 339.179404 -74.391113)
			(xy 339.202044 -74.341539) (xy 339.231509 -74.29569) (xy 339.267198 -74.254502) (xy 339.308386 -74.218812)
			(xy 339.354233 -74.189347) (xy 339.403808 -74.166707) (xy 339.456099 -74.151352) (xy 339.510044 -74.143595)
			(xy 339.537294 -74.143108) (xy 340.400894 -74.143108) (xy 340.428148 -74.143538) (xy 340.482102 -74.151295)
			(xy 340.534403 -74.166651) (xy 340.583986 -74.189294) (xy 340.629842 -74.218763) (xy 340.671037 -74.254459)
			(xy 340.706733 -74.295653) (xy 340.736203 -74.341509) (xy 340.758847 -74.391091) (xy 340.774204 -74.443392)
			(xy 340.781961 -74.497346) (xy 340.781961 -74.551854) (xy 340.774204 -74.605808) (xy 340.758847 -74.658109)
			(xy 340.736203 -74.707691) (xy 340.706733 -74.753547) (xy 340.671037 -74.794741) (xy 340.629842 -74.830437)
			(xy 340.583986 -74.859906) (xy 340.534403 -74.882549) (xy 340.482102 -74.897905) (xy 340.428148 -74.905662)
			(xy 340.400894 -74.906124) (xy 339.537294 -74.906124) (xy 339.510044 -74.905605) (xy 339.456099 -74.897848)
			(xy 339.403808 -74.882493) (xy 339.354233 -74.859853) (xy 339.308386 -74.830388) (xy 339.267198 -74.794698)
			(xy 339.231509 -74.75351) (xy 339.202044 -74.707661) (xy 339.179404 -74.658087) (xy 339.16405 -74.605795)
			(xy 339.156294 -74.55185) (xy 337.899869 -74.55185) (xy 337.899869 -74.590457) (xy 337.89211 -74.644415)
			(xy 337.876751 -74.69672) (xy 337.854104 -74.746306) (xy 337.82463 -74.792164) (xy 337.788929 -74.83336)
			(xy 337.747729 -74.869056) (xy 337.701867 -74.898525) (xy 337.652278 -74.921167) (xy 337.599972 -74.93652)
			(xy 337.546013 -74.944272) (xy 337.518756 -74.944732) (xy 336.655156 -74.944732) (xy 336.627909 -74.944195)
			(xy 336.573969 -74.936434) (xy 336.521683 -74.921076) (xy 336.472114 -74.898434) (xy 336.426272 -74.868968)
			(xy 336.38509 -74.833279) (xy 336.349406 -74.792092) (xy 336.319945 -74.746247) (xy 336.297309 -74.696676)
			(xy 336.281957 -74.644388) (xy 336.274202 -74.590448) (xy 332.26684 -74.590448) (xy 332.258848 -74.59967)
			(xy 332.217646 -74.635368) (xy 332.171784 -74.664839) (xy 332.122194 -74.687482) (xy 332.069886 -74.702837)
			(xy 332.015926 -74.710591) (xy 331.988668 -74.711052) (xy 331.125068 -74.711052) (xy 331.097821 -74.710476)
			(xy 331.043883 -74.702716) (xy 330.991599 -74.68736) (xy 330.942031 -74.66472) (xy 330.89619 -74.635256)
			(xy 330.855009 -74.599569) (xy 330.819325 -74.558384) (xy 330.789865 -74.512541) (xy 330.767229 -74.462971)
			(xy 330.751877 -74.410685) (xy 330.744122 -74.356747) (xy 329.5142 -74.356747) (xy 329.5142 -76.017949)
			(xy 334.874382 -76.017949) (xy 334.874382 -75.963451) (xy 334.882137 -75.909507) (xy 334.89749 -75.857216)
			(xy 334.920128 -75.807642) (xy 334.949591 -75.761793) (xy 334.985278 -75.720605) (xy 335.026463 -75.684914)
			(xy 335.072308 -75.655447) (xy 335.12188 -75.632803) (xy 335.17417 -75.617445) (xy 335.228113 -75.609684)
			(xy 335.255362 -75.609196) (xy 336.118962 -75.609196) (xy 336.146217 -75.609649) (xy 336.200173 -75.617401)
			(xy 336.252475 -75.632754) (xy 336.302061 -75.655395) (xy 336.347919 -75.684862) (xy 336.389117 -75.720556)
			(xy 336.424815 -75.76175) (xy 336.454287 -75.807606) (xy 336.476932 -75.857189) (xy 336.49229 -75.90949)
			(xy 336.500049 -75.963445) (xy 336.500049 -76.017955) (xy 336.49229 -76.07191) (xy 336.476932 -76.124211)
			(xy 336.454287 -76.173794) (xy 336.424815 -76.21965) (xy 336.389117 -76.260844) (xy 336.347919 -76.296538)
			(xy 336.302061 -76.326005) (xy 336.252475 -76.348646) (xy 336.200173 -76.363999) (xy 336.146217 -76.371751)
			(xy 336.118962 -76.372212) (xy 335.255362 -76.372212) (xy 335.228113 -76.371716) (xy 335.17417 -76.363955)
			(xy 335.12188 -76.348597) (xy 335.072308 -76.325953) (xy 335.026463 -76.296486) (xy 334.985278 -76.260795)
			(xy 334.949591 -76.219607) (xy 334.920128 -76.173758) (xy 334.89749 -76.124184) (xy 334.882137 -76.071893)
			(xy 334.874382 -76.017949) (xy 329.5142 -76.017949) (xy 329.5142 -78.00475) (xy 330.84567 -78.00475)
			(xy 330.84567 -77.95025) (xy 330.853426 -77.896304) (xy 330.868779 -77.84401) (xy 330.891419 -77.794434)
			(xy 330.920883 -77.748584) (xy 330.956571 -77.707394) (xy 330.997759 -77.671702) (xy 331.043606 -77.642234)
			(xy 331.09318 -77.619591) (xy 331.145472 -77.604232) (xy 331.199418 -77.596472) (xy 331.226668 -77.595984)
			(xy 332.090268 -77.595984) (xy 332.117522 -77.596461) (xy 332.171475 -77.604214) (xy 332.223776 -77.619567)
			(xy 332.273359 -77.642207) (xy 332.319215 -77.671674) (xy 332.360411 -77.707367) (xy 332.396107 -77.748559)
			(xy 332.425577 -77.794413) (xy 332.448222 -77.843994) (xy 332.463579 -77.896294) (xy 332.471337 -77.950246)
			(xy 332.471337 -78.004754) (xy 332.463579 -78.058706) (xy 332.448222 -78.111006) (xy 332.425577 -78.160587)
			(xy 332.396107 -78.206441) (xy 332.360411 -78.247633) (xy 332.319215 -78.283326) (xy 332.273359 -78.312793)
			(xy 332.223776 -78.335433) (xy 332.171475 -78.350786) (xy 332.117522 -78.358539) (xy 332.090268 -78.359)
			(xy 331.226668 -78.359) (xy 331.199418 -78.358528) (xy 331.145472 -78.350768) (xy 331.09318 -78.335409)
			(xy 331.043606 -78.312766) (xy 330.997759 -78.283298) (xy 330.956571 -78.247606) (xy 330.920883 -78.206416)
			(xy 330.891419 -78.160566) (xy 330.868779 -78.11099) (xy 330.853426 -78.058696) (xy 330.84567 -78.00475)
			(xy 329.5142 -78.00475) (xy 329.5142 -80.025748) (xy 329.51674 -80.033622) (xy 329.526077 -80.063104)
			(xy 329.536165 -80.124115) (xy 329.536806 -80.155034) (xy 329.536144 -80.185951) (xy 329.526062 -80.24696)
			(xy 329.51674 -80.276446) (xy 329.5142 -80.28432) (xy 329.5142 -80.817765) (xy 333.938166 -80.817765)
			(xy 333.938166 -80.763235) (xy 333.945926 -80.70926) (xy 333.961289 -80.656938) (xy 333.98394 -80.607335)
			(xy 334.01342 -80.561461) (xy 334.049129 -80.520248) (xy 334.090338 -80.484537) (xy 334.136211 -80.455054)
			(xy 334.185812 -80.432398) (xy 334.238132 -80.417032) (xy 334.292107 -80.409268) (xy 334.319372 -80.40878)
			(xy 335.182972 -80.40878) (xy 335.210247 -80.409158) (xy 335.264243 -80.416917) (xy 335.316585 -80.432283)
			(xy 335.366207 -80.454941) (xy 335.412099 -80.484432) (xy 335.453327 -80.520153) (xy 335.489052 -80.561378)
			(xy 335.518545 -80.607268) (xy 335.541207 -80.656889) (xy 335.556577 -80.709229) (xy 335.56434 -80.763225)
			(xy 335.56434 -80.817775) (xy 335.556577 -80.871771) (xy 335.541207 -80.924111) (xy 335.518545 -80.973732)
			(xy 335.489052 -81.019622) (xy 335.453327 -81.060847) (xy 335.412099 -81.096568) (xy 335.366207 -81.126059)
			(xy 335.316585 -81.148717) (xy 335.264243 -81.164083) (xy 335.210247 -81.171842) (xy 335.182972 -81.172304)
			(xy 334.319372 -81.172304) (xy 334.292107 -81.171732) (xy 334.238132 -81.163968) (xy 334.185812 -81.148602)
			(xy 334.136211 -81.125946) (xy 334.090338 -81.096463) (xy 334.049129 -81.060752) (xy 334.01342 -81.019539)
			(xy 333.98394 -80.973665) (xy 333.961289 -80.924062) (xy 333.945926 -80.87174) (xy 333.938166 -80.817765)
			(xy 329.5142 -80.817765) (xy 329.5142 -82.06825) (xy 331.768962 -82.06825) (xy 331.768962 -82.01375)
			(xy 331.776717 -81.959803) (xy 331.792071 -81.90751) (xy 331.81471 -81.857933) (xy 331.844174 -81.812083)
			(xy 331.879862 -81.770892) (xy 331.921049 -81.735199) (xy 331.966896 -81.70573) (xy 332.01647 -81.683086)
			(xy 332.068762 -81.667726) (xy 332.122708 -81.659965) (xy 332.149958 -81.659476) (xy 333.013558 -81.659476)
			(xy 333.040812 -81.659968) (xy 333.094765 -81.66772) (xy 333.147066 -81.683072) (xy 333.196649 -81.705711)
			(xy 333.242505 -81.735177) (xy 333.283701 -81.770869) (xy 333.319398 -81.812061) (xy 333.348869 -81.857914)
			(xy 333.371513 -81.907495) (xy 333.386871 -81.959794) (xy 333.394629 -82.013746) (xy 333.394629 -82.068254)
			(xy 333.386871 -82.122206) (xy 333.371513 -82.174505) (xy 333.348869 -82.224086) (xy 333.319398 -82.269939)
			(xy 333.294774 -82.298353) (xy 336.189263 -82.298353) (xy 336.189263 -82.243847) (xy 336.197021 -82.189895)
			(xy 336.212377 -82.137597) (xy 336.235021 -82.088017) (xy 336.26449 -82.042163) (xy 336.300185 -82.000971)
			(xy 336.341379 -81.965278) (xy 336.387234 -81.935811) (xy 336.436816 -81.91317) (xy 336.489115 -81.897816)
			(xy 336.543067 -81.890062) (xy 336.57032 -81.8896) (xy 337.43392 -81.8896) (xy 337.461171 -81.890071)
			(xy 337.515118 -81.89783) (xy 337.567411 -81.913187) (xy 337.616987 -81.93583) (xy 337.662836 -81.965298)
			(xy 337.692804 -81.991267) (xy 339.478646 -81.991267) (xy 339.478646 -81.936733) (xy 339.486407 -81.882755)
			(xy 339.50177 -81.830431) (xy 339.524423 -81.780825) (xy 339.553905 -81.734948) (xy 339.589615 -81.693734)
			(xy 339.630827 -81.65802) (xy 339.676702 -81.628535) (xy 339.726306 -81.605879) (xy 339.77863 -81.590512)
			(xy 339.832607 -81.582748) (xy 339.859874 -81.58226) (xy 340.723474 -81.58226) (xy 340.750748 -81.582678)
			(xy 340.804741 -81.590437) (xy 340.857079 -81.605802) (xy 340.906699 -81.62846) (xy 340.952588 -81.657948)
			(xy 340.993814 -81.693668) (xy 341.029536 -81.734891) (xy 341.059028 -81.780778) (xy 341.081689 -81.830396)
			(xy 341.097057 -81.882734) (xy 341.10482 -81.936726) (xy 341.10482 -81.991274) (xy 341.097057 -82.045266)
			(xy 341.081689 -82.097604) (xy 341.059028 -82.147222) (xy 341.029536 -82.193109) (xy 340.993814 -82.234332)
			(xy 340.952588 -82.270052) (xy 340.906699 -82.29954) (xy 340.857079 -82.322198) (xy 340.804741 -82.337563)
			(xy 340.750748 -82.345322) (xy 340.723474 -82.345784) (xy 339.859874 -82.345784) (xy 339.832607 -82.345252)
			(xy 339.77863 -82.337488) (xy 339.726306 -82.322121) (xy 339.676702 -82.299465) (xy 339.630827 -82.26998)
			(xy 339.589615 -82.234266) (xy 339.553905 -82.193052) (xy 339.524423 -82.147175) (xy 339.50177 -82.097569)
			(xy 339.486407 -82.045245) (xy 339.478646 -81.991267) (xy 337.692804 -81.991267) (xy 337.704024 -82.00099)
			(xy 337.739714 -82.04218) (xy 337.76918 -82.088031) (xy 337.79182 -82.137608) (xy 337.807174 -82.189902)
			(xy 337.81493 -82.243849) (xy 337.81493 -82.298351) (xy 337.807174 -82.352298) (xy 337.79182 -82.404592)
			(xy 337.769179 -82.454169) (xy 337.739714 -82.50002) (xy 337.704024 -82.54121) (xy 337.662836 -82.576902)
			(xy 337.616987 -82.60637) (xy 337.567411 -82.629013) (xy 337.515118 -82.64437) (xy 337.461171 -82.652129)
			(xy 337.43392 -82.652616) (xy 336.57032 -82.652616) (xy 336.543067 -82.652138) (xy 336.489115 -82.644384)
			(xy 336.436816 -82.62903) (xy 336.387234 -82.606389) (xy 336.341379 -82.576922) (xy 336.300185 -82.541229)
			(xy 336.26449 -82.500037) (xy 336.235021 -82.454183) (xy 336.212377 -82.404603) (xy 336.197021 -82.352305)
			(xy 336.189263 -82.298353) (xy 333.294774 -82.298353) (xy 333.283701 -82.311131) (xy 333.242505 -82.346823)
			(xy 333.196649 -82.376289) (xy 333.147066 -82.398928) (xy 333.094765 -82.41428) (xy 333.040812 -82.422032)
			(xy 333.013558 -82.422492) (xy 332.149958 -82.422492) (xy 332.122708 -82.422035) (xy 332.068762 -82.414274)
			(xy 332.01647 -82.398914) (xy 331.966896 -82.37627) (xy 331.921049 -82.346801) (xy 331.879862 -82.311108)
			(xy 331.844174 -82.269917) (xy 331.81471 -82.224067) (xy 331.792071 -82.17449) (xy 331.776717 -82.122197)
			(xy 331.768962 -82.06825) (xy 329.5142 -82.06825) (xy 329.5142 -82.258408) (xy 329.513588 -82.283364)
			(xy 329.503849 -82.332318) (xy 329.484747 -82.37843) (xy 329.457016 -82.41993) (xy 329.439778 -82.437986)
			(xy 328.289293 -83.588471) (xy 341.356398 -83.588471) (xy 341.356398 -83.533929) (xy 341.364161 -83.479942)
			(xy 341.379527 -83.427609) (xy 341.402184 -83.377996) (xy 341.431672 -83.332112) (xy 341.467389 -83.290892)
			(xy 341.508609 -83.255174) (xy 341.554492 -83.225686) (xy 341.604106 -83.203028) (xy 341.656438 -83.187661)
			(xy 341.710425 -83.179899) (xy 341.737696 -83.179412) (xy 342.601296 -83.179412) (xy 342.628565 -83.179927)
			(xy 342.682549 -83.187688) (xy 342.734879 -83.203053) (xy 342.784489 -83.225709) (xy 342.83037 -83.255194)
			(xy 342.871588 -83.290909) (xy 342.907303 -83.332127) (xy 342.936789 -83.378008) (xy 342.959445 -83.427618)
			(xy 342.974811 -83.479947) (xy 342.982573 -83.533931) (xy 342.982573 -83.588469) (xy 342.974811 -83.642453)
			(xy 342.959445 -83.694782) (xy 342.936789 -83.744392) (xy 342.907303 -83.790273) (xy 342.871588 -83.831491)
			(xy 342.83037 -83.867206) (xy 342.784489 -83.896691) (xy 342.734879 -83.919347) (xy 342.682549 -83.934712)
			(xy 342.628565 -83.942473) (xy 342.601296 -83.942936) (xy 341.737696 -83.942936) (xy 341.710425 -83.942501)
			(xy 341.656438 -83.934739) (xy 341.604106 -83.919372) (xy 341.554492 -83.896714) (xy 341.508609 -83.867226)
			(xy 341.467389 -83.831508) (xy 341.431672 -83.790288) (xy 341.402184 -83.744404) (xy 341.379527 -83.694791)
			(xy 341.364161 -83.642458) (xy 341.356398 -83.588471) (xy 328.289293 -83.588471) (xy 327.727818 -84.149946)
			(xy 327.709776 -84.167203) (xy 327.668281 -84.194953) (xy 327.622163 -84.21406) (xy 327.5732 -84.223784)
			(xy 327.54824 -84.224368) (xy 274.03552 -84.224368) (xy 274.010567 -84.223749) (xy 273.961622 -84.213997)
			(xy 273.91552 -84.194884) (xy 273.874033 -84.167145) (xy 273.855942 -84.149946) (xy 272.057622 -82.351626)
			(xy 272.040361 -82.333586) (xy 272.012602 -82.292093) (xy 271.993489 -82.245974) (xy 271.98376 -82.197009)
			(xy 271.9832 -82.172048) (xy 271.9832 -77.311504) (xy 271.725644 -77.053948) (xy 258.303268 -77.053948)
			(xy 258.289806 -77.08392) (xy 258.278121 -77.108661) (xy 258.248716 -77.154802) (xy 258.213021 -77.196269)
			(xy 258.171769 -77.232212) (xy 258.125804 -77.261893) (xy 258.076072 -77.284704) (xy 258.02359 -77.300176)
			(xy 257.969437 -77.307992) (xy 257.914723 -77.307992) (xy 257.86057 -77.300176) (xy 257.808088 -77.284704)
			(xy 257.758356 -77.261893) (xy 257.712391 -77.232212) (xy 257.671139 -77.196269) (xy 257.635444 -77.154802)
			(xy 257.606039 -77.108661) (xy 257.594354 -77.08392) (xy 257.580892 -77.053948) (xy 238.765842 -77.053948)
			(xy 238.751273 -77.054455) (xy 238.723337 -77.062748) (xy 238.698876 -77.078586) (xy 238.679878 -77.100682)
			(xy 238.667886 -77.127241) (xy 238.663875 -77.156105) (xy 238.668171 -77.184927) (xy 238.680424 -77.211366)
			(xy 238.69964 -77.233274) (xy 238.71174 -77.2414) (xy 238.797916 -77.296332) (xy 238.966439 -77.41198)
			(xy 239.130353 -77.534073) (xy 239.28941 -77.662429) (xy 239.443372 -77.796854) (xy 239.592007 -77.937147)
			(xy 239.735091 -78.083096) (xy 239.872411 -78.234483) (xy 240.003758 -78.391079) (xy 240.128936 -78.552649)
			(xy 240.247756 -78.71895) (xy 240.36004 -78.889733) (xy 240.465619 -79.06474) (xy 240.564335 -79.243708)
			(xy 240.656038 -79.426369) (xy 240.740592 -79.612447) (xy 240.817868 -79.801664) (xy 240.887751 -79.993733)
			(xy 240.950135 -80.188368) (xy 241.004928 -80.385274) (xy 241.052046 -80.584157) (xy 241.091419 -80.784717)
			(xy 241.122987 -80.986652) (xy 241.146703 -81.189659) (xy 241.162531 -81.393434) (xy 241.170448 -81.597668)
			(xy 241.170968 -81.699862) (xy 241.170472 -81.802088) (xy 241.162545 -82.006387) (xy 241.146701 -82.210225)
			(xy 241.122965 -82.413296) (xy 241.091374 -82.615293) (xy 241.051973 -82.815913) (xy 241.004823 -83.014855)
			(xy 240.949994 -83.211819) (xy 240.88757 -83.406509) (xy 240.817643 -83.598632) (xy 240.740319 -83.787898)
			(xy 240.655714 -83.974025) (xy 240.563956 -84.15673) (xy 240.465182 -84.335741) (xy 240.359541 -84.510786)
			(xy 240.358902 -84.511757) (xy 337.882119 -84.511757) (xy 337.882119 -84.457243) (xy 337.889878 -84.403284)
			(xy 337.905237 -84.350979) (xy 337.927883 -84.301392) (xy 337.957357 -84.255533) (xy 337.993057 -84.214336)
			(xy 338.034257 -84.178639) (xy 338.080119 -84.149169) (xy 338.129707 -84.126526) (xy 338.182014 -84.111171)
			(xy 338.235973 -84.103417) (xy 338.26323 -84.102956) (xy 339.12683 -84.102956) (xy 339.154077 -84.103516)
			(xy 339.208017 -84.111275) (xy 339.260303 -84.126632) (xy 339.309871 -84.149272) (xy 339.355714 -84.178737)
			(xy 339.396896 -84.214425) (xy 339.432581 -84.25561) (xy 339.462042 -84.301455) (xy 339.484679 -84.351025)
			(xy 339.500031 -84.403313) (xy 339.503159 -84.425069) (xy 344.644951 -84.425069) (xy 344.644951 -84.370531)
			(xy 344.652713 -84.316548) (xy 344.668079 -84.26422) (xy 344.690737 -84.214611) (xy 344.720223 -84.168731)
			(xy 344.75594 -84.127516) (xy 344.797159 -84.091803) (xy 344.843041 -84.06232) (xy 344.892652 -84.039668)
			(xy 344.944981 -84.024306) (xy 344.998965 -84.016549) (xy 345.026234 -84.016088) (xy 345.889834 -84.016088)
			(xy 345.917105 -84.016477) (xy 345.971092 -84.024243) (xy 346.023425 -84.039614) (xy 346.073037 -84.062275)
			(xy 346.11892 -84.091766) (xy 346.160139 -84.127485) (xy 346.195855 -84.168708) (xy 346.225341 -84.214593)
			(xy 346.247998 -84.264207) (xy 346.263364 -84.316541) (xy 346.271126 -84.370529) (xy 346.271126 -84.425071)
			(xy 346.263364 -84.479059) (xy 346.247998 -84.531393) (xy 346.225341 -84.581007) (xy 346.195855 -84.626892)
			(xy 346.160139 -84.668115) (xy 346.11892 -84.703834) (xy 346.073037 -84.733325) (xy 346.023425 -84.755986)
			(xy 345.971092 -84.771357) (xy 345.917105 -84.779123) (xy 345.889834 -84.779612) (xy 345.026234 -84.779612)
			(xy 344.998965 -84.779051) (xy 344.944981 -84.771294) (xy 344.892652 -84.755932) (xy 344.843041 -84.73328)
			(xy 344.797159 -84.703797) (xy 344.75594 -84.668084) (xy 344.720223 -84.626869) (xy 344.690737 -84.580989)
			(xy 344.668079 -84.53138) (xy 344.652713 -84.479052) (xy 344.644951 -84.425069) (xy 339.503159 -84.425069)
			(xy 339.507786 -84.457253) (xy 339.507786 -84.511747) (xy 339.500031 -84.565687) (xy 339.484679 -84.617975)
			(xy 339.462042 -84.667545) (xy 339.432581 -84.71339) (xy 339.396896 -84.754575) (xy 339.355714 -84.790263)
			(xy 339.309871 -84.819728) (xy 339.260303 -84.842368) (xy 339.208017 -84.857725) (xy 339.154077 -84.865484)
			(xy 339.12683 -84.865972) (xy 338.26323 -84.865972) (xy 338.235973 -84.865583) (xy 338.182014 -84.857829)
			(xy 338.129707 -84.842474) (xy 338.080119 -84.819831) (xy 338.034257 -84.790361) (xy 337.993057 -84.754664)
			(xy 337.957357 -84.713467) (xy 337.927883 -84.667608) (xy 337.905237 -84.618021) (xy 337.889878 -84.565716)
			(xy 337.882119 -84.511757) (xy 240.358902 -84.511757) (xy 240.247193 -84.681604) (xy 240.128305 -84.847937)
			(xy 240.003057 -85.009535) (xy 239.871637 -85.166155) (xy 239.734243 -85.317562) (xy 239.591082 -85.463526)
			(xy 239.442368 -85.60383) (xy 239.288326 -85.738263) (xy 239.162975 -85.839368) (xy 342.975946 -85.839368)
			(xy 342.975946 -85.784832) (xy 342.983708 -85.730852) (xy 342.999072 -85.678525) (xy 343.021727 -85.628918)
			(xy 343.051211 -85.58304) (xy 343.086924 -85.541824) (xy 343.12814 -85.506111) (xy 343.174018 -85.476627)
			(xy 343.223625 -85.453972) (xy 343.275952 -85.438608) (xy 343.329932 -85.430846) (xy 343.3572 -85.43036)
			(xy 344.2208 -85.43036) (xy 344.248071 -85.430802) (xy 344.302058 -85.438565) (xy 344.35439 -85.453931)
			(xy 344.404003 -85.476588) (xy 344.449887 -85.506076) (xy 344.491107 -85.541793) (xy 344.526824 -85.583013)
			(xy 344.556312 -85.628897) (xy 344.578969 -85.67851) (xy 344.594335 -85.730842) (xy 344.602098 -85.784829)
			(xy 344.602098 -85.839371) (xy 344.594335 -85.893358) (xy 344.578969 -85.94569) (xy 344.556312 -85.995303)
			(xy 344.526824 -86.041187) (xy 344.491107 -86.082407) (xy 344.449887 -86.118124) (xy 344.404003 -86.147612)
			(xy 344.35439 -86.170269) (xy 344.302058 -86.185635) (xy 344.248071 -86.193398) (xy 344.2208 -86.193884)
			(xy 343.3572 -86.193884) (xy 343.329932 -86.193354) (xy 343.275952 -86.185592) (xy 343.223625 -86.170228)
			(xy 343.174018 -86.147573) (xy 343.12814 -86.118089) (xy 343.086924 -86.082376) (xy 343.051211 -86.04116)
			(xy 343.021727 -85.995282) (xy 342.999072 -85.945675) (xy 342.983708 -85.893348) (xy 342.975946 -85.839368)
			(xy 239.162975 -85.839368) (xy 239.129188 -85.86662) (xy 238.965191 -85.988711) (xy 238.796584 -86.104351)
			(xy 238.62362 -86.213366) (xy 238.446558 -86.315593) (xy 238.265666 -86.410877) (xy 238.081216 -86.499075)
			(xy 237.893484 -86.580054) (xy 237.702753 -86.653694) (xy 237.509311 -86.719882) (xy 237.313447 -86.77852)
			(xy 237.115457 -86.829519) (xy 236.915638 -86.872802) (xy 236.714292 -86.908305) (xy 236.51172 -86.935974)
			(xy 236.308227 -86.955767) (xy 236.10412 -86.967655) (xy 235.899706 -86.97162) (xy 235.695292 -86.967655)
			(xy 235.491185 -86.955767) (xy 235.287692 -86.935974) (xy 235.08512 -86.908305) (xy 234.883774 -86.872802)
			(xy 234.683955 -86.829519) (xy 234.485965 -86.77852) (xy 234.290101 -86.719882) (xy 234.096659 -86.653694)
			(xy 233.905928 -86.580054) (xy 233.718196 -86.499075) (xy 233.533746 -86.410877) (xy 233.352854 -86.315593)
			(xy 233.175792 -86.213366) (xy 233.002828 -86.104351) (xy 232.834221 -85.988711) (xy 232.670224 -85.86662)
			(xy 232.511086 -85.738263) (xy 232.357044 -85.60383) (xy 232.20833 -85.463526) (xy 232.065169 -85.317562)
			(xy 231.927775 -85.166155) (xy 231.796355 -85.009535) (xy 231.671107 -84.847937) (xy 231.552219 -84.681604)
			(xy 231.439871 -84.510786) (xy 231.33423 -84.335741) (xy 231.235456 -84.15673) (xy 231.143698 -83.974025)
			(xy 231.059093 -83.787898) (xy 230.981769 -83.598632) (xy 230.911842 -83.406509) (xy 230.849418 -83.211819)
			(xy 230.794589 -83.014855) (xy 230.747439 -82.815913) (xy 230.708038 -82.615293) (xy 230.676447 -82.413296)
			(xy 230.652711 -82.210225) (xy 230.636867 -82.006387) (xy 230.62894 -81.802088) (xy 230.628444 -81.699862)
			(xy 230.62894 -81.597668) (xy 230.636864 -81.393435) (xy 230.652699 -81.189662) (xy 230.676422 -80.986656)
			(xy 230.707995 -80.784722) (xy 230.747373 -80.584164) (xy 230.794495 -80.385284) (xy 230.849292 -80.188379)
			(xy 230.91168 -79.993746) (xy 230.981565 -79.801678) (xy 231.058844 -79.612464) (xy 231.143399 -79.426387)
			(xy 231.235104 -79.243728) (xy 231.33382 -79.06476) (xy 231.439399 -78.889754) (xy 231.551683 -78.718973)
			(xy 231.670503 -78.552672) (xy 231.79568 -78.391102) (xy 231.927025 -78.234505) (xy 232.064343 -78.083118)
			(xy 232.207425 -77.937168) (xy 232.356058 -77.796873) (xy 232.510017 -77.662446) (xy 232.669071 -77.534088)
			(xy 232.832982 -77.411991) (xy 233.001502 -77.296341) (xy 233.087672 -77.2414) (xy 233.099718 -77.233211)
			(xy 233.118916 -77.21132) (xy 233.131158 -77.184902) (xy 233.13545 -77.156103) (xy 233.131442 -77.127263)
			(xy 233.11946 -77.100726) (xy 233.100479 -77.078647) (xy 233.076039 -77.06282) (xy 233.048127 -77.054531)
			(xy 233.03357 -77.053948) (xy 213.09076 -77.053948) (xy 213.065802 -77.053373) (xy 213.016845 -77.043626)
			(xy 212.970732 -77.024513) (xy 212.929234 -76.996771) (xy 212.911182 -76.979526) (xy 210.665822 -74.734166)
			(xy 210.65236 -74.73061) (xy 210.625514 -74.723063) (xy 210.574194 -74.701249) (xy 210.526596 -74.672197)
			(xy 210.483734 -74.636525) (xy 210.446522 -74.594994) (xy 210.415752 -74.548487) (xy 210.39208 -74.497997)
			(xy 210.376011 -74.444599) (xy 210.367886 -74.38943) (xy 210.367372 -74.361548) (xy 210.36749 -74.346178)
			(xy 210.369902 -74.315532) (xy 210.372198 -74.300334) (xy 210.37296 -74.29627) (xy 210.37296 -71.357998)
			(xy 210.363174 -71.33415) (xy 210.349386 -71.284479) (xy 210.342412 -71.233404) (xy 210.341972 -71.20763)
			(xy 210.342415 -71.181856) (xy 210.34939 -71.130782) (xy 210.363176 -71.081111) (xy 210.37296 -71.057262)
			(xy 210.37296 -70.566026) (xy 210.372198 -70.561962) (xy 210.369917 -70.546762) (xy 210.367502 -70.516118)
			(xy 210.367372 -70.500748) (xy 210.36749 -70.485378) (xy 210.369902 -70.454732) (xy 210.372198 -70.439534)
			(xy 210.37296 -70.43547) (xy 210.37296 -67.311778) (xy 210.371182 -67.305174) (xy 210.364672 -67.280214)
			(xy 210.357662 -67.229111) (xy 210.357212 -67.20332) (xy 210.357674 -67.17753) (xy 210.364683 -67.126428)
			(xy 210.371182 -67.101466) (xy 210.37296 -67.094862) (xy 210.37296 -61.533024) (xy 209.231484 -60.391548)
			(xy 171.50715 -60.391548) (xy 171.5008 -60.435236) (xy 171.496537 -60.462211) (xy 171.4813 -60.514655)
			(xy 171.458739 -60.564389) (xy 171.429315 -60.610397) (xy 171.39363 -60.651738) (xy 171.352413 -60.687567)
			(xy 171.306508 -60.717151) (xy 171.256852 -60.739885) (xy 171.204462 -60.755304) (xy 171.150408 -60.763093)
			(xy 171.095796 -60.763093) (xy 171.041742 -60.755304) (xy 170.989352 -60.739885) (xy 170.939696 -60.717151)
			(xy 170.893791 -60.687567) (xy 170.852574 -60.651738) (xy 170.816889 -60.610397) (xy 170.787465 -60.564389)
			(xy 170.764904 -60.514655) (xy 170.749667 -60.462211) (xy 170.745404 -60.435236) (xy 170.739054 -60.391548)
			(xy 164.7444 -60.391548) (xy 164.71944 -60.390977) (xy 164.670479 -60.381236) (xy 164.624361 -60.362129)
			(xy 164.582857 -60.33439) (xy 164.564822 -60.317126) (xy 161.491422 -57.243726) (xy 161.474161 -57.225686)
			(xy 161.446402 -57.184193) (xy 161.427289 -57.138074) (xy 161.41756 -57.089109) (xy 161.417 -57.064148)
			(xy 161.417 -32.582104) (xy 160.473644 -31.638748) (xy 152.36063 -31.638748) (xy 152.347676 -31.66999)
			(xy 152.336383 -31.695579) (xy 152.307403 -31.743417) (xy 152.271747 -31.786509) (xy 152.230179 -31.823931)
			(xy 152.183591 -31.854879) (xy 152.132981 -31.878691) (xy 152.079437 -31.894855) (xy 152.024106 -31.903025)
			(xy 151.968174 -31.903025) (xy 151.912843 -31.894855) (xy 151.859299 -31.878691) (xy 151.808689 -31.854879)
			(xy 151.762101 -31.823931) (xy 151.720533 -31.786509) (xy 151.684877 -31.743417) (xy 151.655897 -31.695579)
			(xy 151.644604 -31.66999) (xy 151.63165 -31.638748) (xy 97.719896 -31.638748) (xy 97.694496 -31.664148)
			(xy 97.69094 -31.677356) (xy 97.683016 -31.704665) (xy 97.660198 -31.756747) (xy 97.629903 -31.804867)
			(xy 97.592802 -31.847957) (xy 97.549718 -31.885065) (xy 97.501604 -31.915368) (xy 97.449525 -31.938195)
			(xy 97.422208 -31.946088) (xy 97.409 -31.949644) (xy 91.693238 -37.665406) (xy 91.675197 -37.682666)
			(xy 91.633704 -37.710424) (xy 91.587586 -37.729537) (xy 91.538621 -37.739268) (xy 91.51366 -37.739828)
			(xy 87.955628 -37.739828) (xy 87.947754 -37.780976) (xy 87.942051 -37.808143) (xy 87.923834 -37.860579)
			(xy 87.89821 -37.90982) (xy 87.865718 -37.954826) (xy 87.827046 -37.994648) (xy 87.78301 -38.028444)
			(xy 87.73454 -38.0555) (xy 87.68266 -38.075244) (xy 87.628467 -38.08726) (xy 87.573104 -38.091294)
			(xy 87.517741 -38.08726) (xy 87.463548 -38.075244) (xy 87.411668 -38.0555) (xy 87.363198 -38.028444)
			(xy 87.319162 -37.994648) (xy 87.28049 -37.954826) (xy 87.247998 -37.90982) (xy 87.222374 -37.860579)
			(xy 87.204157 -37.808143) (xy 87.198454 -37.780976) (xy 87.19058 -37.739828) (xy 32.708596 -37.739828)
			(xy 25.46096 -44.987464) (xy 25.46096 -47.049813) (xy 59.781451 -47.049813) (xy 59.785436 -46.895317)
			(xy 59.79737 -46.74123) (xy 59.817219 -46.587962) (xy 59.844933 -46.43592) (xy 59.880436 -46.285505)
			(xy 59.923635 -46.137118) (xy 59.974415 -45.991151) (xy 60.032642 -45.847991) (xy 60.098162 -45.708019)
			(xy 60.1708 -45.571605) (xy 60.250363 -45.439111) (xy 60.336642 -45.310889) (xy 60.429407 -45.187278)
			(xy 60.528412 -45.068606) (xy 60.633395 -44.955188) (xy 60.744077 -44.847324) (xy 60.860165 -44.745302)
			(xy 60.981351 -44.64939) (xy 61.107313 -44.559844) (xy 61.237718 -44.476901) (xy 61.37222 -44.400781)
			(xy 61.510462 -44.331685) (xy 61.652077 -44.269798) (xy 61.796691 -44.215282) (xy 61.943919 -44.168283)
			(xy 62.093371 -44.128926) (xy 62.244652 -44.097314) (xy 62.397358 -44.073531) (xy 62.551087 -44.057641)
			(xy 62.70543 -44.049685) (xy 62.782704 -44.049188) (xy 64.383158 -44.049188) (xy 64.461004 -44.049716)
			(xy 64.616485 -44.057793) (xy 64.771339 -44.073923) (xy 64.925148 -44.098061) (xy 65.077498 -44.130145)
			(xy 65.227979 -44.170085) (xy 65.376186 -44.217777) (xy 65.52172 -44.27309) (xy 65.66419 -44.335876)
			(xy 65.803212 -44.405966) (xy 65.938412 -44.483172) (xy 66.069427 -44.567285) (xy 66.195902 -44.65808)
			(xy 66.317499 -44.755312) (xy 66.43389 -44.858719) (xy 66.544761 -44.968023) (xy 66.649815 -45.08293)
			(xy 66.748768 -45.20313) (xy 66.841354 -45.3283) (xy 66.927324 -45.458104) (xy 67.006447 -45.592191)
			(xy 67.07851 -45.730201) (xy 67.111372 -45.800772) (xy 67.117919 -45.814089) (xy 67.137463 -45.836407)
			(xy 67.162592 -45.852176) (xy 67.191189 -45.860067) (xy 67.220848 -45.859416) (xy 67.249072 -45.850279)
			(xy 67.273485 -45.833424) (xy 67.292032 -45.81027) (xy 67.298062 -45.796708) (xy 67.329489 -45.72075)
			(xy 67.398808 -45.571676) (xy 67.475398 -45.426204) (xy 67.559074 -45.284688) (xy 67.64963 -45.147475)
			(xy 67.746848 -45.014897) (xy 67.850489 -44.887277) (xy 67.960301 -44.764928) (xy 68.076018 -44.648146)
			(xy 68.197355 -44.537217) (xy 68.324019 -44.432411) (xy 68.455701 -44.333982) (xy 68.592079 -44.242172)
			(xy 68.732821 -44.157203) (xy 68.877585 -44.079283) (xy 69.026018 -44.008601) (xy 69.177757 -43.945329)
			(xy 69.332434 -43.889623) (xy 69.489672 -43.841617) (xy 69.649086 -43.801429) (xy 69.81029 -43.769156)
			(xy 69.97289 -43.744877) (xy 70.13649 -43.728652) (xy 70.300691 -43.720519) (xy 70.382892 -43.720004)
			(xy 70.464625 -43.720498) (xy 70.627895 -43.728519) (xy 70.790574 -43.744541) (xy 70.952271 -43.768527)
			(xy 71.112596 -43.800418) (xy 71.271164 -43.840137) (xy 71.427591 -43.887589) (xy 71.581502 -43.942659)
			(xy 71.732525 -44.005215) (xy 71.880297 -44.075106) (xy 72.024462 -44.152163) (xy 72.164671 -44.236202)
			(xy 72.300589 -44.327019) (xy 72.431886 -44.424396) (xy 72.558247 -44.528098) (xy 72.679368 -44.637875)
			(xy 72.794956 -44.753463) (xy 72.904733 -44.874584) (xy 73.008435 -45.000945) (xy 73.105812 -45.132243)
			(xy 73.196629 -45.26816) (xy 73.280668 -45.40837) (xy 73.357725 -45.552535) (xy 73.427616 -45.700306)
			(xy 73.490172 -45.85133) (xy 73.545242 -46.00524) (xy 73.592694 -46.161668) (xy 73.632413 -46.320236)
			(xy 73.664304 -46.480561) (xy 73.688289 -46.642258) (xy 73.704312 -46.804937) (xy 73.712332 -46.968207)
			(xy 73.712332 -47.04994) (xy 89.78165 -47.04994) (xy 89.78563 -46.895439) (xy 89.797557 -46.741349)
			(xy 89.817402 -46.588076) (xy 89.84511 -46.436028) (xy 89.880608 -46.285609) (xy 89.923803 -46.137216)
			(xy 89.97458 -45.991243) (xy 90.032804 -45.848078) (xy 90.098321 -45.708101) (xy 90.170957 -45.571681)
			(xy 90.250519 -45.439181) (xy 90.336796 -45.310953) (xy 90.42956 -45.187337) (xy 90.528565 -45.068659)
			(xy 90.633548 -44.955236) (xy 90.74423 -44.847368) (xy 90.860319 -44.74534) (xy 90.981506 -44.649424)
			(xy 91.10747 -44.559873) (xy 91.237877 -44.476926) (xy 91.372381 -44.400801) (xy 91.510626 -44.331702)
			(xy 91.652244 -44.269811) (xy 91.796861 -44.215293) (xy 91.944092 -44.168291) (xy 92.093548 -44.128931)
			(xy 92.244832 -44.097317) (xy 92.397543 -44.073533) (xy 92.551275 -44.057642) (xy 92.705622 -44.049686)
			(xy 92.782898 -44.049188) (xy 94.383098 -44.049188) (xy 94.460945 -44.049695) (xy 94.61643 -44.057764)
			(xy 94.771287 -44.073884) (xy 94.9251 -44.098013) (xy 95.077454 -44.130086) (xy 95.227941 -44.170016)
			(xy 95.376154 -44.217696) (xy 95.521696 -44.272997) (xy 95.664174 -44.335772) (xy 95.803205 -44.40585)
			(xy 95.938415 -44.483043) (xy 96.06944 -44.567145) (xy 96.195928 -44.657927) (xy 96.317538 -44.755147)
			(xy 96.433943 -44.858542) (xy 96.544829 -44.967834) (xy 96.649899 -45.082729) (xy 96.74887 -45.202918)
			(xy 96.841474 -45.328078) (xy 96.927464 -45.457871) (xy 97.006608 -45.591949) (xy 97.078692 -45.729951)
			(xy 97.111566 -45.800518) (xy 97.118214 -45.813727) (xy 97.137759 -45.835901) (xy 97.162829 -45.851559)
			(xy 97.19133 -45.859393) (xy 97.220881 -45.858749) (xy 97.249013 -45.84968) (xy 97.273377 -45.832945)
			(xy 97.291937 -45.809941) (xy 97.298002 -45.796454) (xy 97.329371 -45.720474) (xy 97.398691 -45.571403)
			(xy 97.475283 -45.425935) (xy 97.55896 -45.284424) (xy 97.64952 -45.147215) (xy 97.74674 -45.014643)
			(xy 97.850385 -44.88703) (xy 97.960201 -44.764687) (xy 98.075921 -44.647913) (xy 98.197263 -44.536993)
			(xy 98.323931 -44.432196) (xy 98.455617 -44.333778) (xy 98.592 -44.241978) (xy 98.732746 -44.157021)
			(xy 98.877514 -44.079114) (xy 99.02595 -44.008446) (xy 99.177693 -43.945189) (xy 99.332373 -43.889499)
			(xy 99.489612 -43.84151) (xy 99.649029 -43.801339) (xy 99.810234 -43.769085) (xy 99.972834 -43.744825)
			(xy 100.136433 -43.72862) (xy 100.300632 -43.720508) (xy 100.382832 -43.720004) (xy 100.464565 -43.720498)
			(xy 100.627835 -43.728519) (xy 100.790514 -43.744541) (xy 100.952211 -43.768527) (xy 101.112536 -43.800418)
			(xy 101.271104 -43.840137) (xy 101.427531 -43.887589) (xy 101.581442 -43.942659) (xy 101.732465 -44.005215)
			(xy 101.880237 -44.075106) (xy 102.024402 -44.152163) (xy 102.164611 -44.236202) (xy 102.300529 -44.327019)
			(xy 102.431826 -44.424396) (xy 102.558187 -44.528098) (xy 102.679308 -44.637875) (xy 102.794896 -44.753463)
			(xy 102.904673 -44.874584) (xy 103.008375 -45.000945) (xy 103.105752 -45.132243) (xy 103.196569 -45.26816)
			(xy 103.280608 -45.40837) (xy 103.357665 -45.552535) (xy 103.404915 -45.652436) (xy 155.97378 -45.652436)
			(xy 155.97378 -44.788836) (xy 155.974266 -44.761567) (xy 155.982028 -44.707583) (xy 155.997393 -44.655253)
			(xy 156.02005 -44.605643) (xy 156.049536 -44.559762) (xy 156.085251 -44.518545) (xy 156.126468 -44.48283)
			(xy 156.172349 -44.453344) (xy 156.221959 -44.430687) (xy 156.274289 -44.415322) (xy 156.328273 -44.40756)
			(xy 156.382811 -44.40756) (xy 156.436795 -44.415322) (xy 156.489125 -44.430687) (xy 156.538735 -44.453344)
			(xy 156.584616 -44.48283) (xy 156.625833 -44.518545) (xy 156.661548 -44.559762) (xy 156.691034 -44.605643)
			(xy 156.713691 -44.655253) (xy 156.72159 -44.682156) (xy 159.179768 -44.682156) (xy 159.179768 -43.818556)
			(xy 159.180254 -43.791287) (xy 159.188016 -43.737303) (xy 159.203381 -43.684973) (xy 159.226038 -43.635363)
			(xy 159.255524 -43.589482) (xy 159.291239 -43.548265) (xy 159.332456 -43.51255) (xy 159.378337 -43.483064)
			(xy 159.427947 -43.460407) (xy 159.480277 -43.445042) (xy 159.534261 -43.43728) (xy 159.588799 -43.43728)
			(xy 159.642783 -43.445042) (xy 159.695113 -43.460407) (xy 159.744723 -43.483064) (xy 159.790604 -43.51255)
			(xy 159.831821 -43.548265) (xy 159.867536 -43.589482) (xy 159.897022 -43.635363) (xy 159.919679 -43.684973)
			(xy 159.935044 -43.737303) (xy 159.942806 -43.791287) (xy 159.943292 -43.818556) (xy 159.943292 -44.682156)
			(xy 159.942806 -44.709425) (xy 159.935044 -44.763409) (xy 159.919679 -44.815739) (xy 159.897022 -44.865349)
			(xy 159.867536 -44.91123) (xy 159.831821 -44.952447) (xy 159.790604 -44.988162) (xy 159.744723 -45.017648)
			(xy 159.695113 -45.040305) (xy 159.642783 -45.05567) (xy 159.588799 -45.063432) (xy 159.534261 -45.063432)
			(xy 159.480277 -45.05567) (xy 159.427947 -45.040305) (xy 159.378337 -45.017648) (xy 159.332456 -44.988162)
			(xy 159.291239 -44.952447) (xy 159.255524 -44.91123) (xy 159.226038 -44.865349) (xy 159.203381 -44.815739)
			(xy 159.188016 -44.763409) (xy 159.180254 -44.709425) (xy 159.179768 -44.682156) (xy 156.72159 -44.682156)
			(xy 156.729056 -44.707583) (xy 156.736818 -44.761567) (xy 156.737304 -44.788836) (xy 156.737304 -45.652436)
			(xy 156.736818 -45.679705) (xy 156.729056 -45.733689) (xy 156.713691 -45.786019) (xy 156.691034 -45.835629)
			(xy 156.661548 -45.88151) (xy 156.625833 -45.922727) (xy 156.584616 -45.958442) (xy 156.538735 -45.987928)
			(xy 156.489125 -46.010585) (xy 156.436795 -46.02595) (xy 156.382811 -46.033712) (xy 156.328273 -46.033712)
			(xy 156.274289 -46.02595) (xy 156.221959 -46.010585) (xy 156.172349 -45.987928) (xy 156.126468 -45.958442)
			(xy 156.085251 -45.922727) (xy 156.049536 -45.88151) (xy 156.02005 -45.835629) (xy 155.997393 -45.786019)
			(xy 155.982028 -45.733689) (xy 155.974266 -45.679705) (xy 155.97378 -45.652436) (xy 103.404915 -45.652436)
			(xy 103.427556 -45.700306) (xy 103.490112 -45.85133) (xy 103.545182 -46.00524) (xy 103.592634 -46.161668)
			(xy 103.632353 -46.320236) (xy 103.664244 -46.480561) (xy 103.688229 -46.642258) (xy 103.704252 -46.804937)
			(xy 103.712272 -46.968207) (xy 103.712272 -47.131673) (xy 103.704252 -47.294943) (xy 103.688229 -47.457622)
			(xy 103.664244 -47.619319) (xy 103.632353 -47.779644) (xy 103.592634 -47.938212) (xy 103.582915 -47.97025)
			(xy 155.567386 -47.97025) (xy 155.567386 -47.91575) (xy 155.575142 -47.861805) (xy 155.590495 -47.809513)
			(xy 155.613135 -47.759938) (xy 155.642598 -47.71409) (xy 155.678287 -47.672901) (xy 155.719474 -47.63721)
			(xy 155.765321 -47.607744) (xy 155.814895 -47.585102) (xy 155.867186 -47.569746) (xy 155.92113 -47.561987)
			(xy 155.94838 -47.5615) (xy 156.81198 -47.5615) (xy 156.839234 -47.561946) (xy 156.893189 -47.569701)
			(xy 156.94549 -47.585055) (xy 156.995074 -47.607697) (xy 157.04093 -47.637165) (xy 157.082126 -47.67286)
			(xy 157.117823 -47.714054) (xy 157.147293 -47.759909) (xy 157.169938 -47.809491) (xy 157.185295 -47.861792)
			(xy 157.193053 -47.915746) (xy 157.193053 -47.970249) (xy 158.785586 -47.970249) (xy 158.785586 -47.915751)
			(xy 158.793341 -47.861808) (xy 158.808694 -47.809518) (xy 158.831331 -47.759944) (xy 158.860793 -47.714097)
			(xy 158.89648 -47.672908) (xy 158.937664 -47.637217) (xy 158.983509 -47.607751) (xy 159.03308 -47.585108)
			(xy 159.085369 -47.569749) (xy 159.139311 -47.561988) (xy 159.16656 -47.5615) (xy 160.03016 -47.5615)
			(xy 160.057415 -47.561945) (xy 160.111372 -47.569697) (xy 160.163675 -47.58505) (xy 160.213262 -47.607691)
			(xy 160.259121 -47.637158) (xy 160.300319 -47.672853) (xy 160.336018 -47.714047) (xy 160.36549 -47.759903)
			(xy 160.388136 -47.809487) (xy 160.403494 -47.861789) (xy 160.411253 -47.915745) (xy 160.411253 -47.970255)
			(xy 160.403494 -48.024211) (xy 160.388136 -48.076513) (xy 160.36549 -48.126097) (xy 160.336018 -48.171953)
			(xy 160.300319 -48.213147) (xy 160.259121 -48.248842) (xy 160.213262 -48.278309) (xy 160.163675 -48.30095)
			(xy 160.111372 -48.316303) (xy 160.057415 -48.324055) (xy 160.03016 -48.324516) (xy 159.16656 -48.324516)
			(xy 159.139311 -48.324012) (xy 159.085369 -48.316251) (xy 159.03308 -48.300892) (xy 158.983509 -48.278249)
			(xy 158.937664 -48.248783) (xy 158.89648 -48.213092) (xy 158.860793 -48.171903) (xy 158.831331 -48.126056)
			(xy 158.808694 -48.076482) (xy 158.793341 -48.024192) (xy 158.785586 -47.970249) (xy 157.193053 -47.970249)
			(xy 157.193053 -47.970254) (xy 157.185295 -48.024208) (xy 157.169938 -48.076509) (xy 157.147293 -48.126091)
			(xy 157.117823 -48.171946) (xy 157.082126 -48.21314) (xy 157.04093 -48.248835) (xy 156.995074 -48.278303)
			(xy 156.94549 -48.300945) (xy 156.893189 -48.316299) (xy 156.839234 -48.324054) (xy 156.81198 -48.324516)
			(xy 155.94838 -48.324516) (xy 155.92113 -48.324013) (xy 155.867186 -48.316254) (xy 155.814895 -48.300898)
			(xy 155.765321 -48.278256) (xy 155.719474 -48.24879) (xy 155.678287 -48.213099) (xy 155.642598 -48.17191)
			(xy 155.613135 -48.126062) (xy 155.590495 -48.076487) (xy 155.575142 -48.024195) (xy 155.567386 -47.97025)
			(xy 103.582915 -47.97025) (xy 103.545182 -48.09464) (xy 103.490112 -48.24855) (xy 103.427556 -48.399574)
			(xy 103.357665 -48.547345) (xy 103.280608 -48.69151) (xy 103.196569 -48.83172) (xy 103.105752 -48.967637)
			(xy 103.008375 -49.098935) (xy 102.904673 -49.225296) (xy 102.794896 -49.346417) (xy 102.679308 -49.462005)
			(xy 102.558187 -49.571782) (xy 102.431826 -49.675484) (xy 102.300529 -49.772861) (xy 102.164611 -49.863678)
			(xy 102.024402 -49.947717) (xy 101.880237 -50.024774) (xy 101.732465 -50.094665) (xy 101.581442 -50.157221)
			(xy 101.427531 -50.212291) (xy 101.271104 -50.259743) (xy 101.112536 -50.299462) (xy 100.952211 -50.331353)
			(xy 100.790514 -50.355339) (xy 100.627835 -50.371361) (xy 100.464565 -50.379382) (xy 100.382832 -50.379884)
			(xy 100.300633 -50.379346) (xy 100.136435 -50.371235) (xy 99.972838 -50.35503) (xy 99.81024 -50.33077)
			(xy 99.649037 -50.298516) (xy 99.489622 -50.258346) (xy 99.332384 -50.210357) (xy 99.177706 -50.154667)
			(xy 99.025965 -50.091411) (xy 98.87753 -50.020744) (xy 98.732764 -49.942837) (xy 98.592019 -49.857881)
			(xy 98.455639 -49.766082) (xy 98.323954 -49.667665) (xy 98.197288 -49.562869) (xy 98.075947 -49.451949)
			(xy 97.960229 -49.335176) (xy 97.850414 -49.212835) (xy 97.746771 -49.085223) (xy 97.649552 -48.952651)
			(xy 97.558994 -48.815444) (xy 97.475318 -48.673934) (xy 97.398727 -48.528468) (xy 97.329409 -48.379398)
			(xy 97.298002 -48.303434) (xy 97.291959 -48.289914) (xy 97.273434 -48.266828) (xy 97.249065 -48.250026)
			(xy 97.220901 -48.240919) (xy 97.191308 -48.240273) (xy 97.162774 -48.248142) (xy 97.137695 -48.263865)
			(xy 97.118181 -48.286121) (xy 97.111566 -48.29937) (xy 97.078712 -48.369946) (xy 97.006622 -48.507944)
			(xy 96.927474 -48.642019) (xy 96.84148 -48.77181) (xy 96.748872 -48.896966) (xy 96.649898 -49.017153)
			(xy 96.544826 -49.132045) (xy 96.433938 -49.241335) (xy 96.317532 -49.344728) (xy 96.195921 -49.441946)
			(xy 96.069433 -49.532727) (xy 95.938408 -49.616828) (xy 95.803198 -49.694021) (xy 95.664167 -49.764099)
			(xy 95.52169 -49.826874) (xy 95.376149 -49.882177) (xy 95.227937 -49.929859) (xy 95.077451 -49.969791)
			(xy 94.925097 -50.001867) (xy 94.771285 -50.025999) (xy 94.616429 -50.042123) (xy 94.460945 -50.050196)
			(xy 94.383098 -50.0507) (xy 92.782898 -50.0507) (xy 92.705622 -50.050194) (xy 92.551275 -50.042238)
			(xy 92.397543 -50.026347) (xy 92.244832 -50.002563) (xy 92.093548 -49.970949) (xy 91.944092 -49.931589)
			(xy 91.796861 -49.884587) (xy 91.652244 -49.830069) (xy 91.510626 -49.768178) (xy 91.372381 -49.699079)
			(xy 91.237877 -49.622954) (xy 91.10747 -49.540007) (xy 90.981506 -49.450456) (xy 90.860319 -49.35454)
			(xy 90.74423 -49.252512) (xy 90.633548 -49.144644) (xy 90.528565 -49.031221) (xy 90.42956 -48.912543)
			(xy 90.336796 -48.788927) (xy 90.250519 -48.660699) (xy 90.170957 -48.528199) (xy 90.098321 -48.391779)
			(xy 90.032804 -48.251802) (xy 89.97458 -48.108637) (xy 89.923803 -47.962664) (xy 89.880608 -47.814271)
			(xy 89.84511 -47.663852) (xy 89.817402 -47.511804) (xy 89.797557 -47.358531) (xy 89.78563 -47.204441)
			(xy 89.78165 -47.04994) (xy 73.712332 -47.04994) (xy 73.712332 -47.131673) (xy 73.704312 -47.294943)
			(xy 73.688289 -47.457622) (xy 73.664304 -47.619319) (xy 73.632413 -47.779644) (xy 73.592694 -47.938212)
			(xy 73.545242 -48.09464) (xy 73.490172 -48.24855) (xy 73.427616 -48.399574) (xy 73.357725 -48.547345)
			(xy 73.280668 -48.69151) (xy 73.196629 -48.83172) (xy 73.105812 -48.967637) (xy 73.008435 -49.098935)
			(xy 72.904733 -49.225296) (xy 72.794956 -49.346417) (xy 72.679368 -49.462005) (xy 72.558247 -49.571782)
			(xy 72.431886 -49.675484) (xy 72.300589 -49.772861) (xy 72.164671 -49.863678) (xy 72.024462 -49.947717)
			(xy 71.880297 -50.024774) (xy 71.732525 -50.094665) (xy 71.581502 -50.157221) (xy 71.427591 -50.212291)
			(xy 71.271164 -50.259743) (xy 71.112596 -50.299462) (xy 70.952271 -50.331353) (xy 70.790574 -50.355339)
			(xy 70.627895 -50.371361) (xy 70.464625 -50.379382) (xy 70.382892 -50.379884) (xy 70.300688 -50.379384)
			(xy 70.13648 -50.371273) (xy 69.972873 -50.355068) (xy 69.810265 -50.330807) (xy 69.649053 -50.298549)
			(xy 69.489629 -50.258374) (xy 69.332383 -50.210379) (xy 69.177697 -50.15468) (xy 69.025949 -50.091415)
			(xy 68.877509 -50.020737) (xy 68.732738 -49.942818) (xy 68.591989 -49.857849) (xy 68.455606 -49.766036)
			(xy 68.323921 -49.667603) (xy 68.197255 -49.56279) (xy 68.075917 -49.451854) (xy 67.960202 -49.335063)
			(xy 67.850393 -49.212703) (xy 67.746757 -49.085073) (xy 67.649547 -48.952483) (xy 67.559 -48.815256)
			(xy 67.475337 -48.673727) (xy 67.398761 -48.528241) (xy 67.329459 -48.379153) (xy 67.298062 -48.30318)
			(xy 67.291963 -48.28966) (xy 67.273429 -48.266526) (xy 67.249036 -48.249686) (xy 67.220834 -48.240557)
			(xy 67.1912 -48.239907) (xy 67.162625 -48.24779) (xy 67.137517 -48.263545) (xy 67.117987 -48.285843)
			(xy 67.111372 -48.299116) (xy 67.078481 -48.369679) (xy 67.006404 -48.507691) (xy 66.927268 -48.641781)
			(xy 66.841285 -48.771586) (xy 66.748686 -48.896758) (xy 66.64972 -49.01696) (xy 66.544655 -49.131868)
			(xy 66.433772 -49.241173) (xy 66.31737 -49.34458) (xy 66.195763 -49.441813) (xy 66.069277 -49.532608)
			(xy 65.938253 -49.616723) (xy 65.803043 -49.693929) (xy 65.664011 -49.764021) (xy 65.521532 -49.826808)
			(xy 65.375989 -49.882122) (xy 65.227772 -49.929815) (xy 65.077283 -49.969757) (xy 64.924924 -50.001842)
			(xy 64.771107 -50.025982) (xy 64.616245 -50.042114) (xy 64.460754 -50.050194) (xy 64.382904 -50.0507)
			(xy 62.78245 -50.0507) (xy 62.705176 -50.050188) (xy 62.550834 -50.04222) (xy 62.397107 -50.026316)
			(xy 62.244402 -50.002521) (xy 62.093124 -49.970896) (xy 61.943675 -49.931526) (xy 61.796451 -49.884514)
			(xy 61.651842 -49.829987) (xy 61.510232 -49.768087) (xy 61.371996 -49.69898) (xy 61.2375 -49.622848)
			(xy 61.107102 -49.539894) (xy 60.981148 -49.450337) (xy 60.85997 -49.354416) (xy 60.743891 -49.252383)
			(xy 60.633218 -49.14451) (xy 60.528245 -49.031083) (xy 60.429249 -48.912403) (xy 60.336495 -48.788784)
			(xy 60.250227 -48.660555) (xy 60.170674 -48.528054) (xy 60.098048 -48.391634) (xy 60.032541 -48.251656)
			(xy 59.974326 -48.108492) (xy 59.923558 -47.96252) (xy 59.880371 -47.814129) (xy 59.844881 -47.663712)
			(xy 59.81718 -47.511667) (xy 59.797344 -47.358397) (xy 59.785423 -47.20431) (xy 59.781451 -47.049813)
			(xy 25.46096 -47.049813) (xy 25.46096 -74.760836) (xy 39.554404 -74.760836) (xy 39.554404 -66.060828)
			(xy 39.554909 -65.955304) (xy 39.562993 -65.74441) (xy 39.579149 -65.533981) (xy 39.603352 -65.324324)
			(xy 39.635569 -65.115749) (xy 39.675751 -64.908561) (xy 39.723839 -64.703064) (xy 39.779763 -64.49956)
			(xy 39.84344 -64.298347) (xy 39.914778 -64.09972) (xy 39.993672 -63.903972) (xy 40.080005 -63.71139)
			(xy 40.173652 -63.522255) (xy 40.274474 -63.336846) (xy 40.382324 -63.155435) (xy 40.497043 -62.978288)
			(xy 40.618463 -62.805666) (xy 40.746406 -62.63782) (xy 40.880684 -62.474998) (xy 41.0211 -62.317439)
			(xy 41.167448 -62.165374) (xy 41.319513 -62.019026) (xy 41.477072 -61.87861) (xy 41.639894 -61.744332)
			(xy 41.80774 -61.616389) (xy 41.980362 -61.494969) (xy 42.157509 -61.38025) (xy 42.33892 -61.2724)
			(xy 42.524329 -61.171578) (xy 42.713464 -61.077931) (xy 42.906046 -60.991598) (xy 43.101794 -60.912704)
			(xy 43.300421 -60.841366) (xy 43.501634 -60.777689) (xy 43.705138 -60.721765) (xy 43.910635 -60.673677)
			(xy 44.117823 -60.633495) (xy 44.326398 -60.601278) (xy 44.536055 -60.577075) (xy 44.746484 -60.560919)
			(xy 44.957378 -60.552835) (xy 45.168426 -60.552835) (xy 45.37932 -60.560919) (xy 45.589749 -60.577075)
			(xy 45.799406 -60.601278) (xy 46.007981 -60.633495) (xy 46.215169 -60.673677) (xy 46.420666 -60.721765)
			(xy 46.62417 -60.777689) (xy 46.825383 -60.841366) (xy 47.02401 -60.912704) (xy 47.219758 -60.991598)
			(xy 47.41234 -61.077931) (xy 47.601475 -61.171578) (xy 47.786884 -61.2724) (xy 47.968295 -61.38025)
			(xy 48.145442 -61.494969) (xy 48.318064 -61.616389) (xy 48.48591 -61.744332) (xy 48.648732 -61.87861)
			(xy 48.806291 -62.019026) (xy 48.958356 -62.165374) (xy 49.104704 -62.317439) (xy 49.24512 -62.474998)
			(xy 49.379398 -62.63782) (xy 49.507341 -62.805666) (xy 49.628761 -62.978288) (xy 49.74348 -63.155435)
			(xy 49.85133 -63.336846) (xy 49.952152 -63.522255) (xy 50.045799 -63.71139) (xy 50.132132 -63.903972)
			(xy 50.211026 -64.09972) (xy 50.282364 -64.298347) (xy 50.346041 -64.49956) (xy 50.401965 -64.703064)
			(xy 50.450053 -64.908561) (xy 50.490235 -65.115749) (xy 50.522452 -65.324324) (xy 50.546655 -65.533981)
			(xy 50.562811 -65.74441) (xy 50.570895 -65.955304) (xy 50.5714 -66.060828) (xy 50.5714 -74.760836)
			(xy 50.571366 -74.767948) (xy 173.354492 -74.767948) (xy 173.354492 -66.06794) (xy 173.354997 -65.962416)
			(xy 173.363081 -65.751522) (xy 173.379237 -65.541093) (xy 173.40344 -65.331436) (xy 173.435657 -65.122861)
			(xy 173.475839 -64.915673) (xy 173.523927 -64.710176) (xy 173.579851 -64.506672) (xy 173.643528 -64.305459)
			(xy 173.714866 -64.106832) (xy 173.79376 -63.911084) (xy 173.880093 -63.718502) (xy 173.97374 -63.529367)
			(xy 174.074562 -63.343958) (xy 174.182412 -63.162547) (xy 174.297131 -62.9854) (xy 174.418551 -62.812778)
			(xy 174.546494 -62.644932) (xy 174.680772 -62.48211) (xy 174.821188 -62.324551) (xy 174.967536 -62.172486)
			(xy 175.119601 -62.026138) (xy 175.27716 -61.885722) (xy 175.439982 -61.751444) (xy 175.607828 -61.623501)
			(xy 175.78045 -61.502081) (xy 175.957597 -61.387362) (xy 176.139008 -61.279512) (xy 176.324417 -61.17869)
			(xy 176.513552 -61.085043) (xy 176.706134 -60.99871) (xy 176.901882 -60.919816) (xy 177.100509 -60.848478)
			(xy 177.301722 -60.784801) (xy 177.505226 -60.728877) (xy 177.710723 -60.680789) (xy 177.917911 -60.640607)
			(xy 178.126486 -60.60839) (xy 178.336143 -60.584187) (xy 178.546572 -60.568031) (xy 178.757466 -60.559947)
			(xy 178.968514 -60.559947) (xy 179.179408 -60.568031) (xy 179.389837 -60.584187) (xy 179.599494 -60.60839)
			(xy 179.808069 -60.640607) (xy 180.015257 -60.680789) (xy 180.220754 -60.728877) (xy 180.424258 -60.784801)
			(xy 180.625471 -60.848478) (xy 180.824098 -60.919816) (xy 181.019846 -60.99871) (xy 181.212428 -61.085043)
			(xy 181.401563 -61.17869) (xy 181.586972 -61.279512) (xy 181.768383 -61.387362) (xy 181.94553 -61.502081)
			(xy 182.118152 -61.623501) (xy 182.285998 -61.751444) (xy 182.44882 -61.885722) (xy 182.606379 -62.026138)
			(xy 182.758444 -62.172486) (xy 182.904792 -62.324551) (xy 183.045208 -62.48211) (xy 183.179486 -62.644932)
			(xy 183.307429 -62.812778) (xy 183.428849 -62.9854) (xy 183.543568 -63.162547) (xy 183.651418 -63.343958)
			(xy 183.75224 -63.529367) (xy 183.845887 -63.718502) (xy 183.93222 -63.911084) (xy 184.011114 -64.106832)
			(xy 184.082452 -64.305459) (xy 184.146129 -64.506672) (xy 184.202053 -64.710176) (xy 184.250141 -64.915673)
			(xy 184.290323 -65.122861) (xy 184.32254 -65.331436) (xy 184.346743 -65.541093) (xy 184.362899 -65.751522)
			(xy 184.370983 -65.962416) (xy 184.371488 -66.06794) (xy 184.371488 -74.767948) (xy 184.370983 -74.873472)
			(xy 184.362899 -75.084366) (xy 184.346743 -75.294795) (xy 184.32254 -75.504452) (xy 184.290323 -75.713027)
			(xy 184.250141 -75.920215) (xy 184.202053 -76.125712) (xy 184.146129 -76.329216) (xy 184.082452 -76.530429)
			(xy 184.011114 -76.729056) (xy 183.93222 -76.924804) (xy 183.845887 -77.117386) (xy 183.75224 -77.306521)
			(xy 183.651418 -77.49193) (xy 183.543568 -77.673341) (xy 183.428849 -77.850488) (xy 183.307429 -78.02311)
			(xy 183.179486 -78.190956) (xy 183.045208 -78.353778) (xy 182.904792 -78.511337) (xy 182.758444 -78.663402)
			(xy 182.606379 -78.80975) (xy 182.44882 -78.950166) (xy 182.285998 -79.084444) (xy 182.118152 -79.212387)
			(xy 181.94553 -79.333807) (xy 181.768383 -79.448526) (xy 181.586972 -79.556376) (xy 181.401563 -79.657198)
			(xy 181.212428 -79.750845) (xy 181.019846 -79.837178) (xy 180.824098 -79.916072) (xy 180.625471 -79.98741)
			(xy 180.424258 -80.051087) (xy 180.220754 -80.107011) (xy 180.015257 -80.155099) (xy 179.808069 -80.195281)
			(xy 179.599494 -80.227498) (xy 179.389837 -80.251701) (xy 179.179408 -80.267857) (xy 178.968514 -80.275941)
			(xy 178.757466 -80.275941) (xy 178.546572 -80.267857) (xy 178.336143 -80.251701) (xy 178.126486 -80.227498)
			(xy 177.917911 -80.195281) (xy 177.710723 -80.155099) (xy 177.505226 -80.107011) (xy 177.301722 -80.051087)
			(xy 177.100509 -79.98741) (xy 176.901882 -79.916072) (xy 176.706134 -79.837178) (xy 176.513552 -79.750845)
			(xy 176.324417 -79.657198) (xy 176.139008 -79.556376) (xy 175.957597 -79.448526) (xy 175.78045 -79.333807)
			(xy 175.607828 -79.212387) (xy 175.439982 -79.084444) (xy 175.27716 -78.950166) (xy 175.119601 -78.80975)
			(xy 174.967536 -78.663402) (xy 174.821188 -78.511337) (xy 174.680772 -78.353778) (xy 174.546494 -78.190956)
			(xy 174.418551 -78.02311) (xy 174.297131 -77.850488) (xy 174.182412 -77.673341) (xy 174.074562 -77.49193)
			(xy 173.97374 -77.306521) (xy 173.880093 -77.117386) (xy 173.79376 -76.924804) (xy 173.714866 -76.729056)
			(xy 173.643528 -76.530429) (xy 173.579851 -76.329216) (xy 173.523927 -76.125712) (xy 173.475839 -75.920215)
			(xy 173.435657 -75.713027) (xy 173.40344 -75.504452) (xy 173.379237 -75.294795) (xy 173.363081 -75.084366)
			(xy 173.354997 -74.873472) (xy 173.354492 -74.767948) (xy 50.571366 -74.767948) (xy 50.570895 -74.86636)
			(xy 50.562811 -75.077254) (xy 50.546655 -75.287683) (xy 50.522452 -75.49734) (xy 50.490235 -75.705915)
			(xy 50.450053 -75.913103) (xy 50.401965 -76.1186) (xy 50.346041 -76.322104) (xy 50.282364 -76.523317)
			(xy 50.211026 -76.721944) (xy 50.132132 -76.917692) (xy 50.045799 -77.110274) (xy 49.952152 -77.299409)
			(xy 49.85133 -77.484818) (xy 49.74348 -77.666229) (xy 49.628761 -77.843376) (xy 49.507341 -78.015998)
			(xy 49.379398 -78.183844) (xy 49.24512 -78.346666) (xy 49.104704 -78.504225) (xy 48.958356 -78.65629)
			(xy 48.806291 -78.802638) (xy 48.648732 -78.943054) (xy 48.48591 -79.077332) (xy 48.318064 -79.205275)
			(xy 48.145442 -79.326695) (xy 47.968295 -79.441414) (xy 47.786884 -79.549264) (xy 47.601475 -79.650086)
			(xy 47.41234 -79.743733) (xy 47.219758 -79.830066) (xy 47.02401 -79.90896) (xy 46.825383 -79.980298)
			(xy 46.62417 -80.043975) (xy 46.420666 -80.099899) (xy 46.215169 -80.147987) (xy 46.007981 -80.188169)
			(xy 45.799406 -80.220386) (xy 45.589749 -80.244589) (xy 45.37932 -80.260745) (xy 45.168426 -80.268829)
			(xy 44.957378 -80.268829) (xy 44.746484 -80.260745) (xy 44.536055 -80.244589) (xy 44.326398 -80.220386)
			(xy 44.117823 -80.188169) (xy 43.910635 -80.147987) (xy 43.705138 -80.099899) (xy 43.501634 -80.043975)
			(xy 43.300421 -79.980298) (xy 43.101794 -79.90896) (xy 42.906046 -79.830066) (xy 42.713464 -79.743733)
			(xy 42.524329 -79.650086) (xy 42.33892 -79.549264) (xy 42.157509 -79.441414) (xy 41.980362 -79.326695)
			(xy 41.80774 -79.205275) (xy 41.639894 -79.077332) (xy 41.477072 -78.943054) (xy 41.319513 -78.802638)
			(xy 41.167448 -78.65629) (xy 41.0211 -78.504225) (xy 40.880684 -78.346666) (xy 40.746406 -78.183844)
			(xy 40.618463 -78.015998) (xy 40.497043 -77.843376) (xy 40.382324 -77.666229) (xy 40.274474 -77.484818)
			(xy 40.173652 -77.299409) (xy 40.080005 -77.110274) (xy 39.993672 -76.917692) (xy 39.914778 -76.721944)
			(xy 39.84344 -76.523317) (xy 39.779763 -76.322104) (xy 39.723839 -76.1186) (xy 39.675751 -75.913103)
			(xy 39.635569 -75.705915) (xy 39.603352 -75.49734) (xy 39.579149 -75.287683) (xy 39.562993 -75.077254)
			(xy 39.554909 -74.86636) (xy 39.554404 -74.760836) (xy 25.46096 -74.760836) (xy 25.46096 -98.341434)
			(xy 261.733792 -98.341434) (xy 261.733792 -97.477834) (xy 261.734278 -97.450583) (xy 261.742034 -97.396635)
			(xy 261.757389 -97.34434) (xy 261.780031 -97.294763) (xy 261.809497 -97.248913) (xy 261.845188 -97.207722)
			(xy 261.886379 -97.172031) (xy 261.932229 -97.142565) (xy 261.981806 -97.119923) (xy 262.034101 -97.104568)
			(xy 262.088049 -97.096812) (xy 262.142551 -97.096812) (xy 262.196499 -97.104568) (xy 262.248794 -97.119923)
			(xy 262.298371 -97.142565) (xy 262.344221 -97.172031) (xy 262.385412 -97.207722) (xy 262.421103 -97.248913)
			(xy 262.450569 -97.294763) (xy 262.473211 -97.34434) (xy 262.488566 -97.396635) (xy 262.496322 -97.450583)
			(xy 262.496808 -97.477834) (xy 262.496808 -98.341434) (xy 262.496322 -98.368685) (xy 262.488566 -98.422633)
			(xy 262.473211 -98.474928) (xy 262.450569 -98.524505) (xy 262.421103 -98.570355) (xy 262.385412 -98.611546)
			(xy 262.344221 -98.647237) (xy 262.298371 -98.676703) (xy 262.248794 -98.699345) (xy 262.196499 -98.7147)
			(xy 262.142551 -98.722456) (xy 262.088049 -98.722456) (xy 262.034101 -98.7147) (xy 261.981806 -98.699345)
			(xy 261.932229 -98.676703) (xy 261.886379 -98.647237) (xy 261.845188 -98.611546) (xy 261.809497 -98.570355)
			(xy 261.780031 -98.524505) (xy 261.757389 -98.474928) (xy 261.742034 -98.422633) (xy 261.734278 -98.368685)
			(xy 261.733792 -98.341434) (xy 25.46096 -98.341434) (xy 25.46096 -108.689394) (xy 238.647224 -108.689394)
			(xy 238.647224 -107.825794) (xy 238.64771 -107.798525) (xy 238.655472 -107.744541) (xy 238.670837 -107.692211)
			(xy 238.693494 -107.642601) (xy 238.72298 -107.59672) (xy 238.758695 -107.555503) (xy 238.799912 -107.519788)
			(xy 238.845793 -107.490302) (xy 238.895403 -107.467645) (xy 238.947733 -107.45228) (xy 239.001717 -107.444518)
			(xy 239.056255 -107.444518) (xy 239.110239 -107.45228) (xy 239.162569 -107.467645) (xy 239.212179 -107.490302)
			(xy 239.25806 -107.519788) (xy 239.299277 -107.555503) (xy 239.334992 -107.59672) (xy 239.364478 -107.642601)
			(xy 239.387135 -107.692211) (xy 239.4025 -107.744541) (xy 239.410262 -107.798525) (xy 239.410748 -107.825794)
			(xy 239.410748 -108.689394) (xy 239.410262 -108.716663) (xy 239.4025 -108.770647) (xy 239.387135 -108.822977)
			(xy 239.364478 -108.872587) (xy 239.334992 -108.918468) (xy 239.299277 -108.959685) (xy 239.25806 -108.9954)
			(xy 239.212179 -109.024886) (xy 239.162569 -109.047543) (xy 239.110239 -109.062908) (xy 239.056255 -109.07067)
			(xy 239.001717 -109.07067) (xy 238.947733 -109.062908) (xy 238.895403 -109.047543) (xy 238.845793 -109.024886)
			(xy 238.799912 -108.9954) (xy 238.758695 -108.959685) (xy 238.72298 -108.918468) (xy 238.693494 -108.872587)
			(xy 238.670837 -108.822977) (xy 238.655472 -108.770647) (xy 238.64771 -108.716663) (xy 238.647224 -108.689394)
			(xy 25.46096 -108.689394) (xy 25.46096 -109.550266) (xy 250.428546 -109.550266) (xy 250.428546 -109.495734)
			(xy 250.436306 -109.441757) (xy 250.451669 -109.389434) (xy 250.474321 -109.339829) (xy 250.503801 -109.293953)
			(xy 250.53951 -109.252739) (xy 250.580721 -109.217025) (xy 250.626594 -109.18754) (xy 250.676196 -109.164883)
			(xy 250.728518 -109.149515) (xy 250.782494 -109.141749) (xy 250.80976 -109.14126) (xy 251.67336 -109.14126)
			(xy 251.700634 -109.141677) (xy 251.754629 -109.149435) (xy 251.806969 -109.164798) (xy 251.85659 -109.187455)
			(xy 251.902482 -109.216943) (xy 251.943709 -109.252663) (xy 251.979433 -109.293886) (xy 252.008926 -109.339775)
			(xy 252.031588 -109.389393) (xy 252.046957 -109.441732) (xy 252.05472 -109.495726) (xy 252.05472 -109.550274)
			(xy 252.046957 -109.604268) (xy 252.031588 -109.656607) (xy 252.008926 -109.706225) (xy 251.979433 -109.752114)
			(xy 251.943709 -109.793337) (xy 251.902482 -109.829057) (xy 251.85659 -109.858545) (xy 251.806969 -109.881202)
			(xy 251.754629 -109.896565) (xy 251.700634 -109.904323) (xy 251.67336 -109.904784) (xy 250.80976 -109.904784)
			(xy 250.782494 -109.904251) (xy 250.728518 -109.896485) (xy 250.676196 -109.881117) (xy 250.626594 -109.85846)
			(xy 250.580721 -109.828975) (xy 250.53951 -109.793262) (xy 250.503801 -109.752047) (xy 250.474321 -109.706171)
			(xy 250.451669 -109.656566) (xy 250.436306 -109.604243) (xy 250.428546 -109.550266) (xy 25.46096 -109.550266)
			(xy 25.46096 -111.158274) (xy 239.40262 -111.158274) (xy 239.40262 -110.294674) (xy 239.403106 -110.267423)
			(xy 239.410862 -110.213475) (xy 239.426217 -110.16118) (xy 239.448859 -110.111603) (xy 239.478325 -110.065753)
			(xy 239.514016 -110.024562) (xy 239.555207 -109.988871) (xy 239.601057 -109.959405) (xy 239.650634 -109.936763)
			(xy 239.702929 -109.921408) (xy 239.756877 -109.913652) (xy 239.811379 -109.913652) (xy 239.865327 -109.921408)
			(xy 239.917622 -109.936763) (xy 239.967199 -109.959405) (xy 240.000574 -109.980854) (xy 256.88563 -109.980854)
			(xy 256.88563 -109.926346) (xy 256.893387 -109.872392) (xy 256.908744 -109.820091) (xy 256.931388 -109.770508)
			(xy 256.960857 -109.724652) (xy 256.996552 -109.683457) (xy 257.037747 -109.647761) (xy 257.083602 -109.61829)
			(xy 257.133185 -109.595646) (xy 257.185486 -109.580288) (xy 257.23944 -109.57253) (xy 257.266694 -109.572044)
			(xy 258.130294 -109.572044) (xy 258.157544 -109.572603) (xy 258.211488 -109.580358) (xy 258.26378 -109.595712)
			(xy 258.313355 -109.618351) (xy 258.359203 -109.647815) (xy 258.400391 -109.683504) (xy 258.436081 -109.724692)
			(xy 258.465546 -109.77054) (xy 258.488186 -109.820114) (xy 258.503541 -109.872406) (xy 258.511297 -109.92635)
			(xy 258.511297 -109.98085) (xy 258.503541 -110.034794) (xy 258.488186 -110.087086) (xy 258.465546 -110.13666)
			(xy 258.436081 -110.182508) (xy 258.400391 -110.223696) (xy 258.359203 -110.259385) (xy 258.313355 -110.288849)
			(xy 258.26378 -110.311488) (xy 258.211488 -110.326842) (xy 258.157544 -110.334597) (xy 258.130294 -110.33506)
			(xy 257.266694 -110.33506) (xy 257.23944 -110.33467) (xy 257.185486 -110.326912) (xy 257.133185 -110.311554)
			(xy 257.083602 -110.28891) (xy 257.037747 -110.259439) (xy 256.996552 -110.223743) (xy 256.960857 -110.182548)
			(xy 256.931388 -110.136692) (xy 256.908744 -110.087109) (xy 256.893387 -110.034808) (xy 256.88563 -109.980854)
			(xy 240.000574 -109.980854) (xy 240.013049 -109.988871) (xy 240.05424 -110.024562) (xy 240.089931 -110.065753)
			(xy 240.119397 -110.111603) (xy 240.142039 -110.16118) (xy 240.157394 -110.213475) (xy 240.16515 -110.267423)
			(xy 240.165636 -110.294674) (xy 240.165636 -111.158274) (xy 240.16515 -111.185525) (xy 240.157394 -111.239473)
			(xy 240.142039 -111.291768) (xy 240.119397 -111.341345) (xy 240.089931 -111.387195) (xy 240.05424 -111.428386)
			(xy 240.013049 -111.464077) (xy 239.967199 -111.493543) (xy 239.917622 -111.516185) (xy 239.865327 -111.53154)
			(xy 239.811379 -111.539296) (xy 239.756877 -111.539296) (xy 239.702929 -111.53154) (xy 239.650634 -111.516185)
			(xy 239.601057 -111.493543) (xy 239.555207 -111.464077) (xy 239.514016 -111.428386) (xy 239.478325 -111.387195)
			(xy 239.448859 -111.341345) (xy 239.426217 -111.291768) (xy 239.410862 -111.239473) (xy 239.403106 -111.185525)
			(xy 239.40262 -111.158274) (xy 25.46096 -111.158274) (xy 25.46096 -116.393573) (xy 230.652992 -116.393573)
			(xy 230.652992 -116.339027) (xy 230.660755 -116.285035) (xy 230.676123 -116.232698) (xy 230.698784 -116.183081)
			(xy 230.728276 -116.137195) (xy 230.763998 -116.095973) (xy 230.805224 -116.060254) (xy 230.851113 -116.030767)
			(xy 230.900732 -116.008111) (xy 230.95307 -115.992747) (xy 231.007063 -115.984989) (xy 231.034336 -115.984528)
			(xy 231.897936 -115.984528) (xy 231.925203 -115.985037) (xy 231.979181 -115.992802) (xy 232.031505 -116.008171)
			(xy 232.081109 -116.030828) (xy 232.126985 -116.060314) (xy 232.168197 -116.096029) (xy 232.203907 -116.137244)
			(xy 232.233389 -116.183122) (xy 232.256042 -116.232729) (xy 232.271405 -116.285054) (xy 232.277026 -116.324151)
			(xy 236.866903 -116.324151) (xy 236.866903 -116.269649) (xy 236.87466 -116.215701) (xy 236.890016 -116.163407)
			(xy 236.912659 -116.113831) (xy 236.942127 -116.067981) (xy 236.97782 -116.026793) (xy 237.019012 -115.991104)
			(xy 237.064864 -115.961641) (xy 237.114443 -115.939003) (xy 237.166739 -115.923652) (xy 237.220687 -115.915901)
			(xy 237.247938 -115.91544) (xy 238.111538 -115.91544) (xy 238.138791 -115.915832) (xy 238.192741 -115.923594)
			(xy 238.245038 -115.938955) (xy 238.294617 -115.961601) (xy 238.340468 -115.991072) (xy 238.381659 -116.026768)
			(xy 238.417351 -116.067962) (xy 238.446817 -116.113817) (xy 238.469459 -116.163398) (xy 238.484814 -116.215696)
			(xy 238.49257 -116.269647) (xy 238.49257 -116.324153) (xy 238.484814 -116.378104) (xy 238.469459 -116.430402)
			(xy 238.446817 -116.479983) (xy 238.417351 -116.525838) (xy 238.381659 -116.567032) (xy 238.340468 -116.602728)
			(xy 238.294617 -116.632199) (xy 238.245038 -116.654845) (xy 238.192741 -116.670206) (xy 238.138791 -116.677968)
			(xy 238.111538 -116.678456) (xy 237.247938 -116.678456) (xy 237.220687 -116.677899) (xy 237.166739 -116.670148)
			(xy 237.114443 -116.654797) (xy 237.064864 -116.632159) (xy 237.019012 -116.602696) (xy 236.97782 -116.567007)
			(xy 236.942127 -116.525819) (xy 236.912659 -116.479969) (xy 236.890016 -116.430393) (xy 236.87466 -116.378099)
			(xy 236.866903 -116.324151) (xy 232.277026 -116.324151) (xy 232.279166 -116.339033) (xy 232.279166 -116.393567)
			(xy 232.271405 -116.447546) (xy 232.256042 -116.499871) (xy 232.233389 -116.549478) (xy 232.203907 -116.595356)
			(xy 232.168197 -116.636571) (xy 232.126985 -116.672286) (xy 232.081109 -116.701772) (xy 232.031505 -116.724429)
			(xy 231.979181 -116.739798) (xy 231.925203 -116.747563) (xy 231.897936 -116.748052) (xy 231.034336 -116.748052)
			(xy 231.007063 -116.747611) (xy 230.95307 -116.739853) (xy 230.900732 -116.724489) (xy 230.851113 -116.701833)
			(xy 230.805224 -116.672346) (xy 230.763998 -116.636627) (xy 230.728276 -116.595405) (xy 230.698784 -116.549519)
			(xy 230.676123 -116.499902) (xy 230.660755 -116.447565) (xy 230.652992 -116.393573) (xy 25.46096 -116.393573)
			(xy 25.46096 -117.632251) (xy 233.564903 -117.632251) (xy 233.564903 -117.577749) (xy 233.57266 -117.523801)
			(xy 233.588016 -117.471507) (xy 233.610659 -117.421931) (xy 233.640127 -117.376081) (xy 233.67582 -117.334893)
			(xy 233.717012 -117.299204) (xy 233.762864 -117.269741) (xy 233.812443 -117.247103) (xy 233.864739 -117.231752)
			(xy 233.918687 -117.224001) (xy 233.945938 -117.22354) (xy 234.809538 -117.22354) (xy 234.836791 -117.223932)
			(xy 234.890741 -117.231694) (xy 234.943038 -117.247055) (xy 234.992617 -117.269701) (xy 235.038468 -117.299172)
			(xy 235.079659 -117.334868) (xy 235.115351 -117.376062) (xy 235.144817 -117.421917) (xy 235.167459 -117.471498)
			(xy 235.182814 -117.523796) (xy 235.19057 -117.577747) (xy 235.19057 -117.632251) (xy 238.898903 -117.632251)
			(xy 238.898903 -117.577749) (xy 238.90666 -117.523801) (xy 238.922016 -117.471507) (xy 238.944659 -117.421931)
			(xy 238.974127 -117.376081) (xy 239.00982 -117.334893) (xy 239.051012 -117.299204) (xy 239.096864 -117.269741)
			(xy 239.146443 -117.247103) (xy 239.198739 -117.231752) (xy 239.252687 -117.224001) (xy 239.279938 -117.22354)
			(xy 240.143538 -117.22354) (xy 240.170791 -117.223932) (xy 240.224741 -117.231694) (xy 240.277038 -117.247055)
			(xy 240.326617 -117.269701) (xy 240.372468 -117.299172) (xy 240.413659 -117.334868) (xy 240.449351 -117.376062)
			(xy 240.478817 -117.421917) (xy 240.501459 -117.471498) (xy 240.516814 -117.523796) (xy 240.52457 -117.577747)
			(xy 240.52457 -117.632253) (xy 240.516814 -117.686204) (xy 240.501459 -117.738502) (xy 240.478817 -117.788083)
			(xy 240.449351 -117.833938) (xy 240.413659 -117.875132) (xy 240.372468 -117.910828) (xy 240.326617 -117.940299)
			(xy 240.277038 -117.962945) (xy 240.224741 -117.978306) (xy 240.170791 -117.986068) (xy 240.143538 -117.986556)
			(xy 239.279938 -117.986556) (xy 239.252687 -117.985999) (xy 239.198739 -117.978248) (xy 239.146443 -117.962897)
			(xy 239.096864 -117.940259) (xy 239.051012 -117.910796) (xy 239.00982 -117.875107) (xy 238.974127 -117.833919)
			(xy 238.944659 -117.788069) (xy 238.922016 -117.738493) (xy 238.90666 -117.686199) (xy 238.898903 -117.632251)
			(xy 235.19057 -117.632251) (xy 235.19057 -117.632253) (xy 235.182814 -117.686204) (xy 235.167459 -117.738502)
			(xy 235.144817 -117.788083) (xy 235.115351 -117.833938) (xy 235.079659 -117.875132) (xy 235.038468 -117.910828)
			(xy 234.992617 -117.940299) (xy 234.943038 -117.962945) (xy 234.890741 -117.978306) (xy 234.836791 -117.986068)
			(xy 234.809538 -117.986556) (xy 233.945938 -117.986556) (xy 233.918687 -117.985999) (xy 233.864739 -117.978248)
			(xy 233.812443 -117.962897) (xy 233.762864 -117.940259) (xy 233.717012 -117.910796) (xy 233.67582 -117.875107)
			(xy 233.640127 -117.833919) (xy 233.610659 -117.788069) (xy 233.588016 -117.738493) (xy 233.57266 -117.686199)
			(xy 233.564903 -117.632251) (xy 25.46096 -117.632251) (xy 25.46096 -126.669292) (xy 30.247336 -131.455668)
			(xy 38.74262 -131.455668) (xy 40.263064 -129.935224) (xy 40.281104 -129.917962) (xy 40.322596 -129.890201)
			(xy 40.368715 -129.871086) (xy 40.41768 -129.861355) (xy 40.442642 -129.860802) (xy 41.122854 -129.860802)
			(xy 41.14679 -129.845025) (xy 41.198396 -129.820061) (xy 41.253155 -129.803099) (xy 41.309837 -129.794522)
			(xy 41.367163 -129.794522) (xy 41.423845 -129.803099) (xy 41.478604 -129.820061) (xy 41.53021 -129.845025)
			(xy 41.554146 -129.860802) (xy 109.454188 -129.860802) (xy 109.459268 -129.859786) (xy 109.47673 -129.856453)
			(xy 109.512104 -129.852893) (xy 109.52988 -129.852674) (xy 109.547656 -129.852896) (xy 109.583028 -129.856461)
			(xy 109.600492 -129.859786) (xy 109.605572 -129.860802) (xy 132.09651 -129.860802) (xy 132.105908 -129.822194)
			(xy 132.11312 -129.794916) (xy 132.134482 -129.742694) (xy 132.163305 -129.69419) (xy 132.198959 -129.650462)
			(xy 132.240668 -129.612465) (xy 132.28752 -129.581027) (xy 132.338492 -129.556836) (xy 132.392473 -129.540419)
			(xy 132.448283 -129.532134) (xy 132.476494 -129.531618) (xy 132.477002 -129.531618) (xy 132.507209 -129.53221)
			(xy 132.566864 -129.541766) (xy 132.624266 -129.560609) (xy 132.67798 -129.588265) (xy 132.726661 -129.624044)
			(xy 132.748274 -129.645156) (xy 132.758145 -129.654578) (xy 132.781734 -129.668274) (xy 132.80811 -129.675229)
			(xy 132.835386 -129.674947) (xy 132.861612 -129.667446) (xy 132.884912 -129.653263) (xy 132.894578 -129.643632)
			(xy 132.914753 -129.623012) (xy 132.960574 -129.587967) (xy 133.01148 -129.560833) (xy 133.066118 -129.542332)
			(xy 133.123037 -129.532955) (xy 133.15188 -129.53238) (xy 133.178457 -129.532859) (xy 133.231013 -129.540821)
			(xy 133.281782 -129.556567) (xy 133.329618 -129.579744) (xy 133.373441 -129.609826) (xy 133.39318 -129.62763)
			(xy 133.403279 -129.636554) (xy 133.427054 -129.649225) (xy 133.453318 -129.655227) (xy 133.480238 -129.65414)
			(xy 133.505932 -129.64604) (xy 133.528609 -129.631493) (xy 133.53796 -129.621788) (xy 133.556112 -129.60245)
			(xy 133.596839 -129.568477) (xy 133.641881 -129.540474) (xy 133.690368 -129.518981) (xy 133.741366 -129.504414)
			(xy 133.79389 -129.497053) (xy 133.820408 -129.496566) (xy 133.847359 -129.497032) (xy 133.900723 -129.504621)
			(xy 133.952488 -129.519648) (xy 134.001621 -129.541812) (xy 134.047145 -129.570673) (xy 134.088153 -129.605655)
			(xy 134.123827 -129.646061) (xy 134.153458 -129.691088) (xy 134.176455 -129.739838) (xy 134.192359 -129.791339)
			(xy 134.19709 -129.817876) (xy 134.203948 -129.860802) (xy 150.598124 -129.860802) (xy 150.611354 -129.836323)
			(xy 150.643826 -129.791138) (xy 150.682517 -129.751151) (xy 150.726608 -129.717208) (xy 150.775162 -129.690032)
			(xy 150.827149 -129.670197) (xy 150.881466 -129.658125) (xy 150.93696 -129.654073) (xy 150.992454 -129.658125)
			(xy 151.046771 -129.670197) (xy 151.098758 -129.690032) (xy 151.147312 -129.717208) (xy 151.191403 -129.751151)
			(xy 151.230094 -129.791138) (xy 151.262566 -129.836323) (xy 151.275796 -129.860802) (xy 155.222702 -129.860802)
			(xy 155.244674 -129.848456) (xy 155.291172 -129.829008) (xy 155.339822 -129.815838) (xy 155.38978 -129.809175)
			(xy 155.41498 -129.808732) (xy 155.440184 -129.809133) (xy 155.490152 -129.815771) (xy 155.538806 -129.828948)
			(xy 155.585294 -129.848433) (xy 155.607258 -129.860802) (xy 198.638414 -129.860802) (xy 198.650318 -129.836584)
			(xy 198.679933 -129.791473) (xy 198.71561 -129.750987) (xy 198.756637 -129.715933) (xy 198.802195 -129.687012)
			(xy 198.851375 -129.6648) (xy 198.903194 -129.649741) (xy 198.956619 -129.642135) (xy 199.010581 -129.642135)
			(xy 199.064006 -129.649741) (xy 199.115825 -129.6648) (xy 199.165005 -129.687012) (xy 199.210563 -129.715933)
			(xy 199.25159 -129.750987) (xy 199.287267 -129.791473) (xy 199.316882 -129.836584) (xy 199.328786 -129.860802)
			(xy 202.329288 -129.860802) (xy 202.353208 -129.845076) (xy 202.404764 -129.820198) (xy 202.459456 -129.803296)
			(xy 202.516058 -129.79475) (xy 202.573302 -129.79475) (xy 202.629904 -129.803296) (xy 202.684596 -129.820198)
			(xy 202.736152 -129.845076) (xy 202.760072 -129.860802) (xy 211.66201 -129.860802) (xy 222.918782 -118.60403)
			(xy 222.936825 -118.586775) (xy 222.97832 -118.559027) (xy 223.024438 -118.539922) (xy 223.0734 -118.530198)
			(xy 223.09836 -118.529608) (xy 240.219738 -118.529608) (xy 240.244693 -118.530223) (xy 240.293643 -118.539967)
			(xy 240.339751 -118.559073) (xy 240.381246 -118.586808) (xy 240.399316 -118.60403) (xy 244.7163 -122.921014)
			(xy 245.563136 -122.921014) (xy 245.563136 -122.057414) (xy 245.563622 -122.030163) (xy 245.571378 -121.976215)
			(xy 245.586733 -121.92392) (xy 245.609375 -121.874343) (xy 245.638841 -121.828493) (xy 245.674532 -121.787302)
			(xy 245.715723 -121.751611) (xy 245.761573 -121.722145) (xy 245.81115 -121.699503) (xy 245.863445 -121.684148)
			(xy 245.917393 -121.676392) (xy 245.971895 -121.676392) (xy 246.025843 -121.684148) (xy 246.078138 -121.699503)
			(xy 246.127715 -121.722145) (xy 246.173565 -121.751611) (xy 246.214756 -121.787302) (xy 246.250447 -121.828493)
			(xy 246.279913 -121.874343) (xy 246.302555 -121.92392) (xy 246.31791 -121.976215) (xy 246.325666 -122.030163)
			(xy 246.326152 -122.057414) (xy 246.326152 -122.921014) (xy 246.325666 -122.948265) (xy 246.31791 -123.002213)
			(xy 246.302555 -123.054508) (xy 246.279913 -123.104085) (xy 246.250447 -123.149935) (xy 246.214756 -123.191126)
			(xy 246.173565 -123.226817) (xy 246.127715 -123.256283) (xy 246.078138 -123.278925) (xy 246.025843 -123.29428)
			(xy 245.971895 -123.302036) (xy 245.917393 -123.302036) (xy 245.863445 -123.29428) (xy 245.81115 -123.278925)
			(xy 245.761573 -123.256283) (xy 245.715723 -123.226817) (xy 245.674532 -123.191126) (xy 245.638841 -123.149935)
			(xy 245.609375 -123.104085) (xy 245.586733 -123.054508) (xy 245.571378 -123.002213) (xy 245.563622 -122.948265)
			(xy 245.563136 -122.921014) (xy 244.7163 -122.921014) (xy 255.552194 -133.756908) (xy 296.120058 -133.756908)
		)
		(stroke
			(width 0)
			(type solid)
		)
		(fill yes)
		(layer "In9.Cu")
		(net "P3V3")
	)
	(gr_poly
		(pts
			(xy 121.731532 -261.808722) (xy 121.74278 -261.819215) (xy 121.770005 -261.833505) (xy 121.800247 -261.83906)
			(xy 121.830773 -261.835378) (xy 121.858827 -261.822793) (xy 121.870724 -261.81304) (xy 121.888804 -261.79758)
			(xy 121.928586 -261.771499) (xy 121.971719 -261.751439) (xy 122.017296 -261.737819) (xy 122.064364 -261.730926)
			(xy 122.088148 -261.73049) (xy 122.113022 -261.730946) (xy 122.162202 -261.738446) (xy 122.209687 -261.753282)
			(xy 122.254389 -261.775115) (xy 122.275092 -261.78891) (xy 122.84075 -261.78891) (xy 122.861461 -261.775128)
			(xy 122.906163 -261.753303) (xy 122.953645 -261.73847) (xy 123.002821 -261.730967) (xy 123.052567 -261.730967)
			(xy 123.101743 -261.73847) (xy 123.149225 -261.753303) (xy 123.193927 -261.775128) (xy 123.214638 -261.78891)
			(xy 123.780804 -261.78891) (xy 123.801515 -261.775128) (xy 123.846217 -261.753303) (xy 123.893699 -261.73847)
			(xy 123.942875 -261.730967) (xy 123.992621 -261.730967) (xy 124.041797 -261.73847) (xy 124.089279 -261.753303)
			(xy 124.133981 -261.775128) (xy 124.154692 -261.78891) (xy 124.720604 -261.78891) (xy 124.741315 -261.775128)
			(xy 124.786017 -261.753303) (xy 124.833499 -261.73847) (xy 124.882675 -261.730967) (xy 124.932421 -261.730967)
			(xy 124.981597 -261.73847) (xy 125.029079 -261.753303) (xy 125.073781 -261.775128) (xy 125.094492 -261.78891)
			(xy 125.66015 -261.78891) (xy 125.680861 -261.775129) (xy 125.725564 -261.753301) (xy 125.773045 -261.738461)
			(xy 125.822221 -261.730947) (xy 125.847094 -261.73049) (xy 125.870178 -261.730882) (xy 125.91589 -261.737348)
			(xy 125.960245 -261.750156) (xy 126.002368 -261.76905) (xy 126.0221 -261.781036) (xy 126.034546 -261.78891)
			(xy 126.104142 -261.78891) (xy 126.989078 -260.903974) (xy 126.989078 -259.806694) (xy 126.974821 -259.785783)
			(xy 126.952231 -259.740497) (xy 126.936868 -259.692276) (xy 126.929097 -259.642268) (xy 126.929103 -259.59166)
			(xy 126.936885 -259.541654) (xy 126.952258 -259.493437) (xy 126.974858 -259.448155) (xy 126.989078 -259.427218)
			(xy 126.989078 -258.178554) (xy 126.974884 -258.157654) (xy 126.952401 -258.112412) (xy 126.937112 -258.064261)
			(xy 126.929378 -258.014336) (xy 126.929382 -257.963815) (xy 126.937123 -257.913892) (xy 126.952419 -257.865742)
			(xy 126.974909 -257.820504) (xy 126.989078 -257.799586) (xy 126.989078 -256.551176) (xy 126.974814 -256.530265)
			(xy 126.952212 -256.484976) (xy 126.936837 -256.436753) (xy 126.929055 -256.386739) (xy 126.92905 -256.336123)
			(xy 126.936823 -256.286108) (xy 126.952189 -256.237881) (xy 126.974783 -256.192588) (xy 126.989078 -256.1717)
			(xy 126.989078 -254.92329) (xy 126.974821 -254.902379) (xy 126.952232 -254.857093) (xy 126.93687 -254.808873)
			(xy 126.929099 -254.758865) (xy 126.929105 -254.708257) (xy 126.936888 -254.658251) (xy 126.952261 -254.610035)
			(xy 126.974861 -254.564753) (xy 126.989078 -254.543814) (xy 126.989078 -249.907806) (xy 126.96731 -249.895335)
			(xy 126.9275 -249.864812) (xy 126.892797 -249.828587) (xy 126.864012 -249.787502) (xy 126.841815 -249.742515)
			(xy 126.826723 -249.694674) (xy 126.819087 -249.645094) (xy 126.819085 -249.594929) (xy 126.826717 -249.545348)
			(xy 126.841806 -249.497506) (xy 126.864001 -249.452518) (xy 126.892783 -249.411431) (xy 126.927482 -249.375203)
			(xy 126.967291 -249.344678) (xy 126.989078 -249.332242) (xy 126.989078 -248.27992) (xy 126.967309 -248.267449)
			(xy 126.927496 -248.236926) (xy 126.892792 -248.2007) (xy 126.864005 -248.159614) (xy 126.841806 -248.114626)
			(xy 126.826712 -248.066784) (xy 126.819075 -248.017202) (xy 126.819072 -247.967035) (xy 126.826704 -247.917452)
			(xy 126.841793 -247.869608) (xy 126.863987 -247.824617) (xy 126.892769 -247.783528) (xy 126.927469 -247.747298)
			(xy 126.967279 -247.716771) (xy 126.989078 -247.704356) (xy 126.989078 -246.652288) (xy 126.967312 -246.639817)
			(xy 126.927504 -246.609295) (xy 126.892804 -246.57307) (xy 126.864022 -246.531987) (xy 126.841827 -246.487001)
			(xy 126.826736 -246.439162) (xy 126.819102 -246.389584) (xy 126.819101 -246.339422) (xy 126.826735 -246.289843)
			(xy 126.841824 -246.242004) (xy 126.864019 -246.197018) (xy 126.8928 -246.155934) (xy 126.927499 -246.119709)
			(xy 126.967307 -246.089186) (xy 126.989078 -246.076724) (xy 126.989078 -245.024148) (xy 126.967338 -245.011682)
			(xy 126.927578 -244.981178) (xy 126.892922 -244.944981) (xy 126.864175 -244.903932) (xy 126.842009 -244.858989)
			(xy 126.826937 -244.811196) (xy 126.819312 -244.761666) (xy 126.81931 -244.711553) (xy 126.826933 -244.662023)
			(xy 126.842001 -244.614229) (xy 126.864166 -244.569284) (xy 126.892909 -244.528234) (xy 126.927563 -244.492035)
			(xy 126.967321 -244.461529) (xy 126.989078 -244.449092) (xy 126.989078 -243.39677) (xy 126.967313 -243.384299)
			(xy 126.927508 -243.353777) (xy 126.892811 -243.317553) (xy 126.864031 -243.276471) (xy 126.841838 -243.231487)
			(xy 126.826749 -243.18365) (xy 126.819117 -243.134074) (xy 126.819118 -243.083914) (xy 126.826752 -243.034338)
			(xy 126.841842 -242.986502) (xy 126.864037 -242.941519) (xy 126.892818 -242.900438) (xy 126.927516 -242.864215)
			(xy 126.967323 -242.833695) (xy 126.989078 -242.821206) (xy 126.989078 -241.768884) (xy 126.967312 -241.756413)
			(xy 126.927505 -241.725891) (xy 126.892806 -241.689666) (xy 126.864024 -241.648583) (xy 126.841829 -241.603598)
			(xy 126.826739 -241.55576) (xy 126.819105 -241.506182) (xy 126.819105 -241.45602) (xy 126.826739 -241.406442)
			(xy 126.841828 -241.358603) (xy 126.864023 -241.313619) (xy 126.892804 -241.272535) (xy 126.927503 -241.23631)
			(xy 126.96731 -241.205788) (xy 126.989078 -241.19332) (xy 126.989078 -240.140998) (xy 126.967312 -240.128527)
			(xy 126.927503 -240.098006) (xy 126.892802 -240.061782) (xy 126.864019 -240.020699) (xy 126.841822 -239.975714)
			(xy 126.82673 -239.927875) (xy 126.819094 -239.878297) (xy 126.818644 -239.853216) (xy 126.819066 -239.828862)
			(xy 126.82623 -239.780683) (xy 126.840448 -239.734096) (xy 126.861405 -239.690127) (xy 126.888641 -239.649745)
			(xy 126.90475 -239.631474) (xy 126.639066 -239.36579) (xy 126.623064 -239.362996) (xy 126.598063 -239.358329)
			(xy 126.549798 -239.342298) (xy 126.504585 -239.319011) (xy 126.463507 -239.289027) (xy 126.427548 -239.253063)
			(xy 126.397568 -239.211982) (xy 126.374287 -239.166766) (xy 126.358262 -239.118499) (xy 126.35357 -239.093502)
			(xy 126.350776 -239.0775) (xy 124.967746 -237.69447) (xy 124.935488 -237.709202) (xy 124.913779 -237.718816)
			(xy 124.868283 -237.732385) (xy 124.821304 -237.739247) (xy 124.797566 -237.739682) (xy 124.77178 -237.739174)
			(xy 124.720843 -237.731102) (xy 124.671796 -237.715161) (xy 124.625846 -237.691745) (xy 124.584124 -237.661429)
			(xy 124.547658 -237.624961) (xy 124.517345 -237.583237) (xy 124.493931 -237.537286) (xy 124.477994 -237.488238)
			(xy 124.469925 -237.4373) (xy 124.469398 -237.411514) (xy 124.469836 -237.387776) (xy 124.476707 -237.3408)
			(xy 124.490265 -237.295301) (xy 124.499878 -237.273592) (xy 124.51461 -237.241334) (xy 124.141992 -236.868716)
			(xy 124.138436 -236.86643) (xy 124.114849 -236.849005) (xy 124.073702 -236.807229) (xy 124.056648 -236.783372)
			(xy 122.555 -235.281724) (xy 122.52706 -235.288582) (xy 122.507562 -235.293111) (xy 122.467827 -235.297953)
			(xy 122.447812 -235.298234) (xy 122.422023 -235.297755) (xy 122.371079 -235.289688) (xy 122.322025 -235.273749)
			(xy 122.276068 -235.250333) (xy 122.234341 -235.220015) (xy 122.197871 -235.183542) (xy 122.167556 -235.141813)
			(xy 122.144142 -235.095855) (xy 122.128207 -235.0468) (xy 122.120143 -234.995855) (xy 122.119644 -234.970066)
			(xy 122.119927 -234.950051) (xy 122.124767 -234.910316) (xy 122.129296 -234.890818) (xy 122.136154 -234.862878)
			(xy 120.129046 -232.85577) (xy 120.107202 -232.856532) (xy 120.098312 -232.856532) (xy 120.072523 -232.856053)
			(xy 120.021579 -232.847986) (xy 119.972525 -232.832047) (xy 119.926569 -232.808631) (xy 119.884842 -232.778313)
			(xy 119.848371 -232.74184) (xy 119.818057 -232.700111) (xy 119.794643 -232.654153) (xy 119.778709 -232.605097)
			(xy 119.770645 -232.554153) (xy 119.770144 -232.528364) (xy 119.770144 -232.519474) (xy 119.770906 -232.49763)
			(xy 118.429024 -231.155748) (xy 118.394734 -231.177592) (xy 118.37493 -231.189676) (xy 118.332643 -231.208758)
			(xy 118.288092 -231.221698) (xy 118.242162 -231.228237) (xy 118.218966 -231.228646) (xy 118.193181 -231.228138)
			(xy 118.142246 -231.220065) (xy 118.093201 -231.204124) (xy 118.047254 -231.180708) (xy 118.005535 -231.150391)
			(xy 117.969072 -231.113923) (xy 117.938763 -231.072199) (xy 117.915354 -231.026247) (xy 117.899422 -230.977199)
			(xy 117.891358 -230.926263) (xy 117.890798 -230.900478) (xy 117.891201 -230.877282) (xy 117.897741 -230.831353)
			(xy 117.910687 -230.786804) (xy 117.929782 -230.744523) (xy 117.941852 -230.72471) (xy 117.963696 -230.69042)
			(xy 117.681502 -230.408226) (xy 117.667786 -230.40467) (xy 117.643546 -230.397999) (xy 117.597294 -230.378301)
			(xy 117.554587 -230.351779) (xy 117.516426 -230.319052) (xy 117.483703 -230.280888) (xy 117.457184 -230.238178)
			(xy 117.437491 -230.191924) (xy 117.430804 -230.167688) (xy 117.427248 -230.153972) (xy 116.023644 -228.750368)
			(xy 115.992656 -228.763068) (xy 115.96304 -228.774304) (xy 115.900879 -228.786446) (xy 115.869212 -228.787198)
			(xy 115.843423 -228.786693) (xy 115.79248 -228.778627) (xy 115.743425 -228.762691) (xy 115.697467 -228.739277)
			(xy 115.655738 -228.708963) (xy 115.619265 -228.672494) (xy 115.588945 -228.630768) (xy 115.565525 -228.584814)
			(xy 115.549583 -228.535761) (xy 115.54151 -228.484819) (xy 115.541044 -228.45903) (xy 115.541778 -228.427361)
			(xy 115.553926 -228.365199) (xy 115.565174 -228.335586) (xy 115.577874 -228.304598) (xy 115.180364 -227.907088)
			(xy 115.163342 -227.889242) (xy 115.135841 -227.848313) (xy 115.125754 -227.825808) (xy 115.11289 -227.805595)
			(xy 115.092569 -227.762206) (xy 115.078784 -227.71632) (xy 115.071827 -227.668916) (xy 115.071398 -227.64496)
			(xy 115.071804 -227.621409) (xy 115.078549 -227.574793) (xy 115.091909 -227.529625) (xy 115.10137 -227.508054)
			(xy 115.105942 -227.497894) (xy 115.105942 -226.164394) (xy 115.10137 -226.154234) (xy 115.091916 -226.132661)
			(xy 115.078579 -226.087489) (xy 115.071818 -226.040877) (xy 115.071398 -226.017328) (xy 115.071799 -225.993776)
			(xy 115.078535 -225.947156) (xy 115.091887 -225.901984) (xy 115.10137 -225.880422) (xy 115.105942 -225.870262)
			(xy 115.105942 -224.539556) (xy 115.101116 -224.529396) (xy 115.091333 -224.507374) (xy 115.077521 -224.461209)
			(xy 115.070539 -224.413531) (xy 115.070533 -224.365345) (xy 115.077505 -224.317665) (xy 115.091306 -224.271497)
			(xy 115.101116 -224.249488) (xy 115.105942 -224.239328) (xy 115.105942 -223.883982) (xy 115.046506 -223.883982)
			(xy 115.038378 -223.886776) (xy 115.026664 -223.890741) (xy 115.002761 -223.897095) (xy 114.990626 -223.899476)
			(xy 114.967766 -223.903794) (xy 114.763042 -224.258632) (xy 114.770916 -224.280476) (xy 114.779496 -224.306895)
			(xy 114.788693 -224.36167) (xy 114.789204 -224.389442) (xy 114.788696 -224.415329) (xy 114.780597 -224.466467)
			(xy 114.764598 -224.515707) (xy 114.741092 -224.561839) (xy 114.71066 -224.603726) (xy 114.67405 -224.640336)
			(xy 114.632163 -224.670768) (xy 114.586031 -224.694274) (xy 114.536791 -224.710273) (xy 114.485653 -224.718372)
			(xy 114.433879 -224.718372) (xy 114.382741 -224.710273) (xy 114.333501 -224.694274) (xy 114.287369 -224.670768)
			(xy 114.245482 -224.640336) (xy 114.208872 -224.603726) (xy 114.17844 -224.561839) (xy 114.154934 -224.515707)
			(xy 114.138935 -224.466467) (xy 114.130836 -224.415329) (xy 114.130328 -224.389442) (xy 114.130789 -224.364105)
			(xy 114.138537 -224.314026) (xy 114.153857 -224.265723) (xy 114.176387 -224.220333) (xy 114.205599 -224.178925)
			(xy 114.240802 -224.142475) (xy 114.281169 -224.111841) (xy 114.325747 -224.087744) (xy 114.373488 -224.070754)
			(xy 114.398298 -224.065592) (xy 114.421158 -224.061274) (xy 114.626136 -223.706182) (xy 114.618516 -223.684084)
			(xy 114.60997 -223.657788) (xy 114.600779 -223.60327) (xy 114.600228 -223.575626) (xy 114.600734 -223.549736)
			(xy 114.60883 -223.498594) (xy 114.624826 -223.449347) (xy 114.648329 -223.40321) (xy 114.678761 -223.361317)
			(xy 114.715371 -223.3247) (xy 114.757258 -223.294261) (xy 114.803392 -223.270749) (xy 114.852635 -223.254744)
			(xy 114.903776 -223.246638) (xy 114.929666 -223.246188) (xy 114.944025 -223.246296) (xy 114.972641 -223.248716)
			(xy 114.986816 -223.251014) (xy 115.001477 -223.253064) (xy 115.030864 -223.249591) (xy 115.058024 -223.237844)
			(xy 115.08068 -223.218809) (xy 115.096933 -223.194081) (xy 115.105421 -223.165733) (xy 115.105942 -223.150938)
			(xy 115.105942 -222.908622) (xy 115.10137 -222.898462) (xy 115.091914 -222.87689) (xy 115.078574 -222.831718)
			(xy 115.071809 -222.785106) (xy 115.071398 -222.761556) (xy 115.071804 -222.738005) (xy 115.07855 -222.691389)
			(xy 115.09191 -222.646222) (xy 115.10137 -222.62465) (xy 115.105942 -222.61449) (xy 115.105942 -221.284038)
			(xy 115.101116 -221.273878) (xy 115.091338 -221.251856) (xy 115.077539 -221.205692) (xy 115.070572 -221.158015)
			(xy 115.070128 -221.133924) (xy 115.070655 -221.106216) (xy 115.07985 -221.051569) (xy 115.088416 -221.025212)
			(xy 115.09629 -221.003114) (xy 114.891312 -220.648022) (xy 114.868452 -220.643704) (xy 114.843599 -220.638571)
			(xy 114.795743 -220.621685) (xy 114.751044 -220.597658) (xy 114.71056 -220.567059) (xy 114.675249 -220.530612)
			(xy 114.645946 -220.48918) (xy 114.623346 -220.443744) (xy 114.607983 -220.395378) (xy 114.600221 -220.345228)
			(xy 114.59972 -220.319854) (xy 114.600206 -220.293953) (xy 114.608319 -220.24279) (xy 114.624339 -220.193527)
			(xy 114.64787 -220.147378) (xy 114.678332 -220.10548) (xy 114.714976 -220.068865) (xy 114.756899 -220.038435)
			(xy 114.803066 -220.01494) (xy 114.852342 -219.998959) (xy 114.903511 -219.990885) (xy 114.929412 -219.990416)
			(xy 114.943835 -219.990515) (xy 114.972578 -219.992934) (xy 114.986816 -219.995242) (xy 115.001474 -219.997293)
			(xy 115.030854 -219.993819) (xy 115.058006 -219.982071) (xy 115.080651 -219.963034) (xy 115.09689 -219.938305)
			(xy 115.10536 -219.909958) (xy 115.105942 -219.895166) (xy 115.105942 -219.653104) (xy 115.10137 -219.642944)
			(xy 115.091915 -219.621372) (xy 115.078577 -219.5762) (xy 115.071815 -219.529588) (xy 115.071398 -219.506038)
			(xy 115.071798 -219.482486) (xy 115.078533 -219.435865) (xy 115.091884 -219.390693) (xy 115.10137 -219.369132)
			(xy 115.105942 -219.358972) (xy 115.105942 -218.02852) (xy 115.101116 -218.01836) (xy 115.091333 -217.996339)
			(xy 115.077522 -217.950175) (xy 115.070543 -217.902499) (xy 115.070128 -217.878406) (xy 115.070657 -217.850698)
			(xy 115.079855 -217.796052) (xy 115.088416 -217.769694) (xy 115.09629 -217.747596) (xy 114.891312 -217.392504)
			(xy 114.868452 -217.388186) (xy 114.843596 -217.383054) (xy 114.795735 -217.36617) (xy 114.751029 -217.342145)
			(xy 114.710537 -217.311547) (xy 114.675218 -217.275102) (xy 114.645905 -217.23367) (xy 114.623295 -217.188233)
			(xy 114.60792 -217.139865) (xy 114.600146 -217.089712) (xy 114.59972 -217.064336) (xy 114.600199 -217.038425)
			(xy 114.608301 -216.987241) (xy 114.624311 -216.937954) (xy 114.647834 -216.891779) (xy 114.678292 -216.849853)
			(xy 114.714934 -216.813208) (xy 114.756858 -216.782747) (xy 114.803032 -216.75922) (xy 114.852317 -216.743206)
			(xy 114.903501 -216.735101) (xy 114.929412 -216.734644) (xy 114.94384 -216.734812) (xy 114.972582 -216.737359)
			(xy 114.986816 -216.739724) (xy 115.001478 -216.741774) (xy 115.030865 -216.738301) (xy 115.058026 -216.726554)
			(xy 115.080684 -216.707519) (xy 115.096939 -216.682792) (xy 115.10543 -216.654444) (xy 115.105942 -216.639648)
			(xy 115.105942 -216.398094) (xy 115.10137 -216.387934) (xy 115.091825 -216.366297) (xy 115.078364 -216.320964)
			(xy 115.071569 -216.274165) (xy 115.071144 -216.25052) (xy 115.071581 -216.226877) (xy 115.078403 -216.180086)
			(xy 115.091853 -216.134753) (xy 115.10137 -216.113106) (xy 115.105942 -216.102946) (xy 115.105942 -214.773764)
			(xy 115.101116 -214.76335) (xy 115.091174 -214.741239) (xy 115.077152 -214.694832) (xy 115.070062 -214.646874)
			(xy 115.06962 -214.622634) (xy 115.069981 -214.599657) (xy 115.076293 -214.554141) (xy 115.088869 -214.509943)
			(xy 115.097814 -214.488776) (xy 115.10772 -214.466424) (xy 114.894106 -214.061294) (xy 114.869976 -214.056722)
			(xy 114.845055 -214.051631) (xy 114.797054 -214.034807) (xy 114.752206 -214.010813) (xy 114.711573 -213.980218)
			(xy 114.676118 -213.943748) (xy 114.646682 -213.902268) (xy 114.623963 -213.856761) (xy 114.608499 -213.808305)
			(xy 114.600658 -213.758049) (xy 114.600228 -213.732618) (xy 114.600734 -213.706729) (xy 114.608831 -213.655587)
			(xy 114.624828 -213.606342) (xy 114.648332 -213.560205) (xy 114.678764 -213.518313) (xy 114.715374 -213.481698)
			(xy 114.757261 -213.451259) (xy 114.803394 -213.427748) (xy 114.852637 -213.411743) (xy 114.903777 -213.403638)
			(xy 114.929666 -213.40318) (xy 114.944025 -213.403288) (xy 114.972641 -213.405708) (xy 114.986816 -213.408006)
			(xy 115.001477 -213.410056) (xy 115.030863 -213.406583) (xy 115.058022 -213.394836) (xy 115.080677 -213.375801)
			(xy 115.096928 -213.351073) (xy 115.105414 -213.322725) (xy 115.105942 -213.30793) (xy 115.105942 -195.700396)
			(xy 81.912714 -162.507168) (xy 81.906618 -162.500818) (xy 81.90611 -162.50031) (xy 79.898748 -160.492948)
			(xy 75.538076 -160.492948) (xy 75.517122 -160.510669) (xy 75.471085 -160.540537) (xy 75.42124 -160.563496)
			(xy 75.368619 -160.57907) (xy 75.314309 -160.586939) (xy 75.259431 -160.586939) (xy 75.205121 -160.57907)
			(xy 75.1525 -160.563496) (xy 75.102655 -160.540537) (xy 75.056618 -160.510669) (xy 75.035664 -160.492948)
			(xy 73.050146 -160.492948) (xy 73.028908 -160.511802) (xy 72.981894 -160.543658) (xy 72.930675 -160.568187)
			(xy 72.876384 -160.584849) (xy 72.820223 -160.593272) (xy 72.763433 -160.593272) (xy 72.707272 -160.584849)
			(xy 72.652981 -160.568187) (xy 72.601762 -160.543658) (xy 72.554748 -160.511802) (xy 72.53351 -160.492948)
			(xy 72.073516 -160.492948) (xy 70.918578 -161.647886) (xy 70.900539 -161.665151) (xy 70.859048 -161.692918)
			(xy 70.812929 -161.712039) (xy 70.763963 -161.721778) (xy 70.739 -161.722308) (xy 61.94298 -161.722308)
			(xy 61.582808 -162.08248) (xy 61.587634 -162.108642) (xy 61.590478 -162.125452) (xy 61.593531 -162.159412)
			(xy 61.59373 -162.17646) (xy 61.593194 -162.205721) (xy 61.58425 -162.263557) (xy 61.566582 -162.319349)
			(xy 61.540604 -162.37179) (xy 61.506925 -162.41965) (xy 61.466333 -162.461808) (xy 61.419782 -162.497274)
			(xy 61.39434 -162.51174) (xy 61.39434 -167.448992) (xy 61.395864 -167.455088) (xy 61.399546 -167.470511)
			(xy 61.403498 -167.501972) (xy 61.403738 -167.517826) (xy 61.403492 -167.53368) (xy 61.399538 -167.56514)
			(xy 61.395864 -167.580564) (xy 61.39434 -167.58666) (xy 61.39434 -168.801542) (xy 61.394594 -168.80459)
			(xy 61.396372 -168.8338) (xy 61.396372 -168.862248) (xy 61.394594 -168.891458) (xy 61.39434 -168.894506)
			(xy 61.39434 -169.889932) (xy 61.801756 -170.297348) (xy 65.6844 -170.297348) (xy 65.70936 -170.297919)
			(xy 65.758321 -170.30766) (xy 65.80444 -170.326767) (xy 65.845944 -170.354505) (xy 65.863978 -170.37177)
			(xy 68.177156 -172.684948) (xy 74.980038 -172.684948) (xy 75.004997 -172.685523) (xy 75.053953 -172.69527)
			(xy 75.100067 -172.714381) (xy 75.141566 -172.742123) (xy 75.159616 -172.75937) (xy 77.24902 -174.848774)
			(xy 77.265058 -174.865547) (xy 77.291383 -174.90376) (xy 77.301344 -174.92472) (xy 86.172548 -194.80276)
			(xy 86.176572 -194.811974) (xy 86.18331 -194.83092) (xy 86.18601 -194.840606) (xy 86.864698 -197.36943)
			(xy 86.887304 -197.379082) (xy 86.910791 -197.389673) (xy 86.954682 -197.416654) (xy 86.994192 -197.449719)
			(xy 87.028486 -197.488168) (xy 87.056837 -197.531187) (xy 87.078644 -197.577865) (xy 87.093447 -197.627214)
			(xy 87.100931 -197.678188) (xy 87.101426 -197.703948) (xy 87.100863 -197.732276) (xy 87.091822 -197.788206)
			(xy 87.073979 -197.841979) (xy 87.04779 -197.892219) (xy 87.031322 -197.915276) (xy 87.01659 -197.935088)
			(xy 88.597486 -203.825094) (xy 88.641682 -203.819506) (xy 88.712178 -203.811037) (xy 88.853891 -203.802016)
			(xy 88.924892 -203.801472) (xy 88.992065 -203.801979) (xy 89.126165 -203.81009) (xy 89.25953 -203.826283)
			(xy 89.391675 -203.850499) (xy 89.522116 -203.882649) (xy 89.650378 -203.922617) (xy 89.775993 -203.970256)
			(xy 89.898503 -204.025392) (xy 90.01746 -204.087825) (xy 90.13243 -204.157326) (xy 90.242994 -204.233642)
			(xy 90.348749 -204.316495) (xy 90.449308 -204.405582) (xy 90.544304 -204.500578) (xy 90.633392 -204.601136)
			(xy 90.716246 -204.70689) (xy 90.792563 -204.817453) (xy 90.862065 -204.932423) (xy 90.924499 -205.051379)
			(xy 90.979637 -205.173888) (xy 91.027277 -205.299503) (xy 91.067245 -205.427765) (xy 91.099397 -205.558206)
			(xy 91.123614 -205.69035) (xy 91.139808 -205.823716) (xy 91.147921 -205.957815) (xy 91.148408 -206.024988)
			(xy 91.147952 -206.089784) (xy 91.140422 -206.219157) (xy 91.125369 -206.347872) (xy 91.102844 -206.475492)
			(xy 91.072923 -206.601583) (xy 91.035709 -206.725717) (xy 90.991327 -206.847472) (xy 90.966036 -206.90713)
			(xy 90.94851 -206.948024) (xy 101.025198 -213.021926) (xy 101.043629 -213.033536) (xy 101.076576 -213.062028)
			(xy 101.104177 -213.095724) (xy 101.125622 -213.133637) (xy 101.14028 -213.174654) (xy 101.147723 -213.217571)
			(xy 101.148134 -213.23935) (xy 101.148134 -213.64194) (xy 101.149912 -213.64829) (xy 101.155045 -213.668992)
			(xy 101.160518 -213.711291) (xy 101.160834 -213.732618) (xy 101.443028 -213.732618) (xy 101.443536 -213.706731)
			(xy 101.451635 -213.655593) (xy 101.467634 -213.606353) (xy 101.49114 -213.560221) (xy 101.521572 -213.518334)
			(xy 101.558182 -213.481724) (xy 101.600069 -213.451292) (xy 101.646201 -213.427786) (xy 101.695441 -213.411787)
			(xy 101.746579 -213.403688) (xy 101.798353 -213.403688) (xy 101.849491 -213.411787) (xy 101.898731 -213.427786)
			(xy 101.944863 -213.451292) (xy 101.98675 -213.481724) (xy 102.02336 -213.518334) (xy 102.053792 -213.560221)
			(xy 102.077298 -213.606353) (xy 102.093297 -213.655593) (xy 102.101396 -213.706731) (xy 102.101904 -213.732618)
			(xy 103.322628 -213.732618) (xy 103.323136 -213.706731) (xy 103.331235 -213.655593) (xy 103.347234 -213.606353)
			(xy 103.37074 -213.560221) (xy 103.401172 -213.518334) (xy 103.437782 -213.481724) (xy 103.479669 -213.451292)
			(xy 103.525801 -213.427786) (xy 103.575041 -213.411787) (xy 103.626179 -213.403688) (xy 103.677953 -213.403688)
			(xy 103.729091 -213.411787) (xy 103.778331 -213.427786) (xy 103.824463 -213.451292) (xy 103.86635 -213.481724)
			(xy 103.90296 -213.518334) (xy 103.933392 -213.560221) (xy 103.956898 -213.606353) (xy 103.972897 -213.655593)
			(xy 103.980996 -213.706731) (xy 103.981504 -213.732618) (xy 105.202228 -213.732618) (xy 105.202736 -213.706731)
			(xy 105.210835 -213.655593) (xy 105.226834 -213.606353) (xy 105.25034 -213.560221) (xy 105.280772 -213.518334)
			(xy 105.317382 -213.481724) (xy 105.359269 -213.451292) (xy 105.405401 -213.427786) (xy 105.454641 -213.411787)
			(xy 105.505779 -213.403688) (xy 105.557553 -213.403688) (xy 105.608691 -213.411787) (xy 105.657931 -213.427786)
			(xy 105.704063 -213.451292) (xy 105.74595 -213.481724) (xy 105.78256 -213.518334) (xy 105.812992 -213.560221)
			(xy 105.836498 -213.606353) (xy 105.852497 -213.655593) (xy 105.860596 -213.706731) (xy 105.861104 -213.732618)
			(xy 107.081828 -213.732618) (xy 107.082336 -213.706731) (xy 107.090435 -213.655593) (xy 107.106434 -213.606353)
			(xy 107.12994 -213.560221) (xy 107.160372 -213.518334) (xy 107.196982 -213.481724) (xy 107.238869 -213.451292)
			(xy 107.285001 -213.427786) (xy 107.334241 -213.411787) (xy 107.385379 -213.403688) (xy 107.437153 -213.403688)
			(xy 107.488291 -213.411787) (xy 107.537531 -213.427786) (xy 107.583663 -213.451292) (xy 107.62555 -213.481724)
			(xy 107.66216 -213.518334) (xy 107.692592 -213.560221) (xy 107.716098 -213.606353) (xy 107.732097 -213.655593)
			(xy 107.740196 -213.706731) (xy 107.740704 -213.732618) (xy 107.740353 -213.755595) (xy 107.734032 -213.80111)
			(xy 107.721448 -213.845306) (xy 107.71251 -213.866476) (xy 107.702604 -213.888828) (xy 107.916218 -214.293958)
			(xy 107.940348 -214.29853) (xy 107.965267 -214.303641) (xy 108.013277 -214.320441) (xy 108.058136 -214.344419)
			(xy 108.098776 -214.375006) (xy 108.134234 -214.411476) (xy 108.163666 -214.452961) (xy 108.186373 -214.498476)
			(xy 108.201815 -214.54694) (xy 108.209627 -214.597201) (xy 108.210096 -214.622634) (xy 108.209588 -214.648521)
			(xy 108.201489 -214.699659) (xy 108.18549 -214.748899) (xy 108.161984 -214.795031) (xy 108.131552 -214.836918)
			(xy 108.094942 -214.873528) (xy 108.053055 -214.90396) (xy 108.006923 -214.927466) (xy 107.957683 -214.943465)
			(xy 107.906545 -214.951564) (xy 107.854771 -214.951564) (xy 107.803633 -214.943465) (xy 107.754393 -214.927466)
			(xy 107.708261 -214.90396) (xy 107.666374 -214.873528) (xy 107.629764 -214.836918) (xy 107.599332 -214.795031)
			(xy 107.575826 -214.748899) (xy 107.559827 -214.699659) (xy 107.551728 -214.648521) (xy 107.55122 -214.622634)
			(xy 107.551587 -214.599658) (xy 107.5579 -214.554143) (xy 107.570479 -214.509947) (xy 107.579414 -214.488776)
			(xy 107.58932 -214.466424) (xy 107.375706 -214.061294) (xy 107.351576 -214.056722) (xy 107.32665 -214.051639)
			(xy 107.278636 -214.034839) (xy 107.233775 -214.010859) (xy 107.193132 -213.980269) (xy 107.157674 -213.943796)
			(xy 107.128243 -213.902307) (xy 107.105538 -213.856787) (xy 107.0901 -213.808318) (xy 107.082294 -213.758052)
			(xy 107.081828 -213.732618) (xy 105.861104 -213.732618) (xy 105.860753 -213.755595) (xy 105.854432 -213.80111)
			(xy 105.841848 -213.845306) (xy 105.83291 -213.866476) (xy 105.823004 -213.888828) (xy 106.036618 -214.293958)
			(xy 106.060748 -214.29853) (xy 106.085667 -214.303641) (xy 106.133677 -214.320441) (xy 106.178536 -214.344419)
			(xy 106.219176 -214.375006) (xy 106.254634 -214.411476) (xy 106.284066 -214.452961) (xy 106.306773 -214.498476)
			(xy 106.322215 -214.54694) (xy 106.330027 -214.597201) (xy 106.330496 -214.622634) (xy 106.329988 -214.648521)
			(xy 106.321889 -214.699659) (xy 106.30589 -214.748899) (xy 106.282384 -214.795031) (xy 106.251952 -214.836918)
			(xy 106.215342 -214.873528) (xy 106.173455 -214.90396) (xy 106.127323 -214.927466) (xy 106.078083 -214.943465)
			(xy 106.026945 -214.951564) (xy 105.975171 -214.951564) (xy 105.924033 -214.943465) (xy 105.874793 -214.927466)
			(xy 105.828661 -214.90396) (xy 105.786774 -214.873528) (xy 105.750164 -214.836918) (xy 105.719732 -214.795031)
			(xy 105.696226 -214.748899) (xy 105.680227 -214.699659) (xy 105.672128 -214.648521) (xy 105.67162 -214.622634)
			(xy 105.671987 -214.599658) (xy 105.6783 -214.554143) (xy 105.690879 -214.509947) (xy 105.699814 -214.488776)
			(xy 105.70972 -214.466424) (xy 105.496106 -214.061294) (xy 105.471976 -214.056722) (xy 105.44705 -214.051639)
			(xy 105.399036 -214.034839) (xy 105.354175 -214.010859) (xy 105.313532 -213.980269) (xy 105.278074 -213.943796)
			(xy 105.248643 -213.902307) (xy 105.225938 -213.856787) (xy 105.2105 -213.808318) (xy 105.202694 -213.758052)
			(xy 105.202228 -213.732618) (xy 103.981504 -213.732618) (xy 103.981153 -213.755595) (xy 103.974832 -213.80111)
			(xy 103.962248 -213.845306) (xy 103.95331 -213.866476) (xy 103.943404 -213.888828) (xy 104.157018 -214.293958)
			(xy 104.181148 -214.29853) (xy 104.206067 -214.303641) (xy 104.254077 -214.320441) (xy 104.298936 -214.344419)
			(xy 104.339576 -214.375006) (xy 104.375034 -214.411476) (xy 104.404466 -214.452961) (xy 104.427173 -214.498476)
			(xy 104.442615 -214.54694) (xy 104.450427 -214.597201) (xy 104.450896 -214.622634) (xy 104.450388 -214.648521)
			(xy 104.442289 -214.699659) (xy 104.42629 -214.748899) (xy 104.402784 -214.795031) (xy 104.372352 -214.836918)
			(xy 104.335742 -214.873528) (xy 104.293855 -214.90396) (xy 104.247723 -214.927466) (xy 104.198483 -214.943465)
			(xy 104.147345 -214.951564) (xy 104.095571 -214.951564) (xy 104.044433 -214.943465) (xy 103.995193 -214.927466)
			(xy 103.949061 -214.90396) (xy 103.907174 -214.873528) (xy 103.870564 -214.836918) (xy 103.840132 -214.795031)
			(xy 103.816626 -214.748899) (xy 103.800627 -214.699659) (xy 103.792528 -214.648521) (xy 103.79202 -214.622634)
			(xy 103.792387 -214.599658) (xy 103.7987 -214.554143) (xy 103.811279 -214.509947) (xy 103.820214 -214.488776)
			(xy 103.83012 -214.466424) (xy 103.616506 -214.061294) (xy 103.592376 -214.056722) (xy 103.56745 -214.051639)
			(xy 103.519436 -214.034839) (xy 103.474575 -214.010859) (xy 103.433932 -213.980269) (xy 103.398474 -213.943796)
			(xy 103.369043 -213.902307) (xy 103.346338 -213.856787) (xy 103.3309 -213.808318) (xy 103.323094 -213.758052)
			(xy 103.322628 -213.732618) (xy 102.101904 -213.732618) (xy 102.101553 -213.755595) (xy 102.095232 -213.80111)
			(xy 102.082648 -213.845306) (xy 102.07371 -213.866476) (xy 102.063804 -213.888828) (xy 102.277418 -214.293958)
			(xy 102.301548 -214.29853) (xy 102.326467 -214.303641) (xy 102.374477 -214.320441) (xy 102.419336 -214.344419)
			(xy 102.459976 -214.375006) (xy 102.495434 -214.411476) (xy 102.524866 -214.452961) (xy 102.547573 -214.498476)
			(xy 102.563015 -214.54694) (xy 102.570827 -214.597201) (xy 102.571296 -214.622634) (xy 102.570788 -214.648521)
			(xy 102.562689 -214.699659) (xy 102.54669 -214.748899) (xy 102.523184 -214.795031) (xy 102.492752 -214.836918)
			(xy 102.456142 -214.873528) (xy 102.414255 -214.90396) (xy 102.368123 -214.927466) (xy 102.318883 -214.943465)
			(xy 102.267745 -214.951564) (xy 102.215971 -214.951564) (xy 102.164833 -214.943465) (xy 102.115593 -214.927466)
			(xy 102.069461 -214.90396) (xy 102.027574 -214.873528) (xy 101.990964 -214.836918) (xy 101.960532 -214.795031)
			(xy 101.937026 -214.748899) (xy 101.921027 -214.699659) (xy 101.912928 -214.648521) (xy 101.91242 -214.622634)
			(xy 101.912787 -214.599658) (xy 101.9191 -214.554143) (xy 101.931679 -214.509947) (xy 101.940614 -214.488776)
			(xy 101.95052 -214.466424) (xy 101.736906 -214.061294) (xy 101.712776 -214.056722) (xy 101.68785 -214.051639)
			(xy 101.639836 -214.034839) (xy 101.594975 -214.010859) (xy 101.554332 -213.980269) (xy 101.518874 -213.943796)
			(xy 101.489443 -213.902307) (xy 101.466738 -213.856787) (xy 101.4513 -213.808318) (xy 101.443494 -213.758052)
			(xy 101.443028 -213.732618) (xy 101.160834 -213.732618) (xy 101.160511 -213.753944) (xy 101.155038 -213.796243)
			(xy 101.149912 -213.816946) (xy 101.148134 -213.823296) (xy 101.148134 -214.194644) (xy 101.148633 -214.209003)
			(xy 101.156643 -214.236581) (xy 101.172017 -214.260837) (xy 101.193538 -214.279852) (xy 101.219504 -214.29212)
			(xy 101.247859 -214.296671) (xy 101.26218 -214.295482) (xy 101.272112 -214.294374) (xy 101.292065 -214.293227)
			(xy 101.302058 -214.293196) (xy 101.327949 -214.293674) (xy 101.379093 -214.301769) (xy 101.428341 -214.317766)
			(xy 101.47448 -214.341272) (xy 101.516373 -214.371707) (xy 101.552988 -214.408321) (xy 101.583424 -214.450213)
			(xy 101.606931 -214.496351) (xy 101.622929 -214.545599) (xy 101.631025 -214.596743) (xy 101.631496 -214.622634)
			(xy 101.63103 -214.647968) (xy 101.623272 -214.69804) (xy 101.607946 -214.746335) (xy 101.585411 -214.791716)
			(xy 101.556199 -214.833116) (xy 101.520996 -214.869559) (xy 101.480632 -214.900187) (xy 101.436058 -214.924279)
			(xy 101.388322 -214.941268) (xy 101.363526 -214.946484) (xy 101.340666 -214.950802) (xy 101.148134 -215.284558)
			(xy 101.148134 -215.341962) (xy 101.149912 -215.348566) (xy 101.155578 -215.37016) (xy 101.1617 -215.414383)
			(xy 101.162104 -215.436704) (xy 102.38232 -215.436704) (xy 102.382829 -215.41136) (xy 102.3906 -215.36127)
			(xy 102.405946 -215.31296) (xy 102.428503 -215.267567) (xy 102.457742 -215.226161) (xy 102.492973 -215.189717)
			(xy 102.533365 -215.159094) (xy 102.577969 -215.135013) (xy 102.625732 -215.118041) (xy 102.650544 -215.112854)
			(xy 102.673404 -215.108536) (xy 102.878382 -214.753444) (xy 102.870508 -214.7316) (xy 102.861929 -214.705181)
			(xy 102.852732 -214.650406) (xy 102.85222 -214.622634) (xy 102.852728 -214.596747) (xy 102.860827 -214.545609)
			(xy 102.876826 -214.496369) (xy 102.900332 -214.450237) (xy 102.930764 -214.40835) (xy 102.967374 -214.37174)
			(xy 103.009261 -214.341308) (xy 103.055393 -214.317802) (xy 103.104633 -214.301803) (xy 103.155771 -214.293704)
			(xy 103.207545 -214.293704) (xy 103.258683 -214.301803) (xy 103.307923 -214.317802) (xy 103.354055 -214.341308)
			(xy 103.395942 -214.37174) (xy 103.432552 -214.40835) (xy 103.462984 -214.450237) (xy 103.48649 -214.496369)
			(xy 103.502489 -214.545609) (xy 103.510588 -214.596747) (xy 103.511096 -214.622634) (xy 103.510647 -214.64797)
			(xy 103.50289 -214.698044) (xy 103.487563 -214.746341) (xy 103.465027 -214.791726) (xy 103.435812 -214.833128)
			(xy 103.400608 -214.869572) (xy 103.360242 -214.900202) (xy 103.315665 -214.924296) (xy 103.267927 -214.941286)
			(xy 103.243126 -214.946484) (xy 103.220266 -214.950802) (xy 103.015288 -215.305894) (xy 103.023162 -215.327738)
			(xy 103.03181 -215.354146) (xy 103.041129 -215.408922) (xy 103.041704 -215.436704) (xy 104.26192 -215.436704)
			(xy 104.262429 -215.41136) (xy 104.2702 -215.36127) (xy 104.285546 -215.31296) (xy 104.308103 -215.267567)
			(xy 104.337342 -215.226161) (xy 104.372573 -215.189717) (xy 104.412965 -215.159094) (xy 104.457569 -215.135013)
			(xy 104.505332 -215.118041) (xy 104.530144 -215.112854) (xy 104.553004 -215.108536) (xy 104.757982 -214.753444)
			(xy 104.750108 -214.7316) (xy 104.741529 -214.705181) (xy 104.732332 -214.650406) (xy 104.73182 -214.622634)
			(xy 104.732328 -214.596747) (xy 104.740427 -214.545609) (xy 104.756426 -214.496369) (xy 104.779932 -214.450237)
			(xy 104.810364 -214.40835) (xy 104.846974 -214.37174) (xy 104.888861 -214.341308) (xy 104.934993 -214.317802)
			(xy 104.984233 -214.301803) (xy 105.035371 -214.293704) (xy 105.087145 -214.293704) (xy 105.138283 -214.301803)
			(xy 105.187523 -214.317802) (xy 105.233655 -214.341308) (xy 105.275542 -214.37174) (xy 105.312152 -214.40835)
			(xy 105.342584 -214.450237) (xy 105.36609 -214.496369) (xy 105.382089 -214.545609) (xy 105.390188 -214.596747)
			(xy 105.390696 -214.622634) (xy 105.390247 -214.64797) (xy 105.38249 -214.698044) (xy 105.367163 -214.746341)
			(xy 105.344627 -214.791726) (xy 105.315412 -214.833128) (xy 105.280208 -214.869572) (xy 105.239842 -214.900202)
			(xy 105.195265 -214.924296) (xy 105.147527 -214.941286) (xy 105.122726 -214.946484) (xy 105.099866 -214.950802)
			(xy 104.894888 -215.305894) (xy 104.902762 -215.327738) (xy 104.91141 -215.354146) (xy 104.920729 -215.408922)
			(xy 104.921304 -215.436704) (xy 106.14152 -215.436704) (xy 106.142029 -215.41136) (xy 106.1498 -215.36127)
			(xy 106.165146 -215.31296) (xy 106.187703 -215.267567) (xy 106.216942 -215.226161) (xy 106.252173 -215.189717)
			(xy 106.292565 -215.159094) (xy 106.337169 -215.135013) (xy 106.384932 -215.118041) (xy 106.409744 -215.112854)
			(xy 106.432604 -215.108536) (xy 106.637582 -214.753444) (xy 106.629708 -214.7316) (xy 106.621129 -214.705181)
			(xy 106.611932 -214.650406) (xy 106.61142 -214.622634) (xy 106.611928 -214.596747) (xy 106.620027 -214.545609)
			(xy 106.636026 -214.496369) (xy 106.659532 -214.450237) (xy 106.689964 -214.40835) (xy 106.726574 -214.37174)
			(xy 106.768461 -214.341308) (xy 106.814593 -214.317802) (xy 106.863833 -214.301803) (xy 106.914971 -214.293704)
			(xy 106.966745 -214.293704) (xy 107.017883 -214.301803) (xy 107.067123 -214.317802) (xy 107.113255 -214.341308)
			(xy 107.155142 -214.37174) (xy 107.191752 -214.40835) (xy 107.222184 -214.450237) (xy 107.24569 -214.496369)
			(xy 107.261689 -214.545609) (xy 107.269788 -214.596747) (xy 107.270296 -214.622634) (xy 107.269847 -214.64797)
			(xy 107.26209 -214.698044) (xy 107.246763 -214.746341) (xy 107.224227 -214.791726) (xy 107.195012 -214.833128)
			(xy 107.159808 -214.869572) (xy 107.119442 -214.900202) (xy 107.074865 -214.924296) (xy 107.027127 -214.941286)
			(xy 107.002326 -214.946484) (xy 106.979466 -214.950802) (xy 106.774488 -215.305894) (xy 106.782362 -215.327738)
			(xy 106.79101 -215.354146) (xy 106.800329 -215.408922) (xy 106.800904 -215.436704) (xy 108.02112 -215.436704)
			(xy 108.021629 -215.41136) (xy 108.0294 -215.36127) (xy 108.044746 -215.31296) (xy 108.067303 -215.267567)
			(xy 108.096542 -215.226161) (xy 108.131773 -215.189717) (xy 108.172165 -215.159094) (xy 108.216769 -215.135013)
			(xy 108.264532 -215.118041) (xy 108.289344 -215.112854) (xy 108.312204 -215.108536) (xy 108.517182 -214.753444)
			(xy 108.509308 -214.7316) (xy 108.500729 -214.705181) (xy 108.491532 -214.650406) (xy 108.49102 -214.622634)
			(xy 108.491528 -214.596747) (xy 108.499627 -214.545609) (xy 108.515626 -214.496369) (xy 108.539132 -214.450237)
			(xy 108.569564 -214.40835) (xy 108.606174 -214.37174) (xy 108.648061 -214.341308) (xy 108.694193 -214.317802)
			(xy 108.743433 -214.301803) (xy 108.794571 -214.293704) (xy 108.846345 -214.293704) (xy 108.897483 -214.301803)
			(xy 108.946723 -214.317802) (xy 108.992855 -214.341308) (xy 109.034742 -214.37174) (xy 109.071352 -214.40835)
			(xy 109.101784 -214.450237) (xy 109.12529 -214.496369) (xy 109.141289 -214.545609) (xy 109.14142 -214.546434)
			(xy 110.371128 -214.546434) (xy 110.371636 -214.520547) (xy 110.379735 -214.469409) (xy 110.395734 -214.420169)
			(xy 110.41924 -214.374037) (xy 110.449672 -214.33215) (xy 110.486282 -214.29554) (xy 110.528169 -214.265108)
			(xy 110.574301 -214.241602) (xy 110.623541 -214.225603) (xy 110.674679 -214.217504) (xy 110.726453 -214.217504)
			(xy 110.777591 -214.225603) (xy 110.826831 -214.241602) (xy 110.872963 -214.265108) (xy 110.91485 -214.29554)
			(xy 110.95146 -214.33215) (xy 110.981892 -214.374037) (xy 111.005398 -214.420169) (xy 111.021397 -214.469409)
			(xy 111.029496 -214.520547) (xy 111.030004 -214.546434) (xy 111.029625 -214.569368) (xy 111.029219 -214.572283)
			(xy 112.250803 -214.572283) (xy 112.250803 -214.520517) (xy 112.258901 -214.469389) (xy 112.274896 -214.420157)
			(xy 112.298395 -214.374033) (xy 112.32882 -214.332153) (xy 112.365421 -214.295547) (xy 112.407297 -214.265117)
			(xy 112.453418 -214.241612) (xy 112.502648 -214.22561) (xy 112.553775 -214.217507) (xy 112.579658 -214.216996)
			(xy 112.605169 -214.217509) (xy 112.655581 -214.225363) (xy 112.704182 -214.24089) (xy 112.749811 -214.263719)
			(xy 112.791377 -214.293306) (xy 112.827889 -214.328944) (xy 112.843564 -214.349076) (xy 113.255552 -214.349076)
			(xy 113.271247 -214.328958) (xy 113.307753 -214.293314) (xy 113.349314 -214.263719) (xy 113.394938 -214.24088)
			(xy 113.443536 -214.225342) (xy 113.493947 -214.217476) (xy 113.519458 -214.216996) (xy 113.545352 -214.217406)
			(xy 113.596504 -214.225502) (xy 113.645759 -214.2415) (xy 113.691905 -214.265008) (xy 113.733805 -214.295445)
			(xy 113.770428 -214.332063) (xy 113.80087 -214.373959) (xy 113.824384 -214.420102) (xy 113.840388 -214.469355)
			(xy 113.848491 -214.520506) (xy 113.848491 -214.572294) (xy 113.840388 -214.623445) (xy 113.824384 -214.672698)
			(xy 113.80087 -214.718841) (xy 113.770428 -214.760737) (xy 113.733805 -214.797355) (xy 113.691905 -214.827792)
			(xy 113.645759 -214.8513) (xy 113.596504 -214.867298) (xy 113.545352 -214.875394) (xy 113.519458 -214.875872)
			(xy 113.493944 -214.875433) (xy 113.443527 -214.867566) (xy 113.394925 -214.852025) (xy 113.349296 -214.829181)
			(xy 113.307732 -214.799581) (xy 113.271224 -214.763931) (xy 113.255552 -214.743792) (xy 112.843564 -214.743792)
			(xy 112.827909 -214.763943) (xy 112.791396 -214.799586) (xy 112.749827 -214.829178) (xy 112.704195 -214.852012)
			(xy 112.655589 -214.867542) (xy 112.605171 -214.875398) (xy 112.579658 -214.875872) (xy 112.553775 -214.875293)
			(xy 112.502648 -214.86719) (xy 112.453418 -214.851188) (xy 112.407297 -214.827683) (xy 112.365421 -214.797253)
			(xy 112.32882 -214.760647) (xy 112.298395 -214.718767) (xy 112.274896 -214.672643) (xy 112.258901 -214.623411)
			(xy 112.250803 -214.572283) (xy 111.029219 -214.572283) (xy 111.023299 -214.614796) (xy 111.010731 -214.658907)
			(xy 111.00181 -214.680038) (xy 110.991904 -214.702644) (xy 111.205772 -215.108028) (xy 111.229902 -215.1126)
			(xy 111.254835 -215.117694) (xy 111.302873 -215.134477) (xy 111.347761 -215.158443) (xy 111.388433 -215.189024)
			(xy 111.423922 -215.225492) (xy 111.453384 -215.266981) (xy 111.47612 -215.312505) (xy 111.491589 -215.360982)
			(xy 111.499424 -215.411261) (xy 111.499904 -215.436704) (xy 113.65992 -215.436704) (xy 113.660429 -215.41136)
			(xy 113.6682 -215.36127) (xy 113.683546 -215.31296) (xy 113.706103 -215.267567) (xy 113.735342 -215.226161)
			(xy 113.770573 -215.189717) (xy 113.810965 -215.159094) (xy 113.855569 -215.135013) (xy 113.903332 -215.118041)
			(xy 113.928144 -215.112854) (xy 113.951004 -215.108536) (xy 114.156236 -214.753444) (xy 114.148362 -214.731346)
			(xy 114.139733 -214.704999) (xy 114.130411 -214.650352) (xy 114.12982 -214.622634) (xy 114.130328 -214.596727)
			(xy 114.138434 -214.54555) (xy 114.154446 -214.496271) (xy 114.177969 -214.450104) (xy 114.208425 -214.408185)
			(xy 114.245063 -214.371547) (xy 114.286982 -214.341091) (xy 114.333149 -214.317568) (xy 114.382428 -214.301556)
			(xy 114.433605 -214.29345) (xy 114.485419 -214.29345) (xy 114.536596 -214.301556) (xy 114.585875 -214.317568)
			(xy 114.632042 -214.341091) (xy 114.673961 -214.371547) (xy 114.710599 -214.408185) (xy 114.741055 -214.450104)
			(xy 114.764578 -214.496271) (xy 114.78059 -214.54555) (xy 114.788696 -214.596727) (xy 114.789204 -214.622634)
			(xy 114.78871 -214.647978) (xy 114.780934 -214.698068) (xy 114.765584 -214.746377) (xy 114.743024 -214.791769)
			(xy 114.713783 -214.833174) (xy 114.678552 -214.869617) (xy 114.638158 -214.90024) (xy 114.593555 -214.924322)
			(xy 114.545792 -214.941296) (xy 114.52098 -214.946484) (xy 114.49812 -214.950802) (xy 114.292888 -215.305894)
			(xy 114.300762 -215.327992) (xy 114.309397 -215.354337) (xy 114.318716 -215.408986) (xy 114.319304 -215.436704)
			(xy 114.318796 -215.462611) (xy 114.31069 -215.513788) (xy 114.294678 -215.563067) (xy 114.271155 -215.609234)
			(xy 114.240699 -215.651153) (xy 114.204061 -215.687791) (xy 114.162142 -215.718247) (xy 114.115975 -215.74177)
			(xy 114.066696 -215.757782) (xy 114.015519 -215.765888) (xy 113.963705 -215.765888) (xy 113.912528 -215.757782)
			(xy 113.863249 -215.74177) (xy 113.817082 -215.718247) (xy 113.775163 -215.687791) (xy 113.738525 -215.651153)
			(xy 113.708069 -215.609234) (xy 113.684546 -215.563067) (xy 113.668534 -215.513788) (xy 113.660428 -215.462611)
			(xy 113.65992 -215.436704) (xy 111.499904 -215.436704) (xy 111.499396 -215.462611) (xy 111.49129 -215.513788)
			(xy 111.475278 -215.563067) (xy 111.451755 -215.609234) (xy 111.421299 -215.651153) (xy 111.384661 -215.687791)
			(xy 111.342742 -215.718247) (xy 111.296575 -215.74177) (xy 111.247296 -215.757782) (xy 111.196119 -215.765888)
			(xy 111.144305 -215.765888) (xy 111.093128 -215.757782) (xy 111.043849 -215.74177) (xy 110.997682 -215.718247)
			(xy 110.955763 -215.687791) (xy 110.919125 -215.651153) (xy 110.888669 -215.609234) (xy 110.865146 -215.563067)
			(xy 110.849134 -215.513788) (xy 110.841028 -215.462611) (xy 110.84052 -215.436704) (xy 110.840955 -215.413764)
			(xy 110.847378 -215.368334) (xy 110.860018 -215.324227) (xy 110.868968 -215.3031) (xy 110.878874 -215.280494)
			(xy 110.665006 -214.87511) (xy 110.640876 -214.870538) (xy 110.615954 -214.86544) (xy 110.567941 -214.848641)
			(xy 110.523081 -214.824663) (xy 110.482438 -214.794075) (xy 110.44698 -214.757604) (xy 110.417549 -214.716116)
			(xy 110.394843 -214.670598) (xy 110.379403 -214.622131) (xy 110.371595 -214.571867) (xy 110.371128 -214.546434)
			(xy 109.14142 -214.546434) (xy 109.149388 -214.596747) (xy 109.149896 -214.622634) (xy 109.149447 -214.64797)
			(xy 109.14169 -214.698044) (xy 109.126363 -214.746341) (xy 109.103827 -214.791726) (xy 109.074612 -214.833128)
			(xy 109.039408 -214.869572) (xy 108.999042 -214.900202) (xy 108.954465 -214.924296) (xy 108.906727 -214.941286)
			(xy 108.881926 -214.946484) (xy 108.859066 -214.950802) (xy 108.654088 -215.305894) (xy 108.661962 -215.327738)
			(xy 108.67061 -215.354146) (xy 108.679929 -215.408922) (xy 108.680504 -215.436704) (xy 108.679996 -215.46261)
			(xy 108.961394 -215.46261) (xy 108.961394 -215.41079) (xy 108.9695 -215.359609) (xy 108.985513 -215.310326)
			(xy 109.00904 -215.264155) (xy 109.039499 -215.222232) (xy 109.076141 -215.185591) (xy 109.118065 -215.155133)
			(xy 109.164237 -215.131609) (xy 109.213521 -215.115597) (xy 109.264702 -215.107493) (xy 109.290612 -215.107012)
			(xy 109.316124 -215.107479) (xy 109.36654 -215.115342) (xy 109.415142 -215.130878) (xy 109.46077 -215.153716)
			(xy 109.502335 -215.183311) (xy 109.538845 -215.218956) (xy 109.554518 -215.239092) (xy 109.966506 -215.239092)
			(xy 109.982174 -215.218952) (xy 110.018685 -215.183309) (xy 110.060252 -215.153716) (xy 110.105881 -215.130881)
			(xy 110.154484 -215.115348) (xy 110.2049 -215.107489) (xy 110.230412 -215.107012) (xy 110.256319 -215.107513)
			(xy 110.307495 -215.11562) (xy 110.356773 -215.131633) (xy 110.402939 -215.155158) (xy 110.444856 -215.185614)
			(xy 110.481494 -215.222253) (xy 110.511949 -215.264172) (xy 110.535471 -215.310339) (xy 110.551482 -215.359617)
			(xy 110.559588 -215.410793) (xy 110.559588 -215.462607) (xy 110.551482 -215.513783) (xy 110.535471 -215.563061)
			(xy 110.511949 -215.609228) (xy 110.481494 -215.651147) (xy 110.444856 -215.687786) (xy 110.402939 -215.718242)
			(xy 110.356773 -215.741767) (xy 110.307495 -215.75778) (xy 110.256319 -215.765887) (xy 110.230412 -215.766396)
			(xy 110.2049 -215.765908) (xy 110.154486 -215.758049) (xy 110.105885 -215.742517) (xy 110.060256 -215.719683)
			(xy 110.018691 -215.690092) (xy 109.98218 -215.65445) (xy 109.966506 -215.634316) (xy 109.554518 -215.634316)
			(xy 109.538838 -215.654446) (xy 109.502329 -215.69009) (xy 109.460765 -215.719683) (xy 109.415138 -215.74252)
			(xy 109.366537 -215.758055) (xy 109.316124 -215.765918) (xy 109.290612 -215.766396) (xy 109.264702 -215.765907)
			(xy 109.213521 -215.757803) (xy 109.164237 -215.741791) (xy 109.118065 -215.718267) (xy 109.076141 -215.687809)
			(xy 109.039499 -215.651168) (xy 109.00904 -215.609245) (xy 108.985513 -215.563074) (xy 108.9695 -215.513791)
			(xy 108.961394 -215.46261) (xy 108.679996 -215.46261) (xy 108.679996 -215.462611) (xy 108.67189 -215.513788)
			(xy 108.655878 -215.563067) (xy 108.632355 -215.609234) (xy 108.601899 -215.651153) (xy 108.565261 -215.687791)
			(xy 108.523342 -215.718247) (xy 108.477175 -215.74177) (xy 108.427896 -215.757782) (xy 108.376719 -215.765888)
			(xy 108.324905 -215.765888) (xy 108.273728 -215.757782) (xy 108.224449 -215.74177) (xy 108.178282 -215.718247)
			(xy 108.136363 -215.687791) (xy 108.099725 -215.651153) (xy 108.069269 -215.609234) (xy 108.045746 -215.563067)
			(xy 108.029734 -215.513788) (xy 108.021628 -215.462611) (xy 108.02112 -215.436704) (xy 106.800904 -215.436704)
			(xy 106.800396 -215.462611) (xy 106.79229 -215.513788) (xy 106.776278 -215.563067) (xy 106.752755 -215.609234)
			(xy 106.722299 -215.651153) (xy 106.685661 -215.687791) (xy 106.643742 -215.718247) (xy 106.597575 -215.74177)
			(xy 106.548296 -215.757782) (xy 106.497119 -215.765888) (xy 106.445305 -215.765888) (xy 106.394128 -215.757782)
			(xy 106.344849 -215.74177) (xy 106.298682 -215.718247) (xy 106.256763 -215.687791) (xy 106.220125 -215.651153)
			(xy 106.189669 -215.609234) (xy 106.166146 -215.563067) (xy 106.150134 -215.513788) (xy 106.142028 -215.462611)
			(xy 106.14152 -215.436704) (xy 104.921304 -215.436704) (xy 104.920796 -215.462611) (xy 104.91269 -215.513788)
			(xy 104.896678 -215.563067) (xy 104.873155 -215.609234) (xy 104.842699 -215.651153) (xy 104.806061 -215.687791)
			(xy 104.764142 -215.718247) (xy 104.717975 -215.74177) (xy 104.668696 -215.757782) (xy 104.617519 -215.765888)
			(xy 104.565705 -215.765888) (xy 104.514528 -215.757782) (xy 104.465249 -215.74177) (xy 104.419082 -215.718247)
			(xy 104.377163 -215.687791) (xy 104.340525 -215.651153) (xy 104.310069 -215.609234) (xy 104.286546 -215.563067)
			(xy 104.270534 -215.513788) (xy 104.262428 -215.462611) (xy 104.26192 -215.436704) (xy 103.041704 -215.436704)
			(xy 103.041196 -215.462611) (xy 103.03309 -215.513788) (xy 103.017078 -215.563067) (xy 102.993555 -215.609234)
			(xy 102.963099 -215.651153) (xy 102.926461 -215.687791) (xy 102.884542 -215.718247) (xy 102.838375 -215.74177)
			(xy 102.789096 -215.757782) (xy 102.737919 -215.765888) (xy 102.686105 -215.765888) (xy 102.634928 -215.757782)
			(xy 102.585649 -215.74177) (xy 102.539482 -215.718247) (xy 102.497563 -215.687791) (xy 102.460925 -215.651153)
			(xy 102.430469 -215.609234) (xy 102.406946 -215.563067) (xy 102.390934 -215.513788) (xy 102.382828 -215.462611)
			(xy 102.38232 -215.436704) (xy 101.162104 -215.436704) (xy 101.161683 -215.459024) (xy 101.15557 -215.503247)
			(xy 101.149912 -215.524842) (xy 101.148134 -215.531446) (xy 101.148134 -216.973658) (xy 101.149912 -216.980008)
			(xy 101.15505 -217.000709) (xy 101.160534 -217.043009) (xy 101.160834 -217.064336) (xy 101.160509 -217.085662)
			(xy 101.155034 -217.12796) (xy 101.149912 -217.148664) (xy 101.148134 -217.155014) (xy 101.148134 -217.563192)
			(xy 101.206046 -217.563192) (xy 101.21265 -217.561414) (xy 101.241098 -217.554556) (xy 101.263958 -217.550238)
			(xy 101.468936 -217.195146) (xy 101.461062 -217.173302) (xy 101.452412 -217.146894) (xy 101.443083 -217.092118)
			(xy 101.44252 -217.064336) (xy 101.443028 -217.038429) (xy 101.451134 -216.987252) (xy 101.467146 -216.937973)
			(xy 101.490669 -216.891806) (xy 101.521125 -216.849887) (xy 101.557763 -216.813249) (xy 101.599682 -216.782793)
			(xy 101.645849 -216.75927) (xy 101.695128 -216.743258) (xy 101.746305 -216.735152) (xy 101.798119 -216.735152)
			(xy 101.849296 -216.743258) (xy 101.898575 -216.75927) (xy 101.944742 -216.782793) (xy 101.986661 -216.813249)
			(xy 102.023299 -216.849887) (xy 102.053755 -216.891806) (xy 102.077278 -216.937973) (xy 102.09329 -216.987252)
			(xy 102.101396 -217.038429) (xy 102.101904 -217.064336) (xy 102.101444 -217.089687) (xy 102.093689 -217.139791)
			(xy 102.078354 -217.188117) (xy 102.055799 -217.233525) (xy 102.026556 -217.274944) (xy 101.991316 -217.311396)
			(xy 101.95091 -217.342021) (xy 101.90629 -217.366098) (xy 101.85851 -217.383058) (xy 101.83368 -217.388186)
			(xy 101.81082 -217.392504) (xy 101.605842 -217.747596) (xy 101.613716 -217.76944) (xy 101.622291 -217.795859)
			(xy 101.631477 -217.850635) (xy 101.632004 -217.878406) (xy 101.912928 -217.878406) (xy 101.913436 -217.852519)
			(xy 101.921535 -217.801381) (xy 101.937534 -217.752141) (xy 101.96104 -217.706009) (xy 101.991472 -217.664122)
			(xy 102.028082 -217.627512) (xy 102.069969 -217.59708) (xy 102.116101 -217.573574) (xy 102.165341 -217.557575)
			(xy 102.216479 -217.549476) (xy 102.268253 -217.549476) (xy 102.319391 -217.557575) (xy 102.368631 -217.573574)
			(xy 102.414763 -217.59708) (xy 102.45665 -217.627512) (xy 102.49326 -217.664122) (xy 102.523692 -217.706009)
			(xy 102.547198 -217.752141) (xy 102.563197 -217.801381) (xy 102.571296 -217.852519) (xy 102.571804 -217.878406)
			(xy 102.852728 -217.878406) (xy 102.853194 -217.853071) (xy 102.860946 -217.802996) (xy 102.876269 -217.754698)
			(xy 102.898802 -217.709313) (xy 102.928014 -217.66791) (xy 102.963217 -217.631464) (xy 103.003582 -217.600835)
			(xy 103.048159 -217.576742) (xy 103.095897 -217.559754) (xy 103.120698 -217.554556) (xy 103.143558 -217.550238)
			(xy 103.348536 -217.195146) (xy 103.340662 -217.173302) (xy 103.332024 -217.146891) (xy 103.322699 -217.092117)
			(xy 103.32212 -217.064336) (xy 103.322628 -217.038429) (xy 103.330734 -216.987252) (xy 103.346746 -216.937973)
			(xy 103.370269 -216.891806) (xy 103.400725 -216.849887) (xy 103.437363 -216.813249) (xy 103.479282 -216.782793)
			(xy 103.525449 -216.75927) (xy 103.574728 -216.743258) (xy 103.625905 -216.735152) (xy 103.677719 -216.735152)
			(xy 103.728896 -216.743258) (xy 103.778175 -216.75927) (xy 103.824342 -216.782793) (xy 103.866261 -216.813249)
			(xy 103.902899 -216.849887) (xy 103.933355 -216.891806) (xy 103.956878 -216.937973) (xy 103.97289 -216.987252)
			(xy 103.980996 -217.038429) (xy 103.981504 -217.064336) (xy 103.981012 -217.08968) (xy 103.973235 -217.13977)
			(xy 103.957886 -217.188079) (xy 103.935325 -217.233471) (xy 103.906084 -217.274876) (xy 103.870852 -217.311319)
			(xy 103.830459 -217.341943) (xy 103.785855 -217.366024) (xy 103.738092 -217.382998) (xy 103.71328 -217.388186)
			(xy 103.69042 -217.392504) (xy 103.485442 -217.747596) (xy 103.493316 -217.76944) (xy 103.501906 -217.795856)
			(xy 103.511095 -217.850633) (xy 103.511604 -217.878406) (xy 103.792528 -217.878406) (xy 103.793036 -217.852519)
			(xy 103.801135 -217.801381) (xy 103.817134 -217.752141) (xy 103.84064 -217.706009) (xy 103.871072 -217.664122)
			(xy 103.907682 -217.627512) (xy 103.949569 -217.59708) (xy 103.995701 -217.573574) (xy 104.044941 -217.557575)
			(xy 104.096079 -217.549476) (xy 104.147853 -217.549476) (xy 104.198991 -217.557575) (xy 104.248231 -217.573574)
			(xy 104.294363 -217.59708) (xy 104.33625 -217.627512) (xy 104.37286 -217.664122) (xy 104.403292 -217.706009)
			(xy 104.426798 -217.752141) (xy 104.442797 -217.801381) (xy 104.450896 -217.852519) (xy 104.451404 -217.878406)
			(xy 104.732328 -217.878406) (xy 104.732794 -217.853071) (xy 104.740546 -217.802996) (xy 104.755869 -217.754698)
			(xy 104.778402 -217.709313) (xy 104.807614 -217.66791) (xy 104.842817 -217.631464) (xy 104.883182 -217.600835)
			(xy 104.927759 -217.576742) (xy 104.975497 -217.559754) (xy 105.000298 -217.554556) (xy 105.023158 -217.550238)
			(xy 105.228136 -217.195146) (xy 105.220262 -217.173302) (xy 105.211624 -217.146891) (xy 105.202299 -217.092117)
			(xy 105.20172 -217.064336) (xy 105.202228 -217.038429) (xy 105.210334 -216.987252) (xy 105.226346 -216.937973)
			(xy 105.249869 -216.891806) (xy 105.280325 -216.849887) (xy 105.316963 -216.813249) (xy 105.358882 -216.782793)
			(xy 105.405049 -216.75927) (xy 105.454328 -216.743258) (xy 105.505505 -216.735152) (xy 105.557319 -216.735152)
			(xy 105.608496 -216.743258) (xy 105.657775 -216.75927) (xy 105.703942 -216.782793) (xy 105.745861 -216.813249)
			(xy 105.782499 -216.849887) (xy 105.812955 -216.891806) (xy 105.836478 -216.937973) (xy 105.85249 -216.987252)
			(xy 105.860596 -217.038429) (xy 105.861104 -217.064336) (xy 105.860612 -217.08968) (xy 105.852835 -217.13977)
			(xy 105.837486 -217.188079) (xy 105.814925 -217.233471) (xy 105.785684 -217.274876) (xy 105.750452 -217.311319)
			(xy 105.710059 -217.341943) (xy 105.665455 -217.366024) (xy 105.617692 -217.382998) (xy 105.59288 -217.388186)
			(xy 105.57002 -217.392504) (xy 105.365042 -217.747596) (xy 105.372916 -217.76944) (xy 105.381506 -217.795856)
			(xy 105.390695 -217.850633) (xy 105.391204 -217.878406) (xy 105.672128 -217.878406) (xy 105.672636 -217.852519)
			(xy 105.680735 -217.801381) (xy 105.696734 -217.752141) (xy 105.72024 -217.706009) (xy 105.750672 -217.664122)
			(xy 105.787282 -217.627512) (xy 105.829169 -217.59708) (xy 105.875301 -217.573574) (xy 105.924541 -217.557575)
			(xy 105.975679 -217.549476) (xy 106.027453 -217.549476) (xy 106.078591 -217.557575) (xy 106.127831 -217.573574)
			(xy 106.173963 -217.59708) (xy 106.21585 -217.627512) (xy 106.25246 -217.664122) (xy 106.282892 -217.706009)
			(xy 106.306398 -217.752141) (xy 106.322397 -217.801381) (xy 106.330496 -217.852519) (xy 106.331004 -217.878406)
			(xy 106.611928 -217.878406) (xy 106.612394 -217.853071) (xy 106.620146 -217.802996) (xy 106.635469 -217.754698)
			(xy 106.658002 -217.709313) (xy 106.687214 -217.66791) (xy 106.722417 -217.631464) (xy 106.762782 -217.600835)
			(xy 106.807359 -217.576742) (xy 106.855097 -217.559754) (xy 106.879898 -217.554556) (xy 106.902758 -217.550238)
			(xy 107.107736 -217.195146) (xy 107.099862 -217.173302) (xy 107.091224 -217.146891) (xy 107.081899 -217.092117)
			(xy 107.08132 -217.064336) (xy 107.081828 -217.038429) (xy 107.089934 -216.987252) (xy 107.105946 -216.937973)
			(xy 107.129469 -216.891806) (xy 107.159925 -216.849887) (xy 107.196563 -216.813249) (xy 107.238482 -216.782793)
			(xy 107.284649 -216.75927) (xy 107.333928 -216.743258) (xy 107.385105 -216.735152) (xy 107.436919 -216.735152)
			(xy 107.488096 -216.743258) (xy 107.537375 -216.75927) (xy 107.583542 -216.782793) (xy 107.625461 -216.813249)
			(xy 107.662099 -216.849887) (xy 107.692555 -216.891806) (xy 107.716078 -216.937973) (xy 107.73209 -216.987252)
			(xy 107.740196 -217.038429) (xy 107.740704 -217.064336) (xy 107.740212 -217.08968) (xy 107.732435 -217.13977)
			(xy 107.717086 -217.188079) (xy 107.694525 -217.233471) (xy 107.665284 -217.274876) (xy 107.630052 -217.311319)
			(xy 107.589659 -217.341943) (xy 107.545055 -217.366024) (xy 107.497292 -217.382998) (xy 107.47248 -217.388186)
			(xy 107.44962 -217.392504) (xy 107.244642 -217.747596) (xy 107.252516 -217.76944) (xy 107.261106 -217.795856)
			(xy 107.270295 -217.850633) (xy 107.270804 -217.878406) (xy 107.551728 -217.878406) (xy 107.552236 -217.852519)
			(xy 107.560335 -217.801381) (xy 107.576334 -217.752141) (xy 107.59984 -217.706009) (xy 107.630272 -217.664122)
			(xy 107.666882 -217.627512) (xy 107.708769 -217.59708) (xy 107.754901 -217.573574) (xy 107.804141 -217.557575)
			(xy 107.855279 -217.549476) (xy 107.907053 -217.549476) (xy 107.958191 -217.557575) (xy 108.007431 -217.573574)
			(xy 108.053563 -217.59708) (xy 108.09545 -217.627512) (xy 108.13206 -217.664122) (xy 108.162492 -217.706009)
			(xy 108.185998 -217.752141) (xy 108.201997 -217.801381) (xy 108.210096 -217.852519) (xy 108.210604 -217.878406)
			(xy 108.491528 -217.878406) (xy 108.491994 -217.853071) (xy 108.499746 -217.802996) (xy 108.515069 -217.754698)
			(xy 108.537602 -217.709313) (xy 108.566814 -217.66791) (xy 108.602017 -217.631464) (xy 108.642382 -217.600835)
			(xy 108.686959 -217.576742) (xy 108.734697 -217.559754) (xy 108.759498 -217.554556) (xy 108.782358 -217.550238)
			(xy 108.987336 -217.195146) (xy 108.979462 -217.173302) (xy 108.970824 -217.146891) (xy 108.961499 -217.092117)
			(xy 108.96092 -217.064336) (xy 108.961428 -217.038429) (xy 108.969534 -216.987252) (xy 108.985546 -216.937973)
			(xy 109.009069 -216.891806) (xy 109.039525 -216.849887) (xy 109.076163 -216.813249) (xy 109.118082 -216.782793)
			(xy 109.164249 -216.75927) (xy 109.213528 -216.743258) (xy 109.264705 -216.735152) (xy 109.316519 -216.735152)
			(xy 109.367696 -216.743258) (xy 109.416975 -216.75927) (xy 109.463142 -216.782793) (xy 109.505061 -216.813249)
			(xy 109.541699 -216.849887) (xy 109.572155 -216.891806) (xy 109.595678 -216.937973) (xy 109.61169 -216.987252)
			(xy 109.619796 -217.038429) (xy 109.620304 -217.064336) (xy 109.619812 -217.08968) (xy 109.612035 -217.13977)
			(xy 109.596686 -217.188079) (xy 109.574125 -217.233471) (xy 109.544884 -217.274876) (xy 109.509652 -217.311319)
			(xy 109.469259 -217.341943) (xy 109.424655 -217.366024) (xy 109.376892 -217.382998) (xy 109.35208 -217.388186)
			(xy 109.32922 -217.392504) (xy 109.124242 -217.747596) (xy 109.132116 -217.76944) (xy 109.140706 -217.795856)
			(xy 109.149895 -217.850633) (xy 109.150404 -217.878406) (xy 109.431328 -217.878406) (xy 109.431836 -217.852519)
			(xy 109.439935 -217.801381) (xy 109.455934 -217.752141) (xy 109.47944 -217.706009) (xy 109.509872 -217.664122)
			(xy 109.546482 -217.627512) (xy 109.588369 -217.59708) (xy 109.634501 -217.573574) (xy 109.683741 -217.557575)
			(xy 109.734879 -217.549476) (xy 109.786653 -217.549476) (xy 109.837791 -217.557575) (xy 109.887031 -217.573574)
			(xy 109.933163 -217.59708) (xy 109.97505 -217.627512) (xy 110.01166 -217.664122) (xy 110.042092 -217.706009)
			(xy 110.065598 -217.752141) (xy 110.081597 -217.801381) (xy 110.089696 -217.852519) (xy 110.090204 -217.878406)
			(xy 110.371128 -217.878406) (xy 110.371594 -217.853071) (xy 110.379346 -217.802996) (xy 110.394669 -217.754698)
			(xy 110.417202 -217.709313) (xy 110.446414 -217.66791) (xy 110.481617 -217.631464) (xy 110.521982 -217.600835)
			(xy 110.566559 -217.576742) (xy 110.614297 -217.559754) (xy 110.639098 -217.554556) (xy 110.661958 -217.550238)
			(xy 110.866936 -217.194892) (xy 110.859316 -217.173048) (xy 110.850741 -217.146694) (xy 110.841552 -217.092045)
			(xy 110.841028 -217.064336) (xy 110.841536 -217.038449) (xy 110.849635 -216.987311) (xy 110.865634 -216.938071)
			(xy 110.88914 -216.891939) (xy 110.919572 -216.850052) (xy 110.956182 -216.813442) (xy 110.998069 -216.78301)
			(xy 111.044201 -216.759504) (xy 111.093441 -216.743505) (xy 111.144579 -216.735406) (xy 111.196353 -216.735406)
			(xy 111.247491 -216.743505) (xy 111.296731 -216.759504) (xy 111.342863 -216.78301) (xy 111.38475 -216.813442)
			(xy 111.42136 -216.850052) (xy 111.451792 -216.891939) (xy 111.475298 -216.938071) (xy 111.491297 -216.987311)
			(xy 111.499396 -217.038449) (xy 111.499904 -217.064336) (xy 112.72012 -217.064336) (xy 112.720628 -217.038429)
			(xy 112.728734 -216.987252) (xy 112.744746 -216.937973) (xy 112.768269 -216.891806) (xy 112.798725 -216.849887)
			(xy 112.835363 -216.813249) (xy 112.877282 -216.782793) (xy 112.923449 -216.75927) (xy 112.972728 -216.743258)
			(xy 113.023905 -216.735152) (xy 113.075719 -216.735152) (xy 113.126896 -216.743258) (xy 113.176175 -216.75927)
			(xy 113.222342 -216.782793) (xy 113.264261 -216.813249) (xy 113.300899 -216.849887) (xy 113.331355 -216.891806)
			(xy 113.354878 -216.937973) (xy 113.37089 -216.987252) (xy 113.378996 -217.038429) (xy 113.379504 -217.064336)
			(xy 113.378889 -217.091989) (xy 113.369569 -217.146507) (xy 113.360962 -217.172794) (xy 113.353342 -217.194892)
			(xy 113.558574 -217.550238) (xy 113.581434 -217.554556) (xy 113.606241 -217.559728) (xy 113.653979 -217.576721)
			(xy 113.698556 -217.600818) (xy 113.73892 -217.631451) (xy 113.774123 -217.6679) (xy 113.803334 -217.709305)
			(xy 113.825866 -217.754693) (xy 113.841189 -217.802993) (xy 113.848941 -217.85307) (xy 113.849404 -217.878406)
			(xy 113.848896 -217.904293) (xy 113.840797 -217.955431) (xy 113.824798 -218.004671) (xy 113.801292 -218.050803)
			(xy 113.77086 -218.09269) (xy 113.73425 -218.1293) (xy 113.692363 -218.159732) (xy 113.646231 -218.183238)
			(xy 113.596991 -218.199237) (xy 113.545853 -218.207336) (xy 113.494079 -218.207336) (xy 113.442941 -218.199237)
			(xy 113.393701 -218.183238) (xy 113.347569 -218.159732) (xy 113.305682 -218.1293) (xy 113.269072 -218.09269)
			(xy 113.23864 -218.050803) (xy 113.215134 -218.004671) (xy 113.199135 -217.955431) (xy 113.191036 -217.904293)
			(xy 113.190528 -217.878406) (xy 113.191062 -217.850698) (xy 113.200255 -217.796051) (xy 113.208816 -217.769694)
			(xy 113.21669 -217.747596) (xy 113.011712 -217.392504) (xy 112.988852 -217.388186) (xy 112.963996 -217.383069)
			(xy 112.916148 -217.366166) (xy 112.871456 -217.342128) (xy 112.830977 -217.311523) (xy 112.795667 -217.275076)
			(xy 112.766361 -217.233647) (xy 112.743752 -217.188215) (xy 112.728374 -217.139855) (xy 112.72059 -217.089709)
			(xy 112.72012 -217.064336) (xy 111.499904 -217.064336) (xy 111.499412 -217.08968) (xy 111.491635 -217.13977)
			(xy 111.476286 -217.188079) (xy 111.453725 -217.233471) (xy 111.424484 -217.274876) (xy 111.389252 -217.311319)
			(xy 111.348859 -217.341943) (xy 111.304255 -217.366024) (xy 111.256492 -217.382998) (xy 111.23168 -217.388186)
			(xy 111.20882 -217.392504) (xy 111.003842 -217.747596) (xy 111.011716 -217.76944) (xy 111.020306 -217.795856)
			(xy 111.029495 -217.850633) (xy 111.030004 -217.878406) (xy 111.029496 -217.904293) (xy 111.021397 -217.955431)
			(xy 111.005398 -218.004671) (xy 110.981892 -218.050803) (xy 110.95146 -218.09269) (xy 110.91485 -218.1293)
			(xy 110.872963 -218.159732) (xy 110.826831 -218.183238) (xy 110.777591 -218.199237) (xy 110.726453 -218.207336)
			(xy 110.674679 -218.207336) (xy 110.623541 -218.199237) (xy 110.574301 -218.183238) (xy 110.528169 -218.159732)
			(xy 110.486282 -218.1293) (xy 110.449672 -218.09269) (xy 110.41924 -218.050803) (xy 110.395734 -218.004671)
			(xy 110.379735 -217.955431) (xy 110.371636 -217.904293) (xy 110.371128 -217.878406) (xy 110.090204 -217.878406)
			(xy 110.089676 -217.906114) (xy 110.08048 -217.960761) (xy 110.071916 -217.987118) (xy 110.064296 -218.008962)
			(xy 110.269274 -218.364054) (xy 110.292134 -218.368372) (xy 110.316944 -218.373529) (xy 110.364684 -218.390523)
			(xy 110.409261 -218.414621) (xy 110.449626 -218.445257) (xy 110.484829 -218.481707) (xy 110.51404 -218.523115)
			(xy 110.536571 -218.568504) (xy 110.551892 -218.616807) (xy 110.559642 -218.666885) (xy 110.560104 -218.692222)
			(xy 111.78032 -218.692222) (xy 111.780845 -218.666878) (xy 111.788614 -218.616789) (xy 111.803957 -218.56848)
			(xy 111.826512 -218.523087) (xy 111.855749 -218.481681) (xy 111.890978 -218.445236) (xy 111.931369 -218.414613)
			(xy 111.97597 -218.390531) (xy 112.023732 -218.373559) (xy 112.048544 -218.368372) (xy 112.071404 -218.364054)
			(xy 112.276636 -218.008708) (xy 112.268762 -217.98661) (xy 112.260294 -217.960366) (xy 112.251224 -217.905977)
			(xy 112.250728 -217.878406) (xy 112.251236 -217.852519) (xy 112.259335 -217.801381) (xy 112.275334 -217.752141)
			(xy 112.29884 -217.706009) (xy 112.329272 -217.664122) (xy 112.365882 -217.627512) (xy 112.407769 -217.59708)
			(xy 112.453901 -217.573574) (xy 112.503141 -217.557575) (xy 112.554279 -217.549476) (xy 112.606053 -217.549476)
			(xy 112.657191 -217.557575) (xy 112.706431 -217.573574) (xy 112.752563 -217.59708) (xy 112.79445 -217.627512)
			(xy 112.83106 -217.664122) (xy 112.861492 -217.706009) (xy 112.884998 -217.752141) (xy 112.900997 -217.801381)
			(xy 112.909096 -217.852519) (xy 112.909604 -217.878406) (xy 112.909131 -217.90378) (xy 112.901362 -217.953931)
			(xy 112.885993 -218.002296) (xy 112.863388 -218.047732) (xy 112.834082 -218.089163) (xy 112.798768 -218.125609)
			(xy 112.758282 -218.156208) (xy 112.713582 -218.180235) (xy 112.665726 -218.197122) (xy 112.640872 -218.202256)
			(xy 112.618012 -218.206574) (xy 112.413288 -218.561412) (xy 112.421162 -218.583256) (xy 112.429814 -218.609662)
			(xy 112.43913 -218.66444) (xy 112.439704 -218.692222) (xy 113.660428 -218.692222) (xy 113.660908 -218.666887)
			(xy 113.668658 -218.616813) (xy 113.683979 -218.568515) (xy 113.70651 -218.52313) (xy 113.73572 -218.481727)
			(xy 113.770922 -218.445282) (xy 113.811285 -218.414651) (xy 113.855861 -218.390558) (xy 113.903598 -218.37357)
			(xy 113.928398 -218.368372) (xy 113.951258 -218.364054) (xy 114.156236 -218.008962) (xy 114.148616 -217.986864)
			(xy 114.140061 -217.960571) (xy 114.130869 -217.906051) (xy 114.130328 -217.878406) (xy 114.130836 -217.852519)
			(xy 114.138935 -217.801381) (xy 114.154934 -217.752141) (xy 114.17844 -217.706009) (xy 114.208872 -217.664122)
			(xy 114.245482 -217.627512) (xy 114.287369 -217.59708) (xy 114.333501 -217.573574) (xy 114.382741 -217.557575)
			(xy 114.433879 -217.549476) (xy 114.485653 -217.549476) (xy 114.536791 -217.557575) (xy 114.586031 -217.573574)
			(xy 114.632163 -217.59708) (xy 114.67405 -217.627512) (xy 114.71066 -217.664122) (xy 114.741092 -217.706009)
			(xy 114.764598 -217.752141) (xy 114.780597 -217.801381) (xy 114.788696 -217.852519) (xy 114.789204 -217.878406)
			(xy 114.788769 -217.903771) (xy 114.781019 -217.953906) (xy 114.765673 -218.002259) (xy 114.743093 -218.047686)
			(xy 114.713814 -218.089114) (xy 114.678529 -218.125562) (xy 114.638071 -218.156167) (xy 114.593399 -218.180207)
			(xy 114.545568 -218.197111) (xy 114.520726 -218.202256) (xy 114.497866 -218.206574) (xy 114.293142 -218.561412)
			(xy 114.301016 -218.583256) (xy 114.309609 -218.609671) (xy 114.318797 -218.664449) (xy 114.319304 -218.692222)
			(xy 114.318796 -218.718109) (xy 114.310697 -218.769247) (xy 114.294698 -218.818487) (xy 114.271192 -218.864619)
			(xy 114.24076 -218.906506) (xy 114.20415 -218.943116) (xy 114.162263 -218.973548) (xy 114.116131 -218.997054)
			(xy 114.066891 -219.013053) (xy 114.015753 -219.021152) (xy 113.963979 -219.021152) (xy 113.912841 -219.013053)
			(xy 113.863601 -218.997054) (xy 113.817469 -218.973548) (xy 113.775582 -218.943116) (xy 113.738972 -218.906506)
			(xy 113.70854 -218.864619) (xy 113.685034 -218.818487) (xy 113.669035 -218.769247) (xy 113.660936 -218.718109)
			(xy 113.660428 -218.692222) (xy 112.439704 -218.692222) (xy 112.439196 -218.718129) (xy 112.43109 -218.769306)
			(xy 112.415078 -218.818585) (xy 112.391555 -218.864752) (xy 112.361099 -218.906671) (xy 112.324461 -218.943309)
			(xy 112.282542 -218.973765) (xy 112.236375 -218.997288) (xy 112.187096 -219.0133) (xy 112.135919 -219.021406)
			(xy 112.084105 -219.021406) (xy 112.032928 -219.0133) (xy 111.983649 -218.997288) (xy 111.937482 -218.973765)
			(xy 111.895563 -218.943309) (xy 111.858925 -218.906671) (xy 111.828469 -218.864752) (xy 111.804946 -218.818585)
			(xy 111.788934 -218.769306) (xy 111.780828 -218.718129) (xy 111.78032 -218.692222) (xy 110.560104 -218.692222)
			(xy 110.559596 -218.718109) (xy 110.551497 -218.769247) (xy 110.535498 -218.818487) (xy 110.511992 -218.864619)
			(xy 110.48156 -218.906506) (xy 110.44495 -218.943116) (xy 110.403063 -218.973548) (xy 110.356931 -218.997054)
			(xy 110.307691 -219.013053) (xy 110.256553 -219.021152) (xy 110.204779 -219.021152) (xy 110.153641 -219.013053)
			(xy 110.104401 -218.997054) (xy 110.058269 -218.973548) (xy 110.016382 -218.943116) (xy 109.979772 -218.906506)
			(xy 109.94934 -218.864619) (xy 109.925834 -218.818487) (xy 109.909835 -218.769247) (xy 109.901736 -218.718109)
			(xy 109.901228 -218.692222) (xy 109.901766 -218.664514) (xy 109.910956 -218.609868) (xy 109.919516 -218.58351)
			(xy 109.92739 -218.561412) (xy 109.722412 -218.206574) (xy 109.699552 -218.202256) (xy 109.67472 -218.197133)
			(xy 109.626938 -218.180175) (xy 109.582316 -218.1561) (xy 109.541908 -218.125474) (xy 109.506667 -218.089022)
			(xy 109.477424 -218.047602) (xy 109.45487 -218.002192) (xy 109.439537 -217.953864) (xy 109.431786 -217.903757)
			(xy 109.431328 -217.878406) (xy 109.150404 -217.878406) (xy 109.149896 -217.904293) (xy 109.141797 -217.955431)
			(xy 109.125798 -218.004671) (xy 109.102292 -218.050803) (xy 109.07186 -218.09269) (xy 109.03525 -218.1293)
			(xy 108.993363 -218.159732) (xy 108.947231 -218.183238) (xy 108.897991 -218.199237) (xy 108.846853 -218.207336)
			(xy 108.795079 -218.207336) (xy 108.743941 -218.199237) (xy 108.694701 -218.183238) (xy 108.648569 -218.159732)
			(xy 108.606682 -218.1293) (xy 108.570072 -218.09269) (xy 108.53964 -218.050803) (xy 108.516134 -218.004671)
			(xy 108.500135 -217.955431) (xy 108.492036 -217.904293) (xy 108.491528 -217.878406) (xy 108.210604 -217.878406)
			(xy 108.210076 -217.906114) (xy 108.20088 -217.960761) (xy 108.192316 -217.987118) (xy 108.184442 -218.009216)
			(xy 108.38942 -218.364054) (xy 108.41228 -218.368372) (xy 108.4371 -218.37354) (xy 108.484878 -218.390497)
			(xy 108.529495 -218.41457) (xy 108.5699 -218.44519) (xy 108.60514 -218.481637) (xy 108.634384 -218.52305)
			(xy 108.656942 -218.568452) (xy 108.672281 -218.616773) (xy 108.680041 -218.666873) (xy 108.680504 -218.692222)
			(xy 108.679996 -218.718129) (xy 108.67189 -218.769306) (xy 108.655878 -218.818585) (xy 108.632355 -218.864752)
			(xy 108.601899 -218.906671) (xy 108.565261 -218.943309) (xy 108.523342 -218.973765) (xy 108.477175 -218.997288)
			(xy 108.427896 -219.0133) (xy 108.376719 -219.021406) (xy 108.324905 -219.021406) (xy 108.273728 -219.0133)
			(xy 108.224449 -218.997288) (xy 108.178282 -218.973765) (xy 108.136363 -218.943309) (xy 108.099725 -218.906671)
			(xy 108.069269 -218.864752) (xy 108.045746 -218.818585) (xy 108.029734 -218.769306) (xy 108.021628 -218.718129)
			(xy 108.02112 -218.692222) (xy 108.021718 -218.664505) (xy 108.031039 -218.609858) (xy 108.039662 -218.58351)
			(xy 108.047536 -218.561412) (xy 107.842558 -218.206574) (xy 107.819698 -218.202256) (xy 107.794899 -218.197049)
			(xy 107.747162 -218.180062) (xy 107.702585 -218.15597) (xy 107.66222 -218.125341) (xy 107.627017 -218.088897)
			(xy 107.597804 -218.047495) (xy 107.575271 -218.002112) (xy 107.559946 -217.953814) (xy 107.552192 -217.903741)
			(xy 107.551728 -217.878406) (xy 107.270804 -217.878406) (xy 107.270296 -217.904293) (xy 107.262197 -217.955431)
			(xy 107.246198 -218.004671) (xy 107.222692 -218.050803) (xy 107.19226 -218.09269) (xy 107.15565 -218.1293)
			(xy 107.113763 -218.159732) (xy 107.067631 -218.183238) (xy 107.018391 -218.199237) (xy 106.967253 -218.207336)
			(xy 106.915479 -218.207336) (xy 106.864341 -218.199237) (xy 106.815101 -218.183238) (xy 106.768969 -218.159732)
			(xy 106.727082 -218.1293) (xy 106.690472 -218.09269) (xy 106.66004 -218.050803) (xy 106.636534 -218.004671)
			(xy 106.620535 -217.955431) (xy 106.612436 -217.904293) (xy 106.611928 -217.878406) (xy 106.331004 -217.878406)
			(xy 106.330476 -217.906114) (xy 106.32128 -217.960761) (xy 106.312716 -217.987118) (xy 106.304842 -218.009216)
			(xy 106.50982 -218.364054) (xy 106.53268 -218.368372) (xy 106.5575 -218.37354) (xy 106.605278 -218.390497)
			(xy 106.649895 -218.41457) (xy 106.6903 -218.44519) (xy 106.72554 -218.481637) (xy 106.754784 -218.52305)
			(xy 106.777342 -218.568452) (xy 106.792681 -218.616773) (xy 106.800441 -218.666873) (xy 106.800904 -218.692222)
			(xy 106.800396 -218.718129) (xy 106.79229 -218.769306) (xy 106.776278 -218.818585) (xy 106.752755 -218.864752)
			(xy 106.722299 -218.906671) (xy 106.685661 -218.943309) (xy 106.643742 -218.973765) (xy 106.597575 -218.997288)
			(xy 106.548296 -219.0133) (xy 106.497119 -219.021406) (xy 106.445305 -219.021406) (xy 106.394128 -219.0133)
			(xy 106.344849 -218.997288) (xy 106.298682 -218.973765) (xy 106.256763 -218.943309) (xy 106.220125 -218.906671)
			(xy 106.189669 -218.864752) (xy 106.166146 -218.818585) (xy 106.150134 -218.769306) (xy 106.142028 -218.718129)
			(xy 106.14152 -218.692222) (xy 106.142118 -218.664505) (xy 106.151439 -218.609858) (xy 106.160062 -218.58351)
			(xy 106.167936 -218.561412) (xy 105.962958 -218.206574) (xy 105.940098 -218.202256) (xy 105.915299 -218.197049)
			(xy 105.867562 -218.180062) (xy 105.822985 -218.15597) (xy 105.78262 -218.125341) (xy 105.747417 -218.088897)
			(xy 105.718204 -218.047495) (xy 105.695671 -218.002112) (xy 105.680346 -217.953814) (xy 105.672592 -217.903741)
			(xy 105.672128 -217.878406) (xy 105.391204 -217.878406) (xy 105.390696 -217.904293) (xy 105.382597 -217.955431)
			(xy 105.366598 -218.004671) (xy 105.343092 -218.050803) (xy 105.31266 -218.09269) (xy 105.27605 -218.1293)
			(xy 105.234163 -218.159732) (xy 105.188031 -218.183238) (xy 105.138791 -218.199237) (xy 105.087653 -218.207336)
			(xy 105.035879 -218.207336) (xy 104.984741 -218.199237) (xy 104.935501 -218.183238) (xy 104.889369 -218.159732)
			(xy 104.847482 -218.1293) (xy 104.810872 -218.09269) (xy 104.78044 -218.050803) (xy 104.756934 -218.004671)
			(xy 104.740935 -217.955431) (xy 104.732836 -217.904293) (xy 104.732328 -217.878406) (xy 104.451404 -217.878406)
			(xy 104.450876 -217.906114) (xy 104.44168 -217.960761) (xy 104.433116 -217.987118) (xy 104.425242 -218.009216)
			(xy 104.63022 -218.364054) (xy 104.65308 -218.368372) (xy 104.6779 -218.37354) (xy 104.725678 -218.390497)
			(xy 104.770295 -218.41457) (xy 104.8107 -218.44519) (xy 104.84594 -218.481637) (xy 104.875184 -218.52305)
			(xy 104.897742 -218.568452) (xy 104.913081 -218.616773) (xy 104.920841 -218.666873) (xy 104.921304 -218.692222)
			(xy 104.920796 -218.718129) (xy 104.91269 -218.769306) (xy 104.896678 -218.818585) (xy 104.873155 -218.864752)
			(xy 104.842699 -218.906671) (xy 104.806061 -218.943309) (xy 104.764142 -218.973765) (xy 104.717975 -218.997288)
			(xy 104.668696 -219.0133) (xy 104.617519 -219.021406) (xy 104.565705 -219.021406) (xy 104.514528 -219.0133)
			(xy 104.465249 -218.997288) (xy 104.419082 -218.973765) (xy 104.377163 -218.943309) (xy 104.340525 -218.906671)
			(xy 104.310069 -218.864752) (xy 104.286546 -218.818585) (xy 104.270534 -218.769306) (xy 104.262428 -218.718129)
			(xy 104.26192 -218.692222) (xy 104.262518 -218.664505) (xy 104.271839 -218.609858) (xy 104.280462 -218.58351)
			(xy 104.288336 -218.561412) (xy 104.083358 -218.206574) (xy 104.060498 -218.202256) (xy 104.035699 -218.197049)
			(xy 103.987962 -218.180062) (xy 103.943385 -218.15597) (xy 103.90302 -218.125341) (xy 103.867817 -218.088897)
			(xy 103.838604 -218.047495) (xy 103.816071 -218.002112) (xy 103.800746 -217.953814) (xy 103.792992 -217.903741)
			(xy 103.792528 -217.878406) (xy 103.511604 -217.878406) (xy 103.511096 -217.904293) (xy 103.502997 -217.955431)
			(xy 103.486998 -218.004671) (xy 103.463492 -218.050803) (xy 103.43306 -218.09269) (xy 103.39645 -218.1293)
			(xy 103.354563 -218.159732) (xy 103.308431 -218.183238) (xy 103.259191 -218.199237) (xy 103.208053 -218.207336)
			(xy 103.156279 -218.207336) (xy 103.105141 -218.199237) (xy 103.055901 -218.183238) (xy 103.009769 -218.159732)
			(xy 102.967882 -218.1293) (xy 102.931272 -218.09269) (xy 102.90084 -218.050803) (xy 102.877334 -218.004671)
			(xy 102.861335 -217.955431) (xy 102.853236 -217.904293) (xy 102.852728 -217.878406) (xy 102.571804 -217.878406)
			(xy 102.571276 -217.906114) (xy 102.56208 -217.960761) (xy 102.553516 -217.987118) (xy 102.545642 -218.009216)
			(xy 102.75062 -218.364054) (xy 102.77348 -218.368372) (xy 102.7983 -218.37354) (xy 102.846078 -218.390497)
			(xy 102.890695 -218.41457) (xy 102.9311 -218.44519) (xy 102.96634 -218.481637) (xy 102.995584 -218.52305)
			(xy 103.018142 -218.568452) (xy 103.033481 -218.616773) (xy 103.041241 -218.666873) (xy 103.041704 -218.692222)
			(xy 103.041196 -218.718129) (xy 103.03309 -218.769306) (xy 103.017078 -218.818585) (xy 102.993555 -218.864752)
			(xy 102.963099 -218.906671) (xy 102.926461 -218.943309) (xy 102.884542 -218.973765) (xy 102.838375 -218.997288)
			(xy 102.789096 -219.0133) (xy 102.737919 -219.021406) (xy 102.686105 -219.021406) (xy 102.634928 -219.0133)
			(xy 102.585649 -218.997288) (xy 102.539482 -218.973765) (xy 102.497563 -218.943309) (xy 102.460925 -218.906671)
			(xy 102.430469 -218.864752) (xy 102.406946 -218.818585) (xy 102.390934 -218.769306) (xy 102.382828 -218.718129)
			(xy 102.38232 -218.692222) (xy 102.382918 -218.664505) (xy 102.392239 -218.609858) (xy 102.400862 -218.58351)
			(xy 102.408736 -218.561412) (xy 102.203758 -218.206574) (xy 102.180898 -218.202256) (xy 102.156099 -218.197049)
			(xy 102.108362 -218.180062) (xy 102.063785 -218.15597) (xy 102.02342 -218.125341) (xy 101.988217 -218.088897)
			(xy 101.959004 -218.047495) (xy 101.936471 -218.002112) (xy 101.921146 -217.953814) (xy 101.913392 -217.903741)
			(xy 101.912928 -217.878406) (xy 101.632004 -217.878406) (xy 101.631522 -217.904294) (xy 101.623421 -217.955433)
			(xy 101.60742 -218.004675) (xy 101.583912 -218.050807) (xy 101.553476 -218.092693) (xy 101.516863 -218.129302)
			(xy 101.474973 -218.159733) (xy 101.428838 -218.183235) (xy 101.379594 -218.199231) (xy 101.328454 -218.207325)
			(xy 101.302566 -218.207844) (xy 101.292446 -218.207812) (xy 101.272239 -218.206669) (xy 101.26218 -218.205558)
			(xy 101.247859 -218.204283) (xy 101.219484 -218.208838) (xy 101.193502 -218.221118) (xy 101.171968 -218.24015)
			(xy 101.15659 -218.264427) (xy 101.148583 -218.292027) (xy 101.148134 -218.306396) (xy 101.148134 -218.59748)
			(xy 101.149912 -218.604084) (xy 101.155576 -218.625678) (xy 101.161697 -218.669901) (xy 101.162104 -218.692222)
			(xy 101.161682 -218.714542) (xy 101.155566 -218.758764) (xy 101.149912 -218.78036) (xy 101.148134 -218.786964)
			(xy 101.148134 -219.079572) (xy 101.148624 -219.093938) (xy 101.156622 -219.121533) (xy 101.171992 -219.145808)
			(xy 101.193518 -219.164838) (xy 101.219493 -219.177117) (xy 101.247861 -219.181671) (xy 101.26218 -219.18041)
			(xy 101.272236 -219.179236) (xy 101.292443 -219.177963) (xy 101.302566 -219.17787) (xy 101.328356 -219.178347)
			(xy 101.379302 -219.186412) (xy 101.428359 -219.202348) (xy 101.474319 -219.225764) (xy 101.516049 -219.256081)
			(xy 101.552521 -219.292554) (xy 101.582838 -219.334285) (xy 101.606253 -219.380244) (xy 101.622189 -219.429302)
			(xy 101.630253 -219.480248) (xy 101.630734 -219.506038) (xy 101.630189 -219.532081) (xy 101.62189 -219.583504)
			(xy 101.614224 -219.6084) (xy 101.604572 -219.638118) (xy 102.863396 -220.896942) (xy 102.870762 -220.904562)
			(xy 102.878164 -220.911888) (xy 102.897165 -220.920361) (xy 102.917968 -220.920582) (xy 102.937145 -220.912515)
			(xy 102.944676 -220.905324) (xy 102.962654 -220.88733) (xy 103.003142 -220.856542) (xy 103.047879 -220.832341)
			(xy 103.095804 -220.8153) (xy 103.120698 -220.810074) (xy 103.143558 -220.805756) (xy 103.348536 -220.450664)
			(xy 103.340662 -220.42882) (xy 103.332019 -220.402411) (xy 103.322703 -220.347635) (xy 103.32212 -220.319854)
			(xy 103.322628 -220.293947) (xy 103.330734 -220.24277) (xy 103.346746 -220.193491) (xy 103.370269 -220.147324)
			(xy 103.400725 -220.105405) (xy 103.437363 -220.068767) (xy 103.479282 -220.038311) (xy 103.525449 -220.014788)
			(xy 103.574728 -219.998776) (xy 103.625905 -219.99067) (xy 103.677719 -219.99067) (xy 103.728896 -219.998776)
			(xy 103.778175 -220.014788) (xy 103.824342 -220.038311) (xy 103.866261 -220.068767) (xy 103.902899 -220.105405)
			(xy 103.933355 -220.147324) (xy 103.956878 -220.193491) (xy 103.97289 -220.24277) (xy 103.980996 -220.293947)
			(xy 103.981504 -220.319854) (xy 105.20172 -220.319854) (xy 105.202228 -220.293947) (xy 105.210334 -220.24277)
			(xy 105.226346 -220.193491) (xy 105.249869 -220.147324) (xy 105.280325 -220.105405) (xy 105.316963 -220.068767)
			(xy 105.358882 -220.038311) (xy 105.405049 -220.014788) (xy 105.454328 -219.998776) (xy 105.505505 -219.99067)
			(xy 105.557319 -219.99067) (xy 105.608496 -219.998776) (xy 105.657775 -220.014788) (xy 105.703942 -220.038311)
			(xy 105.745861 -220.068767) (xy 105.782499 -220.105405) (xy 105.812955 -220.147324) (xy 105.836478 -220.193491)
			(xy 105.85249 -220.24277) (xy 105.860596 -220.293947) (xy 105.861104 -220.319854) (xy 107.08132 -220.319854)
			(xy 107.081828 -220.293947) (xy 107.089934 -220.24277) (xy 107.105946 -220.193491) (xy 107.129469 -220.147324)
			(xy 107.159925 -220.105405) (xy 107.196563 -220.068767) (xy 107.238482 -220.038311) (xy 107.284649 -220.014788)
			(xy 107.333928 -219.998776) (xy 107.385105 -219.99067) (xy 107.436919 -219.99067) (xy 107.488096 -219.998776)
			(xy 107.537375 -220.014788) (xy 107.583542 -220.038311) (xy 107.625461 -220.068767) (xy 107.662099 -220.105405)
			(xy 107.692555 -220.147324) (xy 107.716078 -220.193491) (xy 107.73209 -220.24277) (xy 107.740196 -220.293947)
			(xy 107.740704 -220.319854) (xy 108.96092 -220.319854) (xy 108.961428 -220.293947) (xy 108.969534 -220.24277)
			(xy 108.985546 -220.193491) (xy 109.009069 -220.147324) (xy 109.039525 -220.105405) (xy 109.076163 -220.068767)
			(xy 109.118082 -220.038311) (xy 109.164249 -220.014788) (xy 109.213528 -219.998776) (xy 109.264705 -219.99067)
			(xy 109.316519 -219.99067) (xy 109.367696 -219.998776) (xy 109.416975 -220.014788) (xy 109.463142 -220.038311)
			(xy 109.505061 -220.068767) (xy 109.541699 -220.105405) (xy 109.572155 -220.147324) (xy 109.595678 -220.193491)
			(xy 109.61169 -220.24277) (xy 109.619796 -220.293947) (xy 109.620304 -220.319854) (xy 110.84052 -220.319854)
			(xy 110.841028 -220.293947) (xy 110.849134 -220.24277) (xy 110.865146 -220.193491) (xy 110.888669 -220.147324)
			(xy 110.919125 -220.105405) (xy 110.955763 -220.068767) (xy 110.997682 -220.038311) (xy 111.043849 -220.014788)
			(xy 111.093128 -219.998776) (xy 111.144305 -219.99067) (xy 111.196119 -219.99067) (xy 111.247296 -219.998776)
			(xy 111.296575 -220.014788) (xy 111.342742 -220.038311) (xy 111.384661 -220.068767) (xy 111.421299 -220.105405)
			(xy 111.451755 -220.147324) (xy 111.475278 -220.193491) (xy 111.49129 -220.24277) (xy 111.499396 -220.293947)
			(xy 111.499904 -220.319854) (xy 112.72012 -220.319854) (xy 112.720628 -220.293947) (xy 112.728734 -220.24277)
			(xy 112.744746 -220.193491) (xy 112.768269 -220.147324) (xy 112.798725 -220.105405) (xy 112.835363 -220.068767)
			(xy 112.877282 -220.038311) (xy 112.923449 -220.014788) (xy 112.972728 -219.998776) (xy 113.023905 -219.99067)
			(xy 113.075719 -219.99067) (xy 113.126896 -219.998776) (xy 113.176175 -220.014788) (xy 113.222342 -220.038311)
			(xy 113.264261 -220.068767) (xy 113.300899 -220.105405) (xy 113.331355 -220.147324) (xy 113.354878 -220.193491)
			(xy 113.37089 -220.24277) (xy 113.378996 -220.293947) (xy 113.379504 -220.319854) (xy 113.378894 -220.347507)
			(xy 113.369571 -220.402025) (xy 113.360962 -220.428312) (xy 113.353342 -220.45041) (xy 113.558574 -220.805756)
			(xy 113.581434 -220.810074) (xy 113.606245 -220.815229) (xy 113.653984 -220.832223) (xy 113.698562 -220.856322)
			(xy 113.738927 -220.886957) (xy 113.77413 -220.923408) (xy 113.80334 -220.964816) (xy 113.825872 -221.010206)
			(xy 113.841192 -221.058509) (xy 113.848942 -221.108587) (xy 113.849404 -221.133924) (xy 113.848896 -221.159811)
			(xy 113.840797 -221.210949) (xy 113.824798 -221.260189) (xy 113.801292 -221.306321) (xy 113.77086 -221.348208)
			(xy 113.73425 -221.384818) (xy 113.692363 -221.41525) (xy 113.646231 -221.438756) (xy 113.596991 -221.454755)
			(xy 113.545853 -221.462854) (xy 113.494079 -221.462854) (xy 113.442941 -221.454755) (xy 113.393701 -221.438756)
			(xy 113.347569 -221.41525) (xy 113.305682 -221.384818) (xy 113.269072 -221.348208) (xy 113.23864 -221.306321)
			(xy 113.215134 -221.260189) (xy 113.199135 -221.210949) (xy 113.191036 -221.159811) (xy 113.190528 -221.133924)
			(xy 113.191067 -221.106216) (xy 113.200256 -221.05157) (xy 113.208816 -221.025212) (xy 113.21669 -221.003114)
			(xy 113.011712 -220.648022) (xy 112.988852 -220.643704) (xy 112.964 -220.63857) (xy 112.916153 -220.621668)
			(xy 112.871462 -220.597632) (xy 112.830984 -220.567029) (xy 112.795674 -220.530584) (xy 112.766368 -220.489157)
			(xy 112.743757 -220.443728) (xy 112.728377 -220.39537) (xy 112.720591 -220.345226) (xy 112.72012 -220.319854)
			(xy 111.499904 -220.319854) (xy 111.499294 -220.347507) (xy 111.489971 -220.402025) (xy 111.481362 -220.428312)
			(xy 111.473742 -220.45041) (xy 111.678974 -220.805756) (xy 111.701834 -220.810074) (xy 111.726645 -220.815229)
			(xy 111.774384 -220.832223) (xy 111.818962 -220.856322) (xy 111.859327 -220.886957) (xy 111.89453 -220.923408)
			(xy 111.92374 -220.964816) (xy 111.946272 -221.010206) (xy 111.961592 -221.058509) (xy 111.969342 -221.108587)
			(xy 111.969804 -221.133924) (xy 111.969296 -221.159811) (xy 111.961197 -221.210949) (xy 111.945198 -221.260189)
			(xy 111.921692 -221.306321) (xy 111.89126 -221.348208) (xy 111.85465 -221.384818) (xy 111.812763 -221.41525)
			(xy 111.766631 -221.438756) (xy 111.717391 -221.454755) (xy 111.666253 -221.462854) (xy 111.614479 -221.462854)
			(xy 111.563341 -221.454755) (xy 111.514101 -221.438756) (xy 111.467969 -221.41525) (xy 111.426082 -221.384818)
			(xy 111.389472 -221.348208) (xy 111.35904 -221.306321) (xy 111.335534 -221.260189) (xy 111.319535 -221.210949)
			(xy 111.311436 -221.159811) (xy 111.310928 -221.133924) (xy 111.311467 -221.106216) (xy 111.320656 -221.05157)
			(xy 111.329216 -221.025212) (xy 111.33709 -221.003114) (xy 111.132112 -220.648022) (xy 111.109252 -220.643704)
			(xy 111.0844 -220.63857) (xy 111.036553 -220.621668) (xy 110.991862 -220.597632) (xy 110.951384 -220.567029)
			(xy 110.916074 -220.530584) (xy 110.886768 -220.489157) (xy 110.864157 -220.443728) (xy 110.848777 -220.39537)
			(xy 110.840991 -220.345226) (xy 110.84052 -220.319854) (xy 109.620304 -220.319854) (xy 109.619694 -220.347507)
			(xy 109.610371 -220.402025) (xy 109.601762 -220.428312) (xy 109.594142 -220.45041) (xy 109.799374 -220.805756)
			(xy 109.822234 -220.810074) (xy 109.847045 -220.815229) (xy 109.894784 -220.832223) (xy 109.939362 -220.856322)
			(xy 109.979727 -220.886957) (xy 110.01493 -220.923408) (xy 110.04414 -220.964816) (xy 110.066672 -221.010206)
			(xy 110.081992 -221.058509) (xy 110.089742 -221.108587) (xy 110.090204 -221.133924) (xy 110.089696 -221.159811)
			(xy 110.081597 -221.210949) (xy 110.065598 -221.260189) (xy 110.042092 -221.306321) (xy 110.01166 -221.348208)
			(xy 109.97505 -221.384818) (xy 109.933163 -221.41525) (xy 109.887031 -221.438756) (xy 109.837791 -221.454755)
			(xy 109.786653 -221.462854) (xy 109.734879 -221.462854) (xy 109.683741 -221.454755) (xy 109.634501 -221.438756)
			(xy 109.588369 -221.41525) (xy 109.546482 -221.384818) (xy 109.509872 -221.348208) (xy 109.47944 -221.306321)
			(xy 109.455934 -221.260189) (xy 109.439935 -221.210949) (xy 109.431836 -221.159811) (xy 109.431328 -221.133924)
			(xy 109.431867 -221.106216) (xy 109.441056 -221.05157) (xy 109.449616 -221.025212) (xy 109.45749 -221.003114)
			(xy 109.252512 -220.648022) (xy 109.229652 -220.643704) (xy 109.2048 -220.63857) (xy 109.156953 -220.621668)
			(xy 109.112262 -220.597632) (xy 109.071784 -220.567029) (xy 109.036474 -220.530584) (xy 109.007168 -220.489157)
			(xy 108.984557 -220.443728) (xy 108.969177 -220.39537) (xy 108.961391 -220.345226) (xy 108.96092 -220.319854)
			(xy 107.740704 -220.319854) (xy 107.740094 -220.347507) (xy 107.730771 -220.402025) (xy 107.722162 -220.428312)
			(xy 107.714542 -220.45041) (xy 107.919774 -220.805756) (xy 107.942634 -220.810074) (xy 107.967445 -220.815229)
			(xy 108.015184 -220.832223) (xy 108.059762 -220.856322) (xy 108.100127 -220.886957) (xy 108.13533 -220.923408)
			(xy 108.16454 -220.964816) (xy 108.187072 -221.010206) (xy 108.202392 -221.058509) (xy 108.210142 -221.108587)
			(xy 108.210604 -221.133924) (xy 108.210096 -221.159811) (xy 108.201997 -221.210949) (xy 108.185998 -221.260189)
			(xy 108.162492 -221.306321) (xy 108.13206 -221.348208) (xy 108.09545 -221.384818) (xy 108.053563 -221.41525)
			(xy 108.007431 -221.438756) (xy 107.958191 -221.454755) (xy 107.907053 -221.462854) (xy 107.855279 -221.462854)
			(xy 107.804141 -221.454755) (xy 107.754901 -221.438756) (xy 107.708769 -221.41525) (xy 107.666882 -221.384818)
			(xy 107.630272 -221.348208) (xy 107.59984 -221.306321) (xy 107.576334 -221.260189) (xy 107.560335 -221.210949)
			(xy 107.552236 -221.159811) (xy 107.551728 -221.133924) (xy 107.552267 -221.106216) (xy 107.561456 -221.05157)
			(xy 107.570016 -221.025212) (xy 107.57789 -221.003114) (xy 107.372912 -220.648022) (xy 107.350052 -220.643704)
			(xy 107.3252 -220.63857) (xy 107.277353 -220.621668) (xy 107.232662 -220.597632) (xy 107.192184 -220.567029)
			(xy 107.156874 -220.530584) (xy 107.127568 -220.489157) (xy 107.104957 -220.443728) (xy 107.089577 -220.39537)
			(xy 107.081791 -220.345226) (xy 107.08132 -220.319854) (xy 105.861104 -220.319854) (xy 105.860494 -220.347507)
			(xy 105.851171 -220.402025) (xy 105.842562 -220.428312) (xy 105.834942 -220.45041) (xy 106.040174 -220.805756)
			(xy 106.063034 -220.810074) (xy 106.087845 -220.815229) (xy 106.135584 -220.832223) (xy 106.180162 -220.856322)
			(xy 106.220527 -220.886957) (xy 106.25573 -220.923408) (xy 106.28494 -220.964816) (xy 106.307472 -221.010206)
			(xy 106.322792 -221.058509) (xy 106.330542 -221.108587) (xy 106.331004 -221.133924) (xy 106.330496 -221.159811)
			(xy 106.322397 -221.210949) (xy 106.306398 -221.260189) (xy 106.282892 -221.306321) (xy 106.25246 -221.348208)
			(xy 106.21585 -221.384818) (xy 106.173963 -221.41525) (xy 106.127831 -221.438756) (xy 106.078591 -221.454755)
			(xy 106.027453 -221.462854) (xy 105.975679 -221.462854) (xy 105.924541 -221.454755) (xy 105.875301 -221.438756)
			(xy 105.829169 -221.41525) (xy 105.787282 -221.384818) (xy 105.750672 -221.348208) (xy 105.72024 -221.306321)
			(xy 105.696734 -221.260189) (xy 105.680735 -221.210949) (xy 105.672636 -221.159811) (xy 105.672128 -221.133924)
			(xy 105.672667 -221.106216) (xy 105.681856 -221.05157) (xy 105.690416 -221.025212) (xy 105.69829 -221.003114)
			(xy 105.493312 -220.648022) (xy 105.470452 -220.643704) (xy 105.4456 -220.63857) (xy 105.397753 -220.621668)
			(xy 105.353062 -220.597632) (xy 105.312584 -220.567029) (xy 105.277274 -220.530584) (xy 105.247968 -220.489157)
			(xy 105.225357 -220.443728) (xy 105.209977 -220.39537) (xy 105.202191 -220.345226) (xy 105.20172 -220.319854)
			(xy 103.981504 -220.319854) (xy 103.981042 -220.345204) (xy 103.973286 -220.395306) (xy 103.957949 -220.44363)
			(xy 103.935392 -220.489036) (xy 103.90615 -220.530452) (xy 103.870909 -220.566902) (xy 103.830504 -220.597525)
			(xy 103.785885 -220.6216) (xy 103.738106 -220.638559) (xy 103.71328 -220.643704) (xy 103.69042 -220.648022)
			(xy 103.485442 -221.003114) (xy 103.493316 -221.024958) (xy 103.501897 -221.051376) (xy 103.511097 -221.106152)
			(xy 103.511604 -221.133924) (xy 103.511095 -221.159818) (xy 103.502995 -221.210968) (xy 103.486997 -221.260223)
			(xy 103.463494 -221.30637) (xy 103.433066 -221.348276) (xy 103.39646 -221.384909) (xy 103.354577 -221.415368)
			(xy 103.308446 -221.438904) (xy 103.259204 -221.454938) (xy 103.208059 -221.463076) (xy 103.182166 -221.463616)
			(xy 103.154312 -221.46299) (xy 103.099409 -221.453535) (xy 103.072946 -221.44482) (xy 103.059699 -221.440682)
			(xy 103.032014 -221.438911) (xy 103.004875 -221.444661) (xy 102.980287 -221.457506) (xy 102.960067 -221.476499)
			(xy 102.945708 -221.500235) (xy 102.938272 -221.526961) (xy 102.937818 -221.540832) (xy 102.937818 -221.70771)
			(xy 102.957062 -221.726527) (xy 102.98977 -221.769267) (xy 103.015096 -221.816755) (xy 103.032368 -221.867728)
			(xy 103.041125 -221.92083) (xy 103.041704 -221.94774) (xy 104.26192 -221.94774) (xy 104.262371 -221.922394)
			(xy 104.270152 -221.872302) (xy 104.285506 -221.82399) (xy 104.308072 -221.778597) (xy 104.337318 -221.737192)
			(xy 104.372555 -221.700749) (xy 104.412954 -221.670127) (xy 104.457562 -221.646047) (xy 104.50533 -221.629076)
			(xy 104.530144 -221.62389) (xy 104.553004 -221.619572) (xy 104.758236 -221.264226) (xy 104.750362 -221.242128)
			(xy 104.741898 -221.215883) (xy 104.732825 -221.161495) (xy 104.732328 -221.133924) (xy 104.732836 -221.108037)
			(xy 104.740935 -221.056899) (xy 104.756934 -221.007659) (xy 104.78044 -220.961527) (xy 104.810872 -220.91964)
			(xy 104.847482 -220.88303) (xy 104.889369 -220.852598) (xy 104.935501 -220.829092) (xy 104.984741 -220.813093)
			(xy 105.035879 -220.804994) (xy 105.087653 -220.804994) (xy 105.138791 -220.813093) (xy 105.188031 -220.829092)
			(xy 105.234163 -220.852598) (xy 105.27605 -220.88303) (xy 105.31266 -220.91964) (xy 105.343092 -220.961527)
			(xy 105.366598 -221.007659) (xy 105.382597 -221.056899) (xy 105.390696 -221.108037) (xy 105.391204 -221.133924)
			(xy 105.390748 -221.159299) (xy 105.382976 -221.20945) (xy 105.367604 -221.257815) (xy 105.344997 -221.303251)
			(xy 105.315689 -221.344682) (xy 105.280373 -221.381128) (xy 105.239885 -221.411727) (xy 105.195184 -221.435754)
			(xy 105.147326 -221.452641) (xy 105.122472 -221.457774) (xy 105.099612 -221.462092) (xy 104.894888 -221.81693)
			(xy 104.902762 -221.838774) (xy 104.911419 -221.865179) (xy 104.920732 -221.919958) (xy 104.921304 -221.94774)
			(xy 106.14152 -221.94774) (xy 106.141971 -221.922394) (xy 106.149752 -221.872302) (xy 106.165106 -221.82399)
			(xy 106.187672 -221.778597) (xy 106.216918 -221.737192) (xy 106.252155 -221.700749) (xy 106.292554 -221.670127)
			(xy 106.337162 -221.646047) (xy 106.38493 -221.629076) (xy 106.409744 -221.62389) (xy 106.432604 -221.619572)
			(xy 106.637836 -221.264226) (xy 106.629962 -221.242128) (xy 106.621498 -221.215883) (xy 106.612425 -221.161495)
			(xy 106.611928 -221.133924) (xy 106.612436 -221.108037) (xy 106.620535 -221.056899) (xy 106.636534 -221.007659)
			(xy 106.66004 -220.961527) (xy 106.690472 -220.91964) (xy 106.727082 -220.88303) (xy 106.768969 -220.852598)
			(xy 106.815101 -220.829092) (xy 106.864341 -220.813093) (xy 106.915479 -220.804994) (xy 106.967253 -220.804994)
			(xy 107.018391 -220.813093) (xy 107.067631 -220.829092) (xy 107.113763 -220.852598) (xy 107.15565 -220.88303)
			(xy 107.19226 -220.91964) (xy 107.222692 -220.961527) (xy 107.246198 -221.007659) (xy 107.262197 -221.056899)
			(xy 107.270296 -221.108037) (xy 107.270804 -221.133924) (xy 107.270348 -221.159299) (xy 107.262576 -221.20945)
			(xy 107.247204 -221.257815) (xy 107.224597 -221.303251) (xy 107.195289 -221.344682) (xy 107.159973 -221.381128)
			(xy 107.119485 -221.411727) (xy 107.074784 -221.435754) (xy 107.026926 -221.452641) (xy 107.002072 -221.457774)
			(xy 106.979212 -221.462092) (xy 106.774488 -221.81693) (xy 106.782362 -221.838774) (xy 106.791019 -221.865179)
			(xy 106.800332 -221.919958) (xy 106.800904 -221.94774) (xy 108.02112 -221.94774) (xy 108.021571 -221.922394)
			(xy 108.029352 -221.872302) (xy 108.044706 -221.82399) (xy 108.067272 -221.778597) (xy 108.096518 -221.737192)
			(xy 108.131755 -221.700749) (xy 108.172154 -221.670127) (xy 108.216762 -221.646047) (xy 108.26453 -221.629076)
			(xy 108.289344 -221.62389) (xy 108.312204 -221.619572) (xy 108.517436 -221.264226) (xy 108.509562 -221.242128)
			(xy 108.501098 -221.215883) (xy 108.492025 -221.161495) (xy 108.491528 -221.133924) (xy 108.492036 -221.108037)
			(xy 108.500135 -221.056899) (xy 108.516134 -221.007659) (xy 108.53964 -220.961527) (xy 108.570072 -220.91964)
			(xy 108.606682 -220.88303) (xy 108.648569 -220.852598) (xy 108.694701 -220.829092) (xy 108.743941 -220.813093)
			(xy 108.795079 -220.804994) (xy 108.846853 -220.804994) (xy 108.897991 -220.813093) (xy 108.947231 -220.829092)
			(xy 108.993363 -220.852598) (xy 109.03525 -220.88303) (xy 109.07186 -220.91964) (xy 109.102292 -220.961527)
			(xy 109.125798 -221.007659) (xy 109.141797 -221.056899) (xy 109.149896 -221.108037) (xy 109.150404 -221.133924)
			(xy 109.149948 -221.159299) (xy 109.142176 -221.20945) (xy 109.126804 -221.257815) (xy 109.104197 -221.303251)
			(xy 109.074889 -221.344682) (xy 109.039573 -221.381128) (xy 108.999085 -221.411727) (xy 108.954384 -221.435754)
			(xy 108.906526 -221.452641) (xy 108.881672 -221.457774) (xy 108.858812 -221.462092) (xy 108.654088 -221.81693)
			(xy 108.661962 -221.838774) (xy 108.670619 -221.865179) (xy 108.679932 -221.919958) (xy 108.680504 -221.94774)
			(xy 109.901228 -221.94774) (xy 109.901634 -221.922403) (xy 109.909396 -221.872326) (xy 109.924728 -221.824026)
			(xy 109.947269 -221.77864) (xy 109.976489 -221.737238) (xy 110.011699 -221.700794) (xy 110.05207 -221.670165)
			(xy 110.096652 -221.646074) (xy 110.144395 -221.629087) (xy 110.169198 -221.62389) (xy 110.192058 -221.619572)
			(xy 110.397036 -221.26448) (xy 110.389416 -221.242382) (xy 110.380865 -221.216087) (xy 110.371671 -221.161569)
			(xy 110.371128 -221.133924) (xy 110.371636 -221.108037) (xy 110.379735 -221.056899) (xy 110.395734 -221.007659)
			(xy 110.41924 -220.961527) (xy 110.449672 -220.91964) (xy 110.486282 -220.88303) (xy 110.528169 -220.852598)
			(xy 110.574301 -220.829092) (xy 110.623541 -220.813093) (xy 110.674679 -220.804994) (xy 110.726453 -220.804994)
			(xy 110.777591 -220.813093) (xy 110.826831 -220.829092) (xy 110.872963 -220.852598) (xy 110.91485 -220.88303)
			(xy 110.95146 -220.91964) (xy 110.981892 -220.961527) (xy 111.005398 -221.007659) (xy 111.021397 -221.056899)
			(xy 111.029496 -221.108037) (xy 111.030004 -221.133924) (xy 111.029585 -221.15929) (xy 111.021833 -221.209425)
			(xy 111.006484 -221.257778) (xy 110.983902 -221.303206) (xy 110.954621 -221.344633) (xy 110.919333 -221.381081)
			(xy 110.878874 -221.411686) (xy 110.8342 -221.435725) (xy 110.786369 -221.45263) (xy 110.761526 -221.457774)
			(xy 110.738666 -221.462092) (xy 110.533942 -221.81693) (xy 110.541816 -221.838774) (xy 110.550414 -221.865187)
			(xy 110.559598 -221.919967) (xy 110.560104 -221.94774) (xy 111.78032 -221.94774) (xy 111.780771 -221.922394)
			(xy 111.788552 -221.872302) (xy 111.803906 -221.82399) (xy 111.826472 -221.778597) (xy 111.855718 -221.737192)
			(xy 111.890955 -221.700749) (xy 111.931354 -221.670127) (xy 111.975962 -221.646047) (xy 112.02373 -221.629076)
			(xy 112.048544 -221.62389) (xy 112.071404 -221.619572) (xy 112.276636 -221.264226) (xy 112.268762 -221.242128)
			(xy 112.260298 -221.215883) (xy 112.251225 -221.161495) (xy 112.250728 -221.133924) (xy 112.251236 -221.108037)
			(xy 112.259335 -221.056899) (xy 112.275334 -221.007659) (xy 112.29884 -220.961527) (xy 112.329272 -220.91964)
			(xy 112.365882 -220.88303) (xy 112.407769 -220.852598) (xy 112.453901 -220.829092) (xy 112.503141 -220.813093)
			(xy 112.554279 -220.804994) (xy 112.606053 -220.804994) (xy 112.657191 -220.813093) (xy 112.706431 -220.829092)
			(xy 112.752563 -220.852598) (xy 112.79445 -220.88303) (xy 112.83106 -220.91964) (xy 112.861492 -220.961527)
			(xy 112.884998 -221.007659) (xy 112.900997 -221.056899) (xy 112.909096 -221.108037) (xy 112.909604 -221.133924)
			(xy 112.909148 -221.159299) (xy 112.901376 -221.20945) (xy 112.886004 -221.257815) (xy 112.863397 -221.303251)
			(xy 112.834089 -221.344682) (xy 112.798773 -221.381128) (xy 112.758285 -221.411727) (xy 112.713584 -221.435754)
			(xy 112.665726 -221.452641) (xy 112.640872 -221.457774) (xy 112.618012 -221.462092) (xy 112.413288 -221.81693)
			(xy 112.421162 -221.838774) (xy 112.429819 -221.865179) (xy 112.439132 -221.919958) (xy 112.439704 -221.94774)
			(xy 113.660428 -221.94774) (xy 113.660834 -221.922403) (xy 113.668596 -221.872326) (xy 113.683928 -221.824026)
			(xy 113.706469 -221.77864) (xy 113.735689 -221.737238) (xy 113.770899 -221.700794) (xy 113.81127 -221.670165)
			(xy 113.855852 -221.646074) (xy 113.903595 -221.629087) (xy 113.928398 -221.62389) (xy 113.951258 -221.619572)
			(xy 114.156236 -221.26448) (xy 114.148616 -221.242382) (xy 114.140065 -221.216087) (xy 114.130871 -221.161569)
			(xy 114.130328 -221.133924) (xy 114.130836 -221.108037) (xy 114.138935 -221.056899) (xy 114.154934 -221.007659)
			(xy 114.17844 -220.961527) (xy 114.208872 -220.91964) (xy 114.245482 -220.88303) (xy 114.287369 -220.852598)
			(xy 114.333501 -220.829092) (xy 114.382741 -220.813093) (xy 114.433879 -220.804994) (xy 114.485653 -220.804994)
			(xy 114.536791 -220.813093) (xy 114.586031 -220.829092) (xy 114.632163 -220.852598) (xy 114.67405 -220.88303)
			(xy 114.71066 -220.91964) (xy 114.741092 -220.961527) (xy 114.764598 -221.007659) (xy 114.780597 -221.056899)
			(xy 114.788696 -221.108037) (xy 114.789204 -221.133924) (xy 114.788785 -221.15929) (xy 114.781033 -221.209425)
			(xy 114.765684 -221.257778) (xy 114.743102 -221.303206) (xy 114.713821 -221.344633) (xy 114.678533 -221.381081)
			(xy 114.638074 -221.411686) (xy 114.5934 -221.435725) (xy 114.545569 -221.45263) (xy 114.520726 -221.457774)
			(xy 114.497866 -221.462092) (xy 114.293142 -221.81693) (xy 114.301016 -221.838774) (xy 114.309614 -221.865187)
			(xy 114.318798 -221.919967) (xy 114.319304 -221.94774) (xy 114.318796 -221.973627) (xy 114.310697 -222.024765)
			(xy 114.294698 -222.074005) (xy 114.271192 -222.120137) (xy 114.24076 -222.162024) (xy 114.20415 -222.198634)
			(xy 114.162263 -222.229066) (xy 114.116131 -222.252572) (xy 114.066891 -222.268571) (xy 114.015753 -222.27667)
			(xy 113.963979 -222.27667) (xy 113.912841 -222.268571) (xy 113.863601 -222.252572) (xy 113.817469 -222.229066)
			(xy 113.775582 -222.198634) (xy 113.738972 -222.162024) (xy 113.70854 -222.120137) (xy 113.685034 -222.074005)
			(xy 113.669035 -222.024765) (xy 113.660936 -221.973627) (xy 113.660428 -221.94774) (xy 112.439704 -221.94774)
			(xy 112.439196 -221.973647) (xy 112.43109 -222.024824) (xy 112.415078 -222.074103) (xy 112.391555 -222.12027)
			(xy 112.361099 -222.162189) (xy 112.324461 -222.198827) (xy 112.282542 -222.229283) (xy 112.236375 -222.252806)
			(xy 112.187096 -222.268818) (xy 112.135919 -222.276924) (xy 112.084105 -222.276924) (xy 112.032928 -222.268818)
			(xy 111.983649 -222.252806) (xy 111.937482 -222.229283) (xy 111.895563 -222.198827) (xy 111.858925 -222.162189)
			(xy 111.828469 -222.12027) (xy 111.804946 -222.074103) (xy 111.788934 -222.024824) (xy 111.780828 -221.973647)
			(xy 111.78032 -221.94774) (xy 110.560104 -221.94774) (xy 110.559596 -221.973627) (xy 110.551497 -222.024765)
			(xy 110.535498 -222.074005) (xy 110.511992 -222.120137) (xy 110.48156 -222.162024) (xy 110.44495 -222.198634)
			(xy 110.403063 -222.229066) (xy 110.356931 -222.252572) (xy 110.307691 -222.268571) (xy 110.256553 -222.27667)
			(xy 110.204779 -222.27667) (xy 110.153641 -222.268571) (xy 110.104401 -222.252572) (xy 110.058269 -222.229066)
			(xy 110.016382 -222.198634) (xy 109.979772 -222.162024) (xy 109.94934 -222.120137) (xy 109.925834 -222.074005)
			(xy 109.909835 -222.024765) (xy 109.901736 -221.973627) (xy 109.901228 -221.94774) (xy 108.680504 -221.94774)
			(xy 108.679996 -221.973647) (xy 108.67189 -222.024824) (xy 108.655878 -222.074103) (xy 108.632355 -222.12027)
			(xy 108.601899 -222.162189) (xy 108.565261 -222.198827) (xy 108.523342 -222.229283) (xy 108.477175 -222.252806)
			(xy 108.427896 -222.268818) (xy 108.376719 -222.276924) (xy 108.324905 -222.276924) (xy 108.273728 -222.268818)
			(xy 108.224449 -222.252806) (xy 108.178282 -222.229283) (xy 108.136363 -222.198827) (xy 108.099725 -222.162189)
			(xy 108.069269 -222.12027) (xy 108.045746 -222.074103) (xy 108.029734 -222.024824) (xy 108.021628 -221.973647)
			(xy 108.02112 -221.94774) (xy 106.800904 -221.94774) (xy 106.800396 -221.973647) (xy 106.79229 -222.024824)
			(xy 106.776278 -222.074103) (xy 106.752755 -222.12027) (xy 106.722299 -222.162189) (xy 106.685661 -222.198827)
			(xy 106.643742 -222.229283) (xy 106.597575 -222.252806) (xy 106.548296 -222.268818) (xy 106.497119 -222.276924)
			(xy 106.445305 -222.276924) (xy 106.394128 -222.268818) (xy 106.344849 -222.252806) (xy 106.298682 -222.229283)
			(xy 106.256763 -222.198827) (xy 106.220125 -222.162189) (xy 106.189669 -222.12027) (xy 106.166146 -222.074103)
			(xy 106.150134 -222.024824) (xy 106.142028 -221.973647) (xy 106.14152 -221.94774) (xy 104.921304 -221.94774)
			(xy 104.920796 -221.973647) (xy 104.91269 -222.024824) (xy 104.896678 -222.074103) (xy 104.873155 -222.12027)
			(xy 104.842699 -222.162189) (xy 104.806061 -222.198827) (xy 104.764142 -222.229283) (xy 104.717975 -222.252806)
			(xy 104.668696 -222.268818) (xy 104.617519 -222.276924) (xy 104.565705 -222.276924) (xy 104.514528 -222.268818)
			(xy 104.465249 -222.252806) (xy 104.419082 -222.229283) (xy 104.377163 -222.198827) (xy 104.340525 -222.162189)
			(xy 104.310069 -222.12027) (xy 104.286546 -222.074103) (xy 104.270534 -222.024824) (xy 104.262428 -221.973647)
			(xy 104.26192 -221.94774) (xy 103.041704 -221.94774) (xy 103.041144 -221.974647) (xy 103.032355 -222.02774)
			(xy 103.015065 -222.078703) (xy 102.989733 -222.126183) (xy 102.957031 -222.168922) (xy 102.937818 -222.18777)
			(xy 102.937818 -223.337374) (xy 102.956845 -223.356091) (xy 102.989167 -223.398558) (xy 103.014186 -223.445699)
			(xy 103.03124 -223.496269) (xy 103.03988 -223.548934) (xy 103.039877 -223.602302) (xy 103.031232 -223.654966)
			(xy 103.014172 -223.705534) (xy 102.989148 -223.752672) (xy 102.956821 -223.795136) (xy 102.937818 -223.813878)
			(xy 102.937818 -223.982534) (xy 102.938289 -223.996396) (xy 102.945753 -224.023097) (xy 102.96012 -224.046808)
			(xy 102.980334 -224.065783) (xy 103.004906 -224.078624) (xy 103.032025 -224.084386) (xy 103.059694 -224.082644)
			(xy 103.072946 -224.078546) (xy 103.084657 -224.074522) (xy 103.108559 -224.068041) (xy 103.120698 -224.065592)
			(xy 103.143558 -224.061274) (xy 103.348282 -223.706436) (xy 103.340662 -223.684338) (xy 103.332035 -223.65799)
			(xy 103.322706 -223.603344) (xy 103.32212 -223.575626) (xy 103.322628 -223.549719) (xy 103.330734 -223.498542)
			(xy 103.346746 -223.449263) (xy 103.370269 -223.403096) (xy 103.400725 -223.361177) (xy 103.437363 -223.324539)
			(xy 103.479282 -223.294083) (xy 103.525449 -223.27056) (xy 103.574728 -223.254548) (xy 103.625905 -223.246442)
			(xy 103.677719 -223.246442) (xy 103.728896 -223.254548) (xy 103.778175 -223.27056) (xy 103.824342 -223.294083)
			(xy 103.866261 -223.324539) (xy 103.902899 -223.361177) (xy 103.933355 -223.403096) (xy 103.956878 -223.449263)
			(xy 103.97289 -223.498542) (xy 103.980996 -223.549719) (xy 103.981504 -223.575626) (xy 103.981029 -223.600984)
			(xy 103.973244 -223.651099) (xy 103.957876 -223.699431) (xy 103.935288 -223.744839) (xy 103.906013 -223.786253)
			(xy 103.870742 -223.822696) (xy 103.830306 -223.853307) (xy 103.78566 -223.877366) (xy 103.737855 -223.894304)
			(xy 103.713026 -223.899476) (xy 103.690166 -223.903794) (xy 103.485442 -224.258632) (xy 103.493316 -224.280476)
			(xy 103.501896 -224.306895) (xy 103.511093 -224.36167) (xy 103.511604 -224.389442) (xy 103.792528 -224.389442)
			(xy 103.793036 -224.363555) (xy 103.801135 -224.312417) (xy 103.817134 -224.263177) (xy 103.84064 -224.217045)
			(xy 103.871072 -224.175158) (xy 103.907682 -224.138548) (xy 103.949569 -224.108116) (xy 103.995701 -224.08461)
			(xy 104.044941 -224.068611) (xy 104.096079 -224.060512) (xy 104.147853 -224.060512) (xy 104.198991 -224.068611)
			(xy 104.248231 -224.08461) (xy 104.294363 -224.108116) (xy 104.33625 -224.138548) (xy 104.37286 -224.175158)
			(xy 104.403292 -224.217045) (xy 104.426798 -224.263177) (xy 104.442797 -224.312417) (xy 104.450896 -224.363555)
			(xy 104.451404 -224.389442) (xy 104.732328 -224.389442) (xy 104.732735 -224.364105) (xy 104.740497 -224.314028)
			(xy 104.755829 -224.265728) (xy 104.77837 -224.220343) (xy 104.807589 -224.17894) (xy 104.842799 -224.142496)
			(xy 104.88317 -224.111867) (xy 104.927752 -224.087776) (xy 104.975495 -224.070789) (xy 105.000298 -224.065592)
			(xy 105.023158 -224.061274) (xy 105.227882 -223.706436) (xy 105.220262 -223.684338) (xy 105.211631 -223.657991)
			(xy 105.20231 -223.603344) (xy 105.20172 -223.575626) (xy 105.202228 -223.549719) (xy 105.210334 -223.498542)
			(xy 105.226346 -223.449263) (xy 105.249869 -223.403096) (xy 105.280325 -223.361177) (xy 105.316963 -223.324539)
			(xy 105.358882 -223.294083) (xy 105.405049 -223.27056) (xy 105.454328 -223.254548) (xy 105.505505 -223.246442)
			(xy 105.557319 -223.246442) (xy 105.608496 -223.254548) (xy 105.657775 -223.27056) (xy 105.703942 -223.294083)
			(xy 105.745861 -223.324539) (xy 105.782499 -223.361177) (xy 105.812955 -223.403096) (xy 105.836478 -223.449263)
			(xy 105.85249 -223.498542) (xy 105.860596 -223.549719) (xy 105.861104 -223.575626) (xy 105.860687 -223.600992)
			(xy 105.852934 -223.651127) (xy 105.837585 -223.69948) (xy 105.815003 -223.744908) (xy 105.785722 -223.786336)
			(xy 105.750434 -223.822783) (xy 105.709975 -223.853388) (xy 105.665301 -223.877427) (xy 105.617469 -223.894332)
			(xy 105.592626 -223.899476) (xy 105.569766 -223.903794) (xy 105.365042 -224.258632) (xy 105.372916 -224.280476)
			(xy 105.38149 -224.306896) (xy 105.39069 -224.36167) (xy 105.391204 -224.389442) (xy 105.672128 -224.389442)
			(xy 105.672636 -224.363555) (xy 105.680735 -224.312417) (xy 105.696734 -224.263177) (xy 105.72024 -224.217045)
			(xy 105.750672 -224.175158) (xy 105.787282 -224.138548) (xy 105.829169 -224.108116) (xy 105.875301 -224.08461)
			(xy 105.924541 -224.068611) (xy 105.975679 -224.060512) (xy 106.027453 -224.060512) (xy 106.078591 -224.068611)
			(xy 106.127831 -224.08461) (xy 106.173963 -224.108116) (xy 106.21585 -224.138548) (xy 106.25246 -224.175158)
			(xy 106.282892 -224.217045) (xy 106.306398 -224.263177) (xy 106.322397 -224.312417) (xy 106.330496 -224.363555)
			(xy 106.331004 -224.389442) (xy 106.611928 -224.389442) (xy 106.612335 -224.364105) (xy 106.620097 -224.314028)
			(xy 106.635429 -224.265728) (xy 106.65797 -224.220343) (xy 106.687189 -224.17894) (xy 106.722399 -224.142496)
			(xy 106.76277 -224.111867) (xy 106.807352 -224.087776) (xy 106.855095 -224.070789) (xy 106.879898 -224.065592)
			(xy 106.902758 -224.061274) (xy 107.107482 -223.706436) (xy 107.099862 -223.684338) (xy 107.091231 -223.657991)
			(xy 107.08191 -223.603344) (xy 107.08132 -223.575626) (xy 107.081828 -223.549719) (xy 107.089934 -223.498542)
			(xy 107.105946 -223.449263) (xy 107.129469 -223.403096) (xy 107.159925 -223.361177) (xy 107.196563 -223.324539)
			(xy 107.238482 -223.294083) (xy 107.284649 -223.27056) (xy 107.333928 -223.254548) (xy 107.385105 -223.246442)
			(xy 107.436919 -223.246442) (xy 107.488096 -223.254548) (xy 107.537375 -223.27056) (xy 107.583542 -223.294083)
			(xy 107.625461 -223.324539) (xy 107.662099 -223.361177) (xy 107.692555 -223.403096) (xy 107.716078 -223.449263)
			(xy 107.73209 -223.498542) (xy 107.740196 -223.549719) (xy 107.740704 -223.575626) (xy 107.740287 -223.600992)
			(xy 107.732534 -223.651127) (xy 107.717185 -223.69948) (xy 107.694603 -223.744908) (xy 107.665322 -223.786336)
			(xy 107.630034 -223.822783) (xy 107.589575 -223.853388) (xy 107.544901 -223.877427) (xy 107.497069 -223.894332)
			(xy 107.472226 -223.899476) (xy 107.449366 -223.903794) (xy 107.244642 -224.258632) (xy 107.252516 -224.280476)
			(xy 107.26109 -224.306896) (xy 107.27029 -224.36167) (xy 107.270804 -224.389442) (xy 107.551728 -224.389442)
			(xy 107.552236 -224.363555) (xy 107.560335 -224.312417) (xy 107.576334 -224.263177) (xy 107.59984 -224.217045)
			(xy 107.630272 -224.175158) (xy 107.666882 -224.138548) (xy 107.708769 -224.108116) (xy 107.754901 -224.08461)
			(xy 107.804141 -224.068611) (xy 107.855279 -224.060512) (xy 107.907053 -224.060512) (xy 107.958191 -224.068611)
			(xy 108.007431 -224.08461) (xy 108.053563 -224.108116) (xy 108.09545 -224.138548) (xy 108.13206 -224.175158)
			(xy 108.162492 -224.217045) (xy 108.185998 -224.263177) (xy 108.201997 -224.312417) (xy 108.210096 -224.363555)
			(xy 108.210604 -224.389442) (xy 108.491528 -224.389442) (xy 108.491935 -224.364105) (xy 108.499697 -224.314028)
			(xy 108.515029 -224.265728) (xy 108.53757 -224.220343) (xy 108.566789 -224.17894) (xy 108.601999 -224.142496)
			(xy 108.64237 -224.111867) (xy 108.686952 -224.087776) (xy 108.734695 -224.070789) (xy 108.759498 -224.065592)
			(xy 108.782358 -224.061274) (xy 108.987082 -223.706436) (xy 108.979462 -223.684338) (xy 108.970831 -223.657991)
			(xy 108.96151 -223.603344) (xy 108.96092 -223.575626) (xy 108.961428 -223.549719) (xy 108.969534 -223.498542)
			(xy 108.985546 -223.449263) (xy 109.009069 -223.403096) (xy 109.039525 -223.361177) (xy 109.076163 -223.324539)
			(xy 109.118082 -223.294083) (xy 109.164249 -223.27056) (xy 109.213528 -223.254548) (xy 109.264705 -223.246442)
			(xy 109.316519 -223.246442) (xy 109.367696 -223.254548) (xy 109.416975 -223.27056) (xy 109.463142 -223.294083)
			(xy 109.505061 -223.324539) (xy 109.541699 -223.361177) (xy 109.572155 -223.403096) (xy 109.595678 -223.449263)
			(xy 109.61169 -223.498542) (xy 109.619796 -223.549719) (xy 109.620304 -223.575626) (xy 109.619887 -223.600992)
			(xy 109.612134 -223.651127) (xy 109.596785 -223.69948) (xy 109.574203 -223.744908) (xy 109.544922 -223.786336)
			(xy 109.509634 -223.822783) (xy 109.469175 -223.853388) (xy 109.424501 -223.877427) (xy 109.376669 -223.894332)
			(xy 109.351826 -223.899476) (xy 109.328966 -223.903794) (xy 109.124242 -224.258632) (xy 109.132116 -224.280476)
			(xy 109.14069 -224.306896) (xy 109.14989 -224.36167) (xy 109.150404 -224.389442) (xy 109.431328 -224.389442)
			(xy 109.431836 -224.363555) (xy 109.439935 -224.312417) (xy 109.455934 -224.263177) (xy 109.47944 -224.217045)
			(xy 109.509872 -224.175158) (xy 109.546482 -224.138548) (xy 109.588369 -224.108116) (xy 109.634501 -224.08461)
			(xy 109.683741 -224.068611) (xy 109.734879 -224.060512) (xy 109.786653 -224.060512) (xy 109.837791 -224.068611)
			(xy 109.887031 -224.08461) (xy 109.933163 -224.108116) (xy 109.97505 -224.138548) (xy 110.01166 -224.175158)
			(xy 110.042092 -224.217045) (xy 110.065598 -224.263177) (xy 110.081597 -224.312417) (xy 110.089696 -224.363555)
			(xy 110.090204 -224.389442) (xy 110.371128 -224.389442) (xy 110.371535 -224.364105) (xy 110.379297 -224.314028)
			(xy 110.394629 -224.265728) (xy 110.41717 -224.220343) (xy 110.446389 -224.17894) (xy 110.481599 -224.142496)
			(xy 110.52197 -224.111867) (xy 110.566552 -224.087776) (xy 110.614295 -224.070789) (xy 110.639098 -224.065592)
			(xy 110.661958 -224.061274) (xy 110.866682 -223.706436) (xy 110.859062 -223.684338) (xy 110.850431 -223.657991)
			(xy 110.84111 -223.603344) (xy 110.84052 -223.575626) (xy 110.841028 -223.549719) (xy 110.849134 -223.498542)
			(xy 110.865146 -223.449263) (xy 110.888669 -223.403096) (xy 110.919125 -223.361177) (xy 110.955763 -223.324539)
			(xy 110.997682 -223.294083) (xy 111.043849 -223.27056) (xy 111.093128 -223.254548) (xy 111.144305 -223.246442)
			(xy 111.196119 -223.246442) (xy 111.247296 -223.254548) (xy 111.296575 -223.27056) (xy 111.342742 -223.294083)
			(xy 111.384661 -223.324539) (xy 111.421299 -223.361177) (xy 111.451755 -223.403096) (xy 111.475278 -223.449263)
			(xy 111.49129 -223.498542) (xy 111.499396 -223.549719) (xy 111.499904 -223.575626) (xy 111.499487 -223.600992)
			(xy 111.491734 -223.651127) (xy 111.476385 -223.69948) (xy 111.453803 -223.744908) (xy 111.424522 -223.786336)
			(xy 111.389234 -223.822783) (xy 111.348775 -223.853388) (xy 111.304101 -223.877427) (xy 111.256269 -223.894332)
			(xy 111.231426 -223.899476) (xy 111.208566 -223.903794) (xy 111.003842 -224.258632) (xy 111.011716 -224.280476)
			(xy 111.02029 -224.306896) (xy 111.02949 -224.36167) (xy 111.030004 -224.389442) (xy 111.310928 -224.389442)
			(xy 111.311436 -224.363555) (xy 111.319535 -224.312417) (xy 111.335534 -224.263177) (xy 111.35904 -224.217045)
			(xy 111.389472 -224.175158) (xy 111.426082 -224.138548) (xy 111.467969 -224.108116) (xy 111.514101 -224.08461)
			(xy 111.563341 -224.068611) (xy 111.614479 -224.060512) (xy 111.666253 -224.060512) (xy 111.717391 -224.068611)
			(xy 111.766631 -224.08461) (xy 111.812763 -224.108116) (xy 111.85465 -224.138548) (xy 111.89126 -224.175158)
			(xy 111.921692 -224.217045) (xy 111.945198 -224.263177) (xy 111.961197 -224.312417) (xy 111.969296 -224.363555)
			(xy 111.969804 -224.389442) (xy 112.250728 -224.389442) (xy 112.251135 -224.364105) (xy 112.258897 -224.314028)
			(xy 112.274229 -224.265728) (xy 112.29677 -224.220343) (xy 112.325989 -224.17894) (xy 112.361199 -224.142496)
			(xy 112.40157 -224.111867) (xy 112.446152 -224.087776) (xy 112.493895 -224.070789) (xy 112.518698 -224.065592)
			(xy 112.541558 -224.061274) (xy 112.746282 -223.706436) (xy 112.738662 -223.684338) (xy 112.730031 -223.657991)
			(xy 112.72071 -223.603344) (xy 112.72012 -223.575626) (xy 112.720628 -223.549719) (xy 112.728734 -223.498542)
			(xy 112.744746 -223.449263) (xy 112.768269 -223.403096) (xy 112.798725 -223.361177) (xy 112.835363 -223.324539)
			(xy 112.877282 -223.294083) (xy 112.923449 -223.27056) (xy 112.972728 -223.254548) (xy 113.023905 -223.246442)
			(xy 113.075719 -223.246442) (xy 113.126896 -223.254548) (xy 113.176175 -223.27056) (xy 113.222342 -223.294083)
			(xy 113.264261 -223.324539) (xy 113.300899 -223.361177) (xy 113.331355 -223.403096) (xy 113.354878 -223.449263)
			(xy 113.37089 -223.498542) (xy 113.378996 -223.549719) (xy 113.379504 -223.575626) (xy 113.379087 -223.600992)
			(xy 113.371334 -223.651127) (xy 113.355985 -223.69948) (xy 113.333403 -223.744908) (xy 113.304122 -223.786336)
			(xy 113.268834 -223.822783) (xy 113.228375 -223.853388) (xy 113.183701 -223.877427) (xy 113.135869 -223.894332)
			(xy 113.111026 -223.899476) (xy 113.088166 -223.903794) (xy 112.883442 -224.258632) (xy 112.891316 -224.280476)
			(xy 112.89989 -224.306896) (xy 112.90909 -224.36167) (xy 112.909604 -224.389442) (xy 113.190528 -224.389442)
			(xy 113.191036 -224.363555) (xy 113.199135 -224.312417) (xy 113.215134 -224.263177) (xy 113.23864 -224.217045)
			(xy 113.269072 -224.175158) (xy 113.305682 -224.138548) (xy 113.347569 -224.108116) (xy 113.393701 -224.08461)
			(xy 113.442941 -224.068611) (xy 113.494079 -224.060512) (xy 113.545853 -224.060512) (xy 113.596991 -224.068611)
			(xy 113.646231 -224.08461) (xy 113.692363 -224.108116) (xy 113.73425 -224.138548) (xy 113.77086 -224.175158)
			(xy 113.801292 -224.217045) (xy 113.824798 -224.263177) (xy 113.840797 -224.312417) (xy 113.848896 -224.363555)
			(xy 113.849404 -224.389442) (xy 113.84886 -224.417149) (xy 113.839674 -224.471796) (xy 113.831116 -224.498154)
			(xy 113.823242 -224.520252) (xy 114.02822 -224.87509) (xy 114.05108 -224.879408) (xy 114.075909 -224.884542)
			(xy 114.123688 -224.901501) (xy 114.168308 -224.925578) (xy 114.208714 -224.956202) (xy 114.243954 -224.992654)
			(xy 114.273197 -225.034071) (xy 114.295752 -225.079478) (xy 114.311088 -225.127804) (xy 114.318843 -225.177908)
			(xy 114.319304 -225.203258) (xy 114.318796 -225.229165) (xy 114.31069 -225.280342) (xy 114.294678 -225.329621)
			(xy 114.271155 -225.375788) (xy 114.240699 -225.417707) (xy 114.204061 -225.454345) (xy 114.162142 -225.484801)
			(xy 114.115975 -225.508324) (xy 114.066696 -225.524336) (xy 114.015519 -225.532442) (xy 113.963705 -225.532442)
			(xy 113.912528 -225.524336) (xy 113.863249 -225.508324) (xy 113.817082 -225.484801) (xy 113.775163 -225.454345)
			(xy 113.738525 -225.417707) (xy 113.708069 -225.375788) (xy 113.684546 -225.329621) (xy 113.668534 -225.280342)
			(xy 113.660428 -225.229165) (xy 113.65992 -225.203258) (xy 113.660527 -225.175541) (xy 113.669842 -225.120895)
			(xy 113.678462 -225.094546) (xy 113.686336 -225.072448) (xy 113.481358 -224.71761) (xy 113.458498 -224.713292)
			(xy 113.433685 -224.708145) (xy 113.385943 -224.691153) (xy 113.341363 -224.667056) (xy 113.300996 -224.63642)
			(xy 113.265793 -224.599968) (xy 113.236582 -224.558558) (xy 113.214052 -224.513166) (xy 113.198734 -224.46486)
			(xy 113.190988 -224.41478) (xy 113.190528 -224.389442) (xy 112.909604 -224.389442) (xy 112.909096 -224.415329)
			(xy 112.900997 -224.466467) (xy 112.884998 -224.515707) (xy 112.861492 -224.561839) (xy 112.83106 -224.603726)
			(xy 112.79445 -224.640336) (xy 112.752563 -224.670768) (xy 112.706431 -224.694274) (xy 112.657191 -224.710273)
			(xy 112.606053 -224.718372) (xy 112.554279 -224.718372) (xy 112.503141 -224.710273) (xy 112.453901 -224.694274)
			(xy 112.407769 -224.670768) (xy 112.365882 -224.640336) (xy 112.329272 -224.603726) (xy 112.29884 -224.561839)
			(xy 112.275334 -224.515707) (xy 112.259335 -224.466467) (xy 112.251236 -224.415329) (xy 112.250728 -224.389442)
			(xy 111.969804 -224.389442) (xy 111.96926 -224.417149) (xy 111.960074 -224.471796) (xy 111.951516 -224.498154)
			(xy 111.943642 -224.520252) (xy 112.14862 -224.87509) (xy 112.17148 -224.879408) (xy 112.196309 -224.884542)
			(xy 112.244088 -224.901501) (xy 112.288708 -224.925578) (xy 112.329114 -224.956202) (xy 112.364354 -224.992654)
			(xy 112.393597 -225.034071) (xy 112.416152 -225.079478) (xy 112.431488 -225.127804) (xy 112.439243 -225.177908)
			(xy 112.439704 -225.203258) (xy 112.439196 -225.229165) (xy 112.43109 -225.280342) (xy 112.415078 -225.329621)
			(xy 112.391555 -225.375788) (xy 112.361099 -225.417707) (xy 112.324461 -225.454345) (xy 112.282542 -225.484801)
			(xy 112.236375 -225.508324) (xy 112.187096 -225.524336) (xy 112.135919 -225.532442) (xy 112.084105 -225.532442)
			(xy 112.032928 -225.524336) (xy 111.983649 -225.508324) (xy 111.937482 -225.484801) (xy 111.895563 -225.454345)
			(xy 111.858925 -225.417707) (xy 111.828469 -225.375788) (xy 111.804946 -225.329621) (xy 111.788934 -225.280342)
			(xy 111.780828 -225.229165) (xy 111.78032 -225.203258) (xy 111.780927 -225.175541) (xy 111.790242 -225.120895)
			(xy 111.798862 -225.094546) (xy 111.806736 -225.072448) (xy 111.601758 -224.71761) (xy 111.578898 -224.713292)
			(xy 111.554085 -224.708145) (xy 111.506343 -224.691153) (xy 111.461763 -224.667056) (xy 111.421396 -224.63642)
			(xy 111.386193 -224.599968) (xy 111.356982 -224.558558) (xy 111.334452 -224.513166) (xy 111.319134 -224.46486)
			(xy 111.311388 -224.41478) (xy 111.310928 -224.389442) (xy 111.030004 -224.389442) (xy 111.029496 -224.415329)
			(xy 111.021397 -224.466467) (xy 111.005398 -224.515707) (xy 110.981892 -224.561839) (xy 110.95146 -224.603726)
			(xy 110.91485 -224.640336) (xy 110.872963 -224.670768) (xy 110.826831 -224.694274) (xy 110.777591 -224.710273)
			(xy 110.726453 -224.718372) (xy 110.674679 -224.718372) (xy 110.623541 -224.710273) (xy 110.574301 -224.694274)
			(xy 110.528169 -224.670768) (xy 110.486282 -224.640336) (xy 110.449672 -224.603726) (xy 110.41924 -224.561839)
			(xy 110.395734 -224.515707) (xy 110.379735 -224.466467) (xy 110.371636 -224.415329) (xy 110.371128 -224.389442)
			(xy 110.090204 -224.389442) (xy 110.08966 -224.417149) (xy 110.080474 -224.471796) (xy 110.071916 -224.498154)
			(xy 110.064042 -224.520252) (xy 110.26902 -224.87509) (xy 110.29188 -224.879408) (xy 110.316709 -224.884542)
			(xy 110.364488 -224.901501) (xy 110.409108 -224.925578) (xy 110.449514 -224.956202) (xy 110.484754 -224.992654)
			(xy 110.513997 -225.034071) (xy 110.536552 -225.079478) (xy 110.551888 -225.127804) (xy 110.559643 -225.177908)
			(xy 110.560104 -225.203258) (xy 110.559596 -225.229165) (xy 110.55149 -225.280342) (xy 110.535478 -225.329621)
			(xy 110.511955 -225.375788) (xy 110.481499 -225.417707) (xy 110.444861 -225.454345) (xy 110.402942 -225.484801)
			(xy 110.356775 -225.508324) (xy 110.307496 -225.524336) (xy 110.256319 -225.532442) (xy 110.204505 -225.532442)
			(xy 110.153328 -225.524336) (xy 110.104049 -225.508324) (xy 110.057882 -225.484801) (xy 110.015963 -225.454345)
			(xy 109.979325 -225.417707) (xy 109.948869 -225.375788) (xy 109.925346 -225.329621) (xy 109.909334 -225.280342)
			(xy 109.901228 -225.229165) (xy 109.90072 -225.203258) (xy 109.901327 -225.175541) (xy 109.910642 -225.120895)
			(xy 109.919262 -225.094546) (xy 109.927136 -225.072448) (xy 109.722158 -224.71761) (xy 109.699298 -224.713292)
			(xy 109.674485 -224.708145) (xy 109.626743 -224.691153) (xy 109.582163 -224.667056) (xy 109.541796 -224.63642)
			(xy 109.506593 -224.599968) (xy 109.477382 -224.558558) (xy 109.454852 -224.513166) (xy 109.439534 -224.46486)
			(xy 109.431788 -224.41478) (xy 109.431328 -224.389442) (xy 109.150404 -224.389442) (xy 109.149896 -224.415329)
			(xy 109.141797 -224.466467) (xy 109.125798 -224.515707) (xy 109.102292 -224.561839) (xy 109.07186 -224.603726)
			(xy 109.03525 -224.640336) (xy 108.993363 -224.670768) (xy 108.947231 -224.694274) (xy 108.897991 -224.710273)
			(xy 108.846853 -224.718372) (xy 108.795079 -224.718372) (xy 108.743941 -224.710273) (xy 108.694701 -224.694274)
			(xy 108.648569 -224.670768) (xy 108.606682 -224.640336) (xy 108.570072 -224.603726) (xy 108.53964 -224.561839)
			(xy 108.516134 -224.515707) (xy 108.500135 -224.466467) (xy 108.492036 -224.415329) (xy 108.491528 -224.389442)
			(xy 108.210604 -224.389442) (xy 108.21006 -224.417149) (xy 108.200874 -224.471796) (xy 108.192316 -224.498154)
			(xy 108.184442 -224.520252) (xy 108.38942 -224.87509) (xy 108.41228 -224.879408) (xy 108.437109 -224.884542)
			(xy 108.484888 -224.901501) (xy 108.529508 -224.925578) (xy 108.569914 -224.956202) (xy 108.605154 -224.992654)
			(xy 108.634397 -225.034071) (xy 108.656952 -225.079478) (xy 108.672288 -225.127804) (xy 108.680043 -225.177908)
			(xy 108.680504 -225.203258) (xy 108.679996 -225.229165) (xy 108.67189 -225.280342) (xy 108.655878 -225.329621)
			(xy 108.632355 -225.375788) (xy 108.601899 -225.417707) (xy 108.565261 -225.454345) (xy 108.523342 -225.484801)
			(xy 108.477175 -225.508324) (xy 108.427896 -225.524336) (xy 108.376719 -225.532442) (xy 108.324905 -225.532442)
			(xy 108.273728 -225.524336) (xy 108.224449 -225.508324) (xy 108.178282 -225.484801) (xy 108.136363 -225.454345)
			(xy 108.099725 -225.417707) (xy 108.069269 -225.375788) (xy 108.045746 -225.329621) (xy 108.029734 -225.280342)
			(xy 108.021628 -225.229165) (xy 108.02112 -225.203258) (xy 108.021727 -225.175541) (xy 108.031042 -225.120895)
			(xy 108.039662 -225.094546) (xy 108.047536 -225.072448) (xy 107.842558 -224.71761) (xy 107.819698 -224.713292)
			(xy 107.794885 -224.708145) (xy 107.747143 -224.691153) (xy 107.702563 -224.667056) (xy 107.662196 -224.63642)
			(xy 107.626993 -224.599968) (xy 107.597782 -224.558558) (xy 107.575252 -224.513166) (xy 107.559934 -224.46486)
			(xy 107.552188 -224.41478) (xy 107.551728 -224.389442) (xy 107.270804 -224.389442) (xy 107.270296 -224.415329)
			(xy 107.262197 -224.466467) (xy 107.246198 -224.515707) (xy 107.222692 -224.561839) (xy 107.19226 -224.603726)
			(xy 107.15565 -224.640336) (xy 107.113763 -224.670768) (xy 107.067631 -224.694274) (xy 107.018391 -224.710273)
			(xy 106.967253 -224.718372) (xy 106.915479 -224.718372) (xy 106.864341 -224.710273) (xy 106.815101 -224.694274)
			(xy 106.768969 -224.670768) (xy 106.727082 -224.640336) (xy 106.690472 -224.603726) (xy 106.66004 -224.561839)
			(xy 106.636534 -224.515707) (xy 106.620535 -224.466467) (xy 106.612436 -224.415329) (xy 106.611928 -224.389442)
			(xy 106.331004 -224.389442) (xy 106.33046 -224.417149) (xy 106.321274 -224.471796) (xy 106.312716 -224.498154)
			(xy 106.304842 -224.520252) (xy 106.50982 -224.87509) (xy 106.53268 -224.879408) (xy 106.557509 -224.884542)
			(xy 106.605288 -224.901501) (xy 106.649908 -224.925578) (xy 106.690314 -224.956202) (xy 106.725554 -224.992654)
			(xy 106.754797 -225.034071) (xy 106.777352 -225.079478) (xy 106.792688 -225.127804) (xy 106.800443 -225.177908)
			(xy 106.800904 -225.203258) (xy 106.800396 -225.229165) (xy 106.79229 -225.280342) (xy 106.776278 -225.329621)
			(xy 106.752755 -225.375788) (xy 106.722299 -225.417707) (xy 106.685661 -225.454345) (xy 106.643742 -225.484801)
			(xy 106.597575 -225.508324) (xy 106.548296 -225.524336) (xy 106.497119 -225.532442) (xy 106.445305 -225.532442)
			(xy 106.394128 -225.524336) (xy 106.344849 -225.508324) (xy 106.298682 -225.484801) (xy 106.256763 -225.454345)
			(xy 106.220125 -225.417707) (xy 106.189669 -225.375788) (xy 106.166146 -225.329621) (xy 106.150134 -225.280342)
			(xy 106.142028 -225.229165) (xy 106.14152 -225.203258) (xy 106.142127 -225.175541) (xy 106.151442 -225.120895)
			(xy 106.160062 -225.094546) (xy 106.167936 -225.072448) (xy 105.962958 -224.71761) (xy 105.940098 -224.713292)
			(xy 105.915285 -224.708145) (xy 105.867543 -224.691153) (xy 105.822963 -224.667056) (xy 105.782596 -224.63642)
			(xy 105.747393 -224.599968) (xy 105.718182 -224.558558) (xy 105.695652 -224.513166) (xy 105.680334 -224.46486)
			(xy 105.672588 -224.41478) (xy 105.672128 -224.389442) (xy 105.391204 -224.389442) (xy 105.390696 -224.415329)
			(xy 105.382597 -224.466467) (xy 105.366598 -224.515707) (xy 105.343092 -224.561839) (xy 105.31266 -224.603726)
			(xy 105.27605 -224.640336) (xy 105.234163 -224.670768) (xy 105.188031 -224.694274) (xy 105.138791 -224.710273)
			(xy 105.087653 -224.718372) (xy 105.035879 -224.718372) (xy 104.984741 -224.710273) (xy 104.935501 -224.694274)
			(xy 104.889369 -224.670768) (xy 104.847482 -224.640336) (xy 104.810872 -224.603726) (xy 104.78044 -224.561839)
			(xy 104.756934 -224.515707) (xy 104.740935 -224.466467) (xy 104.732836 -224.415329) (xy 104.732328 -224.389442)
			(xy 104.451404 -224.389442) (xy 104.45086 -224.417149) (xy 104.441674 -224.471796) (xy 104.433116 -224.498154)
			(xy 104.425242 -224.520252) (xy 104.63022 -224.87509) (xy 104.65308 -224.879408) (xy 104.677909 -224.884542)
			(xy 104.725688 -224.901501) (xy 104.770308 -224.925578) (xy 104.810714 -224.956202) (xy 104.845954 -224.992654)
			(xy 104.875197 -225.034071) (xy 104.897752 -225.079478) (xy 104.913088 -225.127804) (xy 104.920843 -225.177908)
			(xy 104.921304 -225.203258) (xy 104.920796 -225.229165) (xy 104.91269 -225.280342) (xy 104.896678 -225.329621)
			(xy 104.873155 -225.375788) (xy 104.842699 -225.417707) (xy 104.806061 -225.454345) (xy 104.764142 -225.484801)
			(xy 104.717975 -225.508324) (xy 104.668696 -225.524336) (xy 104.617519 -225.532442) (xy 104.565705 -225.532442)
			(xy 104.514528 -225.524336) (xy 104.465249 -225.508324) (xy 104.419082 -225.484801) (xy 104.377163 -225.454345)
			(xy 104.340525 -225.417707) (xy 104.310069 -225.375788) (xy 104.286546 -225.329621) (xy 104.270534 -225.280342)
			(xy 104.262428 -225.229165) (xy 104.26192 -225.203258) (xy 104.262527 -225.175541) (xy 104.271842 -225.120895)
			(xy 104.280462 -225.094546) (xy 104.288336 -225.072448) (xy 104.083358 -224.71761) (xy 104.060498 -224.713292)
			(xy 104.035685 -224.708145) (xy 103.987943 -224.691153) (xy 103.943363 -224.667056) (xy 103.902996 -224.63642)
			(xy 103.867793 -224.599968) (xy 103.838582 -224.558558) (xy 103.816052 -224.513166) (xy 103.800734 -224.46486)
			(xy 103.792988 -224.41478) (xy 103.792528 -224.389442) (xy 103.511604 -224.389442) (xy 103.511093 -224.415326)
			(xy 103.502988 -224.466457) (xy 103.486985 -224.515689) (xy 103.463477 -224.561813) (xy 103.433043 -224.603691)
			(xy 103.396433 -224.640293) (xy 103.354548 -224.670717) (xy 103.308419 -224.694214) (xy 103.259183 -224.710206)
			(xy 103.20805 -224.718299) (xy 103.182166 -224.71888) (xy 103.15432 -224.718321) (xy 103.099415 -224.709003)
			(xy 103.072946 -224.700338) (xy 103.059699 -224.6962) (xy 103.032016 -224.694428) (xy 103.004878 -224.700177)
			(xy 102.980292 -224.713023) (xy 102.960074 -224.732017) (xy 102.945719 -224.755753) (xy 102.938287 -224.782479)
			(xy 102.937818 -224.79635) (xy 102.937818 -224.963228) (xy 102.957067 -224.982044) (xy 102.989786 -225.024781)
			(xy 103.015124 -225.072268) (xy 103.032408 -225.123241) (xy 103.041178 -225.176346) (xy 103.041704 -225.203258)
			(xy 103.041151 -225.230168) (xy 103.032373 -225.283268) (xy 103.015093 -225.334239) (xy 102.989768 -225.381729)
			(xy 102.95707 -225.424479) (xy 102.937818 -225.443288) (xy 102.937818 -226.592892) (xy 102.956808 -226.611628)
			(xy 102.989061 -226.654116) (xy 103.014022 -226.701259) (xy 103.031035 -226.751816) (xy 103.039652 -226.804459)
			(xy 103.039647 -226.857802) (xy 103.03102 -226.910443) (xy 103.013998 -226.960997) (xy 102.989028 -227.008135)
			(xy 102.956767 -227.050617) (xy 102.937818 -227.069396) (xy 102.937818 -228.220778) (xy 102.956809 -228.239514)
			(xy 102.989064 -228.282002) (xy 103.014028 -228.329146) (xy 103.031043 -228.379704) (xy 103.039662 -228.432348)
			(xy 103.039658 -228.485693) (xy 103.031033 -228.538336) (xy 103.014011 -228.588892) (xy 102.989042 -228.636033)
			(xy 102.956781 -228.678517) (xy 102.937818 -228.697282) (xy 102.937818 -228.98735) (xy 102.937202 -229.012305)
			(xy 102.927457 -229.061254) (xy 102.90835 -229.107362) (xy 102.880617 -229.148857) (xy 102.863396 -229.166928)
			(xy 102.074726 -229.955598) (xy 102.084378 -229.985316) (xy 102.091884 -230.009976) (xy 102.099921 -230.060889)
			(xy 102.10038 -230.086662) (xy 102.099904 -230.112454) (xy 102.09184 -230.163404) (xy 102.075904 -230.212464)
			(xy 102.05249 -230.258428) (xy 102.022173 -230.300163) (xy 101.985701 -230.336641) (xy 101.943971 -230.366964)
			(xy 101.898011 -230.390385) (xy 101.848952 -230.406328) (xy 101.798004 -230.4144) (xy 101.772212 -230.41483)
			(xy 101.746443 -230.414325) (xy 101.695536 -230.406291) (xy 101.670866 -230.398828) (xy 101.641148 -230.389176)
			(xy 100.199698 -231.830626) (xy 100.195888 -231.840024) (xy 100.18557 -231.863696) (xy 100.158596 -231.907728)
			(xy 100.12506 -231.946993) (xy 100.08579 -231.980523) (xy 100.041754 -232.007491) (xy 100.018088 -232.017824)
			(xy 100.00869 -232.021634) (xy 99.692714 -232.33761) (xy 99.711002 -232.370884) (xy 99.723639 -232.395188)
			(xy 99.741535 -232.446956) (xy 99.750595 -232.500976) (xy 99.751134 -232.528364) (xy 99.750657 -232.554155)
			(xy 99.742592 -232.605101) (xy 99.726656 -232.654158) (xy 99.703241 -232.700118) (xy 99.672924 -232.741849)
			(xy 99.636451 -232.778322) (xy 99.59472 -232.80864) (xy 99.54876 -232.832056) (xy 99.499703 -232.847992)
			(xy 99.448756 -232.856057) (xy 99.422966 -232.856532) (xy 99.395578 -232.856004) (xy 99.341556 -232.846946)
			(xy 99.28979 -232.829039) (xy 99.265486 -232.8164) (xy 99.232212 -232.798112) (xy 97.872042 -234.158282)
			(xy 97.870772 -234.177332) (xy 97.868559 -234.203542) (xy 97.856839 -234.254816) (xy 97.83709 -234.303563)
			(xy 97.809815 -234.348534) (xy 97.775714 -234.388578) (xy 97.735662 -234.422667) (xy 97.690683 -234.44993)
			(xy 97.64193 -234.469666) (xy 97.590653 -234.481371) (xy 97.564448 -234.483656) (xy 97.545398 -234.484926)
			(xy 96.986598 -235.043726) (xy 96.986598 -253.737618) (xy 96.999628 -253.757945) (xy 97.020226 -253.801613)
			(xy 97.034209 -253.847826) (xy 97.041274 -253.895589) (xy 97.04127 -253.943871) (xy 97.034196 -253.991632)
			(xy 97.020205 -254.037843) (xy 96.999598 -254.081507) (xy 96.986598 -254.101854) (xy 96.986598 -255.365504)
			(xy 96.999629 -255.385831) (xy 97.020229 -255.429499) (xy 97.034214 -255.475713) (xy 97.041281 -255.523477)
			(xy 97.041278 -255.57176) (xy 97.034206 -255.619523) (xy 97.020216 -255.665735) (xy 96.999611 -255.709401)
			(xy 96.986598 -255.72974) (xy 96.986598 -256.993136) (xy 96.999634 -257.013463) (xy 97.020244 -257.057133)
			(xy 97.034238 -257.10335) (xy 97.041314 -257.151117) (xy 97.04132 -257.199406) (xy 97.034255 -257.247176)
			(xy 97.020272 -257.293395) (xy 96.999672 -257.33707) (xy 96.986598 -257.357372) (xy 96.986598 -258.621022)
			(xy 96.999628 -258.641349) (xy 97.020225 -258.685017) (xy 97.034207 -258.73123) (xy 97.041272 -258.778992)
			(xy 97.041267 -258.827274) (xy 97.034193 -258.875035) (xy 97.020202 -258.921245) (xy 96.999595 -258.964909)
			(xy 96.986598 -258.985258) (xy 96.986598 -260.249416) (xy 96.99952 -260.269679) (xy 97.019939 -260.313183)
			(xy 97.033801 -260.359199) (xy 97.040808 -260.406743) (xy 97.041208 -260.430772) (xy 97.0407 -260.44906)
			(xy 97.03943 -260.471666) (xy 97.391474 -260.82371) (xy 102.427786 -260.82371) (xy 102.567232 -260.684264)
			(xy 102.571042 -260.675882) (xy 102.581151 -260.654793) (xy 102.606454 -260.615463) (xy 102.637083 -260.580123)
			(xy 102.672418 -260.549487) (xy 102.711744 -260.524177) (xy 102.73284 -260.514084) (xy 102.741222 -260.510274)
			(xy 102.837742 -260.413754) (xy 102.837742 -260.025896) (xy 102.79761 -260.01726) (xy 102.772051 -260.01125)
			(xy 102.723126 -259.992206) (xy 102.677859 -259.965613) (xy 102.637404 -259.932149) (xy 102.602796 -259.892669)
			(xy 102.574918 -259.848182) (xy 102.55448 -259.799822) (xy 102.542006 -259.748825) (xy 102.537813 -259.696491)
			(xy 102.542009 -259.644158) (xy 102.554486 -259.593161) (xy 102.574926 -259.544802) (xy 102.602807 -259.500316)
			(xy 102.637417 -259.460839) (xy 102.677873 -259.427377) (xy 102.723142 -259.400786) (xy 102.772068 -259.381745)
			(xy 102.79761 -259.375656) (xy 102.837742 -259.36702) (xy 102.837742 -258.564126) (xy 102.619302 -258.345686)
			(xy 102.602037 -258.327647) (xy 102.57427 -258.286155) (xy 102.555148 -258.240037) (xy 102.545408 -258.191071)
			(xy 102.54488 -258.166108) (xy 102.54488 -257.42773) (xy 102.545498 -257.402776) (xy 102.555247 -257.353829)
			(xy 102.574355 -257.307723) (xy 102.60209 -257.266231) (xy 102.619302 -257.248152) (xy 102.837742 -257.029712)
			(xy 102.837742 -256.135124) (xy 102.805738 -256.122424) (xy 102.783232 -256.112918) (xy 102.74108 -256.088222)
			(xy 102.70305 -256.057556) (xy 102.669981 -256.021597) (xy 102.642601 -255.981137) (xy 102.621515 -255.937068)
			(xy 102.607188 -255.890363) (xy 102.599935 -255.842051) (xy 102.59949 -255.817624) (xy 102.599937 -255.792916)
			(xy 102.607348 -255.744058) (xy 102.622007 -255.696866) (xy 102.643581 -255.652408) (xy 102.671582 -255.611691)
			(xy 102.688136 -255.593342) (xy 102.698182 -255.581835) (xy 102.711503 -255.554362) (xy 102.716117 -255.524181)
			(xy 102.71161 -255.493983) (xy 102.698385 -255.466463) (xy 102.68839 -255.454912) (xy 102.671952 -255.436601)
			(xy 102.644188 -255.395976) (xy 102.622801 -255.351661) (xy 102.608272 -255.304649) (xy 102.600925 -255.255995)
			(xy 102.600506 -255.231392) (xy 102.600944 -255.207022) (xy 102.608144 -255.158817) (xy 102.622397 -255.112207)
			(xy 102.643391 -255.068221) (xy 102.670663 -255.027825) (xy 102.703612 -254.99191) (xy 102.741514 -254.961266)
			(xy 102.783533 -254.936568) (xy 102.805992 -254.9271) (xy 102.837742 -254.914146) (xy 102.837742 -253.123954)
			(xy 102.80142 -253.113286) (xy 102.77642 -253.105232) (xy 102.72917 -253.0823) (xy 102.686171 -253.052142)
			(xy 102.648518 -253.015527) (xy 102.617171 -252.973387) (xy 102.592928 -252.926797) (xy 102.576408 -252.876942)
			(xy 102.56803 -252.825094) (xy 102.567486 -252.798834) (xy 102.567946 -252.774306) (xy 102.575253 -252.725796)
			(xy 102.589695 -252.678914) (xy 102.610949 -252.6347) (xy 102.638544 -252.594141) (xy 102.654862 -252.575822)
			(xy 102.664806 -252.564276) (xy 102.678027 -252.536839) (xy 102.682573 -252.506725) (xy 102.678042 -252.476609)
			(xy 102.664835 -252.449166) (xy 102.654862 -252.437646) (xy 102.638527 -252.41934) (xy 102.610919 -252.378785)
			(xy 102.589662 -252.33457) (xy 102.57523 -252.28768) (xy 102.567945 -252.239164) (xy 102.567486 -252.214634)
			(xy 102.568 -252.188371) (xy 102.57636 -252.136514) (xy 102.592873 -252.086651) (xy 102.617116 -252.040054)
			(xy 102.648471 -251.997913) (xy 102.686138 -251.961304) (xy 102.729154 -251.931161) (xy 102.776422 -251.908254)
			(xy 102.80142 -251.900182) (xy 102.837742 -251.889514) (xy 102.837742 -248.50471) (xy 102.838322 -248.479753)
			(xy 102.848077 -248.430802) (xy 102.867195 -248.384695) (xy 102.894941 -248.343203) (xy 102.912164 -248.325132)
			(xy 103.394764 -247.842532) (xy 103.412806 -247.825275) (xy 103.454301 -247.797524) (xy 103.500419 -247.778416)
			(xy 103.549382 -247.768689) (xy 103.574342 -247.76811) (xy 104.383586 -247.76811) (xy 104.869742 -247.281954)
			(xy 104.869742 -246.298466) (xy 104.688386 -246.11711) (xy 103.574342 -246.11711) (xy 103.549388 -246.116493)
			(xy 103.500439 -246.106746) (xy 103.454333 -246.087638) (xy 103.412839 -246.059904) (xy 103.394764 -246.042688)
			(xy 103.002842 -245.650766) (xy 102.97541 -245.657116) (xy 102.957065 -245.661124) (xy 102.919763 -245.665452)
			(xy 102.900988 -245.665752) (xy 102.875199 -245.665272) (xy 102.824258 -245.657201) (xy 102.775205 -245.641261)
			(xy 102.729251 -245.617844) (xy 102.687525 -245.587526) (xy 102.651056 -245.551054) (xy 102.620741 -245.509325)
			(xy 102.597328 -245.463369) (xy 102.581392 -245.414315) (xy 102.573326 -245.363373) (xy 102.57282 -245.337584)
			(xy 102.573277 -245.313055) (xy 102.580578 -245.264542) (xy 102.595015 -245.217656) (xy 102.616266 -245.173439)
			(xy 102.64386 -245.132875) (xy 102.660196 -245.114572) (xy 102.670187 -245.103062) (xy 102.68341 -245.075614)
			(xy 102.68795 -245.045488) (xy 102.683403 -245.015363) (xy 102.670174 -244.987919) (xy 102.660196 -244.976396)
			(xy 102.643861 -244.95809) (xy 102.616252 -244.917535) (xy 102.594993 -244.873319) (xy 102.580556 -244.826431)
			(xy 102.573266 -244.777915) (xy 102.57282 -244.753384) (xy 102.57334 -244.727103) (xy 102.581724 -244.675213)
			(xy 102.598273 -244.625324) (xy 102.622565 -244.578711) (xy 102.653978 -244.536568) (xy 102.691708 -244.499972)
			(xy 102.734791 -244.469861) (xy 102.75824 -244.457982) (xy 102.786942 -244.444012) (xy 102.786942 -241.235992)
			(xy 102.759002 -241.222022) (xy 102.73611 -241.209916) (xy 102.694124 -241.179608) (xy 102.657412 -241.143089)
			(xy 102.626885 -241.101262) (xy 102.603298 -241.055164) (xy 102.587235 -241.005936) (xy 102.579094 -240.954797)
			(xy 102.578662 -240.928906) (xy 102.579117 -240.904376) (xy 102.586414 -240.855861) (xy 102.600847 -240.808971)
			(xy 102.622093 -240.764749) (xy 102.649682 -240.72418) (xy 102.666038 -240.705894) (xy 102.676029 -240.694382)
			(xy 102.689252 -240.666932) (xy 102.693796 -240.636804) (xy 102.689255 -240.606676) (xy 102.676034 -240.579225)
			(xy 102.666038 -240.567718) (xy 102.6497 -240.549413) (xy 102.622085 -240.50886) (xy 102.60082 -240.464645)
			(xy 102.586378 -240.417755) (xy 102.579083 -240.369238) (xy 102.578662 -240.344706) (xy 102.579148 -240.318817)
			(xy 102.587274 -240.26768) (xy 102.603325 -240.218453) (xy 102.626904 -240.172354) (xy 102.657426 -240.130528)
			(xy 102.694134 -240.094011) (xy 102.736119 -240.063708) (xy 102.759002 -240.05159) (xy 102.786942 -240.03762)
			(xy 102.786942 -239.5982) (xy 102.765042 -239.585753) (xy 102.724972 -239.555232) (xy 102.690029 -239.518953)
			(xy 102.661033 -239.477765) (xy 102.638664 -239.432634) (xy 102.623445 -239.384618) (xy 102.615733 -239.334841)
			(xy 102.615238 -239.309656) (xy 102.615747 -239.283871) (xy 102.623821 -239.232936) (xy 102.639762 -239.183892)
			(xy 102.663179 -239.137944) (xy 102.693495 -239.096226) (xy 102.729964 -239.059763) (xy 102.771687 -239.029453)
			(xy 102.817638 -239.006043) (xy 102.866685 -238.990109) (xy 102.917621 -238.982043) (xy 102.943406 -238.981488)
			(xy 102.964779 -238.981814) (xy 103.007166 -238.987334) (xy 103.048476 -238.998318) (xy 103.068374 -239.006126)
			(xy 103.099616 -239.01908) (xy 104.207564 -237.911132) (xy 104.225606 -237.893875) (xy 104.267101 -237.866124)
			(xy 104.313219 -237.847016) (xy 104.362182 -237.837289) (xy 104.387142 -237.83671) (xy 108.350558 -237.83671)
			(xy 108.35894 -237.796324) (xy 108.364842 -237.770617) (xy 108.383733 -237.721375) (xy 108.410256 -237.675787)
			(xy 108.443727 -237.635028) (xy 108.483285 -237.600145) (xy 108.527912 -237.572036) (xy 108.57646 -237.551426)
			(xy 108.627678 -237.538843) (xy 108.68025 -237.534613) (xy 108.732822 -237.538843) (xy 108.78404 -237.551426)
			(xy 108.832588 -237.572036) (xy 108.877215 -237.600145) (xy 108.916773 -237.635028) (xy 108.950244 -237.675787)
			(xy 108.976767 -237.721375) (xy 108.995658 -237.770617) (xy 109.00156 -237.796324) (xy 109.009942 -237.83671)
			(xy 115.334542 -237.83671) (xy 115.359497 -237.837326) (xy 115.408446 -237.84707) (xy 115.454554 -237.866177)
			(xy 115.496048 -237.893912) (xy 115.51412 -237.911132) (xy 116.02212 -238.419132) (xy 116.039382 -238.437172)
			(xy 116.067144 -238.478665) (xy 116.086261 -238.524783) (xy 116.095996 -238.573748) (xy 116.096542 -238.59871)
			(xy 116.096542 -239.915954) (xy 117.852698 -241.67211) (xy 120.465342 -241.67211) (xy 120.490297 -241.672726)
			(xy 120.539246 -241.68247) (xy 120.585354 -241.701577) (xy 120.626848 -241.729312) (xy 120.64492 -241.746532)
			(xy 121.20372 -242.305332) (xy 121.220982 -242.323372) (xy 121.248744 -242.364865) (xy 121.267861 -242.410983)
			(xy 121.277596 -242.459948) (xy 121.278142 -242.48491) (xy 121.278142 -243.32311) (xy 121.27757 -243.34807)
			(xy 121.267827 -243.397029) (xy 121.248719 -243.443146) (xy 121.220979 -243.484648) (xy 121.20372 -243.502688)
			(xy 120.92432 -243.782088) (xy 120.906279 -243.799348) (xy 120.864786 -243.827105) (xy 120.818668 -243.846216)
			(xy 120.769703 -243.855944) (xy 120.744742 -243.85651) (xy 120.189498 -243.85651) (xy 118.872 -245.174008)
			(xy 118.872 -246.730012) (xy 120.926098 -248.78411) (xy 120.950736 -248.781316) (xy 120.960289 -248.780257)
			(xy 120.979479 -248.779115) (xy 120.98909 -248.77903) (xy 121.01488 -248.779509) (xy 121.065826 -248.787576)
			(xy 121.114882 -248.803514) (xy 121.160841 -248.82693) (xy 121.202571 -248.857247) (xy 121.239045 -248.89372)
			(xy 121.269364 -248.935449) (xy 121.292781 -248.981407) (xy 121.308721 -249.030462) (xy 121.316791 -249.081408)
			(xy 121.317258 -249.107198) (xy 121.316996 -249.124152) (xy 121.313432 -249.157873) (xy 121.310146 -249.174508)
			(xy 121.323928 -249.195788) (xy 121.343644 -249.242488) (xy 121.353731 -249.292165) (xy 121.354342 -249.31751)
			(xy 121.354342 -260.087364) (xy 121.354237 -260.097633) (xy 121.352585 -260.118105) (xy 121.35104 -260.128258)
			(xy 121.346722 -260.153912) (xy 121.571258 -260.378194) (xy 121.582577 -260.390311) (xy 121.599134 -260.419023)
			(xy 121.607742 -260.451031) (xy 121.608342 -260.467602) (xy 121.608342 -261.685532)
		)
		(stroke
			(width 0)
			(type solid)
		)
		(fill yes)
		(layer "In9.Cu")
		(net "PVCCD_HV_CPU1")
	)
	(gr_poly
		(pts
			(xy 369.6716 -261.808722) (xy 369.682848 -261.81922) (xy 369.710076 -261.833519) (xy 369.740323 -261.839082)
			(xy 369.770856 -261.835407) (xy 369.798919 -261.822826) (xy 369.810792 -261.81304) (xy 369.828871 -261.797578)
			(xy 369.868653 -261.771494) (xy 369.911785 -261.751429) (xy 369.957363 -261.737805) (xy 370.004431 -261.730907)
			(xy 370.028216 -261.73049) (xy 370.053017 -261.730947) (xy 370.102052 -261.738422) (xy 370.149401 -261.753199)
			(xy 370.193983 -261.774942) (xy 370.214652 -261.788656) (xy 370.781326 -261.788656) (xy 370.801987 -261.77493)
			(xy 370.846574 -261.753195) (xy 370.893925 -261.738424) (xy 370.942961 -261.730953) (xy 370.992563 -261.730953)
			(xy 371.041599 -261.738424) (xy 371.08895 -261.753195) (xy 371.133537 -261.77493) (xy 371.154198 -261.788656)
			(xy 371.72138 -261.788656) (xy 371.742041 -261.77493) (xy 371.786628 -261.753195) (xy 371.833979 -261.738424)
			(xy 371.883015 -261.730953) (xy 371.932617 -261.730953) (xy 371.981653 -261.738424) (xy 372.029004 -261.753195)
			(xy 372.073591 -261.77493) (xy 372.094252 -261.788656) (xy 372.66118 -261.788656) (xy 372.681841 -261.77493)
			(xy 372.726428 -261.753195) (xy 372.773779 -261.738424) (xy 372.822815 -261.730953) (xy 372.872417 -261.730953)
			(xy 372.921453 -261.738424) (xy 372.968804 -261.753195) (xy 373.013391 -261.77493) (xy 373.034052 -261.788656)
			(xy 373.600726 -261.788656) (xy 373.621388 -261.774931) (xy 373.665975 -261.753198) (xy 373.713326 -261.738425)
			(xy 373.762361 -261.730951) (xy 373.787162 -261.73049) (xy 373.787416 -261.73049) (xy 373.810428 -261.730874)
			(xy 373.856 -261.737303) (xy 373.900224 -261.750048) (xy 373.942229 -261.768857) (xy 373.961914 -261.780782)
			(xy 373.97436 -261.788656) (xy 374.043956 -261.788656) (xy 374.928892 -260.90372) (xy 374.928892 -259.80644)
			(xy 374.914698 -259.78554) (xy 374.892216 -259.740299) (xy 374.876929 -259.692148) (xy 374.869197 -259.642224)
			(xy 374.869203 -259.591704) (xy 374.876946 -259.541782) (xy 374.892243 -259.493634) (xy 374.914735 -259.448398)
			(xy 374.928892 -259.427472) (xy 374.928892 -258.178046) (xy 374.914755 -258.157195) (xy 374.892366 -258.112067)
			(xy 374.877143 -258.064047) (xy 374.869442 -258.014263) (xy 374.869446 -257.963888) (xy 374.877154 -257.914105)
			(xy 374.892385 -257.866087) (xy 374.91478 -257.820963) (xy 374.928892 -257.800094) (xy 374.928892 -256.550922)
			(xy 374.914691 -256.530022) (xy 374.892197 -256.484779) (xy 374.876898 -256.436624) (xy 374.869155 -256.386694)
			(xy 374.86915 -256.336168) (xy 374.876884 -256.286236) (xy 374.892174 -256.238079) (xy 374.91466 -256.192831)
			(xy 374.928892 -256.171954) (xy 374.928892 -254.923036) (xy 374.914698 -254.902136) (xy 374.892217 -254.856895)
			(xy 374.876931 -254.808744) (xy 374.869199 -254.75882) (xy 374.869205 -254.708301) (xy 374.876949 -254.658379)
			(xy 374.892247 -254.610232) (xy 374.914739 -254.564996) (xy 374.928892 -254.544068) (xy 374.928892 -249.907552)
			(xy 374.90715 -249.895086) (xy 374.867389 -249.864583) (xy 374.83273 -249.828386) (xy 374.803982 -249.787338)
			(xy 374.781814 -249.742393) (xy 374.766741 -249.694599) (xy 374.759115 -249.645069) (xy 374.759114 -249.594954)
			(xy 374.766736 -249.545423) (xy 374.781805 -249.497628) (xy 374.80397 -249.452682) (xy 374.832716 -249.411632)
			(xy 374.867371 -249.375432) (xy 374.907131 -249.344926) (xy 374.928892 -249.332496) (xy 374.928892 -248.279666)
			(xy 374.907149 -248.2672) (xy 374.867385 -248.236697) (xy 374.832725 -248.200499) (xy 374.803975 -248.15945)
			(xy 374.781805 -248.114504) (xy 374.766731 -248.066709) (xy 374.759104 -248.017176) (xy 374.759101 -247.96706)
			(xy 374.766723 -247.917527) (xy 374.781791 -247.86973) (xy 374.803956 -247.824782) (xy 374.832702 -247.783729)
			(xy 374.867358 -247.747527) (xy 374.907119 -247.71702) (xy 374.928892 -247.70461) (xy 374.928892 -246.652034)
			(xy 374.907152 -246.639568) (xy 374.867393 -246.609066) (xy 374.832737 -246.57287) (xy 374.803991 -246.531822)
			(xy 374.781825 -246.486879) (xy 374.766755 -246.439087) (xy 374.75913 -246.389559) (xy 374.75913 -246.339447)
			(xy 374.766753 -246.289918) (xy 374.781823 -246.242126) (xy 374.803988 -246.197183) (xy 374.832733 -246.156135)
			(xy 374.867388 -246.119938) (xy 374.907147 -246.089435) (xy 374.928892 -246.076978) (xy 374.928892 -245.024148)
			(xy 374.907178 -245.011662) (xy 374.867472 -244.981129) (xy 374.832866 -244.944917) (xy 374.804165 -244.903868)
			(xy 374.782034 -244.858934) (xy 374.766988 -244.81116) (xy 374.759376 -244.761654) (xy 374.759374 -244.711566)
			(xy 374.766984 -244.662059) (xy 374.782027 -244.614283) (xy 374.804155 -244.569348) (xy 374.832854 -244.528298)
			(xy 374.867457 -244.492084) (xy 374.907161 -244.461549) (xy 374.928892 -244.449092) (xy 374.928892 -243.396516)
			(xy 374.907153 -243.384051) (xy 374.867397 -243.353548) (xy 374.832744 -243.317353) (xy 374.804001 -243.276307)
			(xy 374.781837 -243.231365) (xy 374.766768 -243.183575) (xy 374.759145 -243.134049) (xy 374.759146 -243.08394)
			(xy 374.766771 -243.034414) (xy 374.781841 -242.986624) (xy 374.804006 -242.941683) (xy 374.832751 -242.900638)
			(xy 374.867405 -242.864444) (xy 374.907163 -242.833943) (xy 374.928892 -242.82146) (xy 374.928892 -241.76863)
			(xy 374.907152 -241.756164) (xy 374.867394 -241.725662) (xy 374.832738 -241.689466) (xy 374.803993 -241.648419)
			(xy 374.781828 -241.603476) (xy 374.766758 -241.555685) (xy 374.759134 -241.506157) (xy 374.759134 -241.456045)
			(xy 374.766757 -241.406517) (xy 374.781827 -241.358726) (xy 374.803992 -241.313783) (xy 374.832737 -241.272736)
			(xy 374.867392 -241.236539) (xy 374.907151 -241.206037) (xy 374.928892 -241.193574) (xy 374.928892 -240.140744)
			(xy 374.907151 -240.128281) (xy 374.86739 -240.097782) (xy 374.832734 -240.061587) (xy 374.80399 -240.020539)
			(xy 374.781828 -239.975595) (xy 374.766765 -239.927801) (xy 374.759151 -239.878272) (xy 374.758712 -239.853216)
			(xy 374.759191 -239.82807) (xy 374.766862 -239.778366) (xy 374.782026 -239.730415) (xy 374.804328 -239.685338)
			(xy 374.818402 -239.664494) (xy 374.84304 -239.629696) (xy 374.579134 -239.36579) (xy 374.563132 -239.362996)
			(xy 374.538127 -239.358333) (xy 374.489855 -239.342309) (xy 374.444634 -239.319027) (xy 374.403547 -239.289046)
			(xy 374.36758 -239.253083) (xy 374.337593 -239.212) (xy 374.314306 -239.166781) (xy 374.298277 -239.118511)
			(xy 374.293638 -239.093502) (xy 374.290844 -239.0775) (xy 372.907814 -237.69447) (xy 372.875556 -237.709202)
			(xy 372.853847 -237.718814) (xy 372.80835 -237.732379) (xy 372.761372 -237.739235) (xy 372.737634 -237.739682)
			(xy 372.711842 -237.739205) (xy 372.660893 -237.731141) (xy 372.611833 -237.715205) (xy 372.565869 -237.691791)
			(xy 372.524135 -237.661474) (xy 372.487657 -237.625001) (xy 372.457335 -237.583272) (xy 372.433913 -237.537312)
			(xy 372.41797 -237.488254) (xy 372.409898 -237.437306) (xy 372.409466 -237.411514) (xy 372.409904 -237.387776)
			(xy 372.416775 -237.340799) (xy 372.430332 -237.2953) (xy 372.439946 -237.273592) (xy 372.454678 -237.241334)
			(xy 372.08206 -236.868716) (xy 372.078504 -236.86643) (xy 372.055727 -236.84968) (xy 372.015749 -236.809707)
			(xy 371.999002 -236.786928) (xy 371.996716 -236.783372) (xy 370.495068 -235.281724) (xy 370.467128 -235.288582)
			(xy 370.447755 -235.293087) (xy 370.408275 -235.297927) (xy 370.388388 -235.298234) (xy 370.38788 -235.298234)
			(xy 370.362092 -235.297753) (xy 370.311153 -235.289681) (xy 370.262103 -235.27374) (xy 370.21615 -235.250322)
			(xy 370.174428 -235.220004) (xy 370.137961 -235.183531) (xy 370.10765 -235.141803) (xy 370.084239 -235.095847)
			(xy 370.068306 -235.046795) (xy 370.060243 -234.995854) (xy 370.059712 -234.970066) (xy 370.059712 -234.969558)
			(xy 370.060018 -234.949671) (xy 370.064857 -234.910191) (xy 370.069364 -234.890818) (xy 370.076222 -234.862878)
			(xy 368.069114 -232.85577) (xy 368.04727 -232.856532) (xy 368.03838 -232.856532) (xy 368.012592 -232.856051)
			(xy 367.961653 -232.847979) (xy 367.912603 -232.832038) (xy 367.866651 -232.80862) (xy 367.824928 -232.778302)
			(xy 367.788462 -232.741829) (xy 367.758151 -232.700101) (xy 367.73474 -232.654145) (xy 367.718808 -232.605093)
			(xy 367.710745 -232.554152) (xy 367.710212 -232.528364) (xy 367.710212 -232.519474) (xy 367.710974 -232.49763)
			(xy 366.369092 -231.155748) (xy 366.334802 -231.177592) (xy 366.314998 -231.189674) (xy 366.27271 -231.208752)
			(xy 366.228159 -231.221687) (xy 366.18223 -231.228223) (xy 366.159034 -231.228646) (xy 366.133243 -231.228169)
			(xy 366.082296 -231.220105) (xy 366.033238 -231.204168) (xy 365.987277 -231.180753) (xy 365.945546 -231.150436)
			(xy 365.909072 -231.113963) (xy 365.878753 -231.072233) (xy 365.855336 -231.026273) (xy 365.839398 -230.977216)
			(xy 365.831332 -230.926269) (xy 365.830866 -230.900478) (xy 365.831269 -230.877282) (xy 365.837808 -230.831352)
			(xy 365.850754 -230.786803) (xy 365.869846 -230.744521) (xy 365.88192 -230.72471) (xy 365.903764 -230.69042)
			(xy 365.62157 -230.408226) (xy 365.607854 -230.40467) (xy 365.583616 -230.397997) (xy 365.537367 -230.378296)
			(xy 365.494664 -230.351772) (xy 365.456506 -230.319044) (xy 365.423787 -230.280879) (xy 365.397271 -230.23817)
			(xy 365.37758 -230.191917) (xy 365.370872 -230.167688) (xy 365.367316 -230.153972) (xy 363.963712 -228.750368)
			(xy 363.932724 -228.763068) (xy 363.903109 -228.77431) (xy 363.840949 -228.786466) (xy 363.80928 -228.787198)
			(xy 363.783493 -228.786691) (xy 363.732553 -228.77862) (xy 363.683503 -228.762681) (xy 363.63755 -228.739266)
			(xy 363.595825 -228.708951) (xy 363.559355 -228.672483) (xy 363.529039 -228.630759) (xy 363.505622 -228.584806)
			(xy 363.489682 -228.535757) (xy 363.48161 -228.484817) (xy 363.481112 -228.45903) (xy 363.481846 -228.427361)
			(xy 363.493996 -228.3652) (xy 363.505242 -228.335586) (xy 363.517942 -228.304598) (xy 363.120178 -227.906834)
			(xy 363.103076 -227.888941) (xy 363.075451 -227.84788) (xy 363.065314 -227.8253) (xy 363.052602 -227.805164)
			(xy 363.032494 -227.762001) (xy 363.018831 -227.716386) (xy 363.0119 -227.669276) (xy 363.011466 -227.645468)
			(xy 363.011466 -227.64496) (xy 363.011869 -227.621504) (xy 363.018562 -227.575071) (xy 363.031805 -227.530066)
			(xy 363.041184 -227.508562) (xy 363.045756 -227.498402) (xy 363.045756 -226.163886) (xy 363.041184 -226.153726)
			(xy 363.030001 -226.127881) (xy 363.015663 -226.073428) (xy 363.010833 -226.017326) (xy 363.015654 -225.961223)
			(xy 363.029983 -225.906767) (xy 363.041184 -225.88093) (xy 363.045756 -225.87077) (xy 363.045756 -224.539048)
			(xy 363.04093 -224.528888) (xy 363.0312 -224.506944) (xy 363.017482 -224.460945) (xy 363.010584 -224.413443)
			(xy 363.010196 -224.389442) (xy 363.01059 -224.365441) (xy 363.017479 -224.317937) (xy 363.03119 -224.271935)
			(xy 363.04093 -224.249996) (xy 363.045756 -224.239836) (xy 363.045756 -223.883982) (xy 362.98632 -223.883982)
			(xy 362.978192 -223.886776) (xy 362.96654 -223.890731) (xy 362.942766 -223.897089) (xy 362.930694 -223.899476)
			(xy 362.907834 -223.903794) (xy 362.70311 -224.258632) (xy 362.710984 -224.280476) (xy 362.719563 -224.306895)
			(xy 362.728758 -224.36167) (xy 362.729272 -224.389442) (xy 362.728764 -224.415329) (xy 362.720665 -224.466467)
			(xy 362.704666 -224.515707) (xy 362.68116 -224.561839) (xy 362.650728 -224.603726) (xy 362.614118 -224.640336)
			(xy 362.572231 -224.670768) (xy 362.526099 -224.694274) (xy 362.476859 -224.710273) (xy 362.425721 -224.718372)
			(xy 362.373947 -224.718372) (xy 362.322809 -224.710273) (xy 362.273569 -224.694274) (xy 362.227437 -224.670768)
			(xy 362.18555 -224.640336) (xy 362.14894 -224.603726) (xy 362.118508 -224.561839) (xy 362.095002 -224.515707)
			(xy 362.079003 -224.466467) (xy 362.070904 -224.415329) (xy 362.070396 -224.389442) (xy 362.070856 -224.364104)
			(xy 362.078604 -224.314024) (xy 362.093923 -224.265719) (xy 362.116453 -224.220327) (xy 362.145664 -224.178916)
			(xy 362.180866 -224.142463) (xy 362.221232 -224.111826) (xy 362.26581 -224.087725) (xy 362.313551 -224.07073)
			(xy 362.338366 -224.065592) (xy 362.361226 -224.061274) (xy 362.566204 -223.706182) (xy 362.558584 -223.684084)
			(xy 362.550071 -223.657911) (xy 362.540881 -223.60365) (xy 362.540296 -223.576134) (xy 362.540296 -223.575626)
			(xy 362.540775 -223.549736) (xy 362.548872 -223.498594) (xy 362.564871 -223.449348) (xy 362.588377 -223.403211)
			(xy 362.618812 -223.36132) (xy 362.655426 -223.324707) (xy 362.697318 -223.294273) (xy 362.743455 -223.270768)
			(xy 362.792701 -223.25477) (xy 362.843844 -223.246675) (xy 362.869734 -223.246188) (xy 362.88403 -223.246305)
			(xy 362.912519 -223.248718) (xy 362.92663 -223.251014) (xy 362.941299 -223.253077) (xy 362.970706 -223.249622)
			(xy 362.997889 -223.237883) (xy 363.020567 -223.218845) (xy 363.036838 -223.194107) (xy 363.045335 -223.165743)
			(xy 363.045756 -223.150938) (xy 363.045756 -222.908114) (xy 363.041184 -222.897954) (xy 363.030007 -222.872109)
			(xy 363.015681 -222.817658) (xy 363.010863 -222.76156) (xy 363.015695 -222.705463) (xy 363.030034 -222.651015)
			(xy 363.041184 -222.625158) (xy 363.045756 -222.614998) (xy 363.045756 -221.28353) (xy 363.04093 -221.27337)
			(xy 363.031201 -221.251426) (xy 363.017486 -221.205427) (xy 363.01059 -221.157925) (xy 363.010196 -221.133924)
			(xy 363.010724 -221.106216) (xy 363.01992 -221.051569) (xy 363.028484 -221.025212) (xy 363.036358 -221.003114)
			(xy 362.83138 -220.648022) (xy 362.80852 -220.643704) (xy 362.783668 -220.638569) (xy 362.735817 -220.62168)
			(xy 362.691122 -220.597651) (xy 362.650642 -220.567051) (xy 362.615334 -220.530604) (xy 362.586035 -220.489173)
			(xy 362.563437 -220.443738) (xy 362.548076 -220.395374) (xy 362.540315 -220.345227) (xy 362.539788 -220.319854)
			(xy 362.540274 -220.293955) (xy 362.548387 -220.242796) (xy 362.564408 -220.193538) (xy 362.58794 -220.147393)
			(xy 362.618404 -220.105501) (xy 362.655049 -220.068892) (xy 362.696972 -220.038469) (xy 362.743139 -220.014983)
			(xy 362.792414 -219.999011) (xy 362.84358 -219.990948) (xy 362.86948 -219.990416) (xy 362.883839 -219.990525)
			(xy 362.912455 -219.992946) (xy 362.92663 -219.995242) (xy 362.941296 -219.997305) (xy 362.970696 -219.99385)
			(xy 362.997871 -219.98211) (xy 363.020539 -219.96307) (xy 363.036794 -219.93833) (xy 363.045274 -219.909968)
			(xy 363.045756 -219.895166) (xy 363.045756 -219.652596) (xy 363.041184 -219.642436) (xy 363.03 -219.616591)
			(xy 363.01566 -219.562137) (xy 363.010829 -219.506035) (xy 363.015648 -219.449931) (xy 363.029976 -219.395474)
			(xy 363.041184 -219.36964) (xy 363.045756 -219.35948) (xy 363.045756 -218.028012) (xy 363.04093 -218.017852)
			(xy 363.031202 -217.995908) (xy 363.01749 -217.949909) (xy 363.010597 -217.902406) (xy 363.010196 -217.878406)
			(xy 363.010725 -217.850698) (xy 363.019925 -217.796052) (xy 363.028484 -217.769694) (xy 363.036358 -217.747596)
			(xy 362.83138 -217.392504) (xy 362.80852 -217.388186) (xy 362.783666 -217.383052) (xy 362.735808 -217.366165)
			(xy 362.691107 -217.342138) (xy 362.650619 -217.311539) (xy 362.615303 -217.275093) (xy 362.585994 -217.233662)
			(xy 362.563386 -217.188227) (xy 362.548013 -217.139862) (xy 362.54024 -217.089711) (xy 362.539788 -217.064336)
			(xy 362.540267 -217.038424) (xy 362.548368 -216.987238) (xy 362.564378 -216.937949) (xy 362.587901 -216.891772)
			(xy 362.618358 -216.849843) (xy 362.655 -216.813195) (xy 362.696924 -216.78273) (xy 362.743097 -216.759199)
			(xy 362.792383 -216.743182) (xy 362.843568 -216.735071) (xy 362.86948 -216.734644) (xy 362.883844 -216.734821)
			(xy 362.912461 -216.737361) (xy 362.92663 -216.739724) (xy 362.941299 -216.741787) (xy 362.970708 -216.738331)
			(xy 362.997892 -216.726593) (xy 363.020571 -216.707556) (xy 363.036843 -216.682817) (xy 363.045343 -216.654453)
			(xy 363.045756 -216.639648) (xy 363.045756 -216.397586) (xy 363.041184 -216.387426) (xy 363.03173 -216.365853)
			(xy 363.018394 -216.320681) (xy 363.011634 -216.274069) (xy 363.011212 -216.25052) (xy 363.011613 -216.226968)
			(xy 363.018351 -216.180349) (xy 363.031704 -216.135178) (xy 363.041184 -216.113614) (xy 363.045756 -216.103454)
			(xy 363.045756 -201.196194) (xy 363.046328 -201.171234) (xy 363.05607 -201.122274) (xy 363.075178 -201.076157)
			(xy 363.102917 -201.034654) (xy 363.120178 -201.016616) (xy 397.786352 -166.350442) (xy 397.804394 -166.333184)
			(xy 397.845888 -166.30543) (xy 397.892006 -166.286319) (xy 397.940969 -166.276589) (xy 397.96593 -166.27602)
			(xy 409.64612 -166.27602) (xy 409.966668 -165.955472) (xy 409.966668 -157.991302) (xy 409.505912 -157.530546)
			(xy 373.176038 -157.530546) (xy 369.79523 -160.911354) (xy 372.506163 -160.911354) (xy 372.506163 -160.856846)
			(xy 372.513921 -160.802893) (xy 372.529279 -160.750593) (xy 372.551924 -160.701011) (xy 372.581395 -160.655157)
			(xy 372.617092 -160.613964) (xy 372.658289 -160.578271) (xy 372.704146 -160.548805) (xy 372.75373 -160.526165)
			(xy 372.806032 -160.510813) (xy 372.859986 -160.503061) (xy 372.88724 -160.5026) (xy 373.75084 -160.5026)
			(xy 373.77809 -160.503073) (xy 373.832034 -160.510834) (xy 373.884326 -160.526193) (xy 373.933899 -160.548837)
			(xy 373.979745 -160.578305) (xy 374.020931 -160.613997) (xy 374.056619 -160.655187) (xy 374.086083 -160.701036)
			(xy 374.108721 -160.750612) (xy 374.124075 -160.802905) (xy 374.13183 -160.85685) (xy 374.13183 -160.91135)
			(xy 374.124075 -160.965295) (xy 374.108721 -161.017588) (xy 374.086083 -161.067164) (xy 374.056619 -161.113013)
			(xy 374.020931 -161.154203) (xy 373.979745 -161.189895) (xy 373.933899 -161.219363) (xy 373.884326 -161.242007)
			(xy 373.832034 -161.257366) (xy 373.77809 -161.265127) (xy 373.75084 -161.265616) (xy 372.88724 -161.265616)
			(xy 372.859986 -161.265139) (xy 372.806032 -161.257387) (xy 372.75373 -161.242035) (xy 372.704146 -161.219395)
			(xy 372.658289 -161.189929) (xy 372.617092 -161.154236) (xy 372.581395 -161.113043) (xy 372.551924 -161.067189)
			(xy 372.529279 -161.017607) (xy 372.513921 -160.965307) (xy 372.506163 -160.911354) (xy 369.79523 -160.911354)
			(xy 363.830616 -166.875968) (xy 369.614196 -166.875968) (xy 369.614752 -166.84267) (xy 369.623426 -166.776641)
			(xy 369.640648 -166.71231) (xy 369.666122 -166.650779) (xy 369.699412 -166.593101) (xy 369.739949 -166.540263)
			(xy 369.787038 -166.493171) (xy 369.839873 -166.452631) (xy 369.86845 -166.435532) (xy 370.792502 -165.901878)
			(xy 370.82156 -165.885769) (xy 370.882966 -165.8604) (xy 370.947153 -165.843245) (xy 371.013028 -165.834597)
			(xy 371.046248 -165.83406) (xy 371.046756 -165.83406) (xy 371.077486 -165.834579) (xy 371.138498 -165.841982)
			(xy 371.198173 -165.856685) (xy 371.255641 -165.878475) (xy 371.310063 -165.907032) (xy 371.360647 -165.941941)
			(xy 371.406653 -165.982693) (xy 371.447412 -166.028694) (xy 371.482329 -166.079272) (xy 371.510894 -166.133689)
			(xy 371.532692 -166.191154) (xy 371.547404 -166.250827) (xy 371.554816 -166.311838) (xy 371.555264 -166.342568)
			(xy 371.554757 -166.375868) (xy 371.546077 -166.4419) (xy 371.52885 -166.506232) (xy 371.503369 -166.567765)
			(xy 371.470072 -166.625443) (xy 371.429528 -166.67828) (xy 371.382432 -166.72537) (xy 371.329591 -166.765907)
			(xy 371.30101 -166.783004) (xy 370.964111 -166.977568) (xy 373.398796 -166.977568) (xy 373.399226 -166.946836)
			(xy 373.406638 -166.885821) (xy 373.421351 -166.826144) (xy 373.443149 -166.768676) (xy 373.471715 -166.714254)
			(xy 373.506633 -166.663671) (xy 373.547392 -166.617667) (xy 373.5934 -166.57691) (xy 373.643984 -166.541996)
			(xy 373.698409 -166.513434) (xy 373.755879 -166.49164) (xy 373.815556 -166.476932) (xy 373.876572 -166.469524)
			(xy 373.907304 -166.46906) (xy 373.907812 -166.46906) (xy 373.941031 -166.469606) (xy 374.006903 -166.478264)
			(xy 374.071088 -166.495419) (xy 374.132496 -166.520778) (xy 374.161558 -166.536878) (xy 375.08561 -167.070532)
			(xy 375.114171 -167.087654) (xy 375.166997 -167.128201) (xy 375.214079 -167.175295) (xy 375.254613 -167.22813)
			(xy 375.287906 -167.285802) (xy 375.313388 -167.347326) (xy 375.330623 -167.411649) (xy 375.339318 -167.477672)
			(xy 375.339864 -167.510968) (xy 375.339432 -167.541701) (xy 375.332026 -167.60272) (xy 375.317319 -167.6624)
			(xy 375.295524 -167.719873) (xy 375.266961 -167.774299) (xy 375.232044 -167.824885) (xy 375.191284 -167.870893)
			(xy 375.145275 -167.911651) (xy 375.094689 -167.946567) (xy 375.040262 -167.975129) (xy 374.982789 -167.996923)
			(xy 374.923108 -168.011629) (xy 374.862089 -168.019033) (xy 374.831356 -168.019476) (xy 374.830848 -168.019476)
			(xy 374.797629 -168.018942) (xy 374.731757 -168.01028) (xy 374.667571 -167.993122) (xy 374.606164 -167.967759)
			(xy 374.577102 -167.951658) (xy 373.65305 -167.418004) (xy 373.624495 -167.400872) (xy 373.571672 -167.360325)
			(xy 373.524591 -167.313232) (xy 373.484057 -167.260398) (xy 373.450764 -167.202727) (xy 373.42528 -167.141205)
			(xy 373.408042 -167.076884) (xy 373.399344 -167.010863) (xy 373.398796 -166.977568) (xy 370.964111 -166.977568)
			(xy 370.376958 -167.316658) (xy 370.34791 -167.332786) (xy 370.2865 -167.35815) (xy 370.22231 -167.375299)
			(xy 370.156433 -167.383942) (xy 370.123212 -167.384476) (xy 370.122704 -167.384476) (xy 370.091971 -167.384059)
			(xy 370.030952 -167.37665) (xy 369.971272 -167.36194) (xy 369.9138 -167.340143) (xy 369.859375 -167.311577)
			(xy 369.808789 -167.276659) (xy 369.762782 -167.235898) (xy 369.722023 -167.189889) (xy 369.687108 -167.139301)
			(xy 369.658546 -167.084874) (xy 369.636752 -167.027401) (xy 369.622045 -166.96772) (xy 369.61464 -166.906701)
			(xy 369.614196 -166.875968) (xy 363.830616 -166.875968) (xy 360.782616 -169.923968) (xy 369.614196 -169.923968)
			(xy 369.614752 -169.89067) (xy 369.623426 -169.824641) (xy 369.640648 -169.76031) (xy 369.666122 -169.698779)
			(xy 369.699412 -169.641101) (xy 369.739949 -169.588263) (xy 369.787038 -169.541171) (xy 369.839873 -169.500631)
			(xy 369.86845 -169.483532) (xy 370.792502 -168.949878) (xy 370.82156 -168.933769) (xy 370.882966 -168.9084)
			(xy 370.947153 -168.891245) (xy 371.013028 -168.882597) (xy 371.046248 -168.88206) (xy 371.046756 -168.88206)
			(xy 371.077486 -168.882579) (xy 371.138498 -168.889982) (xy 371.198173 -168.904685) (xy 371.255641 -168.926475)
			(xy 371.310063 -168.955032) (xy 371.360647 -168.989941) (xy 371.406653 -169.030693) (xy 371.447412 -169.076694)
			(xy 371.482329 -169.127272) (xy 371.510894 -169.181689) (xy 371.532692 -169.239154) (xy 371.547404 -169.298827)
			(xy 371.554816 -169.359838) (xy 371.555264 -169.390568) (xy 371.554757 -169.423868) (xy 371.546077 -169.4899)
			(xy 371.52885 -169.554232) (xy 371.503369 -169.615765) (xy 371.470072 -169.673443) (xy 371.429528 -169.72628)
			(xy 371.382432 -169.77337) (xy 371.329591 -169.813907) (xy 371.30101 -169.831004) (xy 370.376958 -170.364658)
			(xy 370.34791 -170.380786) (xy 370.2865 -170.40615) (xy 370.22231 -170.423299) (xy 370.156433 -170.431942)
			(xy 370.123212 -170.432476) (xy 370.122704 -170.432476) (xy 370.091971 -170.432059) (xy 370.030952 -170.42465)
			(xy 369.971272 -170.40994) (xy 369.9138 -170.388143) (xy 369.859375 -170.359577) (xy 369.808789 -170.324659)
			(xy 369.762782 -170.283898) (xy 369.722023 -170.237889) (xy 369.687108 -170.187301) (xy 369.658546 -170.132874)
			(xy 369.636752 -170.075401) (xy 369.622045 -170.01572) (xy 369.61464 -169.954701) (xy 369.614196 -169.923968)
			(xy 360.782616 -169.923968) (xy 360.046016 -170.660568) (xy 373.398796 -170.660568) (xy 373.399226 -170.629836)
			(xy 373.406638 -170.568821) (xy 373.421351 -170.509144) (xy 373.443149 -170.451676) (xy 373.471715 -170.397254)
			(xy 373.506633 -170.346671) (xy 373.547392 -170.300667) (xy 373.5934 -170.25991) (xy 373.643984 -170.224996)
			(xy 373.698409 -170.196434) (xy 373.755879 -170.17464) (xy 373.815556 -170.159932) (xy 373.876572 -170.152524)
			(xy 373.907304 -170.15206) (xy 373.907812 -170.15206) (xy 373.941031 -170.152606) (xy 374.006903 -170.161264)
			(xy 374.071088 -170.178419) (xy 374.132496 -170.203778) (xy 374.161558 -170.219878) (xy 375.08561 -170.753532)
			(xy 375.114171 -170.770654) (xy 375.166997 -170.811201) (xy 375.214079 -170.858295) (xy 375.254613 -170.91113)
			(xy 375.287906 -170.968802) (xy 375.313388 -171.030326) (xy 375.330623 -171.094649) (xy 375.339318 -171.160672)
			(xy 375.339864 -171.193968) (xy 375.339432 -171.224701) (xy 375.332026 -171.28572) (xy 375.317319 -171.3454)
			(xy 375.295524 -171.402873) (xy 375.266961 -171.457299) (xy 375.232044 -171.507885) (xy 375.191284 -171.553893)
			(xy 375.145275 -171.594651) (xy 375.094689 -171.629567) (xy 375.040262 -171.658129) (xy 374.982789 -171.679923)
			(xy 374.923108 -171.694629) (xy 374.862089 -171.702033) (xy 374.831356 -171.702476) (xy 374.830848 -171.702476)
			(xy 374.797629 -171.701942) (xy 374.731757 -171.69328) (xy 374.667571 -171.676122) (xy 374.606164 -171.650759)
			(xy 374.577102 -171.634658) (xy 373.65305 -171.101004) (xy 373.624495 -171.083872) (xy 373.571672 -171.043325)
			(xy 373.524591 -170.996232) (xy 373.484057 -170.943398) (xy 373.450764 -170.885727) (xy 373.42528 -170.824205)
			(xy 373.408042 -170.759884) (xy 373.399344 -170.693863) (xy 373.398796 -170.660568) (xy 360.046016 -170.660568)
			(xy 357.734616 -172.971968) (xy 369.614196 -172.971968) (xy 369.614752 -172.93867) (xy 369.623426 -172.872641)
			(xy 369.640648 -172.80831) (xy 369.666122 -172.746779) (xy 369.699412 -172.689101) (xy 369.739949 -172.636263)
			(xy 369.787038 -172.589171) (xy 369.839873 -172.548631) (xy 369.86845 -172.531532) (xy 370.792502 -171.997878)
			(xy 370.82156 -171.981769) (xy 370.882966 -171.9564) (xy 370.947153 -171.939245) (xy 371.013028 -171.930597)
			(xy 371.046248 -171.93006) (xy 371.046756 -171.93006) (xy 371.077486 -171.930579) (xy 371.138498 -171.937982)
			(xy 371.198173 -171.952685) (xy 371.255641 -171.974475) (xy 371.310063 -172.003032) (xy 371.360647 -172.037941)
			(xy 371.406653 -172.078693) (xy 371.447412 -172.124694) (xy 371.482329 -172.175272) (xy 371.510894 -172.229689)
			(xy 371.532692 -172.287154) (xy 371.547404 -172.346827) (xy 371.554816 -172.407838) (xy 371.555264 -172.438568)
			(xy 371.554757 -172.471868) (xy 371.546077 -172.5379) (xy 371.52885 -172.602232) (xy 371.503369 -172.663765)
			(xy 371.470072 -172.721443) (xy 371.429528 -172.77428) (xy 371.382432 -172.82137) (xy 371.329591 -172.861907)
			(xy 371.30101 -172.879004) (xy 370.376958 -173.412658) (xy 370.34791 -173.428786) (xy 370.2865 -173.45415)
			(xy 370.22231 -173.471299) (xy 370.156433 -173.479942) (xy 370.123212 -173.480476) (xy 370.122704 -173.480476)
			(xy 370.091971 -173.480059) (xy 370.030952 -173.47265) (xy 369.971272 -173.45794) (xy 369.9138 -173.436143)
			(xy 369.859375 -173.407577) (xy 369.808789 -173.372659) (xy 369.762782 -173.331898) (xy 369.722023 -173.285889)
			(xy 369.687108 -173.235301) (xy 369.658546 -173.180874) (xy 369.636752 -173.123401) (xy 369.622045 -173.06372)
			(xy 369.61464 -173.002701) (xy 369.614196 -172.971968) (xy 357.734616 -172.971968) (xy 356.363016 -174.343568)
			(xy 373.398796 -174.343568) (xy 373.399226 -174.312836) (xy 373.406638 -174.251821) (xy 373.421351 -174.192144)
			(xy 373.443149 -174.134676) (xy 373.471715 -174.080254) (xy 373.506633 -174.029671) (xy 373.547392 -173.983667)
			(xy 373.5934 -173.94291) (xy 373.643984 -173.907996) (xy 373.698409 -173.879434) (xy 373.755879 -173.85764)
			(xy 373.815556 -173.842932) (xy 373.876572 -173.835524) (xy 373.907304 -173.83506) (xy 373.907812 -173.83506)
			(xy 373.941031 -173.835606) (xy 374.006903 -173.844264) (xy 374.071088 -173.861419) (xy 374.132496 -173.886778)
			(xy 374.161558 -173.902878) (xy 375.08561 -174.436532) (xy 375.114171 -174.453654) (xy 375.166997 -174.494201)
			(xy 375.214079 -174.541295) (xy 375.254613 -174.59413) (xy 375.287906 -174.651802) (xy 375.313388 -174.713326)
			(xy 375.330623 -174.777649) (xy 375.339318 -174.843672) (xy 375.339864 -174.876968) (xy 375.339432 -174.907701)
			(xy 375.332026 -174.96872) (xy 375.317319 -175.0284) (xy 375.295524 -175.085873) (xy 375.266961 -175.140299)
			(xy 375.232044 -175.190885) (xy 375.191284 -175.236893) (xy 375.145275 -175.277651) (xy 375.094689 -175.312567)
			(xy 375.040262 -175.341129) (xy 374.982789 -175.362923) (xy 374.923108 -175.377629) (xy 374.862089 -175.385033)
			(xy 374.831356 -175.385476) (xy 374.830848 -175.385476) (xy 374.797629 -175.384942) (xy 374.731757 -175.37628)
			(xy 374.667571 -175.359122) (xy 374.606164 -175.333759) (xy 374.577102 -175.317658) (xy 373.65305 -174.784004)
			(xy 373.624495 -174.766872) (xy 373.571672 -174.726325) (xy 373.524591 -174.679232) (xy 373.484057 -174.626398)
			(xy 373.450764 -174.568727) (xy 373.42528 -174.507205) (xy 373.408042 -174.442884) (xy 373.399344 -174.376863)
			(xy 373.398796 -174.343568) (xy 356.363016 -174.343568) (xy 356.09276 -174.613824) (xy 356.09276 -176.019968)
			(xy 369.614196 -176.019968) (xy 369.614752 -175.98667) (xy 369.623426 -175.920641) (xy 369.640648 -175.85631)
			(xy 369.666122 -175.794779) (xy 369.699412 -175.737101) (xy 369.739949 -175.684263) (xy 369.787038 -175.637171)
			(xy 369.839873 -175.596631) (xy 369.86845 -175.579532) (xy 370.792502 -175.045878) (xy 370.82156 -175.029769)
			(xy 370.882966 -175.0044) (xy 370.947153 -174.987245) (xy 371.013028 -174.978597) (xy 371.046248 -174.97806)
			(xy 371.046756 -174.97806) (xy 371.077486 -174.978579) (xy 371.138498 -174.985982) (xy 371.198173 -175.000685)
			(xy 371.255641 -175.022475) (xy 371.310063 -175.051032) (xy 371.360647 -175.085941) (xy 371.406653 -175.126693)
			(xy 371.447412 -175.172694) (xy 371.482329 -175.223272) (xy 371.510894 -175.277689) (xy 371.532692 -175.335154)
			(xy 371.547404 -175.394827) (xy 371.554816 -175.455838) (xy 371.555264 -175.486568) (xy 371.554757 -175.519868)
			(xy 371.546077 -175.5859) (xy 371.52885 -175.650232) (xy 371.503369 -175.711765) (xy 371.470072 -175.769443)
			(xy 371.429528 -175.82228) (xy 371.382432 -175.86937) (xy 371.329591 -175.909907) (xy 371.30101 -175.927004)
			(xy 370.376958 -176.460658) (xy 370.34791 -176.476786) (xy 370.2865 -176.50215) (xy 370.22231 -176.519299)
			(xy 370.156433 -176.527942) (xy 370.123212 -176.528476) (xy 370.122704 -176.528476) (xy 370.091971 -176.528059)
			(xy 370.030952 -176.52065) (xy 369.971272 -176.50594) (xy 369.9138 -176.484143) (xy 369.859375 -176.455577)
			(xy 369.808789 -176.420659) (xy 369.762782 -176.379898) (xy 369.722023 -176.333889) (xy 369.687108 -176.283301)
			(xy 369.658546 -176.228874) (xy 369.636752 -176.171401) (xy 369.622045 -176.11172) (xy 369.61464 -176.050701)
			(xy 369.614196 -176.019968) (xy 356.09276 -176.019968) (xy 356.09276 -179.067968) (xy 369.614196 -179.067968)
			(xy 369.614752 -179.03467) (xy 369.623426 -178.968641) (xy 369.640648 -178.90431) (xy 369.666122 -178.842779)
			(xy 369.699412 -178.785101) (xy 369.739949 -178.732263) (xy 369.787038 -178.685171) (xy 369.839873 -178.644631)
			(xy 369.86845 -178.627532) (xy 370.792502 -178.093878) (xy 370.82156 -178.077769) (xy 370.882966 -178.0524)
			(xy 370.947153 -178.035245) (xy 371.013028 -178.026597) (xy 371.046248 -178.02606) (xy 371.046756 -178.02606)
			(xy 371.076835 -178.026568) (xy 373.398796 -178.026568) (xy 373.399226 -177.995836) (xy 373.406638 -177.934821)
			(xy 373.421351 -177.875144) (xy 373.443149 -177.817676) (xy 373.471715 -177.763254) (xy 373.506633 -177.712671)
			(xy 373.547392 -177.666667) (xy 373.5934 -177.62591) (xy 373.643984 -177.590996) (xy 373.698409 -177.562434)
			(xy 373.755879 -177.54064) (xy 373.815556 -177.525932) (xy 373.876572 -177.518524) (xy 373.907304 -177.51806)
			(xy 373.907812 -177.51806) (xy 373.941031 -177.518606) (xy 374.006903 -177.527264) (xy 374.071088 -177.544419)
			(xy 374.132496 -177.569778) (xy 374.161558 -177.585878) (xy 375.08561 -178.119532) (xy 375.114171 -178.136654)
			(xy 375.166997 -178.177201) (xy 375.214079 -178.224295) (xy 375.254613 -178.27713) (xy 375.287906 -178.334802)
			(xy 375.313388 -178.396326) (xy 375.330623 -178.460649) (xy 375.339318 -178.526672) (xy 375.339864 -178.559968)
			(xy 375.339432 -178.590701) (xy 375.332026 -178.65172) (xy 375.317319 -178.7114) (xy 375.295524 -178.768873)
			(xy 375.266961 -178.823299) (xy 375.232044 -178.873885) (xy 375.191284 -178.919893) (xy 375.145275 -178.960651)
			(xy 375.094689 -178.995567) (xy 375.040262 -179.024129) (xy 374.982789 -179.045923) (xy 374.923108 -179.060629)
			(xy 374.862089 -179.068033) (xy 374.831356 -179.068476) (xy 374.830848 -179.068476) (xy 374.797629 -179.067942)
			(xy 374.731757 -179.05928) (xy 374.667571 -179.042122) (xy 374.606164 -179.016759) (xy 374.577102 -179.000658)
			(xy 373.65305 -178.467004) (xy 373.624495 -178.449872) (xy 373.571672 -178.409325) (xy 373.524591 -178.362232)
			(xy 373.484057 -178.309398) (xy 373.450764 -178.251727) (xy 373.42528 -178.190205) (xy 373.408042 -178.125884)
			(xy 373.399344 -178.059863) (xy 373.398796 -178.026568) (xy 371.076835 -178.026568) (xy 371.077486 -178.026579)
			(xy 371.138498 -178.033982) (xy 371.198173 -178.048685) (xy 371.255641 -178.070475) (xy 371.310063 -178.099032)
			(xy 371.360647 -178.133941) (xy 371.406653 -178.174693) (xy 371.447412 -178.220694) (xy 371.482329 -178.271272)
			(xy 371.510894 -178.325689) (xy 371.532692 -178.383154) (xy 371.547404 -178.442827) (xy 371.554816 -178.503838)
			(xy 371.555264 -178.534568) (xy 371.554757 -178.567868) (xy 371.546077 -178.6339) (xy 371.52885 -178.698232)
			(xy 371.503369 -178.759765) (xy 371.470072 -178.817443) (xy 371.429528 -178.87028) (xy 371.382432 -178.91737)
			(xy 371.329591 -178.957907) (xy 371.30101 -178.975004) (xy 370.376958 -179.508658) (xy 370.34791 -179.524786)
			(xy 370.2865 -179.55015) (xy 370.22231 -179.567299) (xy 370.156433 -179.575942) (xy 370.123212 -179.576476)
			(xy 370.122704 -179.576476) (xy 370.091971 -179.576059) (xy 370.030952 -179.56865) (xy 369.971272 -179.55394)
			(xy 369.9138 -179.532143) (xy 369.859375 -179.503577) (xy 369.808789 -179.468659) (xy 369.762782 -179.427898)
			(xy 369.722023 -179.381889) (xy 369.687108 -179.331301) (xy 369.658546 -179.276874) (xy 369.636752 -179.219401)
			(xy 369.622045 -179.15972) (xy 369.61464 -179.098701) (xy 369.614196 -179.067968) (xy 356.09276 -179.067968)
			(xy 356.09276 -182.115968) (xy 369.614196 -182.115968) (xy 369.614752 -182.08267) (xy 369.623426 -182.016641)
			(xy 369.640648 -181.95231) (xy 369.666122 -181.890779) (xy 369.699412 -181.833101) (xy 369.739949 -181.780263)
			(xy 369.787038 -181.733171) (xy 369.839873 -181.692631) (xy 369.86845 -181.675532) (xy 370.792502 -181.141878)
			(xy 370.82156 -181.125769) (xy 370.882966 -181.1004) (xy 370.947153 -181.083245) (xy 371.013028 -181.074597)
			(xy 371.046248 -181.07406) (xy 371.046756 -181.07406) (xy 371.077486 -181.074579) (xy 371.138498 -181.081982)
			(xy 371.198173 -181.096685) (xy 371.255641 -181.118475) (xy 371.310063 -181.147032) (xy 371.360647 -181.181941)
			(xy 371.406653 -181.222693) (xy 371.447412 -181.268694) (xy 371.482329 -181.319272) (xy 371.510894 -181.373689)
			(xy 371.532692 -181.431154) (xy 371.547404 -181.490827) (xy 371.554816 -181.551838) (xy 371.555264 -181.582568)
			(xy 371.554757 -181.615868) (xy 371.546077 -181.6819) (xy 371.538668 -181.709568) (xy 373.398796 -181.709568)
			(xy 373.399226 -181.678836) (xy 373.406638 -181.617821) (xy 373.421351 -181.558144) (xy 373.443149 -181.500676)
			(xy 373.471715 -181.446254) (xy 373.506633 -181.395671) (xy 373.547392 -181.349667) (xy 373.5934 -181.30891)
			(xy 373.643984 -181.273996) (xy 373.698409 -181.245434) (xy 373.755879 -181.22364) (xy 373.815556 -181.208932)
			(xy 373.876572 -181.201524) (xy 373.907304 -181.20106) (xy 373.907812 -181.20106) (xy 373.941031 -181.201606)
			(xy 374.006903 -181.210264) (xy 374.071088 -181.227419) (xy 374.132496 -181.252778) (xy 374.161558 -181.268878)
			(xy 375.08561 -181.802532) (xy 375.114171 -181.819654) (xy 375.166997 -181.860201) (xy 375.214079 -181.907295)
			(xy 375.254613 -181.96013) (xy 375.287906 -182.017802) (xy 375.313388 -182.079326) (xy 375.330623 -182.143649)
			(xy 375.339318 -182.209672) (xy 375.339864 -182.242968) (xy 375.339432 -182.273701) (xy 375.332026 -182.33472)
			(xy 375.317319 -182.3944) (xy 375.295524 -182.451873) (xy 375.266961 -182.506299) (xy 375.232044 -182.556885)
			(xy 375.191284 -182.602893) (xy 375.145275 -182.643651) (xy 375.094689 -182.678567) (xy 375.040262 -182.707129)
			(xy 374.982789 -182.728923) (xy 374.923108 -182.743629) (xy 374.862089 -182.751033) (xy 374.831356 -182.751476)
			(xy 374.830848 -182.751476) (xy 374.797629 -182.750942) (xy 374.731757 -182.74228) (xy 374.667571 -182.725122)
			(xy 374.606164 -182.699759) (xy 374.577102 -182.683658) (xy 373.65305 -182.150004) (xy 373.624495 -182.132872)
			(xy 373.571672 -182.092325) (xy 373.524591 -182.045232) (xy 373.484057 -181.992398) (xy 373.450764 -181.934727)
			(xy 373.42528 -181.873205) (xy 373.408042 -181.808884) (xy 373.399344 -181.742863) (xy 373.398796 -181.709568)
			(xy 371.538668 -181.709568) (xy 371.52885 -181.746232) (xy 371.503369 -181.807765) (xy 371.470072 -181.865443)
			(xy 371.429528 -181.91828) (xy 371.382432 -181.96537) (xy 371.329591 -182.005907) (xy 371.30101 -182.023004)
			(xy 370.376958 -182.556658) (xy 370.34791 -182.572786) (xy 370.2865 -182.59815) (xy 370.22231 -182.615299)
			(xy 370.156433 -182.623942) (xy 370.123212 -182.624476) (xy 370.122704 -182.624476) (xy 370.091971 -182.624059)
			(xy 370.030952 -182.61665) (xy 369.971272 -182.60194) (xy 369.9138 -182.580143) (xy 369.859375 -182.551577)
			(xy 369.808789 -182.516659) (xy 369.762782 -182.475898) (xy 369.722023 -182.429889) (xy 369.687108 -182.379301)
			(xy 369.658546 -182.324874) (xy 369.636752 -182.267401) (xy 369.622045 -182.20772) (xy 369.61464 -182.146701)
			(xy 369.614196 -182.115968) (xy 356.09276 -182.115968) (xy 356.09276 -185.011568) (xy 372.585996 -185.011568)
			(xy 372.586426 -184.980836) (xy 372.593838 -184.919821) (xy 372.608551 -184.860144) (xy 372.630349 -184.802676)
			(xy 372.658915 -184.748254) (xy 372.693833 -184.697671) (xy 372.734592 -184.651667) (xy 372.7806 -184.61091)
			(xy 372.831184 -184.575996) (xy 372.885609 -184.547434) (xy 372.943079 -184.52564) (xy 373.002756 -184.510932)
			(xy 373.063772 -184.503524) (xy 373.094504 -184.50306) (xy 373.095012 -184.50306) (xy 373.128231 -184.503606)
			(xy 373.194103 -184.512264) (xy 373.258288 -184.529419) (xy 373.319696 -184.554778) (xy 373.348758 -184.570878)
			(xy 374.27281 -185.104532) (xy 374.301371 -185.121654) (xy 374.354197 -185.162201) (xy 374.401279 -185.209295)
			(xy 374.441813 -185.26213) (xy 374.475106 -185.319802) (xy 374.500588 -185.381326) (xy 374.517823 -185.445649)
			(xy 374.526518 -185.511672) (xy 374.527064 -185.544968) (xy 374.526632 -185.575701) (xy 374.519226 -185.63672)
			(xy 374.504519 -185.6964) (xy 374.482724 -185.753873) (xy 374.454161 -185.808299) (xy 374.419244 -185.858885)
			(xy 374.378484 -185.904893) (xy 374.332475 -185.945651) (xy 374.281889 -185.980567) (xy 374.227462 -186.009129)
			(xy 374.169989 -186.030923) (xy 374.110308 -186.045629) (xy 374.049289 -186.053033) (xy 374.018556 -186.053476)
			(xy 374.018048 -186.053476) (xy 373.984829 -186.052942) (xy 373.918957 -186.04428) (xy 373.854771 -186.027122)
			(xy 373.793364 -186.001759) (xy 373.764302 -185.985658) (xy 372.84025 -185.452004) (xy 372.811695 -185.434872)
			(xy 372.758872 -185.394325) (xy 372.711791 -185.347232) (xy 372.671257 -185.294398) (xy 372.637964 -185.236727)
			(xy 372.61248 -185.175205) (xy 372.595242 -185.110884) (xy 372.586544 -185.044863) (xy 372.585996 -185.011568)
			(xy 356.09276 -185.011568) (xy 356.09276 -188.140848) (xy 356.092184 -188.165806) (xy 356.082436 -188.214762)
			(xy 356.063323 -188.260875) (xy 356.035582 -188.302373) (xy 356.018338 -188.320426) (xy 355.378258 -188.960506)
			(xy 355.360218 -188.977768) (xy 355.318725 -189.00553) (xy 355.272607 -189.024646) (xy 355.223642 -189.03438)
			(xy 355.19868 -189.034928) (xy 349.807276 -189.034928) (xy 349.387668 -189.454536) (xy 349.387668 -213.36381)
			(xy 349.388082 -213.377258) (xy 349.395115 -213.403219) (xy 349.408688 -213.42644) (xy 349.427858 -213.445306)
			(xy 349.451294 -213.458505) (xy 349.477364 -213.465121) (xy 349.504257 -213.464692) (xy 349.530103 -213.45725)
			(xy 349.541846 -213.450678) (xy 349.567713 -213.435797) (xy 349.623502 -213.414629) (xy 349.682191 -213.403853)
			(xy 349.712026 -213.40318) (xy 349.712534 -213.40318) (xy 349.738419 -213.40369) (xy 349.789551 -213.411794)
			(xy 349.838786 -213.427796) (xy 349.884912 -213.451304) (xy 349.926792 -213.481737) (xy 349.963397 -213.518347)
			(xy 349.993823 -213.560232) (xy 350.017324 -213.606362) (xy 350.033318 -213.655599) (xy 350.041414 -213.706733)
			(xy 350.041972 -213.732618) (xy 351.262696 -213.732618) (xy 351.263204 -213.706731) (xy 351.271303 -213.655593)
			(xy 351.287302 -213.606353) (xy 351.310808 -213.560221) (xy 351.34124 -213.518334) (xy 351.37785 -213.481724)
			(xy 351.419737 -213.451292) (xy 351.465869 -213.427786) (xy 351.515109 -213.411787) (xy 351.566247 -213.403688)
			(xy 351.618021 -213.403688) (xy 351.669159 -213.411787) (xy 351.718399 -213.427786) (xy 351.764531 -213.451292)
			(xy 351.806418 -213.481724) (xy 351.843028 -213.518334) (xy 351.87346 -213.560221) (xy 351.896966 -213.606353)
			(xy 351.912965 -213.655593) (xy 351.921064 -213.706731) (xy 351.921572 -213.732618) (xy 353.142296 -213.732618)
			(xy 353.142804 -213.706731) (xy 353.150903 -213.655593) (xy 353.166902 -213.606353) (xy 353.190408 -213.560221)
			(xy 353.22084 -213.518334) (xy 353.25745 -213.481724) (xy 353.299337 -213.451292) (xy 353.345469 -213.427786)
			(xy 353.394709 -213.411787) (xy 353.445847 -213.403688) (xy 353.497621 -213.403688) (xy 353.548759 -213.411787)
			(xy 353.597999 -213.427786) (xy 353.644131 -213.451292) (xy 353.686018 -213.481724) (xy 353.722628 -213.518334)
			(xy 353.75306 -213.560221) (xy 353.776566 -213.606353) (xy 353.792565 -213.655593) (xy 353.800664 -213.706731)
			(xy 353.801172 -213.732618) (xy 355.021896 -213.732618) (xy 355.022404 -213.706731) (xy 355.030503 -213.655593)
			(xy 355.046502 -213.606353) (xy 355.070008 -213.560221) (xy 355.10044 -213.518334) (xy 355.13705 -213.481724)
			(xy 355.178937 -213.451292) (xy 355.225069 -213.427786) (xy 355.274309 -213.411787) (xy 355.325447 -213.403688)
			(xy 355.377221 -213.403688) (xy 355.428359 -213.411787) (xy 355.477599 -213.427786) (xy 355.523731 -213.451292)
			(xy 355.565618 -213.481724) (xy 355.602228 -213.518334) (xy 355.63266 -213.560221) (xy 355.656166 -213.606353)
			(xy 355.672165 -213.655593) (xy 355.680264 -213.706731) (xy 355.680772 -213.732618) (xy 355.680423 -213.755595)
			(xy 355.674102 -213.801111) (xy 355.661516 -213.845306) (xy 355.652578 -213.866476) (xy 355.642672 -213.888828)
			(xy 355.856286 -214.293958) (xy 355.880416 -214.29853) (xy 355.90533 -214.303664) (xy 355.95334 -214.320459)
			(xy 355.998199 -214.344434) (xy 356.038841 -214.375017) (xy 356.074299 -214.411484) (xy 356.103732 -214.452967)
			(xy 356.12644 -214.49848) (xy 356.141883 -214.546942) (xy 356.149695 -214.597202) (xy 356.150164 -214.622634)
			(xy 356.149656 -214.648521) (xy 356.141557 -214.699659) (xy 356.125558 -214.748899) (xy 356.102052 -214.795031)
			(xy 356.07162 -214.836918) (xy 356.03501 -214.873528) (xy 355.993123 -214.90396) (xy 355.946991 -214.927466)
			(xy 355.897751 -214.943465) (xy 355.846613 -214.951564) (xy 355.794839 -214.951564) (xy 355.743701 -214.943465)
			(xy 355.694461 -214.927466) (xy 355.648329 -214.90396) (xy 355.606442 -214.873528) (xy 355.569832 -214.836918)
			(xy 355.5394 -214.795031) (xy 355.515894 -214.748899) (xy 355.499895 -214.699659) (xy 355.491796 -214.648521)
			(xy 355.491288 -214.622634) (xy 355.491658 -214.599658) (xy 355.49797 -214.554143) (xy 355.510548 -214.509947)
			(xy 355.519482 -214.488776) (xy 355.529388 -214.466424) (xy 355.315774 -214.061294) (xy 355.291644 -214.056722)
			(xy 355.266713 -214.051663) (xy 355.218699 -214.034858) (xy 355.173839 -214.010874) (xy 355.133197 -213.980281)
			(xy 355.097739 -213.943805) (xy 355.068309 -213.902313) (xy 355.045605 -213.856791) (xy 355.030167 -213.80832)
			(xy 355.022362 -213.758053) (xy 355.021896 -213.732618) (xy 353.801172 -213.732618) (xy 353.800823 -213.755595)
			(xy 353.794502 -213.801111) (xy 353.781916 -213.845306) (xy 353.772978 -213.866476) (xy 353.763072 -213.888828)
			(xy 353.976686 -214.293958) (xy 354.000816 -214.29853) (xy 354.02573 -214.303664) (xy 354.07374 -214.320459)
			(xy 354.118599 -214.344434) (xy 354.159241 -214.375017) (xy 354.194699 -214.411484) (xy 354.224132 -214.452967)
			(xy 354.24684 -214.49848) (xy 354.262283 -214.546942) (xy 354.270095 -214.597202) (xy 354.270564 -214.622634)
			(xy 354.270056 -214.648521) (xy 354.261957 -214.699659) (xy 354.245958 -214.748899) (xy 354.222452 -214.795031)
			(xy 354.19202 -214.836918) (xy 354.15541 -214.873528) (xy 354.113523 -214.90396) (xy 354.067391 -214.927466)
			(xy 354.018151 -214.943465) (xy 353.967013 -214.951564) (xy 353.915239 -214.951564) (xy 353.864101 -214.943465)
			(xy 353.814861 -214.927466) (xy 353.768729 -214.90396) (xy 353.726842 -214.873528) (xy 353.690232 -214.836918)
			(xy 353.6598 -214.795031) (xy 353.636294 -214.748899) (xy 353.620295 -214.699659) (xy 353.612196 -214.648521)
			(xy 353.611688 -214.622634) (xy 353.612058 -214.599658) (xy 353.61837 -214.554143) (xy 353.630948 -214.509947)
			(xy 353.639882 -214.488776) (xy 353.649788 -214.466424) (xy 353.436174 -214.061294) (xy 353.412044 -214.056722)
			(xy 353.387113 -214.051663) (xy 353.339099 -214.034858) (xy 353.294239 -214.010874) (xy 353.253597 -213.980281)
			(xy 353.218139 -213.943805) (xy 353.188709 -213.902313) (xy 353.166005 -213.856791) (xy 353.150567 -213.80832)
			(xy 353.142762 -213.758053) (xy 353.142296 -213.732618) (xy 351.921572 -213.732618) (xy 351.921223 -213.755595)
			(xy 351.914902 -213.801111) (xy 351.902316 -213.845306) (xy 351.893378 -213.866476) (xy 351.883472 -213.888828)
			(xy 352.097086 -214.293958) (xy 352.121216 -214.29853) (xy 352.14613 -214.303664) (xy 352.19414 -214.320459)
			(xy 352.238999 -214.344434) (xy 352.279641 -214.375017) (xy 352.315099 -214.411484) (xy 352.344532 -214.452967)
			(xy 352.36724 -214.49848) (xy 352.382683 -214.546942) (xy 352.390495 -214.597202) (xy 352.390964 -214.622634)
			(xy 352.390456 -214.648521) (xy 352.382357 -214.699659) (xy 352.366358 -214.748899) (xy 352.342852 -214.795031)
			(xy 352.31242 -214.836918) (xy 352.27581 -214.873528) (xy 352.233923 -214.90396) (xy 352.187791 -214.927466)
			(xy 352.138551 -214.943465) (xy 352.087413 -214.951564) (xy 352.035639 -214.951564) (xy 351.984501 -214.943465)
			(xy 351.935261 -214.927466) (xy 351.889129 -214.90396) (xy 351.847242 -214.873528) (xy 351.810632 -214.836918)
			(xy 351.7802 -214.795031) (xy 351.756694 -214.748899) (xy 351.740695 -214.699659) (xy 351.732596 -214.648521)
			(xy 351.732088 -214.622634) (xy 351.732458 -214.599658) (xy 351.73877 -214.554143) (xy 351.751348 -214.509947)
			(xy 351.760282 -214.488776) (xy 351.770188 -214.466424) (xy 351.556574 -214.061294) (xy 351.532444 -214.056722)
			(xy 351.507513 -214.051663) (xy 351.459499 -214.034858) (xy 351.414639 -214.010874) (xy 351.373997 -213.980281)
			(xy 351.338539 -213.943805) (xy 351.309109 -213.902313) (xy 351.286405 -213.856791) (xy 351.270967 -213.80832)
			(xy 351.263162 -213.758053) (xy 351.262696 -213.732618) (xy 350.041972 -213.732618) (xy 350.041607 -213.755594)
			(xy 350.035288 -213.801108) (xy 350.022706 -213.845303) (xy 350.013778 -213.866476) (xy 350.003872 -213.888828)
			(xy 350.217486 -214.293958) (xy 350.241616 -214.29853) (xy 350.266536 -214.303621) (xy 350.314534 -214.320446)
			(xy 350.359379 -214.34444) (xy 350.400008 -214.375035) (xy 350.435459 -214.411506) (xy 350.46489 -214.452987)
			(xy 350.487603 -214.498494) (xy 350.50306 -214.54695) (xy 350.510894 -214.597204) (xy 350.511364 -214.622634)
			(xy 350.510856 -214.648521) (xy 350.502757 -214.699659) (xy 350.486758 -214.748899) (xy 350.463252 -214.795031)
			(xy 350.43282 -214.836918) (xy 350.39621 -214.873528) (xy 350.354323 -214.90396) (xy 350.308191 -214.927466)
			(xy 350.258951 -214.943465) (xy 350.207813 -214.951564) (xy 350.156039 -214.951564) (xy 350.104901 -214.943465)
			(xy 350.055661 -214.927466) (xy 350.009529 -214.90396) (xy 349.967642 -214.873528) (xy 349.931032 -214.836918)
			(xy 349.9006 -214.795031) (xy 349.877094 -214.748899) (xy 349.861095 -214.699659) (xy 349.852996 -214.648521)
			(xy 349.852488 -214.622634) (xy 349.85285 -214.599657) (xy 349.859163 -214.554141) (xy 349.871741 -214.509944)
			(xy 349.880682 -214.488776) (xy 349.890588 -214.466424) (xy 349.676974 -214.061294) (xy 349.652844 -214.056722)
			(xy 349.623588 -214.05067) (xy 349.567745 -214.029451) (xy 349.541846 -214.014558) (xy 349.530127 -214.007956)
			(xy 349.504281 -214.000541) (xy 349.477396 -214.000132) (xy 349.451337 -214.006758) (xy 349.427912 -214.01996)
			(xy 349.408748 -214.038821) (xy 349.395175 -214.062032) (xy 349.388134 -214.087982) (xy 349.387668 -214.101426)
			(xy 349.387668 -214.326978) (xy 349.410954 -214.339025) (xy 349.453711 -214.36936) (xy 349.491127 -214.406081)
			(xy 349.522258 -214.448262) (xy 349.54632 -214.494839) (xy 349.562706 -214.544638) (xy 349.571002 -214.596402)
			(xy 349.570999 -214.648828) (xy 349.562698 -214.700591) (xy 349.546308 -214.750389) (xy 349.522242 -214.796963)
			(xy 349.491107 -214.839141) (xy 349.453688 -214.875859) (xy 349.410928 -214.906191) (xy 349.387668 -214.91829)
			(xy 349.387668 -215.436704) (xy 350.322388 -215.436704) (xy 350.322923 -215.411361) (xy 350.330693 -215.361274)
			(xy 350.346037 -215.312966) (xy 350.368592 -215.267575) (xy 350.397827 -215.226169) (xy 350.433054 -215.189725)
			(xy 350.473443 -215.159101) (xy 350.518042 -215.135018) (xy 350.565801 -215.118043) (xy 350.590612 -215.112854)
			(xy 350.613472 -215.108536) (xy 350.81845 -214.753444) (xy 350.810576 -214.7316) (xy 350.801999 -214.705181)
			(xy 350.7928 -214.650406) (xy 350.792288 -214.622634) (xy 350.792796 -214.596747) (xy 350.800895 -214.545609)
			(xy 350.816894 -214.496369) (xy 350.8404 -214.450237) (xy 350.870832 -214.40835) (xy 350.907442 -214.37174)
			(xy 350.949329 -214.341308) (xy 350.995461 -214.317802) (xy 351.044701 -214.301803) (xy 351.095839 -214.293704)
			(xy 351.147613 -214.293704) (xy 351.198751 -214.301803) (xy 351.247991 -214.317802) (xy 351.294123 -214.341308)
			(xy 351.33601 -214.37174) (xy 351.37262 -214.40835) (xy 351.403052 -214.450237) (xy 351.426558 -214.496369)
			(xy 351.442557 -214.545609) (xy 351.450656 -214.596747) (xy 351.451164 -214.622634) (xy 351.450741 -214.647971)
			(xy 351.442983 -214.698047) (xy 351.427654 -214.746347) (xy 351.405115 -214.791733) (xy 351.375898 -214.833136)
			(xy 351.34069 -214.869581) (xy 351.30032 -214.90021) (xy 351.255739 -214.924301) (xy 351.207997 -214.941288)
			(xy 351.183194 -214.946484) (xy 351.160334 -214.950802) (xy 350.955356 -215.305894) (xy 350.96323 -215.327738)
			(xy 350.971877 -215.354146) (xy 350.981197 -215.408922) (xy 350.981772 -215.436704) (xy 352.201988 -215.436704)
			(xy 352.202523 -215.411361) (xy 352.210293 -215.361274) (xy 352.225637 -215.312966) (xy 352.248192 -215.267575)
			(xy 352.277427 -215.226169) (xy 352.312654 -215.189725) (xy 352.353043 -215.159101) (xy 352.397642 -215.135018)
			(xy 352.445401 -215.118043) (xy 352.470212 -215.112854) (xy 352.493072 -215.108536) (xy 352.69805 -214.753444)
			(xy 352.690176 -214.7316) (xy 352.681599 -214.705181) (xy 352.6724 -214.650406) (xy 352.671888 -214.622634)
			(xy 352.672396 -214.596747) (xy 352.680495 -214.545609) (xy 352.696494 -214.496369) (xy 352.72 -214.450237)
			(xy 352.750432 -214.40835) (xy 352.787042 -214.37174) (xy 352.828929 -214.341308) (xy 352.875061 -214.317802)
			(xy 352.924301 -214.301803) (xy 352.975439 -214.293704) (xy 353.027213 -214.293704) (xy 353.078351 -214.301803)
			(xy 353.127591 -214.317802) (xy 353.173723 -214.341308) (xy 353.21561 -214.37174) (xy 353.25222 -214.40835)
			(xy 353.282652 -214.450237) (xy 353.306158 -214.496369) (xy 353.322157 -214.545609) (xy 353.330256 -214.596747)
			(xy 353.330764 -214.622634) (xy 353.330341 -214.647971) (xy 353.322583 -214.698047) (xy 353.307254 -214.746347)
			(xy 353.284715 -214.791733) (xy 353.255498 -214.833136) (xy 353.22029 -214.869581) (xy 353.17992 -214.90021)
			(xy 353.135339 -214.924301) (xy 353.087597 -214.941288) (xy 353.062794 -214.946484) (xy 353.039934 -214.950802)
			(xy 352.834956 -215.305894) (xy 352.84283 -215.327738) (xy 352.851477 -215.354146) (xy 352.860797 -215.408922)
			(xy 352.861372 -215.436704) (xy 354.081588 -215.436704) (xy 354.082123 -215.411361) (xy 354.089893 -215.361274)
			(xy 354.105237 -215.312966) (xy 354.127792 -215.267575) (xy 354.157027 -215.226169) (xy 354.192254 -215.189725)
			(xy 354.232643 -215.159101) (xy 354.277242 -215.135018) (xy 354.325001 -215.118043) (xy 354.349812 -215.112854)
			(xy 354.372672 -215.108536) (xy 354.57765 -214.753444) (xy 354.569776 -214.7316) (xy 354.561199 -214.705181)
			(xy 354.552 -214.650406) (xy 354.551488 -214.622634) (xy 354.551996 -214.596747) (xy 354.560095 -214.545609)
			(xy 354.576094 -214.496369) (xy 354.5996 -214.450237) (xy 354.630032 -214.40835) (xy 354.666642 -214.37174)
			(xy 354.708529 -214.341308) (xy 354.754661 -214.317802) (xy 354.803901 -214.301803) (xy 354.855039 -214.293704)
			(xy 354.906813 -214.293704) (xy 354.957951 -214.301803) (xy 355.007191 -214.317802) (xy 355.053323 -214.341308)
			(xy 355.09521 -214.37174) (xy 355.13182 -214.40835) (xy 355.162252 -214.450237) (xy 355.185758 -214.496369)
			(xy 355.201757 -214.545609) (xy 355.209856 -214.596747) (xy 355.210364 -214.622634) (xy 355.209941 -214.647971)
			(xy 355.202183 -214.698047) (xy 355.186854 -214.746347) (xy 355.164315 -214.791733) (xy 355.135098 -214.833136)
			(xy 355.09989 -214.869581) (xy 355.05952 -214.90021) (xy 355.014939 -214.924301) (xy 354.967197 -214.941288)
			(xy 354.942394 -214.946484) (xy 354.919534 -214.950802) (xy 354.714556 -215.305894) (xy 354.72243 -215.327738)
			(xy 354.731077 -215.354146) (xy 354.740397 -215.408922) (xy 354.740972 -215.436704) (xy 355.961188 -215.436704)
			(xy 355.961723 -215.411361) (xy 355.969493 -215.361274) (xy 355.984837 -215.312966) (xy 356.007392 -215.267575)
			(xy 356.036627 -215.226169) (xy 356.071854 -215.189725) (xy 356.112243 -215.159101) (xy 356.156842 -215.135018)
			(xy 356.204601 -215.118043) (xy 356.229412 -215.112854) (xy 356.252272 -215.108536) (xy 356.45725 -214.753444)
			(xy 356.449376 -214.7316) (xy 356.440799 -214.705181) (xy 356.4316 -214.650406) (xy 356.431088 -214.622634)
			(xy 356.431596 -214.596747) (xy 356.439695 -214.545609) (xy 356.455694 -214.496369) (xy 356.4792 -214.450237)
			(xy 356.509632 -214.40835) (xy 356.546242 -214.37174) (xy 356.588129 -214.341308) (xy 356.634261 -214.317802)
			(xy 356.683501 -214.301803) (xy 356.734639 -214.293704) (xy 356.786413 -214.293704) (xy 356.837551 -214.301803)
			(xy 356.886791 -214.317802) (xy 356.932923 -214.341308) (xy 356.97481 -214.37174) (xy 357.01142 -214.40835)
			(xy 357.041852 -214.450237) (xy 357.065358 -214.496369) (xy 357.081357 -214.545609) (xy 357.089456 -214.596747)
			(xy 357.089964 -214.622634) (xy 358.310688 -214.622634) (xy 358.311196 -214.596747) (xy 358.319295 -214.545609)
			(xy 358.335294 -214.496369) (xy 358.3588 -214.450237) (xy 358.389232 -214.40835) (xy 358.425842 -214.37174)
			(xy 358.467729 -214.341308) (xy 358.513861 -214.317802) (xy 358.563101 -214.301803) (xy 358.614239 -214.293704)
			(xy 358.666013 -214.293704) (xy 358.717151 -214.301803) (xy 358.766391 -214.317802) (xy 358.812523 -214.341308)
			(xy 358.85441 -214.37174) (xy 358.89102 -214.40835) (xy 358.921452 -214.450237) (xy 358.944958 -214.496369)
			(xy 358.960957 -214.545609) (xy 358.969056 -214.596747) (xy 358.969564 -214.622634) (xy 358.969564 -214.623142)
			(xy 358.968984 -214.650659) (xy 358.959791 -214.70492) (xy 358.951276 -214.731092) (xy 358.943656 -214.75319)
			(xy 359.148888 -215.108536) (xy 359.171748 -215.112854) (xy 359.196559 -215.118062) (xy 359.244336 -215.135013)
			(xy 359.288953 -215.15908) (xy 359.329358 -215.189696) (xy 359.364599 -215.226137) (xy 359.393844 -215.267545)
			(xy 359.416403 -215.312943) (xy 359.431745 -215.36126) (xy 359.439507 -215.411357) (xy 359.439972 -215.436704)
			(xy 359.439464 -215.462611) (xy 359.431358 -215.513788) (xy 359.415346 -215.563067) (xy 359.391823 -215.609234)
			(xy 359.361367 -215.651153) (xy 359.324729 -215.687791) (xy 359.28281 -215.718247) (xy 359.236643 -215.74177)
			(xy 359.187364 -215.757782) (xy 359.136187 -215.765888) (xy 359.084373 -215.765888) (xy 359.033196 -215.757782)
			(xy 358.983917 -215.74177) (xy 358.93775 -215.718247) (xy 358.895831 -215.687791) (xy 358.859193 -215.651153)
			(xy 358.828737 -215.609234) (xy 358.805214 -215.563067) (xy 358.789202 -215.513788) (xy 358.781096 -215.462611)
			(xy 358.780588 -215.436704) (xy 358.781184 -215.408987) (xy 358.790506 -215.35434) (xy 358.79913 -215.327992)
			(xy 358.80675 -215.306148) (xy 358.601772 -214.950802) (xy 358.578912 -214.946484) (xy 358.554096 -214.941291)
			(xy 358.506315 -214.924344) (xy 358.461694 -214.900279) (xy 358.421285 -214.869663) (xy 358.386043 -214.833219)
			(xy 358.356798 -214.791807) (xy 358.33424 -214.746405) (xy 358.318903 -214.698083) (xy 358.311148 -214.647983)
			(xy 358.310688 -214.622634) (xy 357.089964 -214.622634) (xy 357.089541 -214.647971) (xy 357.081783 -214.698047)
			(xy 357.066454 -214.746347) (xy 357.043915 -214.791733) (xy 357.014698 -214.833136) (xy 356.97949 -214.869581)
			(xy 356.93912 -214.90021) (xy 356.894539 -214.924301) (xy 356.846797 -214.941288) (xy 356.821994 -214.946484)
			(xy 356.799134 -214.950802) (xy 356.594156 -215.305894) (xy 356.60203 -215.327738) (xy 356.610677 -215.354146)
			(xy 356.619997 -215.408922) (xy 356.620572 -215.436704) (xy 356.620064 -215.462606) (xy 356.90152 -215.462606)
			(xy 356.90152 -215.410794) (xy 356.909625 -215.35962) (xy 356.925635 -215.310344) (xy 356.949157 -215.264178)
			(xy 356.97961 -215.222261) (xy 357.016246 -215.185623) (xy 357.058161 -215.155167) (xy 357.104325 -215.131643)
			(xy 357.1536 -215.11563) (xy 357.204774 -215.107522) (xy 357.23068 -215.107012) (xy 357.256191 -215.107502)
			(xy 357.306606 -215.11536) (xy 357.355207 -215.130891) (xy 357.400836 -215.153725) (xy 357.442402 -215.183316)
			(xy 357.478912 -215.218958) (xy 357.494586 -215.239092) (xy 357.906574 -215.239092) (xy 357.92226 -215.218967)
			(xy 357.958768 -215.183323) (xy 358.000331 -215.153729) (xy 358.045956 -215.130891) (xy 358.094556 -215.115355)
			(xy 358.144969 -215.107491) (xy 358.17048 -215.107012) (xy 358.196391 -215.107484) (xy 358.247575 -215.115588)
			(xy 358.296861 -215.131599) (xy 358.343035 -215.155124) (xy 358.38496 -215.185582) (xy 358.421605 -215.222224)
			(xy 358.452066 -215.264148) (xy 358.475593 -215.310321) (xy 358.491607 -215.359606) (xy 358.499714 -215.410789)
			(xy 358.499714 -215.462611) (xy 358.491607 -215.513794) (xy 358.475593 -215.563079) (xy 358.452066 -215.609252)
			(xy 358.421605 -215.651176) (xy 358.38496 -215.687818) (xy 358.343035 -215.718276) (xy 358.296861 -215.741801)
			(xy 358.247575 -215.757812) (xy 358.196391 -215.765916) (xy 358.17048 -215.766396) (xy 358.144968 -215.765932)
			(xy 358.094552 -215.758068) (xy 358.04595 -215.742532) (xy 358.000322 -215.719693) (xy 357.958757 -215.690098)
			(xy 357.922247 -215.654452) (xy 357.906574 -215.634316) (xy 357.494586 -215.634316) (xy 357.478925 -215.654461)
			(xy 357.442412 -215.690104) (xy 357.400844 -215.719696) (xy 357.355213 -215.74253) (xy 357.306609 -215.758062)
			(xy 357.256193 -215.76592) (xy 357.23068 -215.766396) (xy 357.204774 -215.765878) (xy 357.1536 -215.75777)
			(xy 357.104325 -215.741757) (xy 357.058161 -215.718233) (xy 357.016246 -215.687777) (xy 356.97961 -215.651139)
			(xy 356.949157 -215.609222) (xy 356.925635 -215.563056) (xy 356.909625 -215.51378) (xy 356.90152 -215.462606)
			(xy 356.620064 -215.462606) (xy 356.620064 -215.462611) (xy 356.611958 -215.513788) (xy 356.595946 -215.563067)
			(xy 356.572423 -215.609234) (xy 356.541967 -215.651153) (xy 356.505329 -215.687791) (xy 356.46341 -215.718247)
			(xy 356.417243 -215.74177) (xy 356.367964 -215.757782) (xy 356.316787 -215.765888) (xy 356.264973 -215.765888)
			(xy 356.213796 -215.757782) (xy 356.164517 -215.74177) (xy 356.11835 -215.718247) (xy 356.076431 -215.687791)
			(xy 356.039793 -215.651153) (xy 356.009337 -215.609234) (xy 355.985814 -215.563067) (xy 355.969802 -215.513788)
			(xy 355.961696 -215.462611) (xy 355.961188 -215.436704) (xy 354.740972 -215.436704) (xy 354.740464 -215.462611)
			(xy 354.732358 -215.513788) (xy 354.716346 -215.563067) (xy 354.692823 -215.609234) (xy 354.662367 -215.651153)
			(xy 354.625729 -215.687791) (xy 354.58381 -215.718247) (xy 354.537643 -215.74177) (xy 354.488364 -215.757782)
			(xy 354.437187 -215.765888) (xy 354.385373 -215.765888) (xy 354.334196 -215.757782) (xy 354.284917 -215.74177)
			(xy 354.23875 -215.718247) (xy 354.196831 -215.687791) (xy 354.160193 -215.651153) (xy 354.129737 -215.609234)
			(xy 354.106214 -215.563067) (xy 354.090202 -215.513788) (xy 354.082096 -215.462611) (xy 354.081588 -215.436704)
			(xy 352.861372 -215.436704) (xy 352.860864 -215.462611) (xy 352.852758 -215.513788) (xy 352.836746 -215.563067)
			(xy 352.813223 -215.609234) (xy 352.782767 -215.651153) (xy 352.746129 -215.687791) (xy 352.70421 -215.718247)
			(xy 352.658043 -215.74177) (xy 352.608764 -215.757782) (xy 352.557587 -215.765888) (xy 352.505773 -215.765888)
			(xy 352.454596 -215.757782) (xy 352.405317 -215.74177) (xy 352.35915 -215.718247) (xy 352.317231 -215.687791)
			(xy 352.280593 -215.651153) (xy 352.250137 -215.609234) (xy 352.226614 -215.563067) (xy 352.210602 -215.513788)
			(xy 352.202496 -215.462611) (xy 352.201988 -215.436704) (xy 350.981772 -215.436704) (xy 350.981264 -215.462611)
			(xy 350.973158 -215.513788) (xy 350.957146 -215.563067) (xy 350.933623 -215.609234) (xy 350.903167 -215.651153)
			(xy 350.866529 -215.687791) (xy 350.82461 -215.718247) (xy 350.778443 -215.74177) (xy 350.729164 -215.757782)
			(xy 350.677987 -215.765888) (xy 350.626173 -215.765888) (xy 350.574996 -215.757782) (xy 350.525717 -215.74177)
			(xy 350.47955 -215.718247) (xy 350.437631 -215.687791) (xy 350.400993 -215.651153) (xy 350.370537 -215.609234)
			(xy 350.347014 -215.563067) (xy 350.331002 -215.513788) (xy 350.322896 -215.462611) (xy 350.322388 -215.436704)
			(xy 349.387668 -215.436704) (xy 349.387668 -215.956134) (xy 349.410859 -215.968125) (xy 349.453444 -215.998326)
			(xy 349.490709 -216.034888) (xy 349.521716 -216.076888) (xy 349.545682 -216.123268) (xy 349.562003 -216.172858)
			(xy 349.570267 -216.224406) (xy 349.570266 -216.276612) (xy 349.561999 -216.328159) (xy 349.545676 -216.377748)
			(xy 349.521707 -216.424127) (xy 349.490697 -216.466126) (xy 349.45343 -216.502686) (xy 349.410844 -216.532884)
			(xy 349.387668 -216.544906) (xy 349.387668 -216.695528) (xy 349.388072 -216.708984) (xy 349.395092 -216.734965)
			(xy 349.408661 -216.758206) (xy 349.427836 -216.777089) (xy 349.451282 -216.790301) (xy 349.477367 -216.796921)
			(xy 349.504276 -216.796489) (xy 349.530135 -216.789036) (xy 349.541846 -216.782396) (xy 349.567738 -216.767448)
			(xy 349.623603 -216.746165) (xy 349.68239 -216.735308) (xy 349.71228 -216.734644) (xy 349.738189 -216.735125)
			(xy 349.78937 -216.743229) (xy 349.838653 -216.75924) (xy 349.884825 -216.782765) (xy 349.926747 -216.813223)
			(xy 349.963387 -216.849866) (xy 349.993844 -216.891789) (xy 350.017366 -216.937961) (xy 350.033375 -216.987245)
			(xy 350.041477 -217.038427) (xy 350.041972 -217.064336) (xy 350.041512 -217.089686) (xy 350.033757 -217.139789)
			(xy 350.018421 -217.188114) (xy 349.995865 -217.233519) (xy 349.966622 -217.274935) (xy 349.931381 -217.311384)
			(xy 349.890973 -217.342006) (xy 349.846353 -217.366079) (xy 349.798573 -217.383035) (xy 349.773748 -217.388186)
			(xy 349.750888 -217.392504) (xy 349.54591 -217.747596) (xy 349.553784 -217.76944) (xy 349.562358 -217.79586)
			(xy 349.571542 -217.850635) (xy 349.572072 -217.878406) (xy 349.852996 -217.878406) (xy 349.853504 -217.852519)
			(xy 349.861603 -217.801381) (xy 349.877602 -217.752141) (xy 349.901108 -217.706009) (xy 349.93154 -217.664122)
			(xy 349.96815 -217.627512) (xy 350.010037 -217.59708) (xy 350.056169 -217.573574) (xy 350.105409 -217.557575)
			(xy 350.156547 -217.549476) (xy 350.208321 -217.549476) (xy 350.259459 -217.557575) (xy 350.308699 -217.573574)
			(xy 350.354831 -217.59708) (xy 350.396718 -217.627512) (xy 350.433328 -217.664122) (xy 350.46376 -217.706009)
			(xy 350.487266 -217.752141) (xy 350.503265 -217.801381) (xy 350.511364 -217.852519) (xy 350.511872 -217.878406)
			(xy 350.792796 -217.878406) (xy 350.793288 -217.853072) (xy 350.801039 -217.803) (xy 350.81636 -217.754704)
			(xy 350.838891 -217.70932) (xy 350.868099 -217.667918) (xy 350.903299 -217.631473) (xy 350.94366 -217.600842)
			(xy 350.988233 -217.576747) (xy 351.035967 -217.559756) (xy 351.060766 -217.554556) (xy 351.083626 -217.550238)
			(xy 351.288604 -217.195146) (xy 351.28073 -217.173302) (xy 351.272091 -217.146892) (xy 351.262767 -217.092117)
			(xy 351.262188 -217.064336) (xy 351.262696 -217.038429) (xy 351.270802 -216.987252) (xy 351.286814 -216.937973)
			(xy 351.310337 -216.891806) (xy 351.340793 -216.849887) (xy 351.377431 -216.813249) (xy 351.41935 -216.782793)
			(xy 351.465517 -216.75927) (xy 351.514796 -216.743258) (xy 351.565973 -216.735152) (xy 351.617787 -216.735152)
			(xy 351.668964 -216.743258) (xy 351.718243 -216.75927) (xy 351.76441 -216.782793) (xy 351.806329 -216.813249)
			(xy 351.842967 -216.849887) (xy 351.873423 -216.891806) (xy 351.896946 -216.937973) (xy 351.912958 -216.987252)
			(xy 351.921064 -217.038429) (xy 351.921572 -217.064336) (xy 351.921106 -217.089682) (xy 351.913328 -217.139773)
			(xy 351.897977 -217.188085) (xy 351.875413 -217.233478) (xy 351.846169 -217.274884) (xy 351.810934 -217.311328)
			(xy 351.770536 -217.34195) (xy 351.725929 -217.36603) (xy 351.678162 -217.383) (xy 351.653348 -217.388186)
			(xy 351.630488 -217.392504) (xy 351.42551 -217.747596) (xy 351.433384 -217.76944) (xy 351.441973 -217.795856)
			(xy 351.451163 -217.850633) (xy 351.451672 -217.878406) (xy 351.732596 -217.878406) (xy 351.733104 -217.852519)
			(xy 351.741203 -217.801381) (xy 351.757202 -217.752141) (xy 351.780708 -217.706009) (xy 351.81114 -217.664122)
			(xy 351.84775 -217.627512) (xy 351.889637 -217.59708) (xy 351.935769 -217.573574) (xy 351.985009 -217.557575)
			(xy 352.036147 -217.549476) (xy 352.087921 -217.549476) (xy 352.139059 -217.557575) (xy 352.188299 -217.573574)
			(xy 352.234431 -217.59708) (xy 352.276318 -217.627512) (xy 352.312928 -217.664122) (xy 352.34336 -217.706009)
			(xy 352.366866 -217.752141) (xy 352.382865 -217.801381) (xy 352.390964 -217.852519) (xy 352.391472 -217.878406)
			(xy 352.672396 -217.878406) (xy 352.672888 -217.853072) (xy 352.680639 -217.803) (xy 352.69596 -217.754704)
			(xy 352.718491 -217.70932) (xy 352.747699 -217.667918) (xy 352.782899 -217.631473) (xy 352.82326 -217.600842)
			(xy 352.867833 -217.576747) (xy 352.915567 -217.559756) (xy 352.940366 -217.554556) (xy 352.963226 -217.550238)
			(xy 353.168204 -217.195146) (xy 353.16033 -217.173302) (xy 353.151691 -217.146892) (xy 353.142367 -217.092117)
			(xy 353.141788 -217.064336) (xy 353.142296 -217.038429) (xy 353.150402 -216.987252) (xy 353.166414 -216.937973)
			(xy 353.189937 -216.891806) (xy 353.220393 -216.849887) (xy 353.257031 -216.813249) (xy 353.29895 -216.782793)
			(xy 353.345117 -216.75927) (xy 353.394396 -216.743258) (xy 353.445573 -216.735152) (xy 353.497387 -216.735152)
			(xy 353.548564 -216.743258) (xy 353.597843 -216.75927) (xy 353.64401 -216.782793) (xy 353.685929 -216.813249)
			(xy 353.722567 -216.849887) (xy 353.753023 -216.891806) (xy 353.776546 -216.937973) (xy 353.792558 -216.987252)
			(xy 353.800664 -217.038429) (xy 353.801172 -217.064336) (xy 353.800706 -217.089682) (xy 353.792928 -217.139773)
			(xy 353.777577 -217.188085) (xy 353.755013 -217.233478) (xy 353.725769 -217.274884) (xy 353.690534 -217.311328)
			(xy 353.650136 -217.34195) (xy 353.605529 -217.36603) (xy 353.557762 -217.383) (xy 353.532948 -217.388186)
			(xy 353.510088 -217.392504) (xy 353.30511 -217.747596) (xy 353.312984 -217.76944) (xy 353.321573 -217.795856)
			(xy 353.330763 -217.850633) (xy 353.331272 -217.878406) (xy 353.612196 -217.878406) (xy 353.612704 -217.852519)
			(xy 353.620803 -217.801381) (xy 353.636802 -217.752141) (xy 353.660308 -217.706009) (xy 353.69074 -217.664122)
			(xy 353.72735 -217.627512) (xy 353.769237 -217.59708) (xy 353.815369 -217.573574) (xy 353.864609 -217.557575)
			(xy 353.915747 -217.549476) (xy 353.967521 -217.549476) (xy 354.018659 -217.557575) (xy 354.067899 -217.573574)
			(xy 354.114031 -217.59708) (xy 354.155918 -217.627512) (xy 354.192528 -217.664122) (xy 354.22296 -217.706009)
			(xy 354.246466 -217.752141) (xy 354.262465 -217.801381) (xy 354.270564 -217.852519) (xy 354.271072 -217.878406)
			(xy 354.551996 -217.878406) (xy 354.552488 -217.853072) (xy 354.560239 -217.803) (xy 354.57556 -217.754704)
			(xy 354.598091 -217.70932) (xy 354.627299 -217.667918) (xy 354.662499 -217.631473) (xy 354.70286 -217.600842)
			(xy 354.747433 -217.576747) (xy 354.795167 -217.559756) (xy 354.819966 -217.554556) (xy 354.842826 -217.550238)
			(xy 355.047804 -217.195146) (xy 355.03993 -217.173302) (xy 355.031291 -217.146892) (xy 355.021967 -217.092117)
			(xy 355.021388 -217.064336) (xy 355.021896 -217.038429) (xy 355.030002 -216.987252) (xy 355.046014 -216.937973)
			(xy 355.069537 -216.891806) (xy 355.099993 -216.849887) (xy 355.136631 -216.813249) (xy 355.17855 -216.782793)
			(xy 355.224717 -216.75927) (xy 355.273996 -216.743258) (xy 355.325173 -216.735152) (xy 355.376987 -216.735152)
			(xy 355.428164 -216.743258) (xy 355.477443 -216.75927) (xy 355.52361 -216.782793) (xy 355.565529 -216.813249)
			(xy 355.602167 -216.849887) (xy 355.632623 -216.891806) (xy 355.656146 -216.937973) (xy 355.672158 -216.987252)
			(xy 355.680264 -217.038429) (xy 355.680772 -217.064336) (xy 355.680306 -217.089682) (xy 355.672528 -217.139773)
			(xy 355.657177 -217.188085) (xy 355.634613 -217.233478) (xy 355.605369 -217.274884) (xy 355.570134 -217.311328)
			(xy 355.529736 -217.34195) (xy 355.485129 -217.36603) (xy 355.437362 -217.383) (xy 355.412548 -217.388186)
			(xy 355.389688 -217.392504) (xy 355.18471 -217.747596) (xy 355.192584 -217.76944) (xy 355.201173 -217.795856)
			(xy 355.210363 -217.850633) (xy 355.210872 -217.878406) (xy 355.491796 -217.878406) (xy 355.492304 -217.852519)
			(xy 355.500403 -217.801381) (xy 355.516402 -217.752141) (xy 355.539908 -217.706009) (xy 355.57034 -217.664122)
			(xy 355.60695 -217.627512) (xy 355.648837 -217.59708) (xy 355.694969 -217.573574) (xy 355.744209 -217.557575)
			(xy 355.795347 -217.549476) (xy 355.847121 -217.549476) (xy 355.898259 -217.557575) (xy 355.947499 -217.573574)
			(xy 355.993631 -217.59708) (xy 356.035518 -217.627512) (xy 356.072128 -217.664122) (xy 356.10256 -217.706009)
			(xy 356.126066 -217.752141) (xy 356.142065 -217.801381) (xy 356.150164 -217.852519) (xy 356.150672 -217.878406)
			(xy 356.431596 -217.878406) (xy 356.432088 -217.853072) (xy 356.439839 -217.803) (xy 356.45516 -217.754704)
			(xy 356.477691 -217.70932) (xy 356.506899 -217.667918) (xy 356.542099 -217.631473) (xy 356.58246 -217.600842)
			(xy 356.627033 -217.576747) (xy 356.674767 -217.559756) (xy 356.699566 -217.554556) (xy 356.722426 -217.550238)
			(xy 356.927404 -217.195146) (xy 356.91953 -217.173302) (xy 356.910891 -217.146892) (xy 356.901567 -217.092117)
			(xy 356.900988 -217.064336) (xy 356.901496 -217.038429) (xy 356.909602 -216.987252) (xy 356.925614 -216.937973)
			(xy 356.949137 -216.891806) (xy 356.979593 -216.849887) (xy 357.016231 -216.813249) (xy 357.05815 -216.782793)
			(xy 357.104317 -216.75927) (xy 357.153596 -216.743258) (xy 357.204773 -216.735152) (xy 357.256587 -216.735152)
			(xy 357.307764 -216.743258) (xy 357.357043 -216.75927) (xy 357.40321 -216.782793) (xy 357.445129 -216.813249)
			(xy 357.481767 -216.849887) (xy 357.512223 -216.891806) (xy 357.535746 -216.937973) (xy 357.551758 -216.987252)
			(xy 357.559864 -217.038429) (xy 357.560372 -217.064336) (xy 357.559906 -217.089682) (xy 357.552128 -217.139773)
			(xy 357.536777 -217.188085) (xy 357.514213 -217.233478) (xy 357.484969 -217.274884) (xy 357.449734 -217.311328)
			(xy 357.409336 -217.34195) (xy 357.364729 -217.36603) (xy 357.316962 -217.383) (xy 357.292148 -217.388186)
			(xy 357.269288 -217.392504) (xy 357.06431 -217.747596) (xy 357.072184 -217.76944) (xy 357.080773 -217.795856)
			(xy 357.089963 -217.850633) (xy 357.090472 -217.878406) (xy 357.371396 -217.878406) (xy 357.371904 -217.852519)
			(xy 357.380003 -217.801381) (xy 357.396002 -217.752141) (xy 357.419508 -217.706009) (xy 357.44994 -217.664122)
			(xy 357.48655 -217.627512) (xy 357.528437 -217.59708) (xy 357.574569 -217.573574) (xy 357.623809 -217.557575)
			(xy 357.674947 -217.549476) (xy 357.726721 -217.549476) (xy 357.777859 -217.557575) (xy 357.827099 -217.573574)
			(xy 357.873231 -217.59708) (xy 357.915118 -217.627512) (xy 357.951728 -217.664122) (xy 357.98216 -217.706009)
			(xy 358.005666 -217.752141) (xy 358.021665 -217.801381) (xy 358.029764 -217.852519) (xy 358.030272 -217.878406)
			(xy 358.311196 -217.878406) (xy 358.311688 -217.853072) (xy 358.319439 -217.803) (xy 358.33476 -217.754704)
			(xy 358.357291 -217.70932) (xy 358.386499 -217.667918) (xy 358.421699 -217.631473) (xy 358.46206 -217.600842)
			(xy 358.506633 -217.576747) (xy 358.554367 -217.559756) (xy 358.579166 -217.554556) (xy 358.602026 -217.550238)
			(xy 358.807004 -217.194892) (xy 358.799384 -217.173048) (xy 358.790811 -217.146694) (xy 358.78162 -217.092045)
			(xy 358.781096 -217.064336) (xy 358.781604 -217.038449) (xy 358.789703 -216.987311) (xy 358.805702 -216.938071)
			(xy 358.829208 -216.891939) (xy 358.85964 -216.850052) (xy 358.89625 -216.813442) (xy 358.938137 -216.78301)
			(xy 358.984269 -216.759504) (xy 359.033509 -216.743505) (xy 359.084647 -216.735406) (xy 359.136421 -216.735406)
			(xy 359.187559 -216.743505) (xy 359.236799 -216.759504) (xy 359.282931 -216.78301) (xy 359.324818 -216.813442)
			(xy 359.361428 -216.850052) (xy 359.39186 -216.891939) (xy 359.415366 -216.938071) (xy 359.431365 -216.987311)
			(xy 359.439464 -217.038449) (xy 359.439972 -217.064336) (xy 360.660188 -217.064336) (xy 360.660696 -217.038429)
			(xy 360.668802 -216.987252) (xy 360.684814 -216.937973) (xy 360.708337 -216.891806) (xy 360.738793 -216.849887)
			(xy 360.775431 -216.813249) (xy 360.81735 -216.782793) (xy 360.863517 -216.75927) (xy 360.912796 -216.743258)
			(xy 360.963973 -216.735152) (xy 361.015787 -216.735152) (xy 361.066964 -216.743258) (xy 361.116243 -216.75927)
			(xy 361.16241 -216.782793) (xy 361.204329 -216.813249) (xy 361.240967 -216.849887) (xy 361.271423 -216.891806)
			(xy 361.294946 -216.937973) (xy 361.310958 -216.987252) (xy 361.319064 -217.038429) (xy 361.319572 -217.064336)
			(xy 361.318959 -217.091989) (xy 361.309638 -217.146507) (xy 361.30103 -217.172794) (xy 361.29341 -217.194892)
			(xy 361.498642 -217.550238) (xy 361.521502 -217.554556) (xy 361.546303 -217.559751) (xy 361.594042 -217.57674)
			(xy 361.638619 -217.600833) (xy 361.678984 -217.631463) (xy 361.714188 -217.667908) (xy 361.7434 -217.709312)
			(xy 361.765933 -217.754697) (xy 361.781256 -217.802996) (xy 361.789008 -217.85307) (xy 361.789472 -217.878406)
			(xy 361.788964 -217.904293) (xy 361.780865 -217.955431) (xy 361.764866 -218.004671) (xy 361.74136 -218.050803)
			(xy 361.710928 -218.09269) (xy 361.674318 -218.1293) (xy 361.632431 -218.159732) (xy 361.586299 -218.183238)
			(xy 361.537059 -218.199237) (xy 361.485921 -218.207336) (xy 361.434147 -218.207336) (xy 361.383009 -218.199237)
			(xy 361.333769 -218.183238) (xy 361.287637 -218.159732) (xy 361.24575 -218.1293) (xy 361.20914 -218.09269)
			(xy 361.178708 -218.050803) (xy 361.155202 -218.004671) (xy 361.139203 -217.955431) (xy 361.131104 -217.904293)
			(xy 361.130596 -217.878406) (xy 361.131127 -217.850698) (xy 361.140321 -217.796051) (xy 361.148884 -217.769694)
			(xy 361.156758 -217.747596) (xy 360.95178 -217.392504) (xy 360.92892 -217.388186) (xy 360.904075 -217.38302)
			(xy 360.856226 -217.366126) (xy 360.811533 -217.342096) (xy 360.771053 -217.311499) (xy 360.735741 -217.275058)
			(xy 360.706433 -217.233634) (xy 360.683822 -217.188207) (xy 360.668443 -217.13985) (xy 360.660658 -217.089708)
			(xy 360.660188 -217.064336) (xy 359.439972 -217.064336) (xy 359.439506 -217.089682) (xy 359.431728 -217.139773)
			(xy 359.416377 -217.188085) (xy 359.393813 -217.233478) (xy 359.364569 -217.274884) (xy 359.329334 -217.311328)
			(xy 359.288936 -217.34195) (xy 359.244329 -217.36603) (xy 359.196562 -217.383) (xy 359.171748 -217.388186)
			(xy 359.148888 -217.392504) (xy 358.94391 -217.747596) (xy 358.951784 -217.76944) (xy 358.960373 -217.795856)
			(xy 358.969563 -217.850633) (xy 358.970072 -217.878406) (xy 358.969564 -217.904293) (xy 358.961465 -217.955431)
			(xy 358.945466 -218.004671) (xy 358.92196 -218.050803) (xy 358.891528 -218.09269) (xy 358.854918 -218.1293)
			(xy 358.813031 -218.159732) (xy 358.766899 -218.183238) (xy 358.717659 -218.199237) (xy 358.666521 -218.207336)
			(xy 358.614747 -218.207336) (xy 358.563609 -218.199237) (xy 358.514369 -218.183238) (xy 358.468237 -218.159732)
			(xy 358.42635 -218.1293) (xy 358.38974 -218.09269) (xy 358.359308 -218.050803) (xy 358.335802 -218.004671)
			(xy 358.319803 -217.955431) (xy 358.311704 -217.904293) (xy 358.311196 -217.878406) (xy 358.030272 -217.878406)
			(xy 358.029741 -217.906114) (xy 358.020546 -217.960761) (xy 358.011984 -217.987118) (xy 358.004364 -218.008962)
			(xy 358.209342 -218.364054) (xy 358.232202 -218.368372) (xy 358.257007 -218.373552) (xy 358.304747 -218.390542)
			(xy 358.349324 -218.414636) (xy 358.38969 -218.445268) (xy 358.424894 -218.481716) (xy 358.454106 -218.523121)
			(xy 358.476638 -218.568508) (xy 358.491959 -218.616809) (xy 358.49971 -218.666886) (xy 358.500172 -218.692222)
			(xy 359.720388 -218.692222) (xy 359.720939 -218.66688) (xy 359.728707 -218.616793) (xy 359.744048 -218.568485)
			(xy 359.766601 -218.523094) (xy 359.795834 -218.481689) (xy 359.831059 -218.445245) (xy 359.871446 -218.41462)
			(xy 359.916044 -218.390537) (xy 359.963802 -218.373561) (xy 359.988612 -218.368372) (xy 360.011472 -218.364054)
			(xy 360.216704 -218.008708) (xy 360.20883 -217.98661) (xy 360.200361 -217.960367) (xy 360.191292 -217.905977)
			(xy 360.190796 -217.878406) (xy 360.191304 -217.852519) (xy 360.199403 -217.801381) (xy 360.215402 -217.752141)
			(xy 360.238908 -217.706009) (xy 360.26934 -217.664122) (xy 360.30595 -217.627512) (xy 360.347837 -217.59708)
			(xy 360.393969 -217.573574) (xy 360.443209 -217.557575) (xy 360.494347 -217.549476) (xy 360.546121 -217.549476)
			(xy 360.597259 -217.557575) (xy 360.646499 -217.573574) (xy 360.692631 -217.59708) (xy 360.734518 -217.627512)
			(xy 360.771128 -217.664122) (xy 360.80156 -217.706009) (xy 360.825066 -217.752141) (xy 360.841065 -217.801381)
			(xy 360.849164 -217.852519) (xy 360.849672 -217.878406) (xy 360.849225 -217.903782) (xy 360.841455 -217.953934)
			(xy 360.826085 -218.002302) (xy 360.803477 -218.047739) (xy 360.774167 -218.089171) (xy 360.73885 -218.125617)
			(xy 360.69836 -218.156215) (xy 360.653656 -218.18024) (xy 360.605796 -218.197124) (xy 360.58094 -218.202256)
			(xy 360.55808 -218.206574) (xy 360.353356 -218.561412) (xy 360.36123 -218.583256) (xy 360.369881 -218.609663)
			(xy 360.379198 -218.66444) (xy 360.379772 -218.692222) (xy 361.600496 -218.692222) (xy 361.601002 -218.666888)
			(xy 361.608751 -218.616817) (xy 361.62407 -218.568521) (xy 361.646599 -218.523138) (xy 361.675805 -218.481736)
			(xy 361.711003 -218.44529) (xy 361.751363 -218.414659) (xy 361.795934 -218.390564) (xy 361.843667 -218.373572)
			(xy 361.868466 -218.368372) (xy 361.891326 -218.364054) (xy 362.096304 -218.008962) (xy 362.088684 -217.986864)
			(xy 362.080159 -217.960694) (xy 362.070969 -217.906431) (xy 362.070396 -217.878914) (xy 362.070396 -217.878406)
			(xy 362.070904 -217.852519) (xy 362.079003 -217.801381) (xy 362.095002 -217.752141) (xy 362.118508 -217.706009)
			(xy 362.14894 -217.664122) (xy 362.18555 -217.627512) (xy 362.227437 -217.59708) (xy 362.273569 -217.573574)
			(xy 362.322809 -217.557575) (xy 362.373947 -217.549476) (xy 362.425721 -217.549476) (xy 362.476859 -217.557575)
			(xy 362.526099 -217.573574) (xy 362.572231 -217.59708) (xy 362.614118 -217.627512) (xy 362.650728 -217.664122)
			(xy 362.68116 -217.706009) (xy 362.704666 -217.752141) (xy 362.720665 -217.801381) (xy 362.728764 -217.852519)
			(xy 362.729272 -217.878406) (xy 362.728863 -217.903772) (xy 362.721112 -217.953909) (xy 362.705764 -218.002264)
			(xy 362.683182 -218.047694) (xy 362.6539 -218.089122) (xy 362.61861 -218.12557) (xy 362.578149 -218.156175)
			(xy 362.533472 -218.180212) (xy 362.485638 -218.197113) (xy 362.460794 -218.202256) (xy 362.437934 -218.206574)
			(xy 362.23321 -218.561412) (xy 362.241084 -218.583256) (xy 362.249677 -218.609671) (xy 362.258865 -218.664449)
			(xy 362.259372 -218.692222) (xy 362.258864 -218.718109) (xy 362.250765 -218.769247) (xy 362.234766 -218.818487)
			(xy 362.21126 -218.864619) (xy 362.180828 -218.906506) (xy 362.144218 -218.943116) (xy 362.102331 -218.973548)
			(xy 362.056199 -218.997054) (xy 362.006959 -219.013053) (xy 361.955821 -219.021152) (xy 361.904047 -219.021152)
			(xy 361.852909 -219.013053) (xy 361.803669 -218.997054) (xy 361.757537 -218.973548) (xy 361.71565 -218.943116)
			(xy 361.67904 -218.906506) (xy 361.648608 -218.864619) (xy 361.625102 -218.818487) (xy 361.609103 -218.769247)
			(xy 361.601004 -218.718109) (xy 361.600496 -218.692222) (xy 360.379772 -218.692222) (xy 360.379264 -218.718129)
			(xy 360.371158 -218.769306) (xy 360.355146 -218.818585) (xy 360.331623 -218.864752) (xy 360.301167 -218.906671)
			(xy 360.264529 -218.943309) (xy 360.22261 -218.973765) (xy 360.176443 -218.997288) (xy 360.127164 -219.0133)
			(xy 360.075987 -219.021406) (xy 360.024173 -219.021406) (xy 359.972996 -219.0133) (xy 359.923717 -218.997288)
			(xy 359.87755 -218.973765) (xy 359.835631 -218.943309) (xy 359.798993 -218.906671) (xy 359.768537 -218.864752)
			(xy 359.745014 -218.818585) (xy 359.729002 -218.769306) (xy 359.720896 -218.718129) (xy 359.720388 -218.692222)
			(xy 358.500172 -218.692222) (xy 358.499664 -218.718109) (xy 358.491565 -218.769247) (xy 358.475566 -218.818487)
			(xy 358.45206 -218.864619) (xy 358.421628 -218.906506) (xy 358.385018 -218.943116) (xy 358.343131 -218.973548)
			(xy 358.296999 -218.997054) (xy 358.247759 -219.013053) (xy 358.196621 -219.021152) (xy 358.144847 -219.021152)
			(xy 358.093709 -219.013053) (xy 358.044469 -218.997054) (xy 357.998337 -218.973548) (xy 357.95645 -218.943116)
			(xy 357.91984 -218.906506) (xy 357.889408 -218.864619) (xy 357.865902 -218.818487) (xy 357.849903 -218.769247)
			(xy 357.841804 -218.718109) (xy 357.841296 -218.692222) (xy 357.841831 -218.664514) (xy 357.851023 -218.609867)
			(xy 357.859584 -218.58351) (xy 357.867458 -218.561412) (xy 357.66248 -218.206574) (xy 357.63962 -218.202256)
			(xy 357.614783 -218.197156) (xy 357.567001 -218.180194) (xy 357.52238 -218.156114) (xy 357.481972 -218.125486)
			(xy 357.446732 -218.08903) (xy 357.417491 -218.047608) (xy 357.394937 -218.002196) (xy 357.379605 -217.953866)
			(xy 357.371854 -217.903758) (xy 357.371396 -217.878406) (xy 357.090472 -217.878406) (xy 357.089964 -217.904293)
			(xy 357.081865 -217.955431) (xy 357.065866 -218.004671) (xy 357.04236 -218.050803) (xy 357.011928 -218.09269)
			(xy 356.975318 -218.1293) (xy 356.933431 -218.159732) (xy 356.887299 -218.183238) (xy 356.838059 -218.199237)
			(xy 356.786921 -218.207336) (xy 356.735147 -218.207336) (xy 356.684009 -218.199237) (xy 356.634769 -218.183238)
			(xy 356.588637 -218.159732) (xy 356.54675 -218.1293) (xy 356.51014 -218.09269) (xy 356.479708 -218.050803)
			(xy 356.456202 -218.004671) (xy 356.440203 -217.955431) (xy 356.432104 -217.904293) (xy 356.431596 -217.878406)
			(xy 356.150672 -217.878406) (xy 356.150141 -217.906114) (xy 356.140946 -217.960761) (xy 356.132384 -217.987118)
			(xy 356.12451 -218.009216) (xy 356.329488 -218.364054) (xy 356.352348 -218.368372) (xy 356.377163 -218.373563)
			(xy 356.424941 -218.390515) (xy 356.469559 -218.414584) (xy 356.509965 -218.445202) (xy 356.545206 -218.481645)
			(xy 356.57445 -218.523056) (xy 356.597009 -218.568456) (xy 356.612349 -218.616776) (xy 356.620108 -218.666874)
			(xy 356.620572 -218.692222) (xy 356.620064 -218.718129) (xy 356.611958 -218.769306) (xy 356.595946 -218.818585)
			(xy 356.572423 -218.864752) (xy 356.541967 -218.906671) (xy 356.505329 -218.943309) (xy 356.46341 -218.973765)
			(xy 356.417243 -218.997288) (xy 356.367964 -219.0133) (xy 356.316787 -219.021406) (xy 356.264973 -219.021406)
			(xy 356.213796 -219.0133) (xy 356.164517 -218.997288) (xy 356.11835 -218.973765) (xy 356.076431 -218.943309)
			(xy 356.039793 -218.906671) (xy 356.009337 -218.864752) (xy 355.985814 -218.818585) (xy 355.969802 -218.769306)
			(xy 355.961696 -218.718129) (xy 355.961188 -218.692222) (xy 355.961788 -218.664505) (xy 355.971107 -218.609859)
			(xy 355.97973 -218.58351) (xy 355.987604 -218.561412) (xy 355.782626 -218.206574) (xy 355.759766 -218.202256)
			(xy 355.734962 -218.197073) (xy 355.687224 -218.180081) (xy 355.642649 -218.155985) (xy 355.602284 -218.125353)
			(xy 355.567082 -218.088906) (xy 355.53787 -218.047502) (xy 355.515337 -218.002116) (xy 355.500013 -217.953817)
			(xy 355.49226 -217.903742) (xy 355.491796 -217.878406) (xy 355.210872 -217.878406) (xy 355.210364 -217.904293)
			(xy 355.202265 -217.955431) (xy 355.186266 -218.004671) (xy 355.16276 -218.050803) (xy 355.132328 -218.09269)
			(xy 355.095718 -218.1293) (xy 355.053831 -218.159732) (xy 355.007699 -218.183238) (xy 354.958459 -218.199237)
			(xy 354.907321 -218.207336) (xy 354.855547 -218.207336) (xy 354.804409 -218.199237) (xy 354.755169 -218.183238)
			(xy 354.709037 -218.159732) (xy 354.66715 -218.1293) (xy 354.63054 -218.09269) (xy 354.600108 -218.050803)
			(xy 354.576602 -218.004671) (xy 354.560603 -217.955431) (xy 354.552504 -217.904293) (xy 354.551996 -217.878406)
			(xy 354.271072 -217.878406) (xy 354.270541 -217.906114) (xy 354.261346 -217.960761) (xy 354.252784 -217.987118)
			(xy 354.24491 -218.009216) (xy 354.449888 -218.364054) (xy 354.472748 -218.368372) (xy 354.497563 -218.373563)
			(xy 354.545341 -218.390515) (xy 354.589959 -218.414584) (xy 354.630365 -218.445202) (xy 354.665606 -218.481645)
			(xy 354.69485 -218.523056) (xy 354.717409 -218.568456) (xy 354.732749 -218.616776) (xy 354.740508 -218.666874)
			(xy 354.740972 -218.692222) (xy 354.740464 -218.718129) (xy 354.732358 -218.769306) (xy 354.716346 -218.818585)
			(xy 354.692823 -218.864752) (xy 354.662367 -218.906671) (xy 354.625729 -218.943309) (xy 354.58381 -218.973765)
			(xy 354.537643 -218.997288) (xy 354.488364 -219.0133) (xy 354.437187 -219.021406) (xy 354.385373 -219.021406)
			(xy 354.334196 -219.0133) (xy 354.284917 -218.997288) (xy 354.23875 -218.973765) (xy 354.196831 -218.943309)
			(xy 354.160193 -218.906671) (xy 354.129737 -218.864752) (xy 354.106214 -218.818585) (xy 354.090202 -218.769306)
			(xy 354.082096 -218.718129) (xy 354.081588 -218.692222) (xy 354.082188 -218.664505) (xy 354.091507 -218.609859)
			(xy 354.10013 -218.58351) (xy 354.108004 -218.561412) (xy 353.903026 -218.206574) (xy 353.880166 -218.202256)
			(xy 353.855362 -218.197073) (xy 353.807624 -218.180081) (xy 353.763049 -218.155985) (xy 353.722684 -218.125353)
			(xy 353.687482 -218.088906) (xy 353.65827 -218.047502) (xy 353.635737 -218.002116) (xy 353.620413 -217.953817)
			(xy 353.61266 -217.903742) (xy 353.612196 -217.878406) (xy 353.331272 -217.878406) (xy 353.330764 -217.904293)
			(xy 353.322665 -217.955431) (xy 353.306666 -218.004671) (xy 353.28316 -218.050803) (xy 353.252728 -218.09269)
			(xy 353.216118 -218.1293) (xy 353.174231 -218.159732) (xy 353.128099 -218.183238) (xy 353.078859 -218.199237)
			(xy 353.027721 -218.207336) (xy 352.975947 -218.207336) (xy 352.924809 -218.199237) (xy 352.875569 -218.183238)
			(xy 352.829437 -218.159732) (xy 352.78755 -218.1293) (xy 352.75094 -218.09269) (xy 352.720508 -218.050803)
			(xy 352.697002 -218.004671) (xy 352.681003 -217.955431) (xy 352.672904 -217.904293) (xy 352.672396 -217.878406)
			(xy 352.391472 -217.878406) (xy 352.390941 -217.906114) (xy 352.381746 -217.960761) (xy 352.373184 -217.987118)
			(xy 352.36531 -218.009216) (xy 352.570288 -218.364054) (xy 352.593148 -218.368372) (xy 352.617963 -218.373563)
			(xy 352.665741 -218.390515) (xy 352.710359 -218.414584) (xy 352.750765 -218.445202) (xy 352.786006 -218.481645)
			(xy 352.81525 -218.523056) (xy 352.837809 -218.568456) (xy 352.853149 -218.616776) (xy 352.860908 -218.666874)
			(xy 352.861372 -218.692222) (xy 352.860864 -218.718129) (xy 352.852758 -218.769306) (xy 352.836746 -218.818585)
			(xy 352.813223 -218.864752) (xy 352.782767 -218.906671) (xy 352.746129 -218.943309) (xy 352.70421 -218.973765)
			(xy 352.658043 -218.997288) (xy 352.608764 -219.0133) (xy 352.557587 -219.021406) (xy 352.505773 -219.021406)
			(xy 352.454596 -219.0133) (xy 352.405317 -218.997288) (xy 352.35915 -218.973765) (xy 352.317231 -218.943309)
			(xy 352.280593 -218.906671) (xy 352.250137 -218.864752) (xy 352.226614 -218.818585) (xy 352.210602 -218.769306)
			(xy 352.202496 -218.718129) (xy 352.201988 -218.692222) (xy 352.202588 -218.664505) (xy 352.211907 -218.609859)
			(xy 352.22053 -218.58351) (xy 352.228404 -218.561412) (xy 352.023426 -218.206574) (xy 352.000566 -218.202256)
			(xy 351.975762 -218.197073) (xy 351.928024 -218.180081) (xy 351.883449 -218.155985) (xy 351.843084 -218.125353)
			(xy 351.807882 -218.088906) (xy 351.77867 -218.047502) (xy 351.756137 -218.002116) (xy 351.740813 -217.953817)
			(xy 351.73306 -217.903742) (xy 351.732596 -217.878406) (xy 351.451672 -217.878406) (xy 351.451164 -217.904293)
			(xy 351.443065 -217.955431) (xy 351.427066 -218.004671) (xy 351.40356 -218.050803) (xy 351.373128 -218.09269)
			(xy 351.336518 -218.1293) (xy 351.294631 -218.159732) (xy 351.248499 -218.183238) (xy 351.199259 -218.199237)
			(xy 351.148121 -218.207336) (xy 351.096347 -218.207336) (xy 351.045209 -218.199237) (xy 350.995969 -218.183238)
			(xy 350.949837 -218.159732) (xy 350.90795 -218.1293) (xy 350.87134 -218.09269) (xy 350.840908 -218.050803)
			(xy 350.817402 -218.004671) (xy 350.801403 -217.955431) (xy 350.793304 -217.904293) (xy 350.792796 -217.878406)
			(xy 350.511872 -217.878406) (xy 350.511341 -217.906114) (xy 350.502146 -217.960761) (xy 350.493584 -217.987118)
			(xy 350.48571 -218.009216) (xy 350.690688 -218.364054) (xy 350.713548 -218.368372) (xy 350.738363 -218.373563)
			(xy 350.786141 -218.390515) (xy 350.830759 -218.414584) (xy 350.871165 -218.445202) (xy 350.906406 -218.481645)
			(xy 350.93565 -218.523056) (xy 350.958209 -218.568456) (xy 350.973549 -218.616776) (xy 350.981308 -218.666874)
			(xy 350.981772 -218.692222) (xy 350.981264 -218.718129) (xy 350.973158 -218.769306) (xy 350.957146 -218.818585)
			(xy 350.933623 -218.864752) (xy 350.903167 -218.906671) (xy 350.866529 -218.943309) (xy 350.82461 -218.973765)
			(xy 350.778443 -218.997288) (xy 350.729164 -219.0133) (xy 350.677987 -219.021406) (xy 350.626173 -219.021406)
			(xy 350.574996 -219.0133) (xy 350.525717 -218.997288) (xy 350.47955 -218.973765) (xy 350.437631 -218.943309)
			(xy 350.400993 -218.906671) (xy 350.370537 -218.864752) (xy 350.347014 -218.818585) (xy 350.331002 -218.769306)
			(xy 350.322896 -218.718129) (xy 350.322388 -218.692222) (xy 350.322988 -218.664505) (xy 350.332307 -218.609859)
			(xy 350.34093 -218.58351) (xy 350.348804 -218.561412) (xy 350.143826 -218.206574) (xy 350.120966 -218.202256)
			(xy 350.096162 -218.197073) (xy 350.048424 -218.180081) (xy 350.003849 -218.155985) (xy 349.963484 -218.125353)
			(xy 349.928282 -218.088906) (xy 349.89907 -218.047502) (xy 349.876537 -218.002116) (xy 349.861213 -217.953817)
			(xy 349.85346 -217.903742) (xy 349.852996 -217.878406) (xy 349.572072 -217.878406) (xy 349.571562 -217.904662)
			(xy 349.563234 -217.956509) (xy 349.54679 -218.00638) (xy 349.522646 -218.053012) (xy 349.491413 -218.095226)
			(xy 349.453881 -218.131953) (xy 349.411001 -218.162264) (xy 349.387668 -218.174316) (xy 349.387668 -218.974924)
			(xy 350.462342 -220.049598) (xy 350.495616 -220.031564) (xy 350.51981 -220.019009) (xy 350.57133 -220.001225)
			(xy 350.625082 -219.992203) (xy 350.652334 -219.991686) (xy 350.678121 -219.992194) (xy 350.72906 -220.000266)
			(xy 350.778109 -220.016206) (xy 350.824062 -220.039622) (xy 350.865786 -220.069937) (xy 350.902255 -220.106405)
			(xy 350.932572 -220.148128) (xy 350.955989 -220.19408) (xy 350.971931 -220.243128) (xy 350.980005 -220.294067)
			(xy 350.980502 -220.319854) (xy 350.979966 -220.347106) (xy 350.970962 -220.400861) (xy 350.953193 -220.452386)
			(xy 350.940624 -220.476572) (xy 350.92259 -220.509846) (xy 351.03943 -220.626686) (xy 351.049124 -220.635829)
			(xy 351.07219 -220.649154) (xy 351.097921 -220.656047) (xy 351.12456 -220.656036) (xy 351.150285 -220.649123)
			(xy 351.173341 -220.63578) (xy 351.192151 -220.616917) (xy 351.199196 -220.605604) (xy 351.288604 -220.450664)
			(xy 351.28073 -220.42882) (xy 351.272087 -220.402411) (xy 351.262773 -220.347635) (xy 351.262188 -220.319854)
			(xy 351.262696 -220.293947) (xy 351.270802 -220.24277) (xy 351.286814 -220.193491) (xy 351.310337 -220.147324)
			(xy 351.340793 -220.105405) (xy 351.377431 -220.068767) (xy 351.41935 -220.038311) (xy 351.465517 -220.014788)
			(xy 351.514796 -219.998776) (xy 351.565973 -219.99067) (xy 351.617787 -219.99067) (xy 351.668964 -219.998776)
			(xy 351.718243 -220.014788) (xy 351.76441 -220.038311) (xy 351.806329 -220.068767) (xy 351.842967 -220.105405)
			(xy 351.873423 -220.147324) (xy 351.896946 -220.193491) (xy 351.912958 -220.24277) (xy 351.921064 -220.293947)
			(xy 351.921572 -220.319854) (xy 353.141788 -220.319854) (xy 353.142296 -220.293947) (xy 353.150402 -220.24277)
			(xy 353.166414 -220.193491) (xy 353.189937 -220.147324) (xy 353.220393 -220.105405) (xy 353.257031 -220.068767)
			(xy 353.29895 -220.038311) (xy 353.345117 -220.014788) (xy 353.394396 -219.998776) (xy 353.445573 -219.99067)
			(xy 353.497387 -219.99067) (xy 353.548564 -219.998776) (xy 353.597843 -220.014788) (xy 353.64401 -220.038311)
			(xy 353.685929 -220.068767) (xy 353.722567 -220.105405) (xy 353.753023 -220.147324) (xy 353.776546 -220.193491)
			(xy 353.792558 -220.24277) (xy 353.800664 -220.293947) (xy 353.801172 -220.319854) (xy 355.021388 -220.319854)
			(xy 355.021896 -220.293947) (xy 355.030002 -220.24277) (xy 355.046014 -220.193491) (xy 355.069537 -220.147324)
			(xy 355.099993 -220.105405) (xy 355.136631 -220.068767) (xy 355.17855 -220.038311) (xy 355.224717 -220.014788)
			(xy 355.273996 -219.998776) (xy 355.325173 -219.99067) (xy 355.376987 -219.99067) (xy 355.428164 -219.998776)
			(xy 355.477443 -220.014788) (xy 355.52361 -220.038311) (xy 355.565529 -220.068767) (xy 355.602167 -220.105405)
			(xy 355.632623 -220.147324) (xy 355.656146 -220.193491) (xy 355.672158 -220.24277) (xy 355.680264 -220.293947)
			(xy 355.680772 -220.319854) (xy 356.900988 -220.319854) (xy 356.901496 -220.293947) (xy 356.909602 -220.24277)
			(xy 356.925614 -220.193491) (xy 356.949137 -220.147324) (xy 356.979593 -220.105405) (xy 357.016231 -220.068767)
			(xy 357.05815 -220.038311) (xy 357.104317 -220.014788) (xy 357.153596 -219.998776) (xy 357.204773 -219.99067)
			(xy 357.256587 -219.99067) (xy 357.307764 -219.998776) (xy 357.357043 -220.014788) (xy 357.40321 -220.038311)
			(xy 357.445129 -220.068767) (xy 357.481767 -220.105405) (xy 357.512223 -220.147324) (xy 357.535746 -220.193491)
			(xy 357.551758 -220.24277) (xy 357.559864 -220.293947) (xy 357.560372 -220.319854) (xy 358.780588 -220.319854)
			(xy 358.781096 -220.293947) (xy 358.789202 -220.24277) (xy 358.805214 -220.193491) (xy 358.828737 -220.147324)
			(xy 358.859193 -220.105405) (xy 358.895831 -220.068767) (xy 358.93775 -220.038311) (xy 358.983917 -220.014788)
			(xy 359.033196 -219.998776) (xy 359.084373 -219.99067) (xy 359.136187 -219.99067) (xy 359.187364 -219.998776)
			(xy 359.236643 -220.014788) (xy 359.28281 -220.038311) (xy 359.324729 -220.068767) (xy 359.361367 -220.105405)
			(xy 359.391823 -220.147324) (xy 359.415346 -220.193491) (xy 359.431358 -220.24277) (xy 359.439464 -220.293947)
			(xy 359.439972 -220.319854) (xy 360.660188 -220.319854) (xy 360.660696 -220.293947) (xy 360.668802 -220.24277)
			(xy 360.684814 -220.193491) (xy 360.708337 -220.147324) (xy 360.738793 -220.105405) (xy 360.775431 -220.068767)
			(xy 360.81735 -220.038311) (xy 360.863517 -220.014788) (xy 360.912796 -219.998776) (xy 360.963973 -219.99067)
			(xy 361.015787 -219.99067) (xy 361.066964 -219.998776) (xy 361.116243 -220.014788) (xy 361.16241 -220.038311)
			(xy 361.204329 -220.068767) (xy 361.240967 -220.105405) (xy 361.271423 -220.147324) (xy 361.294946 -220.193491)
			(xy 361.310958 -220.24277) (xy 361.319064 -220.293947) (xy 361.319572 -220.319854) (xy 361.318963 -220.347508)
			(xy 361.309639 -220.402026) (xy 361.30103 -220.428312) (xy 361.29341 -220.45041) (xy 361.498642 -220.805756)
			(xy 361.521502 -220.810074) (xy 361.546308 -220.815252) (xy 361.594047 -220.832242) (xy 361.638625 -220.856337)
			(xy 361.678991 -220.886969) (xy 361.714195 -220.923417) (xy 361.743406 -220.964822) (xy 361.765938 -221.01021)
			(xy 361.78126 -221.058511) (xy 361.78901 -221.108588) (xy 361.789472 -221.133924) (xy 361.788964 -221.159811)
			(xy 361.780865 -221.210949) (xy 361.764866 -221.260189) (xy 361.74136 -221.306321) (xy 361.710928 -221.348208)
			(xy 361.674318 -221.384818) (xy 361.632431 -221.41525) (xy 361.586299 -221.438756) (xy 361.537059 -221.454755)
			(xy 361.485921 -221.462854) (xy 361.434147 -221.462854) (xy 361.383009 -221.454755) (xy 361.333769 -221.438756)
			(xy 361.287637 -221.41525) (xy 361.24575 -221.384818) (xy 361.20914 -221.348208) (xy 361.178708 -221.306321)
			(xy 361.155202 -221.260189) (xy 361.139203 -221.210949) (xy 361.131104 -221.159811) (xy 361.130596 -221.133924)
			(xy 361.131132 -221.106216) (xy 361.140323 -221.051569) (xy 361.148884 -221.025212) (xy 361.156758 -221.003114)
			(xy 360.95178 -220.648022) (xy 360.92892 -220.643704) (xy 360.904079 -220.638521) (xy 360.856232 -220.621628)
			(xy 360.81154 -220.5976) (xy 360.771059 -220.567005) (xy 360.735748 -220.530566) (xy 360.706439 -220.489145)
			(xy 360.683827 -220.44372) (xy 360.668446 -220.395365) (xy 360.660659 -220.345225) (xy 360.660188 -220.319854)
			(xy 359.439972 -220.319854) (xy 359.439363 -220.347508) (xy 359.430039 -220.402026) (xy 359.42143 -220.428312)
			(xy 359.41381 -220.45041) (xy 359.619042 -220.805756) (xy 359.641902 -220.810074) (xy 359.666708 -220.815252)
			(xy 359.714447 -220.832242) (xy 359.759025 -220.856337) (xy 359.799391 -220.886969) (xy 359.834595 -220.923417)
			(xy 359.863806 -220.964822) (xy 359.886338 -221.01021) (xy 359.90166 -221.058511) (xy 359.90941 -221.108588)
			(xy 359.909872 -221.133924) (xy 359.909364 -221.159811) (xy 359.901265 -221.210949) (xy 359.885266 -221.260189)
			(xy 359.86176 -221.306321) (xy 359.831328 -221.348208) (xy 359.794718 -221.384818) (xy 359.752831 -221.41525)
			(xy 359.706699 -221.438756) (xy 359.657459 -221.454755) (xy 359.606321 -221.462854) (xy 359.554547 -221.462854)
			(xy 359.503409 -221.454755) (xy 359.454169 -221.438756) (xy 359.408037 -221.41525) (xy 359.36615 -221.384818)
			(xy 359.32954 -221.348208) (xy 359.299108 -221.306321) (xy 359.275602 -221.260189) (xy 359.259603 -221.210949)
			(xy 359.251504 -221.159811) (xy 359.250996 -221.133924) (xy 359.251532 -221.106216) (xy 359.260723 -221.051569)
			(xy 359.269284 -221.025212) (xy 359.277158 -221.003114) (xy 359.07218 -220.648022) (xy 359.04932 -220.643704)
			(xy 359.024479 -220.638521) (xy 358.976632 -220.621628) (xy 358.93194 -220.5976) (xy 358.891459 -220.567005)
			(xy 358.856148 -220.530566) (xy 358.826839 -220.489145) (xy 358.804227 -220.44372) (xy 358.788846 -220.395365)
			(xy 358.781059 -220.345225) (xy 358.780588 -220.319854) (xy 357.560372 -220.319854) (xy 357.559763 -220.347508)
			(xy 357.550439 -220.402026) (xy 357.54183 -220.428312) (xy 357.53421 -220.45041) (xy 357.739442 -220.805756)
			(xy 357.762302 -220.810074) (xy 357.787108 -220.815252) (xy 357.834847 -220.832242) (xy 357.879425 -220.856337)
			(xy 357.919791 -220.886969) (xy 357.954995 -220.923417) (xy 357.984206 -220.964822) (xy 358.006738 -221.01021)
			(xy 358.02206 -221.058511) (xy 358.02981 -221.108588) (xy 358.030272 -221.133924) (xy 358.029764 -221.159811)
			(xy 358.021665 -221.210949) (xy 358.005666 -221.260189) (xy 357.98216 -221.306321) (xy 357.951728 -221.348208)
			(xy 357.915118 -221.384818) (xy 357.873231 -221.41525) (xy 357.827099 -221.438756) (xy 357.777859 -221.454755)
			(xy 357.726721 -221.462854) (xy 357.674947 -221.462854) (xy 357.623809 -221.454755) (xy 357.574569 -221.438756)
			(xy 357.528437 -221.41525) (xy 357.48655 -221.384818) (xy 357.44994 -221.348208) (xy 357.419508 -221.306321)
			(xy 357.396002 -221.260189) (xy 357.380003 -221.210949) (xy 357.371904 -221.159811) (xy 357.371396 -221.133924)
			(xy 357.371932 -221.106216) (xy 357.381123 -221.051569) (xy 357.389684 -221.025212) (xy 357.397558 -221.003114)
			(xy 357.19258 -220.648022) (xy 357.16972 -220.643704) (xy 357.144879 -220.638521) (xy 357.097032 -220.621628)
			(xy 357.05234 -220.5976) (xy 357.011859 -220.567005) (xy 356.976548 -220.530566) (xy 356.947239 -220.489145)
			(xy 356.924627 -220.44372) (xy 356.909246 -220.395365) (xy 356.901459 -220.345225) (xy 356.900988 -220.319854)
			(xy 355.680772 -220.319854) (xy 355.680163 -220.347508) (xy 355.670839 -220.402026) (xy 355.66223 -220.428312)
			(xy 355.65461 -220.45041) (xy 355.859842 -220.805756) (xy 355.882702 -220.810074) (xy 355.907508 -220.815252)
			(xy 355.955247 -220.832242) (xy 355.999825 -220.856337) (xy 356.040191 -220.886969) (xy 356.075395 -220.923417)
			(xy 356.104606 -220.964822) (xy 356.127138 -221.01021) (xy 356.14246 -221.058511) (xy 356.15021 -221.108588)
			(xy 356.150672 -221.133924) (xy 356.150164 -221.159811) (xy 356.142065 -221.210949) (xy 356.126066 -221.260189)
			(xy 356.10256 -221.306321) (xy 356.072128 -221.348208) (xy 356.035518 -221.384818) (xy 355.993631 -221.41525)
			(xy 355.947499 -221.438756) (xy 355.898259 -221.454755) (xy 355.847121 -221.462854) (xy 355.795347 -221.462854)
			(xy 355.744209 -221.454755) (xy 355.694969 -221.438756) (xy 355.648837 -221.41525) (xy 355.60695 -221.384818)
			(xy 355.57034 -221.348208) (xy 355.539908 -221.306321) (xy 355.516402 -221.260189) (xy 355.500403 -221.210949)
			(xy 355.492304 -221.159811) (xy 355.491796 -221.133924) (xy 355.492332 -221.106216) (xy 355.501523 -221.051569)
			(xy 355.510084 -221.025212) (xy 355.517958 -221.003114) (xy 355.31298 -220.648022) (xy 355.29012 -220.643704)
			(xy 355.265279 -220.638521) (xy 355.217432 -220.621628) (xy 355.17274 -220.5976) (xy 355.132259 -220.567005)
			(xy 355.096948 -220.530566) (xy 355.067639 -220.489145) (xy 355.045027 -220.44372) (xy 355.029646 -220.395365)
			(xy 355.021859 -220.345225) (xy 355.021388 -220.319854) (xy 353.801172 -220.319854) (xy 353.800563 -220.347508)
			(xy 353.791239 -220.402026) (xy 353.78263 -220.428312) (xy 353.77501 -220.45041) (xy 353.980242 -220.805756)
			(xy 354.003102 -220.810074) (xy 354.027908 -220.815252) (xy 354.075647 -220.832242) (xy 354.120225 -220.856337)
			(xy 354.160591 -220.886969) (xy 354.195795 -220.923417) (xy 354.225006 -220.964822) (xy 354.247538 -221.01021)
			(xy 354.26286 -221.058511) (xy 354.27061 -221.108588) (xy 354.271072 -221.133924) (xy 354.270564 -221.159811)
			(xy 354.262465 -221.210949) (xy 354.246466 -221.260189) (xy 354.22296 -221.306321) (xy 354.192528 -221.348208)
			(xy 354.155918 -221.384818) (xy 354.114031 -221.41525) (xy 354.067899 -221.438756) (xy 354.018659 -221.454755)
			(xy 353.967521 -221.462854) (xy 353.915747 -221.462854) (xy 353.864609 -221.454755) (xy 353.815369 -221.438756)
			(xy 353.769237 -221.41525) (xy 353.72735 -221.384818) (xy 353.69074 -221.348208) (xy 353.660308 -221.306321)
			(xy 353.636802 -221.260189) (xy 353.620803 -221.210949) (xy 353.612704 -221.159811) (xy 353.612196 -221.133924)
			(xy 353.612732 -221.106216) (xy 353.621923 -221.051569) (xy 353.630484 -221.025212) (xy 353.638358 -221.003114)
			(xy 353.43338 -220.648022) (xy 353.41052 -220.643704) (xy 353.385679 -220.638521) (xy 353.337832 -220.621628)
			(xy 353.29314 -220.5976) (xy 353.252659 -220.567005) (xy 353.217348 -220.530566) (xy 353.188039 -220.489145)
			(xy 353.165427 -220.44372) (xy 353.150046 -220.395365) (xy 353.142259 -220.345225) (xy 353.141788 -220.319854)
			(xy 351.921572 -220.319854) (xy 351.92111 -220.345203) (xy 351.913353 -220.395304) (xy 351.898016 -220.443627)
			(xy 351.875459 -220.48903) (xy 351.846215 -220.530444) (xy 351.810974 -220.56689) (xy 351.770567 -220.59751)
			(xy 351.725948 -220.621582) (xy 351.678169 -220.638536) (xy 351.653348 -220.643704) (xy 351.630488 -220.648022)
			(xy 351.425002 -221.003876) (xy 351.430844 -221.0181) (xy 352.141536 -221.728792) (xy 352.151538 -221.738172)
			(xy 352.175372 -221.751708) (xy 352.201948 -221.758413) (xy 352.229351 -221.757803) (xy 352.255603 -221.749923)
			(xy 352.278811 -221.73534) (xy 352.288348 -221.72549) (xy 352.306617 -221.706275) (xy 352.348171 -221.673351)
			(xy 352.39445 -221.647487) (xy 352.444267 -221.629347) (xy 352.470212 -221.62389) (xy 352.493072 -221.619572)
			(xy 352.698304 -221.264226) (xy 352.69043 -221.242128) (xy 352.681967 -221.215884) (xy 352.672903 -221.161494)
			(xy 352.672396 -221.133924) (xy 352.672904 -221.108037) (xy 352.681003 -221.056899) (xy 352.697002 -221.007659)
			(xy 352.720508 -220.961527) (xy 352.75094 -220.91964) (xy 352.78755 -220.88303) (xy 352.829437 -220.852598)
			(xy 352.875569 -220.829092) (xy 352.924809 -220.813093) (xy 352.975947 -220.804994) (xy 353.027721 -220.804994)
			(xy 353.078859 -220.813093) (xy 353.128099 -220.829092) (xy 353.174231 -220.852598) (xy 353.216118 -220.88303)
			(xy 353.252728 -220.91964) (xy 353.28316 -220.961527) (xy 353.306666 -221.007659) (xy 353.322665 -221.056899)
			(xy 353.330764 -221.108037) (xy 353.331272 -221.133924) (xy 353.330803 -221.159298) (xy 353.32302 -221.209444)
			(xy 353.307643 -221.257806) (xy 353.285034 -221.303238) (xy 353.255729 -221.344668) (xy 353.220419 -221.381116)
			(xy 353.179939 -221.411721) (xy 353.135246 -221.435759) (xy 353.087397 -221.452663) (xy 353.06254 -221.457774)
			(xy 353.03968 -221.462092) (xy 352.834956 -221.81693) (xy 352.84283 -221.838774) (xy 352.851474 -221.865183)
			(xy 352.860791 -221.919959) (xy 352.861372 -221.94774) (xy 354.081588 -221.94774) (xy 354.082065 -221.922395)
			(xy 354.089845 -221.872306) (xy 354.105197 -221.823996) (xy 354.12776 -221.778605) (xy 354.157003 -221.7372)
			(xy 354.192237 -221.700757) (xy 354.232631 -221.670134) (xy 354.277236 -221.646052) (xy 354.324999 -221.629078)
			(xy 354.349812 -221.62389) (xy 354.372672 -221.619572) (xy 354.577904 -221.264226) (xy 354.57003 -221.242128)
			(xy 354.561565 -221.215883) (xy 354.552493 -221.161495) (xy 354.551996 -221.133924) (xy 354.552504 -221.108037)
			(xy 354.560603 -221.056899) (xy 354.576602 -221.007659) (xy 354.600108 -220.961527) (xy 354.63054 -220.91964)
			(xy 354.66715 -220.88303) (xy 354.709037 -220.852598) (xy 354.755169 -220.829092) (xy 354.804409 -220.813093)
			(xy 354.855547 -220.804994) (xy 354.907321 -220.804994) (xy 354.958459 -220.813093) (xy 355.007699 -220.829092)
			(xy 355.053831 -220.852598) (xy 355.095718 -220.88303) (xy 355.132328 -220.91964) (xy 355.16276 -220.961527)
			(xy 355.186266 -221.007659) (xy 355.202265 -221.056899) (xy 355.210364 -221.108037) (xy 355.210872 -221.133924)
			(xy 355.210442 -221.1593) (xy 355.202669 -221.209454) (xy 355.187296 -221.257821) (xy 355.164686 -221.303259)
			(xy 355.135374 -221.344691) (xy 355.100055 -221.381137) (xy 355.059563 -221.411734) (xy 355.014858 -221.435759)
			(xy 354.966996 -221.452643) (xy 354.94214 -221.457774) (xy 354.91928 -221.462092) (xy 354.714556 -221.81693)
			(xy 354.72243 -221.838774) (xy 354.731086 -221.865179) (xy 354.7404 -221.919958) (xy 354.740972 -221.94774)
			(xy 355.961188 -221.94774) (xy 355.961665 -221.922395) (xy 355.969445 -221.872306) (xy 355.984797 -221.823996)
			(xy 356.00736 -221.778605) (xy 356.036603 -221.7372) (xy 356.071837 -221.700757) (xy 356.112231 -221.670134)
			(xy 356.156836 -221.646052) (xy 356.204599 -221.629078) (xy 356.229412 -221.62389) (xy 356.252272 -221.619572)
			(xy 356.457504 -221.264226) (xy 356.44963 -221.242128) (xy 356.441165 -221.215883) (xy 356.432093 -221.161495)
			(xy 356.431596 -221.133924) (xy 356.432104 -221.108037) (xy 356.440203 -221.056899) (xy 356.456202 -221.007659)
			(xy 356.479708 -220.961527) (xy 356.51014 -220.91964) (xy 356.54675 -220.88303) (xy 356.588637 -220.852598)
			(xy 356.634769 -220.829092) (xy 356.684009 -220.813093) (xy 356.735147 -220.804994) (xy 356.786921 -220.804994)
			(xy 356.838059 -220.813093) (xy 356.887299 -220.829092) (xy 356.933431 -220.852598) (xy 356.975318 -220.88303)
			(xy 357.011928 -220.91964) (xy 357.04236 -220.961527) (xy 357.065866 -221.007659) (xy 357.081865 -221.056899)
			(xy 357.089964 -221.108037) (xy 357.090472 -221.133924) (xy 357.090042 -221.1593) (xy 357.082269 -221.209454)
			(xy 357.066896 -221.257821) (xy 357.044286 -221.303259) (xy 357.014974 -221.344691) (xy 356.979655 -221.381137)
			(xy 356.939163 -221.411734) (xy 356.894458 -221.435759) (xy 356.846596 -221.452643) (xy 356.82174 -221.457774)
			(xy 356.79888 -221.462092) (xy 356.594156 -221.81693) (xy 356.60203 -221.838774) (xy 356.610686 -221.865179)
			(xy 356.62 -221.919958) (xy 356.620572 -221.94774) (xy 357.841296 -221.94774) (xy 357.841727 -221.922404)
			(xy 357.849489 -221.872329) (xy 357.864819 -221.824032) (xy 357.887358 -221.778648) (xy 357.916574 -221.737246)
			(xy 357.95178 -221.700802) (xy 357.992148 -221.670172) (xy 358.036725 -221.646079) (xy 358.084465 -221.629089)
			(xy 358.109266 -221.62389) (xy 358.132126 -221.619572) (xy 358.337104 -221.26448) (xy 358.329484 -221.242382)
			(xy 358.320964 -221.216211) (xy 358.311771 -221.161949) (xy 358.311196 -221.134432) (xy 358.311196 -221.133924)
			(xy 358.311704 -221.108037) (xy 358.319803 -221.056899) (xy 358.335802 -221.007659) (xy 358.359308 -220.961527)
			(xy 358.38974 -220.91964) (xy 358.42635 -220.88303) (xy 358.468237 -220.852598) (xy 358.514369 -220.829092)
			(xy 358.563609 -220.813093) (xy 358.614747 -220.804994) (xy 358.666521 -220.804994) (xy 358.717659 -220.813093)
			(xy 358.766899 -220.829092) (xy 358.813031 -220.852598) (xy 358.854918 -220.88303) (xy 358.891528 -220.91964)
			(xy 358.92196 -220.961527) (xy 358.945466 -221.007659) (xy 358.961465 -221.056899) (xy 358.969564 -221.108037)
			(xy 358.970072 -221.133924) (xy 358.969679 -221.159291) (xy 358.961926 -221.209429) (xy 358.946575 -221.257784)
			(xy 358.923991 -221.303213) (xy 358.894706 -221.344642) (xy 358.859415 -221.381089) (xy 358.818952 -221.411694)
			(xy 358.774274 -221.435731) (xy 358.726438 -221.452632) (xy 358.701594 -221.457774) (xy 358.678734 -221.462092)
			(xy 358.47401 -221.81693) (xy 358.481884 -221.838774) (xy 358.490481 -221.865188) (xy 358.499666 -221.919967)
			(xy 358.500172 -221.94774) (xy 359.720388 -221.94774) (xy 359.720865 -221.922395) (xy 359.728645 -221.872306)
			(xy 359.743997 -221.823996) (xy 359.76656 -221.778605) (xy 359.795803 -221.7372) (xy 359.831037 -221.700757)
			(xy 359.871431 -221.670134) (xy 359.916036 -221.646052) (xy 359.963799 -221.629078) (xy 359.988612 -221.62389)
			(xy 360.011472 -221.619572) (xy 360.216704 -221.264226) (xy 360.20883 -221.242128) (xy 360.200365 -221.215883)
			(xy 360.191293 -221.161495) (xy 360.190796 -221.133924) (xy 360.191304 -221.108037) (xy 360.199403 -221.056899)
			(xy 360.215402 -221.007659) (xy 360.238908 -220.961527) (xy 360.26934 -220.91964) (xy 360.30595 -220.88303)
			(xy 360.347837 -220.852598) (xy 360.393969 -220.829092) (xy 360.443209 -220.813093) (xy 360.494347 -220.804994)
			(xy 360.546121 -220.804994) (xy 360.597259 -220.813093) (xy 360.646499 -220.829092) (xy 360.692631 -220.852598)
			(xy 360.734518 -220.88303) (xy 360.771128 -220.91964) (xy 360.80156 -220.961527) (xy 360.825066 -221.007659)
			(xy 360.841065 -221.056899) (xy 360.849164 -221.108037) (xy 360.849672 -221.133924) (xy 360.849242 -221.1593)
			(xy 360.841469 -221.209454) (xy 360.826096 -221.257821) (xy 360.803486 -221.303259) (xy 360.774174 -221.344691)
			(xy 360.738855 -221.381137) (xy 360.698363 -221.411734) (xy 360.653658 -221.435759) (xy 360.605796 -221.452643)
			(xy 360.58094 -221.457774) (xy 360.55808 -221.462092) (xy 360.353356 -221.81693) (xy 360.36123 -221.838774)
			(xy 360.369886 -221.865179) (xy 360.3792 -221.919958) (xy 360.379772 -221.94774) (xy 361.600496 -221.94774)
			(xy 361.600927 -221.922404) (xy 361.608689 -221.872329) (xy 361.624019 -221.824032) (xy 361.646558 -221.778648)
			(xy 361.675774 -221.737246) (xy 361.71098 -221.700802) (xy 361.751348 -221.670172) (xy 361.795925 -221.646079)
			(xy 361.843665 -221.629089) (xy 361.868466 -221.62389) (xy 361.891326 -221.619572) (xy 362.096304 -221.26448)
			(xy 362.088684 -221.242382) (xy 362.080164 -221.216211) (xy 362.070971 -221.161949) (xy 362.070396 -221.134432)
			(xy 362.070396 -221.133924) (xy 362.070904 -221.108037) (xy 362.079003 -221.056899) (xy 362.095002 -221.007659)
			(xy 362.118508 -220.961527) (xy 362.14894 -220.91964) (xy 362.18555 -220.88303) (xy 362.227437 -220.852598)
			(xy 362.273569 -220.829092) (xy 362.322809 -220.813093) (xy 362.373947 -220.804994) (xy 362.425721 -220.804994)
			(xy 362.476859 -220.813093) (xy 362.526099 -220.829092) (xy 362.572231 -220.852598) (xy 362.614118 -220.88303)
			(xy 362.650728 -220.91964) (xy 362.68116 -220.961527) (xy 362.704666 -221.007659) (xy 362.720665 -221.056899)
			(xy 362.728764 -221.108037) (xy 362.729272 -221.133924) (xy 362.728879 -221.159291) (xy 362.721126 -221.209429)
			(xy 362.705775 -221.257784) (xy 362.683191 -221.303213) (xy 362.653906 -221.344642) (xy 362.618615 -221.381089)
			(xy 362.578152 -221.411694) (xy 362.533474 -221.435731) (xy 362.485638 -221.452632) (xy 362.460794 -221.457774)
			(xy 362.437934 -221.462092) (xy 362.23321 -221.81693) (xy 362.241084 -221.838774) (xy 362.249681 -221.865188)
			(xy 362.258866 -221.919967) (xy 362.259372 -221.94774) (xy 362.258864 -221.973627) (xy 362.250765 -222.024765)
			(xy 362.234766 -222.074005) (xy 362.21126 -222.120137) (xy 362.180828 -222.162024) (xy 362.144218 -222.198634)
			(xy 362.102331 -222.229066) (xy 362.056199 -222.252572) (xy 362.006959 -222.268571) (xy 361.955821 -222.27667)
			(xy 361.904047 -222.27667) (xy 361.852909 -222.268571) (xy 361.803669 -222.252572) (xy 361.757537 -222.229066)
			(xy 361.71565 -222.198634) (xy 361.67904 -222.162024) (xy 361.648608 -222.120137) (xy 361.625102 -222.074005)
			(xy 361.609103 -222.024765) (xy 361.601004 -221.973627) (xy 361.600496 -221.94774) (xy 360.379772 -221.94774)
			(xy 360.379264 -221.973647) (xy 360.371158 -222.024824) (xy 360.355146 -222.074103) (xy 360.331623 -222.12027)
			(xy 360.301167 -222.162189) (xy 360.264529 -222.198827) (xy 360.22261 -222.229283) (xy 360.176443 -222.252806)
			(xy 360.127164 -222.268818) (xy 360.075987 -222.276924) (xy 360.024173 -222.276924) (xy 359.972996 -222.268818)
			(xy 359.923717 -222.252806) (xy 359.87755 -222.229283) (xy 359.835631 -222.198827) (xy 359.798993 -222.162189)
			(xy 359.768537 -222.12027) (xy 359.745014 -222.074103) (xy 359.729002 -222.024824) (xy 359.720896 -221.973647)
			(xy 359.720388 -221.94774) (xy 358.500172 -221.94774) (xy 358.499664 -221.973627) (xy 358.491565 -222.024765)
			(xy 358.475566 -222.074005) (xy 358.45206 -222.120137) (xy 358.421628 -222.162024) (xy 358.385018 -222.198634)
			(xy 358.343131 -222.229066) (xy 358.296999 -222.252572) (xy 358.247759 -222.268571) (xy 358.196621 -222.27667)
			(xy 358.144847 -222.27667) (xy 358.093709 -222.268571) (xy 358.044469 -222.252572) (xy 357.998337 -222.229066)
			(xy 357.95645 -222.198634) (xy 357.91984 -222.162024) (xy 357.889408 -222.120137) (xy 357.865902 -222.074005)
			(xy 357.849903 -222.024765) (xy 357.841804 -221.973627) (xy 357.841296 -221.94774) (xy 356.620572 -221.94774)
			(xy 356.620064 -221.973647) (xy 356.611958 -222.024824) (xy 356.595946 -222.074103) (xy 356.572423 -222.12027)
			(xy 356.541967 -222.162189) (xy 356.505329 -222.198827) (xy 356.46341 -222.229283) (xy 356.417243 -222.252806)
			(xy 356.367964 -222.268818) (xy 356.316787 -222.276924) (xy 356.264973 -222.276924) (xy 356.213796 -222.268818)
			(xy 356.164517 -222.252806) (xy 356.11835 -222.229283) (xy 356.076431 -222.198827) (xy 356.039793 -222.162189)
			(xy 356.009337 -222.12027) (xy 355.985814 -222.074103) (xy 355.969802 -222.024824) (xy 355.961696 -221.973647)
			(xy 355.961188 -221.94774) (xy 354.740972 -221.94774) (xy 354.740464 -221.973647) (xy 354.732358 -222.024824)
			(xy 354.716346 -222.074103) (xy 354.692823 -222.12027) (xy 354.662367 -222.162189) (xy 354.625729 -222.198827)
			(xy 354.58381 -222.229283) (xy 354.537643 -222.252806) (xy 354.488364 -222.268818) (xy 354.437187 -222.276924)
			(xy 354.385373 -222.276924) (xy 354.334196 -222.268818) (xy 354.284917 -222.252806) (xy 354.23875 -222.229283)
			(xy 354.196831 -222.198827) (xy 354.160193 -222.162189) (xy 354.129737 -222.12027) (xy 354.106214 -222.074103)
			(xy 354.090202 -222.024824) (xy 354.082096 -221.973647) (xy 354.081588 -221.94774) (xy 352.861372 -221.94774)
			(xy 352.860861 -221.973645) (xy 352.85275 -222.024815) (xy 352.836735 -222.074087) (xy 352.813209 -222.120248)
			(xy 352.782752 -222.162159) (xy 352.746114 -222.198791) (xy 352.704196 -222.22924) (xy 352.658032 -222.252758)
			(xy 352.608757 -222.268764) (xy 352.557585 -222.276865) (xy 352.53168 -222.277432) (xy 352.504501 -222.276907)
			(xy 352.450883 -222.267965) (xy 352.425 -222.259652) (xy 352.411797 -222.255649) (xy 352.384264 -222.254087)
			(xy 352.357316 -222.25995) (xy 352.332919 -222.272808) (xy 352.312852 -222.291725) (xy 352.298578 -222.315321)
			(xy 352.291138 -222.341876) (xy 352.290634 -222.355664) (xy 352.290634 -222.526098) (xy 352.309126 -222.544773)
			(xy 352.340518 -222.58692) (xy 352.364793 -222.63353) (xy 352.381331 -222.683413) (xy 352.389709 -222.735293)
			(xy 352.389714 -222.787846) (xy 352.381346 -222.839728) (xy 352.364817 -222.889614) (xy 352.340551 -222.936228)
			(xy 352.309167 -222.978381) (xy 352.290634 -222.997014) (xy 352.290634 -224.151952) (xy 352.309364 -224.170741)
			(xy 352.341168 -224.213199) (xy 352.365755 -224.260206) (xy 352.382489 -224.310546) (xy 352.390938 -224.362917)
			(xy 352.391472 -224.389442) (xy 352.672396 -224.389442) (xy 352.672829 -224.364106) (xy 352.68059 -224.314032)
			(xy 352.69592 -224.265734) (xy 352.718459 -224.22035) (xy 352.747675 -224.178949) (xy 352.782881 -224.142504)
			(xy 352.823248 -224.111874) (xy 352.867826 -224.087781) (xy 352.915565 -224.070791) (xy 352.940366 -224.065592)
			(xy 352.963226 -224.061274) (xy 353.16795 -223.706436) (xy 353.16033 -223.684338) (xy 353.151702 -223.657991)
			(xy 353.142379 -223.603344) (xy 353.141788 -223.575626) (xy 353.142296 -223.549719) (xy 353.150402 -223.498542)
			(xy 353.166414 -223.449263) (xy 353.189937 -223.403096) (xy 353.220393 -223.361177) (xy 353.257031 -223.324539)
			(xy 353.29895 -223.294083) (xy 353.345117 -223.27056) (xy 353.394396 -223.254548) (xy 353.445573 -223.246442)
			(xy 353.497387 -223.246442) (xy 353.548564 -223.254548) (xy 353.597843 -223.27056) (xy 353.64401 -223.294083)
			(xy 353.685929 -223.324539) (xy 353.722567 -223.361177) (xy 353.753023 -223.403096) (xy 353.776546 -223.449263)
			(xy 353.792558 -223.498542) (xy 353.800664 -223.549719) (xy 353.801172 -223.575626) (xy 353.800781 -223.600993)
			(xy 353.793028 -223.651131) (xy 353.777677 -223.699486) (xy 353.755092 -223.744915) (xy 353.725807 -223.786344)
			(xy 353.690516 -223.822791) (xy 353.650052 -223.853396) (xy 353.605374 -223.877433) (xy 353.557539 -223.894334)
			(xy 353.532694 -223.899476) (xy 353.509834 -223.903794) (xy 353.30511 -224.258632) (xy 353.312984 -224.280476)
			(xy 353.321557 -224.306897) (xy 353.330758 -224.36167) (xy 353.331272 -224.389442) (xy 353.612196 -224.389442)
			(xy 353.612704 -224.363555) (xy 353.620803 -224.312417) (xy 353.636802 -224.263177) (xy 353.660308 -224.217045)
			(xy 353.69074 -224.175158) (xy 353.72735 -224.138548) (xy 353.769237 -224.108116) (xy 353.815369 -224.08461)
			(xy 353.864609 -224.068611) (xy 353.915747 -224.060512) (xy 353.967521 -224.060512) (xy 354.018659 -224.068611)
			(xy 354.067899 -224.08461) (xy 354.114031 -224.108116) (xy 354.155918 -224.138548) (xy 354.192528 -224.175158)
			(xy 354.22296 -224.217045) (xy 354.246466 -224.263177) (xy 354.262465 -224.312417) (xy 354.270564 -224.363555)
			(xy 354.271072 -224.389442) (xy 354.551996 -224.389442) (xy 354.552429 -224.364106) (xy 354.56019 -224.314032)
			(xy 354.57552 -224.265734) (xy 354.598059 -224.22035) (xy 354.627275 -224.178949) (xy 354.662481 -224.142504)
			(xy 354.702848 -224.111874) (xy 354.747426 -224.087781) (xy 354.795165 -224.070791) (xy 354.819966 -224.065592)
			(xy 354.842826 -224.061274) (xy 355.04755 -223.706436) (xy 355.03993 -223.684338) (xy 355.031302 -223.657991)
			(xy 355.021979 -223.603344) (xy 355.021388 -223.575626) (xy 355.021896 -223.549719) (xy 355.030002 -223.498542)
			(xy 355.046014 -223.449263) (xy 355.069537 -223.403096) (xy 355.099993 -223.361177) (xy 355.136631 -223.324539)
			(xy 355.17855 -223.294083) (xy 355.224717 -223.27056) (xy 355.273996 -223.254548) (xy 355.325173 -223.246442)
			(xy 355.376987 -223.246442) (xy 355.428164 -223.254548) (xy 355.477443 -223.27056) (xy 355.52361 -223.294083)
			(xy 355.565529 -223.324539) (xy 355.602167 -223.361177) (xy 355.632623 -223.403096) (xy 355.656146 -223.449263)
			(xy 355.672158 -223.498542) (xy 355.680264 -223.549719) (xy 355.680772 -223.575626) (xy 355.680381 -223.600993)
			(xy 355.672628 -223.651131) (xy 355.657277 -223.699486) (xy 355.634692 -223.744915) (xy 355.605407 -223.786344)
			(xy 355.570116 -223.822791) (xy 355.529652 -223.853396) (xy 355.484974 -223.877433) (xy 355.437139 -223.894334)
			(xy 355.412294 -223.899476) (xy 355.389434 -223.903794) (xy 355.18471 -224.258632) (xy 355.192584 -224.280476)
			(xy 355.201157 -224.306897) (xy 355.210358 -224.36167) (xy 355.210872 -224.389442) (xy 355.491796 -224.389442)
			(xy 355.492304 -224.363555) (xy 355.500403 -224.312417) (xy 355.516402 -224.263177) (xy 355.539908 -224.217045)
			(xy 355.57034 -224.175158) (xy 355.60695 -224.138548) (xy 355.648837 -224.108116) (xy 355.694969 -224.08461)
			(xy 355.744209 -224.068611) (xy 355.795347 -224.060512) (xy 355.847121 -224.060512) (xy 355.898259 -224.068611)
			(xy 355.947499 -224.08461) (xy 355.993631 -224.108116) (xy 356.035518 -224.138548) (xy 356.072128 -224.175158)
			(xy 356.10256 -224.217045) (xy 356.126066 -224.263177) (xy 356.142065 -224.312417) (xy 356.150164 -224.363555)
			(xy 356.150672 -224.389442) (xy 356.431596 -224.389442) (xy 356.432029 -224.364106) (xy 356.43979 -224.314032)
			(xy 356.45512 -224.265734) (xy 356.477659 -224.22035) (xy 356.506875 -224.178949) (xy 356.542081 -224.142504)
			(xy 356.582448 -224.111874) (xy 356.627026 -224.087781) (xy 356.674765 -224.070791) (xy 356.699566 -224.065592)
			(xy 356.722426 -224.061274) (xy 356.92715 -223.706436) (xy 356.91953 -223.684338) (xy 356.910902 -223.657991)
			(xy 356.901579 -223.603344) (xy 356.900988 -223.575626) (xy 356.901496 -223.549719) (xy 356.909602 -223.498542)
			(xy 356.925614 -223.449263) (xy 356.949137 -223.403096) (xy 356.979593 -223.361177) (xy 357.016231 -223.324539)
			(xy 357.05815 -223.294083) (xy 357.104317 -223.27056) (xy 357.153596 -223.254548) (xy 357.204773 -223.246442)
			(xy 357.256587 -223.246442) (xy 357.307764 -223.254548) (xy 357.357043 -223.27056) (xy 357.40321 -223.294083)
			(xy 357.445129 -223.324539) (xy 357.481767 -223.361177) (xy 357.512223 -223.403096) (xy 357.535746 -223.449263)
			(xy 357.551758 -223.498542) (xy 357.559864 -223.549719) (xy 357.560372 -223.575626) (xy 357.559981 -223.600993)
			(xy 357.552228 -223.651131) (xy 357.536877 -223.699486) (xy 357.514292 -223.744915) (xy 357.485007 -223.786344)
			(xy 357.449716 -223.822791) (xy 357.409252 -223.853396) (xy 357.364574 -223.877433) (xy 357.316739 -223.894334)
			(xy 357.291894 -223.899476) (xy 357.269034 -223.903794) (xy 357.06431 -224.258632) (xy 357.072184 -224.280476)
			(xy 357.080757 -224.306897) (xy 357.089958 -224.36167) (xy 357.090472 -224.389442) (xy 357.371396 -224.389442)
			(xy 357.371904 -224.363555) (xy 357.380003 -224.312417) (xy 357.396002 -224.263177) (xy 357.419508 -224.217045)
			(xy 357.44994 -224.175158) (xy 357.48655 -224.138548) (xy 357.528437 -224.108116) (xy 357.574569 -224.08461)
			(xy 357.623809 -224.068611) (xy 357.674947 -224.060512) (xy 357.726721 -224.060512) (xy 357.777859 -224.068611)
			(xy 357.827099 -224.08461) (xy 357.873231 -224.108116) (xy 357.915118 -224.138548) (xy 357.951728 -224.175158)
			(xy 357.98216 -224.217045) (xy 358.005666 -224.263177) (xy 358.021665 -224.312417) (xy 358.029764 -224.363555)
			(xy 358.030272 -224.389442) (xy 358.311196 -224.389442) (xy 358.311629 -224.364106) (xy 358.31939 -224.314032)
			(xy 358.33472 -224.265734) (xy 358.357259 -224.22035) (xy 358.386475 -224.178949) (xy 358.421681 -224.142504)
			(xy 358.462048 -224.111874) (xy 358.506626 -224.087781) (xy 358.554365 -224.070791) (xy 358.579166 -224.065592)
			(xy 358.602026 -224.061274) (xy 358.80675 -223.706436) (xy 358.79913 -223.684338) (xy 358.790502 -223.657991)
			(xy 358.781179 -223.603344) (xy 358.780588 -223.575626) (xy 358.781096 -223.549719) (xy 358.789202 -223.498542)
			(xy 358.805214 -223.449263) (xy 358.828737 -223.403096) (xy 358.859193 -223.361177) (xy 358.895831 -223.324539)
			(xy 358.93775 -223.294083) (xy 358.983917 -223.27056) (xy 359.033196 -223.254548) (xy 359.084373 -223.246442)
			(xy 359.136187 -223.246442) (xy 359.187364 -223.254548) (xy 359.236643 -223.27056) (xy 359.28281 -223.294083)
			(xy 359.324729 -223.324539) (xy 359.361367 -223.361177) (xy 359.391823 -223.403096) (xy 359.415346 -223.449263)
			(xy 359.431358 -223.498542) (xy 359.439464 -223.549719) (xy 359.439972 -223.575626) (xy 359.439581 -223.600993)
			(xy 359.431828 -223.651131) (xy 359.416477 -223.699486) (xy 359.393892 -223.744915) (xy 359.364607 -223.786344)
			(xy 359.329316 -223.822791) (xy 359.288852 -223.853396) (xy 359.244174 -223.877433) (xy 359.196339 -223.894334)
			(xy 359.171494 -223.899476) (xy 359.148634 -223.903794) (xy 358.94391 -224.258632) (xy 358.951784 -224.280476)
			(xy 358.960357 -224.306897) (xy 358.969558 -224.36167) (xy 358.970072 -224.389442) (xy 359.250996 -224.389442)
			(xy 359.251504 -224.363555) (xy 359.259603 -224.312417) (xy 359.275602 -224.263177) (xy 359.299108 -224.217045)
			(xy 359.32954 -224.175158) (xy 359.36615 -224.138548) (xy 359.408037 -224.108116) (xy 359.454169 -224.08461)
			(xy 359.503409 -224.068611) (xy 359.554547 -224.060512) (xy 359.606321 -224.060512) (xy 359.657459 -224.068611)
			(xy 359.706699 -224.08461) (xy 359.752831 -224.108116) (xy 359.794718 -224.138548) (xy 359.831328 -224.175158)
			(xy 359.86176 -224.217045) (xy 359.885266 -224.263177) (xy 359.901265 -224.312417) (xy 359.909364 -224.363555)
			(xy 359.909872 -224.389442) (xy 360.190796 -224.389442) (xy 360.191229 -224.364106) (xy 360.19899 -224.314032)
			(xy 360.21432 -224.265734) (xy 360.236859 -224.22035) (xy 360.266075 -224.178949) (xy 360.301281 -224.142504)
			(xy 360.341648 -224.111874) (xy 360.386226 -224.087781) (xy 360.433965 -224.070791) (xy 360.458766 -224.065592)
			(xy 360.481626 -224.061274) (xy 360.68635 -223.706436) (xy 360.67873 -223.684338) (xy 360.670102 -223.657991)
			(xy 360.660779 -223.603344) (xy 360.660188 -223.575626) (xy 360.660696 -223.549719) (xy 360.668802 -223.498542)
			(xy 360.684814 -223.449263) (xy 360.708337 -223.403096) (xy 360.738793 -223.361177) (xy 360.775431 -223.324539)
			(xy 360.81735 -223.294083) (xy 360.863517 -223.27056) (xy 360.912796 -223.254548) (xy 360.963973 -223.246442)
			(xy 361.015787 -223.246442) (xy 361.066964 -223.254548) (xy 361.116243 -223.27056) (xy 361.16241 -223.294083)
			(xy 361.204329 -223.324539) (xy 361.240967 -223.361177) (xy 361.271423 -223.403096) (xy 361.294946 -223.449263)
			(xy 361.310958 -223.498542) (xy 361.319064 -223.549719) (xy 361.319572 -223.575626) (xy 361.319181 -223.600993)
			(xy 361.311428 -223.651131) (xy 361.296077 -223.699486) (xy 361.273492 -223.744915) (xy 361.244207 -223.786344)
			(xy 361.208916 -223.822791) (xy 361.168452 -223.853396) (xy 361.123774 -223.877433) (xy 361.075939 -223.894334)
			(xy 361.051094 -223.899476) (xy 361.028234 -223.903794) (xy 360.82351 -224.258632) (xy 360.831384 -224.280476)
			(xy 360.839957 -224.306897) (xy 360.849158 -224.36167) (xy 360.849672 -224.389442) (xy 361.130596 -224.389442)
			(xy 361.131104 -224.363555) (xy 361.139203 -224.312417) (xy 361.155202 -224.263177) (xy 361.178708 -224.217045)
			(xy 361.20914 -224.175158) (xy 361.24575 -224.138548) (xy 361.287637 -224.108116) (xy 361.333769 -224.08461)
			(xy 361.383009 -224.068611) (xy 361.434147 -224.060512) (xy 361.485921 -224.060512) (xy 361.537059 -224.068611)
			(xy 361.586299 -224.08461) (xy 361.632431 -224.108116) (xy 361.674318 -224.138548) (xy 361.710928 -224.175158)
			(xy 361.74136 -224.217045) (xy 361.764866 -224.263177) (xy 361.780865 -224.312417) (xy 361.788964 -224.363555)
			(xy 361.789472 -224.389442) (xy 361.788925 -224.417149) (xy 361.779741 -224.471796) (xy 361.771184 -224.498154)
			(xy 361.76331 -224.520252) (xy 361.968288 -224.87509) (xy 361.991148 -224.879408) (xy 362.015971 -224.884565)
			(xy 362.063751 -224.90152) (xy 362.108371 -224.925592) (xy 362.148778 -224.956214) (xy 362.184019 -224.992662)
			(xy 362.213263 -225.034077) (xy 362.235819 -225.079482) (xy 362.251156 -225.127806) (xy 362.258911 -225.177908)
			(xy 362.259372 -225.203258) (xy 362.258864 -225.229165) (xy 362.250758 -225.280342) (xy 362.234746 -225.329621)
			(xy 362.211223 -225.375788) (xy 362.180767 -225.417707) (xy 362.144129 -225.454345) (xy 362.10221 -225.484801)
			(xy 362.056043 -225.508324) (xy 362.006764 -225.524336) (xy 361.955587 -225.532442) (xy 361.903773 -225.532442)
			(xy 361.852596 -225.524336) (xy 361.803317 -225.508324) (xy 361.75715 -225.484801) (xy 361.715231 -225.454345)
			(xy 361.678593 -225.417707) (xy 361.648137 -225.375788) (xy 361.624614 -225.329621) (xy 361.608602 -225.280342)
			(xy 361.600496 -225.229165) (xy 361.599988 -225.203258) (xy 361.600597 -225.175541) (xy 361.60991 -225.120895)
			(xy 361.61853 -225.094546) (xy 361.626404 -225.072448) (xy 361.421426 -224.71761) (xy 361.398566 -224.713292)
			(xy 361.373748 -224.708169) (xy 361.326005 -224.691172) (xy 361.281426 -224.667071) (xy 361.24106 -224.636431)
			(xy 361.205857 -224.599976) (xy 361.176648 -224.558564) (xy 361.154119 -224.51317) (xy 361.138801 -224.464863)
			(xy 361.131055 -224.414781) (xy 361.130596 -224.389442) (xy 360.849672 -224.389442) (xy 360.849164 -224.415329)
			(xy 360.841065 -224.466467) (xy 360.825066 -224.515707) (xy 360.80156 -224.561839) (xy 360.771128 -224.603726)
			(xy 360.734518 -224.640336) (xy 360.692631 -224.670768) (xy 360.646499 -224.694274) (xy 360.597259 -224.710273)
			(xy 360.546121 -224.718372) (xy 360.494347 -224.718372) (xy 360.443209 -224.710273) (xy 360.393969 -224.694274)
			(xy 360.347837 -224.670768) (xy 360.30595 -224.640336) (xy 360.26934 -224.603726) (xy 360.238908 -224.561839)
			(xy 360.215402 -224.515707) (xy 360.199403 -224.466467) (xy 360.191304 -224.415329) (xy 360.190796 -224.389442)
			(xy 359.909872 -224.389442) (xy 359.909325 -224.417149) (xy 359.900141 -224.471796) (xy 359.891584 -224.498154)
			(xy 359.88371 -224.520252) (xy 360.088688 -224.87509) (xy 360.111548 -224.879408) (xy 360.136371 -224.884565)
			(xy 360.184151 -224.90152) (xy 360.228771 -224.925592) (xy 360.269178 -224.956214) (xy 360.304419 -224.992662)
			(xy 360.333663 -225.034077) (xy 360.356219 -225.079482) (xy 360.371556 -225.127806) (xy 360.379311 -225.177908)
			(xy 360.379772 -225.203258) (xy 360.379264 -225.229165) (xy 360.371158 -225.280342) (xy 360.355146 -225.329621)
			(xy 360.331623 -225.375788) (xy 360.301167 -225.417707) (xy 360.264529 -225.454345) (xy 360.22261 -225.484801)
			(xy 360.176443 -225.508324) (xy 360.127164 -225.524336) (xy 360.075987 -225.532442) (xy 360.024173 -225.532442)
			(xy 359.972996 -225.524336) (xy 359.923717 -225.508324) (xy 359.87755 -225.484801) (xy 359.835631 -225.454345)
			(xy 359.798993 -225.417707) (xy 359.768537 -225.375788) (xy 359.745014 -225.329621) (xy 359.729002 -225.280342)
			(xy 359.720896 -225.229165) (xy 359.720388 -225.203258) (xy 359.720997 -225.175541) (xy 359.73031 -225.120895)
			(xy 359.73893 -225.094546) (xy 359.746804 -225.072448) (xy 359.541826 -224.71761) (xy 359.518966 -224.713292)
			(xy 359.494148 -224.708169) (xy 359.446405 -224.691172) (xy 359.401826 -224.667071) (xy 359.36146 -224.636431)
			(xy 359.326257 -224.599976) (xy 359.297048 -224.558564) (xy 359.274519 -224.51317) (xy 359.259201 -224.464863)
			(xy 359.251455 -224.414781) (xy 359.250996 -224.389442) (xy 358.970072 -224.389442) (xy 358.969564 -224.415329)
			(xy 358.961465 -224.466467) (xy 358.945466 -224.515707) (xy 358.92196 -224.561839) (xy 358.891528 -224.603726)
			(xy 358.854918 -224.640336) (xy 358.813031 -224.670768) (xy 358.766899 -224.694274) (xy 358.717659 -224.710273)
			(xy 358.666521 -224.718372) (xy 358.614747 -224.718372) (xy 358.563609 -224.710273) (xy 358.514369 -224.694274)
			(xy 358.468237 -224.670768) (xy 358.42635 -224.640336) (xy 358.38974 -224.603726) (xy 358.359308 -224.561839)
			(xy 358.335802 -224.515707) (xy 358.319803 -224.466467) (xy 358.311704 -224.415329) (xy 358.311196 -224.389442)
			(xy 358.030272 -224.389442) (xy 358.029725 -224.417149) (xy 358.020541 -224.471796) (xy 358.011984 -224.498154)
			(xy 358.00411 -224.520252) (xy 358.209088 -224.87509) (xy 358.231948 -224.879408) (xy 358.256771 -224.884565)
			(xy 358.304551 -224.90152) (xy 358.349171 -224.925592) (xy 358.389578 -224.956214) (xy 358.424819 -224.992662)
			(xy 358.454063 -225.034077) (xy 358.476619 -225.079482) (xy 358.491956 -225.127806) (xy 358.499711 -225.177908)
			(xy 358.500172 -225.203258) (xy 358.499664 -225.229165) (xy 358.491558 -225.280342) (xy 358.475546 -225.329621)
			(xy 358.452023 -225.375788) (xy 358.421567 -225.417707) (xy 358.384929 -225.454345) (xy 358.34301 -225.484801)
			(xy 358.296843 -225.508324) (xy 358.247564 -225.524336) (xy 358.196387 -225.532442) (xy 358.144573 -225.532442)
			(xy 358.093396 -225.524336) (xy 358.044117 -225.508324) (xy 357.99795 -225.484801) (xy 357.956031 -225.454345)
			(xy 357.919393 -225.417707) (xy 357.888937 -225.375788) (xy 357.865414 -225.329621) (xy 357.849402 -225.280342)
			(xy 357.841296 -225.229165) (xy 357.840788 -225.203258) (xy 357.841397 -225.175541) (xy 357.85071 -225.120895)
			(xy 357.85933 -225.094546) (xy 357.867204 -225.072448) (xy 357.662226 -224.71761) (xy 357.639366 -224.713292)
			(xy 357.614548 -224.708169) (xy 357.566805 -224.691172) (xy 357.522226 -224.667071) (xy 357.48186 -224.636431)
			(xy 357.446657 -224.599976) (xy 357.417448 -224.558564) (xy 357.394919 -224.51317) (xy 357.379601 -224.464863)
			(xy 357.371855 -224.414781) (xy 357.371396 -224.389442) (xy 357.090472 -224.389442) (xy 357.089964 -224.415329)
			(xy 357.081865 -224.466467) (xy 357.065866 -224.515707) (xy 357.04236 -224.561839) (xy 357.011928 -224.603726)
			(xy 356.975318 -224.640336) (xy 356.933431 -224.670768) (xy 356.887299 -224.694274) (xy 356.838059 -224.710273)
			(xy 356.786921 -224.718372) (xy 356.735147 -224.718372) (xy 356.684009 -224.710273) (xy 356.634769 -224.694274)
			(xy 356.588637 -224.670768) (xy 356.54675 -224.640336) (xy 356.51014 -224.603726) (xy 356.479708 -224.561839)
			(xy 356.456202 -224.515707) (xy 356.440203 -224.466467) (xy 356.432104 -224.415329) (xy 356.431596 -224.389442)
			(xy 356.150672 -224.389442) (xy 356.150125 -224.417149) (xy 356.140941 -224.471796) (xy 356.132384 -224.498154)
			(xy 356.12451 -224.520252) (xy 356.329488 -224.87509) (xy 356.352348 -224.879408) (xy 356.377171 -224.884565)
			(xy 356.424951 -224.90152) (xy 356.469571 -224.925592) (xy 356.509978 -224.956214) (xy 356.545219 -224.992662)
			(xy 356.574463 -225.034077) (xy 356.597019 -225.079482) (xy 356.612356 -225.127806) (xy 356.620111 -225.177908)
			(xy 356.620572 -225.203258) (xy 356.620064 -225.229165) (xy 356.611958 -225.280342) (xy 356.595946 -225.329621)
			(xy 356.572423 -225.375788) (xy 356.541967 -225.417707) (xy 356.505329 -225.454345) (xy 356.46341 -225.484801)
			(xy 356.417243 -225.508324) (xy 356.367964 -225.524336) (xy 356.316787 -225.532442) (xy 356.264973 -225.532442)
			(xy 356.213796 -225.524336) (xy 356.164517 -225.508324) (xy 356.11835 -225.484801) (xy 356.076431 -225.454345)
			(xy 356.039793 -225.417707) (xy 356.009337 -225.375788) (xy 355.985814 -225.329621) (xy 355.969802 -225.280342)
			(xy 355.961696 -225.229165) (xy 355.961188 -225.203258) (xy 355.961797 -225.175541) (xy 355.97111 -225.120895)
			(xy 355.97973 -225.094546) (xy 355.987604 -225.072448) (xy 355.782626 -224.71761) (xy 355.759766 -224.713292)
			(xy 355.734948 -224.708169) (xy 355.687205 -224.691172) (xy 355.642626 -224.667071) (xy 355.60226 -224.636431)
			(xy 355.567057 -224.599976) (xy 355.537848 -224.558564) (xy 355.515319 -224.51317) (xy 355.500001 -224.464863)
			(xy 355.492255 -224.414781) (xy 355.491796 -224.389442) (xy 355.210872 -224.389442) (xy 355.210364 -224.415329)
			(xy 355.202265 -224.466467) (xy 355.186266 -224.515707) (xy 355.16276 -224.561839) (xy 355.132328 -224.603726)
			(xy 355.095718 -224.640336) (xy 355.053831 -224.670768) (xy 355.007699 -224.694274) (xy 354.958459 -224.710273)
			(xy 354.907321 -224.718372) (xy 354.855547 -224.718372) (xy 354.804409 -224.710273) (xy 354.755169 -224.694274)
			(xy 354.709037 -224.670768) (xy 354.66715 -224.640336) (xy 354.63054 -224.603726) (xy 354.600108 -224.561839)
			(xy 354.576602 -224.515707) (xy 354.560603 -224.466467) (xy 354.552504 -224.415329) (xy 354.551996 -224.389442)
			(xy 354.271072 -224.389442) (xy 354.270525 -224.417149) (xy 354.261341 -224.471796) (xy 354.252784 -224.498154)
			(xy 354.24491 -224.520252) (xy 354.449888 -224.87509) (xy 354.472748 -224.879408) (xy 354.497571 -224.884565)
			(xy 354.545351 -224.90152) (xy 354.589971 -224.925592) (xy 354.630378 -224.956214) (xy 354.665619 -224.992662)
			(xy 354.694863 -225.034077) (xy 354.717419 -225.079482) (xy 354.732756 -225.127806) (xy 354.740511 -225.177908)
			(xy 354.740972 -225.203258) (xy 354.740464 -225.229165) (xy 354.732358 -225.280342) (xy 354.716346 -225.329621)
			(xy 354.692823 -225.375788) (xy 354.662367 -225.417707) (xy 354.625729 -225.454345) (xy 354.58381 -225.484801)
			(xy 354.537643 -225.508324) (xy 354.488364 -225.524336) (xy 354.437187 -225.532442) (xy 354.385373 -225.532442)
			(xy 354.334196 -225.524336) (xy 354.284917 -225.508324) (xy 354.23875 -225.484801) (xy 354.196831 -225.454345)
			(xy 354.160193 -225.417707) (xy 354.129737 -225.375788) (xy 354.106214 -225.329621) (xy 354.090202 -225.280342)
			(xy 354.082096 -225.229165) (xy 354.081588 -225.203258) (xy 354.082197 -225.175541) (xy 354.09151 -225.120895)
			(xy 354.10013 -225.094546) (xy 354.108004 -225.072448) (xy 353.903026 -224.71761) (xy 353.880166 -224.713292)
			(xy 353.855348 -224.708169) (xy 353.807605 -224.691172) (xy 353.763026 -224.667071) (xy 353.72266 -224.636431)
			(xy 353.687457 -224.599976) (xy 353.658248 -224.558564) (xy 353.635719 -224.51317) (xy 353.620401 -224.464863)
			(xy 353.612655 -224.414781) (xy 353.612196 -224.389442) (xy 353.331272 -224.389442) (xy 353.330764 -224.415329)
			(xy 353.322665 -224.466467) (xy 353.306666 -224.515707) (xy 353.28316 -224.561839) (xy 353.252728 -224.603726)
			(xy 353.216118 -224.640336) (xy 353.174231 -224.670768) (xy 353.128099 -224.694274) (xy 353.078859 -224.710273)
			(xy 353.027721 -224.718372) (xy 352.975947 -224.718372) (xy 352.924809 -224.710273) (xy 352.875569 -224.694274)
			(xy 352.829437 -224.670768) (xy 352.78755 -224.640336) (xy 352.75094 -224.603726) (xy 352.720508 -224.561839)
			(xy 352.697002 -224.515707) (xy 352.681003 -224.466467) (xy 352.672904 -224.415329) (xy 352.672396 -224.389442)
			(xy 352.391472 -224.389442) (xy 352.390948 -224.417151) (xy 352.381758 -224.4718) (xy 352.373184 -224.498154)
			(xy 352.36531 -224.520252) (xy 352.570288 -224.87509) (xy 352.593148 -224.879408) (xy 352.617962 -224.884594)
			(xy 352.66573 -224.901564) (xy 352.710338 -224.925644) (xy 352.750735 -224.956266) (xy 352.785972 -224.992709)
			(xy 352.815216 -225.034115) (xy 352.837781 -225.079509) (xy 352.853133 -225.12782) (xy 352.860911 -225.177912)
			(xy 352.861372 -225.203258) (xy 352.860893 -225.229163) (xy 352.85279 -225.280336) (xy 352.836779 -225.32961)
			(xy 352.813252 -225.375771) (xy 352.782791 -225.417681) (xy 352.746145 -225.454306) (xy 352.704219 -225.484745)
			(xy 352.658046 -225.508247) (xy 352.608763 -225.524232) (xy 352.557585 -225.532307) (xy 352.53168 -225.532696)
			(xy 352.504509 -225.532238) (xy 352.450888 -225.523432) (xy 352.425 -225.51517) (xy 352.411798 -225.511167)
			(xy 352.384266 -225.509604) (xy 352.357319 -225.515466) (xy 352.332924 -225.528325) (xy 352.31286 -225.547243)
			(xy 352.298589 -225.57084) (xy 352.291153 -225.597395) (xy 352.290634 -225.611182) (xy 352.290634 -225.78187)
			(xy 352.309121 -225.800545) (xy 352.340501 -225.84269) (xy 352.364765 -225.889296) (xy 352.381293 -225.939174)
			(xy 352.389662 -225.991047) (xy 352.389659 -226.043592) (xy 352.381283 -226.095464) (xy 352.36475 -226.14534)
			(xy 352.34048 -226.191944) (xy 352.309095 -226.234085) (xy 352.290634 -226.252786) (xy 352.290634 -227.409502)
			(xy 352.309124 -227.428176) (xy 352.34051 -227.47032) (xy 352.364777 -227.516928) (xy 352.381305 -227.566809)
			(xy 352.389672 -227.618686) (xy 352.390202 -227.64496) (xy 352.389726 -227.670753) (xy 352.381662 -227.721704)
			(xy 352.365727 -227.770766) (xy 352.342313 -227.816732) (xy 352.311997 -227.858469) (xy 352.275525 -227.894949)
			(xy 352.233795 -227.925275) (xy 352.187835 -227.948699) (xy 352.138776 -227.964645) (xy 352.087827 -227.97272)
			(xy 352.062034 -227.973128) (xy 352.025712 -227.971096) (xy 352.001582 -227.968302) (xy 350.01454 -229.955344)
			(xy 350.024192 -229.984808) (xy 350.031789 -230.009583) (xy 350.039952 -230.060753) (xy 350.040448 -230.086662)
			(xy 350.039972 -230.112453) (xy 350.031907 -230.163401) (xy 350.015972 -230.212459) (xy 349.992557 -230.258421)
			(xy 349.962239 -230.300153) (xy 349.925767 -230.336628) (xy 349.884036 -230.366947) (xy 349.838076 -230.390365)
			(xy 349.789018 -230.406303) (xy 349.738071 -230.41437) (xy 349.71228 -230.41483) (xy 349.686372 -230.414322)
			(xy 349.635203 -230.406161) (xy 349.610426 -230.398574) (xy 349.580962 -230.388922) (xy 348.14002 -231.829864)
			(xy 348.13621 -231.839262) (xy 348.125883 -231.863102) (xy 348.098819 -231.907448) (xy 348.065104 -231.946974)
			(xy 348.025582 -231.980694) (xy 347.98124 -232.007764) (xy 347.957394 -232.018078) (xy 347.947996 -232.021888)
			(xy 347.632528 -232.337356) (xy 347.650816 -232.37063) (xy 347.663517 -232.39496) (xy 347.681516 -232.446806)
			(xy 347.690637 -232.500923) (xy 347.691202 -232.528364) (xy 347.690725 -232.554156) (xy 347.682661 -232.605107)
			(xy 347.666726 -232.654169) (xy 347.643312 -232.700134) (xy 347.612996 -232.74187) (xy 347.576524 -232.77835)
			(xy 347.534794 -232.808675) (xy 347.488834 -232.832099) (xy 347.439775 -232.848045) (xy 347.388826 -232.85612)
			(xy 347.363034 -232.856532) (xy 347.335592 -232.855981) (xy 347.281473 -232.846858) (xy 347.229624 -232.828861)
			(xy 347.2053 -232.816146) (xy 347.172026 -232.797858) (xy 345.81211 -234.157774) (xy 345.81084 -234.176824)
			(xy 345.808667 -234.203098) (xy 345.796998 -234.254507) (xy 345.77726 -234.303388) (xy 345.749959 -234.348485)
			(xy 345.715798 -234.388635) (xy 345.675657 -234.422807) (xy 345.630568 -234.45012) (xy 345.581692 -234.469872)
			(xy 345.530286 -234.481554) (xy 345.504008 -234.483656) (xy 345.484958 -234.484926) (xy 344.926412 -235.043472)
			(xy 344.926412 -253.737364) (xy 344.939501 -253.757704) (xy 344.960201 -253.80142) (xy 344.974254 -253.847701)
			(xy 344.981356 -253.895546) (xy 344.981351 -253.943914) (xy 344.974241 -253.991757) (xy 344.96018 -254.038036)
			(xy 344.939472 -254.081748) (xy 344.926412 -254.102108) (xy 344.926412 -255.36525) (xy 344.939502 -255.38559)
			(xy 344.960204 -255.429306) (xy 344.974259 -255.475588) (xy 344.981363 -255.523433) (xy 344.98136 -255.571803)
			(xy 344.974251 -255.619647) (xy 344.960191 -255.665928) (xy 344.939484 -255.709641) (xy 344.926412 -255.729994)
			(xy 344.926412 -256.992882) (xy 344.939508 -257.013222) (xy 344.96022 -257.056939) (xy 344.974284 -257.103225)
			(xy 344.981397 -257.151074) (xy 344.981402 -257.199449) (xy 344.974301 -257.247301) (xy 344.960247 -257.293589)
			(xy 344.939546 -257.337311) (xy 344.926412 -257.357626) (xy 344.926412 -258.620768) (xy 344.939501 -258.641108)
			(xy 344.9602 -258.684823) (xy 344.974253 -258.731105) (xy 344.981354 -258.778949) (xy 344.981349 -258.827317)
			(xy 344.974238 -258.87516) (xy 344.960176 -258.921439) (xy 344.939468 -258.96515) (xy 344.926412 -258.985512)
			(xy 344.926412 -260.249162) (xy 344.93939 -260.269439) (xy 344.959903 -260.312991) (xy 344.973825 -260.359076)
			(xy 344.980857 -260.406701) (xy 344.981276 -260.430772) (xy 344.980768 -260.44906) (xy 344.979498 -260.471666)
			(xy 345.331288 -260.823456) (xy 350.3676 -260.823456) (xy 350.507808 -260.683248) (xy 350.511618 -260.67512)
			(xy 350.521692 -260.654226) (xy 350.546852 -260.615256) (xy 350.577249 -260.580219) (xy 350.612278 -260.549811)
			(xy 350.651239 -260.52464) (xy 350.672146 -260.514592) (xy 350.680274 -260.510782) (xy 350.777556 -260.4135)
			(xy 350.777556 -260.025896) (xy 350.737424 -260.01726) (xy 350.711882 -260.011232) (xy 350.662993 -259.992159)
			(xy 350.617762 -259.965548) (xy 350.577344 -259.932077) (xy 350.542769 -259.8926) (xy 350.514919 -259.848122)
			(xy 350.494503 -259.799778) (xy 350.482041 -259.748802) (xy 350.477853 -259.696491) (xy 350.482044 -259.644181)
			(xy 350.494508 -259.593205) (xy 350.514927 -259.544862) (xy 350.54278 -259.500386) (xy 350.577357 -259.46091)
			(xy 350.617777 -259.427442) (xy 350.663008 -259.400833) (xy 350.711899 -259.381763) (xy 350.737424 -259.375656)
			(xy 350.777556 -259.36702) (xy 350.777556 -256.135124) (xy 350.745552 -256.12217) (xy 350.723074 -256.112666)
			(xy 350.680975 -256.087982) (xy 350.642997 -256.057335) (xy 350.609974 -256.021403) (xy 350.582637 -255.980977)
			(xy 350.561588 -255.936948) (xy 350.547291 -255.890288) (xy 350.540061 -255.842025) (xy 350.539558 -255.817624)
			(xy 350.540004 -255.792916) (xy 350.547415 -255.744058) (xy 350.562073 -255.696865) (xy 350.583645 -255.652405)
			(xy 350.611644 -255.611686) (xy 350.628204 -255.593342) (xy 350.638252 -255.581837) (xy 350.651578 -255.554364)
			(xy 350.656193 -255.524181) (xy 350.651685 -255.493981) (xy 350.638456 -255.466462) (xy 350.628458 -255.454912)
			(xy 350.612021 -255.4366) (xy 350.58426 -255.395975) (xy 350.562875 -255.35166) (xy 350.548347 -255.304648)
			(xy 350.541002 -255.255995) (xy 350.540574 -255.231392) (xy 350.541018 -255.207037) (xy 350.548218 -255.158862)
			(xy 350.562459 -255.11228) (xy 350.583428 -255.068314) (xy 350.610664 -255.02793) (xy 350.643569 -254.992014)
			(xy 350.681421 -254.961356) (xy 350.723388 -254.936629) (xy 350.745806 -254.9271) (xy 350.777556 -254.9144)
			(xy 350.777556 -253.123954) (xy 350.741488 -253.113032) (xy 350.716482 -253.105016) (xy 350.669213 -253.08215)
			(xy 350.626193 -253.052042) (xy 350.588522 -253.015463) (xy 350.557162 -252.973348) (xy 350.532915 -252.926772)
			(xy 350.516401 -252.876928) (xy 350.508043 -252.825089) (xy 350.507554 -252.798834) (xy 350.508014 -252.774306)
			(xy 350.515321 -252.725796) (xy 350.529761 -252.678912) (xy 350.551014 -252.634698) (xy 350.578607 -252.594136)
			(xy 350.59493 -252.575822) (xy 350.604926 -252.56431) (xy 350.618158 -252.536858) (xy 350.622709 -252.506725)
			(xy 350.618173 -252.47659) (xy 350.604954 -252.449131) (xy 350.59493 -252.437646) (xy 350.578596 -252.41934)
			(xy 350.550991 -252.378784) (xy 350.529736 -252.334568) (xy 350.515305 -252.287679) (xy 350.508021 -252.239164)
			(xy 350.507554 -252.214634) (xy 350.508076 -252.188383) (xy 350.516448 -252.136554) (xy 350.532969 -252.08672)
			(xy 350.557216 -252.040153) (xy 350.58857 -251.998042) (xy 350.626231 -251.961463) (xy 350.669237 -251.931349)
			(xy 350.716491 -251.908469) (xy 350.741488 -251.900436) (xy 350.777556 -251.889514) (xy 350.777556 -248.504456)
			(xy 350.778132 -248.479498) (xy 350.78788 -248.430542) (xy 350.806992 -248.384429) (xy 350.834735 -248.342932)
			(xy 350.851978 -248.324878) (xy 351.334578 -247.842278) (xy 351.35262 -247.82502) (xy 351.394114 -247.797266)
			(xy 351.440232 -247.778157) (xy 351.489195 -247.768431) (xy 351.514156 -247.767856) (xy 352.3234 -247.767856)
			(xy 352.809556 -247.2817) (xy 352.809556 -246.298212) (xy 352.6282 -246.116856) (xy 351.514156 -246.116856)
			(xy 351.489198 -246.11628) (xy 351.440242 -246.106533) (xy 351.394128 -246.087421) (xy 351.35263 -246.059679)
			(xy 351.334578 -246.042434) (xy 350.94291 -245.650766) (xy 350.915478 -245.657116) (xy 350.897133 -245.661123)
			(xy 350.859831 -245.665446) (xy 350.841056 -245.665752) (xy 350.815271 -245.665243) (xy 350.764337 -245.657169)
			(xy 350.715293 -245.641228) (xy 350.669347 -245.61781) (xy 350.627629 -245.587494) (xy 350.591167 -245.551025)
			(xy 350.560858 -245.509302) (xy 350.537449 -245.463351) (xy 350.521517 -245.414304) (xy 350.513452 -245.363369)
			(xy 350.512888 -245.337584) (xy 350.513345 -245.313054) (xy 350.520645 -245.264541) (xy 350.535081 -245.217654)
			(xy 350.556331 -245.173436) (xy 350.583923 -245.132871) (xy 350.600264 -245.114572) (xy 350.6102 -245.103026)
			(xy 350.623406 -245.075594) (xy 350.62794 -245.045488) (xy 350.623399 -245.015384) (xy 350.610187 -244.987955)
			(xy 350.600264 -244.976396) (xy 350.58393 -244.958089) (xy 350.556324 -244.917533) (xy 350.535067 -244.873318)
			(xy 350.520632 -244.826429) (xy 350.513342 -244.777914) (xy 350.512888 -244.753384) (xy 350.513406 -244.727117)
			(xy 350.521777 -244.675254) (xy 350.538302 -244.625386) (xy 350.56256 -244.578788) (xy 350.593931 -244.536649)
			(xy 350.631613 -244.500044) (xy 350.674645 -244.46991) (xy 350.698054 -244.457982) (xy 350.726756 -244.444012)
			(xy 350.726756 -241.235992) (xy 350.698816 -241.221768) (xy 350.675955 -241.209665) (xy 350.634028 -241.179373)
			(xy 350.597372 -241.14288) (xy 350.566895 -241.101087) (xy 350.543351 -241.055032) (xy 350.527323 -241.005853)
			(xy 350.519208 -240.954768) (xy 350.51873 -240.928906) (xy 350.519185 -240.904376) (xy 350.526483 -240.855862)
			(xy 350.540918 -240.808974) (xy 350.562169 -240.764755) (xy 350.589761 -240.72419) (xy 350.606106 -240.705894)
			(xy 350.6161 -240.694383) (xy 350.629327 -240.666934) (xy 350.633872 -240.636804) (xy 350.62933 -240.606675)
			(xy 350.616105 -240.579224) (xy 350.606106 -240.567718) (xy 350.589769 -240.549413) (xy 350.562157 -240.508858)
			(xy 350.540894 -240.464643) (xy 350.526454 -240.417754) (xy 350.51916 -240.369237) (xy 350.51873 -240.344706)
			(xy 350.519215 -240.318844) (xy 350.527328 -240.267759) (xy 350.543354 -240.21858) (xy 350.566897 -240.172524)
			(xy 350.597373 -240.130731) (xy 350.634028 -240.094237) (xy 350.675954 -240.063944) (xy 350.698816 -240.051844)
			(xy 350.726756 -240.03762) (xy 350.726756 -239.597946) (xy 350.704853 -239.5855) (xy 350.664777 -239.554982)
			(xy 350.629828 -239.518704) (xy 350.600825 -239.477517) (xy 350.578448 -239.432385) (xy 350.563222 -239.384368)
			(xy 350.555503 -239.334589) (xy 350.555052 -239.309402) (xy 350.555531 -239.283613) (xy 350.5636 -239.232669)
			(xy 350.579539 -239.183616) (xy 350.602956 -239.137659) (xy 350.633273 -239.095932) (xy 350.669746 -239.059462)
			(xy 350.711475 -239.029146) (xy 350.757432 -239.005732) (xy 350.806487 -238.989796) (xy 350.857431 -238.98173)
			(xy 350.88322 -238.981234) (xy 350.883728 -238.981234) (xy 350.915674 -238.98202) (xy 350.978351 -238.99443)
			(xy 351.008188 -239.005872) (xy 351.03943 -239.018826) (xy 352.147378 -237.910878) (xy 352.16542 -237.89362)
			(xy 352.206914 -237.865866) (xy 352.253032 -237.846757) (xy 352.301995 -237.837031) (xy 352.326956 -237.836456)
			(xy 356.290372 -237.836456) (xy 356.298754 -237.79607) (xy 356.304656 -237.770363) (xy 356.323547 -237.721121)
			(xy 356.35007 -237.675533) (xy 356.383541 -237.634774) (xy 356.423099 -237.599891) (xy 356.467726 -237.571782)
			(xy 356.516274 -237.551172) (xy 356.567492 -237.538589) (xy 356.620064 -237.534359) (xy 356.672636 -237.538589)
			(xy 356.723854 -237.551172) (xy 356.772402 -237.571782) (xy 356.817029 -237.599891) (xy 356.856587 -237.634774)
			(xy 356.890058 -237.675533) (xy 356.916581 -237.721121) (xy 356.935472 -237.770363) (xy 356.941374 -237.79607)
			(xy 356.949756 -237.836456) (xy 363.274356 -237.836456) (xy 363.299314 -237.837033) (xy 363.348268 -237.846783)
			(xy 363.394379 -237.865897) (xy 363.435875 -237.893641) (xy 363.453934 -237.910878) (xy 363.961934 -238.418878)
			(xy 363.979192 -238.43692) (xy 364.006944 -238.478414) (xy 364.026052 -238.524532) (xy 364.035778 -238.573496)
			(xy 364.036356 -238.598456) (xy 364.036356 -239.9157) (xy 365.792512 -241.671856) (xy 368.405156 -241.671856)
			(xy 368.430114 -241.672433) (xy 368.479068 -241.682183) (xy 368.525179 -241.701297) (xy 368.566675 -241.729041)
			(xy 368.584734 -241.746278) (xy 369.143534 -242.305078) (xy 369.160792 -242.32312) (xy 369.188544 -242.364614)
			(xy 369.207652 -242.410732) (xy 369.217378 -242.459696) (xy 369.217956 -242.484656) (xy 369.217956 -243.322856)
			(xy 369.217379 -243.347814) (xy 369.20763 -243.396769) (xy 369.188516 -243.44288) (xy 369.160773 -243.484377)
			(xy 369.143534 -243.502434) (xy 368.864134 -243.781834) (xy 368.846093 -243.799093) (xy 368.804599 -243.826847)
			(xy 368.75848 -243.845957) (xy 368.709517 -243.855686) (xy 368.684556 -243.856256) (xy 368.129312 -243.856256)
			(xy 366.982756 -245.002812) (xy 366.982756 -246.7737) (xy 368.993928 -248.784872) (xy 369.007898 -248.788428)
			(xy 369.034038 -248.795492) (xy 369.083731 -248.816987) (xy 369.129227 -248.846342) (xy 369.169292 -248.88276)
			(xy 369.202843 -248.925256) (xy 369.22897 -248.972678) (xy 369.246966 -249.023743) (xy 369.252246 -249.050302)
			(xy 369.265312 -249.071193) (xy 369.283989 -249.116784) (xy 369.29355 -249.165115) (xy 369.294156 -249.189748)
			(xy 369.294156 -260.087364) (xy 369.294042 -260.097569) (xy 369.292387 -260.117914) (xy 369.290854 -260.128004)
			(xy 369.286536 -260.153658) (xy 369.511072 -260.37794) (xy 369.522395 -260.390055) (xy 369.538963 -260.418767)
			(xy 369.547583 -260.450775) (xy 369.548156 -260.467348) (xy 369.548156 -261.685278)
		)
		(stroke
			(width 0)
			(type solid)
		)
		(fill yes)
		(layer "In9.Cu")
		(net "PVCCD_HV_CPU0")
	)
	(gr_poly
		(pts
			(xy 67.751452 -334.284574) (xy 67.769493 -334.267314) (xy 67.810986 -334.239556) (xy 67.857104 -334.220443)
			(xy 67.906069 -334.210711) (xy 67.93103 -334.210152) (xy 72.12838 -334.210152) (xy 72.460358 -333.878174)
			(xy 72.460358 -296.49039) (xy 72.46093 -296.46543) (xy 72.470673 -296.416471) (xy 72.489781 -296.370354)
			(xy 72.517521 -296.328852) (xy 72.53478 -296.310812) (xy 79.978758 -288.866834) (xy 79.9968 -288.849577)
			(xy 80.038295 -288.821824) (xy 80.084413 -288.802715) (xy 80.133376 -288.792987) (xy 80.158336 -288.792412)
			(xy 87.48014 -288.792412) (xy 87.494364 -288.765234) (xy 87.506622 -288.742815) (xy 87.53701 -288.701739)
			(xy 87.573398 -288.665871) (xy 87.614906 -288.636076) (xy 87.660531 -288.613077) (xy 87.70917 -288.597427)
			(xy 87.759647 -288.589507) (xy 87.810741 -288.589507) (xy 87.861218 -288.597427) (xy 87.909857 -288.613077)
			(xy 87.955482 -288.636076) (xy 87.99699 -288.665871) (xy 88.033378 -288.701739) (xy 88.063766 -288.742815)
			(xy 88.076024 -288.765234) (xy 88.090248 -288.792412) (xy 88.41867 -288.792412) (xy 88.432894 -288.76498)
			(xy 88.444755 -288.743166) (xy 88.474023 -288.703058) (xy 88.508971 -288.66779) (xy 88.54881 -288.638157)
			(xy 88.59264 -288.614829) (xy 88.639471 -288.598334) (xy 88.66378 -288.593276) (xy 88.68664 -288.588958)
			(xy 88.891618 -288.233866) (xy 88.883744 -288.212022) (xy 88.875165 -288.185603) (xy 88.865969 -288.130828)
			(xy 88.865456 -288.103056) (xy 88.865964 -288.077169) (xy 88.874063 -288.026031) (xy 88.890062 -287.976791)
			(xy 88.913568 -287.930659) (xy 88.944 -287.888772) (xy 88.98061 -287.852162) (xy 89.022497 -287.82173)
			(xy 89.068629 -287.798224) (xy 89.117869 -287.782225) (xy 89.169007 -287.774126) (xy 89.220781 -287.774126)
			(xy 89.271919 -287.782225) (xy 89.321159 -287.798224) (xy 89.367291 -287.82173) (xy 89.409178 -287.852162)
			(xy 89.445788 -287.888772) (xy 89.47622 -287.930659) (xy 89.499726 -287.976791) (xy 89.515725 -288.026031)
			(xy 89.523824 -288.077169) (xy 89.524332 -288.103056) (xy 89.523871 -288.128392) (xy 89.516123 -288.178469)
			(xy 89.500803 -288.226771) (xy 89.478271 -288.272159) (xy 89.449059 -288.313564) (xy 89.413854 -288.350011)
			(xy 89.373487 -288.380641) (xy 89.328907 -288.404732) (xy 89.281166 -288.421717) (xy 89.256362 -288.426906)
			(xy 89.233502 -288.431224) (xy 89.112852 -288.640012) (xy 89.10567 -288.653469) (xy 89.098891 -288.683196)
			(xy 89.101184 -288.7136) (xy 89.112344 -288.741975) (xy 89.131379 -288.765793) (xy 89.156594 -288.782936)
			(xy 89.185744 -288.791877) (xy 89.20099 -288.792412) (xy 89.35974 -288.792412) (xy 89.373964 -288.765234)
			(xy 89.386222 -288.742815) (xy 89.41661 -288.701739) (xy 89.452998 -288.665871) (xy 89.494506 -288.636076)
			(xy 89.540131 -288.613077) (xy 89.58877 -288.597427) (xy 89.639247 -288.589507) (xy 89.690341 -288.589507)
			(xy 89.740818 -288.597427) (xy 89.789457 -288.613077) (xy 89.835082 -288.636076) (xy 89.87659 -288.665871)
			(xy 89.912978 -288.701739) (xy 89.943366 -288.742815) (xy 89.955624 -288.765234) (xy 89.969848 -288.792412)
			(xy 90.29827 -288.792412) (xy 90.312494 -288.76498) (xy 90.324355 -288.743166) (xy 90.353623 -288.703058)
			(xy 90.388571 -288.66779) (xy 90.42841 -288.638157) (xy 90.47224 -288.614829) (xy 90.519071 -288.598334)
			(xy 90.54338 -288.593276) (xy 90.56624 -288.588958) (xy 90.771218 -288.233866) (xy 90.763344 -288.212022)
			(xy 90.754765 -288.185603) (xy 90.745569 -288.130828) (xy 90.745056 -288.103056) (xy 90.745564 -288.077169)
			(xy 90.753663 -288.026031) (xy 90.769662 -287.976791) (xy 90.793168 -287.930659) (xy 90.8236 -287.888772)
			(xy 90.86021 -287.852162) (xy 90.902097 -287.82173) (xy 90.948229 -287.798224) (xy 90.997469 -287.782225)
			(xy 91.048607 -287.774126) (xy 91.100381 -287.774126) (xy 91.151519 -287.782225) (xy 91.200759 -287.798224)
			(xy 91.246891 -287.82173) (xy 91.288778 -287.852162) (xy 91.325388 -287.888772) (xy 91.35582 -287.930659)
			(xy 91.379326 -287.976791) (xy 91.395325 -288.026031) (xy 91.403424 -288.077169) (xy 91.403932 -288.103056)
			(xy 91.403471 -288.128392) (xy 91.395723 -288.178469) (xy 91.380403 -288.226771) (xy 91.357871 -288.272159)
			(xy 91.328659 -288.313564) (xy 91.293454 -288.350011) (xy 91.253087 -288.380641) (xy 91.208507 -288.404732)
			(xy 91.160766 -288.421717) (xy 91.135962 -288.426906) (xy 91.113102 -288.431224) (xy 90.992452 -288.640012)
			(xy 90.98527 -288.653469) (xy 90.978491 -288.683196) (xy 90.980784 -288.7136) (xy 90.991944 -288.741975)
			(xy 91.010979 -288.765793) (xy 91.036194 -288.782936) (xy 91.065344 -288.791877) (xy 91.08059 -288.792412)
			(xy 91.23807 -288.792412) (xy 91.252294 -288.76498) (xy 91.264604 -288.742428) (xy 91.295133 -288.701104)
			(xy 91.331703 -288.665016) (xy 91.373428 -288.635038) (xy 91.419298 -288.611896) (xy 91.468203 -288.596149)
			(xy 91.518959 -288.588179) (xy 91.570337 -288.588179) (xy 91.621093 -288.596149) (xy 91.669998 -288.611896)
			(xy 91.715868 -288.635038) (xy 91.757593 -288.665016) (xy 91.794163 -288.701104) (xy 91.824692 -288.742428)
			(xy 91.837002 -288.76498) (xy 91.851226 -288.792412) (xy 92.17787 -288.792412) (xy 92.192094 -288.76498)
			(xy 92.203955 -288.743166) (xy 92.233223 -288.703058) (xy 92.268171 -288.66779) (xy 92.30801 -288.638157)
			(xy 92.35184 -288.614829) (xy 92.398671 -288.598334) (xy 92.42298 -288.593276) (xy 92.44584 -288.588958)
			(xy 92.651072 -288.233866) (xy 92.643198 -288.211768) (xy 92.634576 -288.18542) (xy 92.625258 -288.130773)
			(xy 92.624656 -288.103056) (xy 92.625164 -288.077149) (xy 92.63327 -288.025972) (xy 92.649282 -287.976693)
			(xy 92.672805 -287.930526) (xy 92.703261 -287.888607) (xy 92.739899 -287.851969) (xy 92.781818 -287.821513)
			(xy 92.827985 -287.79799) (xy 92.877264 -287.781978) (xy 92.928441 -287.773872) (xy 92.980255 -287.773872)
			(xy 93.031432 -287.781978) (xy 93.080711 -287.79799) (xy 93.126878 -287.821513) (xy 93.168797 -287.851969)
			(xy 93.205435 -287.888607) (xy 93.235891 -287.930526) (xy 93.259414 -287.976693) (xy 93.275426 -288.025972)
			(xy 93.283532 -288.077149) (xy 93.28404 -288.103056) (xy 93.283578 -288.128404) (xy 93.275821 -288.178504)
			(xy 93.260482 -288.226824) (xy 93.237924 -288.272225) (xy 93.208679 -288.313636) (xy 93.173437 -288.35008)
			(xy 93.13303 -288.380696) (xy 93.08841 -288.404763) (xy 93.040631 -288.421713) (xy 93.015816 -288.426906)
			(xy 92.992956 -288.431224) (xy 92.872306 -288.640012) (xy 92.865188 -288.653476) (xy 92.858414 -288.683151)
			(xy 92.860682 -288.713506) (xy 92.871791 -288.741844) (xy 92.890756 -288.765653) (xy 92.915893 -288.782818)
			(xy 92.944971 -288.791817) (xy 92.96019 -288.792412) (xy 93.11767 -288.792412) (xy 93.131894 -288.76498)
			(xy 93.144204 -288.742428) (xy 93.174733 -288.701104) (xy 93.211303 -288.665016) (xy 93.253028 -288.635038)
			(xy 93.298898 -288.611896) (xy 93.347803 -288.596149) (xy 93.398559 -288.588179) (xy 93.449937 -288.588179)
			(xy 93.500693 -288.596149) (xy 93.549598 -288.611896) (xy 93.595468 -288.635038) (xy 93.637193 -288.665016)
			(xy 93.673763 -288.701104) (xy 93.704292 -288.742428) (xy 93.716602 -288.76498) (xy 93.730826 -288.792412)
			(xy 94.05747 -288.792412) (xy 94.071694 -288.76498) (xy 94.083555 -288.743166) (xy 94.112823 -288.703058)
			(xy 94.147771 -288.66779) (xy 94.18761 -288.638157) (xy 94.23144 -288.614829) (xy 94.278271 -288.598334)
			(xy 94.30258 -288.593276) (xy 94.32544 -288.588958) (xy 94.530672 -288.233866) (xy 94.522798 -288.211768)
			(xy 94.514176 -288.18542) (xy 94.504858 -288.130773) (xy 94.504256 -288.103056) (xy 94.504764 -288.077149)
			(xy 94.51287 -288.025972) (xy 94.528882 -287.976693) (xy 94.552405 -287.930526) (xy 94.582861 -287.888607)
			(xy 94.619499 -287.851969) (xy 94.661418 -287.821513) (xy 94.707585 -287.79799) (xy 94.756864 -287.781978)
			(xy 94.808041 -287.773872) (xy 94.859855 -287.773872) (xy 94.911032 -287.781978) (xy 94.960311 -287.79799)
			(xy 95.006478 -287.821513) (xy 95.048397 -287.851969) (xy 95.085035 -287.888607) (xy 95.115491 -287.930526)
			(xy 95.139014 -287.976693) (xy 95.155026 -288.025972) (xy 95.163132 -288.077149) (xy 95.16364 -288.103056)
			(xy 95.163178 -288.128404) (xy 95.155421 -288.178504) (xy 95.140082 -288.226824) (xy 95.117524 -288.272225)
			(xy 95.088279 -288.313636) (xy 95.053037 -288.35008) (xy 95.01263 -288.380696) (xy 94.96801 -288.404763)
			(xy 94.920231 -288.421713) (xy 94.895416 -288.426906) (xy 94.872556 -288.431224) (xy 94.751906 -288.640012)
			(xy 94.744788 -288.653476) (xy 94.738014 -288.683151) (xy 94.740282 -288.713506) (xy 94.751391 -288.741844)
			(xy 94.770356 -288.765653) (xy 94.795493 -288.782818) (xy 94.824571 -288.791817) (xy 94.83979 -288.792412)
			(xy 94.99727 -288.792412) (xy 95.011494 -288.76498) (xy 95.023804 -288.742428) (xy 95.054333 -288.701104)
			(xy 95.090903 -288.665016) (xy 95.132628 -288.635038) (xy 95.178498 -288.611896) (xy 95.227403 -288.596149)
			(xy 95.278159 -288.588179) (xy 95.329537 -288.588179) (xy 95.380293 -288.596149) (xy 95.429198 -288.611896)
			(xy 95.475068 -288.635038) (xy 95.516793 -288.665016) (xy 95.553363 -288.701104) (xy 95.583892 -288.742428)
			(xy 95.596202 -288.76498) (xy 95.610426 -288.792412) (xy 95.93707 -288.792412) (xy 95.951294 -288.76498)
			(xy 95.963155 -288.743166) (xy 95.992423 -288.703058) (xy 96.027371 -288.66779) (xy 96.06721 -288.638157)
			(xy 96.11104 -288.614829) (xy 96.157871 -288.598334) (xy 96.18218 -288.593276) (xy 96.20504 -288.588958)
			(xy 96.410272 -288.233866) (xy 96.402398 -288.211768) (xy 96.393776 -288.18542) (xy 96.384458 -288.130773)
			(xy 96.383856 -288.103056) (xy 96.384364 -288.077149) (xy 96.39247 -288.025972) (xy 96.408482 -287.976693)
			(xy 96.432005 -287.930526) (xy 96.462461 -287.888607) (xy 96.499099 -287.851969) (xy 96.541018 -287.821513)
			(xy 96.587185 -287.79799) (xy 96.636464 -287.781978) (xy 96.687641 -287.773872) (xy 96.739455 -287.773872)
			(xy 96.790632 -287.781978) (xy 96.839911 -287.79799) (xy 96.886078 -287.821513) (xy 96.927997 -287.851969)
			(xy 96.964635 -287.888607) (xy 96.995091 -287.930526) (xy 97.018614 -287.976693) (xy 97.034626 -288.025972)
			(xy 97.042732 -288.077149) (xy 97.04324 -288.103056) (xy 97.042778 -288.128404) (xy 97.035021 -288.178504)
			(xy 97.019682 -288.226824) (xy 96.997124 -288.272225) (xy 96.967879 -288.313636) (xy 96.932637 -288.35008)
			(xy 96.89223 -288.380696) (xy 96.84761 -288.404763) (xy 96.799831 -288.421713) (xy 96.775016 -288.426906)
			(xy 96.752156 -288.431224) (xy 96.631506 -288.640012) (xy 96.624388 -288.653476) (xy 96.617614 -288.683151)
			(xy 96.619882 -288.713506) (xy 96.630991 -288.741844) (xy 96.649956 -288.765653) (xy 96.675093 -288.782818)
			(xy 96.704171 -288.791817) (xy 96.71939 -288.792412) (xy 96.87687 -288.792412) (xy 96.891094 -288.76498)
			(xy 96.903404 -288.742428) (xy 96.933933 -288.701104) (xy 96.970503 -288.665016) (xy 97.012228 -288.635038)
			(xy 97.058098 -288.611896) (xy 97.107003 -288.596149) (xy 97.157759 -288.588179) (xy 97.209137 -288.588179)
			(xy 97.259893 -288.596149) (xy 97.308798 -288.611896) (xy 97.354668 -288.635038) (xy 97.396393 -288.665016)
			(xy 97.432963 -288.701104) (xy 97.463492 -288.742428) (xy 97.475802 -288.76498) (xy 97.490026 -288.792412)
			(xy 97.81667 -288.792412) (xy 97.830894 -288.76498) (xy 97.842755 -288.743166) (xy 97.872023 -288.703058)
			(xy 97.906971 -288.66779) (xy 97.94681 -288.638157) (xy 97.99064 -288.614829) (xy 98.037471 -288.598334)
			(xy 98.06178 -288.593276) (xy 98.08464 -288.588958) (xy 98.289872 -288.233866) (xy 98.281998 -288.211768)
			(xy 98.273376 -288.18542) (xy 98.264058 -288.130773) (xy 98.263456 -288.103056) (xy 98.263964 -288.077149)
			(xy 98.27207 -288.025972) (xy 98.288082 -287.976693) (xy 98.311605 -287.930526) (xy 98.342061 -287.888607)
			(xy 98.378699 -287.851969) (xy 98.420618 -287.821513) (xy 98.466785 -287.79799) (xy 98.516064 -287.781978)
			(xy 98.567241 -287.773872) (xy 98.619055 -287.773872) (xy 98.670232 -287.781978) (xy 98.719511 -287.79799)
			(xy 98.765678 -287.821513) (xy 98.807597 -287.851969) (xy 98.844235 -287.888607) (xy 98.874691 -287.930526)
			(xy 98.898214 -287.976693) (xy 98.914226 -288.025972) (xy 98.922332 -288.077149) (xy 98.92284 -288.103056)
			(xy 98.922378 -288.128404) (xy 98.914621 -288.178504) (xy 98.899282 -288.226824) (xy 98.876724 -288.272225)
			(xy 98.847479 -288.313636) (xy 98.812237 -288.35008) (xy 98.77183 -288.380696) (xy 98.72721 -288.404763)
			(xy 98.679431 -288.421713) (xy 98.654616 -288.426906) (xy 98.631756 -288.431224) (xy 98.511106 -288.640012)
			(xy 98.503988 -288.653476) (xy 98.497214 -288.683151) (xy 98.499482 -288.713506) (xy 98.510591 -288.741844)
			(xy 98.529556 -288.765653) (xy 98.554693 -288.782818) (xy 98.583771 -288.791817) (xy 98.59899 -288.792412)
			(xy 98.75647 -288.792412) (xy 98.770694 -288.76498) (xy 98.783004 -288.742428) (xy 98.813533 -288.701104)
			(xy 98.850103 -288.665016) (xy 98.891828 -288.635038) (xy 98.937698 -288.611896) (xy 98.986603 -288.596149)
			(xy 99.037359 -288.588179) (xy 99.088737 -288.588179) (xy 99.139493 -288.596149) (xy 99.188398 -288.611896)
			(xy 99.234268 -288.635038) (xy 99.275993 -288.665016) (xy 99.312563 -288.701104) (xy 99.343092 -288.742428)
			(xy 99.355402 -288.76498) (xy 99.369626 -288.792412) (xy 99.69627 -288.792412) (xy 99.710494 -288.76498)
			(xy 99.722355 -288.743166) (xy 99.751623 -288.703058) (xy 99.786571 -288.66779) (xy 99.82641 -288.638157)
			(xy 99.87024 -288.614829) (xy 99.917071 -288.598334) (xy 99.94138 -288.593276) (xy 99.96424 -288.588958)
			(xy 100.169472 -288.233866) (xy 100.161598 -288.211768) (xy 100.152976 -288.18542) (xy 100.143658 -288.130773)
			(xy 100.143056 -288.103056) (xy 100.143564 -288.077149) (xy 100.15167 -288.025972) (xy 100.167682 -287.976693)
			(xy 100.191205 -287.930526) (xy 100.221661 -287.888607) (xy 100.258299 -287.851969) (xy 100.300218 -287.821513)
			(xy 100.346385 -287.79799) (xy 100.395664 -287.781978) (xy 100.446841 -287.773872) (xy 100.498655 -287.773872)
			(xy 100.549832 -287.781978) (xy 100.599111 -287.79799) (xy 100.645278 -287.821513) (xy 100.687197 -287.851969)
			(xy 100.723835 -287.888607) (xy 100.754291 -287.930526) (xy 100.777814 -287.976693) (xy 100.793826 -288.025972)
			(xy 100.801932 -288.077149) (xy 100.80244 -288.103056) (xy 100.801978 -288.128404) (xy 100.794221 -288.178504)
			(xy 100.778882 -288.226824) (xy 100.756324 -288.272225) (xy 100.727079 -288.313636) (xy 100.691837 -288.35008)
			(xy 100.65143 -288.380696) (xy 100.60681 -288.404763) (xy 100.559031 -288.421713) (xy 100.534216 -288.426906)
			(xy 100.511356 -288.431224) (xy 100.390706 -288.640012) (xy 100.383588 -288.653476) (xy 100.376814 -288.683151)
			(xy 100.379082 -288.713506) (xy 100.390191 -288.741844) (xy 100.409156 -288.765653) (xy 100.434293 -288.782818)
			(xy 100.463371 -288.791817) (xy 100.47859 -288.792412) (xy 100.63607 -288.792412) (xy 100.650294 -288.76498)
			(xy 100.662604 -288.742428) (xy 100.693133 -288.701104) (xy 100.729703 -288.665016) (xy 100.771428 -288.635038)
			(xy 100.817298 -288.611896) (xy 100.866203 -288.596149) (xy 100.916959 -288.588179) (xy 100.968337 -288.588179)
			(xy 101.019093 -288.596149) (xy 101.067998 -288.611896) (xy 101.113868 -288.635038) (xy 101.155593 -288.665016)
			(xy 101.192163 -288.701104) (xy 101.222692 -288.742428) (xy 101.235002 -288.76498) (xy 101.249226 -288.792412)
			(xy 101.57587 -288.792412) (xy 101.590094 -288.76498) (xy 101.601955 -288.743166) (xy 101.631223 -288.703058)
			(xy 101.666171 -288.66779) (xy 101.70601 -288.638157) (xy 101.74984 -288.614829) (xy 101.796671 -288.598334)
			(xy 101.82098 -288.593276) (xy 101.84384 -288.588958) (xy 102.049072 -288.233866) (xy 102.041198 -288.211768)
			(xy 102.032576 -288.18542) (xy 102.023258 -288.130773) (xy 102.022656 -288.103056) (xy 102.023164 -288.077149)
			(xy 102.03127 -288.025972) (xy 102.047282 -287.976693) (xy 102.070805 -287.930526) (xy 102.101261 -287.888607)
			(xy 102.137899 -287.851969) (xy 102.179818 -287.821513) (xy 102.225985 -287.79799) (xy 102.275264 -287.781978)
			(xy 102.326441 -287.773872) (xy 102.378255 -287.773872) (xy 102.429432 -287.781978) (xy 102.478711 -287.79799)
			(xy 102.524878 -287.821513) (xy 102.566797 -287.851969) (xy 102.603435 -287.888607) (xy 102.633891 -287.930526)
			(xy 102.657414 -287.976693) (xy 102.673426 -288.025972) (xy 102.681532 -288.077149) (xy 102.68204 -288.103056)
			(xy 102.681578 -288.128404) (xy 102.673821 -288.178504) (xy 102.658482 -288.226824) (xy 102.635924 -288.272225)
			(xy 102.606679 -288.313636) (xy 102.571437 -288.35008) (xy 102.53103 -288.380696) (xy 102.48641 -288.404763)
			(xy 102.438631 -288.421713) (xy 102.413816 -288.426906) (xy 102.390956 -288.431224) (xy 102.270306 -288.640012)
			(xy 102.263188 -288.653476) (xy 102.256414 -288.683151) (xy 102.258682 -288.713506) (xy 102.269791 -288.741844)
			(xy 102.288756 -288.765653) (xy 102.313893 -288.782818) (xy 102.342971 -288.791817) (xy 102.35819 -288.792412)
			(xy 102.51567 -288.792412) (xy 102.529894 -288.76498) (xy 102.542204 -288.742428) (xy 102.572733 -288.701104)
			(xy 102.609303 -288.665016) (xy 102.651028 -288.635038) (xy 102.696898 -288.611896) (xy 102.745803 -288.596149)
			(xy 102.796559 -288.588179) (xy 102.847937 -288.588179) (xy 102.898693 -288.596149) (xy 102.947598 -288.611896)
			(xy 102.993468 -288.635038) (xy 103.035193 -288.665016) (xy 103.071763 -288.701104) (xy 103.102292 -288.742428)
			(xy 103.114602 -288.76498) (xy 103.128826 -288.792412) (xy 103.383334 -288.792412) (xy 103.910384 -288.265362)
			(xy 103.928672 -288.233866) (xy 103.920798 -288.211768) (xy 103.912176 -288.18542) (xy 103.902858 -288.130773)
			(xy 103.902256 -288.103056) (xy 103.902748 -288.076987) (xy 103.910953 -288.0255) (xy 103.927169 -287.975949)
			(xy 103.950989 -287.929571) (xy 103.981818 -287.887525) (xy 104.018887 -287.850862) (xy 104.061269 -287.820497)
			(xy 104.084374 -287.808416) (xy 104.112314 -287.794446) (xy 104.112314 -286.782764) (xy 104.084374 -286.76854)
			(xy 104.061425 -286.756481) (xy 104.019321 -286.726239) (xy 103.982498 -286.68975) (xy 103.951875 -286.647922)
			(xy 103.928214 -286.601797) (xy 103.912104 -286.552524) (xy 103.903947 -286.501331) (xy 103.903945 -286.449491)
			(xy 103.912099 -286.398297) (xy 103.928206 -286.349023) (xy 103.951864 -286.302896) (xy 103.982484 -286.261066)
			(xy 104.019304 -286.224575) (xy 104.061407 -286.19433) (xy 104.084374 -286.182308) (xy 104.112314 -286.168084)
			(xy 104.112314 -286.013398) (xy 104.11184 -285.999487) (xy 104.104335 -285.972695) (xy 104.089882 -285.948921)
			(xy 104.069552 -285.929926) (xy 104.044852 -285.917119) (xy 104.017613 -285.911449) (xy 103.989854 -285.913336)
			(xy 103.963633 -285.92264) (xy 103.95204 -285.93034) (xy 103.931056 -285.944595) (xy 103.885631 -285.967176)
			(xy 103.837285 -285.982538) (xy 103.787158 -285.990317) (xy 103.761794 -285.990792) (xy 103.735906 -285.99031)
			(xy 103.684768 -285.982209) (xy 103.635527 -285.966208) (xy 103.589396 -285.942699) (xy 103.547511 -285.912264)
			(xy 103.510903 -285.87565) (xy 103.480473 -285.83376) (xy 103.456972 -285.787625) (xy 103.440979 -285.738381)
			(xy 103.432886 -285.687242) (xy 103.432356 -285.661354) (xy 103.432816 -285.636017) (xy 103.440563 -285.585938)
			(xy 103.455882 -285.537635) (xy 103.478413 -285.492245) (xy 103.507624 -285.450838) (xy 103.542829 -285.414389)
			(xy 103.583196 -285.383756) (xy 103.627776 -285.359662) (xy 103.675518 -285.342674) (xy 103.700326 -285.337504)
			(xy 103.723186 -285.333186) (xy 103.928418 -284.97784) (xy 103.920798 -284.955996) (xy 103.912189 -284.929709)
			(xy 103.902867 -284.875191) (xy 103.902256 -284.847538) (xy 103.902749 -284.82147) (xy 103.910957 -284.769985)
			(xy 103.927174 -284.720435) (xy 103.950995 -284.67406) (xy 103.981825 -284.632016) (xy 104.018894 -284.595355)
			(xy 104.061276 -284.564993) (xy 104.084374 -284.552898) (xy 104.112314 -284.538928) (xy 104.112314 -283.765752)
			(xy 104.11293 -283.740797) (xy 104.122676 -283.691849) (xy 104.141784 -283.645742) (xy 104.169519 -283.604249)
			(xy 104.186736 -283.586174) (xy 105.315004 -282.457906) (xy 105.312972 -282.434284) (xy 105.311956 -282.405836)
			(xy 105.312461 -282.379941) (xy 105.320554 -282.328787) (xy 105.336548 -282.279528) (xy 105.360048 -282.233377)
			(xy 105.390476 -282.191468) (xy 105.427084 -282.154834) (xy 105.46897 -282.124375) (xy 105.515104 -282.100841)
			(xy 105.564351 -282.084811) (xy 105.615499 -282.07668) (xy 105.641394 -282.076144) (xy 105.669842 -282.077414)
			(xy 105.693464 -282.079446) (xy 105.91292 -281.85999) (xy 105.87736 -281.823922) (xy 105.859585 -281.805294)
			(xy 105.82946 -281.763543) (xy 105.806198 -281.717612) (xy 105.790367 -281.668621) (xy 105.782352 -281.617763)
			(xy 105.781856 -281.59202) (xy 105.782337 -281.566111) (xy 105.790441 -281.514931) (xy 105.806452 -281.465648)
			(xy 105.829977 -281.419478) (xy 105.860436 -281.377557) (xy 105.897078 -281.340918) (xy 105.939002 -281.310463)
			(xy 105.985174 -281.286942) (xy 106.034458 -281.270934) (xy 106.085639 -281.262834) (xy 106.111548 -281.262328)
			(xy 106.137287 -281.262848) (xy 106.188134 -281.270891) (xy 106.237116 -281.286729) (xy 106.283047 -281.309977)
			(xy 106.324814 -281.340071) (xy 106.34345 -281.357832) (xy 106.379518 -281.393392) (xy 106.514646 -281.258264)
			(xy 106.524689 -281.247466) (xy 106.538648 -281.221503) (xy 106.544614 -281.192636) (xy 106.542093 -281.163267)
			(xy 106.531294 -281.135839) (xy 106.513116 -281.112635) (xy 106.48907 -281.095584) (xy 106.475276 -281.09037)
			(xy 106.451956 -281.081986) (xy 106.407937 -281.059225) (xy 106.367813 -281.030142) (xy 106.332487 -280.995389)
			(xy 106.317288 -280.975816) (xy 105.9053 -280.975816) (xy 105.889626 -280.995951) (xy 105.853116 -281.031593)
			(xy 105.81155 -281.061185) (xy 105.765922 -281.08402) (xy 105.71732 -281.099553) (xy 105.666906 -281.107413)
			(xy 105.641394 -281.107896) (xy 105.615487 -281.107387) (xy 105.56431 -281.099281) (xy 105.515032 -281.083268)
			(xy 105.468865 -281.059744) (xy 105.426946 -281.029288) (xy 105.390308 -280.992649) (xy 105.359852 -280.95073)
			(xy 105.336329 -280.904563) (xy 105.320318 -280.855284) (xy 105.312212 -280.804107) (xy 105.312212 -280.752293)
			(xy 105.320318 -280.701116) (xy 105.336329 -280.651837) (xy 105.359852 -280.60567) (xy 105.390308 -280.563751)
			(xy 105.426946 -280.527112) (xy 105.468865 -280.496656) (xy 105.515032 -280.473132) (xy 105.56431 -280.457119)
			(xy 105.615487 -280.449013) (xy 105.641394 -280.448512) (xy 105.666906 -280.448989) (xy 105.717321 -280.456849)
			(xy 105.765924 -280.472383) (xy 105.811552 -280.495218) (xy 105.853118 -280.524811) (xy 105.889629 -280.560455)
			(xy 105.9053 -280.580592) (xy 106.317288 -280.580592) (xy 106.332961 -280.560456) (xy 106.369471 -280.524812)
			(xy 106.411036 -280.495218) (xy 106.456665 -280.47238) (xy 106.505267 -280.456845) (xy 106.555682 -280.448983)
			(xy 106.581194 -280.448512) (xy 106.606833 -280.448999) (xy 106.657493 -280.45694) (xy 106.706312 -280.472631)
			(xy 106.752111 -280.495693) (xy 106.793786 -280.52557) (xy 106.830332 -280.561541) (xy 106.860865 -280.602738)
			(xy 106.88465 -280.648166) (xy 106.89336 -280.672286) (xy 106.898542 -280.686105) (xy 106.915565 -280.710199)
			(xy 106.93877 -280.728415) (xy 106.966217 -280.739229) (xy 106.995611 -280.741738) (xy 107.024494 -280.735732)
			(xy 107.050451 -280.721713) (xy 107.061254 -280.711656) (xy 107.685332 -280.087578) (xy 107.676696 -280.058622)
			(xy 107.67017 -280.035547) (xy 107.663154 -279.98811) (xy 107.662726 -279.964134) (xy 107.663221 -279.938108)
			(xy 107.671432 -279.886709) (xy 107.687654 -279.837251) (xy 107.711479 -279.790973) (xy 107.742311 -279.749036)
			(xy 107.779377 -279.712492) (xy 107.821746 -279.682256) (xy 107.844844 -279.670256) (xy 107.873038 -279.656286)
			(xy 107.873038 -278.645874) (xy 107.844844 -278.631904) (xy 107.821617 -278.619832) (xy 107.778977 -278.589471)
			(xy 107.741668 -278.552756) (xy 107.710626 -278.510608) (xy 107.686633 -278.464087) (xy 107.670288 -278.414359)
			(xy 107.662004 -278.362674) (xy 107.661456 -278.336502) (xy 107.662044 -278.308784) (xy 107.671362 -278.254135)
			(xy 107.679998 -278.22779) (xy 107.687872 -278.205692) (xy 107.482894 -277.8506) (xy 107.45978 -277.846282)
			(xy 107.434965 -277.841098) (xy 107.387195 -277.82413) (xy 107.342584 -277.800052) (xy 107.302183 -277.769431)
			(xy 107.266945 -277.732987) (xy 107.237699 -277.69158) (xy 107.215133 -277.646186) (xy 107.199781 -277.597872)
			(xy 107.192003 -277.547779) (xy 107.191556 -277.522432) (xy 107.192061 -277.496537) (xy 107.200155 -277.445384)
			(xy 107.216149 -277.396126) (xy 107.239649 -277.349975) (xy 107.270078 -277.308066) (xy 107.306685 -277.271432)
			(xy 107.348571 -277.240974) (xy 107.394705 -277.21744) (xy 107.443952 -277.201411) (xy 107.495099 -277.19328)
			(xy 107.520994 -277.19274) (xy 107.546557 -277.193242) (xy 107.597064 -277.201171) (xy 107.645745 -277.216792)
			(xy 107.691435 -277.239733) (xy 107.71251 -277.254208) (xy 107.724112 -277.261929) (xy 107.750333 -277.271339)
			(xy 107.778122 -277.273314) (xy 107.805411 -277.267706) (xy 107.830169 -277.254934) (xy 107.850555 -277.235946)
			(xy 107.865052 -277.212156) (xy 107.872581 -277.185333) (xy 107.873038 -277.171404) (xy 107.873038 -277.016464)
			(xy 107.844844 -277.002494) (xy 107.821788 -276.990443) (xy 107.779476 -276.960178) (xy 107.742464 -276.923622)
			(xy 107.711679 -276.881687) (xy 107.687889 -276.835424) (xy 107.67169 -276.785989) (xy 107.663488 -276.734618)
			(xy 107.663487 -276.682596) (xy 107.671687 -276.631225) (xy 107.687883 -276.581789) (xy 107.711671 -276.535525)
			(xy 107.742455 -276.493589) (xy 107.779465 -276.457031) (xy 107.821776 -276.426765) (xy 107.844844 -276.414738)
			(xy 107.873038 -276.400768) (xy 107.873038 -276.245828) (xy 107.872609 -276.231892) (xy 107.865084 -276.205055)
			(xy 107.850585 -276.181251) (xy 107.830192 -276.162252) (xy 107.805423 -276.149471) (xy 107.778121 -276.143861)
			(xy 107.750319 -276.145838) (xy 107.724087 -276.155256) (xy 107.71251 -276.163024) (xy 107.691436 -276.177502)
			(xy 107.645752 -276.200461) (xy 107.59707 -276.216086) (xy 107.546558 -276.224) (xy 107.520994 -276.224492)
			(xy 107.495482 -276.224014) (xy 107.445068 -276.216152) (xy 107.396467 -276.200618) (xy 107.350839 -276.177781)
			(xy 107.309275 -276.148188) (xy 107.272765 -276.112544) (xy 107.257088 -276.092412) (xy 106.8451 -276.092412)
			(xy 106.829426 -276.112547) (xy 106.792916 -276.14819) (xy 106.75135 -276.177782) (xy 106.705722 -276.200617)
			(xy 106.65712 -276.21615) (xy 106.606706 -276.22401) (xy 106.581194 -276.224492) (xy 106.555287 -276.223983)
			(xy 106.504111 -276.215877) (xy 106.454833 -276.199865) (xy 106.408667 -276.176341) (xy 106.366749 -276.145885)
			(xy 106.330111 -276.109247) (xy 106.299656 -276.067328) (xy 106.276133 -276.021161) (xy 106.260122 -275.971883)
			(xy 106.252016 -275.920707) (xy 106.252016 -275.868893) (xy 106.260122 -275.817717) (xy 106.276133 -275.768439)
			(xy 106.299656 -275.722272) (xy 106.330111 -275.680353) (xy 106.366749 -275.643715) (xy 106.408667 -275.613259)
			(xy 106.454833 -275.589735) (xy 106.504111 -275.573723) (xy 106.555287 -275.565617) (xy 106.581194 -275.565108)
			(xy 106.606706 -275.565585) (xy 106.657121 -275.573445) (xy 106.705724 -275.588978) (xy 106.751353 -275.611814)
			(xy 106.792919 -275.641407) (xy 106.82943 -275.67705) (xy 106.8451 -275.697188) (xy 107.257088 -275.697188)
			(xy 107.272762 -275.677053) (xy 107.309271 -275.641408) (xy 107.350837 -275.611815) (xy 107.396465 -275.588978)
			(xy 107.445067 -275.573443) (xy 107.495482 -275.565581) (xy 107.520994 -275.565108) (xy 107.546557 -275.56561)
			(xy 107.597065 -275.573538) (xy 107.645746 -275.589158) (xy 107.691437 -275.612098) (xy 107.71251 -275.626576)
			(xy 107.72411 -275.634299) (xy 107.75033 -275.643712) (xy 107.778118 -275.645688) (xy 107.805406 -275.640081)
			(xy 107.830162 -275.627306) (xy 107.850545 -275.608317) (xy 107.865037 -275.584525) (xy 107.872559 -275.557701)
			(xy 107.873038 -275.543772) (xy 107.873038 -275.390102) (xy 107.844844 -275.376132) (xy 107.821615 -275.36406)
			(xy 107.778973 -275.3337) (xy 107.74166 -275.296986) (xy 107.710616 -275.254839) (xy 107.686618 -275.208317)
			(xy 107.67027 -275.158589) (xy 107.661981 -275.106903) (xy 107.661456 -275.08073) (xy 107.661957 -275.054554)
			(xy 107.670229 -275.00286) (xy 107.686571 -274.953124) (xy 107.71057 -274.906597) (xy 107.741624 -274.86445)
			(xy 107.77895 -274.827742) (xy 107.821611 -274.797398) (xy 107.844844 -274.785328) (xy 107.873038 -274.771358)
			(xy 107.873038 -273.760946) (xy 107.844844 -273.746976) (xy 107.82179 -273.734925) (xy 107.77948 -273.704661)
			(xy 107.742471 -273.668105) (xy 107.711688 -273.626172) (xy 107.687901 -273.57991) (xy 107.671704 -273.530477)
			(xy 107.663503 -273.479109) (xy 107.663503 -273.42709) (xy 107.671704 -273.375721) (xy 107.687901 -273.326288)
			(xy 107.711689 -273.280026) (xy 107.742472 -273.238093) (xy 107.779482 -273.201538) (xy 107.821791 -273.171275)
			(xy 107.844844 -273.15922) (xy 107.873038 -273.14525) (xy 107.873038 -272.13306) (xy 107.844844 -272.11909)
			(xy 107.821789 -272.107039) (xy 107.779477 -272.076774) (xy 107.742466 -272.040218) (xy 107.711681 -271.998284)
			(xy 107.687891 -271.952021) (xy 107.671693 -271.902586) (xy 107.663491 -271.851216) (xy 107.66349 -271.799195)
			(xy 107.671691 -271.747824) (xy 107.687887 -271.698389) (xy 107.711675 -271.652125) (xy 107.742459 -271.61019)
			(xy 107.779469 -271.573633) (xy 107.821779 -271.543367) (xy 107.844844 -271.531334) (xy 107.873038 -271.517364)
			(xy 107.873038 -270.505428) (xy 107.844844 -270.491458) (xy 107.821791 -270.479407) (xy 107.779484 -270.449143)
			(xy 107.742478 -270.412589) (xy 107.711697 -270.370657) (xy 107.687912 -270.324397) (xy 107.671718 -270.274966)
			(xy 107.663519 -270.223599) (xy 107.66352 -270.171583) (xy 107.671722 -270.120217) (xy 107.687919 -270.070787)
			(xy 107.711707 -270.024528) (xy 107.74249 -269.982598) (xy 107.779498 -269.946045) (xy 107.821806 -269.915784)
			(xy 107.844844 -269.903702) (xy 107.873038 -269.889732) (xy 107.873038 -268.877542) (xy 107.844844 -268.863572)
			(xy 107.82179 -268.851521) (xy 107.779481 -268.821257) (xy 107.742473 -268.784701) (xy 107.71169 -268.742769)
			(xy 107.687903 -268.696507) (xy 107.671707 -268.647075) (xy 107.663507 -268.595707) (xy 107.663507 -268.543688)
			(xy 107.671708 -268.49232) (xy 107.687905 -268.442888) (xy 107.711693 -268.396627) (xy 107.742476 -268.354694)
			(xy 107.779485 -268.31814) (xy 107.821795 -268.287877) (xy 107.844844 -268.275816) (xy 107.873038 -268.261846)
			(xy 107.873038 -267.249656) (xy 107.844844 -267.235686) (xy 107.821789 -267.223635) (xy 107.779478 -267.19337)
			(xy 107.742467 -267.156814) (xy 107.711683 -267.114881) (xy 107.687894 -267.068618) (xy 107.671696 -267.019184)
			(xy 107.663495 -266.967814) (xy 107.663494 -266.915793) (xy 107.671695 -266.864423) (xy 107.687891 -266.814989)
			(xy 107.711679 -266.768725) (xy 107.742463 -266.726791) (xy 107.779472 -266.690234) (xy 107.821783 -266.659969)
			(xy 107.844844 -266.64793) (xy 107.873038 -266.63396) (xy 107.873038 -265.622024) (xy 107.844844 -265.608054)
			(xy 107.821791 -265.596003) (xy 107.779485 -265.565739) (xy 107.74248 -265.529185) (xy 107.7117 -265.487253)
			(xy 107.687915 -265.440994) (xy 107.671721 -265.391563) (xy 107.663522 -265.340197) (xy 107.663524 -265.288181)
			(xy 107.671726 -265.236816) (xy 107.687923 -265.187386) (xy 107.711711 -265.141128) (xy 107.742494 -265.099199)
			(xy 107.779502 -265.062647) (xy 107.82181 -265.032386) (xy 107.844844 -265.020298) (xy 107.873038 -265.006328)
			(xy 107.873038 -264.922) (xy 107.717336 -264.766298) (xy 107.683808 -264.785602) (xy 107.658866 -264.799108)
			(xy 107.605486 -264.818267) (xy 107.549606 -264.82796) (xy 107.521248 -264.828528) (xy 107.495457 -264.828052)
			(xy 107.444509 -264.819989) (xy 107.395451 -264.804054) (xy 107.34949 -264.780639) (xy 107.307758 -264.750322)
			(xy 107.271284 -264.713848) (xy 107.240965 -264.672117) (xy 107.217549 -264.626157) (xy 107.201613 -264.577098)
			(xy 107.193549 -264.526151) (xy 107.19308 -264.50036) (xy 107.193654 -264.472002) (xy 107.203349 -264.416123)
			(xy 107.222495 -264.362738) (xy 107.236006 -264.3378) (xy 107.25531 -264.304272) (xy 106.735372 -263.784334)
			(xy 106.718113 -263.766293) (xy 106.690358 -263.724799) (xy 106.671247 -263.678681) (xy 106.661519 -263.629717)
			(xy 106.66095 -263.604756) (xy 106.66095 -262.118094) (xy 106.661522 -262.093134) (xy 106.671264 -262.044174)
			(xy 106.690371 -261.998056) (xy 106.71811 -261.956553) (xy 106.735372 -261.938516) (xy 107.069636 -261.604252)
			(xy 107.087677 -261.586992) (xy 107.129171 -261.559234) (xy 107.175289 -261.54012) (xy 107.224253 -261.530386)
			(xy 107.249214 -261.52983) (xy 107.45216 -261.52983) (xy 107.64393 -261.33806) (xy 107.64393 -261.1882)
			(xy 107.524042 -261.068312) (xy 105.571544 -261.068312) (xy 105.546589 -261.067695) (xy 105.497641 -261.057949)
			(xy 105.451534 -261.038841) (xy 105.41004 -261.011107) (xy 105.391966 -260.99389) (xy 105.297986 -260.89991)
			(xy 105.20045 -260.89991) (xy 105.20045 -260.900164) (xy 104.643936 -260.900164) (xy 104.328468 -261.215886)
			(xy 104.328468 -261.53999) (xy 104.412796 -261.624572) (xy 104.412796 -261.624826) (xy 104.502458 -261.714234)
			(xy 104.51313 -261.725559) (xy 104.529103 -261.752253) (xy 104.538104 -261.782031) (xy 104.539288 -261.797546)
			(xy 104.558301 -261.809008) (xy 104.592347 -261.837494) (xy 104.62092 -261.871467) (xy 104.643148 -261.909893)
			(xy 104.658354 -261.951599) (xy 104.666073 -261.995314) (xy 104.666542 -262.01751) (xy 104.666542 -266.33551)
			(xy 104.66597 -266.36047) (xy 104.656227 -266.409429) (xy 104.637119 -266.455546) (xy 104.609379 -266.497048)
			(xy 104.59212 -266.515088) (xy 102.89032 -268.216888) (xy 102.872279 -268.234148) (xy 102.830786 -268.261905)
			(xy 102.784668 -268.281016) (xy 102.735703 -268.290744) (xy 102.710742 -268.29131) (xy 96.640142 -268.29131)
			(xy 96.615188 -268.290693) (xy 96.566239 -268.280946) (xy 96.520133 -268.261838) (xy 96.478639 -268.234104)
			(xy 96.460564 -268.216888) (xy 96.319848 -268.076172) (xy 96.294194 -268.079982) (xy 96.281578 -268.081868)
			(xy 96.256149 -268.083906) (xy 96.243394 -268.084046) (xy 96.217605 -268.083566) (xy 96.166663 -268.075497)
			(xy 96.11761 -268.059557) (xy 96.071655 -268.03614) (xy 96.029929 -268.005822) (xy 95.99346 -267.969349)
			(xy 95.963146 -267.927621) (xy 95.939732 -267.881664) (xy 95.923797 -267.83261) (xy 95.915732 -267.781667)
			(xy 95.915226 -267.755878) (xy 95.91538 -267.743123) (xy 95.917413 -267.717695) (xy 95.91929 -267.705078)
			(xy 95.9231 -267.679424) (xy 93.886528 -265.642852) (xy 93.867732 -265.641328) (xy 93.842136 -265.638763)
			(xy 93.792137 -265.626682) (xy 93.744635 -265.606948) (xy 93.700793 -265.580046) (xy 93.661686 -265.546633)
			(xy 93.628269 -265.507527) (xy 93.601363 -265.463688) (xy 93.581626 -265.416187) (xy 93.569541 -265.366189)
			(xy 93.566996 -265.340592) (xy 93.565472 -265.321796) (xy 92.202 -263.958324) (xy 92.16898 -263.976104)
			(xy 92.145643 -263.987975) (xy 92.096122 -264.00497) (xy 92.044531 -264.013889) (xy 91.992178 -264.014505)
			(xy 91.940392 -264.006802) (xy 91.890485 -263.990976) (xy 91.843723 -263.967428) (xy 91.801292 -263.936756)
			(xy 91.764269 -263.899736) (xy 91.733592 -263.857309) (xy 91.710038 -263.81055) (xy 91.694207 -263.760645)
			(xy 91.686498 -263.70886) (xy 91.687108 -263.656507) (xy 91.69602 -263.604915) (xy 91.71301 -263.555392)
			(xy 91.724988 -263.532112) (xy 91.742768 -263.499092) (xy 91.419934 -263.176258) (xy 91.411298 -263.172448)
			(xy 91.389396 -263.16226) (xy 91.348592 -263.136406) (xy 91.31202 -263.10485) (xy 91.280469 -263.068274)
			(xy 91.25462 -263.027467) (xy 91.24442 -263.00557) (xy 91.24061 -262.996934) (xy 89.792302 -261.548626)
			(xy 89.763092 -261.558024) (xy 89.739126 -261.565037) (xy 89.689761 -261.572559) (xy 89.664794 -261.57301)
			(xy 89.639006 -261.572504) (xy 89.588064 -261.564435) (xy 89.539011 -261.548498) (xy 89.493055 -261.525083)
			(xy 89.451327 -261.494769) (xy 89.414855 -261.4583) (xy 89.384535 -261.416576) (xy 89.361116 -261.370623)
			(xy 89.345173 -261.321571) (xy 89.337099 -261.27063) (xy 89.336626 -261.244842) (xy 89.336967 -261.223188)
			(xy 89.342662 -261.180257) (xy 89.353971 -261.138452) (xy 89.362026 -261.11835) (xy 89.348564 -261.104888)
			(xy 89.331302 -261.086848) (xy 89.303538 -261.045355) (xy 89.284419 -260.999237) (xy 89.27468 -260.950272)
			(xy 89.274142 -260.92531) (xy 89.274142 -249.790712) (xy 89.267792 -249.779028) (xy 89.254879 -249.754533)
			(xy 89.236545 -249.702287) (xy 89.227219 -249.647708) (xy 89.226644 -249.620024) (xy 89.227212 -249.592337)
			(xy 89.236505 -249.537748) (xy 89.254847 -249.485501) (xy 89.267792 -249.46102) (xy 89.274142 -249.449336)
			(xy 89.274142 -248.162318) (xy 89.267792 -248.150888) (xy 89.254918 -248.126429) (xy 89.236665 -248.074263)
			(xy 89.22743 -248.019772) (xy 89.226898 -247.992138) (xy 89.227468 -247.964507) (xy 89.236712 -247.910023)
			(xy 89.254928 -247.857849) (xy 89.267792 -247.833388) (xy 89.274142 -247.821958) (xy 89.274142 -246.535194)
			(xy 89.267792 -246.52351) (xy 89.254881 -246.499014) (xy 89.236549 -246.446768) (xy 89.227226 -246.39219)
			(xy 89.226644 -246.364506) (xy 89.227213 -246.336819) (xy 89.236509 -246.282232) (xy 89.254854 -246.229986)
			(xy 89.267792 -246.205502) (xy 89.274142 -246.193818) (xy 89.274142 -244.907308) (xy 89.267792 -244.895624)
			(xy 89.254879 -244.871128) (xy 89.236546 -244.818882) (xy 89.227221 -244.764304) (xy 89.226644 -244.73662)
			(xy 89.227212 -244.708933) (xy 89.236506 -244.654345) (xy 89.254849 -244.602097) (xy 89.267792 -244.577616)
			(xy 89.274142 -244.565932) (xy 89.274142 -243.279676) (xy 89.267792 -243.267992) (xy 89.254882 -243.243496)
			(xy 89.236554 -243.191249) (xy 89.227234 -243.136671) (xy 89.226644 -243.108988) (xy 89.227215 -243.081302)
			(xy 89.236513 -243.026716) (xy 89.25486 -242.974471) (xy 89.267792 -242.949984) (xy 89.274142 -242.9383)
			(xy 89.274142 -241.65179) (xy 89.267792 -241.640106) (xy 89.254881 -241.61561) (xy 89.23655 -241.563364)
			(xy 89.227228 -241.508786) (xy 89.226644 -241.481102) (xy 89.227214 -241.453415) (xy 89.23651 -241.398828)
			(xy 89.254855 -241.346583) (xy 89.267792 -241.322098) (xy 89.274142 -241.310414) (xy 89.274142 -240.023904)
			(xy 89.267792 -240.01222) (xy 89.25488 -239.987724) (xy 89.236547 -239.935478) (xy 89.227222 -239.8809)
			(xy 89.226644 -239.853216) (xy 89.227213 -239.825529) (xy 89.236507 -239.770941) (xy 89.25485 -239.718694)
			(xy 89.267792 -239.694212) (xy 89.274142 -239.682528) (xy 89.274142 -238.396272) (xy 89.267792 -238.384588)
			(xy 89.254882 -238.360092) (xy 89.236555 -238.307845) (xy 89.227235 -238.253267) (xy 89.226644 -238.225584)
			(xy 89.227215 -238.197898) (xy 89.236514 -238.143312) (xy 89.254862 -238.091068) (xy 89.267792 -238.06658)
			(xy 89.274142 -238.054896) (xy 89.274142 -236.76864) (xy 89.267792 -236.756956) (xy 89.254885 -236.732459)
			(xy 89.236562 -236.680212) (xy 89.227248 -236.625635) (xy 89.226644 -236.597952) (xy 89.227218 -236.570267)
			(xy 89.236522 -236.515683) (xy 89.254874 -236.463442) (xy 89.267792 -236.438948) (xy 89.274142 -236.427264)
			(xy 89.274142 -235.140754) (xy 89.267792 -235.12907) (xy 89.254884 -235.104574) (xy 89.236559 -235.052327)
			(xy 89.227242 -234.997749) (xy 89.226644 -234.970066) (xy 89.227217 -234.94238) (xy 89.236519 -234.887796)
			(xy 89.254868 -234.835553) (xy 89.267792 -234.811062) (xy 89.274142 -234.799378) (xy 89.274142 -233.665522)
			(xy 89.274525 -233.645656) (xy 89.280709 -233.606409) (xy 89.292929 -233.568604) (xy 89.301574 -233.550714)
			(xy 89.284041 -233.528525) (xy 89.256075 -233.479377) (xy 89.236953 -233.426161) (xy 89.227241 -233.370454)
			(xy 89.226644 -233.34218) (xy 89.227151 -233.316394) (xy 89.235222 -233.265457) (xy 89.251161 -233.216409)
			(xy 89.274577 -233.170459) (xy 89.304893 -233.128738) (xy 89.341362 -233.092272) (xy 89.383086 -233.061961)
			(xy 89.429039 -233.038549) (xy 89.478088 -233.022614) (xy 89.529026 -233.014549) (xy 89.554812 -233.014012)
			(xy 89.58392 -233.014659) (xy 89.641216 -233.024968) (xy 89.695795 -233.045225) (xy 89.721182 -233.059478)
			(xy 89.755218 -233.07929) (xy 91.10599 -231.728518) (xy 91.106244 -231.708198) (xy 91.107208 -231.683054)
			(xy 91.115841 -231.633483) (xy 91.131939 -231.585811) (xy 91.155125 -231.541154) (xy 91.184855 -231.50056)
			(xy 91.220432 -231.464978) (xy 91.261023 -231.435244) (xy 91.305677 -231.412054) (xy 91.353347 -231.39595)
			(xy 91.402917 -231.387312) (xy 91.428062 -231.38638) (xy 91.448382 -231.386126) (xy 93.468444 -229.366064)
			(xy 93.462856 -229.339394) (xy 93.45965 -229.322944) (xy 93.456216 -229.289604) (xy 93.455998 -229.272846)
			(xy 93.456474 -229.247053) (xy 93.464537 -229.196101) (xy 93.480471 -229.147038) (xy 93.503885 -229.101072)
			(xy 93.534201 -229.059334) (xy 93.570673 -229.022853) (xy 93.612403 -228.992526) (xy 93.658364 -228.969102)
			(xy 93.707423 -228.953155) (xy 93.758373 -228.94508) (xy 93.784166 -228.944678) (xy 93.800923 -228.944904)
			(xy 93.834262 -228.948345) (xy 93.850714 -228.951536) (xy 93.877384 -228.957124) (xy 95.844614 -226.989894)
			(xy 95.831152 -226.958652) (xy 95.823018 -226.938391) (xy 95.811581 -226.896256) (xy 95.805841 -226.852974)
			(xy 95.805498 -226.831144) (xy 95.805974 -226.805351) (xy 95.814037 -226.754399) (xy 95.829972 -226.705337)
			(xy 95.853385 -226.659371) (xy 95.883701 -226.617633) (xy 95.920174 -226.581152) (xy 95.961904 -226.550826)
			(xy 96.007864 -226.527402) (xy 96.056924 -226.511455) (xy 96.107873 -226.50338) (xy 96.133666 -226.502976)
			(xy 96.155496 -226.503317) (xy 96.198776 -226.509066) (xy 96.240914 -226.520493) (xy 96.261174 -226.52863)
			(xy 96.292416 -226.542092) (xy 96.854518 -225.97999) (xy 96.854518 -225.449892) (xy 96.834028 -225.430965)
			(xy 96.799098 -225.387483) (xy 96.771989 -225.338739) (xy 96.753477 -225.286125) (xy 96.744091 -225.231146)
			(xy 96.74352 -225.203258) (xy 96.744111 -225.17554) (xy 96.753435 -225.120894) (xy 96.762062 -225.094546)
			(xy 96.769936 -225.072448) (xy 96.564958 -224.71761) (xy 96.542098 -224.713292) (xy 96.517295 -224.708095)
			(xy 96.469554 -224.691108) (xy 96.424973 -224.667016) (xy 96.384604 -224.636387) (xy 96.349396 -224.599942)
			(xy 96.320178 -224.55854) (xy 96.297639 -224.513155) (xy 96.282309 -224.464855) (xy 96.27455 -224.414779)
			(xy 96.274128 -224.389442) (xy 96.274606 -224.363549) (xy 96.282701 -224.312401) (xy 96.298697 -224.263148)
			(xy 96.322201 -224.217005) (xy 96.352635 -224.175106) (xy 96.389248 -224.138484) (xy 96.43114 -224.108041)
			(xy 96.477278 -224.084526) (xy 96.526527 -224.068518) (xy 96.577674 -224.060412) (xy 96.603566 -224.060004)
			(xy 96.6327 -224.060605) (xy 96.690061 -224.070832) (xy 96.717612 -224.080324) (xy 96.730891 -224.084773)
			(xy 96.758798 -224.087004) (xy 96.786261 -224.081569) (xy 96.811214 -224.068877) (xy 96.831781 -224.049883)
			(xy 96.846415 -224.026017) (xy 96.854013 -223.999072) (xy 96.854518 -223.985074) (xy 96.854518 -223.819974)
			(xy 96.836148 -223.802896) (xy 96.804301 -223.764149) (xy 96.778726 -223.721004) (xy 96.760019 -223.674468)
			(xy 96.748616 -223.625626) (xy 96.744784 -223.575617) (xy 96.748611 -223.525608) (xy 96.760009 -223.476765)
			(xy 96.778711 -223.430227) (xy 96.804281 -223.38708) (xy 96.836124 -223.348329) (xy 96.854518 -223.331278)
			(xy 96.854518 -222.194374) (xy 96.834029 -222.175447) (xy 96.799101 -222.131964) (xy 96.771995 -222.083219)
			(xy 96.753486 -222.030606) (xy 96.744103 -221.975627) (xy 96.74352 -221.94774) (xy 96.744113 -221.920023)
			(xy 96.753439 -221.865377) (xy 96.762062 -221.839028) (xy 96.769936 -221.81693) (xy 96.564958 -221.462092)
			(xy 96.542098 -221.457774) (xy 96.517296 -221.452577) (xy 96.469556 -221.435589) (xy 96.424977 -221.411497)
			(xy 96.384609 -221.380868) (xy 96.349403 -221.344423) (xy 96.320187 -221.30302) (xy 96.297651 -221.257635)
			(xy 96.282323 -221.209336) (xy 96.274567 -221.15926) (xy 96.274128 -221.133924) (xy 96.27489 -221.108524)
			(xy 96.276668 -221.085156) (xy 96.14408 -220.952568) (xy 96.13437 -220.943401) (xy 96.111261 -220.930035)
			(xy 96.085478 -220.923111) (xy 96.058782 -220.923103) (xy 96.032995 -220.930011) (xy 96.009878 -220.943364)
			(xy 95.99101 -220.962249) (xy 95.98406 -220.97365) (xy 95.967042 -221.003114) (xy 95.974916 -221.024958)
			(xy 95.983497 -221.051376) (xy 95.992697 -221.106152) (xy 95.993204 -221.133924) (xy 95.992696 -221.159811)
			(xy 95.984597 -221.210949) (xy 95.968598 -221.260189) (xy 95.945092 -221.306321) (xy 95.91466 -221.348208)
			(xy 95.87805 -221.384818) (xy 95.836163 -221.41525) (xy 95.790031 -221.438756) (xy 95.740791 -221.454755)
			(xy 95.689653 -221.462854) (xy 95.637879 -221.462854) (xy 95.586741 -221.454755) (xy 95.537501 -221.438756)
			(xy 95.491369 -221.41525) (xy 95.449482 -221.384818) (xy 95.412872 -221.348208) (xy 95.38244 -221.306321)
			(xy 95.358934 -221.260189) (xy 95.342935 -221.210949) (xy 95.334836 -221.159811) (xy 95.334328 -221.133924)
			(xy 95.33479 -221.108588) (xy 95.34254 -221.058511) (xy 95.357862 -221.01021) (xy 95.380394 -220.964822)
			(xy 95.409605 -220.923417) (xy 95.444809 -220.886969) (xy 95.485175 -220.856337) (xy 95.529753 -220.832242)
			(xy 95.577492 -220.815252) (xy 95.602298 -220.810074) (xy 95.625158 -220.805756) (xy 95.761302 -220.56979)
			(xy 94.98838 -219.796868) (xy 94.971118 -219.778828) (xy 94.943356 -219.737335) (xy 94.924239 -219.691217)
			(xy 94.914504 -219.642252) (xy 94.913958 -219.61729) (xy 94.913958 -218.867228) (xy 94.907354 -218.855544)
			(xy 94.893734 -218.830498) (xy 94.87438 -218.776876) (xy 94.864537 -218.720725) (xy 94.86392 -218.692222)
			(xy 94.864506 -218.664503) (xy 94.87382 -218.609853) (xy 94.882462 -218.58351) (xy 94.890336 -218.561412)
			(xy 94.685358 -218.206574) (xy 94.662498 -218.202256) (xy 94.637867 -218.197097) (xy 94.590431 -218.180303)
			(xy 94.546102 -218.156488) (xy 94.505912 -218.126206) (xy 94.488 -218.10853) (xy 94.020132 -218.10853)
			(xy 94.001383 -218.126991) (xy 93.959108 -218.158311) (xy 93.912392 -218.182515) (xy 93.862424 -218.198989)
			(xy 93.810473 -218.207312) (xy 93.784166 -218.207844) (xy 93.757857 -218.20735) (xy 93.705901 -218.199026)
			(xy 93.655931 -218.182547) (xy 93.609216 -218.158332) (xy 93.566945 -218.126998) (xy 93.5482 -218.10853)
			(xy 93.381068 -218.10853) (xy 93.365834 -218.1091) (xy 93.336718 -218.118079) (xy 93.311535 -218.135232)
			(xy 93.292519 -218.159038) (xy 93.281353 -218.187387) (xy 93.279028 -218.217767) (xy 93.285749 -218.247486)
			(xy 93.29293 -218.26093) (xy 93.35262 -218.364054) (xy 93.37548 -218.368372) (xy 93.40029 -218.373561)
			(xy 93.448049 -218.390535) (xy 93.492648 -218.414618) (xy 93.533036 -218.445243) (xy 93.568262 -218.481687)
			(xy 93.597496 -218.523092) (xy 93.62005 -218.568484) (xy 93.635391 -218.616792) (xy 93.643159 -218.666879)
			(xy 93.643704 -218.692222) (xy 93.643196 -218.718129) (xy 93.63509 -218.769306) (xy 93.619078 -218.818585)
			(xy 93.595555 -218.864752) (xy 93.565099 -218.906671) (xy 93.528461 -218.943309) (xy 93.486542 -218.973765)
			(xy 93.440375 -218.997288) (xy 93.391096 -219.0133) (xy 93.339919 -219.021406) (xy 93.288105 -219.021406)
			(xy 93.236928 -219.0133) (xy 93.187649 -218.997288) (xy 93.141482 -218.973765) (xy 93.099563 -218.943309)
			(xy 93.062925 -218.906671) (xy 93.032469 -218.864752) (xy 93.008946 -218.818585) (xy 92.992934 -218.769306)
			(xy 92.984828 -218.718129) (xy 92.98432 -218.692222) (xy 92.984906 -218.664503) (xy 92.99422 -218.609853)
			(xy 93.002862 -218.58351) (xy 93.010736 -218.561412) (xy 92.805758 -218.206574) (xy 92.782898 -218.202256)
			(xy 92.758267 -218.197097) (xy 92.710831 -218.180303) (xy 92.666502 -218.156488) (xy 92.626312 -218.126206)
			(xy 92.6084 -218.10853) (xy 92.140532 -218.10853) (xy 92.121783 -218.126991) (xy 92.079508 -218.158311)
			(xy 92.032792 -218.182515) (xy 91.982824 -218.198989) (xy 91.930873 -218.207312) (xy 91.904566 -218.207844)
			(xy 91.878257 -218.20735) (xy 91.826301 -218.199026) (xy 91.776331 -218.182547) (xy 91.729616 -218.158332)
			(xy 91.687345 -218.126998) (xy 91.6686 -218.10853) (xy 91.501468 -218.10853) (xy 91.486234 -218.1091)
			(xy 91.457118 -218.118079) (xy 91.431935 -218.135232) (xy 91.412919 -218.159038) (xy 91.401753 -218.187387)
			(xy 91.399428 -218.217767) (xy 91.406149 -218.247486) (xy 91.41333 -218.26093) (xy 91.47302 -218.364054)
			(xy 91.49588 -218.368372) (xy 91.52069 -218.373561) (xy 91.568449 -218.390535) (xy 91.613048 -218.414618)
			(xy 91.653436 -218.445243) (xy 91.688662 -218.481687) (xy 91.717896 -218.523092) (xy 91.74045 -218.568484)
			(xy 91.755791 -218.616792) (xy 91.763559 -218.666879) (xy 91.764104 -218.692222) (xy 91.763596 -218.718129)
			(xy 91.75549 -218.769306) (xy 91.739478 -218.818585) (xy 91.715955 -218.864752) (xy 91.685499 -218.906671)
			(xy 91.648861 -218.943309) (xy 91.606942 -218.973765) (xy 91.560775 -218.997288) (xy 91.511496 -219.0133)
			(xy 91.460319 -219.021406) (xy 91.408505 -219.021406) (xy 91.357328 -219.0133) (xy 91.308049 -218.997288)
			(xy 91.261882 -218.973765) (xy 91.219963 -218.943309) (xy 91.183325 -218.906671) (xy 91.152869 -218.864752)
			(xy 91.129346 -218.818585) (xy 91.113334 -218.769306) (xy 91.105228 -218.718129) (xy 91.10472 -218.692222)
			(xy 91.105306 -218.664503) (xy 91.11462 -218.609853) (xy 91.123262 -218.58351) (xy 91.131136 -218.561412)
			(xy 90.926158 -218.206574) (xy 90.903298 -218.202256) (xy 90.878667 -218.197097) (xy 90.831231 -218.180303)
			(xy 90.786902 -218.156488) (xy 90.746712 -218.126206) (xy 90.7288 -218.10853) (xy 90.260932 -218.10853)
			(xy 90.242183 -218.126991) (xy 90.199908 -218.158311) (xy 90.153192 -218.182515) (xy 90.103224 -218.198989)
			(xy 90.051273 -218.207312) (xy 90.024966 -218.207844) (xy 89.998657 -218.20735) (xy 89.946701 -218.199026)
			(xy 89.896731 -218.182547) (xy 89.850016 -218.158332) (xy 89.807745 -218.126998) (xy 89.789 -218.10853)
			(xy 89.669874 -218.10853) (xy 89.527888 -218.250516) (xy 89.59342 -218.364054) (xy 89.61628 -218.368372)
			(xy 89.64109 -218.373561) (xy 89.688849 -218.390535) (xy 89.733448 -218.414618) (xy 89.773836 -218.445243)
			(xy 89.809062 -218.481687) (xy 89.838296 -218.523092) (xy 89.86085 -218.568484) (xy 89.876191 -218.616792)
			(xy 89.883959 -218.666879) (xy 89.884504 -218.692222) (xy 89.883996 -218.718129) (xy 89.87589 -218.769306)
			(xy 89.859878 -218.818585) (xy 89.836355 -218.864752) (xy 89.805899 -218.906671) (xy 89.769261 -218.943309)
			(xy 89.727342 -218.973765) (xy 89.681175 -218.997288) (xy 89.631896 -219.0133) (xy 89.580719 -219.021406)
			(xy 89.528905 -219.021406) (xy 89.477728 -219.0133) (xy 89.428449 -218.997288) (xy 89.382282 -218.973765)
			(xy 89.340363 -218.943309) (xy 89.303725 -218.906671) (xy 89.273269 -218.864752) (xy 89.249746 -218.818585)
			(xy 89.233734 -218.769306) (xy 89.225628 -218.718129) (xy 89.22512 -218.692222) (xy 89.225628 -218.674696)
			(xy 89.225896 -218.660474) (xy 89.219484 -218.632772) (xy 89.205672 -218.607918) (xy 89.185536 -218.587842)
			(xy 89.16064 -218.574106) (xy 89.13292 -218.567777) (xy 89.118694 -218.568016) (xy 89.104978 -218.56827)
			(xy 74.484738 -218.56827) (xy 74.478642 -218.569794) (xy 74.463041 -218.573587) (xy 74.431195 -218.577666)
			(xy 74.415142 -218.577922) (xy 51.395122 -218.577922) (xy 51.388264 -218.62034) (xy 51.383584 -218.645583)
			(xy 51.36742 -218.694308) (xy 51.343867 -218.739923) (xy 51.313501 -218.781316) (xy 51.277061 -218.817476)
			(xy 51.235436 -218.847523) (xy 51.189641 -218.870724) (xy 51.140793 -218.886513) (xy 51.090082 -218.894505)
			(xy 51.038746 -218.894505) (xy 50.988035 -218.886513) (xy 50.939187 -218.870724) (xy 50.893392 -218.847523)
			(xy 50.851767 -218.817476) (xy 50.815327 -218.781316) (xy 50.784961 -218.739923) (xy 50.761408 -218.694308)
			(xy 50.745244 -218.645583) (xy 50.740564 -218.62034) (xy 50.733706 -218.577922) (xy 47.295054 -218.577922)
			(xy 47.288196 -218.62034) (xy 47.283516 -218.645583) (xy 47.267352 -218.694308) (xy 47.243799 -218.739923)
			(xy 47.213433 -218.781316) (xy 47.176993 -218.817476) (xy 47.135368 -218.847523) (xy 47.089573 -218.870724)
			(xy 47.040725 -218.886513) (xy 46.990014 -218.894505) (xy 46.938678 -218.894505) (xy 46.887967 -218.886513)
			(xy 46.839119 -218.870724) (xy 46.793324 -218.847523) (xy 46.751699 -218.817476) (xy 46.715259 -218.781316)
			(xy 46.684893 -218.739923) (xy 46.66134 -218.694308) (xy 46.645176 -218.645583) (xy 46.640496 -218.62034)
			(xy 46.633638 -218.577922) (xy 36.307522 -218.577922) (xy 36.300664 -218.62034) (xy 36.295984 -218.645583)
			(xy 36.27982 -218.694308) (xy 36.256267 -218.739923) (xy 36.225901 -218.781316) (xy 36.189461 -218.817476)
			(xy 36.147836 -218.847523) (xy 36.102041 -218.870724) (xy 36.053193 -218.886513) (xy 36.002482 -218.894505)
			(xy 35.951146 -218.894505) (xy 35.900435 -218.886513) (xy 35.851587 -218.870724) (xy 35.805792 -218.847523)
			(xy 35.764167 -218.817476) (xy 35.727727 -218.781316) (xy 35.697361 -218.739923) (xy 35.673808 -218.694308)
			(xy 35.657644 -218.645583) (xy 35.652964 -218.62034) (xy 35.646106 -218.577922) (xy 32.276542 -218.577922)
			(xy 32.190436 -218.664028) (xy 32.186626 -218.67495) (xy 32.1781 -218.69803) (xy 32.155127 -218.741537)
			(xy 32.125918 -218.781129) (xy 32.091129 -218.815918) (xy 32.051537 -218.845127) (xy 32.00803 -218.8681)
			(xy 31.98495 -218.876626) (xy 31.974028 -218.880436) (xy 31.743142 -219.111322) (xy 31.743142 -221.133924)
			(xy 88.755728 -221.133924) (xy 88.756236 -221.108037) (xy 88.764335 -221.056899) (xy 88.780334 -221.007659)
			(xy 88.80384 -220.961527) (xy 88.834272 -220.91964) (xy 88.870882 -220.88303) (xy 88.912769 -220.852598)
			(xy 88.958901 -220.829092) (xy 89.008141 -220.813093) (xy 89.059279 -220.804994) (xy 89.111053 -220.804994)
			(xy 89.162191 -220.813093) (xy 89.211431 -220.829092) (xy 89.257563 -220.852598) (xy 89.29945 -220.88303)
			(xy 89.33606 -220.91964) (xy 89.366492 -220.961527) (xy 89.389998 -221.007659) (xy 89.405997 -221.056899)
			(xy 89.414096 -221.108037) (xy 89.414604 -221.133924) (xy 89.695528 -221.133924) (xy 89.69601 -221.108589)
			(xy 89.70376 -221.058515) (xy 89.71908 -221.010217) (xy 89.741611 -220.964832) (xy 89.770821 -220.923429)
			(xy 89.806022 -220.886984) (xy 89.846386 -220.856354) (xy 89.890961 -220.83226) (xy 89.938698 -220.815272)
			(xy 89.963498 -220.810074) (xy 89.986358 -220.805756) (xy 90.191336 -220.450664) (xy 90.183462 -220.42882)
			(xy 90.174829 -220.402408) (xy 90.1655 -220.347635) (xy 90.16492 -220.319854) (xy 90.165428 -220.293947)
			(xy 90.173534 -220.24277) (xy 90.189546 -220.193491) (xy 90.213069 -220.147324) (xy 90.243525 -220.105405)
			(xy 90.280163 -220.068767) (xy 90.322082 -220.038311) (xy 90.368249 -220.014788) (xy 90.417528 -219.998776)
			(xy 90.468705 -219.99067) (xy 90.520519 -219.99067) (xy 90.571696 -219.998776) (xy 90.620975 -220.014788)
			(xy 90.667142 -220.038311) (xy 90.709061 -220.068767) (xy 90.745699 -220.105405) (xy 90.776155 -220.147324)
			(xy 90.799678 -220.193491) (xy 90.81569 -220.24277) (xy 90.823796 -220.293947) (xy 90.824304 -220.319854)
			(xy 90.823828 -220.345199) (xy 90.816049 -220.395289) (xy 90.800697 -220.443599) (xy 90.778134 -220.48899)
			(xy 90.748891 -220.530396) (xy 90.713657 -220.566839) (xy 90.673262 -220.597461) (xy 90.628657 -220.621543)
			(xy 90.580893 -220.638516) (xy 90.55608 -220.643704) (xy 90.53322 -220.648022) (xy 90.328242 -221.003114)
			(xy 90.336116 -221.024958) (xy 90.34471 -221.051373) (xy 90.353897 -221.106151) (xy 90.354404 -221.133924)
			(xy 90.635328 -221.133924) (xy 90.635836 -221.108037) (xy 90.643935 -221.056899) (xy 90.659934 -221.007659)
			(xy 90.68344 -220.961527) (xy 90.713872 -220.91964) (xy 90.750482 -220.88303) (xy 90.792369 -220.852598)
			(xy 90.838501 -220.829092) (xy 90.887741 -220.813093) (xy 90.938879 -220.804994) (xy 90.990653 -220.804994)
			(xy 91.041791 -220.813093) (xy 91.091031 -220.829092) (xy 91.137163 -220.852598) (xy 91.17905 -220.88303)
			(xy 91.21566 -220.91964) (xy 91.246092 -220.961527) (xy 91.269598 -221.007659) (xy 91.285597 -221.056899)
			(xy 91.293696 -221.108037) (xy 91.294204 -221.133924) (xy 91.575128 -221.133924) (xy 91.57561 -221.108589)
			(xy 91.58336 -221.058515) (xy 91.59868 -221.010217) (xy 91.621211 -220.964832) (xy 91.650421 -220.923429)
			(xy 91.685622 -220.886984) (xy 91.725986 -220.856354) (xy 91.770561 -220.83226) (xy 91.818298 -220.815272)
			(xy 91.843098 -220.810074) (xy 91.865958 -220.805756) (xy 92.070936 -220.450664) (xy 92.063062 -220.42882)
			(xy 92.054429 -220.402408) (xy 92.0451 -220.347635) (xy 92.04452 -220.319854) (xy 92.045028 -220.293947)
			(xy 92.053134 -220.24277) (xy 92.069146 -220.193491) (xy 92.092669 -220.147324) (xy 92.123125 -220.105405)
			(xy 92.159763 -220.068767) (xy 92.201682 -220.038311) (xy 92.247849 -220.014788) (xy 92.297128 -219.998776)
			(xy 92.348305 -219.99067) (xy 92.400119 -219.99067) (xy 92.451296 -219.998776) (xy 92.500575 -220.014788)
			(xy 92.546742 -220.038311) (xy 92.588661 -220.068767) (xy 92.625299 -220.105405) (xy 92.655755 -220.147324)
			(xy 92.679278 -220.193491) (xy 92.69529 -220.24277) (xy 92.703396 -220.293947) (xy 92.703904 -220.319854)
			(xy 92.703428 -220.345199) (xy 92.695649 -220.395289) (xy 92.680297 -220.443599) (xy 92.657734 -220.48899)
			(xy 92.628491 -220.530396) (xy 92.593257 -220.566839) (xy 92.552862 -220.597461) (xy 92.508257 -220.621543)
			(xy 92.460493 -220.638516) (xy 92.43568 -220.643704) (xy 92.41282 -220.648022) (xy 92.207842 -221.003114)
			(xy 92.215716 -221.024958) (xy 92.22431 -221.051373) (xy 92.233497 -221.106151) (xy 92.234004 -221.133924)
			(xy 92.514928 -221.133924) (xy 92.515436 -221.108037) (xy 92.523535 -221.056899) (xy 92.539534 -221.007659)
			(xy 92.56304 -220.961527) (xy 92.593472 -220.91964) (xy 92.630082 -220.88303) (xy 92.671969 -220.852598)
			(xy 92.718101 -220.829092) (xy 92.767341 -220.813093) (xy 92.818479 -220.804994) (xy 92.870253 -220.804994)
			(xy 92.921391 -220.813093) (xy 92.970631 -220.829092) (xy 93.016763 -220.852598) (xy 93.05865 -220.88303)
			(xy 93.09526 -220.91964) (xy 93.125692 -220.961527) (xy 93.149198 -221.007659) (xy 93.165197 -221.056899)
			(xy 93.173296 -221.108037) (xy 93.173804 -221.133924) (xy 93.454728 -221.133924) (xy 93.45521 -221.108589)
			(xy 93.46296 -221.058515) (xy 93.47828 -221.010217) (xy 93.500811 -220.964832) (xy 93.530021 -220.923429)
			(xy 93.565222 -220.886984) (xy 93.605586 -220.856354) (xy 93.650161 -220.83226) (xy 93.697898 -220.815272)
			(xy 93.722698 -220.810074) (xy 93.745558 -220.805756) (xy 93.950536 -220.450664) (xy 93.942662 -220.42882)
			(xy 93.934029 -220.402408) (xy 93.9247 -220.347635) (xy 93.92412 -220.319854) (xy 93.924628 -220.293947)
			(xy 93.932734 -220.24277) (xy 93.948746 -220.193491) (xy 93.972269 -220.147324) (xy 94.002725 -220.105405)
			(xy 94.039363 -220.068767) (xy 94.081282 -220.038311) (xy 94.127449 -220.014788) (xy 94.176728 -219.998776)
			(xy 94.227905 -219.99067) (xy 94.279719 -219.99067) (xy 94.330896 -219.998776) (xy 94.380175 -220.014788)
			(xy 94.426342 -220.038311) (xy 94.468261 -220.068767) (xy 94.504899 -220.105405) (xy 94.535355 -220.147324)
			(xy 94.558878 -220.193491) (xy 94.57489 -220.24277) (xy 94.582996 -220.293947) (xy 94.583504 -220.319854)
			(xy 94.583028 -220.345199) (xy 94.575249 -220.395289) (xy 94.559897 -220.443599) (xy 94.537334 -220.48899)
			(xy 94.508091 -220.530396) (xy 94.472857 -220.566839) (xy 94.432462 -220.597461) (xy 94.387857 -220.621543)
			(xy 94.340093 -220.638516) (xy 94.31528 -220.643704) (xy 94.29242 -220.648022) (xy 94.087442 -221.003114)
			(xy 94.095316 -221.024958) (xy 94.10391 -221.051373) (xy 94.113097 -221.106151) (xy 94.113604 -221.133924)
			(xy 94.394528 -221.133924) (xy 94.395036 -221.108037) (xy 94.403135 -221.056899) (xy 94.419134 -221.007659)
			(xy 94.44264 -220.961527) (xy 94.473072 -220.91964) (xy 94.509682 -220.88303) (xy 94.551569 -220.852598)
			(xy 94.597701 -220.829092) (xy 94.646941 -220.813093) (xy 94.698079 -220.804994) (xy 94.749853 -220.804994)
			(xy 94.800991 -220.813093) (xy 94.850231 -220.829092) (xy 94.896363 -220.852598) (xy 94.93825 -220.88303)
			(xy 94.97486 -220.91964) (xy 95.005292 -220.961527) (xy 95.028798 -221.007659) (xy 95.044797 -221.056899)
			(xy 95.052896 -221.108037) (xy 95.053404 -221.133924) (xy 95.05288 -221.161632) (xy 95.043681 -221.216279)
			(xy 95.035116 -221.242636) (xy 95.027242 -221.264734) (xy 95.23222 -221.619572) (xy 95.25508 -221.62389)
			(xy 95.279905 -221.629041) (xy 95.327683 -221.645999) (xy 95.372302 -221.670074) (xy 95.412707 -221.700696)
			(xy 95.447947 -221.737145) (xy 95.47719 -221.778561) (xy 95.499747 -221.823965) (xy 95.515085 -221.872289)
			(xy 95.522842 -221.92239) (xy 95.523304 -221.94774) (xy 95.522796 -221.973647) (xy 95.51469 -222.024824)
			(xy 95.498678 -222.074103) (xy 95.475155 -222.12027) (xy 95.444699 -222.162189) (xy 95.408061 -222.198827)
			(xy 95.366142 -222.229283) (xy 95.319975 -222.252806) (xy 95.270696 -222.268818) (xy 95.219519 -222.276924)
			(xy 95.167705 -222.276924) (xy 95.116528 -222.268818) (xy 95.067249 -222.252806) (xy 95.021082 -222.229283)
			(xy 94.979163 -222.198827) (xy 94.942525 -222.162189) (xy 94.912069 -222.12027) (xy 94.888546 -222.074103)
			(xy 94.872534 -222.024824) (xy 94.864428 -221.973647) (xy 94.86392 -221.94774) (xy 94.864523 -221.920023)
			(xy 94.87384 -221.865377) (xy 94.882462 -221.839028) (xy 94.890336 -221.81693) (xy 94.685358 -221.462092)
			(xy 94.662498 -221.457774) (xy 94.637703 -221.45255) (xy 94.589967 -221.435564) (xy 94.545392 -221.411474)
			(xy 94.505027 -221.380847) (xy 94.469824 -221.344405) (xy 94.440611 -221.303006) (xy 94.418076 -221.257625)
			(xy 94.40275 -221.20933) (xy 94.394994 -221.159258) (xy 94.394528 -221.133924) (xy 94.113604 -221.133924)
			(xy 94.113096 -221.159811) (xy 94.104997 -221.210949) (xy 94.088998 -221.260189) (xy 94.065492 -221.306321)
			(xy 94.03506 -221.348208) (xy 93.99845 -221.384818) (xy 93.956563 -221.41525) (xy 93.910431 -221.438756)
			(xy 93.861191 -221.454755) (xy 93.810053 -221.462854) (xy 93.758279 -221.462854) (xy 93.707141 -221.454755)
			(xy 93.657901 -221.438756) (xy 93.611769 -221.41525) (xy 93.569882 -221.384818) (xy 93.533272 -221.348208)
			(xy 93.50284 -221.306321) (xy 93.479334 -221.260189) (xy 93.463335 -221.210949) (xy 93.455236 -221.159811)
			(xy 93.454728 -221.133924) (xy 93.173804 -221.133924) (xy 93.17328 -221.161632) (xy 93.164081 -221.216279)
			(xy 93.155516 -221.242636) (xy 93.147642 -221.264734) (xy 93.35262 -221.619572) (xy 93.37548 -221.62389)
			(xy 93.400305 -221.629041) (xy 93.448083 -221.645999) (xy 93.492702 -221.670074) (xy 93.533107 -221.700696)
			(xy 93.568347 -221.737145) (xy 93.59759 -221.778561) (xy 93.620147 -221.823965) (xy 93.635485 -221.872289)
			(xy 93.643242 -221.92239) (xy 93.643704 -221.94774) (xy 93.643196 -221.973647) (xy 93.63509 -222.024824)
			(xy 93.619078 -222.074103) (xy 93.595555 -222.12027) (xy 93.565099 -222.162189) (xy 93.528461 -222.198827)
			(xy 93.486542 -222.229283) (xy 93.440375 -222.252806) (xy 93.391096 -222.268818) (xy 93.339919 -222.276924)
			(xy 93.288105 -222.276924) (xy 93.236928 -222.268818) (xy 93.187649 -222.252806) (xy 93.141482 -222.229283)
			(xy 93.099563 -222.198827) (xy 93.062925 -222.162189) (xy 93.032469 -222.12027) (xy 93.008946 -222.074103)
			(xy 92.992934 -222.024824) (xy 92.984828 -221.973647) (xy 92.98432 -221.94774) (xy 92.984923 -221.920023)
			(xy 92.99424 -221.865377) (xy 93.002862 -221.839028) (xy 93.010736 -221.81693) (xy 92.805758 -221.462092)
			(xy 92.782898 -221.457774) (xy 92.758103 -221.45255) (xy 92.710367 -221.435564) (xy 92.665792 -221.411474)
			(xy 92.625427 -221.380847) (xy 92.590224 -221.344405) (xy 92.561011 -221.303006) (xy 92.538476 -221.257625)
			(xy 92.52315 -221.20933) (xy 92.515394 -221.159258) (xy 92.514928 -221.133924) (xy 92.234004 -221.133924)
			(xy 92.233496 -221.159811) (xy 92.225397 -221.210949) (xy 92.209398 -221.260189) (xy 92.185892 -221.306321)
			(xy 92.15546 -221.348208) (xy 92.11885 -221.384818) (xy 92.076963 -221.41525) (xy 92.030831 -221.438756)
			(xy 91.981591 -221.454755) (xy 91.930453 -221.462854) (xy 91.878679 -221.462854) (xy 91.827541 -221.454755)
			(xy 91.778301 -221.438756) (xy 91.732169 -221.41525) (xy 91.690282 -221.384818) (xy 91.653672 -221.348208)
			(xy 91.62324 -221.306321) (xy 91.599734 -221.260189) (xy 91.583735 -221.210949) (xy 91.575636 -221.159811)
			(xy 91.575128 -221.133924) (xy 91.294204 -221.133924) (xy 91.29368 -221.161632) (xy 91.284481 -221.216279)
			(xy 91.275916 -221.242636) (xy 91.268042 -221.264734) (xy 91.47302 -221.619572) (xy 91.49588 -221.62389)
			(xy 91.520705 -221.629041) (xy 91.568483 -221.645999) (xy 91.613102 -221.670074) (xy 91.653507 -221.700696)
			(xy 91.688747 -221.737145) (xy 91.71799 -221.778561) (xy 91.740547 -221.823965) (xy 91.755885 -221.872289)
			(xy 91.763642 -221.92239) (xy 91.764104 -221.94774) (xy 91.763596 -221.973647) (xy 91.75549 -222.024824)
			(xy 91.739478 -222.074103) (xy 91.715955 -222.12027) (xy 91.685499 -222.162189) (xy 91.648861 -222.198827)
			(xy 91.606942 -222.229283) (xy 91.560775 -222.252806) (xy 91.511496 -222.268818) (xy 91.460319 -222.276924)
			(xy 91.408505 -222.276924) (xy 91.357328 -222.268818) (xy 91.308049 -222.252806) (xy 91.261882 -222.229283)
			(xy 91.219963 -222.198827) (xy 91.183325 -222.162189) (xy 91.152869 -222.12027) (xy 91.129346 -222.074103)
			(xy 91.113334 -222.024824) (xy 91.105228 -221.973647) (xy 91.10472 -221.94774) (xy 91.105323 -221.920023)
			(xy 91.11464 -221.865377) (xy 91.123262 -221.839028) (xy 91.131136 -221.81693) (xy 90.926158 -221.462092)
			(xy 90.903298 -221.457774) (xy 90.878503 -221.45255) (xy 90.830767 -221.435564) (xy 90.786192 -221.411474)
			(xy 90.745827 -221.380847) (xy 90.710624 -221.344405) (xy 90.681411 -221.303006) (xy 90.658876 -221.257625)
			(xy 90.64355 -221.20933) (xy 90.635794 -221.159258) (xy 90.635328 -221.133924) (xy 90.354404 -221.133924)
			(xy 90.353896 -221.159811) (xy 90.345797 -221.210949) (xy 90.329798 -221.260189) (xy 90.306292 -221.306321)
			(xy 90.27586 -221.348208) (xy 90.23925 -221.384818) (xy 90.197363 -221.41525) (xy 90.151231 -221.438756)
			(xy 90.101991 -221.454755) (xy 90.050853 -221.462854) (xy 89.999079 -221.462854) (xy 89.947941 -221.454755)
			(xy 89.898701 -221.438756) (xy 89.852569 -221.41525) (xy 89.810682 -221.384818) (xy 89.774072 -221.348208)
			(xy 89.74364 -221.306321) (xy 89.720134 -221.260189) (xy 89.704135 -221.210949) (xy 89.696036 -221.159811)
			(xy 89.695528 -221.133924) (xy 89.414604 -221.133924) (xy 89.41408 -221.161632) (xy 89.404881 -221.216279)
			(xy 89.396316 -221.242636) (xy 89.388442 -221.264734) (xy 89.59342 -221.619572) (xy 89.61628 -221.62389)
			(xy 89.641105 -221.629041) (xy 89.688883 -221.645999) (xy 89.733502 -221.670074) (xy 89.773907 -221.700696)
			(xy 89.809147 -221.737145) (xy 89.83839 -221.778561) (xy 89.860947 -221.823965) (xy 89.876285 -221.872289)
			(xy 89.884042 -221.92239) (xy 89.884504 -221.94774) (xy 89.883996 -221.973647) (xy 89.87589 -222.024824)
			(xy 89.859878 -222.074103) (xy 89.836355 -222.12027) (xy 89.805899 -222.162189) (xy 89.769261 -222.198827)
			(xy 89.727342 -222.229283) (xy 89.681175 -222.252806) (xy 89.631896 -222.268818) (xy 89.580719 -222.276924)
			(xy 89.528905 -222.276924) (xy 89.477728 -222.268818) (xy 89.428449 -222.252806) (xy 89.382282 -222.229283)
			(xy 89.340363 -222.198827) (xy 89.303725 -222.162189) (xy 89.273269 -222.12027) (xy 89.249746 -222.074103)
			(xy 89.233734 -222.024824) (xy 89.225628 -221.973647) (xy 89.22512 -221.94774) (xy 89.225723 -221.920023)
			(xy 89.23504 -221.865377) (xy 89.243662 -221.839028) (xy 89.251536 -221.81693) (xy 89.046558 -221.462092)
			(xy 89.023698 -221.457774) (xy 88.998903 -221.45255) (xy 88.951167 -221.435564) (xy 88.906592 -221.411474)
			(xy 88.866227 -221.380847) (xy 88.831024 -221.344405) (xy 88.801811 -221.303006) (xy 88.779276 -221.257625)
			(xy 88.76395 -221.20933) (xy 88.756194 -221.159258) (xy 88.755728 -221.133924) (xy 31.743142 -221.133924)
			(xy 31.743142 -224.389442) (xy 89.695528 -224.389442) (xy 89.695935 -224.364105) (xy 89.703697 -224.314028)
			(xy 89.719029 -224.265728) (xy 89.74157 -224.220343) (xy 89.770789 -224.17894) (xy 89.805999 -224.142496)
			(xy 89.84637 -224.111867) (xy 89.890952 -224.087776) (xy 89.938695 -224.070789) (xy 89.963498 -224.065592)
			(xy 89.986358 -224.061274) (xy 90.191082 -223.706182) (xy 90.183462 -223.684338) (xy 90.174817 -223.657995)
			(xy 90.165504 -223.603345) (xy 90.16492 -223.575626) (xy 90.165428 -223.549719) (xy 90.173534 -223.498542)
			(xy 90.189546 -223.449263) (xy 90.213069 -223.403096) (xy 90.243525 -223.361177) (xy 90.280163 -223.324539)
			(xy 90.322082 -223.294083) (xy 90.368249 -223.27056) (xy 90.417528 -223.254548) (xy 90.468705 -223.246442)
			(xy 90.520519 -223.246442) (xy 90.571696 -223.254548) (xy 90.620975 -223.27056) (xy 90.667142 -223.294083)
			(xy 90.709061 -223.324539) (xy 90.745699 -223.361177) (xy 90.776155 -223.403096) (xy 90.799678 -223.449263)
			(xy 90.81569 -223.498542) (xy 90.823796 -223.549719) (xy 90.824304 -223.575626) (xy 90.823803 -223.60097)
			(xy 90.816028 -223.651059) (xy 90.800679 -223.699368) (xy 90.77812 -223.74476) (xy 90.74888 -223.786165)
			(xy 90.713649 -223.822609) (xy 90.673257 -223.853232) (xy 90.628654 -223.877314) (xy 90.580892 -223.894288)
			(xy 90.55608 -223.899476) (xy 90.53322 -223.903794) (xy 90.328496 -224.258632) (xy 90.336116 -224.280476)
			(xy 90.344672 -224.306769) (xy 90.353865 -224.361289) (xy 90.354404 -224.388934) (xy 90.354404 -224.389442)
			(xy 90.635328 -224.389442) (xy 90.635836 -224.363555) (xy 90.643935 -224.312417) (xy 90.659934 -224.263177)
			(xy 90.68344 -224.217045) (xy 90.713872 -224.175158) (xy 90.750482 -224.138548) (xy 90.792369 -224.108116)
			(xy 90.838501 -224.08461) (xy 90.887741 -224.068611) (xy 90.938879 -224.060512) (xy 90.990653 -224.060512)
			(xy 91.041791 -224.068611) (xy 91.091031 -224.08461) (xy 91.137163 -224.108116) (xy 91.17905 -224.138548)
			(xy 91.21566 -224.175158) (xy 91.246092 -224.217045) (xy 91.269598 -224.263177) (xy 91.285597 -224.312417)
			(xy 91.293696 -224.363555) (xy 91.294204 -224.389442) (xy 91.575128 -224.389442) (xy 91.575535 -224.364105)
			(xy 91.583297 -224.314028) (xy 91.598629 -224.265728) (xy 91.62117 -224.220343) (xy 91.650389 -224.17894)
			(xy 91.685599 -224.142496) (xy 91.72597 -224.111867) (xy 91.770552 -224.087776) (xy 91.818295 -224.070789)
			(xy 91.843098 -224.065592) (xy 91.865958 -224.061274) (xy 92.070682 -223.706182) (xy 92.063062 -223.684338)
			(xy 92.054417 -223.657995) (xy 92.045104 -223.603345) (xy 92.04452 -223.575626) (xy 92.045028 -223.549719)
			(xy 92.053134 -223.498542) (xy 92.069146 -223.449263) (xy 92.092669 -223.403096) (xy 92.123125 -223.361177)
			(xy 92.159763 -223.324539) (xy 92.201682 -223.294083) (xy 92.247849 -223.27056) (xy 92.297128 -223.254548)
			(xy 92.348305 -223.246442) (xy 92.400119 -223.246442) (xy 92.451296 -223.254548) (xy 92.500575 -223.27056)
			(xy 92.546742 -223.294083) (xy 92.588661 -223.324539) (xy 92.625299 -223.361177) (xy 92.655755 -223.403096)
			(xy 92.679278 -223.449263) (xy 92.69529 -223.498542) (xy 92.703396 -223.549719) (xy 92.703904 -223.575626)
			(xy 92.703403 -223.60097) (xy 92.695628 -223.651059) (xy 92.680279 -223.699368) (xy 92.65772 -223.74476)
			(xy 92.62848 -223.786165) (xy 92.593249 -223.822609) (xy 92.552857 -223.853232) (xy 92.508254 -223.877314)
			(xy 92.460492 -223.894288) (xy 92.43568 -223.899476) (xy 92.41282 -223.903794) (xy 92.208096 -224.258632)
			(xy 92.215716 -224.280476) (xy 92.224272 -224.306769) (xy 92.233465 -224.361289) (xy 92.234004 -224.388934)
			(xy 92.234004 -224.389442) (xy 92.514928 -224.389442) (xy 92.515436 -224.363555) (xy 92.523535 -224.312417)
			(xy 92.539534 -224.263177) (xy 92.56304 -224.217045) (xy 92.593472 -224.175158) (xy 92.630082 -224.138548)
			(xy 92.671969 -224.108116) (xy 92.718101 -224.08461) (xy 92.767341 -224.068611) (xy 92.818479 -224.060512)
			(xy 92.870253 -224.060512) (xy 92.921391 -224.068611) (xy 92.970631 -224.08461) (xy 93.016763 -224.108116)
			(xy 93.05865 -224.138548) (xy 93.09526 -224.175158) (xy 93.125692 -224.217045) (xy 93.149198 -224.263177)
			(xy 93.165197 -224.312417) (xy 93.173296 -224.363555) (xy 93.173804 -224.389442) (xy 93.454728 -224.389442)
			(xy 93.455135 -224.364105) (xy 93.462897 -224.314028) (xy 93.478229 -224.265728) (xy 93.50077 -224.220343)
			(xy 93.529989 -224.17894) (xy 93.565199 -224.142496) (xy 93.60557 -224.111867) (xy 93.650152 -224.087776)
			(xy 93.697895 -224.070789) (xy 93.722698 -224.065592) (xy 93.745558 -224.061274) (xy 93.950282 -223.706436)
			(xy 93.942662 -223.684338) (xy 93.934031 -223.657991) (xy 93.92471 -223.603344) (xy 93.92412 -223.575626)
			(xy 93.924628 -223.549719) (xy 93.932734 -223.498542) (xy 93.948746 -223.449263) (xy 93.972269 -223.403096)
			(xy 94.002725 -223.361177) (xy 94.039363 -223.324539) (xy 94.081282 -223.294083) (xy 94.127449 -223.27056)
			(xy 94.176728 -223.254548) (xy 94.227905 -223.246442) (xy 94.279719 -223.246442) (xy 94.330896 -223.254548)
			(xy 94.380175 -223.27056) (xy 94.426342 -223.294083) (xy 94.468261 -223.324539) (xy 94.504899 -223.361177)
			(xy 94.535355 -223.403096) (xy 94.558878 -223.449263) (xy 94.57489 -223.498542) (xy 94.582996 -223.549719)
			(xy 94.583504 -223.575626) (xy 94.583087 -223.600992) (xy 94.575334 -223.651127) (xy 94.559985 -223.69948)
			(xy 94.537403 -223.744908) (xy 94.508122 -223.786336) (xy 94.472834 -223.822783) (xy 94.432375 -223.853388)
			(xy 94.387701 -223.877427) (xy 94.339869 -223.894332) (xy 94.315026 -223.899476) (xy 94.292166 -223.903794)
			(xy 94.087442 -224.258632) (xy 94.095316 -224.280476) (xy 94.10389 -224.306896) (xy 94.11309 -224.36167)
			(xy 94.113604 -224.389442) (xy 94.394528 -224.389442) (xy 94.395036 -224.363555) (xy 94.403135 -224.312417)
			(xy 94.419134 -224.263177) (xy 94.44264 -224.217045) (xy 94.473072 -224.175158) (xy 94.509682 -224.138548)
			(xy 94.551569 -224.108116) (xy 94.597701 -224.08461) (xy 94.646941 -224.068611) (xy 94.698079 -224.060512)
			(xy 94.749853 -224.060512) (xy 94.800991 -224.068611) (xy 94.850231 -224.08461) (xy 94.896363 -224.108116)
			(xy 94.93825 -224.138548) (xy 94.97486 -224.175158) (xy 95.005292 -224.217045) (xy 95.028798 -224.263177)
			(xy 95.044797 -224.312417) (xy 95.052896 -224.363555) (xy 95.053404 -224.389442) (xy 95.334328 -224.389442)
			(xy 95.334735 -224.364105) (xy 95.342497 -224.314028) (xy 95.357829 -224.265728) (xy 95.38037 -224.220343)
			(xy 95.409589 -224.17894) (xy 95.444799 -224.142496) (xy 95.48517 -224.111867) (xy 95.529752 -224.087776)
			(xy 95.577495 -224.070789) (xy 95.602298 -224.065592) (xy 95.625158 -224.061274) (xy 95.829882 -223.706436)
			(xy 95.822262 -223.684338) (xy 95.813631 -223.657991) (xy 95.80431 -223.603344) (xy 95.80372 -223.575626)
			(xy 95.804228 -223.549719) (xy 95.812334 -223.498542) (xy 95.828346 -223.449263) (xy 95.851869 -223.403096)
			(xy 95.882325 -223.361177) (xy 95.918963 -223.324539) (xy 95.960882 -223.294083) (xy 96.007049 -223.27056)
			(xy 96.056328 -223.254548) (xy 96.107505 -223.246442) (xy 96.159319 -223.246442) (xy 96.210496 -223.254548)
			(xy 96.259775 -223.27056) (xy 96.305942 -223.294083) (xy 96.347861 -223.324539) (xy 96.384499 -223.361177)
			(xy 96.414955 -223.403096) (xy 96.438478 -223.449263) (xy 96.45449 -223.498542) (xy 96.462596 -223.549719)
			(xy 96.463104 -223.575626) (xy 96.462687 -223.600992) (xy 96.454934 -223.651127) (xy 96.439585 -223.69948)
			(xy 96.417003 -223.744908) (xy 96.387722 -223.786336) (xy 96.352434 -223.822783) (xy 96.311975 -223.853388)
			(xy 96.267301 -223.877427) (xy 96.219469 -223.894332) (xy 96.194626 -223.899476) (xy 96.171766 -223.903794)
			(xy 95.967042 -224.258632) (xy 95.974916 -224.280476) (xy 95.98349 -224.306896) (xy 95.99269 -224.36167)
			(xy 95.993204 -224.389442) (xy 95.992696 -224.415329) (xy 95.984597 -224.466467) (xy 95.968598 -224.515707)
			(xy 95.945092 -224.561839) (xy 95.91466 -224.603726) (xy 95.87805 -224.640336) (xy 95.836163 -224.670768)
			(xy 95.790031 -224.694274) (xy 95.740791 -224.710273) (xy 95.689653 -224.718372) (xy 95.637879 -224.718372)
			(xy 95.586741 -224.710273) (xy 95.537501 -224.694274) (xy 95.491369 -224.670768) (xy 95.449482 -224.640336)
			(xy 95.412872 -224.603726) (xy 95.38244 -224.561839) (xy 95.358934 -224.515707) (xy 95.342935 -224.466467)
			(xy 95.334836 -224.415329) (xy 95.334328 -224.389442) (xy 95.053404 -224.389442) (xy 95.05286 -224.417149)
			(xy 95.043674 -224.471796) (xy 95.035116 -224.498154) (xy 95.027242 -224.520252) (xy 95.23222 -224.87509)
			(xy 95.25508 -224.879408) (xy 95.279909 -224.884542) (xy 95.327688 -224.901501) (xy 95.372308 -224.925578)
			(xy 95.412714 -224.956202) (xy 95.447954 -224.992654) (xy 95.477197 -225.034071) (xy 95.499752 -225.079478)
			(xy 95.515088 -225.127804) (xy 95.522843 -225.177908) (xy 95.523304 -225.203258) (xy 95.522796 -225.229165)
			(xy 95.51469 -225.280342) (xy 95.498678 -225.329621) (xy 95.475155 -225.375788) (xy 95.444699 -225.417707)
			(xy 95.408061 -225.454345) (xy 95.366142 -225.484801) (xy 95.319975 -225.508324) (xy 95.270696 -225.524336)
			(xy 95.219519 -225.532442) (xy 95.167705 -225.532442) (xy 95.116528 -225.524336) (xy 95.067249 -225.508324)
			(xy 95.021082 -225.484801) (xy 94.979163 -225.454345) (xy 94.942525 -225.417707) (xy 94.912069 -225.375788)
			(xy 94.888546 -225.329621) (xy 94.872534 -225.280342) (xy 94.864428 -225.229165) (xy 94.86392 -225.203258)
			(xy 94.864527 -225.175541) (xy 94.873842 -225.120895) (xy 94.882462 -225.094546) (xy 94.890336 -225.072448)
			(xy 94.685358 -224.71761) (xy 94.662498 -224.713292) (xy 94.637685 -224.708145) (xy 94.589943 -224.691153)
			(xy 94.545363 -224.667056) (xy 94.504996 -224.63642) (xy 94.469793 -224.599968) (xy 94.440582 -224.558558)
			(xy 94.418052 -224.513166) (xy 94.402734 -224.46486) (xy 94.394988 -224.41478) (xy 94.394528 -224.389442)
			(xy 94.113604 -224.389442) (xy 94.113096 -224.415329) (xy 94.104997 -224.466467) (xy 94.088998 -224.515707)
			(xy 94.065492 -224.561839) (xy 94.03506 -224.603726) (xy 93.99845 -224.640336) (xy 93.956563 -224.670768)
			(xy 93.910431 -224.694274) (xy 93.861191 -224.710273) (xy 93.810053 -224.718372) (xy 93.758279 -224.718372)
			(xy 93.707141 -224.710273) (xy 93.657901 -224.694274) (xy 93.611769 -224.670768) (xy 93.569882 -224.640336)
			(xy 93.533272 -224.603726) (xy 93.50284 -224.561839) (xy 93.479334 -224.515707) (xy 93.463335 -224.466467)
			(xy 93.455236 -224.415329) (xy 93.454728 -224.389442) (xy 93.173804 -224.389442) (xy 93.173804 -224.38995)
			(xy 93.173247 -224.417593) (xy 93.164056 -224.472111) (xy 93.155516 -224.498408) (xy 93.147896 -224.520252)
			(xy 93.35262 -224.87509) (xy 93.37548 -224.879408) (xy 93.400309 -224.884542) (xy 93.448088 -224.901501)
			(xy 93.492708 -224.925578) (xy 93.533114 -224.956202) (xy 93.568354 -224.992654) (xy 93.597597 -225.034071)
			(xy 93.620152 -225.079478) (xy 93.635488 -225.127804) (xy 93.643243 -225.177908) (xy 93.643704 -225.203258)
			(xy 93.643196 -225.229165) (xy 93.63509 -225.280342) (xy 93.619078 -225.329621) (xy 93.595555 -225.375788)
			(xy 93.565099 -225.417707) (xy 93.528461 -225.454345) (xy 93.486542 -225.484801) (xy 93.440375 -225.508324)
			(xy 93.391096 -225.524336) (xy 93.339919 -225.532442) (xy 93.288105 -225.532442) (xy 93.236928 -225.524336)
			(xy 93.187649 -225.508324) (xy 93.141482 -225.484801) (xy 93.099563 -225.454345) (xy 93.062925 -225.417707)
			(xy 93.032469 -225.375788) (xy 93.008946 -225.329621) (xy 92.992934 -225.280342) (xy 92.984828 -225.229165)
			(xy 92.98432 -225.203258) (xy 92.98432 -225.20275) (xy 92.98493 -225.175096) (xy 92.994253 -225.120579)
			(xy 93.002862 -225.094292) (xy 93.010482 -225.072448) (xy 92.805758 -224.71761) (xy 92.782898 -224.713292)
			(xy 92.758085 -224.708145) (xy 92.710343 -224.691153) (xy 92.665763 -224.667056) (xy 92.625396 -224.63642)
			(xy 92.590193 -224.599968) (xy 92.560982 -224.558558) (xy 92.538452 -224.513166) (xy 92.523134 -224.46486)
			(xy 92.515388 -224.41478) (xy 92.514928 -224.389442) (xy 92.234004 -224.389442) (xy 92.233496 -224.415329)
			(xy 92.225397 -224.466467) (xy 92.209398 -224.515707) (xy 92.185892 -224.561839) (xy 92.15546 -224.603726)
			(xy 92.11885 -224.640336) (xy 92.076963 -224.670768) (xy 92.030831 -224.694274) (xy 91.981591 -224.710273)
			(xy 91.930453 -224.718372) (xy 91.878679 -224.718372) (xy 91.827541 -224.710273) (xy 91.778301 -224.694274)
			(xy 91.732169 -224.670768) (xy 91.690282 -224.640336) (xy 91.653672 -224.603726) (xy 91.62324 -224.561839)
			(xy 91.599734 -224.515707) (xy 91.583735 -224.466467) (xy 91.575636 -224.415329) (xy 91.575128 -224.389442)
			(xy 91.294204 -224.389442) (xy 91.294204 -224.38995) (xy 91.293647 -224.417593) (xy 91.284456 -224.472111)
			(xy 91.275916 -224.498408) (xy 91.268296 -224.520252) (xy 91.47302 -224.87509) (xy 91.49588 -224.879408)
			(xy 91.520709 -224.884542) (xy 91.568488 -224.901501) (xy 91.613108 -224.925578) (xy 91.653514 -224.956202)
			(xy 91.688754 -224.992654) (xy 91.717997 -225.034071) (xy 91.740552 -225.079478) (xy 91.755888 -225.127804)
			(xy 91.763643 -225.177908) (xy 91.764104 -225.203258) (xy 91.763596 -225.229165) (xy 91.75549 -225.280342)
			(xy 91.739478 -225.329621) (xy 91.715955 -225.375788) (xy 91.685499 -225.417707) (xy 91.648861 -225.454345)
			(xy 91.606942 -225.484801) (xy 91.560775 -225.508324) (xy 91.511496 -225.524336) (xy 91.460319 -225.532442)
			(xy 91.408505 -225.532442) (xy 91.357328 -225.524336) (xy 91.308049 -225.508324) (xy 91.261882 -225.484801)
			(xy 91.219963 -225.454345) (xy 91.183325 -225.417707) (xy 91.152869 -225.375788) (xy 91.129346 -225.329621)
			(xy 91.113334 -225.280342) (xy 91.105228 -225.229165) (xy 91.10472 -225.203258) (xy 91.10472 -225.20275)
			(xy 91.10533 -225.175096) (xy 91.114653 -225.120579) (xy 91.123262 -225.094292) (xy 91.130882 -225.072448)
			(xy 90.926158 -224.71761) (xy 90.903298 -224.713292) (xy 90.878485 -224.708145) (xy 90.830743 -224.691153)
			(xy 90.786163 -224.667056) (xy 90.745796 -224.63642) (xy 90.710593 -224.599968) (xy 90.681382 -224.558558)
			(xy 90.658852 -224.513166) (xy 90.643534 -224.46486) (xy 90.635788 -224.41478) (xy 90.635328 -224.389442)
			(xy 90.354404 -224.389442) (xy 90.353896 -224.415329) (xy 90.345797 -224.466467) (xy 90.329798 -224.515707)
			(xy 90.306292 -224.561839) (xy 90.27586 -224.603726) (xy 90.23925 -224.640336) (xy 90.197363 -224.670768)
			(xy 90.151231 -224.694274) (xy 90.101991 -224.710273) (xy 90.050853 -224.718372) (xy 89.999079 -224.718372)
			(xy 89.947941 -224.710273) (xy 89.898701 -224.694274) (xy 89.852569 -224.670768) (xy 89.810682 -224.640336)
			(xy 89.774072 -224.603726) (xy 89.74364 -224.561839) (xy 89.720134 -224.515707) (xy 89.704135 -224.466467)
			(xy 89.696036 -224.415329) (xy 89.695528 -224.389442) (xy 31.743142 -224.389442) (xy 31.743142 -251.76988)
			(xy 75.695566 -251.76988) (xy 75.699547 -251.63686) (xy 75.711476 -251.504315) (xy 75.731311 -251.372722)
			(xy 75.75898 -251.24255) (xy 75.794384 -251.114265) (xy 75.837397 -250.988328) (xy 75.887864 -250.865189)
			(xy 75.945605 -250.745288) (xy 76.010414 -250.629055) (xy 76.082058 -250.516905) (xy 76.16028 -250.409241)
			(xy 76.244801 -250.306448) (xy 76.335319 -250.208893) (xy 76.431508 -250.116927) (xy 76.533026 -250.030877)
			(xy 76.639507 -249.951053) (xy 76.750572 -249.87774) (xy 76.865823 -249.8112) (xy 76.984847 -249.751671)
			(xy 77.107218 -249.699367) (xy 77.232497 -249.654475) (xy 77.360238 -249.617156) (xy 77.489981 -249.587543)
			(xy 77.621263 -249.565742) (xy 77.753614 -249.551832) (xy 77.88656 -249.545861) (xy 78.019625 -249.547852)
			(xy 78.152333 -249.557797) (xy 78.284209 -249.575661) (xy 78.41478 -249.601379) (xy 78.54358 -249.63486)
			(xy 78.670146 -249.675984) (xy 78.794027 -249.724604) (xy 78.914778 -249.780545) (xy 79.031968 -249.843607)
			(xy 79.145177 -249.913565) (xy 79.253999 -249.990169) (xy 79.358045 -250.073143) (xy 79.456943 -250.162191)
			(xy 79.550338 -250.256994) (xy 79.637896 -250.357212) (xy 79.719305 -250.462488) (xy 79.794271 -250.572444)
			(xy 79.862528 -250.686686) (xy 79.92383 -250.804806) (xy 79.977959 -250.926381) (xy 80.02472 -251.050975)
			(xy 80.063946 -251.178143) (xy 80.095496 -251.307429) (xy 80.119259 -251.43837) (xy 80.135148 -251.570498)
			(xy 80.143106 -251.70334) (xy 80.143604 -251.76988) (xy 80.143106 -251.83642) (xy 80.135148 -251.969262)
			(xy 80.119259 -252.10139) (xy 80.095496 -252.232331) (xy 80.063946 -252.361617) (xy 80.02472 -252.488785)
			(xy 79.977959 -252.613379) (xy 79.92383 -252.734954) (xy 79.862528 -252.853074) (xy 79.794271 -252.967316)
			(xy 79.719305 -253.077272) (xy 79.637896 -253.182548) (xy 79.550338 -253.282766) (xy 79.456943 -253.377569)
			(xy 79.358045 -253.466617) (xy 79.253999 -253.549591) (xy 79.145177 -253.626195) (xy 79.031968 -253.696153)
			(xy 78.914778 -253.759215) (xy 78.794027 -253.815156) (xy 78.670146 -253.863776) (xy 78.54358 -253.9049)
			(xy 78.41478 -253.938381) (xy 78.284209 -253.964099) (xy 78.152333 -253.981963) (xy 78.019625 -253.991908)
			(xy 77.88656 -253.993899) (xy 77.753614 -253.987928) (xy 77.621263 -253.974018) (xy 77.489981 -253.952217)
			(xy 77.360238 -253.922604) (xy 77.232497 -253.885285) (xy 77.107218 -253.840393) (xy 76.984847 -253.788089)
			(xy 76.865823 -253.72856) (xy 76.750572 -253.66202) (xy 76.639507 -253.588707) (xy 76.533026 -253.508883)
			(xy 76.431508 -253.422833) (xy 76.335319 -253.330867) (xy 76.244801 -253.233312) (xy 76.16028 -253.130519)
			(xy 76.082058 -253.022855) (xy 76.010414 -252.910705) (xy 75.945605 -252.794472) (xy 75.887864 -252.674571)
			(xy 75.837397 -252.551432) (xy 75.794384 -252.425495) (xy 75.75898 -252.29721) (xy 75.731311 -252.167038)
			(xy 75.711476 -252.035445) (xy 75.699547 -251.9029) (xy 75.695566 -251.76988) (xy 31.743142 -251.76988)
			(xy 31.743142 -274.266914) (xy 103.432356 -274.266914) (xy 103.432864 -274.241027) (xy 103.440963 -274.189889)
			(xy 103.456962 -274.140649) (xy 103.480468 -274.094517) (xy 103.5109 -274.05263) (xy 103.54751 -274.01602)
			(xy 103.589397 -273.985588) (xy 103.635529 -273.962082) (xy 103.684769 -273.946083) (xy 103.735907 -273.937984)
			(xy 103.787681 -273.937984) (xy 103.838819 -273.946083) (xy 103.888059 -273.962082) (xy 103.934191 -273.985588)
			(xy 103.976078 -274.01602) (xy 104.012688 -274.05263) (xy 104.04312 -274.094517) (xy 104.066626 -274.140649)
			(xy 104.082625 -274.189889) (xy 104.090724 -274.241027) (xy 104.091232 -274.266914) (xy 104.090675 -274.294558)
			(xy 104.081487 -274.349076) (xy 104.072944 -274.375372) (xy 104.065324 -274.397216) (xy 104.270556 -274.752562)
			(xy 104.293416 -274.75688) (xy 104.318228 -274.762086) (xy 104.366006 -274.779035) (xy 104.410625 -274.803101)
			(xy 104.451032 -274.833715) (xy 104.486274 -274.870157) (xy 104.515519 -274.911566) (xy 104.538078 -274.956966)
			(xy 104.553418 -275.005285) (xy 104.561177 -275.055382) (xy 104.56164 -275.08073) (xy 104.561132 -275.106637)
			(xy 104.553026 -275.157814) (xy 104.537014 -275.207093) (xy 104.513491 -275.25326) (xy 104.483035 -275.295179)
			(xy 104.446397 -275.331817) (xy 104.404478 -275.362273) (xy 104.358311 -275.385796) (xy 104.309032 -275.401808)
			(xy 104.257855 -275.409914) (xy 104.206041 -275.409914) (xy 104.154864 -275.401808) (xy 104.105585 -275.385796)
			(xy 104.059418 -275.362273) (xy 104.017499 -275.331817) (xy 103.980861 -275.295179) (xy 103.950405 -275.25326)
			(xy 103.926882 -275.207093) (xy 103.91087 -275.157814) (xy 103.902764 -275.106637) (xy 103.902256 -275.08073)
			(xy 103.902854 -275.053013) (xy 103.912174 -274.998366) (xy 103.920798 -274.972018) (xy 103.928672 -274.94992)
			(xy 103.723694 -274.595082) (xy 103.700834 -274.590764) (xy 103.676011 -274.585559) (xy 103.628206 -274.568629)
			(xy 103.583558 -274.544577) (xy 103.543121 -274.51397) (xy 103.507847 -274.477532) (xy 103.478571 -274.436121)
			(xy 103.455983 -274.390715) (xy 103.440615 -274.342385) (xy 103.43283 -274.292271) (xy 103.432356 -274.266914)
			(xy 31.743142 -274.266914) (xy 31.743142 -275.10659) (xy 102.023373 -275.10659) (xy 102.023373 -275.05481)
			(xy 102.031474 -275.003669) (xy 102.047476 -274.954425) (xy 102.070985 -274.90829) (xy 102.101423 -274.866402)
			(xy 102.138039 -274.829791) (xy 102.179931 -274.79936) (xy 102.226069 -274.775858) (xy 102.275316 -274.759863)
			(xy 102.326458 -274.75177) (xy 102.352348 -274.751292) (xy 102.377861 -274.751741) (xy 102.428277 -274.759608)
			(xy 102.476879 -274.775148) (xy 102.522507 -274.79799) (xy 102.564072 -274.827588) (xy 102.600581 -274.863235)
			(xy 102.616254 -274.883372) (xy 103.028242 -274.883372) (xy 103.043883 -274.86321) (xy 103.0804 -274.827569)
			(xy 103.121973 -274.797979) (xy 103.167607 -274.775148) (xy 103.216215 -274.75962) (xy 103.266634 -274.751765)
			(xy 103.292148 -274.751292) (xy 103.318035 -274.751743) (xy 103.369171 -274.759849) (xy 103.41841 -274.775854)
			(xy 103.464539 -274.799364) (xy 103.506423 -274.8298) (xy 103.543031 -274.866413) (xy 103.573461 -274.908302)
			(xy 103.596964 -274.954434) (xy 103.612962 -275.003675) (xy 103.62106 -275.054813) (xy 103.62106 -275.106587)
			(xy 103.612962 -275.157725) (xy 103.596964 -275.206966) (xy 103.573461 -275.253098) (xy 103.543031 -275.294987)
			(xy 103.506423 -275.3316) (xy 103.464539 -275.362036) (xy 103.41841 -275.385546) (xy 103.369171 -275.401551)
			(xy 103.318035 -275.409657) (xy 103.292148 -275.410168) (xy 103.266637 -275.409665) (xy 103.216223 -275.401811)
			(xy 103.167621 -275.386283) (xy 103.121992 -275.363452) (xy 103.080426 -275.333862) (xy 103.043916 -275.298222)
			(xy 103.028242 -275.278088) (xy 102.616254 -275.278088) (xy 102.600546 -275.298195) (xy 102.564044 -275.333841)
			(xy 102.522486 -275.363438) (xy 102.476864 -275.386279) (xy 102.428268 -275.401819) (xy 102.377858 -275.409687)
			(xy 102.352348 -275.410168) (xy 102.326458 -275.40963) (xy 102.275316 -275.401537) (xy 102.226069 -275.385542)
			(xy 102.179931 -275.36204) (xy 102.138039 -275.331609) (xy 102.101423 -275.294998) (xy 102.070985 -275.25311)
			(xy 102.047476 -275.206975) (xy 102.031474 -275.157731) (xy 102.023373 -275.10659) (xy 31.743142 -275.10659)
			(xy 31.743142 -276.708616) (xy 102.022656 -276.708616) (xy 102.023189 -276.683284) (xy 102.030938 -276.633215)
			(xy 102.046256 -276.584922) (xy 102.068781 -276.53954) (xy 102.097985 -276.498139) (xy 102.133179 -276.461694)
			(xy 102.173534 -276.431062) (xy 102.218101 -276.406964) (xy 102.265829 -276.389968) (xy 102.290626 -276.384766)
			(xy 102.313486 -276.380448) (xy 102.518464 -276.025356) (xy 102.510844 -276.003512) (xy 102.502285 -275.977153)
			(xy 102.493085 -275.922508) (xy 102.492556 -275.8948) (xy 102.493064 -275.868913) (xy 102.501163 -275.817775)
			(xy 102.517162 -275.768535) (xy 102.540668 -275.722403) (xy 102.5711 -275.680516) (xy 102.60771 -275.643906)
			(xy 102.649597 -275.613474) (xy 102.695729 -275.589968) (xy 102.744969 -275.573969) (xy 102.796107 -275.56587)
			(xy 102.847881 -275.56587) (xy 102.899019 -275.573969) (xy 102.948259 -275.589968) (xy 102.994391 -275.613474)
			(xy 103.036278 -275.643906) (xy 103.072888 -275.680516) (xy 103.10332 -275.722403) (xy 103.126826 -275.768535)
			(xy 103.142825 -275.817775) (xy 103.150924 -275.868913) (xy 103.151432 -275.8948) (xy 104.372156 -275.8948)
			(xy 104.372675 -275.869467) (xy 104.380426 -275.819398) (xy 104.395746 -275.771105) (xy 104.418273 -275.725723)
			(xy 104.447479 -275.684322) (xy 104.482674 -275.647877) (xy 104.523031 -275.617245) (xy 104.567599 -275.593147)
			(xy 104.615329 -275.576152) (xy 104.640126 -275.57095) (xy 104.662986 -275.566632) (xy 104.868218 -275.211286)
			(xy 104.860598 -275.189188) (xy 104.851972 -275.162906) (xy 104.842659 -275.108385) (xy 104.842056 -275.08073)
			(xy 104.842564 -275.054823) (xy 104.85067 -275.003646) (xy 104.866682 -274.954367) (xy 104.890205 -274.9082)
			(xy 104.920661 -274.866281) (xy 104.957299 -274.829643) (xy 104.999218 -274.799187) (xy 105.045385 -274.775664)
			(xy 105.094664 -274.759652) (xy 105.145841 -274.751546) (xy 105.197655 -274.751546) (xy 105.248832 -274.759652)
			(xy 105.298111 -274.775664) (xy 105.344278 -274.799187) (xy 105.386197 -274.829643) (xy 105.422835 -274.866281)
			(xy 105.453291 -274.9082) (xy 105.476814 -274.954367) (xy 105.492826 -275.003646) (xy 105.500932 -275.054823)
			(xy 105.50144 -275.08073) (xy 105.500998 -275.106094) (xy 105.493245 -275.156227) (xy 105.477898 -275.204578)
			(xy 105.455318 -275.250004) (xy 105.42604 -275.291431) (xy 105.390756 -275.327878) (xy 105.350301 -275.358484)
			(xy 105.305631 -275.382526) (xy 105.257803 -275.399433) (xy 105.232962 -275.40458) (xy 105.209848 -275.408898)
			(xy 105.00487 -275.76399) (xy 105.012744 -275.786088) (xy 105.021303 -275.812447) (xy 105.030503 -275.867092)
			(xy 105.031032 -275.8948) (xy 105.030524 -275.920687) (xy 105.022425 -275.971825) (xy 105.006426 -276.021065)
			(xy 104.98292 -276.067197) (xy 104.952488 -276.109084) (xy 104.915878 -276.145694) (xy 104.873991 -276.176126)
			(xy 104.827859 -276.199632) (xy 104.778619 -276.215631) (xy 104.727481 -276.22373) (xy 104.675707 -276.22373)
			(xy 104.624569 -276.215631) (xy 104.575329 -276.199632) (xy 104.529197 -276.176126) (xy 104.48731 -276.145694)
			(xy 104.4507 -276.109084) (xy 104.420268 -276.067197) (xy 104.396762 -276.021065) (xy 104.380763 -275.971825)
			(xy 104.372664 -275.920687) (xy 104.372156 -275.8948) (xy 103.151432 -275.8948) (xy 103.150966 -275.920146)
			(xy 103.143192 -275.97024) (xy 103.127843 -276.018553) (xy 103.105281 -276.063948) (xy 103.076038 -276.105356)
			(xy 103.040801 -276.1418) (xy 103.000402 -276.172421) (xy 102.955792 -276.196499) (xy 102.908023 -276.213466)
			(xy 102.883208 -276.21865) (xy 102.860348 -276.222968) (xy 102.65537 -276.577806) (xy 102.663244 -276.599904)
			(xy 102.671807 -276.626262) (xy 102.681004 -276.680908) (xy 102.681532 -276.708616) (xy 102.962456 -276.708616)
			(xy 102.962964 -276.682709) (xy 102.97107 -276.631532) (xy 102.987082 -276.582253) (xy 103.010605 -276.536086)
			(xy 103.041061 -276.494167) (xy 103.077699 -276.457529) (xy 103.119618 -276.427073) (xy 103.165785 -276.40355)
			(xy 103.215064 -276.387538) (xy 103.266241 -276.379432) (xy 103.318055 -276.379432) (xy 103.369232 -276.387538)
			(xy 103.418511 -276.40355) (xy 103.464678 -276.427073) (xy 103.506597 -276.457529) (xy 103.543235 -276.494167)
			(xy 103.573691 -276.536086) (xy 103.597214 -276.582253) (xy 103.613226 -276.631532) (xy 103.621332 -276.682709)
			(xy 103.62184 -276.708616) (xy 103.621308 -276.734511) (xy 103.902706 -276.734511) (xy 103.902706 -276.682689)
			(xy 103.910813 -276.631506) (xy 103.926828 -276.582222) (xy 103.950356 -276.53605) (xy 103.980818 -276.494128)
			(xy 104.017464 -276.457487) (xy 104.059391 -276.427031) (xy 104.105566 -276.40351) (xy 104.154853 -276.387502)
			(xy 104.206037 -276.379402) (xy 104.231948 -276.378924) (xy 104.257462 -276.37936) (xy 104.307879 -276.387228)
			(xy 104.356482 -276.40277) (xy 104.40211 -276.425614) (xy 104.443674 -276.455215) (xy 104.480182 -276.490865)
			(xy 104.495854 -276.511004) (xy 104.907842 -276.511004) (xy 104.923492 -276.490849) (xy 104.960006 -276.455206)
			(xy 105.001577 -276.425615) (xy 105.04721 -276.402782) (xy 105.095816 -276.387253) (xy 105.146235 -276.379398)
			(xy 105.171748 -276.378924) (xy 105.197654 -276.379404) (xy 105.248828 -276.387515) (xy 105.298102 -276.403532)
			(xy 105.344265 -276.427059) (xy 105.38618 -276.457517) (xy 105.422814 -276.494157) (xy 105.453266 -276.536076)
			(xy 105.476786 -276.582242) (xy 105.492796 -276.631519) (xy 105.5009 -276.682694) (xy 105.5009 -276.734506)
			(xy 105.492796 -276.785681) (xy 105.476786 -276.834958) (xy 105.453266 -276.881124) (xy 105.422814 -276.923043)
			(xy 105.38618 -276.959683) (xy 105.344265 -276.990141) (xy 105.298102 -277.013668) (xy 105.248828 -277.029685)
			(xy 105.197654 -277.037796) (xy 105.171748 -277.038308) (xy 105.146238 -277.037789) (xy 105.095825 -277.029936)
			(xy 105.047224 -277.01441) (xy 105.001596 -276.991582) (xy 104.960029 -276.961996) (xy 104.923517 -276.92636)
			(xy 104.907842 -276.906228) (xy 104.495854 -276.906228) (xy 104.480157 -276.926344) (xy 104.443651 -276.961988)
			(xy 104.40209 -276.991583) (xy 104.356467 -277.014422) (xy 104.307869 -277.029961) (xy 104.257458 -277.037827)
			(xy 104.231948 -277.038308) (xy 104.206037 -277.037798) (xy 104.154853 -277.029698) (xy 104.105566 -277.01369)
			(xy 104.059391 -276.990169) (xy 104.017464 -276.959713) (xy 103.980818 -276.923072) (xy 103.950356 -276.88115)
			(xy 103.926828 -276.834978) (xy 103.910813 -276.785694) (xy 103.902706 -276.734511) (xy 103.621308 -276.734511)
			(xy 103.621269 -276.736398) (xy 103.611945 -276.791174) (xy 103.603298 -276.817582) (xy 103.595424 -276.839426)
			(xy 103.800402 -277.194264) (xy 103.823262 -277.198582) (xy 103.848063 -277.203782) (xy 103.895803 -277.220766)
			(xy 103.940382 -277.244857) (xy 103.98075 -277.275485) (xy 104.015954 -277.311931) (xy 104.045167 -277.353334)
			(xy 104.067699 -277.398721) (xy 104.083021 -277.44702) (xy 104.09077 -277.497096) (xy 104.091232 -277.522432)
			(xy 106.251756 -277.522432) (xy 106.252213 -277.497097) (xy 106.259974 -277.447026) (xy 106.275303 -277.39873)
			(xy 106.297839 -277.353349) (xy 106.327053 -277.311948) (xy 106.362255 -277.275504) (xy 106.402618 -277.244873)
			(xy 106.447192 -277.220777) (xy 106.494926 -277.203783) (xy 106.519726 -277.198582) (xy 106.542586 -277.194264)
			(xy 106.747818 -276.838918) (xy 106.740198 -276.817074) (xy 106.731593 -276.790786) (xy 106.722266 -276.736269)
			(xy 106.721656 -276.708616) (xy 106.722164 -276.682709) (xy 106.73027 -276.631532) (xy 106.746282 -276.582253)
			(xy 106.769805 -276.536086) (xy 106.800261 -276.494167) (xy 106.836899 -276.457529) (xy 106.878818 -276.427073)
			(xy 106.924985 -276.40355) (xy 106.974264 -276.387538) (xy 107.025441 -276.379432) (xy 107.077255 -276.379432)
			(xy 107.128432 -276.387538) (xy 107.177711 -276.40355) (xy 107.223878 -276.427073) (xy 107.265797 -276.457529)
			(xy 107.302435 -276.494167) (xy 107.332891 -276.536086) (xy 107.356414 -276.582253) (xy 107.372426 -276.631532)
			(xy 107.380532 -276.682709) (xy 107.38104 -276.708616) (xy 107.380628 -276.733993) (xy 107.372856 -276.784149)
			(xy 107.357482 -276.832518) (xy 107.334871 -276.877958) (xy 107.305557 -276.91939) (xy 107.270234 -276.955836)
			(xy 107.229739 -276.986433) (xy 107.18503 -277.010456) (xy 107.137166 -277.027337) (xy 107.112308 -277.032466)
			(xy 107.089448 -277.036784) (xy 106.88447 -277.391622) (xy 106.892344 -277.41372) (xy 106.90091 -277.440076)
			(xy 106.910105 -277.494723) (xy 106.910632 -277.522432) (xy 106.910124 -277.548319) (xy 106.902025 -277.599457)
			(xy 106.886026 -277.648697) (xy 106.86252 -277.694829) (xy 106.832088 -277.736716) (xy 106.795478 -277.773326)
			(xy 106.753591 -277.803758) (xy 106.707459 -277.827264) (xy 106.658219 -277.843263) (xy 106.607081 -277.851362)
			(xy 106.555307 -277.851362) (xy 106.504169 -277.843263) (xy 106.454929 -277.827264) (xy 106.408797 -277.803758)
			(xy 106.36691 -277.773326) (xy 106.3303 -277.736716) (xy 106.299868 -277.694829) (xy 106.276362 -277.648697)
			(xy 106.260363 -277.599457) (xy 106.252264 -277.548319) (xy 106.251756 -277.522432) (xy 104.091232 -277.522432)
			(xy 104.090724 -277.548319) (xy 104.082625 -277.599457) (xy 104.066626 -277.648697) (xy 104.04312 -277.694829)
			(xy 104.012688 -277.736716) (xy 103.976078 -277.773326) (xy 103.934191 -277.803758) (xy 103.888059 -277.827264)
			(xy 103.838819 -277.843263) (xy 103.787681 -277.851362) (xy 103.735907 -277.851362) (xy 103.684769 -277.843263)
			(xy 103.635529 -277.827264) (xy 103.589397 -277.803758) (xy 103.54751 -277.773326) (xy 103.5109 -277.736716)
			(xy 103.480468 -277.694829) (xy 103.456962 -277.648697) (xy 103.440963 -277.599457) (xy 103.432864 -277.548319)
			(xy 103.432356 -277.522432) (xy 103.432895 -277.494724) (xy 103.442084 -277.440078) (xy 103.450644 -277.41372)
			(xy 103.458518 -277.391622) (xy 103.25354 -277.036784) (xy 103.23068 -277.032466) (xy 103.205855 -277.027313)
			(xy 103.158073 -277.01036) (xy 103.113452 -276.986289) (xy 103.073043 -276.955668) (xy 103.037801 -276.919219)
			(xy 103.008557 -276.877803) (xy 102.986002 -276.832396) (xy 102.970667 -276.78407) (xy 102.962915 -276.733966)
			(xy 102.962456 -276.708616) (xy 102.681532 -276.708616) (xy 102.681024 -276.734503) (xy 102.672925 -276.785641)
			(xy 102.656926 -276.834881) (xy 102.63342 -276.881013) (xy 102.602988 -276.9229) (xy 102.566378 -276.95951)
			(xy 102.524491 -276.989942) (xy 102.478359 -277.013448) (xy 102.429119 -277.029447) (xy 102.377981 -277.037546)
			(xy 102.326207 -277.037546) (xy 102.275069 -277.029447) (xy 102.225829 -277.013448) (xy 102.179697 -276.989942)
			(xy 102.13781 -276.95951) (xy 102.1012 -276.9229) (xy 102.070768 -276.881013) (xy 102.047262 -276.834881)
			(xy 102.031263 -276.785641) (xy 102.023164 -276.734503) (xy 102.022656 -276.708616) (xy 31.743142 -276.708616)
			(xy 31.743142 -279.150318) (xy 101.552756 -279.150318) (xy 101.553264 -279.124431) (xy 101.561363 -279.073293)
			(xy 101.577362 -279.024053) (xy 101.600868 -278.977921) (xy 101.6313 -278.936034) (xy 101.66791 -278.899424)
			(xy 101.709797 -278.868992) (xy 101.755929 -278.845486) (xy 101.805169 -278.829487) (xy 101.856307 -278.821388)
			(xy 101.908081 -278.821388) (xy 101.959219 -278.829487) (xy 102.008459 -278.845486) (xy 102.054591 -278.868992)
			(xy 102.096478 -278.899424) (xy 102.133088 -278.936034) (xy 102.16352 -278.977921) (xy 102.187026 -279.024053)
			(xy 102.203025 -279.073293) (xy 102.211124 -279.124431) (xy 102.211632 -279.150318) (xy 102.211112 -279.176186)
			(xy 102.493088 -279.176186) (xy 102.493088 -279.124414) (xy 102.501186 -279.07328) (xy 102.517184 -279.024043)
			(xy 102.540688 -278.977914) (xy 102.571118 -278.93603) (xy 102.607725 -278.899422) (xy 102.649609 -278.868991)
			(xy 102.695737 -278.845487) (xy 102.744975 -278.829488) (xy 102.796108 -278.821388) (xy 102.821994 -278.82088)
			(xy 102.847505 -278.821372) (xy 102.897919 -278.829232) (xy 102.94652 -278.844763) (xy 102.992148 -278.867597)
			(xy 103.033714 -278.897186) (xy 103.070226 -278.932826) (xy 103.0859 -278.95296) (xy 103.497888 -278.95296)
			(xy 103.513557 -278.932822) (xy 103.550069 -278.89718) (xy 103.591636 -278.867588) (xy 103.637265 -278.844752)
			(xy 103.685867 -278.829219) (xy 103.736282 -278.821357) (xy 103.761794 -278.82088) (xy 103.787685 -278.821325)
			(xy 103.83883 -278.829425) (xy 103.888078 -278.845425) (xy 103.934217 -278.868934) (xy 103.97611 -278.89937)
			(xy 104.012726 -278.935985) (xy 104.043163 -278.977878) (xy 104.066672 -279.024016) (xy 104.082674 -279.073264)
			(xy 104.090775 -279.124409) (xy 104.090775 -279.176191) (xy 104.082674 -279.227336) (xy 104.066672 -279.276584)
			(xy 104.043163 -279.322722) (xy 104.012726 -279.364615) (xy 103.97611 -279.40123) (xy 103.934217 -279.431666)
			(xy 103.888078 -279.455175) (xy 103.83883 -279.471175) (xy 103.787685 -279.479275) (xy 103.761794 -279.479756)
			(xy 103.736281 -279.479297) (xy 103.685865 -279.471435) (xy 103.637262 -279.455898) (xy 103.591633 -279.433058)
			(xy 103.550069 -279.403461) (xy 103.51356 -279.367813) (xy 103.497888 -279.347676) (xy 103.0859 -279.347676)
			(xy 103.07022 -279.367806) (xy 103.033713 -279.403452) (xy 102.992149 -279.433046) (xy 102.946521 -279.455884)
			(xy 102.89792 -279.471418) (xy 102.847506 -279.479279) (xy 102.821994 -279.479756) (xy 102.796108 -279.479212)
			(xy 102.744975 -279.471112) (xy 102.695737 -279.455113) (xy 102.649609 -279.431609) (xy 102.607725 -279.401178)
			(xy 102.571118 -279.36457) (xy 102.540688 -279.322686) (xy 102.517184 -279.276557) (xy 102.501186 -279.22732)
			(xy 102.493088 -279.176186) (xy 102.211112 -279.176186) (xy 102.211076 -279.177962) (xy 102.201888 -279.23248)
			(xy 102.193344 -279.258776) (xy 102.185724 -279.28062) (xy 102.390956 -279.635966) (xy 102.413816 -279.640284)
			(xy 102.438629 -279.645487) (xy 102.486407 -279.662435) (xy 102.531027 -279.686501) (xy 102.571434 -279.717117)
			(xy 102.606676 -279.753559) (xy 102.635921 -279.794969) (xy 102.658479 -279.840369) (xy 102.673819 -279.888688)
			(xy 102.681577 -279.938786) (xy 102.68204 -279.964134) (xy 102.681532 -279.990041) (xy 102.673426 -280.041218)
			(xy 102.657414 -280.090497) (xy 102.633891 -280.136664) (xy 102.603435 -280.178583) (xy 102.566797 -280.215221)
			(xy 102.524878 -280.245677) (xy 102.478711 -280.2692) (xy 102.429432 -280.285212) (xy 102.378255 -280.293318)
			(xy 102.326441 -280.293318) (xy 102.275264 -280.285212) (xy 102.225985 -280.2692) (xy 102.179818 -280.245677)
			(xy 102.137899 -280.215221) (xy 102.101261 -280.178583) (xy 102.070805 -280.136664) (xy 102.047282 -280.090497)
			(xy 102.03127 -280.041218) (xy 102.023164 -279.990041) (xy 102.022656 -279.964134) (xy 102.023255 -279.936417)
			(xy 102.032575 -279.88177) (xy 102.041198 -279.855422) (xy 102.049072 -279.833324) (xy 101.844094 -279.478486)
			(xy 101.821234 -279.474168) (xy 101.796412 -279.468959) (xy 101.748608 -279.452029) (xy 101.70396 -279.427978)
			(xy 101.663522 -279.397372) (xy 101.628249 -279.360934) (xy 101.598973 -279.319523) (xy 101.576384 -279.274117)
			(xy 101.561016 -279.225788) (xy 101.553231 -279.175675) (xy 101.552756 -279.150318) (xy 31.743142 -279.150318)
			(xy 31.743142 -279.989984) (xy 88.866003 -279.989984) (xy 88.866003 -279.938216) (xy 88.874102 -279.887084)
			(xy 88.890099 -279.837849) (xy 88.913601 -279.791722) (xy 88.94403 -279.74984) (xy 88.980636 -279.713234)
			(xy 89.022517 -279.682805) (xy 89.068643 -279.659301) (xy 89.117878 -279.643303) (xy 89.16901 -279.635204)
			(xy 89.194894 -279.634696) (xy 89.220406 -279.635183) (xy 89.27082 -279.643042) (xy 89.319421 -279.658575)
			(xy 89.365049 -279.681409) (xy 89.406615 -279.711) (xy 89.443126 -279.746642) (xy 89.4588 -279.766776)
			(xy 89.870788 -279.766776) (xy 89.886462 -279.746641) (xy 89.922972 -279.710998) (xy 89.964538 -279.681405)
			(xy 90.010166 -279.658569) (xy 90.058768 -279.643035) (xy 90.109182 -279.635173) (xy 90.134694 -279.634696)
			(xy 90.160586 -279.635109) (xy 90.211734 -279.643209) (xy 90.260984 -279.659211) (xy 90.307125 -279.68272)
			(xy 90.349021 -279.713158) (xy 90.385638 -279.749775) (xy 90.416077 -279.791669) (xy 90.439587 -279.83781)
			(xy 90.45559 -279.88706) (xy 90.463691 -279.938208) (xy 90.463691 -279.964134) (xy 96.383856 -279.964134)
			(xy 96.384364 -279.938227) (xy 96.39247 -279.88705) (xy 96.408482 -279.837771) (xy 96.432005 -279.791604)
			(xy 96.462461 -279.749685) (xy 96.499099 -279.713047) (xy 96.541018 -279.682591) (xy 96.587185 -279.659068)
			(xy 96.636464 -279.643056) (xy 96.687641 -279.63495) (xy 96.739455 -279.63495) (xy 96.790632 -279.643056)
			(xy 96.839911 -279.659068) (xy 96.886078 -279.682591) (xy 96.927997 -279.713047) (xy 96.964635 -279.749685)
			(xy 96.995091 -279.791604) (xy 97.018614 -279.837771) (xy 97.034626 -279.88705) (xy 97.042732 -279.938227)
			(xy 97.04324 -279.964134) (xy 97.042606 -279.991926) (xy 97.033158 -280.046702) (xy 97.024444 -280.0731)
			(xy 97.016824 -280.095198) (xy 97.221802 -280.450036) (xy 97.244662 -280.454354) (xy 97.269457 -280.45958)
			(xy 97.317195 -280.476563) (xy 97.361773 -280.50065) (xy 97.402139 -280.531276) (xy 97.437344 -280.567718)
			(xy 97.466557 -280.609118) (xy 97.489091 -280.6545) (xy 97.504415 -280.702797) (xy 97.512168 -280.752869)
			(xy 97.512632 -280.778204) (xy 97.512124 -280.804091) (xy 97.504025 -280.855229) (xy 97.488026 -280.904469)
			(xy 97.46452 -280.950601) (xy 97.434088 -280.992488) (xy 97.397478 -281.029098) (xy 97.355591 -281.05953)
			(xy 97.309459 -281.083036) (xy 97.260219 -281.099035) (xy 97.209081 -281.107134) (xy 97.157307 -281.107134)
			(xy 97.106169 -281.099035) (xy 97.056929 -281.083036) (xy 97.010797 -281.05953) (xy 96.96891 -281.029098)
			(xy 96.9323 -280.992488) (xy 96.901868 -280.950601) (xy 96.878362 -280.904469) (xy 96.862363 -280.855229)
			(xy 96.854264 -280.804091) (xy 96.853756 -280.778204) (xy 96.854288 -280.750496) (xy 96.863482 -280.695849)
			(xy 96.872044 -280.669492) (xy 96.879918 -280.647394) (xy 96.674686 -280.292302) (xy 96.651826 -280.287984)
			(xy 96.627038 -280.282731) (xy 96.579302 -280.265749) (xy 96.534727 -280.241664) (xy 96.494362 -280.211041)
			(xy 96.459158 -280.174603) (xy 96.429944 -280.133207) (xy 96.407407 -280.087828) (xy 96.39208 -280.039536)
			(xy 96.384322 -279.989467) (xy 96.383856 -279.964134) (xy 90.463691 -279.964134) (xy 90.463691 -279.989992)
			(xy 90.45559 -280.04114) (xy 90.439587 -280.09039) (xy 90.416077 -280.13653) (xy 90.385638 -280.178425)
			(xy 90.349021 -280.215042) (xy 90.307125 -280.24548) (xy 90.260984 -280.268989) (xy 90.211734 -280.284991)
			(xy 90.160586 -280.293091) (xy 90.134694 -280.293572) (xy 90.109181 -280.293107) (xy 90.058766 -280.285245)
			(xy 90.010163 -280.269709) (xy 89.964535 -280.24687) (xy 89.92297 -280.217275) (xy 89.886461 -280.181628)
			(xy 89.870788 -280.161492) (xy 89.4588 -280.161492) (xy 89.443124 -280.181626) (xy 89.406615 -280.21727)
			(xy 89.365051 -280.246864) (xy 89.319422 -280.269701) (xy 89.270821 -280.285235) (xy 89.220406 -280.293095)
			(xy 89.194894 -280.293572) (xy 89.16901 -280.292996) (xy 89.117878 -280.284897) (xy 89.068643 -280.268899)
			(xy 89.022517 -280.245395) (xy 88.980636 -280.214966) (xy 88.94403 -280.17836) (xy 88.913601 -280.136478)
			(xy 88.890099 -280.090351) (xy 88.874102 -280.041116) (xy 88.866003 -279.989984) (xy 31.743142 -279.989984)
			(xy 31.743142 -280.804107) (xy 86.51622 -280.804107) (xy 86.51622 -280.752293) (xy 86.524326 -280.701118)
			(xy 86.540337 -280.65184) (xy 86.563859 -280.605674) (xy 86.594314 -280.563756) (xy 86.630951 -280.527118)
			(xy 86.672869 -280.496662) (xy 86.719035 -280.473139) (xy 86.768312 -280.457127) (xy 86.819487 -280.449021)
			(xy 86.845394 -280.448512) (xy 86.870888 -280.448996) (xy 86.921265 -280.456856) (xy 86.969828 -280.472391)
			(xy 87.015416 -280.495227) (xy 87.056936 -280.52482) (xy 87.093398 -280.56046) (xy 87.109046 -280.580592)
			(xy 87.521542 -280.580592) (xy 87.537192 -280.560462) (xy 87.573653 -280.52482) (xy 87.615173 -280.495227)
			(xy 87.66076 -280.472389) (xy 87.709323 -280.456853) (xy 87.7597 -280.448991) (xy 87.785194 -280.448512)
			(xy 87.811104 -280.448985) (xy 87.862286 -280.457091) (xy 87.91157 -280.473103) (xy 87.957743 -280.496628)
			(xy 87.999666 -280.527087) (xy 88.036309 -280.563729) (xy 88.066768 -280.605652) (xy 88.090294 -280.651824)
			(xy 88.106308 -280.701108) (xy 88.114414 -280.75229) (xy 88.114414 -280.80411) (xy 88.106308 -280.855292)
			(xy 88.090294 -280.904576) (xy 88.066768 -280.950748) (xy 88.036309 -280.992671) (xy 87.999666 -281.029313)
			(xy 87.957743 -281.059772) (xy 87.91157 -281.083297) (xy 87.862286 -281.099309) (xy 87.811104 -281.107415)
			(xy 87.785194 -281.107896) (xy 87.7597 -281.107418) (xy 87.709323 -281.099555) (xy 87.660759 -281.08402)
			(xy 87.615172 -281.061182) (xy 87.573652 -281.031589) (xy 87.53719 -280.995948) (xy 87.521542 -280.975816)
			(xy 87.109046 -280.975816) (xy 87.093405 -280.995954) (xy 87.056942 -281.031594) (xy 87.01542 -281.061187)
			(xy 86.969831 -281.084023) (xy 86.921267 -281.099558) (xy 86.870888 -281.107418) (xy 86.845394 -281.107896)
			(xy 86.819487 -281.107379) (xy 86.768312 -281.099273) (xy 86.719035 -281.083261) (xy 86.672869 -281.059738)
			(xy 86.630951 -281.029282) (xy 86.594314 -280.992644) (xy 86.563859 -280.950726) (xy 86.540337 -280.90456)
			(xy 86.524326 -280.855282) (xy 86.51622 -280.804107) (xy 31.743142 -280.804107) (xy 31.743142 -282.405836)
			(xy 86.515956 -282.405836) (xy 86.516374 -282.380488) (xy 86.524157 -282.330393) (xy 86.539514 -282.282079)
			(xy 86.562083 -282.236685) (xy 86.591333 -282.195278) (xy 86.626575 -282.158835) (xy 86.666978 -282.128214)
			(xy 86.711591 -282.104137) (xy 86.759364 -282.08717) (xy 86.78418 -282.081986) (xy 86.80704 -282.077668)
			(xy 87.012018 -281.722576) (xy 87.004398 -281.700732) (xy 86.995753 -281.67439) (xy 86.986439 -281.619739)
			(xy 86.985856 -281.59202) (xy 86.986364 -281.566113) (xy 86.99447 -281.514936) (xy 87.010482 -281.465657)
			(xy 87.034005 -281.41949) (xy 87.064461 -281.377571) (xy 87.101099 -281.340933) (xy 87.143018 -281.310477)
			(xy 87.189185 -281.286954) (xy 87.238464 -281.270942) (xy 87.289641 -281.262836) (xy 87.341455 -281.262836)
			(xy 87.392632 -281.270942) (xy 87.441911 -281.286954) (xy 87.488078 -281.310477) (xy 87.529997 -281.340933)
			(xy 87.566635 -281.377571) (xy 87.597091 -281.41949) (xy 87.620614 -281.465657) (xy 87.636626 -281.514936)
			(xy 87.644732 -281.566113) (xy 87.64524 -281.59202) (xy 88.865456 -281.59202) (xy 88.86595 -281.566675)
			(xy 88.87372 -281.516583) (xy 88.889066 -281.468271) (xy 88.911624 -281.422876) (xy 88.940864 -281.381469)
			(xy 88.976098 -281.345025) (xy 89.016493 -281.314403) (xy 89.0611 -281.290323) (xy 89.108866 -281.273355)
			(xy 89.13368 -281.26817) (xy 89.15654 -281.263852) (xy 89.361518 -280.909014) (xy 89.353898 -280.88717)
			(xy 89.345254 -280.860761) (xy 89.335932 -280.805986) (xy 89.335356 -280.778204) (xy 89.335819 -280.752307)
			(xy 89.343918 -280.70115) (xy 89.359916 -280.651889) (xy 89.383421 -280.605736) (xy 89.413854 -280.563826)
			(xy 89.450466 -280.527191) (xy 89.492357 -280.496731) (xy 89.538495 -280.473197) (xy 89.587746 -280.457167)
			(xy 89.638897 -280.449036) (xy 89.664794 -280.448512) (xy 89.690698 -280.44895) (xy 89.741869 -280.457058)
			(xy 89.79114 -280.473077) (xy 89.837295 -280.49661) (xy 89.879199 -280.527077) (xy 89.915817 -280.563728)
			(xy 89.946246 -280.605659) (xy 89.969738 -280.651836) (xy 89.985711 -280.701121) (xy 89.993774 -280.752299)
			(xy 89.994232 -280.778204) (xy 92.154756 -280.778204) (xy 92.155193 -280.752292) (xy 92.163301 -280.701107)
			(xy 92.179316 -280.65182) (xy 92.202845 -280.605646) (xy 92.233308 -280.563722) (xy 92.269955 -280.527079)
			(xy 92.311884 -280.496622) (xy 92.358061 -280.473099) (xy 92.40735 -280.45709) (xy 92.458536 -280.44899)
			(xy 92.484448 -280.448512) (xy 92.510354 -280.4489) (xy 92.561526 -280.457017) (xy 92.610798 -280.473042)
			(xy 92.656954 -280.496582) (xy 92.698857 -280.527055) (xy 92.735474 -280.563712) (xy 92.765902 -280.605647)
			(xy 92.789393 -280.651828) (xy 92.805366 -280.701117) (xy 92.813428 -280.752298) (xy 92.813886 -280.778204)
			(xy 92.813354 -280.804107) (xy 94.97442 -280.804107) (xy 94.97442 -280.752293) (xy 94.982526 -280.701118)
			(xy 94.998537 -280.65184) (xy 95.022059 -280.605674) (xy 95.052514 -280.563756) (xy 95.089151 -280.527118)
			(xy 95.131069 -280.496662) (xy 95.177235 -280.473139) (xy 95.226512 -280.457127) (xy 95.277687 -280.449021)
			(xy 95.303594 -280.448512) (xy 95.329106 -280.448992) (xy 95.379521 -280.456852) (xy 95.428122 -280.472385)
			(xy 95.473751 -280.495221) (xy 95.515316 -280.524814) (xy 95.551826 -280.560457) (xy 95.5675 -280.580592)
			(xy 95.979742 -280.580592) (xy 95.995389 -280.560435) (xy 96.031904 -280.524793) (xy 96.073475 -280.495202)
			(xy 96.119109 -280.472369) (xy 96.167716 -280.45684) (xy 96.218134 -280.448986) (xy 96.243648 -280.448512)
			(xy 96.269553 -280.449016) (xy 96.320725 -280.457128) (xy 96.369997 -280.473144) (xy 96.416159 -280.49667)
			(xy 96.458071 -280.527127) (xy 96.494704 -280.563765) (xy 96.525155 -280.605682) (xy 96.548675 -280.651847)
			(xy 96.564684 -280.701122) (xy 96.572788 -280.752295) (xy 96.572788 -280.804105) (xy 96.564684 -280.855278)
			(xy 96.548675 -280.904553) (xy 96.525155 -280.950718) (xy 96.494704 -280.992635) (xy 96.458071 -281.029273)
			(xy 96.416159 -281.05973) (xy 96.369997 -281.083256) (xy 96.320725 -281.099272) (xy 96.269553 -281.107384)
			(xy 96.243648 -281.107896) (xy 96.218137 -281.107382) (xy 96.167724 -281.099529) (xy 96.119123 -281.084002)
			(xy 96.073495 -281.061173) (xy 96.031928 -281.031586) (xy 95.995417 -280.995948) (xy 95.979742 -280.975816)
			(xy 95.5675 -280.975816) (xy 95.551831 -280.995955) (xy 95.51532 -281.031598) (xy 95.473753 -281.06119)
			(xy 95.428124 -281.084026) (xy 95.379522 -281.099559) (xy 95.329106 -281.107419) (xy 95.303594 -281.107896)
			(xy 95.277687 -281.107379) (xy 95.226512 -281.099273) (xy 95.177235 -281.083261) (xy 95.131069 -281.059738)
			(xy 95.089151 -281.029282) (xy 95.052514 -280.992644) (xy 95.022059 -280.950726) (xy 94.998537 -280.90456)
			(xy 94.982526 -280.855282) (xy 94.97442 -280.804107) (xy 92.813354 -280.804107) (xy 92.813315 -280.805986)
			(xy 92.803991 -280.860762) (xy 92.795344 -280.88717) (xy 92.787724 -280.909014) (xy 92.992702 -281.263852)
			(xy 93.015562 -281.26817) (xy 93.04036 -281.273381) (xy 93.0881 -281.290365) (xy 93.132678 -281.314454)
			(xy 93.173045 -281.345081) (xy 93.20825 -281.381525) (xy 93.237463 -281.422927) (xy 93.259996 -281.468312)
			(xy 93.275318 -281.51661) (xy 93.283069 -281.566685) (xy 93.283532 -281.59202) (xy 93.283024 -281.617907)
			(xy 93.274925 -281.669045) (xy 93.258926 -281.718285) (xy 93.23542 -281.764417) (xy 93.204988 -281.806304)
			(xy 93.168378 -281.842914) (xy 93.126491 -281.873346) (xy 93.080359 -281.896852) (xy 93.031119 -281.912851)
			(xy 92.979981 -281.92095) (xy 92.928207 -281.92095) (xy 92.877069 -281.912851) (xy 92.827829 -281.896852)
			(xy 92.781697 -281.873346) (xy 92.73981 -281.842914) (xy 92.7032 -281.806304) (xy 92.672768 -281.764417)
			(xy 92.649262 -281.718285) (xy 92.633263 -281.669045) (xy 92.625164 -281.617907) (xy 92.624656 -281.59202)
			(xy 92.625203 -281.564313) (xy 92.634391 -281.509667) (xy 92.642944 -281.483308) (xy 92.650564 -281.461464)
			(xy 92.445586 -281.106372) (xy 92.422726 -281.102054) (xy 92.397931 -281.096829) (xy 92.350193 -281.079845)
			(xy 92.305616 -281.055757) (xy 92.265251 -281.025131) (xy 92.230046 -280.988689) (xy 92.200833 -280.947289)
			(xy 92.178299 -280.901907) (xy 92.162974 -280.853611) (xy 92.15522 -280.803539) (xy 92.154756 -280.778204)
			(xy 89.994232 -280.778204) (xy 89.993765 -280.803528) (xy 89.986033 -280.853583) (xy 89.970734 -280.901865)
			(xy 89.94823 -280.947239) (xy 89.91905 -280.988637) (xy 89.883881 -281.025084) (xy 89.843551 -281.055722)
			(xy 89.799008 -281.079831) (xy 89.751302 -281.096842) (xy 89.726516 -281.102054) (xy 89.703656 -281.106372)
			(xy 89.498678 -281.46121) (xy 89.506298 -281.483054) (xy 89.51491 -281.50934) (xy 89.524233 -281.563858)
			(xy 89.52484 -281.591512) (xy 89.52484 -281.59202) (xy 89.524332 -281.617905) (xy 90.745336 -281.617905)
			(xy 90.745336 -281.566095) (xy 90.753441 -281.514922) (xy 90.769451 -281.465646) (xy 90.792973 -281.419482)
			(xy 90.823426 -281.377566) (xy 90.860062 -281.34093) (xy 90.901977 -281.310476) (xy 90.948141 -281.286954)
			(xy 90.997416 -281.270943) (xy 91.048589 -281.262837) (xy 91.074494 -281.262328) (xy 91.100006 -281.262802)
			(xy 91.150421 -281.270662) (xy 91.199024 -281.286196) (xy 91.244652 -281.309033) (xy 91.286218 -281.338627)
			(xy 91.322727 -281.374272) (xy 91.3384 -281.394408) (xy 91.750388 -281.394408) (xy 91.766071 -281.37428)
			(xy 91.802578 -281.338635) (xy 91.844142 -281.309041) (xy 91.889768 -281.286203) (xy 91.938369 -281.270668)
			(xy 91.988782 -281.262806) (xy 92.014294 -281.262328) (xy 92.040205 -281.262769) (xy 92.09139 -281.270875)
			(xy 92.140676 -281.286888) (xy 92.186851 -281.310415) (xy 92.228777 -281.340875) (xy 92.265421 -281.377519)
			(xy 92.295882 -281.419444) (xy 92.319409 -281.465618) (xy 92.335423 -281.514904) (xy 92.34353 -281.566089)
			(xy 92.34353 -281.617911) (xy 92.335423 -281.669096) (xy 92.319409 -281.718382) (xy 92.295882 -281.764556)
			(xy 92.265421 -281.806481) (xy 92.228777 -281.843125) (xy 92.186851 -281.873585) (xy 92.140676 -281.897112)
			(xy 92.09139 -281.913125) (xy 92.040205 -281.921231) (xy 92.014294 -281.921712) (xy 91.988782 -281.921231)
			(xy 91.938368 -281.91337) (xy 91.889767 -281.897836) (xy 91.844138 -281.875001) (xy 91.802573 -281.845409)
			(xy 91.766062 -281.809767) (xy 91.750388 -281.789632) (xy 91.3384 -281.789632) (xy 91.322735 -281.809774)
			(xy 91.286223 -281.845417) (xy 91.244655 -281.875008) (xy 91.199025 -281.897843) (xy 91.150422 -281.913376)
			(xy 91.100006 -281.921235) (xy 91.074494 -281.921712) (xy 91.048589 -281.921163) (xy 90.997416 -281.913057)
			(xy 90.948141 -281.897046) (xy 90.901977 -281.873524) (xy 90.860062 -281.84307) (xy 90.823426 -281.806434)
			(xy 90.792973 -281.764518) (xy 90.769451 -281.718354) (xy 90.753441 -281.669078) (xy 90.745336 -281.617905)
			(xy 89.524332 -281.617905) (xy 89.524332 -281.617927) (xy 89.516226 -281.669104) (xy 89.500214 -281.718383)
			(xy 89.476691 -281.76455) (xy 89.446235 -281.806469) (xy 89.409597 -281.843107) (xy 89.367678 -281.873563)
			(xy 89.321511 -281.897086) (xy 89.272232 -281.913098) (xy 89.221055 -281.921204) (xy 89.169241 -281.921204)
			(xy 89.118064 -281.913098) (xy 89.068785 -281.897086) (xy 89.022618 -281.873563) (xy 88.980699 -281.843107)
			(xy 88.944061 -281.806469) (xy 88.913605 -281.76455) (xy 88.890082 -281.718383) (xy 88.87407 -281.669104)
			(xy 88.865964 -281.617927) (xy 88.865456 -281.59202) (xy 87.64524 -281.59202) (xy 87.644785 -281.617367)
			(xy 87.637009 -281.66746) (xy 87.621658 -281.715773) (xy 87.599094 -281.761168) (xy 87.569849 -281.802575)
			(xy 87.534611 -281.839019) (xy 87.494211 -281.86964) (xy 87.449601 -281.893718) (xy 87.401831 -281.910686)
			(xy 87.377016 -281.91587) (xy 87.354156 -281.920188) (xy 87.149178 -282.27528) (xy 87.156798 -282.297124)
			(xy 87.165433 -282.32347) (xy 87.174753 -282.378118) (xy 87.17534 -282.405836) (xy 87.455756 -282.405836)
			(xy 87.456264 -282.379949) (xy 87.464363 -282.328811) (xy 87.480362 -282.279571) (xy 87.503868 -282.233439)
			(xy 87.5343 -282.191552) (xy 87.57091 -282.154942) (xy 87.612797 -282.12451) (xy 87.658929 -282.101004)
			(xy 87.708169 -282.085005) (xy 87.759307 -282.076906) (xy 87.811081 -282.076906) (xy 87.862219 -282.085005)
			(xy 87.911459 -282.101004) (xy 87.957591 -282.12451) (xy 87.999478 -282.154942) (xy 88.036088 -282.191552)
			(xy 88.06652 -282.233439) (xy 88.090026 -282.279571) (xy 88.106025 -282.328811) (xy 88.114124 -282.379949)
			(xy 88.114632 -282.405836) (xy 88.114145 -282.431709) (xy 88.396026 -282.431709) (xy 88.396026 -282.379891)
			(xy 88.404133 -282.328711) (xy 88.420147 -282.27943) (xy 88.443674 -282.233261) (xy 88.474134 -282.191341)
			(xy 88.510778 -282.154703) (xy 88.552702 -282.124249) (xy 88.598874 -282.100729) (xy 88.648158 -282.084722)
			(xy 88.699339 -282.076622) (xy 88.725248 -282.076144) (xy 88.750741 -282.076648) (xy 88.801118 -282.084503)
			(xy 88.849682 -282.100032) (xy 88.895269 -282.122865) (xy 88.936791 -282.152454) (xy 88.973252 -282.188093)
			(xy 88.9889 -282.208224) (xy 89.401396 -282.208224) (xy 89.417024 -282.188075) (xy 89.453488 -282.152433)
			(xy 89.495013 -282.122841) (xy 89.540604 -282.100006) (xy 89.589171 -282.084474) (xy 89.639553 -282.076619)
			(xy 89.665048 -282.076144) (xy 89.690956 -282.076584) (xy 89.742132 -282.084696) (xy 89.79141 -282.100714)
			(xy 89.837576 -282.124242) (xy 89.879493 -282.154702) (xy 89.916129 -282.191344) (xy 89.946583 -282.233265)
			(xy 89.970105 -282.279434) (xy 89.986115 -282.328714) (xy 89.99422 -282.379892) (xy 89.99422 -282.431708)
			(xy 89.986115 -282.482886) (xy 89.970105 -282.532166) (xy 89.946583 -282.578335) (xy 89.916129 -282.620256)
			(xy 89.879493 -282.656898) (xy 89.837576 -282.687358) (xy 89.79141 -282.710886) (xy 89.742132 -282.726904)
			(xy 89.690956 -282.735016) (xy 89.665048 -282.735528) (xy 89.639556 -282.734998) (xy 89.589182 -282.727145)
			(xy 89.54062 -282.711619) (xy 89.495033 -282.688791) (xy 89.453511 -282.659207) (xy 89.417046 -282.623576)
			(xy 89.401396 -282.603448) (xy 88.9889 -282.603448) (xy 88.973236 -282.623567) (xy 88.936776 -282.659207)
			(xy 88.895259 -282.6888) (xy 88.849675 -282.71164) (xy 88.801115 -282.727179) (xy 88.750741 -282.735046)
			(xy 88.725248 -282.735528) (xy 88.699339 -282.734978) (xy 88.648158 -282.726878) (xy 88.598874 -282.710871)
			(xy 88.552702 -282.687351) (xy 88.510778 -282.656897) (xy 88.474134 -282.620259) (xy 88.443674 -282.578339)
			(xy 88.420147 -282.53217) (xy 88.404133 -282.482889) (xy 88.396026 -282.431709) (xy 88.114145 -282.431709)
			(xy 88.11411 -282.433545) (xy 88.10491 -282.488191) (xy 88.096344 -282.514548) (xy 88.08847 -282.536646)
			(xy 88.293702 -282.891738) (xy 88.316562 -282.896056) (xy 88.341357 -282.90128) (xy 88.389096 -282.918263)
			(xy 88.433673 -282.942351) (xy 88.47404 -282.972977) (xy 88.509244 -283.009419) (xy 88.538458 -283.050819)
			(xy 88.560992 -283.096202) (xy 88.576316 -283.144498) (xy 88.584068 -283.194571) (xy 88.584532 -283.219906)
			(xy 90.745056 -283.219906) (xy 90.74558 -283.194573) (xy 90.75333 -283.144505) (xy 90.768649 -283.096211)
			(xy 90.791176 -283.05083) (xy 90.820381 -283.009429) (xy 90.855576 -282.972983) (xy 90.895932 -282.942351)
			(xy 90.9405 -282.918254) (xy 90.988229 -282.901258) (xy 91.013026 -282.896056) (xy 91.035886 -282.891738)
			(xy 91.241118 -282.536392) (xy 91.233498 -282.514548) (xy 91.224857 -282.488204) (xy 91.215541 -282.433555)
			(xy 91.214956 -282.405836) (xy 91.215464 -282.379929) (xy 91.22357 -282.328752) (xy 91.239582 -282.279473)
			(xy 91.263105 -282.233306) (xy 91.293561 -282.191387) (xy 91.330199 -282.154749) (xy 91.372118 -282.124293)
			(xy 91.418285 -282.10077) (xy 91.467564 -282.084758) (xy 91.518741 -282.076652) (xy 91.570555 -282.076652)
			(xy 91.621732 -282.084758) (xy 91.671011 -282.10077) (xy 91.717178 -282.124293) (xy 91.759097 -282.154749)
			(xy 91.795735 -282.191387) (xy 91.826191 -282.233306) (xy 91.849714 -282.279473) (xy 91.865726 -282.328752)
			(xy 91.873832 -282.379929) (xy 91.87434 -282.405836) (xy 93.094556 -282.405836) (xy 93.094974 -282.380488)
			(xy 93.102757 -282.330393) (xy 93.118114 -282.282079) (xy 93.140683 -282.236685) (xy 93.169933 -282.195278)
			(xy 93.205175 -282.158835) (xy 93.245578 -282.128214) (xy 93.290191 -282.104137) (xy 93.337964 -282.08717)
			(xy 93.36278 -282.081986) (xy 93.38564 -282.077668) (xy 93.590618 -281.72283) (xy 93.582744 -281.700986)
			(xy 93.574162 -281.674568) (xy 93.564967 -281.619792) (xy 93.564456 -281.59202) (xy 93.564964 -281.566133)
			(xy 93.573063 -281.514995) (xy 93.589062 -281.465755) (xy 93.612568 -281.419623) (xy 93.643 -281.377736)
			(xy 93.67961 -281.341126) (xy 93.721497 -281.310694) (xy 93.767629 -281.287188) (xy 93.816869 -281.271189)
			(xy 93.868007 -281.26309) (xy 93.919781 -281.26309) (xy 93.970919 -281.271189) (xy 94.020159 -281.287188)
			(xy 94.066291 -281.310694) (xy 94.108178 -281.341126) (xy 94.144788 -281.377736) (xy 94.17522 -281.419623)
			(xy 94.198726 -281.465755) (xy 94.214725 -281.514995) (xy 94.222824 -281.566133) (xy 94.223332 -281.59202)
			(xy 94.222842 -281.617354) (xy 94.215087 -281.667425) (xy 94.199764 -281.71572) (xy 94.177233 -281.761102)
			(xy 94.148024 -281.802503) (xy 94.112825 -281.838948) (xy 94.072465 -281.869579) (xy 94.027893 -281.893676)
			(xy 93.980161 -281.910669) (xy 93.955362 -281.91587) (xy 93.932502 -281.920188) (xy 93.727524 -282.275026)
			(xy 93.735398 -282.297124) (xy 93.744018 -282.323474) (xy 93.753346 -282.378119) (xy 93.75394 -282.405836)
			(xy 94.974156 -282.405836) (xy 94.974616 -282.380501) (xy 94.982377 -282.33043) (xy 94.997705 -282.282135)
			(xy 95.020241 -282.236753) (xy 95.049454 -282.195352) (xy 95.084656 -282.158908) (xy 95.125019 -282.128277)
			(xy 95.169592 -282.104181) (xy 95.217327 -282.087187) (xy 95.242126 -282.081986) (xy 95.264986 -282.077668)
			(xy 95.470218 -281.722322) (xy 95.462598 -281.700478) (xy 95.45397 -281.674197) (xy 95.444658 -281.619675)
			(xy 95.444056 -281.59202) (xy 95.444564 -281.566113) (xy 95.45267 -281.514936) (xy 95.468682 -281.465657)
			(xy 95.492205 -281.41949) (xy 95.522661 -281.377571) (xy 95.559299 -281.340933) (xy 95.601218 -281.310477)
			(xy 95.647385 -281.286954) (xy 95.696664 -281.270942) (xy 95.747841 -281.262836) (xy 95.799655 -281.262836)
			(xy 95.850832 -281.270942) (xy 95.900111 -281.286954) (xy 95.946278 -281.310477) (xy 95.988197 -281.340933)
			(xy 96.024835 -281.377571) (xy 96.055291 -281.41949) (xy 96.078814 -281.465657) (xy 96.094826 -281.514936)
			(xy 96.102932 -281.566113) (xy 96.10344 -281.59202) (xy 97.323656 -281.59202) (xy 97.32415 -281.566675)
			(xy 97.33192 -281.516583) (xy 97.347266 -281.468271) (xy 97.369824 -281.422876) (xy 97.399064 -281.381469)
			(xy 97.434298 -281.345025) (xy 97.474693 -281.314403) (xy 97.5193 -281.290323) (xy 97.567066 -281.273355)
			(xy 97.59188 -281.26817) (xy 97.61474 -281.263852) (xy 97.819718 -280.909014) (xy 97.811844 -280.88717)
			(xy 97.803259 -280.860753) (xy 97.794066 -280.805977) (xy 97.793556 -280.778204) (xy 97.794064 -280.752317)
			(xy 97.802163 -280.701179) (xy 97.818162 -280.651939) (xy 97.841668 -280.605807) (xy 97.8721 -280.56392)
			(xy 97.90871 -280.52731) (xy 97.950597 -280.496878) (xy 97.996729 -280.473372) (xy 98.045969 -280.457373)
			(xy 98.097107 -280.449274) (xy 98.148881 -280.449274) (xy 98.200019 -280.457373) (xy 98.249259 -280.473372)
			(xy 98.295391 -280.496878) (xy 98.337278 -280.52731) (xy 98.373888 -280.56392) (xy 98.40432 -280.605807)
			(xy 98.427826 -280.651939) (xy 98.443825 -280.701179) (xy 98.451924 -280.752317) (xy 98.452432 -280.778204)
			(xy 100.612956 -280.778204) (xy 100.613464 -280.752317) (xy 100.621563 -280.701179) (xy 100.637562 -280.651939)
			(xy 100.661068 -280.605807) (xy 100.6915 -280.56392) (xy 100.72811 -280.52731) (xy 100.769997 -280.496878)
			(xy 100.816129 -280.473372) (xy 100.865369 -280.457373) (xy 100.916507 -280.449274) (xy 100.968281 -280.449274)
			(xy 101.019419 -280.457373) (xy 101.068659 -280.473372) (xy 101.114791 -280.496878) (xy 101.156678 -280.52731)
			(xy 101.193288 -280.56392) (xy 101.22372 -280.605807) (xy 101.247226 -280.651939) (xy 101.263225 -280.701179)
			(xy 101.271324 -280.752317) (xy 101.271832 -280.778204) (xy 103.432356 -280.778204) (xy 103.432864 -280.752317)
			(xy 103.440963 -280.701179) (xy 103.456962 -280.651939) (xy 103.480468 -280.605807) (xy 103.5109 -280.56392)
			(xy 103.54751 -280.52731) (xy 103.589397 -280.496878) (xy 103.635529 -280.473372) (xy 103.684769 -280.457373)
			(xy 103.735907 -280.449274) (xy 103.787681 -280.449274) (xy 103.838819 -280.457373) (xy 103.888059 -280.473372)
			(xy 103.934191 -280.496878) (xy 103.976078 -280.52731) (xy 104.012688 -280.56392) (xy 104.04312 -280.605807)
			(xy 104.066626 -280.651939) (xy 104.082625 -280.701179) (xy 104.090724 -280.752317) (xy 104.091232 -280.778204)
			(xy 104.372156 -280.778204) (xy 104.372678 -280.752871) (xy 104.380429 -280.702803) (xy 104.395748 -280.654509)
			(xy 104.418275 -280.609127) (xy 104.44748 -280.567726) (xy 104.482675 -280.531281) (xy 104.523032 -280.500649)
			(xy 104.567599 -280.476552) (xy 104.615329 -280.459556) (xy 104.640126 -280.454354) (xy 104.662986 -280.450036)
			(xy 104.868218 -280.09469) (xy 104.860598 -280.072592) (xy 104.851973 -280.04631) (xy 104.842659 -279.991789)
			(xy 104.842056 -279.964134) (xy 104.842564 -279.938227) (xy 104.85067 -279.88705) (xy 104.866682 -279.837771)
			(xy 104.890205 -279.791604) (xy 104.920661 -279.749685) (xy 104.957299 -279.713047) (xy 104.999218 -279.682591)
			(xy 105.045385 -279.659068) (xy 105.094664 -279.643056) (xy 105.145841 -279.63495) (xy 105.197655 -279.63495)
			(xy 105.248832 -279.643056) (xy 105.298111 -279.659068) (xy 105.344278 -279.682591) (xy 105.386197 -279.713047)
			(xy 105.422835 -279.749685) (xy 105.453291 -279.791604) (xy 105.476814 -279.837771) (xy 105.492826 -279.88705)
			(xy 105.500932 -279.938227) (xy 105.50144 -279.964134) (xy 105.501001 -279.989499) (xy 105.493248 -280.039631)
			(xy 105.4779 -280.087982) (xy 105.45532 -280.133408) (xy 105.426041 -280.174835) (xy 105.390757 -280.211282)
			(xy 105.350301 -280.241888) (xy 105.305631 -280.26593) (xy 105.257803 -280.282837) (xy 105.232962 -280.287984)
			(xy 105.209848 -280.292302) (xy 105.00487 -280.647394) (xy 105.012744 -280.669492) (xy 105.021304 -280.69585)
			(xy 105.030503 -280.750496) (xy 105.031032 -280.778204) (xy 105.030524 -280.804091) (xy 105.022425 -280.855229)
			(xy 105.006426 -280.904469) (xy 104.98292 -280.950601) (xy 104.952488 -280.992488) (xy 104.915878 -281.029098)
			(xy 104.873991 -281.05953) (xy 104.827859 -281.083036) (xy 104.778619 -281.099035) (xy 104.727481 -281.107134)
			(xy 104.675707 -281.107134) (xy 104.624569 -281.099035) (xy 104.575329 -281.083036) (xy 104.529197 -281.05953)
			(xy 104.48731 -281.029098) (xy 104.4507 -280.992488) (xy 104.420268 -280.950601) (xy 104.396762 -280.904469)
			(xy 104.380763 -280.855229) (xy 104.372664 -280.804091) (xy 104.372156 -280.778204) (xy 104.091232 -280.778204)
			(xy 104.090673 -280.805848) (xy 104.081487 -280.860366) (xy 104.072944 -280.886662) (xy 104.065324 -280.908506)
			(xy 104.270556 -281.263852) (xy 104.293416 -281.26817) (xy 104.318226 -281.273386) (xy 104.366003 -281.290334)
			(xy 104.410622 -281.314398) (xy 104.451028 -281.345012) (xy 104.48627 -281.381453) (xy 104.515516 -281.422861)
			(xy 104.538075 -281.468259) (xy 104.553416 -281.516576) (xy 104.561176 -281.566673) (xy 104.56164 -281.59202)
			(xy 104.561132 -281.617927) (xy 104.553026 -281.669104) (xy 104.537014 -281.718383) (xy 104.513491 -281.76455)
			(xy 104.483035 -281.806469) (xy 104.446397 -281.843107) (xy 104.404478 -281.873563) (xy 104.358311 -281.897086)
			(xy 104.309032 -281.913098) (xy 104.257855 -281.921204) (xy 104.206041 -281.921204) (xy 104.154864 -281.913098)
			(xy 104.105585 -281.897086) (xy 104.059418 -281.873563) (xy 104.017499 -281.843107) (xy 103.980861 -281.806469)
			(xy 103.950405 -281.76455) (xy 103.926882 -281.718383) (xy 103.91087 -281.669104) (xy 103.902764 -281.617927)
			(xy 103.902256 -281.59202) (xy 103.902852 -281.564303) (xy 103.912174 -281.509656) (xy 103.920798 -281.483308)
			(xy 103.928672 -281.46121) (xy 103.723694 -281.106372) (xy 103.700834 -281.102054) (xy 103.676009 -281.096858)
			(xy 103.628203 -281.079927) (xy 103.583555 -281.055874) (xy 103.543117 -281.025267) (xy 103.507844 -280.988827)
			(xy 103.478568 -280.947415) (xy 103.45598 -280.902007) (xy 103.440613 -280.853676) (xy 103.43283 -280.803562)
			(xy 103.432356 -280.778204) (xy 101.271832 -280.778204) (xy 101.271273 -280.805848) (xy 101.262087 -280.860366)
			(xy 101.253544 -280.886662) (xy 101.245924 -280.908506) (xy 101.451156 -281.263852) (xy 101.474016 -281.26817)
			(xy 101.498826 -281.273386) (xy 101.546603 -281.290334) (xy 101.591222 -281.314398) (xy 101.631628 -281.345012)
			(xy 101.66687 -281.381453) (xy 101.696116 -281.422861) (xy 101.718675 -281.468259) (xy 101.734016 -281.516576)
			(xy 101.741776 -281.566673) (xy 101.74224 -281.59202) (xy 101.741732 -281.617927) (xy 101.733626 -281.669104)
			(xy 101.717614 -281.718383) (xy 101.694091 -281.76455) (xy 101.663635 -281.806469) (xy 101.626997 -281.843107)
			(xy 101.585078 -281.873563) (xy 101.538911 -281.897086) (xy 101.489632 -281.913098) (xy 101.438455 -281.921204)
			(xy 101.386641 -281.921204) (xy 101.335464 -281.913098) (xy 101.286185 -281.897086) (xy 101.240018 -281.873563)
			(xy 101.198099 -281.843107) (xy 101.161461 -281.806469) (xy 101.131005 -281.76455) (xy 101.107482 -281.718383)
			(xy 101.09147 -281.669104) (xy 101.083364 -281.617927) (xy 101.082856 -281.59202) (xy 101.083452 -281.564303)
			(xy 101.092774 -281.509656) (xy 101.101398 -281.483308) (xy 101.109272 -281.46121) (xy 100.904294 -281.106372)
			(xy 100.881434 -281.102054) (xy 100.856609 -281.096858) (xy 100.808803 -281.079927) (xy 100.764155 -281.055874)
			(xy 100.723717 -281.025267) (xy 100.688444 -280.988827) (xy 100.659168 -280.947415) (xy 100.63658 -280.902007)
			(xy 100.621213 -280.853676) (xy 100.61343 -280.803562) (xy 100.612956 -280.778204) (xy 98.452432 -280.778204)
			(xy 98.451927 -280.803537) (xy 98.444175 -280.853607) (xy 98.428854 -280.901902) (xy 98.406324 -280.947284)
			(xy 98.377117 -280.988685) (xy 98.34192 -281.025131) (xy 98.301561 -281.055762) (xy 98.256992 -281.079859)
			(xy 98.20926 -281.096853) (xy 98.184462 -281.102054) (xy 98.161602 -281.106372) (xy 97.956624 -281.46121)
			(xy 97.964498 -281.483308) (xy 97.973138 -281.509652) (xy 97.982453 -281.564301) (xy 97.98304 -281.59202)
			(xy 97.982532 -281.61791) (xy 99.20371 -281.61791) (xy 99.20371 -281.56609) (xy 99.211817 -281.514907)
			(xy 99.227832 -281.465624) (xy 99.25136 -281.419452) (xy 99.281822 -281.37753) (xy 99.318467 -281.34089)
			(xy 99.360393 -281.310435) (xy 99.406568 -281.286913) (xy 99.455854 -281.270906) (xy 99.507038 -281.262806)
			(xy 99.532948 -281.262328) (xy 99.558462 -281.262762) (xy 99.608879 -281.270631) (xy 99.657482 -281.286173)
			(xy 99.70311 -281.309017) (xy 99.744675 -281.338618) (xy 99.781182 -281.374269) (xy 99.796854 -281.394408)
			(xy 100.208842 -281.394408) (xy 100.224493 -281.374254) (xy 100.261007 -281.338611) (xy 100.302577 -281.309019)
			(xy 100.34821 -281.286186) (xy 100.396816 -281.270657) (xy 100.447235 -281.262802) (xy 100.472748 -281.262328)
			(xy 100.498654 -281.2628) (xy 100.549829 -281.270912) (xy 100.599104 -281.286928) (xy 100.645267 -281.310456)
			(xy 100.687182 -281.340914) (xy 100.723817 -281.377554) (xy 100.754269 -281.419474) (xy 100.77779 -281.465641)
			(xy 100.7938 -281.514918) (xy 100.801904 -281.566093) (xy 100.801904 -281.617907) (xy 100.7938 -281.669082)
			(xy 100.77779 -281.718359) (xy 100.754269 -281.764526) (xy 100.723817 -281.806446) (xy 100.687182 -281.843086)
			(xy 100.645267 -281.873544) (xy 100.599104 -281.897072) (xy 100.549829 -281.913088) (xy 100.498654 -281.9212)
			(xy 100.472748 -281.921712) (xy 100.447238 -281.921192) (xy 100.396825 -281.913339) (xy 100.348225 -281.897813)
			(xy 100.302596 -281.874985) (xy 100.26103 -281.8454) (xy 100.224517 -281.809764) (xy 100.208842 -281.789632)
			(xy 99.796854 -281.789632) (xy 99.781158 -281.809749) (xy 99.744652 -281.845392) (xy 99.703091 -281.874987)
			(xy 99.657467 -281.897826) (xy 99.60887 -281.913365) (xy 99.558459 -281.921231) (xy 99.532948 -281.921712)
			(xy 99.507038 -281.921194) (xy 99.455854 -281.913094) (xy 99.406568 -281.897087) (xy 99.360393 -281.873565)
			(xy 99.318467 -281.84311) (xy 99.281822 -281.80647) (xy 99.25136 -281.764548) (xy 99.227832 -281.718376)
			(xy 99.211817 -281.669093) (xy 99.20371 -281.61791) (xy 97.982532 -281.61791) (xy 97.982532 -281.617927)
			(xy 97.974426 -281.669104) (xy 97.958414 -281.718383) (xy 97.934891 -281.76455) (xy 97.904435 -281.806469)
			(xy 97.867797 -281.843107) (xy 97.825878 -281.873563) (xy 97.779711 -281.897086) (xy 97.730432 -281.913098)
			(xy 97.679255 -281.921204) (xy 97.627441 -281.921204) (xy 97.576264 -281.913098) (xy 97.526985 -281.897086)
			(xy 97.480818 -281.873563) (xy 97.438899 -281.843107) (xy 97.402261 -281.806469) (xy 97.371805 -281.76455)
			(xy 97.348282 -281.718383) (xy 97.33227 -281.669104) (xy 97.324164 -281.617927) (xy 97.323656 -281.59202)
			(xy 96.10344 -281.59202) (xy 96.103032 -281.617397) (xy 96.095259 -281.667553) (xy 96.079885 -281.715923)
			(xy 96.057273 -281.761362) (xy 96.027958 -281.802795) (xy 95.992635 -281.839241) (xy 95.95214 -281.869837)
			(xy 95.907431 -281.89386) (xy 95.859566 -281.910741) (xy 95.834708 -281.91587) (xy 95.811848 -281.920188)
			(xy 95.60687 -282.275026) (xy 95.614744 -282.297124) (xy 95.623311 -282.32348) (xy 95.632506 -282.378127)
			(xy 95.633032 -282.405836) (xy 95.913956 -282.405836) (xy 95.914464 -282.379949) (xy 95.922563 -282.328811)
			(xy 95.938562 -282.279571) (xy 95.962068 -282.233439) (xy 95.9925 -282.191552) (xy 96.02911 -282.154942)
			(xy 96.070997 -282.12451) (xy 96.117129 -282.101004) (xy 96.166369 -282.085005) (xy 96.217507 -282.076906)
			(xy 96.269281 -282.076906) (xy 96.320419 -282.085005) (xy 96.369659 -282.101004) (xy 96.415791 -282.12451)
			(xy 96.457678 -282.154942) (xy 96.494288 -282.191552) (xy 96.52472 -282.233439) (xy 96.548226 -282.279571)
			(xy 96.564225 -282.328811) (xy 96.572324 -282.379949) (xy 96.572832 -282.405836) (xy 96.572316 -282.431704)
			(xy 96.854052 -282.431704) (xy 96.854052 -282.379896) (xy 96.862157 -282.328725) (xy 96.878166 -282.279453)
			(xy 96.901687 -282.233291) (xy 96.932138 -282.191377) (xy 96.968772 -282.154742) (xy 97.010686 -282.12429)
			(xy 97.056847 -282.100769) (xy 97.106119 -282.084758) (xy 97.15729 -282.076653) (xy 97.183194 -282.076144)
			(xy 97.208707 -282.076611) (xy 97.259122 -282.084472) (xy 97.307725 -282.100007) (xy 97.353354 -282.122845)
			(xy 97.394919 -282.152441) (xy 97.431427 -282.188087) (xy 97.4471 -282.208224) (xy 97.859088 -282.208224)
			(xy 97.874775 -282.188099) (xy 97.911281 -282.152454) (xy 97.952843 -282.122858) (xy 97.998469 -282.10002)
			(xy 98.047069 -282.084484) (xy 98.097483 -282.076622) (xy 98.122994 -282.076144) (xy 98.148907 -282.076553)
			(xy 98.200094 -282.08466) (xy 98.249383 -282.100674) (xy 98.295559 -282.124201) (xy 98.337487 -282.154663)
			(xy 98.374133 -282.191308) (xy 98.404596 -282.233235) (xy 98.428124 -282.279412) (xy 98.444139 -282.3287)
			(xy 98.452246 -282.379887) (xy 98.452246 -282.431713) (xy 98.444139 -282.4829) (xy 98.428124 -282.532188)
			(xy 98.404596 -282.578365) (xy 98.374133 -282.620292) (xy 98.337487 -282.656937) (xy 98.295559 -282.687399)
			(xy 98.249383 -282.710926) (xy 98.200094 -282.72694) (xy 98.148907 -282.735047) (xy 98.122994 -282.735528)
			(xy 98.097483 -282.735041) (xy 98.047069 -282.72718) (xy 97.998468 -282.711647) (xy 97.95284 -282.688813)
			(xy 97.911274 -282.659222) (xy 97.874762 -282.623582) (xy 97.859088 -282.603448) (xy 97.4471 -282.603448)
			(xy 97.43144 -282.623594) (xy 97.394926 -282.659235) (xy 97.353357 -282.688826) (xy 97.307726 -282.71166)
			(xy 97.259123 -282.727192) (xy 97.208707 -282.735052) (xy 97.183194 -282.735528) (xy 97.15729 -282.734947)
			(xy 97.106119 -282.726842) (xy 97.056847 -282.710831) (xy 97.010686 -282.68731) (xy 96.968772 -282.656858)
			(xy 96.932138 -282.620223) (xy 96.901687 -282.578309) (xy 96.878166 -282.532147) (xy 96.862157 -282.482875)
			(xy 96.854052 -282.431704) (xy 96.572316 -282.431704) (xy 96.572281 -282.43348) (xy 96.56309 -282.487998)
			(xy 96.554544 -282.514294) (xy 96.546924 -282.536392) (xy 96.752156 -282.891738) (xy 96.775016 -282.896056)
			(xy 96.799823 -282.901285) (xy 96.847599 -282.918232) (xy 96.892217 -282.942295) (xy 96.932623 -282.972907)
			(xy 96.967865 -283.009346) (xy 96.997111 -283.050752) (xy 97.019671 -283.096149) (xy 97.035013 -283.144464)
			(xy 97.042775 -283.194559) (xy 97.04324 -283.219906) (xy 99.203256 -283.219906) (xy 99.203737 -283.19456)
			(xy 99.21151 -283.144468) (xy 99.226857 -283.096156) (xy 99.249417 -283.050761) (xy 99.278659 -283.009354)
			(xy 99.313894 -282.97291) (xy 99.354291 -282.942288) (xy 99.398899 -282.918209) (xy 99.446666 -282.901241)
			(xy 99.47148 -282.896056) (xy 99.49434 -282.891738) (xy 99.699318 -282.5369) (xy 99.691698 -282.514802)
			(xy 99.683062 -282.488391) (xy 99.673735 -282.433617) (xy 99.673156 -282.405836) (xy 99.673664 -282.379949)
			(xy 99.681763 -282.328811) (xy 99.697762 -282.279571) (xy 99.721268 -282.233439) (xy 99.7517 -282.191552)
			(xy 99.78831 -282.154942) (xy 99.830197 -282.12451) (xy 99.876329 -282.101004) (xy 99.925569 -282.085005)
			(xy 99.976707 -282.076906) (xy 100.028481 -282.076906) (xy 100.079619 -282.085005) (xy 100.128859 -282.101004)
			(xy 100.174991 -282.12451) (xy 100.216878 -282.154942) (xy 100.253488 -282.191552) (xy 100.28392 -282.233439)
			(xy 100.307426 -282.279571) (xy 100.323425 -282.328811) (xy 100.331524 -282.379949) (xy 100.332032 -282.405836)
			(xy 101.552756 -282.405836) (xy 101.553216 -282.380501) (xy 101.560977 -282.33043) (xy 101.576305 -282.282135)
			(xy 101.598841 -282.236753) (xy 101.628054 -282.195352) (xy 101.663256 -282.158908) (xy 101.703619 -282.128277)
			(xy 101.748192 -282.104181) (xy 101.795927 -282.087187) (xy 101.820726 -282.081986) (xy 101.843586 -282.077668)
			(xy 102.048818 -281.722322) (xy 102.041198 -281.700478) (xy 102.03257 -281.674197) (xy 102.023258 -281.619675)
			(xy 102.022656 -281.59202) (xy 102.023164 -281.566113) (xy 102.03127 -281.514936) (xy 102.047282 -281.465657)
			(xy 102.070805 -281.41949) (xy 102.101261 -281.377571) (xy 102.137899 -281.340933) (xy 102.179818 -281.310477)
			(xy 102.225985 -281.286954) (xy 102.275264 -281.270942) (xy 102.326441 -281.262836) (xy 102.378255 -281.262836)
			(xy 102.429432 -281.270942) (xy 102.478711 -281.286954) (xy 102.524878 -281.310477) (xy 102.566797 -281.340933)
			(xy 102.603435 -281.377571) (xy 102.633891 -281.41949) (xy 102.657414 -281.465657) (xy 102.673426 -281.514936)
			(xy 102.681532 -281.566113) (xy 102.68204 -281.59202) (xy 102.681632 -281.617397) (xy 102.673859 -281.667553)
			(xy 102.658485 -281.715923) (xy 102.635873 -281.761362) (xy 102.606558 -281.802795) (xy 102.571235 -281.839241)
			(xy 102.53074 -281.869837) (xy 102.486031 -281.89386) (xy 102.438166 -281.910741) (xy 102.413308 -281.91587)
			(xy 102.390448 -281.920188) (xy 102.18547 -282.275026) (xy 102.193344 -282.297124) (xy 102.201911 -282.32348)
			(xy 102.211106 -282.378127) (xy 102.211632 -282.405836) (xy 102.211124 -282.431704) (xy 103.432652 -282.431704)
			(xy 103.432652 -282.379896) (xy 103.440757 -282.328725) (xy 103.456766 -282.279453) (xy 103.480287 -282.233291)
			(xy 103.510738 -282.191377) (xy 103.547372 -282.154742) (xy 103.589286 -282.12429) (xy 103.635447 -282.100769)
			(xy 103.684719 -282.084758) (xy 103.73589 -282.076653) (xy 103.761794 -282.076144) (xy 103.787307 -282.076611)
			(xy 103.837722 -282.084472) (xy 103.886325 -282.100007) (xy 103.931954 -282.122845) (xy 103.973519 -282.152441)
			(xy 104.010027 -282.188087) (xy 104.0257 -282.208224) (xy 104.437688 -282.208224) (xy 104.453375 -282.188099)
			(xy 104.489881 -282.152454) (xy 104.531443 -282.122858) (xy 104.577069 -282.10002) (xy 104.625669 -282.084484)
			(xy 104.676083 -282.076622) (xy 104.701594 -282.076144) (xy 104.727507 -282.076553) (xy 104.778694 -282.08466)
			(xy 104.827983 -282.100674) (xy 104.874159 -282.124201) (xy 104.916087 -282.154663) (xy 104.952733 -282.191308)
			(xy 104.983196 -282.233235) (xy 105.006724 -282.279412) (xy 105.022739 -282.3287) (xy 105.030846 -282.379887)
			(xy 105.030846 -282.431713) (xy 105.022739 -282.4829) (xy 105.006724 -282.532188) (xy 104.983196 -282.578365)
			(xy 104.952733 -282.620292) (xy 104.916087 -282.656937) (xy 104.874159 -282.687399) (xy 104.827983 -282.710926)
			(xy 104.778694 -282.72694) (xy 104.727507 -282.735047) (xy 104.701594 -282.735528) (xy 104.676083 -282.735041)
			(xy 104.625669 -282.72718) (xy 104.577068 -282.711647) (xy 104.53144 -282.688813) (xy 104.489874 -282.659222)
			(xy 104.453362 -282.623582) (xy 104.437688 -282.603448) (xy 104.0257 -282.603448) (xy 104.01004 -282.623594)
			(xy 103.973526 -282.659235) (xy 103.931957 -282.688826) (xy 103.886326 -282.71166) (xy 103.837723 -282.727192)
			(xy 103.787307 -282.735052) (xy 103.761794 -282.735528) (xy 103.73589 -282.734947) (xy 103.684719 -282.726842)
			(xy 103.635447 -282.710831) (xy 103.589286 -282.68731) (xy 103.547372 -282.656858) (xy 103.510738 -282.620223)
			(xy 103.480287 -282.578309) (xy 103.456766 -282.532147) (xy 103.440757 -282.482875) (xy 103.432652 -282.431704)
			(xy 102.211124 -282.431704) (xy 102.211124 -282.431723) (xy 102.203025 -282.482861) (xy 102.187026 -282.532101)
			(xy 102.16352 -282.578233) (xy 102.133088 -282.62012) (xy 102.096478 -282.65673) (xy 102.054591 -282.687162)
			(xy 102.008459 -282.710668) (xy 101.959219 -282.726667) (xy 101.908081 -282.734766) (xy 101.856307 -282.734766)
			(xy 101.805169 -282.726667) (xy 101.755929 -282.710668) (xy 101.709797 -282.687162) (xy 101.66791 -282.65673)
			(xy 101.6313 -282.62012) (xy 101.600868 -282.578233) (xy 101.577362 -282.532101) (xy 101.561363 -282.482861)
			(xy 101.553264 -282.431723) (xy 101.552756 -282.405836) (xy 100.332032 -282.405836) (xy 100.331594 -282.431161)
			(xy 100.323857 -282.481217) (xy 100.308554 -282.5295) (xy 100.286046 -282.574874) (xy 100.256862 -282.616272)
			(xy 100.22169 -282.652718) (xy 100.181356 -282.683356) (xy 100.136812 -282.707464) (xy 100.089103 -282.724474)
			(xy 100.064316 -282.729686) (xy 100.041456 -282.734004) (xy 99.836224 -283.089096) (xy 99.844098 -283.111194)
			(xy 99.852735 -283.137539) (xy 99.862052 -283.192188) (xy 99.86264 -283.219906) (xy 99.862132 -283.245791)
			(xy 101.083549 -283.245791) (xy 101.083549 -283.194009) (xy 101.091651 -283.142863) (xy 101.107654 -283.093616)
			(xy 101.131165 -283.047478) (xy 101.161604 -283.005586) (xy 101.198223 -282.968973) (xy 101.240119 -282.93854)
			(xy 101.28626 -282.915036) (xy 101.33551 -282.89904) (xy 101.386657 -282.890946) (xy 101.412548 -282.890468)
			(xy 101.43806 -282.890926) (xy 101.488475 -282.898793) (xy 101.537077 -282.914332) (xy 101.582705 -282.937172)
			(xy 101.62427 -282.966767) (xy 101.66078 -283.002412) (xy 101.676454 -283.022548) (xy 102.088442 -283.022548)
			(xy 102.104077 -283.002381) (xy 102.140596 -282.966741) (xy 102.18217 -282.937153) (xy 102.227806 -282.914323)
			(xy 102.276414 -282.898795) (xy 102.326834 -282.890941) (xy 102.352348 -282.890468) (xy 102.378233 -282.890967)
			(xy 102.429366 -282.899073) (xy 102.478601 -282.915077) (xy 102.524727 -282.938585) (xy 102.566608 -282.969019)
			(xy 102.603213 -283.005629) (xy 102.63364 -283.047514) (xy 102.657142 -283.093643) (xy 102.673139 -283.142881)
			(xy 102.681237 -283.194015) (xy 102.681237 -283.245785) (xy 102.673139 -283.296919) (xy 102.657142 -283.346157)
			(xy 102.63364 -283.392286) (xy 102.603213 -283.434171) (xy 102.566608 -283.470781) (xy 102.524727 -283.501215)
			(xy 102.478601 -283.524723) (xy 102.429366 -283.540727) (xy 102.378233 -283.548833) (xy 102.352348 -283.549344)
			(xy 102.326836 -283.548851) (xy 102.276422 -283.540996) (xy 102.227819 -283.525467) (xy 102.18219 -283.502633)
			(xy 102.140624 -283.473042) (xy 102.104115 -283.437399) (xy 102.088442 -283.417264) (xy 101.676454 -283.417264)
			(xy 101.660739 -283.437366) (xy 101.624239 -283.473014) (xy 101.582683 -283.502612) (xy 101.537062 -283.525454)
			(xy 101.488467 -283.540995) (xy 101.438058 -283.548863) (xy 101.412548 -283.549344) (xy 101.386657 -283.548854)
			(xy 101.33551 -283.54076) (xy 101.28626 -283.524764) (xy 101.240119 -283.50126) (xy 101.198223 -283.470827)
			(xy 101.161604 -283.434214) (xy 101.131165 -283.392322) (xy 101.107654 -283.346184) (xy 101.091651 -283.296937)
			(xy 101.083549 -283.245791) (xy 99.862132 -283.245791) (xy 99.862132 -283.245813) (xy 99.854026 -283.29699)
			(xy 99.838014 -283.346269) (xy 99.814491 -283.392436) (xy 99.784035 -283.434355) (xy 99.747397 -283.470993)
			(xy 99.705478 -283.501449) (xy 99.659311 -283.524972) (xy 99.610032 -283.540984) (xy 99.558855 -283.54909)
			(xy 99.507041 -283.54909) (xy 99.455864 -283.540984) (xy 99.406585 -283.524972) (xy 99.360418 -283.501449)
			(xy 99.318499 -283.470993) (xy 99.281861 -283.434355) (xy 99.251405 -283.392436) (xy 99.227882 -283.346269)
			(xy 99.21187 -283.29699) (xy 99.203764 -283.245813) (xy 99.203256 -283.219906) (xy 97.04324 -283.219906)
			(xy 97.042732 -283.245813) (xy 97.034626 -283.29699) (xy 97.018614 -283.346269) (xy 96.995091 -283.392436)
			(xy 96.964635 -283.434355) (xy 96.927997 -283.470993) (xy 96.886078 -283.501449) (xy 96.839911 -283.524972)
			(xy 96.790632 -283.540984) (xy 96.739455 -283.54909) (xy 96.687641 -283.54909) (xy 96.636464 -283.540984)
			(xy 96.587185 -283.524972) (xy 96.541018 -283.501449) (xy 96.499099 -283.470993) (xy 96.462461 -283.434355)
			(xy 96.432005 -283.392436) (xy 96.408482 -283.346269) (xy 96.39247 -283.29699) (xy 96.384364 -283.245813)
			(xy 96.383856 -283.219906) (xy 96.384448 -283.192189) (xy 96.393773 -283.137542) (xy 96.402398 -283.111194)
			(xy 96.410272 -283.089096) (xy 96.205294 -282.734004) (xy 96.18218 -282.729686) (xy 96.15736 -282.724514)
			(xy 96.109579 -282.707563) (xy 96.064958 -282.683494) (xy 96.024551 -282.652875) (xy 95.989309 -282.616428)
			(xy 95.960065 -282.575014) (xy 95.937508 -282.52961) (xy 95.922171 -282.481287) (xy 95.914416 -282.431185)
			(xy 95.913956 -282.405836) (xy 95.633032 -282.405836) (xy 95.632524 -282.431723) (xy 95.624425 -282.482861)
			(xy 95.608426 -282.532101) (xy 95.58492 -282.578233) (xy 95.554488 -282.62012) (xy 95.517878 -282.65673)
			(xy 95.475991 -282.687162) (xy 95.429859 -282.710668) (xy 95.380619 -282.726667) (xy 95.329481 -282.734766)
			(xy 95.277707 -282.734766) (xy 95.226569 -282.726667) (xy 95.177329 -282.710668) (xy 95.131197 -282.687162)
			(xy 95.08931 -282.65673) (xy 95.0527 -282.62012) (xy 95.022268 -282.578233) (xy 94.998762 -282.532101)
			(xy 94.982763 -282.482861) (xy 94.974664 -282.431723) (xy 94.974156 -282.405836) (xy 93.75394 -282.405836)
			(xy 93.753432 -282.431743) (xy 93.745326 -282.48292) (xy 93.729314 -282.532199) (xy 93.705791 -282.578366)
			(xy 93.675335 -282.620285) (xy 93.638697 -282.656923) (xy 93.596778 -282.687379) (xy 93.550611 -282.710902)
			(xy 93.501332 -282.726914) (xy 93.450155 -282.73502) (xy 93.398341 -282.73502) (xy 93.347164 -282.726914)
			(xy 93.297885 -282.710902) (xy 93.251718 -282.687379) (xy 93.209799 -282.656923) (xy 93.173161 -282.620285)
			(xy 93.142705 -282.578366) (xy 93.119182 -282.532199) (xy 93.10317 -282.48292) (xy 93.095064 -282.431743)
			(xy 93.094556 -282.405836) (xy 91.87434 -282.405836) (xy 91.873903 -282.431201) (xy 91.86615 -282.481333)
			(xy 91.850801 -282.529685) (xy 91.828221 -282.575111) (xy 91.798942 -282.616537) (xy 91.763657 -282.652984)
			(xy 91.723202 -282.683591) (xy 91.678531 -282.707632) (xy 91.630703 -282.724539) (xy 91.605862 -282.729686)
			(xy 91.583002 -282.734004) (xy 91.378024 -283.089096) (xy 91.385644 -283.11094) (xy 91.394193 -283.137235)
			(xy 91.40339 -283.191753) (xy 91.403932 -283.219398) (xy 91.403932 -283.219906) (xy 91.403424 -283.245787)
			(xy 92.625176 -283.245787) (xy 92.625176 -283.194013) (xy 92.633275 -283.142878) (xy 92.649273 -283.093638)
			(xy 92.672778 -283.047508) (xy 92.703209 -283.005622) (xy 92.739818 -282.969013) (xy 92.781703 -282.938581)
			(xy 92.827833 -282.915076) (xy 92.877072 -282.899076) (xy 92.928207 -282.890976) (xy 92.954094 -282.890468)
			(xy 92.979605 -282.890965) (xy 93.030018 -282.898824) (xy 93.078619 -282.914355) (xy 93.124247 -282.937187)
			(xy 93.165813 -282.966776) (xy 93.202325 -283.002415) (xy 93.218 -283.022548) (xy 93.629988 -283.022548)
			(xy 93.645654 -283.002407) (xy 93.682167 -282.966766) (xy 93.723734 -282.937174) (xy 93.769364 -282.91434)
			(xy 93.817967 -282.898806) (xy 93.868382 -282.890945) (xy 93.893894 -282.890468) (xy 93.919784 -282.890937)
			(xy 93.970927 -282.899036) (xy 94.020174 -282.915037) (xy 94.066311 -282.938544) (xy 94.108202 -282.968979)
			(xy 94.144817 -283.005593) (xy 94.175253 -283.047484) (xy 94.198761 -283.093621) (xy 94.214762 -283.142867)
			(xy 94.222863 -283.19401) (xy 94.222863 -283.24579) (xy 94.214762 -283.296933) (xy 94.198761 -283.346179)
			(xy 94.175253 -283.392316) (xy 94.144817 -283.434207) (xy 94.108202 -283.470821) (xy 94.066311 -283.501256)
			(xy 94.020174 -283.524763) (xy 93.970927 -283.540764) (xy 93.919784 -283.548863) (xy 93.893894 -283.549344)
			(xy 93.868381 -283.54889) (xy 93.817964 -283.541027) (xy 93.769361 -283.52549) (xy 93.723732 -283.502649)
			(xy 93.682168 -283.473051) (xy 93.64566 -283.437402) (xy 93.629988 -283.417264) (xy 93.218 -283.417264)
			(xy 93.202317 -283.437392) (xy 93.16581 -283.473038) (xy 93.124247 -283.502633) (xy 93.078621 -283.525471)
			(xy 93.03002 -283.541006) (xy 92.979606 -283.548867) (xy 92.954094 -283.549344) (xy 92.928207 -283.548824)
			(xy 92.877072 -283.540724) (xy 92.827833 -283.524724) (xy 92.781703 -283.501219) (xy 92.739818 -283.470787)
			(xy 92.703209 -283.434178) (xy 92.672778 -283.392292) (xy 92.649273 -283.346162) (xy 92.633275 -283.296922)
			(xy 92.625176 -283.245787) (xy 91.403424 -283.245787) (xy 91.403424 -283.245793) (xy 91.395325 -283.296931)
			(xy 91.379326 -283.346171) (xy 91.35582 -283.392303) (xy 91.325388 -283.43419) (xy 91.288778 -283.4708)
			(xy 91.246891 -283.501232) (xy 91.200759 -283.524738) (xy 91.151519 -283.540737) (xy 91.100381 -283.548836)
			(xy 91.048607 -283.548836) (xy 90.997469 -283.540737) (xy 90.948229 -283.524738) (xy 90.902097 -283.501232)
			(xy 90.86021 -283.4708) (xy 90.8236 -283.43419) (xy 90.793168 -283.392303) (xy 90.769662 -283.346171)
			(xy 90.753663 -283.296931) (xy 90.745564 -283.245793) (xy 90.745056 -283.219906) (xy 88.584532 -283.219906)
			(xy 88.584024 -283.245793) (xy 88.575925 -283.296931) (xy 88.559926 -283.346171) (xy 88.53642 -283.392303)
			(xy 88.505988 -283.43419) (xy 88.469378 -283.4708) (xy 88.427491 -283.501232) (xy 88.381359 -283.524738)
			(xy 88.332119 -283.540737) (xy 88.280981 -283.548836) (xy 88.229207 -283.548836) (xy 88.178069 -283.540737)
			(xy 88.128829 -283.524738) (xy 88.082697 -283.501232) (xy 88.04081 -283.4708) (xy 88.0042 -283.43419)
			(xy 87.973768 -283.392303) (xy 87.950262 -283.346171) (xy 87.934263 -283.296931) (xy 87.926164 -283.245793)
			(xy 87.925656 -283.219906) (xy 87.926189 -283.192198) (xy 87.935382 -283.137551) (xy 87.943944 -283.111194)
			(xy 87.951818 -283.089096) (xy 87.746586 -282.734004) (xy 87.723726 -282.729686) (xy 87.698938 -282.724431)
			(xy 87.651203 -282.70745) (xy 87.606628 -282.683364) (xy 87.566263 -282.652742) (xy 87.531059 -282.616304)
			(xy 87.501844 -282.574908) (xy 87.479308 -282.52953) (xy 87.463981 -282.481238) (xy 87.456223 -282.431169)
			(xy 87.455756 -282.405836) (xy 87.17534 -282.405836) (xy 87.174832 -282.431743) (xy 87.166726 -282.48292)
			(xy 87.150714 -282.532199) (xy 87.127191 -282.578366) (xy 87.096735 -282.620285) (xy 87.060097 -282.656923)
			(xy 87.018178 -282.687379) (xy 86.972011 -282.710902) (xy 86.922732 -282.726914) (xy 86.871555 -282.73502)
			(xy 86.819741 -282.73502) (xy 86.768564 -282.726914) (xy 86.719285 -282.710902) (xy 86.673118 -282.687379)
			(xy 86.631199 -282.656923) (xy 86.594561 -282.620285) (xy 86.564105 -282.578366) (xy 86.540582 -282.532199)
			(xy 86.52457 -282.48292) (xy 86.516464 -282.431743) (xy 86.515956 -282.405836) (xy 31.743142 -282.405836)
			(xy 31.743142 -284.033722) (xy 86.515956 -284.033722) (xy 86.516464 -284.007815) (xy 86.52457 -283.956638)
			(xy 86.540582 -283.907359) (xy 86.564105 -283.861192) (xy 86.594561 -283.819273) (xy 86.631199 -283.782635)
			(xy 86.673118 -283.752179) (xy 86.719285 -283.728656) (xy 86.768564 -283.712644) (xy 86.819741 -283.704538)
			(xy 86.871555 -283.704538) (xy 86.922732 -283.712644) (xy 86.972011 -283.728656) (xy 87.018178 -283.752179)
			(xy 87.060097 -283.782635) (xy 87.096735 -283.819273) (xy 87.127191 -283.861192) (xy 87.150714 -283.907359)
			(xy 87.166726 -283.956638) (xy 87.174832 -284.007815) (xy 87.17534 -284.033722) (xy 87.174755 -284.06144)
			(xy 87.165426 -284.116086) (xy 87.156798 -284.142434) (xy 87.148924 -284.164532) (xy 87.353902 -284.51937)
			(xy 87.376762 -284.523688) (xy 87.401564 -284.528882) (xy 87.449305 -284.545867) (xy 87.493884 -284.569958)
			(xy 87.534252 -284.600587) (xy 87.569457 -284.637033) (xy 87.598669 -284.678438) (xy 87.621201 -284.723825)
			(xy 87.636522 -284.772125) (xy 87.644271 -284.822202) (xy 87.644732 -284.847538) (xy 87.644224 -284.873425)
			(xy 87.636125 -284.924563) (xy 87.620126 -284.973803) (xy 87.59662 -285.019935) (xy 87.566188 -285.061822)
			(xy 87.529578 -285.098432) (xy 87.487691 -285.128864) (xy 87.441559 -285.15237) (xy 87.392319 -285.168369)
			(xy 87.341181 -285.176468) (xy 87.289407 -285.176468) (xy 87.238269 -285.168369) (xy 87.189029 -285.15237)
			(xy 87.142897 -285.128864) (xy 87.10101 -285.098432) (xy 87.0644 -285.061822) (xy 87.033968 -285.019935)
			(xy 87.010462 -284.973803) (xy 86.994463 -284.924563) (xy 86.986364 -284.873425) (xy 86.985856 -284.847538)
			(xy 86.986397 -284.81983) (xy 86.995584 -284.765184) (xy 87.004144 -284.738826) (xy 87.012018 -284.716728)
			(xy 86.80704 -284.36189) (xy 86.78418 -284.357572) (xy 86.759356 -284.352414) (xy 86.711575 -284.335461)
			(xy 86.666954 -284.311391) (xy 86.626545 -284.28077) (xy 86.591303 -284.244322) (xy 86.56206 -284.202906)
			(xy 86.539504 -284.1575) (xy 86.524169 -284.109175) (xy 86.516415 -284.059072) (xy 86.515956 -284.033722)
			(xy 31.743142 -284.033722) (xy 31.743142 -284.873384) (xy 85.106807 -284.873384) (xy 85.106807 -284.821616)
			(xy 85.114906 -284.770485) (xy 85.130903 -284.72125) (xy 85.154405 -284.675125) (xy 85.184833 -284.633243)
			(xy 85.221438 -284.596637) (xy 85.263319 -284.566208) (xy 85.309445 -284.542705) (xy 85.358679 -284.526707)
			(xy 85.40981 -284.518608) (xy 85.435694 -284.5181) (xy 85.461187 -284.518588) (xy 85.511565 -284.526449)
			(xy 85.560127 -284.541983) (xy 85.605714 -284.564818) (xy 85.647235 -284.594409) (xy 85.683698 -284.630049)
			(xy 85.699346 -284.65018) (xy 86.111842 -284.65018) (xy 86.127489 -284.630047) (xy 86.163951 -284.594407)
			(xy 86.205472 -284.564814) (xy 86.251059 -284.541976) (xy 86.299622 -284.526441) (xy 86.35 -284.518579)
			(xy 86.375494 -284.5181) (xy 86.401387 -284.518505) (xy 86.452535 -284.526605) (xy 86.501786 -284.542607)
			(xy 86.547927 -284.566116) (xy 86.589823 -284.596555) (xy 86.626441 -284.633172) (xy 86.65688 -284.675067)
			(xy 86.680391 -284.721208) (xy 86.696394 -284.770459) (xy 86.704495 -284.821607) (xy 86.704495 -284.873393)
			(xy 86.696394 -284.924541) (xy 86.680391 -284.973792) (xy 86.65688 -285.019933) (xy 86.626441 -285.061828)
			(xy 86.589823 -285.098445) (xy 86.547927 -285.128884) (xy 86.501786 -285.152393) (xy 86.452535 -285.168395)
			(xy 86.401387 -285.176495) (xy 86.375494 -285.176976) (xy 86.35 -285.176506) (xy 86.299621 -285.168643)
			(xy 86.251058 -285.153106) (xy 86.205471 -285.130267) (xy 86.16395 -285.100672) (xy 86.127489 -285.065029)
			(xy 86.111842 -285.044896) (xy 85.699346 -285.044896) (xy 85.683699 -285.065029) (xy 85.647238 -285.100671)
			(xy 85.605717 -285.130265) (xy 85.56013 -285.153102) (xy 85.511566 -285.168637) (xy 85.461188 -285.176498)
			(xy 85.435694 -285.176976) (xy 85.40981 -285.176392) (xy 85.358679 -285.168293) (xy 85.309445 -285.152295)
			(xy 85.263319 -285.128792) (xy 85.221438 -285.098363) (xy 85.184833 -285.061757) (xy 85.154405 -285.019875)
			(xy 85.130903 -284.97375) (xy 85.114906 -284.924515) (xy 85.106807 -284.873384) (xy 31.743142 -284.873384)
			(xy 31.743142 -285.661354) (xy 87.455756 -285.661354) (xy 87.456232 -285.63602) (xy 87.46399 -285.585949)
			(xy 87.479317 -285.537654) (xy 87.50185 -285.492273) (xy 87.531061 -285.450872) (xy 87.566261 -285.414427)
			(xy 87.606622 -285.383796) (xy 87.651194 -285.3597) (xy 87.698927 -285.342705) (xy 87.723726 -285.337504)
			(xy 87.746586 -285.333186) (xy 87.951564 -284.978094) (xy 87.943944 -284.95625) (xy 87.935376 -284.929894)
			(xy 87.926181 -284.875247) (xy 87.925656 -284.847538) (xy 87.926164 -284.821651) (xy 87.934263 -284.770513)
			(xy 87.950262 -284.721273) (xy 87.973768 -284.675141) (xy 88.0042 -284.633254) (xy 88.04081 -284.596644)
			(xy 88.082697 -284.566212) (xy 88.128829 -284.542706) (xy 88.178069 -284.526707) (xy 88.229207 -284.518608)
			(xy 88.280981 -284.518608) (xy 88.332119 -284.526707) (xy 88.381359 -284.542706) (xy 88.427491 -284.566212)
			(xy 88.469378 -284.596644) (xy 88.505988 -284.633254) (xy 88.53642 -284.675141) (xy 88.559926 -284.721273)
			(xy 88.575925 -284.770513) (xy 88.584024 -284.821651) (xy 88.584532 -284.847538) (xy 88.584058 -284.872872)
			(xy 88.576301 -284.922944) (xy 88.560975 -284.971239) (xy 88.538441 -285.016622) (xy 88.50923 -285.058022)
			(xy 88.47403 -285.094467) (xy 88.433668 -285.125098) (xy 88.389095 -285.149194) (xy 88.341361 -285.166187)
			(xy 88.316562 -285.171388) (xy 88.293702 -285.175706) (xy 88.088724 -285.530798) (xy 88.096344 -285.552642)
			(xy 88.104909 -285.578999) (xy 88.114106 -285.633646) (xy 88.114632 -285.661354) (xy 89.335356 -285.661354)
			(xy 89.335864 -285.635467) (xy 89.343963 -285.584329) (xy 89.359962 -285.535089) (xy 89.383468 -285.488957)
			(xy 89.4139 -285.44707) (xy 89.45051 -285.41046) (xy 89.492397 -285.380028) (xy 89.538529 -285.356522)
			(xy 89.587769 -285.340523) (xy 89.638907 -285.332424) (xy 89.690681 -285.332424) (xy 89.741819 -285.340523)
			(xy 89.791059 -285.356522) (xy 89.837191 -285.380028) (xy 89.879078 -285.41046) (xy 89.915688 -285.44707)
			(xy 89.94612 -285.488957) (xy 89.969626 -285.535089) (xy 89.985625 -285.584329) (xy 89.993724 -285.635467)
			(xy 89.994232 -285.661354) (xy 90.275156 -285.661354) (xy 90.27559 -285.636007) (xy 90.28337 -285.585913)
			(xy 90.298725 -285.537599) (xy 90.321292 -285.492204) (xy 90.35054 -285.450798) (xy 90.385779 -285.414354)
			(xy 90.426181 -285.383733) (xy 90.470793 -285.359656) (xy 90.518564 -285.342688) (xy 90.54338 -285.337504)
			(xy 90.56624 -285.333186) (xy 90.771218 -284.978348) (xy 90.763344 -284.956504) (xy 90.754767 -284.930085)
			(xy 90.745569 -284.87531) (xy 90.745056 -284.847538) (xy 90.745564 -284.821651) (xy 90.753663 -284.770513)
			(xy 90.769662 -284.721273) (xy 90.793168 -284.675141) (xy 90.8236 -284.633254) (xy 90.86021 -284.596644)
			(xy 90.902097 -284.566212) (xy 90.948229 -284.542706) (xy 90.997469 -284.526707) (xy 91.048607 -284.518608)
			(xy 91.100381 -284.518608) (xy 91.151519 -284.526707) (xy 91.200759 -284.542706) (xy 91.246891 -284.566212)
			(xy 91.288778 -284.596644) (xy 91.325388 -284.633254) (xy 91.35582 -284.675141) (xy 91.379326 -284.721273)
			(xy 91.395325 -284.770513) (xy 91.403424 -284.821651) (xy 91.403932 -284.847538) (xy 91.403458 -284.872872)
			(xy 91.395701 -284.922944) (xy 91.380375 -284.971239) (xy 91.357841 -285.016622) (xy 91.32863 -285.058022)
			(xy 91.29343 -285.094467) (xy 91.253068 -285.125098) (xy 91.208495 -285.149194) (xy 91.160761 -285.166187)
			(xy 91.135962 -285.171388) (xy 91.113102 -285.175706) (xy 90.908124 -285.530544) (xy 90.915998 -285.552642)
			(xy 90.924622 -285.57899) (xy 90.933948 -285.633636) (xy 90.93454 -285.661354) (xy 91.214956 -285.661354)
			(xy 91.215464 -285.635447) (xy 91.22357 -285.58427) (xy 91.239582 -285.534991) (xy 91.263105 -285.488824)
			(xy 91.293561 -285.446905) (xy 91.330199 -285.410267) (xy 91.372118 -285.379811) (xy 91.418285 -285.356288)
			(xy 91.467564 -285.340276) (xy 91.518741 -285.33217) (xy 91.570555 -285.33217) (xy 91.621732 -285.340276)
			(xy 91.671011 -285.356288) (xy 91.717178 -285.379811) (xy 91.759097 -285.410267) (xy 91.795735 -285.446905)
			(xy 91.826191 -285.488824) (xy 91.849714 -285.534991) (xy 91.865726 -285.58427) (xy 91.873832 -285.635447)
			(xy 91.87434 -285.661354) (xy 92.154756 -285.661354) (xy 92.155232 -285.63602) (xy 92.16299 -285.585949)
			(xy 92.178317 -285.537654) (xy 92.20085 -285.492273) (xy 92.230061 -285.450872) (xy 92.265261 -285.414427)
			(xy 92.305622 -285.383796) (xy 92.350194 -285.3597) (xy 92.397927 -285.342705) (xy 92.422726 -285.337504)
			(xy 92.445586 -285.333186) (xy 92.650818 -284.97784) (xy 92.643198 -284.955996) (xy 92.634574 -284.929714)
			(xy 92.625259 -284.875193) (xy 92.624656 -284.847538) (xy 92.625164 -284.821631) (xy 92.63327 -284.770454)
			(xy 92.649282 -284.721175) (xy 92.672805 -284.675008) (xy 92.703261 -284.633089) (xy 92.739899 -284.596451)
			(xy 92.781818 -284.565995) (xy 92.827985 -284.542472) (xy 92.877264 -284.52646) (xy 92.928441 -284.518354)
			(xy 92.980255 -284.518354) (xy 93.031432 -284.52646) (xy 93.080711 -284.542472) (xy 93.126878 -284.565995)
			(xy 93.168797 -284.596451) (xy 93.205435 -284.633089) (xy 93.235891 -284.675008) (xy 93.259414 -284.721175)
			(xy 93.275426 -284.770454) (xy 93.283532 -284.821631) (xy 93.28404 -284.847538) (xy 93.283648 -284.872916)
			(xy 93.275873 -284.923072) (xy 93.260496 -284.971442) (xy 93.237881 -285.016882) (xy 93.208565 -285.058314)
			(xy 93.17324 -285.09476) (xy 93.132743 -285.125356) (xy 93.088033 -285.149379) (xy 93.040166 -285.166259)
			(xy 93.015308 -285.171388) (xy 92.992448 -285.175706) (xy 92.78747 -285.530544) (xy 92.795344 -285.552642)
			(xy 92.803916 -285.578997) (xy 92.813107 -285.633645) (xy 92.813632 -285.661354) (xy 93.094556 -285.661354)
			(xy 93.095064 -285.635467) (xy 93.103163 -285.584329) (xy 93.119162 -285.535089) (xy 93.142668 -285.488957)
			(xy 93.1731 -285.44707) (xy 93.20971 -285.41046) (xy 93.251597 -285.380028) (xy 93.297729 -285.356522)
			(xy 93.346969 -285.340523) (xy 93.398107 -285.332424) (xy 93.449881 -285.332424) (xy 93.501019 -285.340523)
			(xy 93.550259 -285.356522) (xy 93.596391 -285.380028) (xy 93.638278 -285.41046) (xy 93.674888 -285.44707)
			(xy 93.70532 -285.488957) (xy 93.728826 -285.535089) (xy 93.744825 -285.584329) (xy 93.752924 -285.635467)
			(xy 93.753432 -285.661354) (xy 94.034356 -285.661354) (xy 94.034832 -285.63602) (xy 94.04259 -285.585949)
			(xy 94.057917 -285.537654) (xy 94.08045 -285.492273) (xy 94.109661 -285.450872) (xy 94.144861 -285.414427)
			(xy 94.185222 -285.383796) (xy 94.229794 -285.3597) (xy 94.277527 -285.342705) (xy 94.302326 -285.337504)
			(xy 94.325186 -285.333186) (xy 94.530418 -284.97784) (xy 94.522798 -284.955996) (xy 94.514174 -284.929714)
			(xy 94.504859 -284.875193) (xy 94.504256 -284.847538) (xy 94.504764 -284.821631) (xy 94.51287 -284.770454)
			(xy 94.528882 -284.721175) (xy 94.552405 -284.675008) (xy 94.582861 -284.633089) (xy 94.619499 -284.596451)
			(xy 94.661418 -284.565995) (xy 94.707585 -284.542472) (xy 94.756864 -284.52646) (xy 94.808041 -284.518354)
			(xy 94.859855 -284.518354) (xy 94.911032 -284.52646) (xy 94.960311 -284.542472) (xy 95.006478 -284.565995)
			(xy 95.048397 -284.596451) (xy 95.085035 -284.633089) (xy 95.115491 -284.675008) (xy 95.139014 -284.721175)
			(xy 95.155026 -284.770454) (xy 95.163132 -284.821631) (xy 95.16364 -284.847538) (xy 95.163248 -284.872916)
			(xy 95.155473 -284.923072) (xy 95.140096 -284.971442) (xy 95.117481 -285.016882) (xy 95.088165 -285.058314)
			(xy 95.05284 -285.09476) (xy 95.012343 -285.125356) (xy 94.967633 -285.149379) (xy 94.919766 -285.166259)
			(xy 94.894908 -285.171388) (xy 94.872048 -285.175706) (xy 94.66707 -285.530544) (xy 94.674944 -285.552642)
			(xy 94.683516 -285.578997) (xy 94.692707 -285.633645) (xy 94.693232 -285.661354) (xy 94.974156 -285.661354)
			(xy 94.974664 -285.635467) (xy 94.982763 -285.584329) (xy 94.998762 -285.535089) (xy 95.022268 -285.488957)
			(xy 95.0527 -285.44707) (xy 95.08931 -285.41046) (xy 95.131197 -285.380028) (xy 95.177329 -285.356522)
			(xy 95.226569 -285.340523) (xy 95.277707 -285.332424) (xy 95.329481 -285.332424) (xy 95.380619 -285.340523)
			(xy 95.429859 -285.356522) (xy 95.475991 -285.380028) (xy 95.517878 -285.41046) (xy 95.554488 -285.44707)
			(xy 95.58492 -285.488957) (xy 95.608426 -285.535089) (xy 95.624425 -285.584329) (xy 95.632524 -285.635467)
			(xy 95.633032 -285.661354) (xy 95.913956 -285.661354) (xy 95.914432 -285.63602) (xy 95.92219 -285.585949)
			(xy 95.937517 -285.537654) (xy 95.96005 -285.492273) (xy 95.989261 -285.450872) (xy 96.024461 -285.414427)
			(xy 96.064822 -285.383796) (xy 96.109394 -285.3597) (xy 96.157127 -285.342705) (xy 96.181926 -285.337504)
			(xy 96.204786 -285.333186) (xy 96.410018 -284.97784) (xy 96.402398 -284.955996) (xy 96.393774 -284.929714)
			(xy 96.384459 -284.875193) (xy 96.383856 -284.847538) (xy 96.384364 -284.821631) (xy 96.39247 -284.770454)
			(xy 96.408482 -284.721175) (xy 96.432005 -284.675008) (xy 96.462461 -284.633089) (xy 96.499099 -284.596451)
			(xy 96.541018 -284.565995) (xy 96.587185 -284.542472) (xy 96.636464 -284.52646) (xy 96.687641 -284.518354)
			(xy 96.739455 -284.518354) (xy 96.790632 -284.52646) (xy 96.839911 -284.542472) (xy 96.886078 -284.565995)
			(xy 96.927997 -284.596451) (xy 96.964635 -284.633089) (xy 96.995091 -284.675008) (xy 97.018614 -284.721175)
			(xy 97.034626 -284.770454) (xy 97.042732 -284.821631) (xy 97.04324 -284.847538) (xy 97.042848 -284.872916)
			(xy 97.035073 -284.923072) (xy 97.019696 -284.971442) (xy 96.997081 -285.016882) (xy 96.967765 -285.058314)
			(xy 96.93244 -285.09476) (xy 96.891943 -285.125356) (xy 96.847233 -285.149379) (xy 96.799366 -285.166259)
			(xy 96.774508 -285.171388) (xy 96.751648 -285.175706) (xy 96.54667 -285.530544) (xy 96.554544 -285.552642)
			(xy 96.563116 -285.578997) (xy 96.572307 -285.633645) (xy 96.572832 -285.661354) (xy 96.853756 -285.661354)
			(xy 96.854264 -285.635467) (xy 96.862363 -285.584329) (xy 96.878362 -285.535089) (xy 96.901868 -285.488957)
			(xy 96.9323 -285.44707) (xy 96.96891 -285.41046) (xy 97.010797 -285.380028) (xy 97.056929 -285.356522)
			(xy 97.106169 -285.340523) (xy 97.157307 -285.332424) (xy 97.209081 -285.332424) (xy 97.260219 -285.340523)
			(xy 97.309459 -285.356522) (xy 97.355591 -285.380028) (xy 97.397478 -285.41046) (xy 97.434088 -285.44707)
			(xy 97.46452 -285.488957) (xy 97.488026 -285.535089) (xy 97.504025 -285.584329) (xy 97.512124 -285.635467)
			(xy 97.512632 -285.661354) (xy 97.793556 -285.661354) (xy 97.794032 -285.63602) (xy 97.80179 -285.585949)
			(xy 97.817117 -285.537654) (xy 97.83965 -285.492273) (xy 97.868861 -285.450872) (xy 97.904061 -285.414427)
			(xy 97.944422 -285.383796) (xy 97.988994 -285.3597) (xy 98.036727 -285.342705) (xy 98.061526 -285.337504)
			(xy 98.084386 -285.333186) (xy 98.289618 -284.97784) (xy 98.281998 -284.955996) (xy 98.273374 -284.929714)
			(xy 98.264059 -284.875193) (xy 98.263456 -284.847538) (xy 98.263964 -284.821631) (xy 98.27207 -284.770454)
			(xy 98.288082 -284.721175) (xy 98.311605 -284.675008) (xy 98.342061 -284.633089) (xy 98.378699 -284.596451)
			(xy 98.420618 -284.565995) (xy 98.466785 -284.542472) (xy 98.516064 -284.52646) (xy 98.567241 -284.518354)
			(xy 98.619055 -284.518354) (xy 98.670232 -284.52646) (xy 98.719511 -284.542472) (xy 98.765678 -284.565995)
			(xy 98.807597 -284.596451) (xy 98.844235 -284.633089) (xy 98.874691 -284.675008) (xy 98.898214 -284.721175)
			(xy 98.914226 -284.770454) (xy 98.922332 -284.821631) (xy 98.92284 -284.847538) (xy 98.922448 -284.872916)
			(xy 98.914673 -284.923072) (xy 98.899296 -284.971442) (xy 98.876681 -285.016882) (xy 98.847365 -285.058314)
			(xy 98.81204 -285.09476) (xy 98.771543 -285.125356) (xy 98.726833 -285.149379) (xy 98.678966 -285.166259)
			(xy 98.654108 -285.171388) (xy 98.631248 -285.175706) (xy 98.42627 -285.530544) (xy 98.434144 -285.552642)
			(xy 98.442716 -285.578997) (xy 98.451907 -285.633645) (xy 98.452432 -285.661354) (xy 98.733356 -285.661354)
			(xy 98.733864 -285.635467) (xy 98.741963 -285.584329) (xy 98.757962 -285.535089) (xy 98.781468 -285.488957)
			(xy 98.8119 -285.44707) (xy 98.84851 -285.41046) (xy 98.890397 -285.380028) (xy 98.936529 -285.356522)
			(xy 98.985769 -285.340523) (xy 99.036907 -285.332424) (xy 99.088681 -285.332424) (xy 99.139819 -285.340523)
			(xy 99.189059 -285.356522) (xy 99.235191 -285.380028) (xy 99.277078 -285.41046) (xy 99.313688 -285.44707)
			(xy 99.34412 -285.488957) (xy 99.367626 -285.535089) (xy 99.383625 -285.584329) (xy 99.391724 -285.635467)
			(xy 99.392232 -285.661354) (xy 99.673156 -285.661354) (xy 99.673632 -285.63602) (xy 99.68139 -285.585949)
			(xy 99.696717 -285.537654) (xy 99.71925 -285.492273) (xy 99.748461 -285.450872) (xy 99.783661 -285.414427)
			(xy 99.824022 -285.383796) (xy 99.868594 -285.3597) (xy 99.916327 -285.342705) (xy 99.941126 -285.337504)
			(xy 99.963986 -285.333186) (xy 100.169218 -284.97784) (xy 100.161598 -284.955996) (xy 100.152974 -284.929714)
			(xy 100.143659 -284.875193) (xy 100.143056 -284.847538) (xy 100.143564 -284.821631) (xy 100.15167 -284.770454)
			(xy 100.167682 -284.721175) (xy 100.191205 -284.675008) (xy 100.221661 -284.633089) (xy 100.258299 -284.596451)
			(xy 100.300218 -284.565995) (xy 100.346385 -284.542472) (xy 100.395664 -284.52646) (xy 100.446841 -284.518354)
			(xy 100.498655 -284.518354) (xy 100.549832 -284.52646) (xy 100.599111 -284.542472) (xy 100.645278 -284.565995)
			(xy 100.687197 -284.596451) (xy 100.723835 -284.633089) (xy 100.754291 -284.675008) (xy 100.777814 -284.721175)
			(xy 100.793826 -284.770454) (xy 100.801932 -284.821631) (xy 100.80244 -284.847538) (xy 100.802048 -284.872916)
			(xy 100.794273 -284.923072) (xy 100.778896 -284.971442) (xy 100.756281 -285.016882) (xy 100.726965 -285.058314)
			(xy 100.69164 -285.09476) (xy 100.651143 -285.125356) (xy 100.606433 -285.149379) (xy 100.558566 -285.166259)
			(xy 100.533708 -285.171388) (xy 100.510848 -285.175706) (xy 100.30587 -285.530544) (xy 100.313744 -285.552642)
			(xy 100.322316 -285.578997) (xy 100.331507 -285.633645) (xy 100.332032 -285.661354) (xy 100.612956 -285.661354)
			(xy 100.613464 -285.635467) (xy 100.621563 -285.584329) (xy 100.637562 -285.535089) (xy 100.661068 -285.488957)
			(xy 100.6915 -285.44707) (xy 100.72811 -285.41046) (xy 100.769997 -285.380028) (xy 100.816129 -285.356522)
			(xy 100.865369 -285.340523) (xy 100.916507 -285.332424) (xy 100.968281 -285.332424) (xy 101.019419 -285.340523)
			(xy 101.068659 -285.356522) (xy 101.114791 -285.380028) (xy 101.156678 -285.41046) (xy 101.193288 -285.44707)
			(xy 101.22372 -285.488957) (xy 101.247226 -285.535089) (xy 101.263225 -285.584329) (xy 101.271324 -285.635467)
			(xy 101.271832 -285.661354) (xy 101.552756 -285.661354) (xy 101.553232 -285.63602) (xy 101.56099 -285.585949)
			(xy 101.576317 -285.537654) (xy 101.59885 -285.492273) (xy 101.628061 -285.450872) (xy 101.663261 -285.414427)
			(xy 101.703622 -285.383796) (xy 101.748194 -285.3597) (xy 101.795927 -285.342705) (xy 101.820726 -285.337504)
			(xy 101.843586 -285.333186) (xy 102.048818 -284.97784) (xy 102.041198 -284.955996) (xy 102.032574 -284.929714)
			(xy 102.023259 -284.875193) (xy 102.022656 -284.847538) (xy 102.023164 -284.821631) (xy 102.03127 -284.770454)
			(xy 102.047282 -284.721175) (xy 102.070805 -284.675008) (xy 102.101261 -284.633089) (xy 102.137899 -284.596451)
			(xy 102.179818 -284.565995) (xy 102.225985 -284.542472) (xy 102.275264 -284.52646) (xy 102.326441 -284.518354)
			(xy 102.378255 -284.518354) (xy 102.429432 -284.52646) (xy 102.478711 -284.542472) (xy 102.524878 -284.565995)
			(xy 102.566797 -284.596451) (xy 102.603435 -284.633089) (xy 102.633891 -284.675008) (xy 102.657414 -284.721175)
			(xy 102.673426 -284.770454) (xy 102.681532 -284.821631) (xy 102.68204 -284.847538) (xy 102.681648 -284.872916)
			(xy 102.673873 -284.923072) (xy 102.658496 -284.971442) (xy 102.635881 -285.016882) (xy 102.606565 -285.058314)
			(xy 102.57124 -285.09476) (xy 102.530743 -285.125356) (xy 102.486033 -285.149379) (xy 102.438166 -285.166259)
			(xy 102.413308 -285.171388) (xy 102.390448 -285.175706) (xy 102.18547 -285.530544) (xy 102.193344 -285.552642)
			(xy 102.201916 -285.578997) (xy 102.211107 -285.633645) (xy 102.211632 -285.661354) (xy 102.492556 -285.661354)
			(xy 102.493064 -285.635467) (xy 102.501163 -285.584329) (xy 102.517162 -285.535089) (xy 102.540668 -285.488957)
			(xy 102.5711 -285.44707) (xy 102.60771 -285.41046) (xy 102.649597 -285.380028) (xy 102.695729 -285.356522)
			(xy 102.744969 -285.340523) (xy 102.796107 -285.332424) (xy 102.847881 -285.332424) (xy 102.899019 -285.340523)
			(xy 102.948259 -285.356522) (xy 102.994391 -285.380028) (xy 103.036278 -285.41046) (xy 103.072888 -285.44707)
			(xy 103.10332 -285.488957) (xy 103.126826 -285.535089) (xy 103.142825 -285.584329) (xy 103.150924 -285.635467)
			(xy 103.151432 -285.661354) (xy 103.150885 -285.688998) (xy 103.141691 -285.743516) (xy 103.133144 -285.769812)
			(xy 103.125524 -285.79191) (xy 103.330756 -286.147256) (xy 103.353616 -286.151574) (xy 103.378427 -286.156786)
			(xy 103.426204 -286.173734) (xy 103.470823 -286.197799) (xy 103.51123 -286.228413) (xy 103.546472 -286.264855)
			(xy 103.575717 -286.306263) (xy 103.598276 -286.351662) (xy 103.613617 -286.399979) (xy 103.621377 -286.450077)
			(xy 103.62184 -286.475424) (xy 103.621332 -286.501331) (xy 103.613226 -286.552508) (xy 103.597214 -286.601787)
			(xy 103.573691 -286.647954) (xy 103.543235 -286.689873) (xy 103.506597 -286.726511) (xy 103.464678 -286.756967)
			(xy 103.418511 -286.78049) (xy 103.369232 -286.796502) (xy 103.318055 -286.804608) (xy 103.266241 -286.804608)
			(xy 103.215064 -286.796502) (xy 103.165785 -286.78049) (xy 103.119618 -286.756967) (xy 103.077699 -286.726511)
			(xy 103.041061 -286.689873) (xy 103.010605 -286.647954) (xy 102.987082 -286.601787) (xy 102.97107 -286.552508)
			(xy 102.962964 -286.501331) (xy 102.962456 -286.475424) (xy 102.963053 -286.447707) (xy 102.972374 -286.39306)
			(xy 102.980998 -286.366712) (xy 102.988872 -286.344614) (xy 102.783894 -285.989522) (xy 102.76078 -285.985204)
			(xy 102.735964 -285.980016) (xy 102.688184 -285.963065) (xy 102.643565 -285.938998) (xy 102.603157 -285.908381)
			(xy 102.567916 -285.871936) (xy 102.538671 -285.830525) (xy 102.516113 -285.785123) (xy 102.500775 -285.736802)
			(xy 102.493018 -285.686702) (xy 102.492556 -285.661354) (xy 102.211632 -285.661354) (xy 102.211124 -285.687241)
			(xy 102.203025 -285.738379) (xy 102.187026 -285.787619) (xy 102.16352 -285.833751) (xy 102.133088 -285.875638)
			(xy 102.096478 -285.912248) (xy 102.054591 -285.94268) (xy 102.008459 -285.966186) (xy 101.959219 -285.982185)
			(xy 101.908081 -285.990284) (xy 101.856307 -285.990284) (xy 101.805169 -285.982185) (xy 101.755929 -285.966186)
			(xy 101.709797 -285.94268) (xy 101.66791 -285.912248) (xy 101.6313 -285.875638) (xy 101.600868 -285.833751)
			(xy 101.577362 -285.787619) (xy 101.561363 -285.738379) (xy 101.553264 -285.687241) (xy 101.552756 -285.661354)
			(xy 101.271832 -285.661354) (xy 101.271285 -285.688998) (xy 101.262091 -285.743516) (xy 101.253544 -285.769812)
			(xy 101.245924 -285.79191) (xy 101.451156 -286.147256) (xy 101.474016 -286.151574) (xy 101.498827 -286.156786)
			(xy 101.546604 -286.173734) (xy 101.591223 -286.197799) (xy 101.63163 -286.228413) (xy 101.666872 -286.264855)
			(xy 101.696117 -286.306263) (xy 101.718676 -286.351662) (xy 101.734017 -286.399979) (xy 101.741777 -286.450077)
			(xy 101.74224 -286.475424) (xy 101.741732 -286.501331) (xy 101.733626 -286.552508) (xy 101.717614 -286.601787)
			(xy 101.694091 -286.647954) (xy 101.663635 -286.689873) (xy 101.626997 -286.726511) (xy 101.585078 -286.756967)
			(xy 101.538911 -286.78049) (xy 101.489632 -286.796502) (xy 101.438455 -286.804608) (xy 101.386641 -286.804608)
			(xy 101.335464 -286.796502) (xy 101.286185 -286.78049) (xy 101.240018 -286.756967) (xy 101.198099 -286.726511)
			(xy 101.161461 -286.689873) (xy 101.131005 -286.647954) (xy 101.107482 -286.601787) (xy 101.09147 -286.552508)
			(xy 101.083364 -286.501331) (xy 101.082856 -286.475424) (xy 101.083453 -286.447707) (xy 101.092774 -286.39306)
			(xy 101.101398 -286.366712) (xy 101.109272 -286.344614) (xy 100.904294 -285.989522) (xy 100.88118 -285.985204)
			(xy 100.856364 -285.980016) (xy 100.808584 -285.963065) (xy 100.763965 -285.938998) (xy 100.723557 -285.908381)
			(xy 100.688316 -285.871936) (xy 100.659071 -285.830525) (xy 100.636513 -285.785123) (xy 100.621175 -285.736802)
			(xy 100.613418 -285.686702) (xy 100.612956 -285.661354) (xy 100.332032 -285.661354) (xy 100.331524 -285.687241)
			(xy 100.323425 -285.738379) (xy 100.307426 -285.787619) (xy 100.28392 -285.833751) (xy 100.253488 -285.875638)
			(xy 100.216878 -285.912248) (xy 100.174991 -285.94268) (xy 100.128859 -285.966186) (xy 100.079619 -285.982185)
			(xy 100.028481 -285.990284) (xy 99.976707 -285.990284) (xy 99.925569 -285.982185) (xy 99.876329 -285.966186)
			(xy 99.830197 -285.94268) (xy 99.78831 -285.912248) (xy 99.7517 -285.875638) (xy 99.721268 -285.833751)
			(xy 99.697762 -285.787619) (xy 99.681763 -285.738379) (xy 99.673664 -285.687241) (xy 99.673156 -285.661354)
			(xy 99.392232 -285.661354) (xy 99.391685 -285.688998) (xy 99.382491 -285.743516) (xy 99.373944 -285.769812)
			(xy 99.366324 -285.79191) (xy 99.571556 -286.147256) (xy 99.594416 -286.151574) (xy 99.619227 -286.156786)
			(xy 99.667004 -286.173734) (xy 99.711623 -286.197799) (xy 99.75203 -286.228413) (xy 99.787272 -286.264855)
			(xy 99.816517 -286.306263) (xy 99.839076 -286.351662) (xy 99.854417 -286.399979) (xy 99.862177 -286.450077)
			(xy 99.86264 -286.475424) (xy 99.862132 -286.501331) (xy 99.854026 -286.552508) (xy 99.838014 -286.601787)
			(xy 99.814491 -286.647954) (xy 99.784035 -286.689873) (xy 99.747397 -286.726511) (xy 99.705478 -286.756967)
			(xy 99.659311 -286.78049) (xy 99.610032 -286.796502) (xy 99.558855 -286.804608) (xy 99.507041 -286.804608)
			(xy 99.455864 -286.796502) (xy 99.406585 -286.78049) (xy 99.360418 -286.756967) (xy 99.318499 -286.726511)
			(xy 99.281861 -286.689873) (xy 99.251405 -286.647954) (xy 99.227882 -286.601787) (xy 99.21187 -286.552508)
			(xy 99.203764 -286.501331) (xy 99.203256 -286.475424) (xy 99.203853 -286.447707) (xy 99.213174 -286.39306)
			(xy 99.221798 -286.366712) (xy 99.229672 -286.344614) (xy 99.024694 -285.989522) (xy 99.00158 -285.985204)
			(xy 98.976764 -285.980016) (xy 98.928984 -285.963065) (xy 98.884365 -285.938998) (xy 98.843957 -285.908381)
			(xy 98.808716 -285.871936) (xy 98.779471 -285.830525) (xy 98.756913 -285.785123) (xy 98.741575 -285.736802)
			(xy 98.733818 -285.686702) (xy 98.733356 -285.661354) (xy 98.452432 -285.661354) (xy 98.451924 -285.687241)
			(xy 98.443825 -285.738379) (xy 98.427826 -285.787619) (xy 98.40432 -285.833751) (xy 98.373888 -285.875638)
			(xy 98.337278 -285.912248) (xy 98.295391 -285.94268) (xy 98.249259 -285.966186) (xy 98.200019 -285.982185)
			(xy 98.148881 -285.990284) (xy 98.097107 -285.990284) (xy 98.045969 -285.982185) (xy 97.996729 -285.966186)
			(xy 97.950597 -285.94268) (xy 97.90871 -285.912248) (xy 97.8721 -285.875638) (xy 97.841668 -285.833751)
			(xy 97.818162 -285.787619) (xy 97.802163 -285.738379) (xy 97.794064 -285.687241) (xy 97.793556 -285.661354)
			(xy 97.512632 -285.661354) (xy 97.512085 -285.688998) (xy 97.502891 -285.743516) (xy 97.494344 -285.769812)
			(xy 97.486724 -285.79191) (xy 97.691956 -286.147256) (xy 97.714816 -286.151574) (xy 97.739627 -286.156786)
			(xy 97.787404 -286.173734) (xy 97.832023 -286.197799) (xy 97.87243 -286.228413) (xy 97.907672 -286.264855)
			(xy 97.936917 -286.306263) (xy 97.959476 -286.351662) (xy 97.974817 -286.399979) (xy 97.982577 -286.450077)
			(xy 97.98304 -286.475424) (xy 97.982532 -286.501331) (xy 97.974426 -286.552508) (xy 97.958414 -286.601787)
			(xy 97.934891 -286.647954) (xy 97.904435 -286.689873) (xy 97.867797 -286.726511) (xy 97.825878 -286.756967)
			(xy 97.779711 -286.78049) (xy 97.730432 -286.796502) (xy 97.679255 -286.804608) (xy 97.627441 -286.804608)
			(xy 97.576264 -286.796502) (xy 97.526985 -286.78049) (xy 97.480818 -286.756967) (xy 97.438899 -286.726511)
			(xy 97.402261 -286.689873) (xy 97.371805 -286.647954) (xy 97.348282 -286.601787) (xy 97.33227 -286.552508)
			(xy 97.324164 -286.501331) (xy 97.323656 -286.475424) (xy 97.324253 -286.447707) (xy 97.333574 -286.39306)
			(xy 97.342198 -286.366712) (xy 97.350072 -286.344614) (xy 97.145094 -285.989522) (xy 97.12198 -285.985204)
			(xy 97.097164 -285.980016) (xy 97.049384 -285.963065) (xy 97.004765 -285.938998) (xy 96.964357 -285.908381)
			(xy 96.929116 -285.871936) (xy 96.899871 -285.830525) (xy 96.877313 -285.785123) (xy 96.861975 -285.736802)
			(xy 96.854218 -285.686702) (xy 96.853756 -285.661354) (xy 96.572832 -285.661354) (xy 96.572324 -285.687241)
			(xy 96.564225 -285.738379) (xy 96.548226 -285.787619) (xy 96.52472 -285.833751) (xy 96.494288 -285.875638)
			(xy 96.457678 -285.912248) (xy 96.415791 -285.94268) (xy 96.369659 -285.966186) (xy 96.320419 -285.982185)
			(xy 96.269281 -285.990284) (xy 96.217507 -285.990284) (xy 96.166369 -285.982185) (xy 96.117129 -285.966186)
			(xy 96.070997 -285.94268) (xy 96.02911 -285.912248) (xy 95.9925 -285.875638) (xy 95.962068 -285.833751)
			(xy 95.938562 -285.787619) (xy 95.922563 -285.738379) (xy 95.914464 -285.687241) (xy 95.913956 -285.661354)
			(xy 95.633032 -285.661354) (xy 95.632485 -285.688998) (xy 95.623291 -285.743516) (xy 95.614744 -285.769812)
			(xy 95.607124 -285.79191) (xy 95.812356 -286.147256) (xy 95.835216 -286.151574) (xy 95.860027 -286.156786)
			(xy 95.907804 -286.173734) (xy 95.952423 -286.197799) (xy 95.99283 -286.228413) (xy 96.028072 -286.264855)
			(xy 96.057317 -286.306263) (xy 96.079876 -286.351662) (xy 96.095217 -286.399979) (xy 96.102977 -286.450077)
			(xy 96.10344 -286.475424) (xy 96.102932 -286.501331) (xy 96.094826 -286.552508) (xy 96.078814 -286.601787)
			(xy 96.055291 -286.647954) (xy 96.024835 -286.689873) (xy 95.988197 -286.726511) (xy 95.946278 -286.756967)
			(xy 95.900111 -286.78049) (xy 95.850832 -286.796502) (xy 95.799655 -286.804608) (xy 95.747841 -286.804608)
			(xy 95.696664 -286.796502) (xy 95.647385 -286.78049) (xy 95.601218 -286.756967) (xy 95.559299 -286.726511)
			(xy 95.522661 -286.689873) (xy 95.492205 -286.647954) (xy 95.468682 -286.601787) (xy 95.45267 -286.552508)
			(xy 95.444564 -286.501331) (xy 95.444056 -286.475424) (xy 95.444653 -286.447707) (xy 95.453974 -286.39306)
			(xy 95.462598 -286.366712) (xy 95.470472 -286.344614) (xy 95.265494 -285.989522) (xy 95.24238 -285.985204)
			(xy 95.217564 -285.980016) (xy 95.169784 -285.963065) (xy 95.125165 -285.938998) (xy 95.084757 -285.908381)
			(xy 95.049516 -285.871936) (xy 95.020271 -285.830525) (xy 94.997713 -285.785123) (xy 94.982375 -285.736802)
			(xy 94.974618 -285.686702) (xy 94.974156 -285.661354) (xy 94.693232 -285.661354) (xy 94.692724 -285.687241)
			(xy 94.684625 -285.738379) (xy 94.668626 -285.787619) (xy 94.64512 -285.833751) (xy 94.614688 -285.875638)
			(xy 94.578078 -285.912248) (xy 94.536191 -285.94268) (xy 94.490059 -285.966186) (xy 94.440819 -285.982185)
			(xy 94.389681 -285.990284) (xy 94.337907 -285.990284) (xy 94.286769 -285.982185) (xy 94.237529 -285.966186)
			(xy 94.191397 -285.94268) (xy 94.14951 -285.912248) (xy 94.1129 -285.875638) (xy 94.082468 -285.833751)
			(xy 94.058962 -285.787619) (xy 94.042963 -285.738379) (xy 94.034864 -285.687241) (xy 94.034356 -285.661354)
			(xy 93.753432 -285.661354) (xy 93.752885 -285.688998) (xy 93.743691 -285.743516) (xy 93.735144 -285.769812)
			(xy 93.727524 -285.79191) (xy 93.932756 -286.147256) (xy 93.955616 -286.151574) (xy 93.980427 -286.156786)
			(xy 94.028204 -286.173734) (xy 94.072823 -286.197799) (xy 94.11323 -286.228413) (xy 94.148472 -286.264855)
			(xy 94.177717 -286.306263) (xy 94.200276 -286.351662) (xy 94.215617 -286.399979) (xy 94.223377 -286.450077)
			(xy 94.22384 -286.475424) (xy 94.223332 -286.501331) (xy 94.215226 -286.552508) (xy 94.199214 -286.601787)
			(xy 94.175691 -286.647954) (xy 94.145235 -286.689873) (xy 94.108597 -286.726511) (xy 94.066678 -286.756967)
			(xy 94.020511 -286.78049) (xy 93.971232 -286.796502) (xy 93.920055 -286.804608) (xy 93.868241 -286.804608)
			(xy 93.817064 -286.796502) (xy 93.767785 -286.78049) (xy 93.721618 -286.756967) (xy 93.679699 -286.726511)
			(xy 93.643061 -286.689873) (xy 93.612605 -286.647954) (xy 93.589082 -286.601787) (xy 93.57307 -286.552508)
			(xy 93.564964 -286.501331) (xy 93.564456 -286.475424) (xy 93.565053 -286.447707) (xy 93.574374 -286.39306)
			(xy 93.582998 -286.366712) (xy 93.590872 -286.344614) (xy 93.385894 -285.989522) (xy 93.36278 -285.985204)
			(xy 93.337964 -285.980016) (xy 93.290184 -285.963065) (xy 93.245565 -285.938998) (xy 93.205157 -285.908381)
			(xy 93.169916 -285.871936) (xy 93.140671 -285.830525) (xy 93.118113 -285.785123) (xy 93.102775 -285.736802)
			(xy 93.095018 -285.686702) (xy 93.094556 -285.661354) (xy 92.813632 -285.661354) (xy 92.813124 -285.687241)
			(xy 92.805025 -285.738379) (xy 92.789026 -285.787619) (xy 92.76552 -285.833751) (xy 92.735088 -285.875638)
			(xy 92.698478 -285.912248) (xy 92.656591 -285.94268) (xy 92.610459 -285.966186) (xy 92.561219 -285.982185)
			(xy 92.510081 -285.990284) (xy 92.458307 -285.990284) (xy 92.407169 -285.982185) (xy 92.357929 -285.966186)
			(xy 92.311797 -285.94268) (xy 92.26991 -285.912248) (xy 92.2333 -285.875638) (xy 92.202868 -285.833751)
			(xy 92.179362 -285.787619) (xy 92.163363 -285.738379) (xy 92.155264 -285.687241) (xy 92.154756 -285.661354)
			(xy 91.87434 -285.661354) (xy 91.873738 -285.689071) (xy 91.86442 -285.743718) (xy 91.855798 -285.770066)
			(xy 91.847924 -285.792164) (xy 92.053156 -286.147256) (xy 92.076016 -286.151574) (xy 92.100827 -286.156786)
			(xy 92.148604 -286.173734) (xy 92.193223 -286.197799) (xy 92.23363 -286.228413) (xy 92.268872 -286.264855)
			(xy 92.298117 -286.306263) (xy 92.320676 -286.351662) (xy 92.336017 -286.399979) (xy 92.343777 -286.450077)
			(xy 92.34424 -286.475424) (xy 92.343732 -286.501331) (xy 92.335626 -286.552508) (xy 92.319614 -286.601787)
			(xy 92.296091 -286.647954) (xy 92.265635 -286.689873) (xy 92.228997 -286.726511) (xy 92.187078 -286.756967)
			(xy 92.140911 -286.78049) (xy 92.091632 -286.796502) (xy 92.040455 -286.804608) (xy 91.988641 -286.804608)
			(xy 91.937464 -286.796502) (xy 91.888185 -286.78049) (xy 91.842018 -286.756967) (xy 91.800099 -286.726511)
			(xy 91.763461 -286.689873) (xy 91.733005 -286.647954) (xy 91.709482 -286.601787) (xy 91.69347 -286.552508)
			(xy 91.685364 -286.501331) (xy 91.684856 -286.475424) (xy 91.685453 -286.447707) (xy 91.694774 -286.39306)
			(xy 91.703398 -286.366712) (xy 91.711272 -286.344614) (xy 91.50604 -285.989522) (xy 91.48318 -285.985204)
			(xy 91.458364 -285.980016) (xy 91.410584 -285.963065) (xy 91.365965 -285.938998) (xy 91.325557 -285.908381)
			(xy 91.290316 -285.871936) (xy 91.261071 -285.830525) (xy 91.238513 -285.785123) (xy 91.223175 -285.736802)
			(xy 91.215418 -285.686702) (xy 91.214956 -285.661354) (xy 90.93454 -285.661354) (xy 90.934032 -285.687261)
			(xy 90.925926 -285.738438) (xy 90.909914 -285.787717) (xy 90.886391 -285.833884) (xy 90.855935 -285.875803)
			(xy 90.819297 -285.912441) (xy 90.777378 -285.942897) (xy 90.731211 -285.96642) (xy 90.681932 -285.982432)
			(xy 90.630755 -285.990538) (xy 90.578941 -285.990538) (xy 90.527764 -285.982432) (xy 90.478485 -285.96642)
			(xy 90.432318 -285.942897) (xy 90.390399 -285.912441) (xy 90.353761 -285.875803) (xy 90.323305 -285.833884)
			(xy 90.299782 -285.787717) (xy 90.28377 -285.738438) (xy 90.275664 -285.687261) (xy 90.275156 -285.661354)
			(xy 89.994232 -285.661354) (xy 89.993689 -285.689062) (xy 89.984503 -285.743708) (xy 89.975944 -285.770066)
			(xy 89.96807 -285.792164) (xy 90.173302 -286.147256) (xy 90.196162 -286.151574) (xy 90.220961 -286.156781)
			(xy 90.268701 -286.173765) (xy 90.31328 -286.197855) (xy 90.353647 -286.228483) (xy 90.388851 -286.264927)
			(xy 90.418064 -286.30633) (xy 90.440597 -286.351715) (xy 90.455919 -286.400014) (xy 90.46367 -286.450088)
			(xy 90.464132 -286.475424) (xy 90.463624 -286.501311) (xy 90.455525 -286.552449) (xy 90.439526 -286.601689)
			(xy 90.41602 -286.647821) (xy 90.385588 -286.689708) (xy 90.348978 -286.726318) (xy 90.307091 -286.75675)
			(xy 90.260959 -286.780256) (xy 90.211719 -286.796255) (xy 90.160581 -286.804354) (xy 90.108807 -286.804354)
			(xy 90.057669 -286.796255) (xy 90.008429 -286.780256) (xy 89.962297 -286.75675) (xy 89.92041 -286.726318)
			(xy 89.8838 -286.689708) (xy 89.853368 -286.647821) (xy 89.829862 -286.601689) (xy 89.813863 -286.552449)
			(xy 89.805764 -286.501311) (xy 89.805256 -286.475424) (xy 89.805793 -286.447716) (xy 89.814983 -286.393069)
			(xy 89.823544 -286.366712) (xy 89.831418 -286.344614) (xy 89.626186 -285.989522) (xy 89.603326 -285.985204)
			(xy 89.57852 -285.980026) (xy 89.530779 -285.963039) (xy 89.486199 -285.938946) (xy 89.445832 -285.908314)
			(xy 89.410627 -285.871866) (xy 89.381416 -285.83046) (xy 89.358884 -285.785071) (xy 89.343564 -285.736769)
			(xy 89.335817 -285.686691) (xy 89.335356 -285.661354) (xy 88.114632 -285.661354) (xy 88.114124 -285.687241)
			(xy 88.106025 -285.738379) (xy 88.090026 -285.787619) (xy 88.06652 -285.833751) (xy 88.036088 -285.875638)
			(xy 87.999478 -285.912248) (xy 87.957591 -285.94268) (xy 87.911459 -285.966186) (xy 87.862219 -285.982185)
			(xy 87.811081 -285.990284) (xy 87.759307 -285.990284) (xy 87.708169 -285.982185) (xy 87.658929 -285.966186)
			(xy 87.612797 -285.94268) (xy 87.57091 -285.912248) (xy 87.5343 -285.875638) (xy 87.503868 -285.833751)
			(xy 87.480362 -285.787619) (xy 87.464363 -285.738379) (xy 87.456264 -285.687241) (xy 87.455756 -285.661354)
			(xy 31.743142 -285.661354) (xy 31.743142 -286.475424) (xy 86.046056 -286.475424) (xy 86.046564 -286.449537)
			(xy 86.054663 -286.398399) (xy 86.070662 -286.349159) (xy 86.094168 -286.303027) (xy 86.1246 -286.26114)
			(xy 86.16121 -286.22453) (xy 86.203097 -286.194098) (xy 86.249229 -286.170592) (xy 86.298469 -286.154593)
			(xy 86.349607 -286.146494) (xy 86.401381 -286.146494) (xy 86.452519 -286.154593) (xy 86.501759 -286.170592)
			(xy 86.547891 -286.194098) (xy 86.589778 -286.22453) (xy 86.626388 -286.26114) (xy 86.65682 -286.303027)
			(xy 86.680326 -286.349159) (xy 86.696325 -286.398399) (xy 86.704424 -286.449537) (xy 86.704932 -286.475424)
			(xy 86.704442 -286.501305) (xy 86.98614 -286.501305) (xy 86.98614 -286.449495) (xy 86.994245 -286.398322)
			(xy 87.010255 -286.349048) (xy 87.033776 -286.302885) (xy 87.064229 -286.260969) (xy 87.100864 -286.224333)
			(xy 87.142779 -286.193879) (xy 87.188942 -286.170357) (xy 87.238217 -286.154347) (xy 87.289389 -286.146241)
			(xy 87.315294 -286.145732) (xy 87.340788 -286.146208) (xy 87.391166 -286.154069) (xy 87.43973 -286.169604)
			(xy 87.485317 -286.192442) (xy 87.526838 -286.222037) (xy 87.563299 -286.257679) (xy 87.578946 -286.277812)
			(xy 87.991442 -286.277812) (xy 88.007098 -286.257686) (xy 88.043557 -286.222043) (xy 88.085076 -286.192449)
			(xy 88.130661 -286.16961) (xy 88.179224 -286.154073) (xy 88.229601 -286.146211) (xy 88.255094 -286.145732)
			(xy 88.281006 -286.146165) (xy 88.332191 -286.154271) (xy 88.381478 -286.170285) (xy 88.427653 -286.193811)
			(xy 88.469579 -286.224272) (xy 88.506224 -286.260916) (xy 88.536685 -286.302842) (xy 88.560213 -286.349016)
			(xy 88.576227 -286.398303) (xy 88.584334 -286.449488) (xy 88.584334 -286.501312) (xy 88.576227 -286.552497)
			(xy 88.560213 -286.601784) (xy 88.536685 -286.647958) (xy 88.506224 -286.689884) (xy 88.469579 -286.726528)
			(xy 88.427653 -286.756989) (xy 88.381478 -286.780515) (xy 88.332191 -286.796529) (xy 88.281006 -286.804635)
			(xy 88.255094 -286.805116) (xy 88.229601 -286.80463) (xy 88.179224 -286.796768) (xy 88.130661 -286.781233)
			(xy 88.085074 -286.758397) (xy 88.043553 -286.728806) (xy 88.007091 -286.693167) (xy 87.991442 -286.673036)
			(xy 87.578946 -286.673036) (xy 87.56331 -286.693178) (xy 87.526845 -286.728817) (xy 87.485322 -286.758409)
			(xy 87.439733 -286.781244) (xy 87.391168 -286.796778) (xy 87.340788 -286.804638) (xy 87.315294 -286.805116)
			(xy 87.289389 -286.804559) (xy 87.238217 -286.796453) (xy 87.188942 -286.780443) (xy 87.142779 -286.756921)
			(xy 87.100864 -286.726467) (xy 87.064229 -286.689831) (xy 87.033776 -286.647915) (xy 87.010255 -286.601752)
			(xy 86.994245 -286.552478) (xy 86.98614 -286.501305) (xy 86.704442 -286.501305) (xy 86.704407 -286.503132)
			(xy 86.695209 -286.557779) (xy 86.686644 -286.584136) (xy 86.679024 -286.60598) (xy 86.884002 -286.961072)
			(xy 86.906862 -286.96539) (xy 86.931665 -286.970582) (xy 86.979406 -286.987567) (xy 87.023985 -287.011659)
			(xy 87.064353 -287.042288) (xy 87.099557 -287.078734) (xy 87.12877 -287.120139) (xy 87.151302 -287.165526)
			(xy 87.166622 -287.213827) (xy 87.174371 -287.263904) (xy 87.174832 -287.28924) (xy 87.174324 -287.315127)
			(xy 87.166225 -287.366265) (xy 87.150226 -287.415505) (xy 87.12672 -287.461637) (xy 87.096288 -287.503524)
			(xy 87.059678 -287.540134) (xy 87.017791 -287.570566) (xy 86.971659 -287.594072) (xy 86.922419 -287.610071)
			(xy 86.871281 -287.61817) (xy 86.819507 -287.61817) (xy 86.768369 -287.610071) (xy 86.719129 -287.594072)
			(xy 86.672997 -287.570566) (xy 86.63111 -287.540134) (xy 86.5945 -287.503524) (xy 86.564068 -287.461637)
			(xy 86.540562 -287.415505) (xy 86.524563 -287.366265) (xy 86.516464 -287.315127) (xy 86.515956 -287.28924)
			(xy 86.516497 -287.261532) (xy 86.525685 -287.206886) (xy 86.534244 -287.180528) (xy 86.541864 -287.158684)
			(xy 86.336886 -286.803592) (xy 86.314026 -286.799274) (xy 86.289236 -286.79403) (xy 86.241499 -286.777048)
			(xy 86.196923 -286.752961) (xy 86.156558 -286.722338) (xy 86.121354 -286.685898) (xy 86.09214 -286.644501)
			(xy 86.069605 -286.599121) (xy 86.054278 -286.550828) (xy 86.046522 -286.500758) (xy 86.046056 -286.475424)
			(xy 31.743142 -286.475424) (xy 31.743142 -318.41567) (xy 33.585658 -320.258186) (xy 33.617916 -320.243454)
			(xy 33.641401 -320.233123) (xy 33.690591 -320.218547) (xy 33.741362 -320.211162) (xy 33.767014 -320.210688)
			(xy 33.794996 -320.211238) (xy 33.850272 -320.219995) (xy 33.903498 -320.23729) (xy 33.953362 -320.262699)
			(xy 33.998638 -320.295596) (xy 34.038211 -320.335169) (xy 34.071106 -320.380446) (xy 34.096513 -320.430312)
			(xy 34.113808 -320.483538) (xy 34.122563 -320.538813) (xy 34.123122 -320.566796) (xy 34.122678 -320.592451)
			(xy 34.115309 -320.643228) (xy 34.100708 -320.692416) (xy 34.090356 -320.715894) (xy 34.075624 -320.748152)
			(xy 36.479988 -323.152516) (xy 36.497253 -323.170555) (xy 36.525021 -323.212046) (xy 36.544143 -323.258164)
			(xy 36.553883 -323.307131) (xy 36.55441 -323.332094) (xy 36.55441 -341.442802) (xy 38.330632 -343.219024)
			(xy 58.817002 -343.219024)
		)
		(stroke
			(width 0)
			(type solid)
		)
		(fill yes)
		(layer "In9.Cu")
		(net "PVCCFA_EHV_FIVRA_CPU1")
	)
	(gr_poly
		(pts
			(xy 285.336742 -351.711006) (xy 285.346946 -351.686358) (xy 285.373611 -351.640157) (xy 285.406862 -351.598444)
			(xy 285.445958 -351.562153) (xy 285.490025 -351.532092) (xy 285.53808 -351.508933) (xy 285.589049 -351.493193)
			(xy 285.641794 -351.485225) (xy 285.668466 -351.484692) (xy 285.695792 -351.485166) (xy 285.749807 -351.493477)
			(xy 285.801915 -351.509953) (xy 285.850888 -351.534208) (xy 285.895575 -351.565669) (xy 285.915608 -351.58426)
			(xy 285.92723 -351.594657) (xy 285.955164 -351.608481) (xy 285.985966 -351.613237) (xy 286.016768 -351.608481)
			(xy 286.044702 -351.594657) (xy 286.056324 -351.58426) (xy 286.076376 -351.565695) (xy 286.121074 -351.534265)
			(xy 286.170046 -351.510023) (xy 286.222142 -351.493537) (xy 286.276145 -351.485194) (xy 286.303466 -351.484692)
			(xy 286.331471 -351.485211) (xy 286.386792 -351.493971) (xy 286.44006 -351.511281) (xy 286.489963 -351.536714)
			(xy 286.535271 -351.569644) (xy 286.555434 -351.589086) (xy 286.565131 -351.598252) (xy 286.588217 -351.611617)
			(xy 286.613979 -351.618536) (xy 286.640653 -351.618536) (xy 286.666415 -351.611617) (xy 286.689501 -351.598252)
			(xy 286.699198 -351.589086) (xy 286.719387 -351.569674) (xy 286.764694 -351.536752) (xy 286.814591 -351.51132)
			(xy 286.867851 -351.494002) (xy 286.923164 -351.485225) (xy 286.951166 -351.484692) (xy 286.977843 -351.485164)
			(xy 287.030602 -351.493117) (xy 287.081584 -351.508849) (xy 287.12965 -351.53201) (xy 287.173724 -351.56208)
			(xy 287.21282 -351.598387) (xy 287.246064 -351.640119) (xy 287.272711 -351.686342) (xy 287.28289 -351.711006)
			(xy 287.295336 -351.743264) (xy 290.294568 -351.743264) (xy 290.307014 -351.711006) (xy 290.317218 -351.686357)
			(xy 290.343882 -351.640153) (xy 290.377132 -351.598438) (xy 290.416228 -351.562143) (xy 290.460295 -351.532079)
			(xy 290.508349 -351.508917) (xy 290.559319 -351.493174) (xy 290.612065 -351.485201) (xy 290.638738 -351.484692)
			(xy 290.666744 -351.485208) (xy 290.722067 -351.493965) (xy 290.775338 -351.511272) (xy 290.825244 -351.536703)
			(xy 290.870555 -351.569631) (xy 290.890706 -351.589086) (xy 290.900403 -351.598252) (xy 290.923489 -351.611617)
			(xy 290.949251 -351.618536) (xy 290.975925 -351.618536) (xy 291.001687 -351.611617) (xy 291.024773 -351.598252)
			(xy 291.03447 -351.589086) (xy 291.054661 -351.569678) (xy 291.09997 -351.536766) (xy 291.149868 -351.511343)
			(xy 291.203127 -351.494036) (xy 291.258438 -351.48527) (xy 291.286438 -351.484692) (xy 291.313765 -351.485164)
			(xy 291.367782 -351.493471) (xy 291.419892 -351.509944) (xy 291.468869 -351.534196) (xy 291.513558 -351.565656)
			(xy 291.53358 -351.58426) (xy 291.545202 -351.594657) (xy 291.573136 -351.608481) (xy 291.603938 -351.613237)
			(xy 291.63474 -351.608481) (xy 291.662674 -351.594657) (xy 291.674296 -351.58426) (xy 291.694349 -351.565699)
			(xy 291.73905 -351.534278) (xy 291.788022 -351.510046) (xy 291.840118 -351.493571) (xy 291.894118 -351.485239)
			(xy 291.921438 -351.484692) (xy 291.948116 -351.485162) (xy 292.000878 -351.493111) (xy 292.051863 -351.508841)
			(xy 292.099932 -351.531999) (xy 292.14401 -351.562068) (xy 292.183109 -351.598375) (xy 292.216356 -351.640107)
			(xy 292.243006 -351.686332) (xy 292.253162 -351.711006) (xy 292.265608 -351.743264) (xy 295.001696 -351.743264)
			(xy 295.014142 -351.711006) (xy 295.024346 -351.686358) (xy 295.051011 -351.640157) (xy 295.084262 -351.598444)
			(xy 295.123358 -351.562153) (xy 295.167425 -351.532092) (xy 295.21548 -351.508933) (xy 295.266449 -351.493193)
			(xy 295.319194 -351.485225) (xy 295.345866 -351.484692) (xy 295.373192 -351.485166) (xy 295.427207 -351.493477)
			(xy 295.479315 -351.509953) (xy 295.528288 -351.534208) (xy 295.572975 -351.565669) (xy 295.593008 -351.58426)
			(xy 295.60463 -351.594657) (xy 295.632564 -351.608481) (xy 295.663366 -351.613237) (xy 295.694168 -351.608481)
			(xy 295.722102 -351.594657) (xy 295.733724 -351.58426) (xy 295.753776 -351.565695) (xy 295.798474 -351.534265)
			(xy 295.847446 -351.510023) (xy 295.899542 -351.493537) (xy 295.953545 -351.485194) (xy 295.980866 -351.484692)
			(xy 296.008871 -351.485211) (xy 296.064192 -351.493971) (xy 296.11746 -351.511281) (xy 296.167363 -351.536714)
			(xy 296.212671 -351.569644) (xy 296.232834 -351.589086) (xy 296.242531 -351.598252) (xy 296.265617 -351.611617)
			(xy 296.291379 -351.618536) (xy 296.318053 -351.618536) (xy 296.343815 -351.611617) (xy 296.366901 -351.598252)
			(xy 296.376598 -351.589086) (xy 296.396787 -351.569674) (xy 296.442094 -351.536752) (xy 296.491991 -351.51132)
			(xy 296.545251 -351.494002) (xy 296.600564 -351.485225) (xy 296.628566 -351.484692) (xy 296.655243 -351.485164)
			(xy 296.708002 -351.493117) (xy 296.758984 -351.508849) (xy 296.80705 -351.53201) (xy 296.851124 -351.56208)
			(xy 296.89022 -351.598387) (xy 296.923464 -351.640119) (xy 296.950111 -351.686342) (xy 296.96029 -351.711006)
			(xy 296.972736 -351.743264) (xy 300.073568 -351.743264) (xy 300.086014 -351.711006) (xy 300.096218 -351.686357)
			(xy 300.122882 -351.640153) (xy 300.156132 -351.598438) (xy 300.195228 -351.562143) (xy 300.239295 -351.532079)
			(xy 300.287349 -351.508917) (xy 300.338319 -351.493174) (xy 300.391065 -351.485201) (xy 300.417738 -351.484692)
			(xy 300.445744 -351.485208) (xy 300.501067 -351.493965) (xy 300.554338 -351.511272) (xy 300.604244 -351.536703)
			(xy 300.649555 -351.569631) (xy 300.669706 -351.589086) (xy 300.679403 -351.598252) (xy 300.702489 -351.611617)
			(xy 300.728251 -351.618536) (xy 300.754925 -351.618536) (xy 300.780687 -351.611617) (xy 300.803773 -351.598252)
			(xy 300.81347 -351.589086) (xy 300.833661 -351.569678) (xy 300.87897 -351.536766) (xy 300.928868 -351.511343)
			(xy 300.982127 -351.494036) (xy 301.037438 -351.48527) (xy 301.065438 -351.484692) (xy 301.092765 -351.485164)
			(xy 301.146782 -351.493471) (xy 301.198892 -351.509944) (xy 301.247869 -351.534196) (xy 301.292558 -351.565656)
			(xy 301.31258 -351.58426) (xy 301.324202 -351.594657) (xy 301.352136 -351.608481) (xy 301.382938 -351.613237)
			(xy 301.41374 -351.608481) (xy 301.441674 -351.594657) (xy 301.453296 -351.58426) (xy 301.473349 -351.565699)
			(xy 301.51805 -351.534278) (xy 301.567022 -351.510046) (xy 301.619118 -351.493571) (xy 301.673118 -351.485239)
			(xy 301.700438 -351.484692) (xy 301.727116 -351.485162) (xy 301.779878 -351.493111) (xy 301.830863 -351.508841)
			(xy 301.878932 -351.531999) (xy 301.92301 -351.562068) (xy 301.962109 -351.598375) (xy 301.995356 -351.640107)
			(xy 302.022006 -351.686332) (xy 302.032162 -351.711006) (xy 302.044608 -351.743264) (xy 316.954916 -351.743264)
			(xy 318.142874 -350.555306) (xy 318.142874 -339.272372) (xy 318.123647 -339.252729) (xy 318.090464 -339.20891)
			(xy 318.063913 -339.160782) (xy 318.044544 -339.109342) (xy 318.032758 -339.055655) (xy 318.028799 -339.000832)
			(xy 318.032748 -338.946009) (xy 318.044525 -338.89232) (xy 318.063886 -338.840876) (xy 318.090428 -338.792744)
			(xy 318.123604 -338.74892) (xy 318.142874 -338.72932) (xy 318.142874 -332.950058) (xy 318.143489 -332.925103)
			(xy 318.153233 -332.876153) (xy 318.172338 -332.830043) (xy 318.20007 -332.788546) (xy 318.217296 -332.77048)
			(xy 318.669162 -332.318614) (xy 318.687202 -332.301353) (xy 318.728695 -332.273592) (xy 318.774813 -332.254478)
			(xy 318.823778 -332.244747) (xy 318.84874 -332.244192) (xy 321.8815 -332.244192) (xy 322.221098 -331.904594)
			(xy 322.221098 -296.86885) (xy 322.221714 -296.843895) (xy 322.23146 -296.794947) (xy 322.250567 -296.748839)
			(xy 322.278302 -296.707345) (xy 322.29552 -296.689272) (xy 330.118212 -288.86658) (xy 330.136252 -288.849317)
			(xy 330.177744 -288.821552) (xy 330.223862 -288.802431) (xy 330.272827 -288.792691) (xy 330.29779 -288.792158)
			(xy 335.419954 -288.792158) (xy 335.434178 -288.76498) (xy 335.446448 -288.742575) (xy 335.476852 -288.701528)
			(xy 335.513247 -288.665687) (xy 335.554756 -288.635918) (xy 335.600375 -288.612938) (xy 335.649004 -288.597302)
			(xy 335.699468 -288.589389) (xy 335.750548 -288.589389) (xy 335.801012 -288.597302) (xy 335.849641 -288.612938)
			(xy 335.89526 -288.635918) (xy 335.936769 -288.665687) (xy 335.973164 -288.701528) (xy 336.003568 -288.742575)
			(xy 336.015838 -288.76498) (xy 336.030062 -288.792158) (xy 336.358738 -288.792158) (xy 336.372962 -288.764726)
			(xy 336.384825 -288.742926) (xy 336.414096 -288.702849) (xy 336.449047 -288.667617) (xy 336.488889 -288.638026)
			(xy 336.532719 -288.614747) (xy 336.579546 -288.598307) (xy 336.603848 -288.593276) (xy 336.626708 -288.588958)
			(xy 336.831686 -288.233866) (xy 336.823812 -288.212022) (xy 336.815234 -288.185603) (xy 336.806039 -288.130828)
			(xy 336.805524 -288.103056) (xy 336.806032 -288.077169) (xy 336.814131 -288.026031) (xy 336.83013 -287.976791)
			(xy 336.853636 -287.930659) (xy 336.884068 -287.888772) (xy 336.920678 -287.852162) (xy 336.962565 -287.82173)
			(xy 337.008697 -287.798224) (xy 337.057937 -287.782225) (xy 337.109075 -287.774126) (xy 337.160849 -287.774126)
			(xy 337.211987 -287.782225) (xy 337.261227 -287.798224) (xy 337.307359 -287.82173) (xy 337.349246 -287.852162)
			(xy 337.385856 -287.888772) (xy 337.416288 -287.930659) (xy 337.439794 -287.976791) (xy 337.455793 -288.026031)
			(xy 337.463892 -288.077169) (xy 337.4644 -288.103056) (xy 337.463939 -288.128394) (xy 337.456192 -288.178474)
			(xy 337.440873 -288.226779) (xy 337.418343 -288.272171) (xy 337.389133 -288.313581) (xy 337.35393 -288.350034)
			(xy 337.313564 -288.380672) (xy 337.268986 -288.404772) (xy 337.221244 -288.421767) (xy 337.19643 -288.426906)
			(xy 337.17357 -288.431224) (xy 337.053174 -288.639758) (xy 337.046049 -288.653227) (xy 337.039261 -288.682916)
			(xy 337.041521 -288.713287) (xy 337.052628 -288.741644) (xy 337.071596 -288.765471) (xy 337.09674 -288.782654)
			(xy 337.125831 -288.791666) (xy 337.141058 -288.792158) (xy 337.299554 -288.792158) (xy 337.313778 -288.76498)
			(xy 337.326048 -288.742575) (xy 337.356452 -288.701528) (xy 337.392847 -288.665687) (xy 337.434356 -288.635918)
			(xy 337.479975 -288.612938) (xy 337.528604 -288.597302) (xy 337.579068 -288.589389) (xy 337.630148 -288.589389)
			(xy 337.680612 -288.597302) (xy 337.729241 -288.612938) (xy 337.77486 -288.635918) (xy 337.816369 -288.665687)
			(xy 337.852764 -288.701528) (xy 337.883168 -288.742575) (xy 337.895438 -288.76498) (xy 337.909662 -288.792158)
			(xy 338.238338 -288.792158) (xy 338.252562 -288.764726) (xy 338.264425 -288.742926) (xy 338.293696 -288.702849)
			(xy 338.328647 -288.667617) (xy 338.368489 -288.638026) (xy 338.412319 -288.614747) (xy 338.459146 -288.598307)
			(xy 338.483448 -288.593276) (xy 338.506308 -288.588958) (xy 338.711286 -288.233866) (xy 338.703412 -288.212022)
			(xy 338.694834 -288.185603) (xy 338.685639 -288.130828) (xy 338.685124 -288.103056) (xy 338.685632 -288.077169)
			(xy 338.693731 -288.026031) (xy 338.70973 -287.976791) (xy 338.733236 -287.930659) (xy 338.763668 -287.888772)
			(xy 338.800278 -287.852162) (xy 338.842165 -287.82173) (xy 338.888297 -287.798224) (xy 338.937537 -287.782225)
			(xy 338.988675 -287.774126) (xy 339.040449 -287.774126) (xy 339.091587 -287.782225) (xy 339.140827 -287.798224)
			(xy 339.186959 -287.82173) (xy 339.228846 -287.852162) (xy 339.265456 -287.888772) (xy 339.295888 -287.930659)
			(xy 339.319394 -287.976791) (xy 339.335393 -288.026031) (xy 339.343492 -288.077169) (xy 339.344 -288.103056)
			(xy 339.343539 -288.128394) (xy 339.335792 -288.178474) (xy 339.320473 -288.226779) (xy 339.297943 -288.272171)
			(xy 339.268733 -288.313581) (xy 339.23353 -288.350034) (xy 339.193164 -288.380672) (xy 339.148586 -288.404772)
			(xy 339.100844 -288.421767) (xy 339.07603 -288.426906) (xy 339.05317 -288.431224) (xy 338.932774 -288.639758)
			(xy 338.925649 -288.653227) (xy 338.918861 -288.682916) (xy 338.921121 -288.713287) (xy 338.932228 -288.741644)
			(xy 338.951196 -288.765471) (xy 338.97634 -288.782654) (xy 339.005431 -288.791666) (xy 339.020658 -288.792158)
			(xy 339.178138 -288.792158) (xy 339.192362 -288.764726) (xy 339.204677 -288.742186) (xy 339.235214 -288.700891)
			(xy 339.271791 -288.664836) (xy 339.31352 -288.634895) (xy 339.35939 -288.611793) (xy 339.408291 -288.59609)
			(xy 339.459036 -288.588167) (xy 339.484716 -288.587688) (xy 339.510393 -288.588165) (xy 339.561131 -288.596103)
			(xy 339.610022 -288.611817) (xy 339.655883 -288.634925) (xy 339.697605 -288.664869) (xy 339.734175 -288.700922)
			(xy 339.76471 -288.742213) (xy 339.77707 -288.764726) (xy 339.791294 -288.792158) (xy 340.117938 -288.792158)
			(xy 340.132162 -288.764726) (xy 340.144025 -288.742926) (xy 340.173296 -288.702849) (xy 340.208247 -288.667617)
			(xy 340.248089 -288.638026) (xy 340.291919 -288.614747) (xy 340.338746 -288.598307) (xy 340.363048 -288.593276)
			(xy 340.385908 -288.588958) (xy 340.59114 -288.233866) (xy 340.583266 -288.211768) (xy 340.574644 -288.185419)
			(xy 340.565327 -288.130773) (xy 340.564724 -288.103056) (xy 340.565232 -288.077149) (xy 340.573338 -288.025972)
			(xy 340.58935 -287.976693) (xy 340.612873 -287.930526) (xy 340.643329 -287.888607) (xy 340.679967 -287.851969)
			(xy 340.721886 -287.821513) (xy 340.768053 -287.79799) (xy 340.817332 -287.781978) (xy 340.868509 -287.773872)
			(xy 340.920323 -287.773872) (xy 340.9715 -287.781978) (xy 341.020779 -287.79799) (xy 341.066946 -287.821513)
			(xy 341.108865 -287.851969) (xy 341.145503 -287.888607) (xy 341.175959 -287.930526) (xy 341.199482 -287.976693)
			(xy 341.215494 -288.025972) (xy 341.2236 -288.077149) (xy 341.224108 -288.103056) (xy 341.223646 -288.128406)
			(xy 341.215889 -288.178508) (xy 341.200552 -288.226832) (xy 341.177996 -288.272238) (xy 341.148753 -288.313654)
			(xy 341.113513 -288.350104) (xy 341.073107 -288.380727) (xy 341.028489 -288.404803) (xy 340.98071 -288.421762)
			(xy 340.955884 -288.426906) (xy 340.933024 -288.431224) (xy 340.812628 -288.639758) (xy 340.8055 -288.653225)
			(xy 340.798709 -288.68291) (xy 340.800967 -288.713279) (xy 340.812075 -288.741633) (xy 340.831046 -288.765454)
			(xy 340.856194 -288.782628) (xy 340.885286 -288.791627) (xy 340.900512 -288.792158) (xy 341.057738 -288.792158)
			(xy 341.071962 -288.764726) (xy 341.084277 -288.742186) (xy 341.114814 -288.700891) (xy 341.151391 -288.664836)
			(xy 341.19312 -288.634895) (xy 341.23899 -288.611793) (xy 341.287891 -288.59609) (xy 341.338636 -288.588167)
			(xy 341.364316 -288.587688) (xy 341.389993 -288.588165) (xy 341.440731 -288.596103) (xy 341.489622 -288.611817)
			(xy 341.535483 -288.634925) (xy 341.577205 -288.664869) (xy 341.613775 -288.700922) (xy 341.64431 -288.742213)
			(xy 341.65667 -288.764726) (xy 341.670894 -288.792158) (xy 341.997538 -288.792158) (xy 342.011762 -288.764726)
			(xy 342.023625 -288.742926) (xy 342.052896 -288.702849) (xy 342.087847 -288.667617) (xy 342.127689 -288.638026)
			(xy 342.171519 -288.614747) (xy 342.218346 -288.598307) (xy 342.242648 -288.593276) (xy 342.265508 -288.588958)
			(xy 342.47074 -288.233866) (xy 342.462866 -288.211768) (xy 342.454244 -288.185419) (xy 342.444927 -288.130773)
			(xy 342.444324 -288.103056) (xy 342.444832 -288.077149) (xy 342.452938 -288.025972) (xy 342.46895 -287.976693)
			(xy 342.492473 -287.930526) (xy 342.522929 -287.888607) (xy 342.559567 -287.851969) (xy 342.601486 -287.821513)
			(xy 342.647653 -287.79799) (xy 342.696932 -287.781978) (xy 342.748109 -287.773872) (xy 342.799923 -287.773872)
			(xy 342.8511 -287.781978) (xy 342.900379 -287.79799) (xy 342.946546 -287.821513) (xy 342.988465 -287.851969)
			(xy 343.025103 -287.888607) (xy 343.055559 -287.930526) (xy 343.079082 -287.976693) (xy 343.095094 -288.025972)
			(xy 343.1032 -288.077149) (xy 343.103708 -288.103056) (xy 343.103246 -288.128406) (xy 343.095489 -288.178508)
			(xy 343.080152 -288.226832) (xy 343.057596 -288.272238) (xy 343.028353 -288.313654) (xy 342.993113 -288.350104)
			(xy 342.952707 -288.380727) (xy 342.908089 -288.404803) (xy 342.86031 -288.421762) (xy 342.835484 -288.426906)
			(xy 342.812624 -288.431224) (xy 342.692228 -288.639758) (xy 342.6851 -288.653225) (xy 342.678309 -288.68291)
			(xy 342.680567 -288.713279) (xy 342.691675 -288.741633) (xy 342.710646 -288.765454) (xy 342.735794 -288.782628)
			(xy 342.764886 -288.791627) (xy 342.780112 -288.792158) (xy 342.937338 -288.792158) (xy 342.951562 -288.764726)
			(xy 342.963877 -288.742186) (xy 342.994414 -288.700891) (xy 343.030991 -288.664836) (xy 343.07272 -288.634895)
			(xy 343.11859 -288.611793) (xy 343.167491 -288.59609) (xy 343.218236 -288.588167) (xy 343.243916 -288.587688)
			(xy 343.269593 -288.588165) (xy 343.320331 -288.596103) (xy 343.369222 -288.611817) (xy 343.415083 -288.634925)
			(xy 343.456805 -288.664869) (xy 343.493375 -288.700922) (xy 343.52391 -288.742213) (xy 343.53627 -288.764726)
			(xy 343.550494 -288.792158) (xy 343.877138 -288.792158) (xy 343.891362 -288.764726) (xy 343.903225 -288.742926)
			(xy 343.932496 -288.702849) (xy 343.967447 -288.667617) (xy 344.007289 -288.638026) (xy 344.051119 -288.614747)
			(xy 344.097946 -288.598307) (xy 344.122248 -288.593276) (xy 344.145108 -288.588958) (xy 344.35034 -288.233866)
			(xy 344.342466 -288.211768) (xy 344.333844 -288.185419) (xy 344.324527 -288.130773) (xy 344.323924 -288.103056)
			(xy 344.324432 -288.077149) (xy 344.332538 -288.025972) (xy 344.34855 -287.976693) (xy 344.372073 -287.930526)
			(xy 344.402529 -287.888607) (xy 344.439167 -287.851969) (xy 344.481086 -287.821513) (xy 344.527253 -287.79799)
			(xy 344.576532 -287.781978) (xy 344.627709 -287.773872) (xy 344.679523 -287.773872) (xy 344.7307 -287.781978)
			(xy 344.779979 -287.79799) (xy 344.826146 -287.821513) (xy 344.868065 -287.851969) (xy 344.904703 -287.888607)
			(xy 344.935159 -287.930526) (xy 344.958682 -287.976693) (xy 344.974694 -288.025972) (xy 344.9828 -288.077149)
			(xy 344.983308 -288.103056) (xy 344.982846 -288.128406) (xy 344.975089 -288.178508) (xy 344.959752 -288.226832)
			(xy 344.937196 -288.272238) (xy 344.907953 -288.313654) (xy 344.872713 -288.350104) (xy 344.832307 -288.380727)
			(xy 344.787689 -288.404803) (xy 344.73991 -288.421762) (xy 344.715084 -288.426906) (xy 344.692224 -288.431224)
			(xy 344.571828 -288.639758) (xy 344.5647 -288.653225) (xy 344.557909 -288.68291) (xy 344.560167 -288.713279)
			(xy 344.571275 -288.741633) (xy 344.590246 -288.765454) (xy 344.615394 -288.782628) (xy 344.644486 -288.791627)
			(xy 344.659712 -288.792158) (xy 344.816938 -288.792158) (xy 344.831162 -288.764726) (xy 344.843477 -288.742186)
			(xy 344.874014 -288.700891) (xy 344.910591 -288.664836) (xy 344.95232 -288.634895) (xy 344.99819 -288.611793)
			(xy 345.047091 -288.59609) (xy 345.097836 -288.588167) (xy 345.123516 -288.587688) (xy 345.149193 -288.588165)
			(xy 345.199931 -288.596103) (xy 345.248822 -288.611817) (xy 345.294683 -288.634925) (xy 345.336405 -288.664869)
			(xy 345.372975 -288.700922) (xy 345.40351 -288.742213) (xy 345.41587 -288.764726) (xy 345.430094 -288.792158)
			(xy 345.756738 -288.792158) (xy 345.770962 -288.764726) (xy 345.782825 -288.742926) (xy 345.812096 -288.702849)
			(xy 345.847047 -288.667617) (xy 345.886889 -288.638026) (xy 345.930719 -288.614747) (xy 345.977546 -288.598307)
			(xy 346.001848 -288.593276) (xy 346.024708 -288.588958) (xy 346.22994 -288.233866) (xy 346.222066 -288.211768)
			(xy 346.213444 -288.185419) (xy 346.204127 -288.130773) (xy 346.203524 -288.103056) (xy 346.204032 -288.077149)
			(xy 346.212138 -288.025972) (xy 346.22815 -287.976693) (xy 346.251673 -287.930526) (xy 346.282129 -287.888607)
			(xy 346.318767 -287.851969) (xy 346.360686 -287.821513) (xy 346.406853 -287.79799) (xy 346.456132 -287.781978)
			(xy 346.507309 -287.773872) (xy 346.559123 -287.773872) (xy 346.6103 -287.781978) (xy 346.659579 -287.79799)
			(xy 346.705746 -287.821513) (xy 346.747665 -287.851969) (xy 346.784303 -287.888607) (xy 346.814759 -287.930526)
			(xy 346.838282 -287.976693) (xy 346.854294 -288.025972) (xy 346.8624 -288.077149) (xy 346.862908 -288.103056)
			(xy 346.862446 -288.128406) (xy 346.854689 -288.178508) (xy 346.839352 -288.226832) (xy 346.816796 -288.272238)
			(xy 346.787553 -288.313654) (xy 346.752313 -288.350104) (xy 346.711907 -288.380727) (xy 346.667289 -288.404803)
			(xy 346.61951 -288.421762) (xy 346.594684 -288.426906) (xy 346.571824 -288.431224) (xy 346.451428 -288.639758)
			(xy 346.4443 -288.653225) (xy 346.437509 -288.68291) (xy 346.439767 -288.713279) (xy 346.450875 -288.741633)
			(xy 346.469846 -288.765454) (xy 346.494994 -288.782628) (xy 346.524086 -288.791627) (xy 346.539312 -288.792158)
			(xy 346.696538 -288.792158) (xy 346.710762 -288.764726) (xy 346.723077 -288.742186) (xy 346.753614 -288.700891)
			(xy 346.790191 -288.664836) (xy 346.83192 -288.634895) (xy 346.87779 -288.611793) (xy 346.926691 -288.59609)
			(xy 346.977436 -288.588167) (xy 347.003116 -288.587688) (xy 347.028793 -288.588165) (xy 347.079531 -288.596103)
			(xy 347.128422 -288.611817) (xy 347.174283 -288.634925) (xy 347.216005 -288.664869) (xy 347.252575 -288.700922)
			(xy 347.28311 -288.742213) (xy 347.29547 -288.764726) (xy 347.309694 -288.792158) (xy 347.636338 -288.792158)
			(xy 347.650562 -288.764726) (xy 347.662425 -288.742926) (xy 347.691696 -288.702849) (xy 347.726647 -288.667617)
			(xy 347.766489 -288.638026) (xy 347.810319 -288.614747) (xy 347.857146 -288.598307) (xy 347.881448 -288.593276)
			(xy 347.904308 -288.588958) (xy 348.10954 -288.233866) (xy 348.101666 -288.211768) (xy 348.093044 -288.185419)
			(xy 348.083727 -288.130773) (xy 348.083124 -288.103056) (xy 348.083632 -288.077149) (xy 348.091738 -288.025972)
			(xy 348.10775 -287.976693) (xy 348.131273 -287.930526) (xy 348.161729 -287.888607) (xy 348.198367 -287.851969)
			(xy 348.240286 -287.821513) (xy 348.286453 -287.79799) (xy 348.335732 -287.781978) (xy 348.386909 -287.773872)
			(xy 348.438723 -287.773872) (xy 348.4899 -287.781978) (xy 348.539179 -287.79799) (xy 348.585346 -287.821513)
			(xy 348.627265 -287.851969) (xy 348.663903 -287.888607) (xy 348.694359 -287.930526) (xy 348.717882 -287.976693)
			(xy 348.733894 -288.025972) (xy 348.742 -288.077149) (xy 348.742508 -288.103056) (xy 348.742046 -288.128406)
			(xy 348.734289 -288.178508) (xy 348.718952 -288.226832) (xy 348.696396 -288.272238) (xy 348.667153 -288.313654)
			(xy 348.631913 -288.350104) (xy 348.591507 -288.380727) (xy 348.546889 -288.404803) (xy 348.49911 -288.421762)
			(xy 348.474284 -288.426906) (xy 348.451424 -288.431224) (xy 348.331028 -288.639758) (xy 348.3239 -288.653225)
			(xy 348.317109 -288.68291) (xy 348.319367 -288.713279) (xy 348.330475 -288.741633) (xy 348.349446 -288.765454)
			(xy 348.374594 -288.782628) (xy 348.403686 -288.791627) (xy 348.418912 -288.792158) (xy 348.576138 -288.792158)
			(xy 348.590362 -288.764726) (xy 348.602677 -288.742186) (xy 348.633214 -288.700891) (xy 348.669791 -288.664836)
			(xy 348.71152 -288.634895) (xy 348.75739 -288.611793) (xy 348.806291 -288.59609) (xy 348.857036 -288.588167)
			(xy 348.882716 -288.587688) (xy 348.908393 -288.588165) (xy 348.959131 -288.596103) (xy 349.008022 -288.611817)
			(xy 349.053883 -288.634925) (xy 349.095605 -288.664869) (xy 349.132175 -288.700922) (xy 349.16271 -288.742213)
			(xy 349.17507 -288.764726) (xy 349.189294 -288.792158) (xy 349.515938 -288.792158) (xy 349.530162 -288.764726)
			(xy 349.542025 -288.742926) (xy 349.571296 -288.702849) (xy 349.606247 -288.667617) (xy 349.646089 -288.638026)
			(xy 349.689919 -288.614747) (xy 349.736746 -288.598307) (xy 349.761048 -288.593276) (xy 349.783908 -288.588958)
			(xy 349.98914 -288.233866) (xy 349.981266 -288.211768) (xy 349.972644 -288.185419) (xy 349.963327 -288.130773)
			(xy 349.962724 -288.103056) (xy 349.963232 -288.077149) (xy 349.971338 -288.025972) (xy 349.98735 -287.976693)
			(xy 350.010873 -287.930526) (xy 350.041329 -287.888607) (xy 350.077967 -287.851969) (xy 350.119886 -287.821513)
			(xy 350.166053 -287.79799) (xy 350.215332 -287.781978) (xy 350.266509 -287.773872) (xy 350.318323 -287.773872)
			(xy 350.3695 -287.781978) (xy 350.418779 -287.79799) (xy 350.464946 -287.821513) (xy 350.506865 -287.851969)
			(xy 350.543503 -287.888607) (xy 350.573959 -287.930526) (xy 350.597482 -287.976693) (xy 350.613494 -288.025972)
			(xy 350.6216 -288.077149) (xy 350.622108 -288.103056) (xy 350.621646 -288.128406) (xy 350.613889 -288.178508)
			(xy 350.598552 -288.226832) (xy 350.575996 -288.272238) (xy 350.546753 -288.313654) (xy 350.511513 -288.350104)
			(xy 350.471107 -288.380727) (xy 350.426489 -288.404803) (xy 350.37871 -288.421762) (xy 350.353884 -288.426906)
			(xy 350.331024 -288.431224) (xy 350.210628 -288.639758) (xy 350.2035 -288.653225) (xy 350.196709 -288.68291)
			(xy 350.198967 -288.713279) (xy 350.210075 -288.741633) (xy 350.229046 -288.765454) (xy 350.254194 -288.782628)
			(xy 350.283286 -288.791627) (xy 350.298512 -288.792158) (xy 350.455738 -288.792158) (xy 350.469962 -288.764726)
			(xy 350.482277 -288.742186) (xy 350.512814 -288.700891) (xy 350.549391 -288.664836) (xy 350.59112 -288.634895)
			(xy 350.63699 -288.611793) (xy 350.685891 -288.59609) (xy 350.736636 -288.588167) (xy 350.762316 -288.587688)
			(xy 350.787993 -288.588165) (xy 350.838731 -288.596103) (xy 350.887622 -288.611817) (xy 350.933483 -288.634925)
			(xy 350.975205 -288.664869) (xy 351.011775 -288.700922) (xy 351.04231 -288.742213) (xy 351.05467 -288.764726)
			(xy 351.068894 -288.792158) (xy 351.323148 -288.792158) (xy 351.85096 -288.264346) (xy 351.86874 -288.233866)
			(xy 351.860866 -288.211768) (xy 351.852244 -288.185419) (xy 351.842927 -288.130773) (xy 351.842324 -288.103056)
			(xy 351.842813 -288.077) (xy 351.851006 -288.025536) (xy 351.867194 -287.976003) (xy 351.890976 -287.929634)
			(xy 351.921759 -287.887585) (xy 351.958775 -287.850905) (xy 352.001103 -287.820507) (xy 352.024188 -287.808416)
			(xy 352.052128 -287.794446) (xy 352.052128 -286.78251) (xy 352.024188 -286.76854) (xy 352.001272 -286.756454)
			(xy 351.959236 -286.726174) (xy 351.922479 -286.689666) (xy 351.891913 -286.647837) (xy 351.868299 -286.601726)
			(xy 351.852222 -286.552477) (xy 351.844081 -286.501314) (xy 351.844079 -286.449508) (xy 351.852217 -286.398344)
			(xy 351.86829 -286.349094) (xy 351.891902 -286.302981) (xy 351.922465 -286.26115) (xy 351.959219 -286.22464)
			(xy 352.001253 -286.194357) (xy 352.024188 -286.182308) (xy 352.052128 -286.168338) (xy 352.052128 -286.013652)
			(xy 352.051649 -285.999744) (xy 352.044136 -285.972962) (xy 352.02968 -285.949197) (xy 352.009352 -285.930209)
			(xy 351.984658 -285.917406) (xy 351.957425 -285.911736) (xy 351.929673 -285.913618) (xy 351.903456 -285.922913)
			(xy 351.891854 -285.930594) (xy 351.870886 -285.9448) (xy 351.825513 -285.967299) (xy 351.777234 -285.982601)
			(xy 351.727185 -285.990348) (xy 351.701862 -285.990792) (xy 351.675976 -285.990308) (xy 351.624842 -285.982203)
			(xy 351.575605 -285.966198) (xy 351.529478 -285.942689) (xy 351.487597 -285.912252) (xy 351.450993 -285.875639)
			(xy 351.420568 -285.83375) (xy 351.397069 -285.787617) (xy 351.381077 -285.738377) (xy 351.372985 -285.68724)
			(xy 351.372424 -285.661354) (xy 351.372884 -285.636016) (xy 351.38063 -285.585936) (xy 351.395949 -285.537631)
			(xy 351.418479 -285.492239) (xy 351.44769 -285.450829) (xy 351.482893 -285.414377) (xy 351.52326 -285.383742)
			(xy 351.567839 -285.359644) (xy 351.615581 -285.342651) (xy 351.640394 -285.337504) (xy 351.663254 -285.333186)
			(xy 351.868486 -284.97784) (xy 351.860866 -284.955996) (xy 351.852258 -284.929709) (xy 351.842937 -284.875191)
			(xy 351.842324 -284.847538) (xy 351.842815 -284.821483) (xy 351.851009 -284.770021) (xy 351.8672 -284.720489)
			(xy 351.890983 -284.674123) (xy 351.921767 -284.632077) (xy 351.958783 -284.595399) (xy 352.00111 -284.565003)
			(xy 352.024188 -284.552898) (xy 352.052128 -284.538928) (xy 352.052128 -283.765498) (xy 352.0527 -283.740538)
			(xy 352.06244 -283.691577) (xy 352.081546 -283.645457) (xy 352.109283 -283.603952) (xy 352.12655 -283.58592)
			(xy 353.255072 -282.457398) (xy 353.25304 -282.433776) (xy 353.252024 -282.405836) (xy 353.252529 -282.37994)
			(xy 353.260622 -282.328784) (xy 353.276615 -282.279524) (xy 353.300115 -282.23337) (xy 353.330542 -282.191458)
			(xy 353.36715 -282.154821) (xy 353.409036 -282.124358) (xy 353.45517 -282.10082) (xy 353.504417 -282.084786)
			(xy 353.555566 -282.07665) (xy 353.581462 -282.076144) (xy 353.609402 -282.077414) (xy 353.633024 -282.079446)
			(xy 353.817174 -281.895296) (xy 353.823854 -281.887884) (xy 353.831444 -281.869454) (xy 353.831439 -281.849521)
			(xy 353.82384 -281.831094) (xy 353.817174 -281.823668) (xy 353.799439 -281.80505) (xy 353.769386 -281.763332)
			(xy 353.746182 -281.71745) (xy 353.730391 -281.668519) (xy 353.722396 -281.617728) (xy 353.721924 -281.59202)
			(xy 353.722404 -281.56611) (xy 353.730508 -281.514928) (xy 353.746519 -281.465643) (xy 353.770044 -281.419471)
			(xy 353.800502 -281.377547) (xy 353.837144 -281.340905) (xy 353.879067 -281.310446) (xy 353.92524 -281.286921)
			(xy 353.974524 -281.270909) (xy 354.025706 -281.262804) (xy 354.051616 -281.262328) (xy 354.07732 -281.262843)
			(xy 354.128101 -281.270859) (xy 354.177025 -281.28665) (xy 354.22291 -281.309832) (xy 354.264648 -281.339847)
			(xy 354.283264 -281.357578) (xy 354.290676 -281.364262) (xy 354.309109 -281.371859) (xy 354.329047 -281.371859)
			(xy 354.34748 -281.364262) (xy 354.354892 -281.357578) (xy 354.454206 -281.258264) (xy 354.464285 -281.247476)
			(xy 354.478315 -281.221514) (xy 354.484345 -281.192626) (xy 354.481872 -281.163219) (xy 354.471103 -281.135744)
			(xy 354.452934 -281.11249) (xy 354.42888 -281.095393) (xy 354.41509 -281.090116) (xy 354.391813 -281.08175)
			(xy 354.347875 -281.059035) (xy 354.307824 -281.03001) (xy 354.27256 -280.995327) (xy 354.257356 -280.975816)
			(xy 353.845368 -280.975816) (xy 353.829693 -280.995949) (xy 353.793182 -281.031588) (xy 353.751616 -281.061176)
			(xy 353.705987 -281.084006) (xy 353.657386 -281.099535) (xy 353.606973 -281.107389) (xy 353.581462 -281.107896)
			(xy 353.555556 -281.107385) (xy 353.504384 -281.099274) (xy 353.455109 -281.083259) (xy 353.408947 -281.059734)
			(xy 353.367033 -281.029277) (xy 353.330399 -280.992638) (xy 353.299947 -280.950721) (xy 353.276426 -280.904555)
			(xy 353.260417 -280.855279) (xy 353.252312 -280.804106) (xy 353.252312 -280.752294) (xy 353.260417 -280.701121)
			(xy 353.276426 -280.651845) (xy 353.299947 -280.605679) (xy 353.330399 -280.563762) (xy 353.367033 -280.527123)
			(xy 353.408947 -280.496666) (xy 353.455109 -280.473141) (xy 353.504384 -280.457126) (xy 353.555556 -280.449015)
			(xy 353.581462 -280.448512) (xy 353.606975 -280.448987) (xy 353.657393 -280.456843) (xy 353.705999 -280.472373)
			(xy 353.751631 -280.495206) (xy 353.793201 -280.524797) (xy 353.829715 -280.56044) (xy 353.845368 -280.580592)
			(xy 354.257356 -280.580592) (xy 354.273028 -280.560454) (xy 354.309537 -280.524806) (xy 354.351102 -280.495208)
			(xy 354.39673 -280.472366) (xy 354.445333 -280.456827) (xy 354.495749 -280.44896) (xy 354.521262 -280.448512)
			(xy 354.546879 -280.448996) (xy 354.597495 -280.456922) (xy 354.646274 -280.472591) (xy 354.692039 -280.495622)
			(xy 354.733685 -280.525462) (xy 354.77021 -280.56139) (xy 354.80073 -280.60254) (xy 354.824512 -280.64792)
			(xy 354.833174 -280.672032) (xy 354.838398 -280.685846) (xy 354.855496 -280.709912) (xy 354.878759 -280.728088)
			(xy 354.906246 -280.738858) (xy 354.935665 -280.741322) (xy 354.964561 -280.735277) (xy 354.990524 -280.721225)
			(xy 355.001322 -280.711148) (xy 355.625146 -280.087324) (xy 355.61651 -280.058114) (xy 355.61009 -280.035152)
			(xy 355.603203 -279.987973) (xy 355.602794 -279.964134) (xy 355.603288 -279.938123) (xy 355.611487 -279.88675)
			(xy 355.627684 -279.837314) (xy 355.651476 -279.79105) (xy 355.682266 -279.749118) (xy 355.719283 -279.712566)
			(xy 355.761602 -279.682309) (xy 355.784658 -279.670256) (xy 355.812852 -279.656286) (xy 355.812852 -278.64562)
			(xy 355.784658 -278.63165) (xy 355.761456 -278.619586) (xy 355.718864 -278.589247) (xy 355.681599 -278.552561)
			(xy 355.650599 -278.510448) (xy 355.62664 -278.463967) (xy 355.610325 -278.414284) (xy 355.602064 -278.362648)
			(xy 355.601524 -278.336502) (xy 355.602112 -278.308784) (xy 355.611428 -278.254135) (xy 355.620066 -278.22779)
			(xy 355.62794 -278.205692) (xy 355.422962 -277.8506) (xy 355.399848 -277.846282) (xy 355.375034 -277.841096)
			(xy 355.327268 -277.824125) (xy 355.282661 -277.800045) (xy 355.242265 -277.769422) (xy 355.20703 -277.732979)
			(xy 355.177787 -277.691573) (xy 355.155225 -277.64618) (xy 355.139874 -277.597869) (xy 355.132097 -277.547777)
			(xy 355.131624 -277.522432) (xy 355.132129 -277.496536) (xy 355.140223 -277.445381) (xy 355.156216 -277.396121)
			(xy 355.179716 -277.349967) (xy 355.210144 -277.308057) (xy 355.246751 -277.27142) (xy 355.288637 -277.240957)
			(xy 355.334771 -277.21742) (xy 355.384018 -277.201386) (xy 355.435167 -277.19325) (xy 355.461062 -277.19274)
			(xy 355.486585 -277.193217) (xy 355.53702 -277.201087) (xy 355.585638 -277.216643) (xy 355.631273 -277.239514)
			(xy 355.652324 -277.253954) (xy 355.663908 -277.261668) (xy 355.690091 -277.271077) (xy 355.717842 -277.273067)
			(xy 355.7451 -277.26749) (xy 355.769839 -277.25476) (xy 355.790223 -277.235824) (xy 355.804737 -277.212088)
			(xy 355.812302 -277.185314) (xy 355.812852 -277.171404) (xy 355.812852 -277.01621) (xy 355.784658 -277.00224)
			(xy 355.761628 -276.990194) (xy 355.719366 -276.959948) (xy 355.682399 -276.92342) (xy 355.651651 -276.881522)
			(xy 355.62789 -276.835301) (xy 355.611712 -276.785913) (xy 355.60352 -276.734592) (xy 355.603519 -276.682622)
			(xy 355.611709 -276.631301) (xy 355.627885 -276.581912) (xy 355.651643 -276.535691) (xy 355.682389 -276.493791)
			(xy 355.719355 -276.457261) (xy 355.761616 -276.427013) (xy 355.784658 -276.414992) (xy 355.812852 -276.401022)
			(xy 355.812852 -276.245828) (xy 355.812385 -276.231912) (xy 355.804802 -276.205131) (xy 355.790272 -276.181391)
			(xy 355.769875 -276.162452) (xy 355.745123 -276.149721) (xy 355.717854 -276.144142) (xy 355.690091 -276.146129)
			(xy 355.663895 -276.155535) (xy 355.652324 -276.163278) (xy 355.631266 -276.177707) (xy 355.585633 -276.200582)
			(xy 355.537018 -276.216147) (xy 355.486585 -276.224028) (xy 355.461062 -276.224492) (xy 355.435551 -276.224012)
			(xy 355.38514 -276.216146) (xy 355.336542 -276.200608) (xy 355.290918 -276.177769) (xy 355.249357 -276.148173)
			(xy 355.212852 -276.112529) (xy 355.197156 -276.092412) (xy 354.785168 -276.092412) (xy 354.769494 -276.112545)
			(xy 354.732982 -276.148184) (xy 354.691416 -276.177773) (xy 354.645788 -276.200604) (xy 354.597186 -276.216132)
			(xy 354.546773 -276.223987) (xy 354.521262 -276.224492) (xy 354.495357 -276.223981) (xy 354.444185 -276.21587)
			(xy 354.394911 -276.199855) (xy 354.348749 -276.17633) (xy 354.306835 -276.145874) (xy 354.270202 -276.109236)
			(xy 354.23975 -276.067318) (xy 354.21623 -276.021154) (xy 354.200221 -275.971878) (xy 354.192116 -275.920705)
			(xy 354.192116 -275.868895) (xy 354.200221 -275.817722) (xy 354.21623 -275.768446) (xy 354.23975 -275.722282)
			(xy 354.270202 -275.680364) (xy 354.306835 -275.643726) (xy 354.348749 -275.61327) (xy 354.394911 -275.589745)
			(xy 354.444185 -275.57373) (xy 354.495357 -275.565619) (xy 354.521262 -275.565108) (xy 354.546775 -275.565583)
			(xy 354.597193 -275.573438) (xy 354.645799 -275.588968) (xy 354.691432 -275.611801) (xy 354.733002 -275.641392)
			(xy 354.769516 -275.677035) (xy 354.785168 -275.697188) (xy 355.197156 -275.697188) (xy 355.212829 -275.677051)
			(xy 355.249337 -275.641403) (xy 355.290902 -275.611805) (xy 355.336531 -275.588964) (xy 355.385133 -275.573424)
			(xy 355.435549 -275.565557) (xy 355.461062 -275.565108) (xy 355.486585 -275.565584) (xy 355.537021 -275.573453)
			(xy 355.585639 -275.589009) (xy 355.631276 -275.611878) (xy 355.652324 -275.626322) (xy 355.663907 -275.634038)
			(xy 355.690088 -275.643449) (xy 355.717838 -275.645441) (xy 355.745095 -275.639864) (xy 355.769832 -275.627133)
			(xy 355.790213 -275.608195) (xy 355.804722 -275.584457) (xy 355.812281 -275.557682) (xy 355.812852 -275.543772)
			(xy 355.812852 -275.389848) (xy 355.784658 -275.375878) (xy 355.761453 -275.363814) (xy 355.718857 -275.333474)
			(xy 355.681588 -275.296786) (xy 355.650583 -275.254671) (xy 355.626621 -275.208187) (xy 355.610303 -275.158502)
			(xy 355.602039 -275.106862) (xy 355.602037 -275.054565) (xy 355.610297 -275.002924) (xy 355.626611 -274.953237)
			(xy 355.650569 -274.906751) (xy 355.681571 -274.864634) (xy 355.718836 -274.827943) (xy 355.761431 -274.7976)
			(xy 355.784658 -274.785582) (xy 355.812852 -274.771612) (xy 355.812852 -273.760692) (xy 355.784658 -273.746722)
			(xy 355.76163 -273.734676) (xy 355.71937 -273.704431) (xy 355.682405 -273.667903) (xy 355.65166 -273.626006)
			(xy 355.627902 -273.579787) (xy 355.611726 -273.530401) (xy 355.603535 -273.479083) (xy 355.603536 -273.427115)
			(xy 355.611726 -273.375797) (xy 355.627903 -273.326411) (xy 355.651661 -273.280192) (xy 355.682407 -273.238295)
			(xy 355.719371 -273.201768) (xy 355.761631 -273.171523) (xy 355.784658 -273.159474) (xy 355.812852 -273.145504)
			(xy 355.812852 -272.132806) (xy 355.784658 -272.118836) (xy 355.761629 -272.10679) (xy 355.719367 -272.076545)
			(xy 355.6824 -272.040016) (xy 355.651653 -271.998118) (xy 355.627893 -271.951898) (xy 355.611715 -271.90251)
			(xy 355.603523 -271.85119) (xy 355.603523 -271.79922) (xy 355.611713 -271.7479) (xy 355.627889 -271.698512)
			(xy 355.651647 -271.652291) (xy 355.682393 -271.610392) (xy 355.719359 -271.573862) (xy 355.761619 -271.543615)
			(xy 355.784658 -271.531588) (xy 355.812852 -271.517618) (xy 355.812852 -270.505174) (xy 355.784658 -270.491204)
			(xy 355.761631 -270.479158) (xy 355.719374 -270.448913) (xy 355.682412 -270.412387) (xy 355.651669 -270.370491)
			(xy 355.627914 -270.324274) (xy 355.61174 -270.27489) (xy 355.603551 -270.223574) (xy 355.603552 -270.171608)
			(xy 355.611744 -270.120293) (xy 355.627921 -270.07091) (xy 355.651679 -270.024694) (xy 355.682424 -269.9828)
			(xy 355.719388 -269.946275) (xy 355.761646 -269.916033) (xy 355.784658 -269.903956) (xy 355.812852 -269.889986)
			(xy 355.812852 -268.877288) (xy 355.784658 -268.863318) (xy 355.76163 -268.851272) (xy 355.719371 -268.821027)
			(xy 355.682407 -268.7845) (xy 355.651662 -268.742603) (xy 355.627905 -268.696384) (xy 355.611729 -268.646999)
			(xy 355.603539 -268.595681) (xy 355.603539 -268.543714) (xy 355.61173 -268.492396) (xy 355.627907 -268.443011)
			(xy 355.651665 -268.396793) (xy 355.682411 -268.354896) (xy 355.719375 -268.318369) (xy 355.761635 -268.288125)
			(xy 355.784658 -268.27607) (xy 355.812852 -268.2621) (xy 355.812852 -267.249402) (xy 355.784658 -267.235432)
			(xy 355.761629 -267.223386) (xy 355.719368 -267.193141) (xy 355.682402 -267.156613) (xy 355.651655 -267.114715)
			(xy 355.627896 -267.068495) (xy 355.611718 -267.019108) (xy 355.603527 -266.967788) (xy 355.603526 -266.915819)
			(xy 355.611717 -266.864499) (xy 355.627893 -266.815112) (xy 355.651651 -266.768891) (xy 355.682397 -266.726993)
			(xy 355.719362 -266.690464) (xy 355.761623 -266.660218) (xy 355.784658 -266.648184) (xy 355.812852 -266.634214)
			(xy 355.812852 -265.62177) (xy 355.784658 -265.6078) (xy 355.761631 -265.595754) (xy 355.719375 -265.56551)
			(xy 355.682414 -265.528983) (xy 355.651672 -265.487088) (xy 355.627917 -265.440871) (xy 355.611743 -265.391487)
			(xy 355.603554 -265.340172) (xy 355.603556 -265.288207) (xy 355.611748 -265.236892) (xy 355.627925 -265.18751)
			(xy 355.651683 -265.141294) (xy 355.682428 -265.099401) (xy 355.719392 -265.062877) (xy 355.76165 -265.032635)
			(xy 355.784658 -265.020552) (xy 355.812852 -265.006582) (xy 355.812852 -264.921746) (xy 355.657404 -264.766298)
			(xy 355.623876 -264.785602) (xy 355.598934 -264.799105) (xy 355.545553 -264.818259) (xy 355.489673 -264.827947)
			(xy 355.461316 -264.828528) (xy 355.435527 -264.828049) (xy 355.384583 -264.819982) (xy 355.335529 -264.804044)
			(xy 355.289572 -264.780628) (xy 355.247844 -264.75031) (xy 355.211374 -264.713837) (xy 355.181059 -264.672108)
			(xy 355.157646 -264.626149) (xy 355.141712 -264.577094) (xy 355.133649 -264.526149) (xy 355.133148 -264.50036)
			(xy 355.133722 -264.472002) (xy 355.143416 -264.416122) (xy 355.16256 -264.362737) (xy 355.176074 -264.3378)
			(xy 355.195378 -264.304272) (xy 354.675186 -263.78408) (xy 354.657923 -263.76604) (xy 354.630159 -263.724548)
			(xy 354.611039 -263.67843) (xy 354.601301 -263.629464) (xy 354.600764 -263.604502) (xy 354.600764 -262.11784)
			(xy 354.601381 -262.092885) (xy 354.611127 -262.043937) (xy 354.630234 -261.997829) (xy 354.657967 -261.956334)
			(xy 354.675186 -261.938262) (xy 355.00945 -261.603998) (xy 355.02749 -261.586736) (xy 355.068983 -261.558976)
			(xy 355.115101 -261.53986) (xy 355.164066 -261.530127) (xy 355.189028 -261.529576) (xy 355.391974 -261.529576)
			(xy 355.583744 -261.337806) (xy 355.583744 -261.187946) (xy 355.463856 -261.068058) (xy 353.511358 -261.068058)
			(xy 353.486399 -261.067483) (xy 353.437443 -261.057735) (xy 353.39133 -261.038624) (xy 353.349831 -261.010882)
			(xy 353.33178 -260.993636) (xy 353.2378 -260.899656) (xy 352.93935 -260.899656) (xy 352.907854 -260.931406)
			(xy 352.900996 -260.937756) (xy 352.899218 -260.939026) (xy 352.479864 -261.358634) (xy 352.479864 -261.797546)
			(xy 352.498768 -261.80907) (xy 352.532626 -261.837589) (xy 352.561029 -261.871545) (xy 352.583117 -261.909909)
			(xy 352.598221 -261.951521) (xy 352.605884 -261.995122) (xy 352.606356 -262.017256) (xy 352.606356 -266.335256)
			(xy 352.605779 -266.360214) (xy 352.59603 -266.409169) (xy 352.576916 -266.45528) (xy 352.549173 -266.496777)
			(xy 352.531934 -266.514834) (xy 350.830134 -268.216634) (xy 350.812093 -268.233893) (xy 350.770599 -268.261647)
			(xy 350.72448 -268.280757) (xy 350.675517 -268.290486) (xy 350.650556 -268.291056) (xy 344.579956 -268.291056)
			(xy 344.554998 -268.29048) (xy 344.506042 -268.280733) (xy 344.459928 -268.261621) (xy 344.41843 -268.233879)
			(xy 344.400378 -268.216634) (xy 344.259916 -268.076172) (xy 344.234262 -268.079982) (xy 344.221646 -268.081867)
			(xy 344.196217 -268.083902) (xy 344.183462 -268.084046) (xy 344.157677 -268.083537) (xy 344.106743 -268.075464)
			(xy 344.057698 -268.059523) (xy 344.011751 -268.036106) (xy 343.970033 -268.00579) (xy 343.933571 -267.969321)
			(xy 343.903262 -267.927597) (xy 343.879854 -267.881646) (xy 343.863922 -267.832599) (xy 343.855858 -267.781663)
			(xy 343.855294 -267.755878) (xy 343.855448 -267.743123) (xy 343.857481 -267.717695) (xy 343.859358 -267.705078)
			(xy 343.863168 -267.679424) (xy 341.826596 -265.642852) (xy 341.8078 -265.641328) (xy 341.782206 -265.638761)
			(xy 341.732211 -265.626676) (xy 341.684713 -265.60694) (xy 341.640875 -265.580036) (xy 341.601772 -265.546622)
			(xy 341.568359 -265.507518) (xy 341.541456 -265.463679) (xy 341.521721 -265.416181) (xy 341.509638 -265.366185)
			(xy 341.507064 -265.340592) (xy 341.50554 -265.321796) (xy 340.142068 -263.958324) (xy 340.109048 -263.976104)
			(xy 340.085712 -263.987972) (xy 340.036194 -264.004962) (xy 339.984608 -264.013876) (xy 339.932261 -264.014488)
			(xy 339.88048 -264.006784) (xy 339.830578 -263.990957) (xy 339.783822 -263.96741) (xy 339.741396 -263.936739)
			(xy 339.704377 -263.899723) (xy 339.673703 -263.857299) (xy 339.650152 -263.810545) (xy 339.634322 -263.760645)
			(xy 339.626613 -263.708864) (xy 339.627222 -263.656517) (xy 339.636132 -263.60493) (xy 339.653118 -263.555411)
			(xy 339.665056 -263.532112) (xy 339.682836 -263.499092) (xy 339.360002 -263.176258) (xy 339.351366 -263.172448)
			(xy 339.329465 -263.162258) (xy 339.288665 -263.136402) (xy 339.252096 -263.104844) (xy 339.220548 -263.068267)
			(xy 339.194702 -263.02746) (xy 339.184488 -263.00557) (xy 339.180678 -262.996934) (xy 337.73237 -261.548626)
			(xy 337.70316 -261.558024) (xy 337.679194 -261.565042) (xy 337.62983 -261.572574) (xy 337.604862 -261.57301)
			(xy 337.579075 -261.572502) (xy 337.528137 -261.564429) (xy 337.479089 -261.548488) (xy 337.433137 -261.525073)
			(xy 337.391414 -261.494757) (xy 337.354945 -261.45829) (xy 337.32463 -261.416566) (xy 337.301213 -261.370615)
			(xy 337.285272 -261.321567) (xy 337.277199 -261.270629) (xy 337.276694 -261.244842) (xy 337.277035 -261.223188)
			(xy 337.282731 -261.180258) (xy 337.294043 -261.138454) (xy 337.302094 -261.11835) (xy 337.288378 -261.104634)
			(xy 337.271119 -261.086593) (xy 337.243363 -261.045099) (xy 337.224252 -260.998981) (xy 337.214523 -260.950017)
			(xy 337.213956 -260.925056) (xy 337.213956 -249.790204) (xy 337.207606 -249.778774) (xy 337.194733 -249.754315)
			(xy 337.176481 -249.702149) (xy 337.167248 -249.647658) (xy 337.166712 -249.620024) (xy 337.167284 -249.592393)
			(xy 337.17653 -249.53791) (xy 337.194749 -249.485738) (xy 337.207606 -249.461274) (xy 337.213956 -249.449844)
			(xy 337.213956 -248.16181) (xy 337.207606 -248.15038) (xy 337.194827 -248.125981) (xy 337.176707 -248.073973)
			(xy 337.167515 -248.019671) (xy 337.16751 -247.964596) (xy 337.17669 -247.910292) (xy 337.1948 -247.85828)
			(xy 337.207606 -247.833896) (xy 337.213956 -247.822466) (xy 337.213956 -246.534686) (xy 337.207606 -246.523256)
			(xy 337.194734 -246.498797) (xy 337.176486 -246.44663) (xy 337.167255 -246.39214) (xy 337.166712 -246.364506)
			(xy 337.167286 -246.336876) (xy 337.176534 -246.282394) (xy 337.194756 -246.230223) (xy 337.207606 -246.205756)
			(xy 337.213956 -246.194326) (xy 337.213956 -244.9068) (xy 337.207606 -244.89537) (xy 337.194733 -244.870911)
			(xy 337.176482 -244.818745) (xy 337.167249 -244.764254) (xy 337.166712 -244.73662) (xy 337.167284 -244.708989)
			(xy 337.176531 -244.654506) (xy 337.194751 -244.602335) (xy 337.207606 -244.57787) (xy 337.213956 -244.56644)
			(xy 337.213956 -243.279168) (xy 337.207606 -243.267738) (xy 337.194736 -243.243279) (xy 337.17649 -243.191112)
			(xy 337.167262 -243.136621) (xy 337.166712 -243.108988) (xy 337.167287 -243.081358) (xy 337.176538 -243.026877)
			(xy 337.194762 -242.974708) (xy 337.207606 -242.950238) (xy 337.213956 -242.938808) (xy 337.213956 -241.651282)
			(xy 337.207606 -241.639852) (xy 337.194734 -241.615393) (xy 337.176486 -241.563226) (xy 337.167257 -241.508736)
			(xy 337.166712 -241.481102) (xy 337.167286 -241.453472) (xy 337.176535 -241.39899) (xy 337.194757 -241.34682)
			(xy 337.207606 -241.322352) (xy 337.213956 -241.310922) (xy 337.213956 -240.023396) (xy 337.207606 -240.011966)
			(xy 337.194733 -239.987507) (xy 337.176483 -239.93534) (xy 337.167251 -239.88085) (xy 337.166712 -239.853216)
			(xy 337.167285 -239.825585) (xy 337.176532 -239.771103) (xy 337.194752 -239.718931) (xy 337.207606 -239.694466)
			(xy 337.213956 -239.683036) (xy 337.213956 -238.395764) (xy 337.207606 -238.384334) (xy 337.194736 -238.359875)
			(xy 337.176491 -238.307707) (xy 337.167264 -238.253217) (xy 337.166712 -238.225584) (xy 337.167287 -238.197954)
			(xy 337.176539 -238.143474) (xy 337.194764 -238.091305) (xy 337.207606 -238.066834) (xy 337.213956 -238.055404)
			(xy 337.213956 -236.768132) (xy 337.207606 -236.756702) (xy 337.194738 -236.732242) (xy 337.176498 -236.680074)
			(xy 337.167277 -236.625585) (xy 337.166712 -236.597952) (xy 337.16729 -236.570323) (xy 337.176547 -236.515845)
			(xy 337.194775 -236.463679) (xy 337.207606 -236.439202) (xy 337.213956 -236.427772) (xy 337.213956 -235.140246)
			(xy 337.207606 -235.128816) (xy 337.194737 -235.104356) (xy 337.176495 -235.052189) (xy 337.167271 -234.997699)
			(xy 337.166712 -234.970066) (xy 337.167289 -234.942436) (xy 337.176544 -234.887957) (xy 337.19477 -234.83579)
			(xy 337.207606 -234.811316) (xy 337.213956 -234.799886) (xy 337.213956 -233.51236) (xy 337.207606 -233.50093)
			(xy 337.194736 -233.476471) (xy 337.176492 -233.424303) (xy 337.167265 -233.369813) (xy 337.166712 -233.34218)
			(xy 337.167288 -233.31455) (xy 337.17654 -233.26007) (xy 337.194765 -233.207902) (xy 337.207606 -233.18343)
			(xy 337.213956 -233.172) (xy 337.213956 -232.578656) (xy 337.214532 -232.553698) (xy 337.22428 -232.504742)
			(xy 337.243392 -232.458629) (xy 337.271135 -232.417132) (xy 337.288378 -232.399078) (xy 338.18068 -231.506776)
			(xy 338.190825 -231.494618) (xy 338.213086 -231.472097) (xy 338.22513 -231.461818) (xy 338.227162 -231.460294)
			(xy 338.619846 -231.06761) (xy 338.605368 -231.035606) (xy 338.596192 -231.014275) (xy 338.583272 -230.969675)
			(xy 338.576784 -230.923696) (xy 338.576412 -230.900478) (xy 338.576919 -230.874691) (xy 338.58499 -230.823752)
			(xy 338.600929 -230.774703) (xy 338.624345 -230.728751) (xy 338.65466 -230.687027) (xy 338.691129 -230.650559)
			(xy 338.732853 -230.620244) (xy 338.778805 -230.596829) (xy 338.827854 -230.58089) (xy 338.878793 -230.572819)
			(xy 338.90458 -230.57231) (xy 338.927795 -230.572701) (xy 338.973766 -230.579212) (xy 339.018366 -230.592122)
			(xy 339.039708 -230.601266) (xy 339.071712 -230.615744) (xy 340.458806 -229.22865) (xy 340.461854 -229.213156)
			(xy 340.46679 -229.188932) (xy 340.482972 -229.14222) (xy 340.50598 -229.098466) (xy 340.535294 -229.05866)
			(xy 340.570249 -229.023703) (xy 340.610054 -228.994387) (xy 340.653807 -228.971377) (xy 340.700519 -228.955193)
			(xy 340.724744 -228.950266) (xy 340.740238 -228.947218) (xy 341.0077 -228.679756) (xy 340.98357 -228.644958)
			(xy 340.969932 -228.624336) (xy 340.948354 -228.579855) (xy 340.933709 -228.532635) (xy 340.926331 -228.48375)
			(xy 340.925912 -228.45903) (xy 340.926389 -228.433238) (xy 340.934454 -228.382289) (xy 340.95039 -228.333229)
			(xy 340.973805 -228.287266) (xy 341.004121 -228.245532) (xy 341.040593 -228.209054) (xy 341.082323 -228.178731)
			(xy 341.128283 -228.155309) (xy 341.17734 -228.139366) (xy 341.228288 -228.131293) (xy 341.25408 -228.130862)
			(xy 341.278797 -228.131312) (xy 341.327672 -228.138719) (xy 341.37489 -228.153354) (xy 341.419386 -228.174888)
			(xy 341.440008 -228.18852) (xy 341.474806 -228.21265) (xy 342.808306 -226.87915) (xy 342.806528 -226.856036)
			(xy 342.805512 -226.831144) (xy 342.805988 -226.805352) (xy 342.814051 -226.754401) (xy 342.829986 -226.705339)
			(xy 342.8534 -226.659374) (xy 342.883716 -226.617637) (xy 342.920189 -226.581158) (xy 342.961919 -226.550833)
			(xy 343.007879 -226.52741) (xy 343.056938 -226.511466) (xy 343.107888 -226.503393) (xy 343.13368 -226.502976)
			(xy 343.158572 -226.503992) (xy 343.181686 -226.50577) (xy 344.605356 -225.0821) (xy 344.605356 -224.891346)
			(xy 344.505026 -224.71761) (xy 344.482166 -224.713292) (xy 344.457365 -224.708093) (xy 344.409627 -224.691103)
			(xy 344.365051 -224.667009) (xy 344.324685 -224.636379) (xy 344.289481 -224.599934) (xy 344.260267 -224.558532)
			(xy 344.23773 -224.513149) (xy 344.222402 -224.464851) (xy 344.214644 -224.414778) (xy 344.214196 -224.389442)
			(xy 344.21474 -224.362368) (xy 344.223586 -224.308948) (xy 344.241047 -224.257694) (xy 344.266653 -224.209983)
			(xy 344.299715 -224.167102) (xy 344.339343 -224.130202) (xy 344.384471 -224.100279) (xy 344.433883 -224.078136)
			(xy 344.486251 -224.064369) (xy 344.513154 -224.061274) (xy 344.528081 -224.059341) (xy 344.555927 -224.047951)
			(xy 344.579254 -224.028953) (xy 344.596046 -224.003991) (xy 344.60485 -223.975223) (xy 344.605356 -223.960182)
			(xy 344.605356 -221.635828) (xy 344.505026 -221.462092) (xy 344.482166 -221.457774) (xy 344.457366 -221.452575)
			(xy 344.409629 -221.435584) (xy 344.365054 -221.41149) (xy 344.32469 -221.38086) (xy 344.289488 -221.344415)
			(xy 344.260275 -221.303013) (xy 344.237741 -221.257629) (xy 344.222416 -221.209332) (xy 344.21466 -221.159259)
			(xy 344.214196 -221.133924) (xy 344.214742 -221.106851) (xy 344.22359 -221.053434) (xy 344.241053 -221.002181)
			(xy 344.26666 -220.954474) (xy 344.299722 -220.911594) (xy 344.339349 -220.874697) (xy 344.384476 -220.844776)
			(xy 344.433887 -220.822634) (xy 344.486254 -220.808869) (xy 344.513154 -220.805756) (xy 344.52808 -220.803822)
			(xy 344.555923 -220.792432) (xy 344.579248 -220.773434) (xy 344.596035 -220.748472) (xy 344.604834 -220.719704)
			(xy 344.605356 -220.704664) (xy 344.605356 -220.597476) (xy 344.500454 -220.492574) (xy 344.48958 -220.482411)
			(xy 344.463385 -220.468308) (xy 344.434236 -220.462356) (xy 344.404609 -220.465059) (xy 344.377019 -220.476188)
			(xy 344.353808 -220.494798) (xy 344.345006 -220.506798) (xy 344.330007 -220.527717) (xy 344.294587 -220.565063)
			(xy 344.25379 -220.596446) (xy 344.208609 -220.621103) (xy 344.160143 -220.638435) (xy 344.134948 -220.643704)
			(xy 344.112088 -220.648022) (xy 343.90711 -221.003114) (xy 343.914984 -221.024958) (xy 343.923564 -221.051377)
			(xy 343.932762 -221.106152) (xy 343.933272 -221.133924) (xy 343.932764 -221.159811) (xy 343.924665 -221.210949)
			(xy 343.908666 -221.260189) (xy 343.88516 -221.306321) (xy 343.854728 -221.348208) (xy 343.818118 -221.384818)
			(xy 343.776231 -221.41525) (xy 343.730099 -221.438756) (xy 343.680859 -221.454755) (xy 343.629721 -221.462854)
			(xy 343.577947 -221.462854) (xy 343.526809 -221.454755) (xy 343.477569 -221.438756) (xy 343.431437 -221.41525)
			(xy 343.38955 -221.384818) (xy 343.35294 -221.348208) (xy 343.322508 -221.306321) (xy 343.299002 -221.260189)
			(xy 343.283003 -221.210949) (xy 343.274904 -221.159811) (xy 343.274396 -221.133924) (xy 343.274858 -221.108587)
			(xy 343.282608 -221.058509) (xy 343.297928 -221.010206) (xy 343.32046 -220.964816) (xy 343.34967 -220.923408)
			(xy 343.384873 -220.886957) (xy 343.425238 -220.856322) (xy 343.469816 -220.832223) (xy 343.517555 -220.815229)
			(xy 343.542366 -220.810074) (xy 343.565226 -220.805756) (xy 343.770204 -220.450664) (xy 343.76233 -220.42882)
			(xy 343.753687 -220.402411) (xy 343.744373 -220.347635) (xy 343.743788 -220.319854) (xy 343.744293 -220.293247)
			(xy 343.752836 -220.240723) (xy 343.769708 -220.190254) (xy 343.79447 -220.143153) (xy 343.826479 -220.100642)
			(xy 343.864904 -220.063828) (xy 343.886536 -220.048328) (xy 343.898463 -220.039458) (xy 343.917009 -220.016249)
			(xy 343.9281 -219.988687) (xy 343.9308 -219.959101) (xy 343.924881 -219.929987) (xy 343.910842 -219.903804)
			(xy 343.90076 -219.89288) (xy 343.787984 -219.780104) (xy 343.754964 -219.797376) (xy 343.731478 -219.808973)
			(xy 343.681738 -219.825385) (xy 343.630023 -219.833691) (xy 343.603834 -219.834206) (xy 343.578044 -219.833703)
			(xy 343.527097 -219.825639) (xy 343.478039 -219.809705) (xy 343.432078 -219.786293) (xy 343.390345 -219.755979)
			(xy 343.353868 -219.71951) (xy 343.323545 -219.677784) (xy 343.300123 -219.631827) (xy 343.284178 -219.582773)
			(xy 343.276103 -219.531828) (xy 343.275666 -219.506038) (xy 343.27618 -219.47985) (xy 343.2845 -219.428139)
			(xy 343.300918 -219.378404) (xy 343.312496 -219.354908) (xy 343.329768 -219.321888) (xy 343.002616 -218.994736)
			(xy 342.994488 -218.990926) (xy 342.968633 -218.978223) (xy 342.921443 -218.94519) (xy 342.880712 -218.904459)
			(xy 342.847678 -218.85727) (xy 342.834976 -218.831414) (xy 342.831166 -218.823286) (xy 342.447118 -218.439238)
			(xy 341.657686 -218.439238) (xy 341.643687 -218.439722) (xy 341.61676 -218.447406) (xy 341.59293 -218.462111)
			(xy 341.573987 -218.482732) (xy 341.561352 -218.50772) (xy 341.555974 -218.5352) (xy 341.558258 -218.563109)
			(xy 341.56269 -218.576398) (xy 341.572538 -218.604335) (xy 341.583153 -218.662607) (xy 341.583772 -218.692222)
			(xy 341.583264 -218.718129) (xy 341.575158 -218.769306) (xy 341.559146 -218.818585) (xy 341.535623 -218.864752)
			(xy 341.505167 -218.906671) (xy 341.468529 -218.943309) (xy 341.42661 -218.973765) (xy 341.380443 -218.997288)
			(xy 341.331164 -219.0133) (xy 341.279987 -219.021406) (xy 341.228173 -219.021406) (xy 341.176996 -219.0133)
			(xy 341.127717 -218.997288) (xy 341.08155 -218.973765) (xy 341.039631 -218.943309) (xy 341.002993 -218.906671)
			(xy 340.972537 -218.864752) (xy 340.949014 -218.818585) (xy 340.933002 -218.769306) (xy 340.924896 -218.718129)
			(xy 340.924388 -218.692222) (xy 340.924975 -218.664503) (xy 340.93429 -218.609854) (xy 340.94293 -218.58351)
			(xy 340.950804 -218.561412) (xy 340.880192 -218.439238) (xy 339.778086 -218.439238) (xy 339.764087 -218.439722)
			(xy 339.73716 -218.447406) (xy 339.71333 -218.462111) (xy 339.694387 -218.482732) (xy 339.681752 -218.50772)
			(xy 339.676374 -218.5352) (xy 339.678658 -218.563109) (xy 339.68309 -218.576398) (xy 339.692938 -218.604335)
			(xy 339.703553 -218.662607) (xy 339.704172 -218.692222) (xy 339.703664 -218.718129) (xy 339.695558 -218.769306)
			(xy 339.679546 -218.818585) (xy 339.656023 -218.864752) (xy 339.625567 -218.906671) (xy 339.588929 -218.943309)
			(xy 339.54701 -218.973765) (xy 339.500843 -218.997288) (xy 339.451564 -219.0133) (xy 339.400387 -219.021406)
			(xy 339.348573 -219.021406) (xy 339.297396 -219.0133) (xy 339.248117 -218.997288) (xy 339.20195 -218.973765)
			(xy 339.160031 -218.943309) (xy 339.123393 -218.906671) (xy 339.092937 -218.864752) (xy 339.069414 -218.818585)
			(xy 339.053402 -218.769306) (xy 339.045296 -218.718129) (xy 339.044788 -218.692222) (xy 339.045375 -218.664503)
			(xy 339.05469 -218.609854) (xy 339.06333 -218.58351) (xy 339.071204 -218.561412) (xy 339.000592 -218.439238)
			(xy 337.898486 -218.439238) (xy 337.884487 -218.439722) (xy 337.85756 -218.447406) (xy 337.83373 -218.462111)
			(xy 337.814787 -218.482732) (xy 337.802152 -218.50772) (xy 337.796774 -218.5352) (xy 337.799058 -218.563109)
			(xy 337.80349 -218.576398) (xy 337.813338 -218.604335) (xy 337.823953 -218.662607) (xy 337.824572 -218.692222)
			(xy 337.824064 -218.718129) (xy 337.815958 -218.769306) (xy 337.799946 -218.818585) (xy 337.776423 -218.864752)
			(xy 337.745967 -218.906671) (xy 337.709329 -218.943309) (xy 337.66741 -218.973765) (xy 337.621243 -218.997288)
			(xy 337.571964 -219.0133) (xy 337.520787 -219.021406) (xy 337.468973 -219.021406) (xy 337.417796 -219.0133)
			(xy 337.368517 -218.997288) (xy 337.32235 -218.973765) (xy 337.280431 -218.943309) (xy 337.243793 -218.906671)
			(xy 337.213337 -218.864752) (xy 337.189814 -218.818585) (xy 337.173802 -218.769306) (xy 337.165696 -218.718129)
			(xy 337.165188 -218.692222) (xy 337.165775 -218.664503) (xy 337.17509 -218.609854) (xy 337.18373 -218.58351)
			(xy 337.191604 -218.561412) (xy 337.120992 -218.439238) (xy 285.287466 -218.439238) (xy 284.8356 -218.891104)
			(xy 284.8356 -221.133924) (xy 336.695796 -221.133924) (xy 336.696304 -221.108037) (xy 336.704403 -221.056899)
			(xy 336.720402 -221.007659) (xy 336.743908 -220.961527) (xy 336.77434 -220.91964) (xy 336.81095 -220.88303)
			(xy 336.852837 -220.852598) (xy 336.898969 -220.829092) (xy 336.948209 -220.813093) (xy 336.999347 -220.804994)
			(xy 337.051121 -220.804994) (xy 337.102259 -220.813093) (xy 337.151499 -220.829092) (xy 337.197631 -220.852598)
			(xy 337.239518 -220.88303) (xy 337.276128 -220.91964) (xy 337.30656 -220.961527) (xy 337.330066 -221.007659)
			(xy 337.346065 -221.056899) (xy 337.354164 -221.108037) (xy 337.354672 -221.133924) (xy 337.635596 -221.133924)
			(xy 337.636104 -221.10859) (xy 337.643853 -221.058519) (xy 337.659172 -221.010223) (xy 337.6817 -220.96484)
			(xy 337.710906 -220.923438) (xy 337.746104 -220.886992) (xy 337.786463 -220.856361) (xy 337.831034 -220.832266)
			(xy 337.878767 -220.815274) (xy 337.903566 -220.810074) (xy 337.926426 -220.805756) (xy 338.131404 -220.450664)
			(xy 338.12353 -220.42882) (xy 338.114896 -220.402408) (xy 338.105568 -220.347635) (xy 338.104988 -220.319854)
			(xy 338.105496 -220.293947) (xy 338.113602 -220.24277) (xy 338.129614 -220.193491) (xy 338.153137 -220.147324)
			(xy 338.183593 -220.105405) (xy 338.220231 -220.068767) (xy 338.26215 -220.038311) (xy 338.308317 -220.014788)
			(xy 338.357596 -219.998776) (xy 338.408773 -219.99067) (xy 338.460587 -219.99067) (xy 338.511764 -219.998776)
			(xy 338.561043 -220.014788) (xy 338.60721 -220.038311) (xy 338.649129 -220.068767) (xy 338.685767 -220.105405)
			(xy 338.716223 -220.147324) (xy 338.739746 -220.193491) (xy 338.755758 -220.24277) (xy 338.763864 -220.293947)
			(xy 338.764372 -220.319854) (xy 338.763922 -220.3452) (xy 338.756142 -220.395293) (xy 338.740788 -220.443604)
			(xy 338.718222 -220.488998) (xy 338.688976 -220.530404) (xy 338.653739 -220.566847) (xy 338.61334 -220.597469)
			(xy 338.568731 -220.621548) (xy 338.520963 -220.638518) (xy 338.496148 -220.643704) (xy 338.473288 -220.648022)
			(xy 338.26831 -221.003114) (xy 338.276184 -221.024958) (xy 338.284777 -221.051373) (xy 338.293965 -221.106151)
			(xy 338.294472 -221.133924) (xy 338.575396 -221.133924) (xy 338.575904 -221.108037) (xy 338.584003 -221.056899)
			(xy 338.600002 -221.007659) (xy 338.623508 -220.961527) (xy 338.65394 -220.91964) (xy 338.69055 -220.88303)
			(xy 338.732437 -220.852598) (xy 338.778569 -220.829092) (xy 338.827809 -220.813093) (xy 338.878947 -220.804994)
			(xy 338.930721 -220.804994) (xy 338.981859 -220.813093) (xy 339.031099 -220.829092) (xy 339.077231 -220.852598)
			(xy 339.119118 -220.88303) (xy 339.155728 -220.91964) (xy 339.18616 -220.961527) (xy 339.209666 -221.007659)
			(xy 339.225665 -221.056899) (xy 339.233764 -221.108037) (xy 339.234272 -221.133924) (xy 339.515196 -221.133924)
			(xy 339.515704 -221.10859) (xy 339.523453 -221.058519) (xy 339.538772 -221.010223) (xy 339.5613 -220.96484)
			(xy 339.590506 -220.923438) (xy 339.625704 -220.886992) (xy 339.666063 -220.856361) (xy 339.710634 -220.832266)
			(xy 339.758367 -220.815274) (xy 339.783166 -220.810074) (xy 339.806026 -220.805756) (xy 340.011004 -220.450664)
			(xy 340.00313 -220.42882) (xy 339.994496 -220.402408) (xy 339.985168 -220.347635) (xy 339.984588 -220.319854)
			(xy 339.985096 -220.293947) (xy 339.993202 -220.24277) (xy 340.009214 -220.193491) (xy 340.032737 -220.147324)
			(xy 340.063193 -220.105405) (xy 340.099831 -220.068767) (xy 340.14175 -220.038311) (xy 340.187917 -220.014788)
			(xy 340.237196 -219.998776) (xy 340.288373 -219.99067) (xy 340.340187 -219.99067) (xy 340.391364 -219.998776)
			(xy 340.440643 -220.014788) (xy 340.48681 -220.038311) (xy 340.528729 -220.068767) (xy 340.565367 -220.105405)
			(xy 340.595823 -220.147324) (xy 340.619346 -220.193491) (xy 340.635358 -220.24277) (xy 340.643464 -220.293947)
			(xy 340.643972 -220.319854) (xy 340.643522 -220.3452) (xy 340.635742 -220.395293) (xy 340.620388 -220.443604)
			(xy 340.597822 -220.488998) (xy 340.568576 -220.530404) (xy 340.533339 -220.566847) (xy 340.49294 -220.597469)
			(xy 340.448331 -220.621548) (xy 340.400563 -220.638518) (xy 340.375748 -220.643704) (xy 340.352888 -220.648022)
			(xy 340.14791 -221.003114) (xy 340.155784 -221.024958) (xy 340.164377 -221.051373) (xy 340.173565 -221.106151)
			(xy 340.174072 -221.133924) (xy 340.454996 -221.133924) (xy 340.455504 -221.108037) (xy 340.463603 -221.056899)
			(xy 340.479602 -221.007659) (xy 340.503108 -220.961527) (xy 340.53354 -220.91964) (xy 340.57015 -220.88303)
			(xy 340.612037 -220.852598) (xy 340.658169 -220.829092) (xy 340.707409 -220.813093) (xy 340.758547 -220.804994)
			(xy 340.810321 -220.804994) (xy 340.861459 -220.813093) (xy 340.910699 -220.829092) (xy 340.956831 -220.852598)
			(xy 340.998718 -220.88303) (xy 341.035328 -220.91964) (xy 341.06576 -220.961527) (xy 341.089266 -221.007659)
			(xy 341.105265 -221.056899) (xy 341.113364 -221.108037) (xy 341.113872 -221.133924) (xy 341.394796 -221.133924)
			(xy 341.395304 -221.10859) (xy 341.403053 -221.058519) (xy 341.418372 -221.010223) (xy 341.4409 -220.96484)
			(xy 341.470106 -220.923438) (xy 341.505304 -220.886992) (xy 341.545663 -220.856361) (xy 341.590234 -220.832266)
			(xy 341.637967 -220.815274) (xy 341.662766 -220.810074) (xy 341.685626 -220.805756) (xy 341.890604 -220.450664)
			(xy 341.88273 -220.42882) (xy 341.874096 -220.402408) (xy 341.864768 -220.347635) (xy 341.864188 -220.319854)
			(xy 341.864696 -220.293947) (xy 341.872802 -220.24277) (xy 341.888814 -220.193491) (xy 341.912337 -220.147324)
			(xy 341.942793 -220.105405) (xy 341.979431 -220.068767) (xy 342.02135 -220.038311) (xy 342.067517 -220.014788)
			(xy 342.116796 -219.998776) (xy 342.167973 -219.99067) (xy 342.219787 -219.99067) (xy 342.270964 -219.998776)
			(xy 342.320243 -220.014788) (xy 342.36641 -220.038311) (xy 342.408329 -220.068767) (xy 342.444967 -220.105405)
			(xy 342.475423 -220.147324) (xy 342.498946 -220.193491) (xy 342.514958 -220.24277) (xy 342.523064 -220.293947)
			(xy 342.523572 -220.319854) (xy 342.523122 -220.3452) (xy 342.515342 -220.395293) (xy 342.499988 -220.443604)
			(xy 342.477422 -220.488998) (xy 342.448176 -220.530404) (xy 342.412939 -220.566847) (xy 342.37254 -220.597469)
			(xy 342.327931 -220.621548) (xy 342.280163 -220.638518) (xy 342.255348 -220.643704) (xy 342.232488 -220.648022)
			(xy 342.02751 -221.003114) (xy 342.035384 -221.024958) (xy 342.043977 -221.051373) (xy 342.053165 -221.106151)
			(xy 342.053672 -221.133924) (xy 342.334596 -221.133924) (xy 342.335104 -221.108037) (xy 342.343203 -221.056899)
			(xy 342.359202 -221.007659) (xy 342.382708 -220.961527) (xy 342.41314 -220.91964) (xy 342.44975 -220.88303)
			(xy 342.491637 -220.852598) (xy 342.537769 -220.829092) (xy 342.587009 -220.813093) (xy 342.638147 -220.804994)
			(xy 342.689921 -220.804994) (xy 342.741059 -220.813093) (xy 342.790299 -220.829092) (xy 342.836431 -220.852598)
			(xy 342.878318 -220.88303) (xy 342.914928 -220.91964) (xy 342.94536 -220.961527) (xy 342.968866 -221.007659)
			(xy 342.984865 -221.056899) (xy 342.992964 -221.108037) (xy 342.993472 -221.133924) (xy 342.992945 -221.161632)
			(xy 342.983748 -221.216279) (xy 342.975184 -221.242636) (xy 342.96731 -221.264734) (xy 343.172288 -221.619572)
			(xy 343.195148 -221.62389) (xy 343.219967 -221.629064) (xy 343.267746 -221.646018) (xy 343.312365 -221.670088)
			(xy 343.352772 -221.700708) (xy 343.388013 -221.737154) (xy 343.417257 -221.778566) (xy 343.439814 -221.823969)
			(xy 343.455152 -221.872291) (xy 343.46291 -221.922391) (xy 343.463372 -221.94774) (xy 343.462864 -221.973647)
			(xy 343.454758 -222.024824) (xy 343.438746 -222.074103) (xy 343.415223 -222.12027) (xy 343.384767 -222.162189)
			(xy 343.348129 -222.198827) (xy 343.30621 -222.229283) (xy 343.260043 -222.252806) (xy 343.210764 -222.268818)
			(xy 343.159587 -222.276924) (xy 343.107773 -222.276924) (xy 343.056596 -222.268818) (xy 343.007317 -222.252806)
			(xy 342.96115 -222.229283) (xy 342.919231 -222.198827) (xy 342.882593 -222.162189) (xy 342.852137 -222.12027)
			(xy 342.828614 -222.074103) (xy 342.812602 -222.024824) (xy 342.804496 -221.973647) (xy 342.803988 -221.94774)
			(xy 342.804592 -221.920023) (xy 342.813909 -221.865377) (xy 342.82253 -221.839028) (xy 342.830404 -221.81693)
			(xy 342.625426 -221.462092) (xy 342.602566 -221.457774) (xy 342.577766 -221.452574) (xy 342.53003 -221.435583)
			(xy 342.485455 -221.411489) (xy 342.445091 -221.380859) (xy 342.409889 -221.344414) (xy 342.380676 -221.303012)
			(xy 342.358142 -221.257629) (xy 342.342817 -221.209332) (xy 342.335061 -221.159259) (xy 342.334596 -221.133924)
			(xy 342.053672 -221.133924) (xy 342.053164 -221.159811) (xy 342.045065 -221.210949) (xy 342.029066 -221.260189)
			(xy 342.00556 -221.306321) (xy 341.975128 -221.348208) (xy 341.938518 -221.384818) (xy 341.896631 -221.41525)
			(xy 341.850499 -221.438756) (xy 341.801259 -221.454755) (xy 341.750121 -221.462854) (xy 341.698347 -221.462854)
			(xy 341.647209 -221.454755) (xy 341.597969 -221.438756) (xy 341.551837 -221.41525) (xy 341.50995 -221.384818)
			(xy 341.47334 -221.348208) (xy 341.442908 -221.306321) (xy 341.419402 -221.260189) (xy 341.403403 -221.210949)
			(xy 341.395304 -221.159811) (xy 341.394796 -221.133924) (xy 341.113872 -221.133924) (xy 341.113345 -221.161632)
			(xy 341.104148 -221.216279) (xy 341.095584 -221.242636) (xy 341.08771 -221.264734) (xy 341.292688 -221.619572)
			(xy 341.315548 -221.62389) (xy 341.340367 -221.629064) (xy 341.388146 -221.646018) (xy 341.432765 -221.670088)
			(xy 341.473172 -221.700708) (xy 341.508413 -221.737154) (xy 341.537657 -221.778566) (xy 341.560214 -221.823969)
			(xy 341.575552 -221.872291) (xy 341.58331 -221.922391) (xy 341.583772 -221.94774) (xy 341.583264 -221.973647)
			(xy 341.575158 -222.024824) (xy 341.559146 -222.074103) (xy 341.535623 -222.12027) (xy 341.505167 -222.162189)
			(xy 341.468529 -222.198827) (xy 341.42661 -222.229283) (xy 341.380443 -222.252806) (xy 341.331164 -222.268818)
			(xy 341.279987 -222.276924) (xy 341.228173 -222.276924) (xy 341.176996 -222.268818) (xy 341.127717 -222.252806)
			(xy 341.08155 -222.229283) (xy 341.039631 -222.198827) (xy 341.002993 -222.162189) (xy 340.972537 -222.12027)
			(xy 340.949014 -222.074103) (xy 340.933002 -222.024824) (xy 340.924896 -221.973647) (xy 340.924388 -221.94774)
			(xy 340.924992 -221.920023) (xy 340.934309 -221.865377) (xy 340.94293 -221.839028) (xy 340.950804 -221.81693)
			(xy 340.745826 -221.462092) (xy 340.722966 -221.457774) (xy 340.698166 -221.452574) (xy 340.65043 -221.435583)
			(xy 340.605855 -221.411489) (xy 340.565491 -221.380859) (xy 340.530289 -221.344414) (xy 340.501076 -221.303012)
			(xy 340.478542 -221.257629) (xy 340.463217 -221.209332) (xy 340.455461 -221.159259) (xy 340.454996 -221.133924)
			(xy 340.174072 -221.133924) (xy 340.173564 -221.159811) (xy 340.165465 -221.210949) (xy 340.149466 -221.260189)
			(xy 340.12596 -221.306321) (xy 340.095528 -221.348208) (xy 340.058918 -221.384818) (xy 340.017031 -221.41525)
			(xy 339.970899 -221.438756) (xy 339.921659 -221.454755) (xy 339.870521 -221.462854) (xy 339.818747 -221.462854)
			(xy 339.767609 -221.454755) (xy 339.718369 -221.438756) (xy 339.672237 -221.41525) (xy 339.63035 -221.384818)
			(xy 339.59374 -221.348208) (xy 339.563308 -221.306321) (xy 339.539802 -221.260189) (xy 339.523803 -221.210949)
			(xy 339.515704 -221.159811) (xy 339.515196 -221.133924) (xy 339.234272 -221.133924) (xy 339.233745 -221.161632)
			(xy 339.224548 -221.216279) (xy 339.215984 -221.242636) (xy 339.20811 -221.264734) (xy 339.413088 -221.619572)
			(xy 339.435948 -221.62389) (xy 339.460767 -221.629064) (xy 339.508546 -221.646018) (xy 339.553165 -221.670088)
			(xy 339.593572 -221.700708) (xy 339.628813 -221.737154) (xy 339.658057 -221.778566) (xy 339.680614 -221.823969)
			(xy 339.695952 -221.872291) (xy 339.70371 -221.922391) (xy 339.704172 -221.94774) (xy 339.703664 -221.973647)
			(xy 339.695558 -222.024824) (xy 339.679546 -222.074103) (xy 339.656023 -222.12027) (xy 339.625567 -222.162189)
			(xy 339.588929 -222.198827) (xy 339.54701 -222.229283) (xy 339.500843 -222.252806) (xy 339.451564 -222.268818)
			(xy 339.400387 -222.276924) (xy 339.348573 -222.276924) (xy 339.297396 -222.268818) (xy 339.248117 -222.252806)
			(xy 339.20195 -222.229283) (xy 339.160031 -222.198827) (xy 339.123393 -222.162189) (xy 339.092937 -222.12027)
			(xy 339.069414 -222.074103) (xy 339.053402 -222.024824) (xy 339.045296 -221.973647) (xy 339.044788 -221.94774)
			(xy 339.045392 -221.920023) (xy 339.054709 -221.865377) (xy 339.06333 -221.839028) (xy 339.071204 -221.81693)
			(xy 338.866226 -221.462092) (xy 338.843366 -221.457774) (xy 338.818566 -221.452574) (xy 338.77083 -221.435583)
			(xy 338.726255 -221.411489) (xy 338.685891 -221.380859) (xy 338.650689 -221.344414) (xy 338.621476 -221.303012)
			(xy 338.598942 -221.257629) (xy 338.583617 -221.209332) (xy 338.575861 -221.159259) (xy 338.575396 -221.133924)
			(xy 338.294472 -221.133924) (xy 338.293964 -221.159811) (xy 338.285865 -221.210949) (xy 338.269866 -221.260189)
			(xy 338.24636 -221.306321) (xy 338.215928 -221.348208) (xy 338.179318 -221.384818) (xy 338.137431 -221.41525)
			(xy 338.091299 -221.438756) (xy 338.042059 -221.454755) (xy 337.990921 -221.462854) (xy 337.939147 -221.462854)
			(xy 337.888009 -221.454755) (xy 337.838769 -221.438756) (xy 337.792637 -221.41525) (xy 337.75075 -221.384818)
			(xy 337.71414 -221.348208) (xy 337.683708 -221.306321) (xy 337.660202 -221.260189) (xy 337.644203 -221.210949)
			(xy 337.636104 -221.159811) (xy 337.635596 -221.133924) (xy 337.354672 -221.133924) (xy 337.354145 -221.161632)
			(xy 337.344948 -221.216279) (xy 337.336384 -221.242636) (xy 337.32851 -221.264734) (xy 337.533488 -221.619572)
			(xy 337.556348 -221.62389) (xy 337.581167 -221.629064) (xy 337.628946 -221.646018) (xy 337.673565 -221.670088)
			(xy 337.713972 -221.700708) (xy 337.749213 -221.737154) (xy 337.778457 -221.778566) (xy 337.801014 -221.823969)
			(xy 337.816352 -221.872291) (xy 337.82411 -221.922391) (xy 337.824572 -221.94774) (xy 337.824064 -221.973647)
			(xy 337.815958 -222.024824) (xy 337.799946 -222.074103) (xy 337.776423 -222.12027) (xy 337.745967 -222.162189)
			(xy 337.709329 -222.198827) (xy 337.66741 -222.229283) (xy 337.621243 -222.252806) (xy 337.571964 -222.268818)
			(xy 337.520787 -222.276924) (xy 337.468973 -222.276924) (xy 337.417796 -222.268818) (xy 337.368517 -222.252806)
			(xy 337.32235 -222.229283) (xy 337.280431 -222.198827) (xy 337.243793 -222.162189) (xy 337.213337 -222.12027)
			(xy 337.189814 -222.074103) (xy 337.173802 -222.024824) (xy 337.165696 -221.973647) (xy 337.165188 -221.94774)
			(xy 337.165792 -221.920023) (xy 337.175109 -221.865377) (xy 337.18373 -221.839028) (xy 337.191604 -221.81693)
			(xy 336.986626 -221.462092) (xy 336.963766 -221.457774) (xy 336.938966 -221.452574) (xy 336.89123 -221.435583)
			(xy 336.846655 -221.411489) (xy 336.806291 -221.380859) (xy 336.771089 -221.344414) (xy 336.741876 -221.303012)
			(xy 336.719342 -221.257629) (xy 336.704017 -221.209332) (xy 336.696261 -221.159259) (xy 336.695796 -221.133924)
			(xy 284.8356 -221.133924) (xy 284.8356 -224.389442) (xy 337.635596 -224.389442) (xy 337.636029 -224.364106)
			(xy 337.64379 -224.314032) (xy 337.65912 -224.265734) (xy 337.681659 -224.22035) (xy 337.710875 -224.178949)
			(xy 337.746081 -224.142504) (xy 337.786448 -224.111874) (xy 337.831026 -224.087781) (xy 337.878765 -224.070791)
			(xy 337.903566 -224.065592) (xy 337.926426 -224.061274) (xy 338.13115 -223.706182) (xy 338.12353 -223.684338)
			(xy 338.114887 -223.657995) (xy 338.105572 -223.603345) (xy 338.104988 -223.575626) (xy 338.105496 -223.549719)
			(xy 338.113602 -223.498542) (xy 338.129614 -223.449263) (xy 338.153137 -223.403096) (xy 338.183593 -223.361177)
			(xy 338.220231 -223.324539) (xy 338.26215 -223.294083) (xy 338.308317 -223.27056) (xy 338.357596 -223.254548)
			(xy 338.408773 -223.246442) (xy 338.460587 -223.246442) (xy 338.511764 -223.254548) (xy 338.561043 -223.27056)
			(xy 338.60721 -223.294083) (xy 338.649129 -223.324539) (xy 338.685767 -223.361177) (xy 338.716223 -223.403096)
			(xy 338.739746 -223.449263) (xy 338.755758 -223.498542) (xy 338.763864 -223.549719) (xy 338.764372 -223.575626)
			(xy 338.763897 -223.600971) (xy 338.756121 -223.651063) (xy 338.740771 -223.699374) (xy 338.718208 -223.744767)
			(xy 338.688966 -223.786173) (xy 338.653731 -223.822617) (xy 338.613335 -223.853239) (xy 338.568728 -223.877319)
			(xy 338.520962 -223.89429) (xy 338.496148 -223.899476) (xy 338.473288 -223.903794) (xy 338.268564 -224.258632)
			(xy 338.276184 -224.280476) (xy 338.284739 -224.306769) (xy 338.293932 -224.361289) (xy 338.294472 -224.388934)
			(xy 338.294472 -224.389442) (xy 338.575396 -224.389442) (xy 338.575904 -224.363555) (xy 338.584003 -224.312417)
			(xy 338.600002 -224.263177) (xy 338.623508 -224.217045) (xy 338.65394 -224.175158) (xy 338.69055 -224.138548)
			(xy 338.732437 -224.108116) (xy 338.778569 -224.08461) (xy 338.827809 -224.068611) (xy 338.878947 -224.060512)
			(xy 338.930721 -224.060512) (xy 338.981859 -224.068611) (xy 339.031099 -224.08461) (xy 339.077231 -224.108116)
			(xy 339.119118 -224.138548) (xy 339.155728 -224.175158) (xy 339.18616 -224.217045) (xy 339.209666 -224.263177)
			(xy 339.225665 -224.312417) (xy 339.233764 -224.363555) (xy 339.234272 -224.389442) (xy 339.515196 -224.389442)
			(xy 339.515629 -224.364106) (xy 339.52339 -224.314032) (xy 339.53872 -224.265734) (xy 339.561259 -224.22035)
			(xy 339.590475 -224.178949) (xy 339.625681 -224.142504) (xy 339.666048 -224.111874) (xy 339.710626 -224.087781)
			(xy 339.758365 -224.070791) (xy 339.783166 -224.065592) (xy 339.806026 -224.061274) (xy 340.01075 -223.706182)
			(xy 340.00313 -223.684338) (xy 339.994487 -223.657995) (xy 339.985172 -223.603345) (xy 339.984588 -223.575626)
			(xy 339.985096 -223.549719) (xy 339.993202 -223.498542) (xy 340.009214 -223.449263) (xy 340.032737 -223.403096)
			(xy 340.063193 -223.361177) (xy 340.099831 -223.324539) (xy 340.14175 -223.294083) (xy 340.187917 -223.27056)
			(xy 340.237196 -223.254548) (xy 340.288373 -223.246442) (xy 340.340187 -223.246442) (xy 340.391364 -223.254548)
			(xy 340.440643 -223.27056) (xy 340.48681 -223.294083) (xy 340.528729 -223.324539) (xy 340.565367 -223.361177)
			(xy 340.595823 -223.403096) (xy 340.619346 -223.449263) (xy 340.635358 -223.498542) (xy 340.643464 -223.549719)
			(xy 340.643972 -223.575626) (xy 340.643497 -223.600971) (xy 340.635721 -223.651063) (xy 340.620371 -223.699374)
			(xy 340.597808 -223.744767) (xy 340.568566 -223.786173) (xy 340.533331 -223.822617) (xy 340.492935 -223.853239)
			(xy 340.448328 -223.877319) (xy 340.400562 -223.89429) (xy 340.375748 -223.899476) (xy 340.352888 -223.903794)
			(xy 340.148164 -224.258632) (xy 340.155784 -224.280476) (xy 340.164339 -224.306769) (xy 340.173532 -224.361289)
			(xy 340.174072 -224.388934) (xy 340.174072 -224.389442) (xy 340.454996 -224.389442) (xy 340.455504 -224.363555)
			(xy 340.463603 -224.312417) (xy 340.479602 -224.263177) (xy 340.503108 -224.217045) (xy 340.53354 -224.175158)
			(xy 340.57015 -224.138548) (xy 340.612037 -224.108116) (xy 340.658169 -224.08461) (xy 340.707409 -224.068611)
			(xy 340.758547 -224.060512) (xy 340.810321 -224.060512) (xy 340.861459 -224.068611) (xy 340.910699 -224.08461)
			(xy 340.956831 -224.108116) (xy 340.998718 -224.138548) (xy 341.035328 -224.175158) (xy 341.06576 -224.217045)
			(xy 341.089266 -224.263177) (xy 341.105265 -224.312417) (xy 341.113364 -224.363555) (xy 341.113872 -224.389442)
			(xy 341.394796 -224.389442) (xy 341.395229 -224.364106) (xy 341.40299 -224.314032) (xy 341.41832 -224.265734)
			(xy 341.440859 -224.22035) (xy 341.470075 -224.178949) (xy 341.505281 -224.142504) (xy 341.545648 -224.111874)
			(xy 341.590226 -224.087781) (xy 341.637965 -224.070791) (xy 341.662766 -224.065592) (xy 341.685626 -224.061274)
			(xy 341.89035 -223.706436) (xy 341.88273 -223.684338) (xy 341.874102 -223.657991) (xy 341.864779 -223.603344)
			(xy 341.864188 -223.575626) (xy 341.864696 -223.549719) (xy 341.872802 -223.498542) (xy 341.888814 -223.449263)
			(xy 341.912337 -223.403096) (xy 341.942793 -223.361177) (xy 341.979431 -223.324539) (xy 342.02135 -223.294083)
			(xy 342.067517 -223.27056) (xy 342.116796 -223.254548) (xy 342.167973 -223.246442) (xy 342.219787 -223.246442)
			(xy 342.270964 -223.254548) (xy 342.320243 -223.27056) (xy 342.36641 -223.294083) (xy 342.408329 -223.324539)
			(xy 342.444967 -223.361177) (xy 342.475423 -223.403096) (xy 342.498946 -223.449263) (xy 342.514958 -223.498542)
			(xy 342.523064 -223.549719) (xy 342.523572 -223.575626) (xy 342.523181 -223.600993) (xy 342.515428 -223.651131)
			(xy 342.500077 -223.699486) (xy 342.477492 -223.744915) (xy 342.448207 -223.786344) (xy 342.412916 -223.822791)
			(xy 342.372452 -223.853396) (xy 342.327774 -223.877433) (xy 342.279939 -223.894334) (xy 342.255094 -223.899476)
			(xy 342.232234 -223.903794) (xy 342.02751 -224.258632) (xy 342.035384 -224.280476) (xy 342.043957 -224.306897)
			(xy 342.053158 -224.36167) (xy 342.053672 -224.389442) (xy 342.334596 -224.389442) (xy 342.335104 -224.363555)
			(xy 342.343203 -224.312417) (xy 342.359202 -224.263177) (xy 342.382708 -224.217045) (xy 342.41314 -224.175158)
			(xy 342.44975 -224.138548) (xy 342.491637 -224.108116) (xy 342.537769 -224.08461) (xy 342.587009 -224.068611)
			(xy 342.638147 -224.060512) (xy 342.689921 -224.060512) (xy 342.741059 -224.068611) (xy 342.790299 -224.08461)
			(xy 342.836431 -224.108116) (xy 342.878318 -224.138548) (xy 342.914928 -224.175158) (xy 342.94536 -224.217045)
			(xy 342.968866 -224.263177) (xy 342.984865 -224.312417) (xy 342.992964 -224.363555) (xy 342.993472 -224.389442)
			(xy 343.274396 -224.389442) (xy 343.274829 -224.364106) (xy 343.28259 -224.314032) (xy 343.29792 -224.265734)
			(xy 343.320459 -224.22035) (xy 343.349675 -224.178949) (xy 343.384881 -224.142504) (xy 343.425248 -224.111874)
			(xy 343.469826 -224.087781) (xy 343.517565 -224.070791) (xy 343.542366 -224.065592) (xy 343.565226 -224.061274)
			(xy 343.76995 -223.706436) (xy 343.76233 -223.684338) (xy 343.753702 -223.657991) (xy 343.744379 -223.603344)
			(xy 343.743788 -223.575626) (xy 343.744296 -223.549719) (xy 343.752402 -223.498542) (xy 343.768414 -223.449263)
			(xy 343.791937 -223.403096) (xy 343.822393 -223.361177) (xy 343.859031 -223.324539) (xy 343.90095 -223.294083)
			(xy 343.947117 -223.27056) (xy 343.996396 -223.254548) (xy 344.047573 -223.246442) (xy 344.099387 -223.246442)
			(xy 344.150564 -223.254548) (xy 344.199843 -223.27056) (xy 344.24601 -223.294083) (xy 344.287929 -223.324539)
			(xy 344.324567 -223.361177) (xy 344.355023 -223.403096) (xy 344.378546 -223.449263) (xy 344.394558 -223.498542)
			(xy 344.402664 -223.549719) (xy 344.403172 -223.575626) (xy 344.402781 -223.600993) (xy 344.395028 -223.651131)
			(xy 344.379677 -223.699486) (xy 344.357092 -223.744915) (xy 344.327807 -223.786344) (xy 344.292516 -223.822791)
			(xy 344.252052 -223.853396) (xy 344.207374 -223.877433) (xy 344.159539 -223.894334) (xy 344.134694 -223.899476)
			(xy 344.111834 -223.903794) (xy 343.90711 -224.258632) (xy 343.914984 -224.280476) (xy 343.923557 -224.306897)
			(xy 343.932758 -224.36167) (xy 343.933272 -224.389442) (xy 343.932764 -224.415329) (xy 343.924665 -224.466467)
			(xy 343.908666 -224.515707) (xy 343.88516 -224.561839) (xy 343.854728 -224.603726) (xy 343.818118 -224.640336)
			(xy 343.776231 -224.670768) (xy 343.730099 -224.694274) (xy 343.680859 -224.710273) (xy 343.629721 -224.718372)
			(xy 343.577947 -224.718372) (xy 343.526809 -224.710273) (xy 343.477569 -224.694274) (xy 343.431437 -224.670768)
			(xy 343.38955 -224.640336) (xy 343.35294 -224.603726) (xy 343.322508 -224.561839) (xy 343.299002 -224.515707)
			(xy 343.283003 -224.466467) (xy 343.274904 -224.415329) (xy 343.274396 -224.389442) (xy 342.993472 -224.389442)
			(xy 342.992925 -224.417149) (xy 342.983741 -224.471796) (xy 342.975184 -224.498154) (xy 342.96731 -224.520252)
			(xy 343.172288 -224.87509) (xy 343.195148 -224.879408) (xy 343.219971 -224.884565) (xy 343.267751 -224.90152)
			(xy 343.312371 -224.925592) (xy 343.352778 -224.956214) (xy 343.388019 -224.992662) (xy 343.417263 -225.034077)
			(xy 343.439819 -225.079482) (xy 343.455156 -225.127806) (xy 343.462911 -225.177908) (xy 343.463372 -225.203258)
			(xy 343.462864 -225.229165) (xy 343.454758 -225.280342) (xy 343.438746 -225.329621) (xy 343.415223 -225.375788)
			(xy 343.384767 -225.417707) (xy 343.348129 -225.454345) (xy 343.30621 -225.484801) (xy 343.260043 -225.508324)
			(xy 343.210764 -225.524336) (xy 343.159587 -225.532442) (xy 343.107773 -225.532442) (xy 343.056596 -225.524336)
			(xy 343.007317 -225.508324) (xy 342.96115 -225.484801) (xy 342.919231 -225.454345) (xy 342.882593 -225.417707)
			(xy 342.852137 -225.375788) (xy 342.828614 -225.329621) (xy 342.812602 -225.280342) (xy 342.804496 -225.229165)
			(xy 342.803988 -225.203258) (xy 342.804597 -225.175541) (xy 342.81391 -225.120895) (xy 342.82253 -225.094546)
			(xy 342.830404 -225.072448) (xy 342.625426 -224.71761) (xy 342.602566 -224.713292) (xy 342.577748 -224.708169)
			(xy 342.530005 -224.691172) (xy 342.485426 -224.667071) (xy 342.44506 -224.636431) (xy 342.409857 -224.599976)
			(xy 342.380648 -224.558564) (xy 342.358119 -224.51317) (xy 342.342801 -224.464863) (xy 342.335055 -224.414781)
			(xy 342.334596 -224.389442) (xy 342.053672 -224.389442) (xy 342.053164 -224.415329) (xy 342.045065 -224.466467)
			(xy 342.029066 -224.515707) (xy 342.00556 -224.561839) (xy 341.975128 -224.603726) (xy 341.938518 -224.640336)
			(xy 341.896631 -224.670768) (xy 341.850499 -224.694274) (xy 341.801259 -224.710273) (xy 341.750121 -224.718372)
			(xy 341.698347 -224.718372) (xy 341.647209 -224.710273) (xy 341.597969 -224.694274) (xy 341.551837 -224.670768)
			(xy 341.50995 -224.640336) (xy 341.47334 -224.603726) (xy 341.442908 -224.561839) (xy 341.419402 -224.515707)
			(xy 341.403403 -224.466467) (xy 341.395304 -224.415329) (xy 341.394796 -224.389442) (xy 341.113872 -224.389442)
			(xy 341.113872 -224.38995) (xy 341.113311 -224.417593) (xy 341.104122 -224.472111) (xy 341.095584 -224.498408)
			(xy 341.087964 -224.520252) (xy 341.292688 -224.87509) (xy 341.315548 -224.879408) (xy 341.340371 -224.884565)
			(xy 341.388151 -224.90152) (xy 341.432771 -224.925592) (xy 341.473178 -224.956214) (xy 341.508419 -224.992662)
			(xy 341.537663 -225.034077) (xy 341.560219 -225.079482) (xy 341.575556 -225.127806) (xy 341.583311 -225.177908)
			(xy 341.583772 -225.203258) (xy 341.583264 -225.229165) (xy 341.575158 -225.280342) (xy 341.559146 -225.329621)
			(xy 341.535623 -225.375788) (xy 341.505167 -225.417707) (xy 341.468529 -225.454345) (xy 341.42661 -225.484801)
			(xy 341.380443 -225.508324) (xy 341.331164 -225.524336) (xy 341.279987 -225.532442) (xy 341.228173 -225.532442)
			(xy 341.176996 -225.524336) (xy 341.127717 -225.508324) (xy 341.08155 -225.484801) (xy 341.039631 -225.454345)
			(xy 341.002993 -225.417707) (xy 340.972537 -225.375788) (xy 340.949014 -225.329621) (xy 340.933002 -225.280342)
			(xy 340.924896 -225.229165) (xy 340.924388 -225.203258) (xy 340.924388 -225.20275) (xy 340.924995 -225.175096)
			(xy 340.93432 -225.120578) (xy 340.94293 -225.094292) (xy 340.95055 -225.072448) (xy 340.745826 -224.71761)
			(xy 340.722966 -224.713292) (xy 340.698148 -224.708169) (xy 340.650405 -224.691172) (xy 340.605826 -224.667071)
			(xy 340.56546 -224.636431) (xy 340.530257 -224.599976) (xy 340.501048 -224.558564) (xy 340.478519 -224.51317)
			(xy 340.463201 -224.464863) (xy 340.455455 -224.414781) (xy 340.454996 -224.389442) (xy 340.174072 -224.389442)
			(xy 340.173564 -224.415329) (xy 340.165465 -224.466467) (xy 340.149466 -224.515707) (xy 340.12596 -224.561839)
			(xy 340.095528 -224.603726) (xy 340.058918 -224.640336) (xy 340.017031 -224.670768) (xy 339.970899 -224.694274)
			(xy 339.921659 -224.710273) (xy 339.870521 -224.718372) (xy 339.818747 -224.718372) (xy 339.767609 -224.710273)
			(xy 339.718369 -224.694274) (xy 339.672237 -224.670768) (xy 339.63035 -224.640336) (xy 339.59374 -224.603726)
			(xy 339.563308 -224.561839) (xy 339.539802 -224.515707) (xy 339.523803 -224.466467) (xy 339.515704 -224.415329)
			(xy 339.515196 -224.389442) (xy 339.234272 -224.389442) (xy 339.234272 -224.38995) (xy 339.233711 -224.417593)
			(xy 339.224522 -224.472111) (xy 339.215984 -224.498408) (xy 339.208364 -224.520252) (xy 339.413088 -224.87509)
			(xy 339.435948 -224.879408) (xy 339.460771 -224.884565) (xy 339.508551 -224.90152) (xy 339.553171 -224.925592)
			(xy 339.593578 -224.956214) (xy 339.628819 -224.992662) (xy 339.658063 -225.034077) (xy 339.680619 -225.079482)
			(xy 339.695956 -225.127806) (xy 339.703711 -225.177908) (xy 339.704172 -225.203258) (xy 339.703664 -225.229165)
			(xy 339.695558 -225.280342) (xy 339.679546 -225.329621) (xy 339.656023 -225.375788) (xy 339.625567 -225.417707)
			(xy 339.588929 -225.454345) (xy 339.54701 -225.484801) (xy 339.500843 -225.508324) (xy 339.451564 -225.524336)
			(xy 339.400387 -225.532442) (xy 339.348573 -225.532442) (xy 339.297396 -225.524336) (xy 339.248117 -225.508324)
			(xy 339.20195 -225.484801) (xy 339.160031 -225.454345) (xy 339.123393 -225.417707) (xy 339.092937 -225.375788)
			(xy 339.069414 -225.329621) (xy 339.053402 -225.280342) (xy 339.045296 -225.229165) (xy 339.044788 -225.203258)
			(xy 339.044788 -225.20275) (xy 339.045395 -225.175096) (xy 339.05472 -225.120578) (xy 339.06333 -225.094292)
			(xy 339.07095 -225.072448) (xy 338.866226 -224.71761) (xy 338.843366 -224.713292) (xy 338.818548 -224.708169)
			(xy 338.770805 -224.691172) (xy 338.726226 -224.667071) (xy 338.68586 -224.636431) (xy 338.650657 -224.599976)
			(xy 338.621448 -224.558564) (xy 338.598919 -224.51317) (xy 338.583601 -224.464863) (xy 338.575855 -224.414781)
			(xy 338.575396 -224.389442) (xy 338.294472 -224.389442) (xy 338.293964 -224.415329) (xy 338.285865 -224.466467)
			(xy 338.269866 -224.515707) (xy 338.24636 -224.561839) (xy 338.215928 -224.603726) (xy 338.179318 -224.640336)
			(xy 338.137431 -224.670768) (xy 338.091299 -224.694274) (xy 338.042059 -224.710273) (xy 337.990921 -224.718372)
			(xy 337.939147 -224.718372) (xy 337.888009 -224.710273) (xy 337.838769 -224.694274) (xy 337.792637 -224.670768)
			(xy 337.75075 -224.640336) (xy 337.71414 -224.603726) (xy 337.683708 -224.561839) (xy 337.660202 -224.515707)
			(xy 337.644203 -224.466467) (xy 337.636104 -224.415329) (xy 337.635596 -224.389442) (xy 284.8356 -224.389442)
			(xy 284.8356 -251.76988) (xy 323.635634 -251.76988) (xy 323.639615 -251.63686) (xy 323.651544 -251.504315)
			(xy 323.671379 -251.372722) (xy 323.699048 -251.24255) (xy 323.734452 -251.114265) (xy 323.777465 -250.988328)
			(xy 323.827932 -250.865189) (xy 323.885673 -250.745288) (xy 323.950482 -250.629055) (xy 324.022126 -250.516905)
			(xy 324.100348 -250.409241) (xy 324.184869 -250.306448) (xy 324.275387 -250.208893) (xy 324.371576 -250.116927)
			(xy 324.473094 -250.030877) (xy 324.579575 -249.951053) (xy 324.69064 -249.87774) (xy 324.805891 -249.8112)
			(xy 324.924915 -249.751671) (xy 325.047286 -249.699367) (xy 325.172565 -249.654475) (xy 325.300306 -249.617156)
			(xy 325.430049 -249.587543) (xy 325.561331 -249.565742) (xy 325.693682 -249.551832) (xy 325.826628 -249.545861)
			(xy 325.959693 -249.547852) (xy 326.092401 -249.557797) (xy 326.224277 -249.575661) (xy 326.354848 -249.601379)
			(xy 326.483648 -249.63486) (xy 326.610214 -249.675984) (xy 326.734095 -249.724604) (xy 326.854846 -249.780545)
			(xy 326.972036 -249.843607) (xy 327.085245 -249.913565) (xy 327.194067 -249.990169) (xy 327.298113 -250.073143)
			(xy 327.397011 -250.162191) (xy 327.490406 -250.256994) (xy 327.577964 -250.357212) (xy 327.659373 -250.462488)
			(xy 327.734339 -250.572444) (xy 327.802596 -250.686686) (xy 327.863898 -250.804806) (xy 327.918027 -250.926381)
			(xy 327.964788 -251.050975) (xy 328.004014 -251.178143) (xy 328.035564 -251.307429) (xy 328.059327 -251.43837)
			(xy 328.075216 -251.570498) (xy 328.083174 -251.70334) (xy 328.083672 -251.76988) (xy 328.083174 -251.83642)
			(xy 328.075216 -251.969262) (xy 328.059327 -252.10139) (xy 328.035564 -252.232331) (xy 328.004014 -252.361617)
			(xy 327.964788 -252.488785) (xy 327.918027 -252.613379) (xy 327.863898 -252.734954) (xy 327.802596 -252.853074)
			(xy 327.734339 -252.967316) (xy 327.659373 -253.077272) (xy 327.577964 -253.182548) (xy 327.490406 -253.282766)
			(xy 327.397011 -253.377569) (xy 327.298113 -253.466617) (xy 327.194067 -253.549591) (xy 327.085245 -253.626195)
			(xy 326.972036 -253.696153) (xy 326.854846 -253.759215) (xy 326.734095 -253.815156) (xy 326.610214 -253.863776)
			(xy 326.483648 -253.9049) (xy 326.354848 -253.938381) (xy 326.224277 -253.964099) (xy 326.092401 -253.981963)
			(xy 325.959693 -253.991908) (xy 325.826628 -253.993899) (xy 325.693682 -253.987928) (xy 325.561331 -253.974018)
			(xy 325.430049 -253.952217) (xy 325.300306 -253.922604) (xy 325.172565 -253.885285) (xy 325.047286 -253.840393)
			(xy 324.924915 -253.788089) (xy 324.805891 -253.72856) (xy 324.69064 -253.66202) (xy 324.579575 -253.588707)
			(xy 324.473094 -253.508883) (xy 324.371576 -253.422833) (xy 324.275387 -253.330867) (xy 324.184869 -253.233312)
			(xy 324.100348 -253.130519) (xy 324.022126 -253.022855) (xy 323.950482 -252.910705) (xy 323.885673 -252.794472)
			(xy 323.827932 -252.674571) (xy 323.777465 -252.551432) (xy 323.734452 -252.425495) (xy 323.699048 -252.29721)
			(xy 323.671379 -252.167038) (xy 323.651544 -252.035445) (xy 323.639615 -251.9029) (xy 323.635634 -251.76988)
			(xy 284.8356 -251.76988) (xy 284.8356 -274.266914) (xy 351.372424 -274.266914) (xy 351.372932 -274.241027)
			(xy 351.381031 -274.189889) (xy 351.39703 -274.140649) (xy 351.420536 -274.094517) (xy 351.450968 -274.05263)
			(xy 351.487578 -274.01602) (xy 351.529465 -273.985588) (xy 351.575597 -273.962082) (xy 351.624837 -273.946083)
			(xy 351.675975 -273.937984) (xy 351.727749 -273.937984) (xy 351.778887 -273.946083) (xy 351.828127 -273.962082)
			(xy 351.874259 -273.985588) (xy 351.916146 -274.01602) (xy 351.952756 -274.05263) (xy 351.983188 -274.094517)
			(xy 352.006694 -274.140649) (xy 352.022693 -274.189889) (xy 352.030792 -274.241027) (xy 352.0313 -274.266914)
			(xy 352.030745 -274.294558) (xy 352.021556 -274.349076) (xy 352.013012 -274.375372) (xy 352.005392 -274.397216)
			(xy 352.210624 -274.752562) (xy 352.233484 -274.75688) (xy 352.258307 -274.762037) (xy 352.306085 -274.778995)
			(xy 352.350703 -274.80307) (xy 352.391108 -274.833692) (xy 352.426348 -274.87014) (xy 352.455591 -274.911554)
			(xy 352.478148 -274.956958) (xy 352.493487 -275.00528) (xy 352.501245 -275.055381) (xy 352.501708 -275.08073)
			(xy 352.5012 -275.106637) (xy 352.493094 -275.157814) (xy 352.477082 -275.207093) (xy 352.453559 -275.25326)
			(xy 352.423103 -275.295179) (xy 352.386465 -275.331817) (xy 352.344546 -275.362273) (xy 352.298379 -275.385796)
			(xy 352.2491 -275.401808) (xy 352.197923 -275.409914) (xy 352.146109 -275.409914) (xy 352.094932 -275.401808)
			(xy 352.045653 -275.385796) (xy 351.999486 -275.362273) (xy 351.957567 -275.331817) (xy 351.920929 -275.295179)
			(xy 351.890473 -275.25326) (xy 351.86695 -275.207093) (xy 351.850938 -275.157814) (xy 351.842832 -275.106637)
			(xy 351.842324 -275.08073) (xy 351.842924 -275.053013) (xy 351.852243 -274.998366) (xy 351.860866 -274.972018)
			(xy 351.86874 -274.94992) (xy 351.663762 -274.595082) (xy 351.640902 -274.590764) (xy 351.616074 -274.585582)
			(xy 351.568269 -274.568647) (xy 351.523622 -274.544591) (xy 351.483185 -274.513981) (xy 351.447913 -274.47754)
			(xy 351.418638 -274.436127) (xy 351.39605 -274.390718) (xy 351.380683 -274.342387) (xy 351.372898 -274.292272)
			(xy 351.372424 -274.266914) (xy 284.8356 -274.266914) (xy 284.8356 -275.106588) (xy 349.963473 -275.106588)
			(xy 349.963473 -275.054812) (xy 349.971573 -275.003674) (xy 349.987573 -274.954432) (xy 350.011079 -274.9083)
			(xy 350.041513 -274.866413) (xy 350.078125 -274.829803) (xy 350.120014 -274.799371) (xy 350.166147 -274.775867)
			(xy 350.215389 -274.759869) (xy 350.266528 -274.751772) (xy 350.292416 -274.751292) (xy 350.317928 -274.751764)
			(xy 350.368343 -274.759627) (xy 350.416945 -274.775162) (xy 350.462573 -274.797999) (xy 350.504138 -274.827593)
			(xy 350.540648 -274.863237) (xy 350.556322 -274.883372) (xy 350.96831 -274.883372) (xy 350.98397 -274.863226)
			(xy 351.020483 -274.827584) (xy 351.062052 -274.797992) (xy 351.107683 -274.775158) (xy 351.156287 -274.759626)
			(xy 351.206703 -274.751768) (xy 351.232216 -274.751292) (xy 351.258105 -274.751741) (xy 351.309245 -274.759843)
			(xy 351.358488 -274.775845) (xy 351.404622 -274.799353) (xy 351.44651 -274.829789) (xy 351.483122 -274.866402)
			(xy 351.513555 -274.908292) (xy 351.537061 -274.954427) (xy 351.553061 -275.003671) (xy 351.56116 -275.054811)
			(xy 351.56116 -275.106589) (xy 351.553061 -275.157729) (xy 351.537061 -275.206973) (xy 351.513555 -275.253108)
			(xy 351.483122 -275.294998) (xy 351.44651 -275.331611) (xy 351.404622 -275.362047) (xy 351.358488 -275.385555)
			(xy 351.309245 -275.401557) (xy 351.258105 -275.409659) (xy 351.232216 -275.410168) (xy 351.206704 -275.409689)
			(xy 351.156289 -275.401829) (xy 351.107687 -275.386297) (xy 351.062058 -275.363461) (xy 351.020493 -275.333868)
			(xy 350.983983 -275.298224) (xy 350.96831 -275.278088) (xy 350.556322 -275.278088) (xy 350.540633 -275.29821)
			(xy 350.504126 -275.333856) (xy 350.462565 -275.363451) (xy 350.416939 -275.386289) (xy 350.36834 -275.401826)
			(xy 350.317927 -275.409689) (xy 350.292416 -275.410168) (xy 350.266528 -275.409628) (xy 350.215389 -275.401531)
			(xy 350.166147 -275.385533) (xy 350.120014 -275.362029) (xy 350.078125 -275.331597) (xy 350.041513 -275.294987)
			(xy 350.011079 -275.2531) (xy 349.987573 -275.206968) (xy 349.971573 -275.157726) (xy 349.963473 -275.106588)
			(xy 284.8356 -275.106588) (xy 284.8356 -276.708616) (xy 349.962724 -276.708616) (xy 349.963202 -276.683281)
			(xy 349.970953 -276.633207) (xy 349.986274 -276.584909) (xy 350.008806 -276.539525) (xy 350.038016 -276.498122)
			(xy 350.073218 -276.461676) (xy 350.113581 -276.431046) (xy 350.158157 -276.406953) (xy 350.205894 -276.389964)
			(xy 350.230694 -276.384766) (xy 350.253554 -276.380448) (xy 350.458532 -276.025356) (xy 350.450912 -276.003512)
			(xy 350.442352 -275.977154) (xy 350.433153 -275.922508) (xy 350.432624 -275.8948) (xy 350.433132 -275.868913)
			(xy 350.441231 -275.817775) (xy 350.45723 -275.768535) (xy 350.480736 -275.722403) (xy 350.511168 -275.680516)
			(xy 350.547778 -275.643906) (xy 350.589665 -275.613474) (xy 350.635797 -275.589968) (xy 350.685037 -275.573969)
			(xy 350.736175 -275.56587) (xy 350.787949 -275.56587) (xy 350.839087 -275.573969) (xy 350.888327 -275.589968)
			(xy 350.934459 -275.613474) (xy 350.976346 -275.643906) (xy 351.012956 -275.680516) (xy 351.043388 -275.722403)
			(xy 351.066894 -275.768535) (xy 351.082893 -275.817775) (xy 351.090992 -275.868913) (xy 351.0915 -275.8948)
			(xy 352.312224 -275.8948) (xy 352.312688 -275.869465) (xy 352.320441 -275.81939) (xy 352.335764 -275.771092)
			(xy 352.358298 -275.725707) (xy 352.38751 -275.684304) (xy 352.422713 -275.647859) (xy 352.463078 -275.617229)
			(xy 352.507655 -275.593136) (xy 352.555393 -275.576148) (xy 352.580194 -275.57095) (xy 352.603054 -275.566632)
			(xy 352.808286 -275.211286) (xy 352.800666 -275.189188) (xy 352.792042 -275.162906) (xy 352.782727 -275.108385)
			(xy 352.782124 -275.08073) (xy 352.782632 -275.054823) (xy 352.790738 -275.003646) (xy 352.80675 -274.954367)
			(xy 352.830273 -274.9082) (xy 352.860729 -274.866281) (xy 352.897367 -274.829643) (xy 352.939286 -274.799187)
			(xy 352.985453 -274.775664) (xy 353.034732 -274.759652) (xy 353.085909 -274.751546) (xy 353.137723 -274.751546)
			(xy 353.1889 -274.759652) (xy 353.238179 -274.775664) (xy 353.284346 -274.799187) (xy 353.326265 -274.829643)
			(xy 353.362903 -274.866281) (xy 353.393359 -274.9082) (xy 353.416882 -274.954367) (xy 353.432894 -275.003646)
			(xy 353.441 -275.054823) (xy 353.441508 -275.08073) (xy 353.441092 -275.106096) (xy 353.433338 -275.156231)
			(xy 353.417989 -275.204584) (xy 353.395406 -275.250011) (xy 353.366125 -275.291439) (xy 353.330837 -275.327886)
			(xy 353.290378 -275.358492) (xy 353.245704 -275.382531) (xy 353.197873 -275.399435) (xy 353.17303 -275.40458)
			(xy 353.149916 -275.408898) (xy 352.944938 -275.76399) (xy 352.952812 -275.786088) (xy 352.96137 -275.812447)
			(xy 352.97057 -275.867092) (xy 352.9711 -275.8948) (xy 352.970592 -275.920687) (xy 352.962493 -275.971825)
			(xy 352.946494 -276.021065) (xy 352.922988 -276.067197) (xy 352.892556 -276.109084) (xy 352.855946 -276.145694)
			(xy 352.814059 -276.176126) (xy 352.767927 -276.199632) (xy 352.718687 -276.215631) (xy 352.667549 -276.22373)
			(xy 352.615775 -276.22373) (xy 352.564637 -276.215631) (xy 352.515397 -276.199632) (xy 352.469265 -276.176126)
			(xy 352.427378 -276.145694) (xy 352.390768 -276.109084) (xy 352.360336 -276.067197) (xy 352.33683 -276.021065)
			(xy 352.320831 -275.971825) (xy 352.312732 -275.920687) (xy 352.312224 -275.8948) (xy 351.0915 -275.8948)
			(xy 351.090979 -275.920144) (xy 351.083207 -275.970232) (xy 351.067862 -276.018541) (xy 351.045306 -276.063932)
			(xy 351.016069 -276.105338) (xy 350.98084 -276.141782) (xy 350.940449 -276.172406) (xy 350.895848 -276.196488)
			(xy 350.848087 -276.213462) (xy 350.823276 -276.21865) (xy 350.800416 -276.222968) (xy 350.595438 -276.577806)
			(xy 350.603312 -276.599904) (xy 350.611874 -276.626262) (xy 350.621072 -276.680908) (xy 350.6216 -276.708616)
			(xy 350.902524 -276.708616) (xy 350.903032 -276.682709) (xy 350.911138 -276.631532) (xy 350.92715 -276.582253)
			(xy 350.950673 -276.536086) (xy 350.981129 -276.494167) (xy 351.017767 -276.457529) (xy 351.059686 -276.427073)
			(xy 351.105853 -276.40355) (xy 351.155132 -276.387538) (xy 351.206309 -276.379432) (xy 351.258123 -276.379432)
			(xy 351.3093 -276.387538) (xy 351.358579 -276.40355) (xy 351.404746 -276.427073) (xy 351.446665 -276.457529)
			(xy 351.483303 -276.494167) (xy 351.513759 -276.536086) (xy 351.537282 -276.582253) (xy 351.553294 -276.631532)
			(xy 351.5614 -276.682709) (xy 351.561908 -276.708616) (xy 351.561377 -276.734509) (xy 351.842805 -276.734509)
			(xy 351.842805 -276.682691) (xy 351.850912 -276.631511) (xy 351.866925 -276.582229) (xy 351.89045 -276.53606)
			(xy 351.920909 -276.494139) (xy 351.957551 -276.457499) (xy 351.999473 -276.427042) (xy 352.045644 -276.403519)
			(xy 352.094927 -276.387508) (xy 352.146107 -276.379404) (xy 352.172016 -276.378924) (xy 352.197529 -276.379383)
			(xy 352.247945 -276.387247) (xy 352.296547 -276.402784) (xy 352.342175 -276.425624) (xy 352.38374 -276.45522)
			(xy 352.420249 -276.490867) (xy 352.435922 -276.511004) (xy 352.84791 -276.511004) (xy 352.863579 -276.490865)
			(xy 352.900089 -276.455221) (xy 352.941656 -276.425628) (xy 352.987285 -276.402792) (xy 353.035888 -276.387259)
			(xy 353.086304 -276.3794) (xy 353.111816 -276.378924) (xy 353.137724 -276.379401) (xy 353.188901 -276.387509)
			(xy 353.23818 -276.403523) (xy 353.284347 -276.427048) (xy 353.326266 -276.457506) (xy 353.362904 -276.494146)
			(xy 353.39336 -276.536066) (xy 353.416883 -276.582235) (xy 353.432895 -276.631514) (xy 353.441 -276.682692)
			(xy 353.441 -276.734508) (xy 353.432895 -276.785686) (xy 353.416883 -276.834965) (xy 353.39336 -276.881134)
			(xy 353.362904 -276.923054) (xy 353.326266 -276.959694) (xy 353.284347 -276.990152) (xy 353.23818 -277.013677)
			(xy 353.188901 -277.029691) (xy 353.137724 -277.037799) (xy 353.111816 -277.038308) (xy 353.086305 -277.037813)
			(xy 353.035891 -277.029955) (xy 352.98729 -277.014424) (xy 352.941662 -276.991591) (xy 352.900096 -276.962001)
			(xy 352.863585 -276.926361) (xy 352.84791 -276.906228) (xy 352.435922 -276.906228) (xy 352.420244 -276.926359)
			(xy 352.383734 -276.962002) (xy 352.342169 -276.991595) (xy 352.296542 -277.014432) (xy 352.247941 -277.029967)
			(xy 352.197528 -277.03783) (xy 352.172016 -277.038308) (xy 352.146107 -277.037796) (xy 352.094927 -277.029692)
			(xy 352.045644 -277.013681) (xy 351.999473 -276.990158) (xy 351.957551 -276.959701) (xy 351.920909 -276.923061)
			(xy 351.89045 -276.88114) (xy 351.866925 -276.834971) (xy 351.850912 -276.785689) (xy 351.842805 -276.734509)
			(xy 351.561377 -276.734509) (xy 351.561338 -276.736398) (xy 351.552014 -276.791174) (xy 351.543366 -276.817582)
			(xy 351.535492 -276.839426) (xy 351.74047 -277.194264) (xy 351.76333 -277.198582) (xy 351.788142 -277.203733)
			(xy 351.835882 -277.220727) (xy 351.88046 -277.244826) (xy 351.920825 -277.275462) (xy 351.956028 -277.311913)
			(xy 351.985239 -277.353322) (xy 352.007769 -277.398712) (xy 352.02309 -277.447016) (xy 352.030838 -277.497095)
			(xy 352.0313 -277.522432) (xy 354.191824 -277.522432) (xy 354.192226 -277.497095) (xy 354.199989 -277.447018)
			(xy 354.215322 -277.398718) (xy 354.237864 -277.353333) (xy 354.267084 -277.31193) (xy 354.302294 -277.275486)
			(xy 354.342666 -277.244857) (xy 354.387248 -277.220766) (xy 354.434991 -277.203779) (xy 354.459794 -277.198582)
			(xy 354.482654 -277.194264) (xy 354.687886 -276.838918) (xy 354.680266 -276.817074) (xy 354.671663 -276.790785)
			(xy 354.662334 -276.736269) (xy 354.661724 -276.708616) (xy 354.662232 -276.682709) (xy 354.670338 -276.631532)
			(xy 354.68635 -276.582253) (xy 354.709873 -276.536086) (xy 354.740329 -276.494167) (xy 354.776967 -276.457529)
			(xy 354.818886 -276.427073) (xy 354.865053 -276.40355) (xy 354.914332 -276.387538) (xy 354.965509 -276.379432)
			(xy 355.017323 -276.379432) (xy 355.0685 -276.387538) (xy 355.117779 -276.40355) (xy 355.163946 -276.427073)
			(xy 355.205865 -276.457529) (xy 355.242503 -276.494167) (xy 355.272959 -276.536086) (xy 355.296482 -276.582253)
			(xy 355.312494 -276.631532) (xy 355.3206 -276.682709) (xy 355.321108 -276.708616) (xy 355.320641 -276.73399)
			(xy 355.312871 -276.784141) (xy 355.297501 -276.832506) (xy 355.274895 -276.877942) (xy 355.245588 -276.919373)
			(xy 355.210273 -276.955819) (xy 355.169787 -276.986418) (xy 355.125087 -277.010445) (xy 355.07723 -277.027332)
			(xy 355.052376 -277.032466) (xy 355.029516 -277.036784) (xy 354.824538 -277.391622) (xy 354.832412 -277.41372)
			(xy 354.840977 -277.440077) (xy 354.850173 -277.494724) (xy 354.8507 -277.522432) (xy 354.850192 -277.548319)
			(xy 354.842093 -277.599457) (xy 354.826094 -277.648697) (xy 354.802588 -277.694829) (xy 354.772156 -277.736716)
			(xy 354.735546 -277.773326) (xy 354.693659 -277.803758) (xy 354.647527 -277.827264) (xy 354.598287 -277.843263)
			(xy 354.547149 -277.851362) (xy 354.495375 -277.851362) (xy 354.444237 -277.843263) (xy 354.394997 -277.827264)
			(xy 354.348865 -277.803758) (xy 354.306978 -277.773326) (xy 354.270368 -277.736716) (xy 354.239936 -277.694829)
			(xy 354.21643 -277.648697) (xy 354.200431 -277.599457) (xy 354.192332 -277.548319) (xy 354.191824 -277.522432)
			(xy 352.0313 -277.522432) (xy 352.030792 -277.548319) (xy 352.022693 -277.599457) (xy 352.006694 -277.648697)
			(xy 351.983188 -277.694829) (xy 351.952756 -277.736716) (xy 351.916146 -277.773326) (xy 351.874259 -277.803758)
			(xy 351.828127 -277.827264) (xy 351.778887 -277.843263) (xy 351.727749 -277.851362) (xy 351.675975 -277.851362)
			(xy 351.624837 -277.843263) (xy 351.575597 -277.827264) (xy 351.529465 -277.803758) (xy 351.487578 -277.773326)
			(xy 351.450968 -277.736716) (xy 351.420536 -277.694829) (xy 351.39703 -277.648697) (xy 351.381031 -277.599457)
			(xy 351.372932 -277.548319) (xy 351.372424 -277.522432) (xy 351.37296 -277.494724) (xy 351.382151 -277.440077)
			(xy 351.390712 -277.41372) (xy 351.398586 -277.391622) (xy 351.193608 -277.036784) (xy 351.170748 -277.032466)
			(xy 351.145918 -277.027336) (xy 351.098136 -277.010379) (xy 351.053515 -276.986304) (xy 351.013107 -276.955679)
			(xy 350.977866 -276.919227) (xy 350.948624 -276.877808) (xy 350.926069 -276.8324) (xy 350.910735 -276.784072)
			(xy 350.902983 -276.733967) (xy 350.902524 -276.708616) (xy 350.6216 -276.708616) (xy 350.621092 -276.734503)
			(xy 350.612993 -276.785641) (xy 350.596994 -276.834881) (xy 350.573488 -276.881013) (xy 350.543056 -276.9229)
			(xy 350.506446 -276.95951) (xy 350.464559 -276.989942) (xy 350.418427 -277.013448) (xy 350.369187 -277.029447)
			(xy 350.318049 -277.037546) (xy 350.266275 -277.037546) (xy 350.215137 -277.029447) (xy 350.165897 -277.013448)
			(xy 350.119765 -276.989942) (xy 350.077878 -276.95951) (xy 350.041268 -276.9229) (xy 350.010836 -276.881013)
			(xy 349.98733 -276.834881) (xy 349.971331 -276.785641) (xy 349.963232 -276.734503) (xy 349.962724 -276.708616)
			(xy 284.8356 -276.708616) (xy 284.8356 -279.150318) (xy 349.492824 -279.150318) (xy 349.493332 -279.124431)
			(xy 349.501431 -279.073293) (xy 349.51743 -279.024053) (xy 349.540936 -278.977921) (xy 349.571368 -278.936034)
			(xy 349.607978 -278.899424) (xy 349.649865 -278.868992) (xy 349.695997 -278.845486) (xy 349.745237 -278.829487)
			(xy 349.796375 -278.821388) (xy 349.848149 -278.821388) (xy 349.899287 -278.829487) (xy 349.948527 -278.845486)
			(xy 349.994659 -278.868992) (xy 350.036546 -278.899424) (xy 350.073156 -278.936034) (xy 350.103588 -278.977921)
			(xy 350.127094 -279.024053) (xy 350.143093 -279.073293) (xy 350.151192 -279.124431) (xy 350.1517 -279.150318)
			(xy 350.151182 -279.176184) (xy 350.433187 -279.176184) (xy 350.433187 -279.124416) (xy 350.441285 -279.073285)
			(xy 350.457281 -279.02405) (xy 350.480782 -278.977924) (xy 350.511209 -278.936041) (xy 350.547812 -278.899433)
			(xy 350.589691 -278.869002) (xy 350.635815 -278.845496) (xy 350.685048 -278.829494) (xy 350.736178 -278.82139)
			(xy 350.762062 -278.82088) (xy 350.787572 -278.821396) (xy 350.837985 -278.82925) (xy 350.886585 -278.844777)
			(xy 350.932214 -278.867606) (xy 350.97378 -278.897192) (xy 351.010293 -278.932828) (xy 351.025968 -278.95296)
			(xy 351.437956 -278.95296) (xy 351.453644 -278.932837) (xy 351.490152 -278.897194) (xy 351.531715 -278.8676)
			(xy 351.57734 -278.844762) (xy 351.625939 -278.829225) (xy 351.676351 -278.82136) (xy 351.701862 -278.82088)
			(xy 351.727755 -278.821322) (xy 351.778904 -278.829418) (xy 351.828156 -278.845416) (xy 351.874299 -278.868923)
			(xy 351.916197 -278.899359) (xy 351.952817 -278.935974) (xy 351.983257 -278.977868) (xy 352.006769 -279.024009)
			(xy 352.022773 -279.073259) (xy 352.030875 -279.124407) (xy 352.030875 -279.176193) (xy 352.022773 -279.227341)
			(xy 352.006769 -279.276591) (xy 351.983257 -279.322732) (xy 351.952817 -279.364626) (xy 351.916197 -279.401241)
			(xy 351.874299 -279.431677) (xy 351.828156 -279.455184) (xy 351.778904 -279.471182) (xy 351.727755 -279.479278)
			(xy 351.701862 -279.479756) (xy 351.676348 -279.47932) (xy 351.625931 -279.471453) (xy 351.577328 -279.455912)
			(xy 351.531699 -279.433068) (xy 351.490135 -279.403466) (xy 351.453628 -279.367815) (xy 351.437956 -279.347676)
			(xy 351.025968 -279.347676) (xy 351.010307 -279.367822) (xy 350.973795 -279.403466) (xy 350.932228 -279.433059)
			(xy 350.886597 -279.455894) (xy 350.837992 -279.471425) (xy 350.787575 -279.479281) (xy 350.762062 -279.479756)
			(xy 350.736178 -279.47921) (xy 350.685048 -279.471106) (xy 350.635815 -279.455104) (xy 350.589691 -279.431598)
			(xy 350.547812 -279.401167) (xy 350.511209 -279.364559) (xy 350.480782 -279.322676) (xy 350.457281 -279.27655)
			(xy 350.441285 -279.227315) (xy 350.433187 -279.176184) (xy 350.151182 -279.176184) (xy 350.151146 -279.177962)
			(xy 350.141956 -279.23248) (xy 350.133412 -279.258776) (xy 350.125792 -279.28062) (xy 350.331024 -279.635966)
			(xy 350.353884 -279.640284) (xy 350.378708 -279.645438) (xy 350.426486 -279.662396) (xy 350.471104 -279.68647)
			(xy 350.511509 -279.717093) (xy 350.546749 -279.753542) (xy 350.575992 -279.794956) (xy 350.598549 -279.84036)
			(xy 350.613887 -279.888683) (xy 350.621645 -279.938785) (xy 350.622108 -279.964134) (xy 350.6216 -279.990041)
			(xy 350.613494 -280.041218) (xy 350.597482 -280.090497) (xy 350.573959 -280.136664) (xy 350.543503 -280.178583)
			(xy 350.506865 -280.215221) (xy 350.464946 -280.245677) (xy 350.418779 -280.2692) (xy 350.3695 -280.285212)
			(xy 350.318323 -280.293318) (xy 350.266509 -280.293318) (xy 350.215332 -280.285212) (xy 350.166053 -280.2692)
			(xy 350.119886 -280.245677) (xy 350.077967 -280.215221) (xy 350.041329 -280.178583) (xy 350.010873 -280.136664)
			(xy 349.98735 -280.090497) (xy 349.971338 -280.041218) (xy 349.963232 -279.990041) (xy 349.962724 -279.964134)
			(xy 349.963325 -279.936417) (xy 349.972644 -279.88177) (xy 349.981266 -279.855422) (xy 349.98914 -279.833324)
			(xy 349.784162 -279.478486) (xy 349.761302 -279.474168) (xy 349.736475 -279.468982) (xy 349.688671 -279.452048)
			(xy 349.644023 -279.427992) (xy 349.603586 -279.397383) (xy 349.568314 -279.360942) (xy 349.539039 -279.319529)
			(xy 349.516451 -279.274121) (xy 349.501083 -279.22579) (xy 349.493299 -279.175676) (xy 349.492824 -279.150318)
			(xy 284.8356 -279.150318) (xy 284.8356 -279.989983) (xy 336.806103 -279.989983) (xy 336.806103 -279.938217)
			(xy 336.814201 -279.887089) (xy 336.830196 -279.837856) (xy 336.853696 -279.791732) (xy 336.884121 -279.749851)
			(xy 336.920722 -279.713245) (xy 336.9626 -279.682815) (xy 337.008721 -279.659311) (xy 337.057952 -279.64331)
			(xy 337.109079 -279.635206) (xy 337.134962 -279.634696) (xy 337.160473 -279.635206) (xy 337.210886 -279.64306)
			(xy 337.259487 -279.658588) (xy 337.305115 -279.681418) (xy 337.346681 -279.711006) (xy 337.383193 -279.746643)
			(xy 337.398868 -279.766776) (xy 337.810856 -279.766776) (xy 337.826548 -279.746656) (xy 337.863055 -279.711012)
			(xy 337.904617 -279.681418) (xy 337.950241 -279.658579) (xy 337.998839 -279.643041) (xy 338.049251 -279.635176)
			(xy 338.074762 -279.634696) (xy 338.100656 -279.635106) (xy 338.151807 -279.643203) (xy 338.201062 -279.659201)
			(xy 338.247208 -279.682709) (xy 338.289107 -279.713146) (xy 338.325729 -279.749764) (xy 338.356171 -279.79166)
			(xy 338.379684 -279.837803) (xy 338.395689 -279.887056) (xy 338.403791 -279.938206) (xy 338.403791 -279.964134)
			(xy 344.323924 -279.964134) (xy 344.324432 -279.938227) (xy 344.332538 -279.88705) (xy 344.34855 -279.837771)
			(xy 344.372073 -279.791604) (xy 344.402529 -279.749685) (xy 344.439167 -279.713047) (xy 344.481086 -279.682591)
			(xy 344.527253 -279.659068) (xy 344.576532 -279.643056) (xy 344.627709 -279.63495) (xy 344.679523 -279.63495)
			(xy 344.7307 -279.643056) (xy 344.779979 -279.659068) (xy 344.826146 -279.682591) (xy 344.868065 -279.713047)
			(xy 344.904703 -279.749685) (xy 344.935159 -279.791604) (xy 344.958682 -279.837771) (xy 344.974694 -279.88705)
			(xy 344.9828 -279.938227) (xy 344.983308 -279.964134) (xy 344.982671 -279.991925) (xy 344.973225 -280.046702)
			(xy 344.964512 -280.0731) (xy 344.956892 -280.095198) (xy 345.16187 -280.450036) (xy 345.18473 -280.454354)
			(xy 345.209535 -280.459531) (xy 345.257274 -280.476523) (xy 345.30185 -280.500619) (xy 345.342215 -280.531252)
			(xy 345.377417 -280.5677) (xy 345.406629 -280.609105) (xy 345.429161 -280.654492) (xy 345.444484 -280.702792)
			(xy 345.452236 -280.752868) (xy 345.4527 -280.778204) (xy 345.452192 -280.804091) (xy 345.444093 -280.855229)
			(xy 345.428094 -280.904469) (xy 345.404588 -280.950601) (xy 345.374156 -280.992488) (xy 345.337546 -281.029098)
			(xy 345.295659 -281.05953) (xy 345.249527 -281.083036) (xy 345.200287 -281.099035) (xy 345.149149 -281.107134)
			(xy 345.097375 -281.107134) (xy 345.046237 -281.099035) (xy 344.996997 -281.083036) (xy 344.950865 -281.05953)
			(xy 344.908978 -281.029098) (xy 344.872368 -280.992488) (xy 344.841936 -280.950601) (xy 344.81843 -280.904469)
			(xy 344.802431 -280.855229) (xy 344.794332 -280.804091) (xy 344.793824 -280.778204) (xy 344.794353 -280.750496)
			(xy 344.803549 -280.695849) (xy 344.812112 -280.669492) (xy 344.819986 -280.647394) (xy 344.614754 -280.292302)
			(xy 344.591894 -280.287984) (xy 344.567101 -280.282754) (xy 344.519365 -280.265768) (xy 344.47479 -280.241678)
			(xy 344.434426 -280.211052) (xy 344.399223 -280.174611) (xy 344.37001 -280.133213) (xy 344.347475 -280.087832)
			(xy 344.332148 -280.039538) (xy 344.32439 -279.989468) (xy 344.323924 -279.964134) (xy 338.403791 -279.964134)
			(xy 338.403791 -279.989994) (xy 338.395689 -280.041144) (xy 338.379684 -280.090397) (xy 338.356171 -280.13654)
			(xy 338.325729 -280.178436) (xy 338.289107 -280.215054) (xy 338.247208 -280.245491) (xy 338.201062 -280.268999)
			(xy 338.151807 -280.284997) (xy 338.100656 -280.293094) (xy 338.074762 -280.293572) (xy 338.049249 -280.293131)
			(xy 337.998832 -280.285263) (xy 337.950229 -280.269723) (xy 337.9046 -280.24688) (xy 337.863036 -280.21728)
			(xy 337.826528 -280.18163) (xy 337.810856 -280.161492) (xy 337.398868 -280.161492) (xy 337.383211 -280.181641)
			(xy 337.346698 -280.217284) (xy 337.305129 -280.246877) (xy 337.259498 -280.269711) (xy 337.210893 -280.285241)
			(xy 337.160475 -280.293097) (xy 337.134962 -280.293572) (xy 337.109079 -280.292994) (xy 337.057952 -280.28489)
			(xy 337.008721 -280.268889) (xy 336.9626 -280.245385) (xy 336.920722 -280.214955) (xy 336.884121 -280.178349)
			(xy 336.853696 -280.136468) (xy 336.830196 -280.090344) (xy 336.814201 -280.041111) (xy 336.806103 -279.989983)
			(xy 284.8356 -279.989983) (xy 284.8356 -280.804105) (xy 334.45632 -280.804105) (xy 334.45632 -280.752295)
			(xy 334.464425 -280.701122) (xy 334.480434 -280.651848) (xy 334.503953 -280.605684) (xy 334.534405 -280.563767)
			(xy 334.571038 -280.527129) (xy 334.612951 -280.496673) (xy 334.659113 -280.473148) (xy 334.708385 -280.457133)
			(xy 334.759557 -280.449023) (xy 334.785462 -280.448512) (xy 334.810955 -280.449019) (xy 334.861331 -280.456875)
			(xy 334.909894 -280.472404) (xy 334.955481 -280.495237) (xy 334.997003 -280.524825) (xy 335.033465 -280.560462)
			(xy 335.049114 -280.580592) (xy 335.46161 -280.580592) (xy 335.477279 -280.560477) (xy 335.513736 -280.524835)
			(xy 335.555252 -280.495239) (xy 335.600835 -280.472399) (xy 335.649395 -280.45686) (xy 335.699769 -280.448993)
			(xy 335.725262 -280.448512) (xy 335.751174 -280.448983) (xy 335.80236 -280.457084) (xy 335.851648 -280.473094)
			(xy 335.897825 -280.496618) (xy 335.939753 -280.527076) (xy 335.9764 -280.563718) (xy 336.006863 -280.605643)
			(xy 336.030391 -280.651817) (xy 336.046407 -280.701103) (xy 336.054514 -280.752288) (xy 336.054514 -280.804112)
			(xy 336.046407 -280.855297) (xy 336.030391 -280.904583) (xy 336.006863 -280.950757) (xy 335.9764 -280.992682)
			(xy 335.939753 -281.029324) (xy 335.897825 -281.059782) (xy 335.851648 -281.083306) (xy 335.80236 -281.099316)
			(xy 335.751174 -281.107417) (xy 335.725262 -281.107896) (xy 335.699767 -281.107441) (xy 335.649389 -281.099574)
			(xy 335.600825 -281.084033) (xy 335.555238 -281.061192) (xy 335.513718 -281.031594) (xy 335.477257 -280.99595)
			(xy 335.46161 -280.975816) (xy 335.049114 -280.975816) (xy 335.033491 -280.995969) (xy 334.997025 -281.031609)
			(xy 334.955498 -281.061199) (xy 334.909906 -281.084033) (xy 334.861339 -281.099564) (xy 334.810957 -281.107421)
			(xy 334.785462 -281.107896) (xy 334.759557 -281.107377) (xy 334.708385 -281.099267) (xy 334.659113 -281.083252)
			(xy 334.612951 -281.059727) (xy 334.571038 -281.029271) (xy 334.534405 -280.992633) (xy 334.503953 -280.950716)
			(xy 334.480434 -280.904552) (xy 334.464425 -280.855278) (xy 334.45632 -280.804105) (xy 284.8356 -280.804105)
			(xy 284.8356 -282.405836) (xy 334.456024 -282.405836) (xy 334.456468 -282.38049) (xy 334.46425 -282.330397)
			(xy 334.479605 -282.282085) (xy 334.502171 -282.236692) (xy 334.531418 -282.195286) (xy 334.566656 -282.158843)
			(xy 334.607056 -282.128222) (xy 334.651665 -282.104142) (xy 334.699433 -282.087172) (xy 334.724248 -282.081986)
			(xy 334.747108 -282.077668) (xy 334.952086 -281.722576) (xy 334.944466 -281.700732) (xy 334.93582 -281.67439)
			(xy 334.926507 -281.619739) (xy 334.925924 -281.59202) (xy 334.926432 -281.566113) (xy 334.934538 -281.514936)
			(xy 334.95055 -281.465657) (xy 334.974073 -281.41949) (xy 335.004529 -281.377571) (xy 335.041167 -281.340933)
			(xy 335.083086 -281.310477) (xy 335.129253 -281.286954) (xy 335.178532 -281.270942) (xy 335.229709 -281.262836)
			(xy 335.281523 -281.262836) (xy 335.3327 -281.270942) (xy 335.381979 -281.286954) (xy 335.428146 -281.310477)
			(xy 335.470065 -281.340933) (xy 335.506703 -281.377571) (xy 335.537159 -281.41949) (xy 335.560682 -281.465657)
			(xy 335.576694 -281.514936) (xy 335.5848 -281.566113) (xy 335.585308 -281.59202) (xy 336.805524 -281.59202)
			(xy 336.806044 -281.566676) (xy 336.813813 -281.516587) (xy 336.829157 -281.468277) (xy 336.851713 -281.422884)
			(xy 336.88095 -281.381477) (xy 336.916179 -281.345033) (xy 336.956571 -281.31441) (xy 337.001174 -281.290329)
			(xy 337.048936 -281.273357) (xy 337.073748 -281.26817) (xy 337.096608 -281.263852) (xy 337.301586 -280.909014)
			(xy 337.293966 -280.88717) (xy 337.285321 -280.860761) (xy 337.276 -280.805986) (xy 337.275424 -280.778204)
			(xy 337.275919 -280.752309) (xy 337.284017 -280.701155) (xy 337.300013 -280.651897) (xy 337.323515 -280.605746)
			(xy 337.353945 -280.563837) (xy 337.390553 -280.527202) (xy 337.432439 -280.496742) (xy 337.478573 -280.473206)
			(xy 337.527819 -280.457173) (xy 337.578967 -280.449038) (xy 337.604862 -280.448512) (xy 337.630766 -280.448979)
			(xy 337.681935 -280.457083) (xy 337.731205 -280.473097) (xy 337.777361 -280.496626) (xy 337.819265 -280.52709)
			(xy 337.855883 -280.563738) (xy 337.886313 -280.605666) (xy 337.909805 -280.651841) (xy 337.925779 -280.701124)
			(xy 337.933841 -280.7523) (xy 337.9343 -280.778204) (xy 340.094824 -280.778204) (xy 340.095293 -280.752294)
			(xy 340.103399 -280.701112) (xy 340.119413 -280.651828) (xy 340.142939 -280.605656) (xy 340.173399 -280.563733)
			(xy 340.210042 -280.527091) (xy 340.251966 -280.496633) (xy 340.298139 -280.473108) (xy 340.347423 -280.457097)
			(xy 340.398606 -280.448992) (xy 340.424516 -280.448512) (xy 340.450421 -280.448929) (xy 340.501592 -280.457041)
			(xy 340.550863 -280.473063) (xy 340.597019 -280.496598) (xy 340.638922 -280.527068) (xy 340.67554 -280.563721)
			(xy 340.705969 -280.605654) (xy 340.72946 -280.651833) (xy 340.745433 -280.701119) (xy 340.753496 -280.752298)
			(xy 340.753954 -280.778204) (xy 340.753418 -280.804105) (xy 342.91452 -280.804105) (xy 342.91452 -280.752295)
			(xy 342.922625 -280.701122) (xy 342.938634 -280.651848) (xy 342.962153 -280.605684) (xy 342.992605 -280.563767)
			(xy 343.029238 -280.527129) (xy 343.071151 -280.496673) (xy 343.117313 -280.473148) (xy 343.166585 -280.457133)
			(xy 343.217757 -280.449023) (xy 343.243662 -280.448512) (xy 343.269173 -280.449015) (xy 343.319587 -280.45687)
			(xy 343.368188 -280.472399) (xy 343.413817 -280.49523) (xy 343.455383 -280.524819) (xy 343.491894 -280.560459)
			(xy 343.507568 -280.580592) (xy 343.91981 -280.580592) (xy 343.935476 -280.56045) (xy 343.971987 -280.524807)
			(xy 344.013554 -280.495214) (xy 344.059184 -280.472379) (xy 344.107788 -280.456847) (xy 344.158204 -280.448988)
			(xy 344.183716 -280.448512) (xy 344.209623 -280.449014) (xy 344.260798 -280.457121) (xy 344.310075 -280.473134)
			(xy 344.356241 -280.496659) (xy 344.398158 -280.527115) (xy 344.434795 -280.563754) (xy 344.465249 -280.605673)
			(xy 344.488772 -280.65184) (xy 344.504782 -280.701117) (xy 344.512888 -280.752293) (xy 344.512888 -280.804107)
			(xy 344.504782 -280.855283) (xy 344.488772 -280.90456) (xy 344.465249 -280.950727) (xy 344.434795 -280.992646)
			(xy 344.398158 -281.029285) (xy 344.356241 -281.059741) (xy 344.310075 -281.083266) (xy 344.260798 -281.099279)
			(xy 344.209623 -281.107386) (xy 344.183716 -281.107896) (xy 344.158205 -281.107405) (xy 344.107791 -281.099547)
			(xy 344.059189 -281.084016) (xy 344.013561 -281.061182) (xy 343.971995 -281.031591) (xy 343.935484 -280.99595)
			(xy 343.91981 -280.975816) (xy 343.507568 -280.975816) (xy 343.491917 -280.99597) (xy 343.455403 -281.031612)
			(xy 343.413832 -281.061203) (xy 343.368199 -281.084036) (xy 343.319593 -281.099566) (xy 343.269175 -281.107421)
			(xy 343.243662 -281.107896) (xy 343.217757 -281.107377) (xy 343.166585 -281.099267) (xy 343.117313 -281.083252)
			(xy 343.071151 -281.059727) (xy 343.029238 -281.029271) (xy 342.992605 -280.992633) (xy 342.962153 -280.950716)
			(xy 342.938634 -280.904552) (xy 342.922625 -280.855278) (xy 342.91452 -280.804105) (xy 340.753418 -280.804105)
			(xy 340.753379 -280.805986) (xy 340.744058 -280.860762) (xy 340.735412 -280.88717) (xy 340.727792 -280.909014)
			(xy 340.93277 -281.263852) (xy 340.95563 -281.26817) (xy 340.980439 -281.273332) (xy 341.028178 -281.290325)
			(xy 341.072756 -281.314423) (xy 341.113121 -281.345058) (xy 341.148323 -281.381508) (xy 341.177534 -281.422915)
			(xy 341.200066 -281.468304) (xy 341.215387 -281.516606) (xy 341.223138 -281.566683) (xy 341.2236 -281.59202)
			(xy 341.223092 -281.617907) (xy 341.214993 -281.669045) (xy 341.198994 -281.718285) (xy 341.175488 -281.764417)
			(xy 341.145056 -281.806304) (xy 341.108446 -281.842914) (xy 341.066559 -281.873346) (xy 341.020427 -281.896852)
			(xy 340.971187 -281.912851) (xy 340.920049 -281.92095) (xy 340.868275 -281.92095) (xy 340.817137 -281.912851)
			(xy 340.767897 -281.896852) (xy 340.721765 -281.873346) (xy 340.679878 -281.842914) (xy 340.643268 -281.806304)
			(xy 340.612836 -281.764417) (xy 340.58933 -281.718285) (xy 340.573331 -281.669045) (xy 340.565232 -281.617907)
			(xy 340.564724 -281.59202) (xy 340.565273 -281.564313) (xy 340.574459 -281.509667) (xy 340.583012 -281.483308)
			(xy 340.590632 -281.461464) (xy 340.385654 -281.106372) (xy 340.362794 -281.102054) (xy 340.337994 -281.096852)
			(xy 340.290256 -281.079864) (xy 340.24568 -281.055771) (xy 340.205315 -281.025142) (xy 340.170112 -280.988697)
			(xy 340.140899 -280.947295) (xy 340.118366 -280.901911) (xy 340.103042 -280.853613) (xy 340.095288 -280.803539)
			(xy 340.094824 -280.778204) (xy 337.9343 -280.778204) (xy 337.933779 -280.803526) (xy 337.926048 -280.853575)
			(xy 337.910753 -280.901853) (xy 337.888254 -280.947223) (xy 337.859081 -280.988619) (xy 337.82392 -281.025066)
			(xy 337.783598 -281.055707) (xy 337.739064 -281.07982) (xy 337.691367 -281.096838) (xy 337.666584 -281.102054)
			(xy 337.643724 -281.106372) (xy 337.438746 -281.46121) (xy 337.446366 -281.483054) (xy 337.454977 -281.50934)
			(xy 337.464301 -281.563858) (xy 337.464908 -281.591512) (xy 337.464908 -281.59202) (xy 337.4644 -281.617904)
			(xy 338.685436 -281.617904) (xy 338.685436 -281.566096) (xy 338.69354 -281.514926) (xy 338.709548 -281.465654)
			(xy 338.733067 -281.419492) (xy 338.763517 -281.377577) (xy 338.800148 -281.340942) (xy 338.84206 -281.310487)
			(xy 338.888219 -281.286963) (xy 338.937489 -281.270949) (xy 338.988658 -281.262839) (xy 339.014562 -281.262328)
			(xy 339.040073 -281.262825) (xy 339.090487 -281.270681) (xy 339.139089 -281.28621) (xy 339.184718 -281.309042)
			(xy 339.226284 -281.338633) (xy 339.262794 -281.374274) (xy 339.278468 -281.394408) (xy 339.690456 -281.394408)
			(xy 339.706157 -281.374295) (xy 339.742661 -281.33865) (xy 339.784221 -281.309053) (xy 339.829844 -281.286213)
			(xy 339.878441 -281.270675) (xy 339.928852 -281.262808) (xy 339.954362 -281.262328) (xy 339.980275 -281.262767)
			(xy 340.031464 -281.270869) (xy 340.080754 -281.286879) (xy 340.126933 -281.310404) (xy 340.168863 -281.340863)
			(xy 340.205512 -281.377508) (xy 340.235976 -281.419434) (xy 340.259506 -281.465611) (xy 340.275522 -281.514899)
			(xy 340.28363 -281.566087) (xy 340.28363 -281.617913) (xy 340.275522 -281.669101) (xy 340.259506 -281.718389)
			(xy 340.235976 -281.764566) (xy 340.205512 -281.806492) (xy 340.168863 -281.843137) (xy 340.126933 -281.873596)
			(xy 340.080754 -281.897121) (xy 340.031464 -281.913131) (xy 339.980275 -281.921233) (xy 339.954362 -281.921712)
			(xy 339.928849 -281.921255) (xy 339.878434 -281.913389) (xy 339.829832 -281.89785) (xy 339.784204 -281.87501)
			(xy 339.742639 -281.845414) (xy 339.706129 -281.809768) (xy 339.690456 -281.789632) (xy 339.278468 -281.789632)
			(xy 339.262822 -281.80979) (xy 339.226306 -281.845431) (xy 339.184734 -281.875021) (xy 339.139101 -281.897853)
			(xy 339.090494 -281.913382) (xy 339.040076 -281.921238) (xy 339.014562 -281.921712) (xy 338.988658 -281.921161)
			(xy 338.937489 -281.913051) (xy 338.888219 -281.897037) (xy 338.84206 -281.873513) (xy 338.800148 -281.843058)
			(xy 338.763517 -281.806423) (xy 338.733067 -281.764508) (xy 338.709548 -281.718346) (xy 338.69354 -281.669074)
			(xy 338.685436 -281.617904) (xy 337.4644 -281.617904) (xy 337.4644 -281.617927) (xy 337.456294 -281.669104)
			(xy 337.440282 -281.718383) (xy 337.416759 -281.76455) (xy 337.386303 -281.806469) (xy 337.349665 -281.843107)
			(xy 337.307746 -281.873563) (xy 337.261579 -281.897086) (xy 337.2123 -281.913098) (xy 337.161123 -281.921204)
			(xy 337.109309 -281.921204) (xy 337.058132 -281.913098) (xy 337.008853 -281.897086) (xy 336.962686 -281.873563)
			(xy 336.920767 -281.843107) (xy 336.884129 -281.806469) (xy 336.853673 -281.76455) (xy 336.83015 -281.718383)
			(xy 336.814138 -281.669104) (xy 336.806032 -281.617927) (xy 336.805524 -281.59202) (xy 335.585308 -281.59202)
			(xy 335.584798 -281.617364) (xy 335.577024 -281.667452) (xy 335.561677 -281.715761) (xy 335.539118 -281.761152)
			(xy 335.50988 -281.802558) (xy 335.47465 -281.839001) (xy 335.434259 -281.869625) (xy 335.389657 -281.893707)
			(xy 335.341896 -281.910681) (xy 335.317084 -281.91587) (xy 335.294224 -281.920188) (xy 335.089246 -282.27528)
			(xy 335.096866 -282.297124) (xy 335.1055 -282.32347) (xy 335.114821 -282.378118) (xy 335.115408 -282.405836)
			(xy 335.395824 -282.405836) (xy 335.396332 -282.379949) (xy 335.404431 -282.328811) (xy 335.42043 -282.279571)
			(xy 335.443936 -282.233439) (xy 335.474368 -282.191552) (xy 335.510978 -282.154942) (xy 335.552865 -282.12451)
			(xy 335.598997 -282.101004) (xy 335.648237 -282.085005) (xy 335.699375 -282.076906) (xy 335.751149 -282.076906)
			(xy 335.802287 -282.085005) (xy 335.851527 -282.101004) (xy 335.897659 -282.12451) (xy 335.939546 -282.154942)
			(xy 335.976156 -282.191552) (xy 336.006588 -282.233439) (xy 336.030094 -282.279571) (xy 336.046093 -282.328811)
			(xy 336.054192 -282.379949) (xy 336.0547 -282.405836) (xy 336.054214 -282.431707) (xy 336.336126 -282.431707)
			(xy 336.336126 -282.379893) (xy 336.344232 -282.328716) (xy 336.360244 -282.279437) (xy 336.383768 -282.23327)
			(xy 336.414225 -282.191352) (xy 336.450864 -282.154714) (xy 336.492784 -282.12426) (xy 336.538952 -282.100738)
			(xy 336.588231 -282.084728) (xy 336.639409 -282.076625) (xy 336.665316 -282.076144) (xy 336.690811 -282.076599)
			(xy 336.74119 -282.084464) (xy 336.789755 -282.100003) (xy 336.835342 -282.122845) (xy 336.876862 -282.152443)
			(xy 336.913321 -282.188089) (xy 336.928968 -282.208224) (xy 337.341464 -282.208224) (xy 337.35711 -282.18809)
			(xy 337.393571 -282.152447) (xy 337.435092 -282.122853) (xy 337.480679 -282.100016) (xy 337.529243 -282.084481)
			(xy 337.579622 -282.076621) (xy 337.605116 -282.076144) (xy 337.631025 -282.076581) (xy 337.682206 -282.08469)
			(xy 337.731488 -282.100704) (xy 337.777658 -282.124231) (xy 337.819579 -282.154691) (xy 337.85622 -282.191333)
			(xy 337.886677 -282.233256) (xy 337.910202 -282.279427) (xy 337.926214 -282.32871) (xy 337.93432 -282.379891)
			(xy 337.93432 -282.431709) (xy 337.926214 -282.48289) (xy 337.910202 -282.532173) (xy 337.886677 -282.578344)
			(xy 337.85622 -282.620267) (xy 337.819579 -282.656909) (xy 337.777658 -282.687369) (xy 337.731488 -282.710896)
			(xy 337.682206 -282.72691) (xy 337.631025 -282.735019) (xy 337.605116 -282.735528) (xy 337.579623 -282.735021)
			(xy 337.529248 -282.727163) (xy 337.480686 -282.711632) (xy 337.435099 -282.6888) (xy 337.393577 -282.659213)
			(xy 337.357114 -282.623577) (xy 337.341464 -282.603448) (xy 336.928968 -282.603448) (xy 336.913322 -282.623582)
			(xy 336.876859 -282.659221) (xy 336.835338 -282.688813) (xy 336.78975 -282.71165) (xy 336.741187 -282.727186)
			(xy 336.69081 -282.735049) (xy 336.665316 -282.735528) (xy 336.639409 -282.734975) (xy 336.588231 -282.726872)
			(xy 336.538952 -282.710862) (xy 336.492784 -282.68734) (xy 336.450864 -282.656886) (xy 336.414225 -282.620248)
			(xy 336.383768 -282.57833) (xy 336.360244 -282.532163) (xy 336.344232 -282.482884) (xy 336.336126 -282.431707)
			(xy 336.054214 -282.431707) (xy 336.054179 -282.433545) (xy 336.044978 -282.488191) (xy 336.036412 -282.514548)
			(xy 336.028538 -282.536646) (xy 336.23377 -282.891738) (xy 336.25663 -282.896056) (xy 336.281436 -282.901231)
			(xy 336.329174 -282.918223) (xy 336.373751 -282.94232) (xy 336.414116 -282.972953) (xy 336.449318 -283.009401)
			(xy 336.478529 -283.050806) (xy 336.501062 -283.096194) (xy 336.516384 -283.144494) (xy 336.524137 -283.19457)
			(xy 336.5246 -283.219906) (xy 338.685124 -283.219906) (xy 338.685593 -283.194571) (xy 338.693345 -283.144497)
			(xy 338.708668 -283.096199) (xy 338.731201 -283.050814) (xy 338.760412 -283.009411) (xy 338.795615 -282.972966)
			(xy 338.83598 -282.942336) (xy 338.880556 -282.918243) (xy 338.928293 -282.901254) (xy 338.953094 -282.896056)
			(xy 338.975954 -282.891738) (xy 339.181186 -282.536392) (xy 339.173566 -282.514548) (xy 339.164924 -282.488205)
			(xy 339.155609 -282.433555) (xy 339.155024 -282.405836) (xy 339.155532 -282.379929) (xy 339.163638 -282.328752)
			(xy 339.17965 -282.279473) (xy 339.203173 -282.233306) (xy 339.233629 -282.191387) (xy 339.270267 -282.154749)
			(xy 339.312186 -282.124293) (xy 339.358353 -282.10077) (xy 339.407632 -282.084758) (xy 339.458809 -282.076652)
			(xy 339.510623 -282.076652) (xy 339.5618 -282.084758) (xy 339.611079 -282.10077) (xy 339.657246 -282.124293)
			(xy 339.699165 -282.154749) (xy 339.735803 -282.191387) (xy 339.766259 -282.233306) (xy 339.789782 -282.279473)
			(xy 339.805794 -282.328752) (xy 339.8139 -282.379929) (xy 339.814408 -282.405836) (xy 341.034624 -282.405836)
			(xy 341.035068 -282.38049) (xy 341.04285 -282.330397) (xy 341.058205 -282.282085) (xy 341.080771 -282.236692)
			(xy 341.110018 -282.195286) (xy 341.145256 -282.158843) (xy 341.185656 -282.128222) (xy 341.230265 -282.104142)
			(xy 341.278033 -282.087172) (xy 341.302848 -282.081986) (xy 341.325708 -282.077668) (xy 341.530686 -281.72283)
			(xy 341.522812 -281.700986) (xy 341.514229 -281.674568) (xy 341.505035 -281.619792) (xy 341.504524 -281.59202)
			(xy 341.505032 -281.566133) (xy 341.513131 -281.514995) (xy 341.52913 -281.465755) (xy 341.552636 -281.419623)
			(xy 341.583068 -281.377736) (xy 341.619678 -281.341126) (xy 341.661565 -281.310694) (xy 341.707697 -281.287188)
			(xy 341.756937 -281.271189) (xy 341.808075 -281.26309) (xy 341.859849 -281.26309) (xy 341.910987 -281.271189)
			(xy 341.960227 -281.287188) (xy 342.006359 -281.310694) (xy 342.048246 -281.341126) (xy 342.084856 -281.377736)
			(xy 342.115288 -281.419623) (xy 342.138794 -281.465755) (xy 342.154793 -281.514995) (xy 342.162892 -281.566133)
			(xy 342.1634 -281.59202) (xy 342.162935 -281.617355) (xy 342.15518 -281.667428) (xy 342.139855 -281.715725)
			(xy 342.117321 -281.761109) (xy 342.088109 -281.802511) (xy 342.052906 -281.838956) (xy 342.012542 -281.869586)
			(xy 341.967967 -281.89368) (xy 341.92023 -281.910671) (xy 341.89543 -281.91587) (xy 341.87257 -281.920188)
			(xy 341.667592 -282.275026) (xy 341.675466 -282.297124) (xy 341.684085 -282.323474) (xy 341.693414 -282.378119)
			(xy 341.694008 -282.405836) (xy 342.914224 -282.405836) (xy 342.914629 -282.380499) (xy 342.922392 -282.330422)
			(xy 342.937724 -282.282122) (xy 342.960266 -282.236737) (xy 342.989485 -282.195335) (xy 343.024695 -282.15889)
			(xy 343.065066 -282.128262) (xy 343.109648 -282.10417) (xy 343.157391 -282.087183) (xy 343.182194 -282.081986)
			(xy 343.205054 -282.077668) (xy 343.410286 -281.722322) (xy 343.402666 -281.700478) (xy 343.39404 -281.674196)
			(xy 343.384726 -281.619675) (xy 343.384124 -281.59202) (xy 343.384632 -281.566113) (xy 343.392738 -281.514936)
			(xy 343.40875 -281.465657) (xy 343.432273 -281.41949) (xy 343.462729 -281.377571) (xy 343.499367 -281.340933)
			(xy 343.541286 -281.310477) (xy 343.587453 -281.286954) (xy 343.636732 -281.270942) (xy 343.687909 -281.262836)
			(xy 343.739723 -281.262836) (xy 343.7909 -281.270942) (xy 343.840179 -281.286954) (xy 343.886346 -281.310477)
			(xy 343.928265 -281.340933) (xy 343.964903 -281.377571) (xy 343.995359 -281.41949) (xy 344.018882 -281.465657)
			(xy 344.034894 -281.514936) (xy 344.043 -281.566113) (xy 344.043508 -281.59202) (xy 345.263724 -281.59202)
			(xy 345.264244 -281.566676) (xy 345.272013 -281.516587) (xy 345.287357 -281.468277) (xy 345.309913 -281.422884)
			(xy 345.33915 -281.381477) (xy 345.374379 -281.345033) (xy 345.414771 -281.31441) (xy 345.459374 -281.290329)
			(xy 345.507136 -281.273357) (xy 345.531948 -281.26817) (xy 345.554808 -281.263852) (xy 345.759786 -280.909014)
			(xy 345.751912 -280.88717) (xy 345.743326 -280.860753) (xy 345.734134 -280.805977) (xy 345.733624 -280.778204)
			(xy 345.734132 -280.752317) (xy 345.742231 -280.701179) (xy 345.75823 -280.651939) (xy 345.781736 -280.605807)
			(xy 345.812168 -280.56392) (xy 345.848778 -280.52731) (xy 345.890665 -280.496878) (xy 345.936797 -280.473372)
			(xy 345.986037 -280.457373) (xy 346.037175 -280.449274) (xy 346.088949 -280.449274) (xy 346.140087 -280.457373)
			(xy 346.189327 -280.473372) (xy 346.235459 -280.496878) (xy 346.277346 -280.52731) (xy 346.313956 -280.56392)
			(xy 346.344388 -280.605807) (xy 346.367894 -280.651939) (xy 346.383893 -280.701179) (xy 346.391992 -280.752317)
			(xy 346.3925 -280.778204) (xy 348.553024 -280.778204) (xy 348.553532 -280.752317) (xy 348.561631 -280.701179)
			(xy 348.57763 -280.651939) (xy 348.601136 -280.605807) (xy 348.631568 -280.56392) (xy 348.668178 -280.52731)
			(xy 348.710065 -280.496878) (xy 348.756197 -280.473372) (xy 348.805437 -280.457373) (xy 348.856575 -280.449274)
			(xy 348.908349 -280.449274) (xy 348.959487 -280.457373) (xy 349.008727 -280.473372) (xy 349.054859 -280.496878)
			(xy 349.096746 -280.52731) (xy 349.133356 -280.56392) (xy 349.163788 -280.605807) (xy 349.187294 -280.651939)
			(xy 349.203293 -280.701179) (xy 349.211392 -280.752317) (xy 349.2119 -280.778204) (xy 351.372424 -280.778204)
			(xy 351.372932 -280.752317) (xy 351.381031 -280.701179) (xy 351.39703 -280.651939) (xy 351.420536 -280.605807)
			(xy 351.450968 -280.56392) (xy 351.487578 -280.52731) (xy 351.529465 -280.496878) (xy 351.575597 -280.473372)
			(xy 351.624837 -280.457373) (xy 351.675975 -280.449274) (xy 351.727749 -280.449274) (xy 351.778887 -280.457373)
			(xy 351.828127 -280.473372) (xy 351.874259 -280.496878) (xy 351.916146 -280.52731) (xy 351.952756 -280.56392)
			(xy 351.983188 -280.605807) (xy 352.006694 -280.651939) (xy 352.022693 -280.701179) (xy 352.030792 -280.752317)
			(xy 352.0313 -280.778204) (xy 352.312224 -280.778204) (xy 352.312691 -280.752869) (xy 352.320444 -280.702795)
			(xy 352.335767 -280.654496) (xy 352.3583 -280.609112) (xy 352.387511 -280.567709) (xy 352.422714 -280.531263)
			(xy 352.463079 -280.500633) (xy 352.507655 -280.47654) (xy 352.555393 -280.459552) (xy 352.580194 -280.454354)
			(xy 352.603054 -280.450036) (xy 352.808286 -280.09469) (xy 352.800666 -280.072592) (xy 352.792043 -280.046309)
			(xy 352.782727 -279.991789) (xy 352.782124 -279.964134) (xy 352.782632 -279.938227) (xy 352.790738 -279.88705)
			(xy 352.80675 -279.837771) (xy 352.830273 -279.791604) (xy 352.860729 -279.749685) (xy 352.897367 -279.713047)
			(xy 352.939286 -279.682591) (xy 352.985453 -279.659068) (xy 353.034732 -279.643056) (xy 353.085909 -279.63495)
			(xy 353.137723 -279.63495) (xy 353.1889 -279.643056) (xy 353.238179 -279.659068) (xy 353.284346 -279.682591)
			(xy 353.326265 -279.713047) (xy 353.362903 -279.749685) (xy 353.393359 -279.791604) (xy 353.416882 -279.837771)
			(xy 353.432894 -279.88705) (xy 353.441 -279.938227) (xy 353.441508 -279.964134) (xy 353.441095 -279.9895)
			(xy 353.433341 -280.039635) (xy 353.417991 -280.087988) (xy 353.395408 -280.133416) (xy 353.366127 -280.174843)
			(xy 353.330839 -280.211291) (xy 353.290379 -280.241896) (xy 353.245705 -280.265935) (xy 353.197873 -280.282839)
			(xy 353.17303 -280.287984) (xy 353.149916 -280.292302) (xy 352.944938 -280.647394) (xy 352.952812 -280.669492)
			(xy 352.961371 -280.695851) (xy 352.970571 -280.750496) (xy 352.9711 -280.778204) (xy 352.970592 -280.804091)
			(xy 352.962493 -280.855229) (xy 352.946494 -280.904469) (xy 352.922988 -280.950601) (xy 352.892556 -280.992488)
			(xy 352.855946 -281.029098) (xy 352.814059 -281.05953) (xy 352.767927 -281.083036) (xy 352.718687 -281.099035)
			(xy 352.667549 -281.107134) (xy 352.615775 -281.107134) (xy 352.564637 -281.099035) (xy 352.515397 -281.083036)
			(xy 352.469265 -281.05953) (xy 352.427378 -281.029098) (xy 352.390768 -280.992488) (xy 352.360336 -280.950601)
			(xy 352.33683 -280.904469) (xy 352.320831 -280.855229) (xy 352.312732 -280.804091) (xy 352.312224 -280.778204)
			(xy 352.0313 -280.778204) (xy 352.030742 -280.805848) (xy 352.021555 -280.860366) (xy 352.013012 -280.886662)
			(xy 352.005392 -280.908506) (xy 352.210624 -281.263852) (xy 352.233484 -281.26817) (xy 352.258305 -281.273337)
			(xy 352.306082 -281.290294) (xy 352.350699 -281.314367) (xy 352.391104 -281.344988) (xy 352.426344 -281.381435)
			(xy 352.455588 -281.422848) (xy 352.478145 -281.46825) (xy 352.493485 -281.516571) (xy 352.501244 -281.566671)
			(xy 352.501708 -281.59202) (xy 352.5012 -281.617927) (xy 352.493094 -281.669104) (xy 352.477082 -281.718383)
			(xy 352.453559 -281.76455) (xy 352.423103 -281.806469) (xy 352.386465 -281.843107) (xy 352.344546 -281.873563)
			(xy 352.298379 -281.897086) (xy 352.2491 -281.913098) (xy 352.197923 -281.921204) (xy 352.146109 -281.921204)
			(xy 352.094932 -281.913098) (xy 352.045653 -281.897086) (xy 351.999486 -281.873563) (xy 351.957567 -281.843107)
			(xy 351.920929 -281.806469) (xy 351.890473 -281.76455) (xy 351.86695 -281.718383) (xy 351.850938 -281.669104)
			(xy 351.842832 -281.617927) (xy 351.842324 -281.59202) (xy 351.842922 -281.564303) (xy 351.852242 -281.509656)
			(xy 351.860866 -281.483308) (xy 351.86874 -281.46121) (xy 351.663762 -281.106372) (xy 351.640902 -281.102054)
			(xy 351.616072 -281.096882) (xy 351.568266 -281.079946) (xy 351.523618 -281.055889) (xy 351.483181 -281.025278)
			(xy 351.447909 -280.988835) (xy 351.418634 -280.947421) (xy 351.396047 -280.902011) (xy 351.380681 -280.853678)
			(xy 351.372898 -280.803562) (xy 351.372424 -280.778204) (xy 349.2119 -280.778204) (xy 349.211342 -280.805848)
			(xy 349.202155 -280.860366) (xy 349.193612 -280.886662) (xy 349.185992 -280.908506) (xy 349.391224 -281.263852)
			(xy 349.414084 -281.26817) (xy 349.438905 -281.273337) (xy 349.486682 -281.290294) (xy 349.531299 -281.314367)
			(xy 349.571704 -281.344988) (xy 349.606944 -281.381435) (xy 349.636188 -281.422848) (xy 349.658745 -281.46825)
			(xy 349.674085 -281.516571) (xy 349.681844 -281.566671) (xy 349.682308 -281.59202) (xy 349.6818 -281.617927)
			(xy 349.673694 -281.669104) (xy 349.657682 -281.718383) (xy 349.634159 -281.76455) (xy 349.603703 -281.806469)
			(xy 349.567065 -281.843107) (xy 349.525146 -281.873563) (xy 349.478979 -281.897086) (xy 349.4297 -281.913098)
			(xy 349.378523 -281.921204) (xy 349.326709 -281.921204) (xy 349.275532 -281.913098) (xy 349.226253 -281.897086)
			(xy 349.180086 -281.873563) (xy 349.138167 -281.843107) (xy 349.101529 -281.806469) (xy 349.071073 -281.76455)
			(xy 349.04755 -281.718383) (xy 349.031538 -281.669104) (xy 349.023432 -281.617927) (xy 349.022924 -281.59202)
			(xy 349.023522 -281.564303) (xy 349.032842 -281.509656) (xy 349.041466 -281.483308) (xy 349.04934 -281.46121)
			(xy 348.844362 -281.106372) (xy 348.821502 -281.102054) (xy 348.796672 -281.096882) (xy 348.748866 -281.079946)
			(xy 348.704218 -281.055889) (xy 348.663781 -281.025278) (xy 348.628509 -280.988835) (xy 348.599234 -280.947421)
			(xy 348.576647 -280.902011) (xy 348.561281 -280.853678) (xy 348.553498 -280.803562) (xy 348.553024 -280.778204)
			(xy 346.3925 -280.778204) (xy 346.392021 -280.803539) (xy 346.384268 -280.853611) (xy 346.368945 -280.901908)
			(xy 346.346413 -280.947292) (xy 346.317203 -280.988694) (xy 346.282002 -281.025139) (xy 346.241639 -281.055769)
			(xy 346.197065 -281.079864) (xy 346.14933 -281.096855) (xy 346.12453 -281.102054) (xy 346.10167 -281.106372)
			(xy 345.896692 -281.46121) (xy 345.904566 -281.483308) (xy 345.913205 -281.509652) (xy 345.922521 -281.564301)
			(xy 345.923108 -281.59202) (xy 345.9226 -281.617909) (xy 347.143809 -281.617909) (xy 347.143809 -281.566091)
			(xy 347.151916 -281.514912) (xy 347.167929 -281.465631) (xy 347.191454 -281.419462) (xy 347.221912 -281.377541)
			(xy 347.258553 -281.340902) (xy 347.300475 -281.310446) (xy 347.346646 -281.286923) (xy 347.395928 -281.270912)
			(xy 347.447107 -281.262808) (xy 347.473016 -281.262328) (xy 347.498529 -281.262786) (xy 347.548945 -281.27065)
			(xy 347.597547 -281.286187) (xy 347.643176 -281.309027) (xy 347.684741 -281.338624) (xy 347.721249 -281.374271)
			(xy 347.736922 -281.394408) (xy 348.14891 -281.394408) (xy 348.16458 -281.37427) (xy 348.20109 -281.338625)
			(xy 348.242656 -281.309032) (xy 348.288285 -281.286196) (xy 348.336888 -281.270663) (xy 348.387304 -281.262804)
			(xy 348.412816 -281.262328) (xy 348.438724 -281.262797) (xy 348.489902 -281.270905) (xy 348.539182 -281.286919)
			(xy 348.585349 -281.310445) (xy 348.627269 -281.340903) (xy 348.663907 -281.377543) (xy 348.694363 -281.419464)
			(xy 348.717887 -281.465633) (xy 348.733899 -281.514914) (xy 348.742004 -281.566092) (xy 348.742004 -281.617908)
			(xy 348.733899 -281.669086) (xy 348.717887 -281.718367) (xy 348.694363 -281.764536) (xy 348.663907 -281.806457)
			(xy 348.627269 -281.843097) (xy 348.585349 -281.873555) (xy 348.539182 -281.897081) (xy 348.489902 -281.913095)
			(xy 348.438724 -281.921203) (xy 348.412816 -281.921712) (xy 348.387305 -281.921215) (xy 348.336891 -281.913357)
			(xy 348.28829 -281.897827) (xy 348.242662 -281.874994) (xy 348.201096 -281.845405) (xy 348.164585 -281.809765)
			(xy 348.14891 -281.789632) (xy 347.736922 -281.789632) (xy 347.721245 -281.809764) (xy 347.684735 -281.845407)
			(xy 347.64317 -281.875) (xy 347.597542 -281.897836) (xy 347.548942 -281.913371) (xy 347.498528 -281.921234)
			(xy 347.473016 -281.921712) (xy 347.447107 -281.921192) (xy 347.395928 -281.913088) (xy 347.346646 -281.897077)
			(xy 347.300475 -281.873554) (xy 347.258553 -281.843098) (xy 347.221912 -281.806459) (xy 347.191454 -281.764538)
			(xy 347.167929 -281.718369) (xy 347.151916 -281.669088) (xy 347.143809 -281.617909) (xy 345.9226 -281.617909)
			(xy 345.9226 -281.617927) (xy 345.914494 -281.669104) (xy 345.898482 -281.718383) (xy 345.874959 -281.76455)
			(xy 345.844503 -281.806469) (xy 345.807865 -281.843107) (xy 345.765946 -281.873563) (xy 345.719779 -281.897086)
			(xy 345.6705 -281.913098) (xy 345.619323 -281.921204) (xy 345.567509 -281.921204) (xy 345.516332 -281.913098)
			(xy 345.467053 -281.897086) (xy 345.420886 -281.873563) (xy 345.378967 -281.843107) (xy 345.342329 -281.806469)
			(xy 345.311873 -281.76455) (xy 345.28835 -281.718383) (xy 345.272338 -281.669104) (xy 345.264232 -281.617927)
			(xy 345.263724 -281.59202) (xy 344.043508 -281.59202) (xy 344.043045 -281.617395) (xy 344.035274 -281.667545)
			(xy 344.019903 -281.71591) (xy 343.997297 -281.761346) (xy 343.967989 -281.802777) (xy 343.932674 -281.839223)
			(xy 343.892188 -281.869822) (xy 343.847487 -281.893849) (xy 343.79963 -281.910736) (xy 343.774776 -281.91587)
			(xy 343.751916 -281.920188) (xy 343.546938 -282.275026) (xy 343.554812 -282.297124) (xy 343.563378 -282.32348)
			(xy 343.572573 -282.378127) (xy 343.5731 -282.405836) (xy 343.854024 -282.405836) (xy 343.854532 -282.379949)
			(xy 343.862631 -282.328811) (xy 343.87863 -282.279571) (xy 343.902136 -282.233439) (xy 343.932568 -282.191552)
			(xy 343.969178 -282.154942) (xy 344.011065 -282.12451) (xy 344.057197 -282.101004) (xy 344.106437 -282.085005)
			(xy 344.157575 -282.076906) (xy 344.209349 -282.076906) (xy 344.260487 -282.085005) (xy 344.309727 -282.101004)
			(xy 344.355859 -282.12451) (xy 344.397746 -282.154942) (xy 344.434356 -282.191552) (xy 344.464788 -282.233439)
			(xy 344.488294 -282.279571) (xy 344.504293 -282.328811) (xy 344.512392 -282.379949) (xy 344.5129 -282.405836)
			(xy 344.512385 -282.431703) (xy 344.794152 -282.431703) (xy 344.794152 -282.379897) (xy 344.802256 -282.32873)
			(xy 344.818263 -282.27946) (xy 344.841781 -282.2333) (xy 344.872229 -282.191388) (xy 344.908859 -282.154754)
			(xy 344.950768 -282.124301) (xy 344.996925 -282.100778) (xy 345.046193 -282.084765) (xy 345.097359 -282.076655)
			(xy 345.123262 -282.076144) (xy 345.148774 -282.076635) (xy 345.199188 -282.084491) (xy 345.247791 -282.100021)
			(xy 345.293419 -282.122855) (xy 345.334985 -282.152446) (xy 345.371495 -282.188089) (xy 345.387168 -282.208224)
			(xy 345.799156 -282.208224) (xy 345.814861 -282.188115) (xy 345.851364 -282.152468) (xy 345.892922 -282.122871)
			(xy 345.938545 -282.10003) (xy 345.987141 -282.084491) (xy 346.037552 -282.076624) (xy 346.063062 -282.076144)
			(xy 346.088976 -282.076551) (xy 346.140167 -282.084653) (xy 346.18946 -282.100664) (xy 346.235642 -282.12419)
			(xy 346.277574 -282.154651) (xy 346.314224 -282.191297) (xy 346.34469 -282.233226) (xy 346.368221 -282.279404)
			(xy 346.384238 -282.328696) (xy 346.392346 -282.379886) (xy 346.392346 -282.431714) (xy 346.384238 -282.482904)
			(xy 346.368221 -282.532196) (xy 346.34469 -282.578374) (xy 346.314224 -282.620303) (xy 346.277574 -282.656949)
			(xy 346.235642 -282.68741) (xy 346.18946 -282.710936) (xy 346.140167 -282.726947) (xy 346.088976 -282.735049)
			(xy 346.063062 -282.735528) (xy 346.03755 -282.735064) (xy 345.987135 -282.727199) (xy 345.938534 -282.711661)
			(xy 345.892906 -282.688822) (xy 345.85134 -282.659228) (xy 345.81483 -282.623584) (xy 345.799156 -282.603448)
			(xy 345.387168 -282.603448) (xy 345.371526 -282.623609) (xy 345.335009 -282.659249) (xy 345.293436 -282.688839)
			(xy 345.247802 -282.71167) (xy 345.199195 -282.727199) (xy 345.148776 -282.735054) (xy 345.123262 -282.735528)
			(xy 345.097359 -282.734945) (xy 345.046193 -282.726835) (xy 344.996925 -282.710822) (xy 344.950768 -282.687299)
			(xy 344.908859 -282.656846) (xy 344.872229 -282.620212) (xy 344.841781 -282.5783) (xy 344.818263 -282.53214)
			(xy 344.802256 -282.48287) (xy 344.794152 -282.431703) (xy 344.512385 -282.431703) (xy 344.51235 -282.43348)
			(xy 344.503158 -282.487998) (xy 344.494612 -282.514294) (xy 344.486992 -282.536392) (xy 344.692224 -282.891738)
			(xy 344.715084 -282.896056) (xy 344.739902 -282.901236) (xy 344.787678 -282.918192) (xy 344.832294 -282.942264)
			(xy 344.872699 -282.972884) (xy 344.907939 -283.009329) (xy 344.937183 -283.05074) (xy 344.959741 -283.09614)
			(xy 344.975082 -283.14446) (xy 344.982843 -283.194558) (xy 344.983308 -283.219906) (xy 347.143324 -283.219906)
			(xy 347.143831 -283.194562) (xy 347.151603 -283.144472) (xy 347.166948 -283.096161) (xy 347.189506 -283.050768)
			(xy 347.218745 -283.009362) (xy 347.253975 -282.972918) (xy 347.294368 -282.942295) (xy 347.338972 -282.918214)
			(xy 347.386736 -282.901243) (xy 347.411548 -282.896056) (xy 347.434408 -282.891738) (xy 347.639386 -282.5369)
			(xy 347.631766 -282.514802) (xy 347.623129 -282.488391) (xy 347.613803 -282.433617) (xy 347.613224 -282.405836)
			(xy 347.613732 -282.379949) (xy 347.621831 -282.328811) (xy 347.63783 -282.279571) (xy 347.661336 -282.233439)
			(xy 347.691768 -282.191552) (xy 347.728378 -282.154942) (xy 347.770265 -282.12451) (xy 347.816397 -282.101004)
			(xy 347.865637 -282.085005) (xy 347.916775 -282.076906) (xy 347.968549 -282.076906) (xy 348.019687 -282.085005)
			(xy 348.068927 -282.101004) (xy 348.115059 -282.12451) (xy 348.156946 -282.154942) (xy 348.193556 -282.191552)
			(xy 348.223988 -282.233439) (xy 348.247494 -282.279571) (xy 348.263493 -282.328811) (xy 348.271592 -282.379949)
			(xy 348.2721 -282.405836) (xy 349.492824 -282.405836) (xy 349.493229 -282.380499) (xy 349.500992 -282.330422)
			(xy 349.516324 -282.282122) (xy 349.538866 -282.236737) (xy 349.568085 -282.195335) (xy 349.603295 -282.15889)
			(xy 349.643666 -282.128262) (xy 349.688248 -282.10417) (xy 349.735991 -282.087183) (xy 349.760794 -282.081986)
			(xy 349.783654 -282.077668) (xy 349.988886 -281.722322) (xy 349.981266 -281.700478) (xy 349.97264 -281.674196)
			(xy 349.963326 -281.619675) (xy 349.962724 -281.59202) (xy 349.963232 -281.566113) (xy 349.971338 -281.514936)
			(xy 349.98735 -281.465657) (xy 350.010873 -281.41949) (xy 350.041329 -281.377571) (xy 350.077967 -281.340933)
			(xy 350.119886 -281.310477) (xy 350.166053 -281.286954) (xy 350.215332 -281.270942) (xy 350.266509 -281.262836)
			(xy 350.318323 -281.262836) (xy 350.3695 -281.270942) (xy 350.418779 -281.286954) (xy 350.464946 -281.310477)
			(xy 350.506865 -281.340933) (xy 350.543503 -281.377571) (xy 350.573959 -281.41949) (xy 350.597482 -281.465657)
			(xy 350.613494 -281.514936) (xy 350.6216 -281.566113) (xy 350.622108 -281.59202) (xy 350.621645 -281.617395)
			(xy 350.613874 -281.667545) (xy 350.598503 -281.71591) (xy 350.575897 -281.761346) (xy 350.546589 -281.802777)
			(xy 350.511274 -281.839223) (xy 350.470788 -281.869822) (xy 350.426087 -281.893849) (xy 350.37823 -281.910736)
			(xy 350.353376 -281.91587) (xy 350.330516 -281.920188) (xy 350.125538 -282.275026) (xy 350.133412 -282.297124)
			(xy 350.141978 -282.32348) (xy 350.151173 -282.378127) (xy 350.1517 -282.405836) (xy 350.151192 -282.431703)
			(xy 351.372752 -282.431703) (xy 351.372752 -282.379897) (xy 351.380856 -282.32873) (xy 351.396863 -282.27946)
			(xy 351.420381 -282.2333) (xy 351.450829 -282.191388) (xy 351.487459 -282.154754) (xy 351.529368 -282.124301)
			(xy 351.575525 -282.100778) (xy 351.624793 -282.084765) (xy 351.675959 -282.076655) (xy 351.701862 -282.076144)
			(xy 351.727374 -282.076635) (xy 351.777788 -282.084491) (xy 351.826391 -282.100021) (xy 351.872019 -282.122855)
			(xy 351.913585 -282.152446) (xy 351.950095 -282.188089) (xy 351.965768 -282.208224) (xy 352.377756 -282.208224)
			(xy 352.393461 -282.188115) (xy 352.429964 -282.152468) (xy 352.471522 -282.122871) (xy 352.517145 -282.10003)
			(xy 352.565741 -282.084491) (xy 352.616152 -282.076624) (xy 352.641662 -282.076144) (xy 352.667576 -282.076551)
			(xy 352.718767 -282.084653) (xy 352.76806 -282.100664) (xy 352.814242 -282.12419) (xy 352.856174 -282.154651)
			(xy 352.892824 -282.191297) (xy 352.92329 -282.233226) (xy 352.946821 -282.279404) (xy 352.962838 -282.328696)
			(xy 352.970946 -282.379886) (xy 352.970946 -282.431714) (xy 352.962838 -282.482904) (xy 352.946821 -282.532196)
			(xy 352.92329 -282.578374) (xy 352.892824 -282.620303) (xy 352.856174 -282.656949) (xy 352.814242 -282.68741)
			(xy 352.76806 -282.710936) (xy 352.718767 -282.726947) (xy 352.667576 -282.735049) (xy 352.641662 -282.735528)
			(xy 352.61615 -282.735064) (xy 352.565735 -282.727199) (xy 352.517134 -282.711661) (xy 352.471506 -282.688822)
			(xy 352.42994 -282.659228) (xy 352.39343 -282.623584) (xy 352.377756 -282.603448) (xy 351.965768 -282.603448)
			(xy 351.950126 -282.623609) (xy 351.913609 -282.659249) (xy 351.872036 -282.688839) (xy 351.826402 -282.71167)
			(xy 351.777795 -282.727199) (xy 351.727376 -282.735054) (xy 351.701862 -282.735528) (xy 351.675959 -282.734945)
			(xy 351.624793 -282.726835) (xy 351.575525 -282.710822) (xy 351.529368 -282.687299) (xy 351.487459 -282.656846)
			(xy 351.450829 -282.620212) (xy 351.420381 -282.5783) (xy 351.396863 -282.53214) (xy 351.380856 -282.48287)
			(xy 351.372752 -282.431703) (xy 350.151192 -282.431703) (xy 350.151192 -282.431723) (xy 350.143093 -282.482861)
			(xy 350.127094 -282.532101) (xy 350.103588 -282.578233) (xy 350.073156 -282.62012) (xy 350.036546 -282.65673)
			(xy 349.994659 -282.687162) (xy 349.948527 -282.710668) (xy 349.899287 -282.726667) (xy 349.848149 -282.734766)
			(xy 349.796375 -282.734766) (xy 349.745237 -282.726667) (xy 349.695997 -282.710668) (xy 349.649865 -282.687162)
			(xy 349.607978 -282.65673) (xy 349.571368 -282.62012) (xy 349.540936 -282.578233) (xy 349.51743 -282.532101)
			(xy 349.501431 -282.482861) (xy 349.493332 -282.431723) (xy 349.492824 -282.405836) (xy 348.2721 -282.405836)
			(xy 348.271608 -282.431158) (xy 348.263872 -282.481209) (xy 348.248573 -282.529487) (xy 348.22607 -282.574858)
			(xy 348.196893 -282.616254) (xy 348.161729 -282.6527) (xy 348.121404 -282.68334) (xy 348.076868 -282.707453)
			(xy 348.029168 -282.72447) (xy 348.004384 -282.729686) (xy 347.981524 -282.734004) (xy 347.776292 -283.089096)
			(xy 347.784166 -283.111194) (xy 347.792802 -283.137539) (xy 347.80212 -283.192188) (xy 347.802708 -283.219906)
			(xy 347.8022 -283.24579) (xy 349.023649 -283.24579) (xy 349.023649 -283.19401) (xy 349.03175 -283.142868)
			(xy 349.047751 -283.093623) (xy 349.071259 -283.047487) (xy 349.101695 -283.005597) (xy 349.13831 -282.968985)
			(xy 349.180201 -282.938551) (xy 349.226338 -282.915045) (xy 349.275584 -282.899046) (xy 349.326726 -282.890948)
			(xy 349.352616 -282.890468) (xy 349.378128 -282.890949) (xy 349.428541 -282.898811) (xy 349.477143 -282.914346)
			(xy 349.522771 -282.937181) (xy 349.564336 -282.966773) (xy 349.600848 -283.002414) (xy 349.616522 -283.022548)
			(xy 350.02851 -283.022548) (xy 350.044163 -283.002397) (xy 350.080679 -282.966756) (xy 350.122249 -282.937166)
			(xy 350.167881 -282.914333) (xy 350.216486 -282.898802) (xy 350.266903 -282.890944) (xy 350.292416 -282.890468)
			(xy 350.318303 -282.890965) (xy 350.369439 -282.899066) (xy 350.418679 -282.915067) (xy 350.464809 -282.938574)
			(xy 350.506694 -282.969007) (xy 350.543303 -283.005618) (xy 350.573735 -283.047505) (xy 350.597239 -283.093636)
			(xy 350.613237 -283.142876) (xy 350.621336 -283.194013) (xy 350.621336 -283.245787) (xy 350.613237 -283.296924)
			(xy 350.597239 -283.346164) (xy 350.573735 -283.392295) (xy 350.543303 -283.434182) (xy 350.506694 -283.470793)
			(xy 350.464809 -283.501226) (xy 350.418679 -283.524733) (xy 350.369439 -283.540734) (xy 350.318303 -283.548835)
			(xy 350.292416 -283.549344) (xy 350.266904 -283.548874) (xy 350.216488 -283.541014) (xy 350.167885 -283.52548)
			(xy 350.122256 -283.502643) (xy 350.080691 -283.473047) (xy 350.044182 -283.437401) (xy 350.02851 -283.417264)
			(xy 349.616522 -283.417264) (xy 349.600826 -283.437381) (xy 349.564322 -283.473028) (xy 349.522762 -283.502625)
			(xy 349.477138 -283.525464) (xy 349.428539 -283.541001) (xy 349.378127 -283.548865) (xy 349.352616 -283.549344)
			(xy 349.326726 -283.548852) (xy 349.275584 -283.540754) (xy 349.226338 -283.524755) (xy 349.180201 -283.501249)
			(xy 349.13831 -283.470815) (xy 349.101695 -283.434203) (xy 349.071259 -283.392313) (xy 349.047751 -283.346177)
			(xy 349.03175 -283.296932) (xy 349.023649 -283.24579) (xy 347.8022 -283.24579) (xy 347.8022 -283.245813)
			(xy 347.794094 -283.29699) (xy 347.778082 -283.346269) (xy 347.754559 -283.392436) (xy 347.724103 -283.434355)
			(xy 347.687465 -283.470993) (xy 347.645546 -283.501449) (xy 347.599379 -283.524972) (xy 347.5501 -283.540984)
			(xy 347.498923 -283.54909) (xy 347.447109 -283.54909) (xy 347.395932 -283.540984) (xy 347.346653 -283.524972)
			(xy 347.300486 -283.501449) (xy 347.258567 -283.470993) (xy 347.221929 -283.434355) (xy 347.191473 -283.392436)
			(xy 347.16795 -283.346269) (xy 347.151938 -283.29699) (xy 347.143832 -283.245813) (xy 347.143324 -283.219906)
			(xy 344.983308 -283.219906) (xy 344.9828 -283.245813) (xy 344.974694 -283.29699) (xy 344.958682 -283.346269)
			(xy 344.935159 -283.392436) (xy 344.904703 -283.434355) (xy 344.868065 -283.470993) (xy 344.826146 -283.501449)
			(xy 344.779979 -283.524972) (xy 344.7307 -283.540984) (xy 344.679523 -283.54909) (xy 344.627709 -283.54909)
			(xy 344.576532 -283.540984) (xy 344.527253 -283.524972) (xy 344.481086 -283.501449) (xy 344.439167 -283.470993)
			(xy 344.402529 -283.434355) (xy 344.372073 -283.392436) (xy 344.34855 -283.346269) (xy 344.332538 -283.29699)
			(xy 344.324432 -283.245813) (xy 344.323924 -283.219906) (xy 344.324518 -283.192189) (xy 344.333841 -283.137542)
			(xy 344.342466 -283.111194) (xy 344.35034 -283.089096) (xy 344.145362 -282.734004) (xy 344.122248 -282.729686)
			(xy 344.097423 -282.724538) (xy 344.049642 -282.707582) (xy 344.005022 -282.683508) (xy 343.964615 -282.652886)
			(xy 343.929374 -282.616436) (xy 343.900131 -282.57502) (xy 343.877575 -282.529614) (xy 343.862239 -282.481289)
			(xy 343.854484 -282.431186) (xy 343.854024 -282.405836) (xy 343.5731 -282.405836) (xy 343.572592 -282.431723)
			(xy 343.564493 -282.482861) (xy 343.548494 -282.532101) (xy 343.524988 -282.578233) (xy 343.494556 -282.62012)
			(xy 343.457946 -282.65673) (xy 343.416059 -282.687162) (xy 343.369927 -282.710668) (xy 343.320687 -282.726667)
			(xy 343.269549 -282.734766) (xy 343.217775 -282.734766) (xy 343.166637 -282.726667) (xy 343.117397 -282.710668)
			(xy 343.071265 -282.687162) (xy 343.029378 -282.65673) (xy 342.992768 -282.62012) (xy 342.962336 -282.578233)
			(xy 342.93883 -282.532101) (xy 342.922831 -282.482861) (xy 342.914732 -282.431723) (xy 342.914224 -282.405836)
			(xy 341.694008 -282.405836) (xy 341.6935 -282.431743) (xy 341.685394 -282.48292) (xy 341.669382 -282.532199)
			(xy 341.645859 -282.578366) (xy 341.615403 -282.620285) (xy 341.578765 -282.656923) (xy 341.536846 -282.687379)
			(xy 341.490679 -282.710902) (xy 341.4414 -282.726914) (xy 341.390223 -282.73502) (xy 341.338409 -282.73502)
			(xy 341.287232 -282.726914) (xy 341.237953 -282.710902) (xy 341.191786 -282.687379) (xy 341.149867 -282.656923)
			(xy 341.113229 -282.620285) (xy 341.082773 -282.578366) (xy 341.05925 -282.532199) (xy 341.043238 -282.48292)
			(xy 341.035132 -282.431743) (xy 341.034624 -282.405836) (xy 339.814408 -282.405836) (xy 339.813997 -282.431202)
			(xy 339.806243 -282.481337) (xy 339.790893 -282.52969) (xy 339.768309 -282.575118) (xy 339.739027 -282.616545)
			(xy 339.703739 -282.652993) (xy 339.663279 -282.683598) (xy 339.618605 -282.707637) (xy 339.570773 -282.724541)
			(xy 339.54593 -282.729686) (xy 339.52307 -282.734004) (xy 339.318092 -283.089096) (xy 339.325712 -283.11094)
			(xy 339.33426 -283.137236) (xy 339.343458 -283.191753) (xy 339.344 -283.219398) (xy 339.344 -283.219906)
			(xy 339.343492 -283.245785) (xy 340.565275 -283.245785) (xy 340.565275 -283.194015) (xy 340.573373 -283.142882)
			(xy 340.58937 -283.093646) (xy 340.612872 -283.047517) (xy 340.643299 -283.005633) (xy 340.679904 -282.969024)
			(xy 340.721785 -282.938592) (xy 340.76791 -282.915085) (xy 340.817145 -282.899082) (xy 340.868277 -282.890978)
			(xy 340.894162 -282.890468) (xy 340.919672 -282.890989) (xy 340.970084 -282.898843) (xy 341.018684 -282.914369)
			(xy 341.064312 -282.937197) (xy 341.105879 -282.966782) (xy 341.142392 -283.002417) (xy 341.158068 -283.022548)
			(xy 341.570056 -283.022548) (xy 341.585741 -283.002422) (xy 341.62225 -282.96678) (xy 341.663813 -282.937187)
			(xy 341.709439 -282.91435) (xy 341.758039 -282.898813) (xy 341.808451 -282.890948) (xy 341.833962 -282.890468)
			(xy 341.859854 -282.890934) (xy 341.911001 -282.89903) (xy 341.960252 -282.915027) (xy 342.006393 -282.938533)
			(xy 342.048289 -282.968968) (xy 342.084908 -283.005582) (xy 342.115347 -283.047475) (xy 342.138858 -283.093613)
			(xy 342.154861 -283.142862) (xy 342.162963 -283.194008) (xy 342.162963 -283.245792) (xy 342.154861 -283.296938)
			(xy 342.138858 -283.346187) (xy 342.115347 -283.392325) (xy 342.084908 -283.434218) (xy 342.048289 -283.470832)
			(xy 342.006393 -283.501267) (xy 341.960252 -283.524773) (xy 341.911001 -283.54077) (xy 341.859854 -283.548866)
			(xy 341.833962 -283.549344) (xy 341.808448 -283.548913) (xy 341.75803 -283.541045) (xy 341.709427 -283.525503)
			(xy 341.663798 -283.502658) (xy 341.622234 -283.473056) (xy 341.585727 -283.437404) (xy 341.570056 -283.417264)
			(xy 341.158068 -283.417264) (xy 341.142404 -283.437407) (xy 341.105893 -283.473052) (xy 341.064326 -283.502646)
			(xy 341.018696 -283.525481) (xy 340.970092 -283.541013) (xy 340.919675 -283.548869) (xy 340.894162 -283.549344)
			(xy 340.868277 -283.548822) (xy 340.817145 -283.540718) (xy 340.76791 -283.524715) (xy 340.721785 -283.501208)
			(xy 340.679904 -283.470776) (xy 340.643299 -283.434167) (xy 340.612872 -283.392283) (xy 340.58937 -283.346154)
			(xy 340.573373 -283.296918) (xy 340.565275 -283.245785) (xy 339.343492 -283.245785) (xy 339.343492 -283.245793)
			(xy 339.335393 -283.296931) (xy 339.319394 -283.346171) (xy 339.295888 -283.392303) (xy 339.265456 -283.43419)
			(xy 339.228846 -283.4708) (xy 339.186959 -283.501232) (xy 339.140827 -283.524738) (xy 339.091587 -283.540737)
			(xy 339.040449 -283.548836) (xy 338.988675 -283.548836) (xy 338.937537 -283.540737) (xy 338.888297 -283.524738)
			(xy 338.842165 -283.501232) (xy 338.800278 -283.4708) (xy 338.763668 -283.43419) (xy 338.733236 -283.392303)
			(xy 338.70973 -283.346171) (xy 338.693731 -283.296931) (xy 338.685632 -283.245793) (xy 338.685124 -283.219906)
			(xy 336.5246 -283.219906) (xy 336.524092 -283.245793) (xy 336.515993 -283.296931) (xy 336.499994 -283.346171)
			(xy 336.476488 -283.392303) (xy 336.446056 -283.43419) (xy 336.409446 -283.4708) (xy 336.367559 -283.501232)
			(xy 336.321427 -283.524738) (xy 336.272187 -283.540737) (xy 336.221049 -283.548836) (xy 336.169275 -283.548836)
			(xy 336.118137 -283.540737) (xy 336.068897 -283.524738) (xy 336.022765 -283.501232) (xy 335.980878 -283.4708)
			(xy 335.944268 -283.43419) (xy 335.913836 -283.392303) (xy 335.89033 -283.346171) (xy 335.874331 -283.296931)
			(xy 335.866232 -283.245793) (xy 335.865724 -283.219906) (xy 335.866254 -283.192198) (xy 335.875449 -283.137551)
			(xy 335.884012 -283.111194) (xy 335.891886 -283.089096) (xy 335.686654 -282.734004) (xy 335.663794 -282.729686)
			(xy 335.639001 -282.724454) (xy 335.591266 -282.707468) (xy 335.546691 -282.683379) (xy 335.506327 -282.652753)
			(xy 335.471124 -282.616312) (xy 335.441911 -282.574914) (xy 335.419375 -282.529534) (xy 335.404048 -282.48124)
			(xy 335.396291 -282.43117) (xy 335.395824 -282.405836) (xy 335.115408 -282.405836) (xy 335.1149 -282.431743)
			(xy 335.106794 -282.48292) (xy 335.090782 -282.532199) (xy 335.067259 -282.578366) (xy 335.036803 -282.620285)
			(xy 335.000165 -282.656923) (xy 334.958246 -282.687379) (xy 334.912079 -282.710902) (xy 334.8628 -282.726914)
			(xy 334.811623 -282.73502) (xy 334.759809 -282.73502) (xy 334.708632 -282.726914) (xy 334.659353 -282.710902)
			(xy 334.613186 -282.687379) (xy 334.571267 -282.656923) (xy 334.534629 -282.620285) (xy 334.504173 -282.578366)
			(xy 334.48065 -282.532199) (xy 334.464638 -282.48292) (xy 334.456532 -282.431743) (xy 334.456024 -282.405836)
			(xy 284.8356 -282.405836) (xy 284.8356 -284.033722) (xy 334.456024 -284.033722) (xy 334.456532 -284.007815)
			(xy 334.464638 -283.956638) (xy 334.48065 -283.907359) (xy 334.504173 -283.861192) (xy 334.534629 -283.819273)
			(xy 334.571267 -283.782635) (xy 334.613186 -283.752179) (xy 334.659353 -283.728656) (xy 334.708632 -283.712644)
			(xy 334.759809 -283.704538) (xy 334.811623 -283.704538) (xy 334.8628 -283.712644) (xy 334.912079 -283.728656)
			(xy 334.958246 -283.752179) (xy 335.000165 -283.782635) (xy 335.036803 -283.819273) (xy 335.067259 -283.861192)
			(xy 335.090782 -283.907359) (xy 335.106794 -283.956638) (xy 335.1149 -284.007815) (xy 335.115408 -284.033722)
			(xy 335.114819 -284.06144) (xy 335.105492 -284.116086) (xy 335.096866 -284.142434) (xy 335.088992 -284.164532)
			(xy 335.29397 -284.51937) (xy 335.31683 -284.523688) (xy 335.341643 -284.528833) (xy 335.389384 -284.545828)
			(xy 335.433962 -284.569927) (xy 335.474328 -284.600564) (xy 335.50953 -284.637016) (xy 335.538741 -284.678425)
			(xy 335.561271 -284.723817) (xy 335.576591 -284.772121) (xy 335.584339 -284.8222) (xy 335.5848 -284.847538)
			(xy 335.584292 -284.873425) (xy 335.576193 -284.924563) (xy 335.560194 -284.973803) (xy 335.536688 -285.019935)
			(xy 335.506256 -285.061822) (xy 335.469646 -285.098432) (xy 335.427759 -285.128864) (xy 335.381627 -285.15237)
			(xy 335.332387 -285.168369) (xy 335.281249 -285.176468) (xy 335.229475 -285.176468) (xy 335.178337 -285.168369)
			(xy 335.129097 -285.15237) (xy 335.082965 -285.128864) (xy 335.041078 -285.098432) (xy 335.004468 -285.061822)
			(xy 334.974036 -285.019935) (xy 334.95053 -284.973803) (xy 334.934531 -284.924563) (xy 334.926432 -284.873425)
			(xy 334.925924 -284.847538) (xy 334.926462 -284.81983) (xy 334.935651 -284.765183) (xy 334.944212 -284.738826)
			(xy 334.952086 -284.716728) (xy 334.747108 -284.36189) (xy 334.724248 -284.357572) (xy 334.699419 -284.352437)
			(xy 334.651638 -284.33548) (xy 334.607017 -284.311405) (xy 334.56661 -284.280781) (xy 334.531369 -284.24433)
			(xy 334.502126 -284.202912) (xy 334.479571 -284.157504) (xy 334.464236 -284.109178) (xy 334.456483 -284.059073)
			(xy 334.456024 -284.033722) (xy 284.8356 -284.033722) (xy 284.8356 -284.873383) (xy 333.046907 -284.873383)
			(xy 333.046907 -284.821618) (xy 333.055005 -284.77049) (xy 333.071 -284.721258) (xy 333.094499 -284.675134)
			(xy 333.124924 -284.633254) (xy 333.161525 -284.596648) (xy 333.203402 -284.566219) (xy 333.249523 -284.542714)
			(xy 333.298753 -284.526713) (xy 333.34988 -284.51861) (xy 333.375762 -284.5181) (xy 333.401254 -284.518612)
			(xy 333.451631 -284.526467) (xy 333.500193 -284.541996) (xy 333.54578 -284.564827) (xy 333.587302 -284.594415)
			(xy 333.623765 -284.63005) (xy 333.639414 -284.65018) (xy 334.05191 -284.65018) (xy 334.067576 -284.630063)
			(xy 334.104034 -284.594421) (xy 334.145551 -284.564826) (xy 334.191135 -284.541986) (xy 334.239694 -284.526447)
			(xy 334.290069 -284.518581) (xy 334.315562 -284.5181) (xy 334.341456 -284.518502) (xy 334.392608 -284.526599)
			(xy 334.441864 -284.542598) (xy 334.48801 -284.566106) (xy 334.52991 -284.596543) (xy 334.566532 -284.633161)
			(xy 334.596975 -284.675058) (xy 334.620488 -284.721201) (xy 334.636492 -284.770455) (xy 334.644595 -284.821606)
			(xy 334.644595 -284.873394) (xy 334.636492 -284.924545) (xy 334.620488 -284.973799) (xy 334.596975 -285.019942)
			(xy 334.566532 -285.061839) (xy 334.52991 -285.098457) (xy 334.48801 -285.128894) (xy 334.441864 -285.152402)
			(xy 334.392608 -285.168401) (xy 334.341456 -285.176498) (xy 334.315562 -285.176976) (xy 334.290067 -285.176529)
			(xy 334.239687 -285.168661) (xy 334.191123 -285.15312) (xy 334.145536 -285.130277) (xy 334.104016 -285.100678)
			(xy 334.067557 -285.065031) (xy 334.05191 -285.044896) (xy 333.639414 -285.044896) (xy 333.623786 -285.065045)
			(xy 333.587321 -285.100686) (xy 333.545796 -285.130277) (xy 333.500205 -285.153112) (xy 333.451638 -285.168644)
			(xy 333.401257 -285.176501) (xy 333.375762 -285.176976) (xy 333.34988 -285.17639) (xy 333.298753 -285.168287)
			(xy 333.249523 -285.152286) (xy 333.203402 -285.128781) (xy 333.161525 -285.098352) (xy 333.124924 -285.061746)
			(xy 333.094499 -285.019866) (xy 333.071 -284.973742) (xy 333.055005 -284.92451) (xy 333.046907 -284.873383)
			(xy 284.8356 -284.873383) (xy 284.8356 -285.661354) (xy 335.395824 -285.661354) (xy 335.396245 -285.636017)
			(xy 335.404005 -285.585941) (xy 335.419335 -285.537642) (xy 335.441875 -285.492257) (xy 335.471092 -285.450854)
			(xy 335.5063 -285.41441) (xy 335.54667 -285.383781) (xy 335.59125 -285.359689) (xy 335.638992 -285.342701)
			(xy 335.663794 -285.337504) (xy 335.686654 -285.333186) (xy 335.891632 -284.978094) (xy 335.884012 -284.95625)
			(xy 335.875447 -284.929893) (xy 335.86625 -284.875247) (xy 335.865724 -284.847538) (xy 335.866232 -284.821651)
			(xy 335.874331 -284.770513) (xy 335.89033 -284.721273) (xy 335.913836 -284.675141) (xy 335.944268 -284.633254)
			(xy 335.980878 -284.596644) (xy 336.022765 -284.566212) (xy 336.068897 -284.542706) (xy 336.118137 -284.526707)
			(xy 336.169275 -284.518608) (xy 336.221049 -284.518608) (xy 336.272187 -284.526707) (xy 336.321427 -284.542706)
			(xy 336.367559 -284.566212) (xy 336.409446 -284.596644) (xy 336.446056 -284.633254) (xy 336.476488 -284.675141)
			(xy 336.499994 -284.721273) (xy 336.515993 -284.770513) (xy 336.524092 -284.821651) (xy 336.5246 -284.847538)
			(xy 336.524152 -284.872874) (xy 336.516394 -284.922948) (xy 336.501066 -284.971245) (xy 336.47853 -285.016629)
			(xy 336.449316 -285.058031) (xy 336.414111 -285.094476) (xy 336.373746 -285.125106) (xy 336.329169 -285.149199)
			(xy 336.281431 -285.16619) (xy 336.25663 -285.171388) (xy 336.23377 -285.175706) (xy 336.028792 -285.530798)
			(xy 336.036412 -285.552642) (xy 336.044976 -285.578999) (xy 336.054174 -285.633646) (xy 336.0547 -285.661354)
			(xy 337.275424 -285.661354) (xy 337.275932 -285.635467) (xy 337.284031 -285.584329) (xy 337.30003 -285.535089)
			(xy 337.323536 -285.488957) (xy 337.353968 -285.44707) (xy 337.390578 -285.41046) (xy 337.432465 -285.380028)
			(xy 337.478597 -285.356522) (xy 337.527837 -285.340523) (xy 337.578975 -285.332424) (xy 337.630749 -285.332424)
			(xy 337.681887 -285.340523) (xy 337.731127 -285.356522) (xy 337.777259 -285.380028) (xy 337.819146 -285.41046)
			(xy 337.855756 -285.44707) (xy 337.886188 -285.488957) (xy 337.909694 -285.535089) (xy 337.925693 -285.584329)
			(xy 337.933792 -285.635467) (xy 337.9343 -285.661354) (xy 338.215224 -285.661354) (xy 338.215684 -285.636008)
			(xy 338.223463 -285.585916) (xy 338.238816 -285.537605) (xy 338.26138 -285.492212) (xy 338.290625 -285.450806)
			(xy 338.325861 -285.414363) (xy 338.366259 -285.383741) (xy 338.410867 -285.359661) (xy 338.458634 -285.34269)
			(xy 338.483448 -285.337504) (xy 338.506308 -285.333186) (xy 338.711286 -284.978348) (xy 338.703412 -284.956504)
			(xy 338.694834 -284.930085) (xy 338.685636 -284.87531) (xy 338.685124 -284.847538) (xy 338.685632 -284.821651)
			(xy 338.693731 -284.770513) (xy 338.70973 -284.721273) (xy 338.733236 -284.675141) (xy 338.763668 -284.633254)
			(xy 338.800278 -284.596644) (xy 338.842165 -284.566212) (xy 338.888297 -284.542706) (xy 338.937537 -284.526707)
			(xy 338.988675 -284.518608) (xy 339.040449 -284.518608) (xy 339.091587 -284.526707) (xy 339.140827 -284.542706)
			(xy 339.186959 -284.566212) (xy 339.228846 -284.596644) (xy 339.265456 -284.633254) (xy 339.295888 -284.675141)
			(xy 339.319394 -284.721273) (xy 339.335393 -284.770513) (xy 339.343492 -284.821651) (xy 339.344 -284.847538)
			(xy 339.343552 -284.872874) (xy 339.335794 -284.922948) (xy 339.320466 -284.971245) (xy 339.29793 -285.016629)
			(xy 339.268716 -285.058031) (xy 339.233511 -285.094476) (xy 339.193146 -285.125106) (xy 339.148569 -285.149199)
			(xy 339.100831 -285.16619) (xy 339.07603 -285.171388) (xy 339.05317 -285.175706) (xy 338.848192 -285.530544)
			(xy 338.856066 -285.552642) (xy 338.86469 -285.578991) (xy 338.874015 -285.633637) (xy 338.874608 -285.661354)
			(xy 339.155024 -285.661354) (xy 339.155532 -285.635447) (xy 339.163638 -285.58427) (xy 339.17965 -285.534991)
			(xy 339.203173 -285.488824) (xy 339.233629 -285.446905) (xy 339.270267 -285.410267) (xy 339.312186 -285.379811)
			(xy 339.358353 -285.356288) (xy 339.407632 -285.340276) (xy 339.458809 -285.33217) (xy 339.510623 -285.33217)
			(xy 339.5618 -285.340276) (xy 339.611079 -285.356288) (xy 339.657246 -285.379811) (xy 339.699165 -285.410267)
			(xy 339.735803 -285.446905) (xy 339.766259 -285.488824) (xy 339.789782 -285.534991) (xy 339.805794 -285.58427)
			(xy 339.8139 -285.635447) (xy 339.814408 -285.661354) (xy 340.094824 -285.661354) (xy 340.095245 -285.636017)
			(xy 340.103005 -285.585941) (xy 340.118335 -285.537642) (xy 340.140875 -285.492257) (xy 340.170092 -285.450854)
			(xy 340.2053 -285.41441) (xy 340.24567 -285.383781) (xy 340.29025 -285.359689) (xy 340.337992 -285.342701)
			(xy 340.362794 -285.337504) (xy 340.385654 -285.333186) (xy 340.590886 -284.97784) (xy 340.583266 -284.955996)
			(xy 340.574644 -284.929713) (xy 340.565327 -284.875193) (xy 340.564724 -284.847538) (xy 340.565232 -284.821631)
			(xy 340.573338 -284.770454) (xy 340.58935 -284.721175) (xy 340.612873 -284.675008) (xy 340.643329 -284.633089)
			(xy 340.679967 -284.596451) (xy 340.721886 -284.565995) (xy 340.768053 -284.542472) (xy 340.817332 -284.52646)
			(xy 340.868509 -284.518354) (xy 340.920323 -284.518354) (xy 340.9715 -284.52646) (xy 341.020779 -284.542472)
			(xy 341.066946 -284.565995) (xy 341.108865 -284.596451) (xy 341.145503 -284.633089) (xy 341.175959 -284.675008)
			(xy 341.199482 -284.721175) (xy 341.215494 -284.770454) (xy 341.2236 -284.821631) (xy 341.224108 -284.847538)
			(xy 341.223661 -284.872913) (xy 341.215887 -284.923064) (xy 341.200514 -284.97143) (xy 341.177905 -285.016866)
			(xy 341.148596 -285.058297) (xy 341.113279 -285.094742) (xy 341.072791 -285.125341) (xy 341.028089 -285.149367)
			(xy 340.980231 -285.166254) (xy 340.955376 -285.171388) (xy 340.932516 -285.175706) (xy 340.727538 -285.530544)
			(xy 340.735412 -285.552642) (xy 340.743983 -285.578997) (xy 340.753175 -285.633645) (xy 340.7537 -285.661354)
			(xy 341.034624 -285.661354) (xy 341.035132 -285.635467) (xy 341.043231 -285.584329) (xy 341.05923 -285.535089)
			(xy 341.082736 -285.488957) (xy 341.113168 -285.44707) (xy 341.149778 -285.41046) (xy 341.191665 -285.380028)
			(xy 341.237797 -285.356522) (xy 341.287037 -285.340523) (xy 341.338175 -285.332424) (xy 341.389949 -285.332424)
			(xy 341.441087 -285.340523) (xy 341.490327 -285.356522) (xy 341.536459 -285.380028) (xy 341.578346 -285.41046)
			(xy 341.614956 -285.44707) (xy 341.645388 -285.488957) (xy 341.668894 -285.535089) (xy 341.684893 -285.584329)
			(xy 341.692992 -285.635467) (xy 341.6935 -285.661354) (xy 341.974424 -285.661354) (xy 341.974845 -285.636017)
			(xy 341.982605 -285.585941) (xy 341.997935 -285.537642) (xy 342.020475 -285.492257) (xy 342.049692 -285.450854)
			(xy 342.0849 -285.41441) (xy 342.12527 -285.383781) (xy 342.16985 -285.359689) (xy 342.217592 -285.342701)
			(xy 342.242394 -285.337504) (xy 342.265254 -285.333186) (xy 342.470486 -284.97784) (xy 342.462866 -284.955996)
			(xy 342.454244 -284.929713) (xy 342.444927 -284.875193) (xy 342.444324 -284.847538) (xy 342.444832 -284.821631)
			(xy 342.452938 -284.770454) (xy 342.46895 -284.721175) (xy 342.492473 -284.675008) (xy 342.522929 -284.633089)
			(xy 342.559567 -284.596451) (xy 342.601486 -284.565995) (xy 342.647653 -284.542472) (xy 342.696932 -284.52646)
			(xy 342.748109 -284.518354) (xy 342.799923 -284.518354) (xy 342.8511 -284.52646) (xy 342.900379 -284.542472)
			(xy 342.946546 -284.565995) (xy 342.988465 -284.596451) (xy 343.025103 -284.633089) (xy 343.055559 -284.675008)
			(xy 343.079082 -284.721175) (xy 343.095094 -284.770454) (xy 343.1032 -284.821631) (xy 343.103708 -284.847538)
			(xy 343.103261 -284.872913) (xy 343.095487 -284.923064) (xy 343.080114 -284.97143) (xy 343.057505 -285.016866)
			(xy 343.028196 -285.058297) (xy 342.992879 -285.094742) (xy 342.952391 -285.125341) (xy 342.907689 -285.149367)
			(xy 342.859831 -285.166254) (xy 342.834976 -285.171388) (xy 342.812116 -285.175706) (xy 342.607138 -285.530544)
			(xy 342.615012 -285.552642) (xy 342.623583 -285.578997) (xy 342.632775 -285.633645) (xy 342.6333 -285.661354)
			(xy 342.914224 -285.661354) (xy 342.914732 -285.635467) (xy 342.922831 -285.584329) (xy 342.93883 -285.535089)
			(xy 342.962336 -285.488957) (xy 342.992768 -285.44707) (xy 343.029378 -285.41046) (xy 343.071265 -285.380028)
			(xy 343.117397 -285.356522) (xy 343.166637 -285.340523) (xy 343.217775 -285.332424) (xy 343.269549 -285.332424)
			(xy 343.320687 -285.340523) (xy 343.369927 -285.356522) (xy 343.416059 -285.380028) (xy 343.457946 -285.41046)
			(xy 343.494556 -285.44707) (xy 343.524988 -285.488957) (xy 343.548494 -285.535089) (xy 343.564493 -285.584329)
			(xy 343.572592 -285.635467) (xy 343.5731 -285.661354) (xy 343.854024 -285.661354) (xy 343.854445 -285.636017)
			(xy 343.862205 -285.585941) (xy 343.877535 -285.537642) (xy 343.900075 -285.492257) (xy 343.929292 -285.450854)
			(xy 343.9645 -285.41441) (xy 344.00487 -285.383781) (xy 344.04945 -285.359689) (xy 344.097192 -285.342701)
			(xy 344.121994 -285.337504) (xy 344.144854 -285.333186) (xy 344.350086 -284.97784) (xy 344.342466 -284.955996)
			(xy 344.333844 -284.929713) (xy 344.324527 -284.875193) (xy 344.323924 -284.847538) (xy 344.324432 -284.821631)
			(xy 344.332538 -284.770454) (xy 344.34855 -284.721175) (xy 344.372073 -284.675008) (xy 344.402529 -284.633089)
			(xy 344.439167 -284.596451) (xy 344.481086 -284.565995) (xy 344.527253 -284.542472) (xy 344.576532 -284.52646)
			(xy 344.627709 -284.518354) (xy 344.679523 -284.518354) (xy 344.7307 -284.52646) (xy 344.779979 -284.542472)
			(xy 344.826146 -284.565995) (xy 344.868065 -284.596451) (xy 344.904703 -284.633089) (xy 344.935159 -284.675008)
			(xy 344.958682 -284.721175) (xy 344.974694 -284.770454) (xy 344.9828 -284.821631) (xy 344.983308 -284.847538)
			(xy 344.982861 -284.872913) (xy 344.975087 -284.923064) (xy 344.959714 -284.97143) (xy 344.937105 -285.016866)
			(xy 344.907796 -285.058297) (xy 344.872479 -285.094742) (xy 344.831991 -285.125341) (xy 344.787289 -285.149367)
			(xy 344.739431 -285.166254) (xy 344.714576 -285.171388) (xy 344.691716 -285.175706) (xy 344.486738 -285.530544)
			(xy 344.494612 -285.552642) (xy 344.503183 -285.578997) (xy 344.512375 -285.633645) (xy 344.5129 -285.661354)
			(xy 344.793824 -285.661354) (xy 344.794332 -285.635467) (xy 344.802431 -285.584329) (xy 344.81843 -285.535089)
			(xy 344.841936 -285.488957) (xy 344.872368 -285.44707) (xy 344.908978 -285.41046) (xy 344.950865 -285.380028)
			(xy 344.996997 -285.356522) (xy 345.046237 -285.340523) (xy 345.097375 -285.332424) (xy 345.149149 -285.332424)
			(xy 345.200287 -285.340523) (xy 345.249527 -285.356522) (xy 345.295659 -285.380028) (xy 345.337546 -285.41046)
			(xy 345.374156 -285.44707) (xy 345.404588 -285.488957) (xy 345.428094 -285.535089) (xy 345.444093 -285.584329)
			(xy 345.452192 -285.635467) (xy 345.4527 -285.661354) (xy 345.733624 -285.661354) (xy 345.734045 -285.636017)
			(xy 345.741805 -285.585941) (xy 345.757135 -285.537642) (xy 345.779675 -285.492257) (xy 345.808892 -285.450854)
			(xy 345.8441 -285.41441) (xy 345.88447 -285.383781) (xy 345.92905 -285.359689) (xy 345.976792 -285.342701)
			(xy 346.001594 -285.337504) (xy 346.024454 -285.333186) (xy 346.229686 -284.97784) (xy 346.222066 -284.955996)
			(xy 346.213444 -284.929713) (xy 346.204127 -284.875193) (xy 346.203524 -284.847538) (xy 346.204032 -284.821631)
			(xy 346.212138 -284.770454) (xy 346.22815 -284.721175) (xy 346.251673 -284.675008) (xy 346.282129 -284.633089)
			(xy 346.318767 -284.596451) (xy 346.360686 -284.565995) (xy 346.406853 -284.542472) (xy 346.456132 -284.52646)
			(xy 346.507309 -284.518354) (xy 346.559123 -284.518354) (xy 346.6103 -284.52646) (xy 346.659579 -284.542472)
			(xy 346.705746 -284.565995) (xy 346.747665 -284.596451) (xy 346.784303 -284.633089) (xy 346.814759 -284.675008)
			(xy 346.838282 -284.721175) (xy 346.854294 -284.770454) (xy 346.8624 -284.821631) (xy 346.862908 -284.847538)
			(xy 346.862461 -284.872913) (xy 346.854687 -284.923064) (xy 346.839314 -284.97143) (xy 346.816705 -285.016866)
			(xy 346.787396 -285.058297) (xy 346.752079 -285.094742) (xy 346.711591 -285.125341) (xy 346.666889 -285.149367)
			(xy 346.619031 -285.166254) (xy 346.594176 -285.171388) (xy 346.571316 -285.175706) (xy 346.366338 -285.530544)
			(xy 346.374212 -285.552642) (xy 346.382783 -285.578997) (xy 346.391975 -285.633645) (xy 346.3925 -285.661354)
			(xy 346.673424 -285.661354) (xy 346.673932 -285.635467) (xy 346.682031 -285.584329) (xy 346.69803 -285.535089)
			(xy 346.721536 -285.488957) (xy 346.751968 -285.44707) (xy 346.788578 -285.41046) (xy 346.830465 -285.380028)
			(xy 346.876597 -285.356522) (xy 346.925837 -285.340523) (xy 346.976975 -285.332424) (xy 347.028749 -285.332424)
			(xy 347.079887 -285.340523) (xy 347.129127 -285.356522) (xy 347.175259 -285.380028) (xy 347.217146 -285.41046)
			(xy 347.253756 -285.44707) (xy 347.284188 -285.488957) (xy 347.307694 -285.535089) (xy 347.323693 -285.584329)
			(xy 347.331792 -285.635467) (xy 347.3323 -285.661354) (xy 347.613224 -285.661354) (xy 347.613645 -285.636017)
			(xy 347.621405 -285.585941) (xy 347.636735 -285.537642) (xy 347.659275 -285.492257) (xy 347.688492 -285.450854)
			(xy 347.7237 -285.41441) (xy 347.76407 -285.383781) (xy 347.80865 -285.359689) (xy 347.856392 -285.342701)
			(xy 347.881194 -285.337504) (xy 347.904054 -285.333186) (xy 348.109286 -284.97784) (xy 348.101666 -284.955996)
			(xy 348.093044 -284.929713) (xy 348.083727 -284.875193) (xy 348.083124 -284.847538) (xy 348.083632 -284.821631)
			(xy 348.091738 -284.770454) (xy 348.10775 -284.721175) (xy 348.131273 -284.675008) (xy 348.161729 -284.633089)
			(xy 348.198367 -284.596451) (xy 348.240286 -284.565995) (xy 348.286453 -284.542472) (xy 348.335732 -284.52646)
			(xy 348.386909 -284.518354) (xy 348.438723 -284.518354) (xy 348.4899 -284.52646) (xy 348.539179 -284.542472)
			(xy 348.585346 -284.565995) (xy 348.627265 -284.596451) (xy 348.663903 -284.633089) (xy 348.694359 -284.675008)
			(xy 348.717882 -284.721175) (xy 348.733894 -284.770454) (xy 348.742 -284.821631) (xy 348.742508 -284.847538)
			(xy 348.742061 -284.872913) (xy 348.734287 -284.923064) (xy 348.718914 -284.97143) (xy 348.696305 -285.016866)
			(xy 348.666996 -285.058297) (xy 348.631679 -285.094742) (xy 348.591191 -285.125341) (xy 348.546489 -285.149367)
			(xy 348.498631 -285.166254) (xy 348.473776 -285.171388) (xy 348.450916 -285.175706) (xy 348.245938 -285.530544)
			(xy 348.253812 -285.552642) (xy 348.262383 -285.578997) (xy 348.271575 -285.633645) (xy 348.2721 -285.661354)
			(xy 348.553024 -285.661354) (xy 348.553532 -285.635467) (xy 348.561631 -285.584329) (xy 348.57763 -285.535089)
			(xy 348.601136 -285.488957) (xy 348.631568 -285.44707) (xy 348.668178 -285.41046) (xy 348.710065 -285.380028)
			(xy 348.756197 -285.356522) (xy 348.805437 -285.340523) (xy 348.856575 -285.332424) (xy 348.908349 -285.332424)
			(xy 348.959487 -285.340523) (xy 349.008727 -285.356522) (xy 349.054859 -285.380028) (xy 349.096746 -285.41046)
			(xy 349.133356 -285.44707) (xy 349.163788 -285.488957) (xy 349.187294 -285.535089) (xy 349.203293 -285.584329)
			(xy 349.211392 -285.635467) (xy 349.2119 -285.661354) (xy 349.492824 -285.661354) (xy 349.493245 -285.636017)
			(xy 349.501005 -285.585941) (xy 349.516335 -285.537642) (xy 349.538875 -285.492257) (xy 349.568092 -285.450854)
			(xy 349.6033 -285.41441) (xy 349.64367 -285.383781) (xy 349.68825 -285.359689) (xy 349.735992 -285.342701)
			(xy 349.760794 -285.337504) (xy 349.783654 -285.333186) (xy 349.988886 -284.97784) (xy 349.981266 -284.955996)
			(xy 349.972644 -284.929713) (xy 349.963327 -284.875193) (xy 349.962724 -284.847538) (xy 349.963232 -284.821631)
			(xy 349.971338 -284.770454) (xy 349.98735 -284.721175) (xy 350.010873 -284.675008) (xy 350.041329 -284.633089)
			(xy 350.077967 -284.596451) (xy 350.119886 -284.565995) (xy 350.166053 -284.542472) (xy 350.215332 -284.52646)
			(xy 350.266509 -284.518354) (xy 350.318323 -284.518354) (xy 350.3695 -284.52646) (xy 350.418779 -284.542472)
			(xy 350.464946 -284.565995) (xy 350.506865 -284.596451) (xy 350.543503 -284.633089) (xy 350.573959 -284.675008)
			(xy 350.597482 -284.721175) (xy 350.613494 -284.770454) (xy 350.6216 -284.821631) (xy 350.622108 -284.847538)
			(xy 350.621661 -284.872913) (xy 350.613887 -284.923064) (xy 350.598514 -284.97143) (xy 350.575905 -285.016866)
			(xy 350.546596 -285.058297) (xy 350.511279 -285.094742) (xy 350.470791 -285.125341) (xy 350.426089 -285.149367)
			(xy 350.378231 -285.166254) (xy 350.353376 -285.171388) (xy 350.330516 -285.175706) (xy 350.125538 -285.530544)
			(xy 350.133412 -285.552642) (xy 350.141983 -285.578997) (xy 350.151175 -285.633645) (xy 350.1517 -285.661354)
			(xy 350.432624 -285.661354) (xy 350.433132 -285.635467) (xy 350.441231 -285.584329) (xy 350.45723 -285.535089)
			(xy 350.480736 -285.488957) (xy 350.511168 -285.44707) (xy 350.547778 -285.41046) (xy 350.589665 -285.380028)
			(xy 350.635797 -285.356522) (xy 350.685037 -285.340523) (xy 350.736175 -285.332424) (xy 350.787949 -285.332424)
			(xy 350.839087 -285.340523) (xy 350.888327 -285.356522) (xy 350.934459 -285.380028) (xy 350.976346 -285.41046)
			(xy 351.012956 -285.44707) (xy 351.043388 -285.488957) (xy 351.066894 -285.535089) (xy 351.082893 -285.584329)
			(xy 351.090992 -285.635467) (xy 351.0915 -285.661354) (xy 351.090955 -285.688998) (xy 351.081759 -285.743516)
			(xy 351.073212 -285.769812) (xy 351.065592 -285.79191) (xy 351.270824 -286.147256) (xy 351.293684 -286.151574)
			(xy 351.318506 -286.156737) (xy 351.366283 -286.173695) (xy 351.410901 -286.197768) (xy 351.451306 -286.22839)
			(xy 351.486546 -286.264837) (xy 351.515789 -286.30625) (xy 351.538346 -286.351653) (xy 351.553685 -286.399975)
			(xy 351.561445 -286.450075) (xy 351.561908 -286.475424) (xy 351.5614 -286.501331) (xy 351.553294 -286.552508)
			(xy 351.537282 -286.601787) (xy 351.513759 -286.647954) (xy 351.483303 -286.689873) (xy 351.446665 -286.726511)
			(xy 351.404746 -286.756967) (xy 351.358579 -286.78049) (xy 351.3093 -286.796502) (xy 351.258123 -286.804608)
			(xy 351.206309 -286.804608) (xy 351.155132 -286.796502) (xy 351.105853 -286.78049) (xy 351.059686 -286.756967)
			(xy 351.017767 -286.726511) (xy 350.981129 -286.689873) (xy 350.950673 -286.647954) (xy 350.92715 -286.601787)
			(xy 350.911138 -286.552508) (xy 350.903032 -286.501331) (xy 350.902524 -286.475424) (xy 350.903123 -286.447707)
			(xy 350.912443 -286.39306) (xy 350.921066 -286.366712) (xy 350.92894 -286.344614) (xy 350.723962 -285.989522)
			(xy 350.700848 -285.985204) (xy 350.676027 -285.980039) (xy 350.628247 -285.963084) (xy 350.583628 -285.939012)
			(xy 350.543222 -285.908392) (xy 350.507981 -285.871945) (xy 350.478737 -285.830531) (xy 350.45618 -285.785127)
			(xy 350.440843 -285.736804) (xy 350.433086 -285.686703) (xy 350.432624 -285.661354) (xy 350.1517 -285.661354)
			(xy 350.151192 -285.687241) (xy 350.143093 -285.738379) (xy 350.127094 -285.787619) (xy 350.103588 -285.833751)
			(xy 350.073156 -285.875638) (xy 350.036546 -285.912248) (xy 349.994659 -285.94268) (xy 349.948527 -285.966186)
			(xy 349.899287 -285.982185) (xy 349.848149 -285.990284) (xy 349.796375 -285.990284) (xy 349.745237 -285.982185)
			(xy 349.695997 -285.966186) (xy 349.649865 -285.94268) (xy 349.607978 -285.912248) (xy 349.571368 -285.875638)
			(xy 349.540936 -285.833751) (xy 349.51743 -285.787619) (xy 349.501431 -285.738379) (xy 349.493332 -285.687241)
			(xy 349.492824 -285.661354) (xy 349.2119 -285.661354) (xy 349.211355 -285.688998) (xy 349.202159 -285.743516)
			(xy 349.193612 -285.769812) (xy 349.185992 -285.79191) (xy 349.391224 -286.147256) (xy 349.414084 -286.151574)
			(xy 349.438906 -286.156737) (xy 349.486683 -286.173695) (xy 349.531301 -286.197768) (xy 349.571706 -286.22839)
			(xy 349.606946 -286.264837) (xy 349.636189 -286.30625) (xy 349.658746 -286.351653) (xy 349.674085 -286.399975)
			(xy 349.681845 -286.450075) (xy 349.682308 -286.475424) (xy 349.6818 -286.501331) (xy 349.673694 -286.552508)
			(xy 349.657682 -286.601787) (xy 349.634159 -286.647954) (xy 349.603703 -286.689873) (xy 349.567065 -286.726511)
			(xy 349.525146 -286.756967) (xy 349.478979 -286.78049) (xy 349.4297 -286.796502) (xy 349.378523 -286.804608)
			(xy 349.326709 -286.804608) (xy 349.275532 -286.796502) (xy 349.226253 -286.78049) (xy 349.180086 -286.756967)
			(xy 349.138167 -286.726511) (xy 349.101529 -286.689873) (xy 349.071073 -286.647954) (xy 349.04755 -286.601787)
			(xy 349.031538 -286.552508) (xy 349.023432 -286.501331) (xy 349.022924 -286.475424) (xy 349.023523 -286.447707)
			(xy 349.032843 -286.39306) (xy 349.041466 -286.366712) (xy 349.04934 -286.344614) (xy 348.844362 -285.989522)
			(xy 348.821248 -285.985204) (xy 348.796427 -285.980039) (xy 348.748647 -285.963084) (xy 348.704028 -285.939012)
			(xy 348.663622 -285.908392) (xy 348.628381 -285.871945) (xy 348.599137 -285.830531) (xy 348.57658 -285.785127)
			(xy 348.561243 -285.736804) (xy 348.553486 -285.686703) (xy 348.553024 -285.661354) (xy 348.2721 -285.661354)
			(xy 348.271592 -285.687241) (xy 348.263493 -285.738379) (xy 348.247494 -285.787619) (xy 348.223988 -285.833751)
			(xy 348.193556 -285.875638) (xy 348.156946 -285.912248) (xy 348.115059 -285.94268) (xy 348.068927 -285.966186)
			(xy 348.019687 -285.982185) (xy 347.968549 -285.990284) (xy 347.916775 -285.990284) (xy 347.865637 -285.982185)
			(xy 347.816397 -285.966186) (xy 347.770265 -285.94268) (xy 347.728378 -285.912248) (xy 347.691768 -285.875638)
			(xy 347.661336 -285.833751) (xy 347.63783 -285.787619) (xy 347.621831 -285.738379) (xy 347.613732 -285.687241)
			(xy 347.613224 -285.661354) (xy 347.3323 -285.661354) (xy 347.331755 -285.688998) (xy 347.322559 -285.743516)
			(xy 347.314012 -285.769812) (xy 347.306392 -285.79191) (xy 347.511624 -286.147256) (xy 347.534484 -286.151574)
			(xy 347.559306 -286.156737) (xy 347.607083 -286.173695) (xy 347.651701 -286.197768) (xy 347.692106 -286.22839)
			(xy 347.727346 -286.264837) (xy 347.756589 -286.30625) (xy 347.779146 -286.351653) (xy 347.794485 -286.399975)
			(xy 347.802245 -286.450075) (xy 347.802708 -286.475424) (xy 347.8022 -286.501331) (xy 347.794094 -286.552508)
			(xy 347.778082 -286.601787) (xy 347.754559 -286.647954) (xy 347.724103 -286.689873) (xy 347.687465 -286.726511)
			(xy 347.645546 -286.756967) (xy 347.599379 -286.78049) (xy 347.5501 -286.796502) (xy 347.498923 -286.804608)
			(xy 347.447109 -286.804608) (xy 347.395932 -286.796502) (xy 347.346653 -286.78049) (xy 347.300486 -286.756967)
			(xy 347.258567 -286.726511) (xy 347.221929 -286.689873) (xy 347.191473 -286.647954) (xy 347.16795 -286.601787)
			(xy 347.151938 -286.552508) (xy 347.143832 -286.501331) (xy 347.143324 -286.475424) (xy 347.143923 -286.447707)
			(xy 347.153243 -286.39306) (xy 347.161866 -286.366712) (xy 347.16974 -286.344614) (xy 346.964762 -285.989522)
			(xy 346.941648 -285.985204) (xy 346.916827 -285.980039) (xy 346.869047 -285.963084) (xy 346.824428 -285.939012)
			(xy 346.784022 -285.908392) (xy 346.748781 -285.871945) (xy 346.719537 -285.830531) (xy 346.69698 -285.785127)
			(xy 346.681643 -285.736804) (xy 346.673886 -285.686703) (xy 346.673424 -285.661354) (xy 346.3925 -285.661354)
			(xy 346.391992 -285.687241) (xy 346.383893 -285.738379) (xy 346.367894 -285.787619) (xy 346.344388 -285.833751)
			(xy 346.313956 -285.875638) (xy 346.277346 -285.912248) (xy 346.235459 -285.94268) (xy 346.189327 -285.966186)
			(xy 346.140087 -285.982185) (xy 346.088949 -285.990284) (xy 346.037175 -285.990284) (xy 345.986037 -285.982185)
			(xy 345.936797 -285.966186) (xy 345.890665 -285.94268) (xy 345.848778 -285.912248) (xy 345.812168 -285.875638)
			(xy 345.781736 -285.833751) (xy 345.75823 -285.787619) (xy 345.742231 -285.738379) (xy 345.734132 -285.687241)
			(xy 345.733624 -285.661354) (xy 345.4527 -285.661354) (xy 345.452155 -285.688998) (xy 345.442959 -285.743516)
			(xy 345.434412 -285.769812) (xy 345.426792 -285.79191) (xy 345.632024 -286.147256) (xy 345.654884 -286.151574)
			(xy 345.679706 -286.156737) (xy 345.727483 -286.173695) (xy 345.772101 -286.197768) (xy 345.812506 -286.22839)
			(xy 345.847746 -286.264837) (xy 345.876989 -286.30625) (xy 345.899546 -286.351653) (xy 345.914885 -286.399975)
			(xy 345.922645 -286.450075) (xy 345.923108 -286.475424) (xy 345.9226 -286.501331) (xy 345.914494 -286.552508)
			(xy 345.898482 -286.601787) (xy 345.874959 -286.647954) (xy 345.844503 -286.689873) (xy 345.807865 -286.726511)
			(xy 345.765946 -286.756967) (xy 345.719779 -286.78049) (xy 345.6705 -286.796502) (xy 345.619323 -286.804608)
			(xy 345.567509 -286.804608) (xy 345.516332 -286.796502) (xy 345.467053 -286.78049) (xy 345.420886 -286.756967)
			(xy 345.378967 -286.726511) (xy 345.342329 -286.689873) (xy 345.311873 -286.647954) (xy 345.28835 -286.601787)
			(xy 345.272338 -286.552508) (xy 345.264232 -286.501331) (xy 345.263724 -286.475424) (xy 345.264323 -286.447707)
			(xy 345.273643 -286.39306) (xy 345.282266 -286.366712) (xy 345.29014 -286.344614) (xy 345.085162 -285.989522)
			(xy 345.062048 -285.985204) (xy 345.037227 -285.980039) (xy 344.989447 -285.963084) (xy 344.944828 -285.939012)
			(xy 344.904422 -285.908392) (xy 344.869181 -285.871945) (xy 344.839937 -285.830531) (xy 344.81738 -285.785127)
			(xy 344.802043 -285.736804) (xy 344.794286 -285.686703) (xy 344.793824 -285.661354) (xy 344.5129 -285.661354)
			(xy 344.512392 -285.687241) (xy 344.504293 -285.738379) (xy 344.488294 -285.787619) (xy 344.464788 -285.833751)
			(xy 344.434356 -285.875638) (xy 344.397746 -285.912248) (xy 344.355859 -285.94268) (xy 344.309727 -285.966186)
			(xy 344.260487 -285.982185) (xy 344.209349 -285.990284) (xy 344.157575 -285.990284) (xy 344.106437 -285.982185)
			(xy 344.057197 -285.966186) (xy 344.011065 -285.94268) (xy 343.969178 -285.912248) (xy 343.932568 -285.875638)
			(xy 343.902136 -285.833751) (xy 343.87863 -285.787619) (xy 343.862631 -285.738379) (xy 343.854532 -285.687241)
			(xy 343.854024 -285.661354) (xy 343.5731 -285.661354) (xy 343.572555 -285.688998) (xy 343.563359 -285.743516)
			(xy 343.554812 -285.769812) (xy 343.547192 -285.79191) (xy 343.752424 -286.147256) (xy 343.775284 -286.151574)
			(xy 343.800106 -286.156737) (xy 343.847883 -286.173695) (xy 343.892501 -286.197768) (xy 343.932906 -286.22839)
			(xy 343.968146 -286.264837) (xy 343.997389 -286.30625) (xy 344.019946 -286.351653) (xy 344.035285 -286.399975)
			(xy 344.043045 -286.450075) (xy 344.043508 -286.475424) (xy 344.043 -286.501331) (xy 344.034894 -286.552508)
			(xy 344.018882 -286.601787) (xy 343.995359 -286.647954) (xy 343.964903 -286.689873) (xy 343.928265 -286.726511)
			(xy 343.886346 -286.756967) (xy 343.840179 -286.78049) (xy 343.7909 -286.796502) (xy 343.739723 -286.804608)
			(xy 343.687909 -286.804608) (xy 343.636732 -286.796502) (xy 343.587453 -286.78049) (xy 343.541286 -286.756967)
			(xy 343.499367 -286.726511) (xy 343.462729 -286.689873) (xy 343.432273 -286.647954) (xy 343.40875 -286.601787)
			(xy 343.392738 -286.552508) (xy 343.384632 -286.501331) (xy 343.384124 -286.475424) (xy 343.384723 -286.447707)
			(xy 343.394043 -286.39306) (xy 343.402666 -286.366712) (xy 343.41054 -286.344614) (xy 343.205562 -285.989522)
			(xy 343.182448 -285.985204) (xy 343.157627 -285.980039) (xy 343.109847 -285.963084) (xy 343.065228 -285.939012)
			(xy 343.024822 -285.908392) (xy 342.989581 -285.871945) (xy 342.960337 -285.830531) (xy 342.93778 -285.785127)
			(xy 342.922443 -285.736804) (xy 342.914686 -285.686703) (xy 342.914224 -285.661354) (xy 342.6333 -285.661354)
			(xy 342.632792 -285.687241) (xy 342.624693 -285.738379) (xy 342.608694 -285.787619) (xy 342.585188 -285.833751)
			(xy 342.554756 -285.875638) (xy 342.518146 -285.912248) (xy 342.476259 -285.94268) (xy 342.430127 -285.966186)
			(xy 342.380887 -285.982185) (xy 342.329749 -285.990284) (xy 342.277975 -285.990284) (xy 342.226837 -285.982185)
			(xy 342.177597 -285.966186) (xy 342.131465 -285.94268) (xy 342.089578 -285.912248) (xy 342.052968 -285.875638)
			(xy 342.022536 -285.833751) (xy 341.99903 -285.787619) (xy 341.983031 -285.738379) (xy 341.974932 -285.687241)
			(xy 341.974424 -285.661354) (xy 341.6935 -285.661354) (xy 341.692955 -285.688998) (xy 341.683759 -285.743516)
			(xy 341.675212 -285.769812) (xy 341.667592 -285.79191) (xy 341.872824 -286.147256) (xy 341.895684 -286.151574)
			(xy 341.920506 -286.156737) (xy 341.968283 -286.173695) (xy 342.012901 -286.197768) (xy 342.053306 -286.22839)
			(xy 342.088546 -286.264837) (xy 342.117789 -286.30625) (xy 342.140346 -286.351653) (xy 342.155685 -286.399975)
			(xy 342.163445 -286.450075) (xy 342.163908 -286.475424) (xy 342.1634 -286.501331) (xy 342.155294 -286.552508)
			(xy 342.139282 -286.601787) (xy 342.115759 -286.647954) (xy 342.085303 -286.689873) (xy 342.048665 -286.726511)
			(xy 342.006746 -286.756967) (xy 341.960579 -286.78049) (xy 341.9113 -286.796502) (xy 341.860123 -286.804608)
			(xy 341.808309 -286.804608) (xy 341.757132 -286.796502) (xy 341.707853 -286.78049) (xy 341.661686 -286.756967)
			(xy 341.619767 -286.726511) (xy 341.583129 -286.689873) (xy 341.552673 -286.647954) (xy 341.52915 -286.601787)
			(xy 341.513138 -286.552508) (xy 341.505032 -286.501331) (xy 341.504524 -286.475424) (xy 341.505123 -286.447707)
			(xy 341.514443 -286.39306) (xy 341.523066 -286.366712) (xy 341.53094 -286.344614) (xy 341.325962 -285.989522)
			(xy 341.302848 -285.985204) (xy 341.278027 -285.980039) (xy 341.230247 -285.963084) (xy 341.185628 -285.939012)
			(xy 341.145222 -285.908392) (xy 341.109981 -285.871945) (xy 341.080737 -285.830531) (xy 341.05818 -285.785127)
			(xy 341.042843 -285.736804) (xy 341.035086 -285.686703) (xy 341.034624 -285.661354) (xy 340.7537 -285.661354)
			(xy 340.753192 -285.687241) (xy 340.745093 -285.738379) (xy 340.729094 -285.787619) (xy 340.705588 -285.833751)
			(xy 340.675156 -285.875638) (xy 340.638546 -285.912248) (xy 340.596659 -285.94268) (xy 340.550527 -285.966186)
			(xy 340.501287 -285.982185) (xy 340.450149 -285.990284) (xy 340.398375 -285.990284) (xy 340.347237 -285.982185)
			(xy 340.297997 -285.966186) (xy 340.251865 -285.94268) (xy 340.209978 -285.912248) (xy 340.173368 -285.875638)
			(xy 340.142936 -285.833751) (xy 340.11943 -285.787619) (xy 340.103431 -285.738379) (xy 340.095332 -285.687241)
			(xy 340.094824 -285.661354) (xy 339.814408 -285.661354) (xy 339.813802 -285.689071) (xy 339.804487 -285.743717)
			(xy 339.795866 -285.770066) (xy 339.787992 -285.792164) (xy 339.993224 -286.147256) (xy 340.016084 -286.151574)
			(xy 340.040906 -286.156737) (xy 340.088683 -286.173695) (xy 340.133301 -286.197768) (xy 340.173706 -286.22839)
			(xy 340.208946 -286.264837) (xy 340.238189 -286.30625) (xy 340.260746 -286.351653) (xy 340.276085 -286.399975)
			(xy 340.283845 -286.450075) (xy 340.284308 -286.475424) (xy 340.2838 -286.501331) (xy 340.275694 -286.552508)
			(xy 340.259682 -286.601787) (xy 340.236159 -286.647954) (xy 340.205703 -286.689873) (xy 340.169065 -286.726511)
			(xy 340.127146 -286.756967) (xy 340.080979 -286.78049) (xy 340.0317 -286.796502) (xy 339.980523 -286.804608)
			(xy 339.928709 -286.804608) (xy 339.877532 -286.796502) (xy 339.828253 -286.78049) (xy 339.782086 -286.756967)
			(xy 339.740167 -286.726511) (xy 339.703529 -286.689873) (xy 339.673073 -286.647954) (xy 339.64955 -286.601787)
			(xy 339.633538 -286.552508) (xy 339.625432 -286.501331) (xy 339.624924 -286.475424) (xy 339.625523 -286.447707)
			(xy 339.634843 -286.39306) (xy 339.643466 -286.366712) (xy 339.65134 -286.344614) (xy 339.446108 -285.989522)
			(xy 339.423248 -285.985204) (xy 339.398427 -285.980039) (xy 339.350647 -285.963084) (xy 339.306028 -285.939012)
			(xy 339.265622 -285.908392) (xy 339.230381 -285.871945) (xy 339.201137 -285.830531) (xy 339.17858 -285.785127)
			(xy 339.163243 -285.736804) (xy 339.155486 -285.686703) (xy 339.155024 -285.661354) (xy 338.874608 -285.661354)
			(xy 338.8741 -285.687261) (xy 338.865994 -285.738438) (xy 338.849982 -285.787717) (xy 338.826459 -285.833884)
			(xy 338.796003 -285.875803) (xy 338.759365 -285.912441) (xy 338.717446 -285.942897) (xy 338.671279 -285.96642)
			(xy 338.622 -285.982432) (xy 338.570823 -285.990538) (xy 338.519009 -285.990538) (xy 338.467832 -285.982432)
			(xy 338.418553 -285.96642) (xy 338.372386 -285.942897) (xy 338.330467 -285.912441) (xy 338.293829 -285.875803)
			(xy 338.263373 -285.833884) (xy 338.23985 -285.787717) (xy 338.223838 -285.738438) (xy 338.215732 -285.687261)
			(xy 338.215224 -285.661354) (xy 337.9343 -285.661354) (xy 337.933759 -285.689062) (xy 337.924571 -285.743708)
			(xy 337.916012 -285.770066) (xy 337.908138 -285.792164) (xy 338.11337 -286.147256) (xy 338.13623 -286.151574)
			(xy 338.16104 -286.156732) (xy 338.20878 -286.173726) (xy 338.253357 -286.197824) (xy 338.293722 -286.228459)
			(xy 338.328925 -286.264909) (xy 338.358136 -286.306317) (xy 338.380667 -286.351707) (xy 338.395988 -286.400009)
			(xy 338.403738 -286.450087) (xy 338.4042 -286.475424) (xy 338.403692 -286.501311) (xy 338.395593 -286.552449)
			(xy 338.379594 -286.601689) (xy 338.356088 -286.647821) (xy 338.325656 -286.689708) (xy 338.289046 -286.726318)
			(xy 338.247159 -286.75675) (xy 338.201027 -286.780256) (xy 338.151787 -286.796255) (xy 338.100649 -286.804354)
			(xy 338.048875 -286.804354) (xy 337.997737 -286.796255) (xy 337.948497 -286.780256) (xy 337.902365 -286.75675)
			(xy 337.860478 -286.726318) (xy 337.823868 -286.689708) (xy 337.793436 -286.647821) (xy 337.76993 -286.601689)
			(xy 337.753931 -286.552449) (xy 337.745832 -286.501311) (xy 337.745324 -286.475424) (xy 337.745858 -286.447716)
			(xy 337.75505 -286.393069) (xy 337.763612 -286.366712) (xy 337.771486 -286.344614) (xy 337.566254 -285.989522)
			(xy 337.543394 -285.985204) (xy 337.518583 -285.980049) (xy 337.470842 -285.963057) (xy 337.426263 -285.93896)
			(xy 337.385896 -285.908325) (xy 337.350693 -285.871874) (xy 337.321482 -285.830466) (xy 337.298951 -285.785075)
			(xy 337.283632 -285.736771) (xy 337.275885 -285.686692) (xy 337.275424 -285.661354) (xy 336.0547 -285.661354)
			(xy 336.054192 -285.687241) (xy 336.046093 -285.738379) (xy 336.030094 -285.787619) (xy 336.006588 -285.833751)
			(xy 335.976156 -285.875638) (xy 335.939546 -285.912248) (xy 335.897659 -285.94268) (xy 335.851527 -285.966186)
			(xy 335.802287 -285.982185) (xy 335.751149 -285.990284) (xy 335.699375 -285.990284) (xy 335.648237 -285.982185)
			(xy 335.598997 -285.966186) (xy 335.552865 -285.94268) (xy 335.510978 -285.912248) (xy 335.474368 -285.875638)
			(xy 335.443936 -285.833751) (xy 335.42043 -285.787619) (xy 335.404431 -285.738379) (xy 335.396332 -285.687241)
			(xy 335.395824 -285.661354) (xy 284.8356 -285.661354) (xy 284.8356 -286.475424) (xy 333.986124 -286.475424)
			(xy 333.986632 -286.449537) (xy 333.994731 -286.398399) (xy 334.01073 -286.349159) (xy 334.034236 -286.303027)
			(xy 334.064668 -286.26114) (xy 334.101278 -286.22453) (xy 334.143165 -286.194098) (xy 334.189297 -286.170592)
			(xy 334.238537 -286.154593) (xy 334.289675 -286.146494) (xy 334.341449 -286.146494) (xy 334.392587 -286.154593)
			(xy 334.441827 -286.170592) (xy 334.487959 -286.194098) (xy 334.529846 -286.22453) (xy 334.566456 -286.26114)
			(xy 334.596888 -286.303027) (xy 334.620394 -286.349159) (xy 334.636393 -286.398399) (xy 334.644492 -286.449537)
			(xy 334.645 -286.475424) (xy 334.644511 -286.501304) (xy 334.92624 -286.501304) (xy 334.92624 -286.449496)
			(xy 334.934344 -286.398327) (xy 334.950352 -286.349055) (xy 334.97387 -286.302894) (xy 335.00432 -286.26098)
			(xy 335.040951 -286.224345) (xy 335.082862 -286.19389) (xy 335.12902 -286.170367) (xy 335.17829 -286.154353)
			(xy 335.229459 -286.146243) (xy 335.255362 -286.145732) (xy 335.280855 -286.146231) (xy 335.331232 -286.154087)
			(xy 335.379796 -286.169618) (xy 335.425383 -286.192452) (xy 335.466904 -286.222042) (xy 335.503366 -286.257681)
			(xy 335.519014 -286.277812) (xy 335.93151 -286.277812) (xy 335.947185 -286.257701) (xy 335.98364 -286.222058)
			(xy 336.025155 -286.192461) (xy 336.070737 -286.16962) (xy 336.119296 -286.15408) (xy 336.16967 -286.146213)
			(xy 336.195162 -286.145732) (xy 336.221075 -286.146163) (xy 336.272264 -286.154265) (xy 336.321556 -286.170276)
			(xy 336.367735 -286.193801) (xy 336.409666 -286.22426) (xy 336.446315 -286.260905) (xy 336.47678 -286.302832)
			(xy 336.50031 -286.349009) (xy 336.516326 -286.398299) (xy 336.524434 -286.449487) (xy 336.524434 -286.501313)
			(xy 336.516326 -286.552501) (xy 336.50031 -286.601791) (xy 336.47678 -286.647968) (xy 336.446315 -286.689895)
			(xy 336.409666 -286.72654) (xy 336.367735 -286.756999) (xy 336.321556 -286.780524) (xy 336.272264 -286.796535)
			(xy 336.221075 -286.804637) (xy 336.195162 -286.805116) (xy 336.169668 -286.804653) (xy 336.11929 -286.796786)
			(xy 336.070727 -286.781247) (xy 336.02514 -286.758407) (xy 335.98362 -286.728811) (xy 335.947158 -286.693169)
			(xy 335.93151 -286.673036) (xy 335.519014 -286.673036) (xy 335.503397 -286.693193) (xy 335.466928 -286.728832)
			(xy 335.425401 -286.758421) (xy 335.379808 -286.781254) (xy 335.33124 -286.796785) (xy 335.280857 -286.804641)
			(xy 335.255362 -286.805116) (xy 335.229459 -286.804557) (xy 335.17829 -286.796447) (xy 335.12902 -286.780433)
			(xy 335.082862 -286.75691) (xy 335.040951 -286.726455) (xy 335.00432 -286.68982) (xy 334.97387 -286.647906)
			(xy 334.950352 -286.601745) (xy 334.934344 -286.552473) (xy 334.92624 -286.501304) (xy 334.644511 -286.501304)
			(xy 334.644476 -286.503132) (xy 334.635277 -286.557779) (xy 334.626712 -286.584136) (xy 334.619092 -286.60598)
			(xy 334.82407 -286.961072) (xy 334.84693 -286.96539) (xy 334.871744 -286.970533) (xy 334.919484 -286.987528)
			(xy 334.964063 -287.011628) (xy 335.004428 -287.042264) (xy 335.039631 -287.078717) (xy 335.068841 -287.120126)
			(xy 335.091372 -287.165518) (xy 335.106691 -287.213822) (xy 335.114439 -287.263902) (xy 335.1149 -287.28924)
			(xy 335.114392 -287.315127) (xy 335.106293 -287.366265) (xy 335.090294 -287.415505) (xy 335.066788 -287.461637)
			(xy 335.036356 -287.503524) (xy 334.999746 -287.540134) (xy 334.957859 -287.570566) (xy 334.911727 -287.594072)
			(xy 334.862487 -287.610071) (xy 334.811349 -287.61817) (xy 334.759575 -287.61817) (xy 334.708437 -287.610071)
			(xy 334.659197 -287.594072) (xy 334.613065 -287.570566) (xy 334.571178 -287.540134) (xy 334.534568 -287.503524)
			(xy 334.504136 -287.461637) (xy 334.48063 -287.415505) (xy 334.464631 -287.366265) (xy 334.456532 -287.315127)
			(xy 334.456024 -287.28924) (xy 334.456562 -287.261532) (xy 334.465751 -287.206885) (xy 334.474312 -287.180528)
			(xy 334.481932 -287.158684) (xy 334.276954 -286.803592) (xy 334.254094 -286.799274) (xy 334.229299 -286.794053)
			(xy 334.181562 -286.777067) (xy 334.136987 -286.752976) (xy 334.096622 -286.722349) (xy 334.061419 -286.685906)
			(xy 334.032206 -286.644507) (xy 334.009672 -286.599125) (xy 333.994346 -286.55083) (xy 333.98659 -286.500758)
			(xy 333.986124 -286.475424) (xy 284.8356 -286.475424) (xy 284.8356 -319.065148) (xy 284.834984 -319.090103)
			(xy 284.825238 -319.139052) (xy 284.806131 -319.185159) (xy 284.778397 -319.226653) (xy 284.761178 -319.244726)
			(xy 284.516576 -319.489328) (xy 284.498685 -319.506432) (xy 284.457626 -319.534063) (xy 284.435042 -319.544192)
			(xy 284.4038 -319.557146) (xy 284.4038 -351.068132) (xy 285.078932 -351.743264) (xy 285.324296 -351.743264)
		)
		(stroke
			(width 0)
			(type solid)
		)
		(fill yes)
		(layer "In9.Cu")
		(net "PVCCFA_EHV_FIVRA_CPU0")
	)
	(gr_poly
		(pts
			(xy 256.292096 -31.120588) (xy 256.292096 -11.780012) (xy 256.29258 -11.709658) (xy 256.300469 -11.56917)
			(xy 256.316223 -11.429347) (xy 256.339792 -11.290626) (xy 256.371101 -11.153445) (xy 256.410054 -11.018236)
			(xy 256.456527 -10.885423) (xy 256.510373 -10.755425) (xy 256.571423 -10.628651) (xy 256.639486 -10.505499)
			(xy 256.714347 -10.386357) (xy 256.795771 -10.2716) (xy 256.883501 -10.16159) (xy 256.977261 -10.056671)
			(xy 257.076757 -9.957175) (xy 257.181674 -9.863414) (xy 257.291684 -9.775683) (xy 257.406441 -9.694258)
			(xy 257.525582 -9.619396) (xy 257.648733 -9.551333) (xy 257.775507 -9.490281) (xy 257.905504 -9.436434)
			(xy 258.038317 -9.38996) (xy 258.173526 -9.351006) (xy 258.310706 -9.319695) (xy 258.449427 -9.296125)
			(xy 258.589251 -9.280371) (xy 258.729738 -9.272481) (xy 258.800092 -9.272016) (xy 383.601976 -9.272016)
			(xy 383.657784 -9.271508) (xy 383.769089 -9.263168) (xy 383.879459 -9.246534) (xy 383.988278 -9.221699)
			(xy 384.094936 -9.188801) (xy 384.198838 -9.148025) (xy 384.299402 -9.099598) (xy 384.396066 -9.043791)
			(xy 384.488289 -8.980916) (xy 384.575555 -8.911326) (xy 384.657377 -8.835408) (xy 384.733297 -8.753588)
			(xy 384.80289 -8.666324) (xy 384.865767 -8.574103) (xy 384.921577 -8.477441) (xy 384.970007 -8.376878)
			(xy 385.010787 -8.272978) (xy 385.043688 -8.16632) (xy 385.068526 -8.057503) (xy 385.085163 -7.947133)
			(xy 385.093506 -7.835828) (xy 385.093972 -7.78002) (xy 385.093972 0.999998) (xy 385.094465 1.070352)
			(xy 385.102355 1.210839) (xy 385.118109 1.350662) (xy 385.141678 1.489383) (xy 385.172988 1.626563)
			(xy 385.211941 1.761772) (xy 385.258413 1.894584) (xy 385.312259 2.024582) (xy 385.37331 2.151356)
			(xy 385.441373 2.274507) (xy 385.516233 2.393649) (xy 385.597656 2.508405) (xy 385.685386 2.618416)
			(xy 385.779146 2.723335) (xy 385.878641 2.822831) (xy 385.983558 2.916592) (xy 386.093567 3.004323)
			(xy 386.208323 3.085748) (xy 386.327463 3.16061) (xy 386.450614 3.228674) (xy 386.577387 3.289727)
			(xy 386.707384 3.343575) (xy 386.840195 3.390049) (xy 386.975404 3.429003) (xy 387.112584 3.460315)
			(xy 387.251304 3.483887) (xy 387.391127 3.499643) (xy 387.531614 3.507534) (xy 387.601968 3.507994)
			(xy 456.202034 3.507994) (xy 456.272387 3.5075) (xy 456.412872 3.499608) (xy 456.552693 3.483853)
			(xy 456.691411 3.460282) (xy 456.828589 3.42897) (xy 456.963796 3.390016) (xy 457.096605 3.343542)
			(xy 457.226601 3.289695) (xy 457.353372 3.228644) (xy 457.476521 3.16058) (xy 457.595659 3.085719)
			(xy 457.710413 3.004295) (xy 457.820421 2.916565) (xy 457.925337 2.822806) (xy 458.02483 2.723311)
			(xy 458.118589 2.618393) (xy 458.206317 2.508384) (xy 458.287739 2.393629) (xy 458.362598 2.27449)
			(xy 458.43066 2.15134) (xy 458.49171 2.024568) (xy 458.545555 1.894572) (xy 458.592027 1.761761)
			(xy 458.630979 1.626554) (xy 458.662289 1.489376) (xy 458.685858 1.350658) (xy 458.701612 1.210836)
			(xy 458.709501 1.070351) (xy 458.71003 0.999998) (xy 458.71003 -7.78002) (xy 458.71054 -7.835827)
			(xy 458.718882 -7.947128) (xy 458.735519 -8.057494) (xy 458.760357 -8.166309) (xy 458.793257 -8.272963)
			(xy 458.834035 -8.37686) (xy 458.882464 -8.47742) (xy 458.938272 -8.574079) (xy 459.001148 -8.666297)
			(xy 459.070739 -8.753559) (xy 459.146656 -8.835376) (xy 459.228476 -8.911291) (xy 459.31574 -8.98088)
			(xy 459.40796 -9.043752) (xy 459.504621 -9.099557) (xy 459.605182 -9.147983) (xy 459.70908 -9.188758)
			(xy 459.815736 -9.221655) (xy 459.924551 -9.24649) (xy 460.034918 -9.263123) (xy 460.146219 -9.271462)
			(xy 460.202026 -9.272016) (xy 464.327748 -9.272016) (xy 464.332574 -9.271) (xy 464.357024 -9.266474)
			(xy 464.406516 -9.261643) (xy 464.43138 -9.261348) (xy 464.456244 -9.26164) (xy 464.505735 -9.266479)
			(xy 464.530186 -9.271) (xy 464.535012 -9.272016) (xy 469.799924 -9.272016) (xy 469.855731 -9.271493)
			(xy 469.967032 -9.263151) (xy 470.077399 -9.246514) (xy 470.186213 -9.221677) (xy 470.292868 -9.188777)
			(xy 470.396765 -9.147999) (xy 470.497325 -9.099571) (xy 470.593985 -9.043764) (xy 470.686204 -8.980889)
			(xy 470.773467 -8.911299) (xy 470.855285 -8.835382) (xy 470.931202 -8.753564) (xy 471.000791 -8.666301)
			(xy 471.063666 -8.574082) (xy 471.119473 -8.477422) (xy 471.167901 -8.376862) (xy 471.208678 -8.272964)
			(xy 471.241578 -8.166309) (xy 471.266415 -8.057495) (xy 471.283051 -7.947128) (xy 471.291394 -7.835827)
			(xy 471.29192 -7.78002) (xy 471.29192 10.40003) (xy 471.291397 10.455837) (xy 471.283054 10.567138)
			(xy 471.266417 10.677504) (xy 471.241579 10.786319) (xy 471.208679 10.892973) (xy 471.167901 10.99687)
			(xy 471.119473 11.09743) (xy 471.063666 11.194089) (xy 471.000791 11.286308) (xy 470.931201 11.373571)
			(xy 470.855284 11.455389) (xy 470.773466 11.531305) (xy 470.686203 11.600895) (xy 470.593984 11.663769)
			(xy 470.497324 11.719576) (xy 470.396765 11.768004) (xy 470.292867 11.808781) (xy 470.186213 11.841681)
			(xy 470.077398 11.866518) (xy 469.967032 11.883155) (xy 469.855731 11.891497) (xy 469.799924 11.892026)
			(xy 1.999996 11.892026) (xy 1.944189 11.891504) (xy 1.832887 11.883163) (xy 1.72252 11.866527) (xy 1.613705 11.841691)
			(xy 1.50705 11.808792) (xy 1.403151 11.768014) (xy 1.302591 11.719587) (xy 1.20593 11.66378) (xy 1.113711 11.600905)
			(xy 1.026448 11.531315) (xy 0.944629 11.455398) (xy 0.868712 11.373579) (xy 0.799122 11.286316) (xy 0.736248 11.194096)
			(xy 0.680441 11.097436) (xy 0.632014 10.996875) (xy 0.591237 10.892977) (xy 0.558338 10.786321) (xy 0.533502 10.677506)
			(xy 0.516867 10.567139) (xy 0.508526 10.455837) (xy 0.508 10.40003) (xy 0.508 7.335466) (xy 2.904225 7.335466)
			(xy 2.904225 7.464606) (xy 2.912175 7.593501) (xy 2.928045 7.721661) (xy 2.951774 7.848602) (xy 2.983273 7.973841)
			(xy 3.022422 8.096904) (xy 3.069073 8.217323) (xy 3.123048 8.334642) (xy 3.184143 8.448416) (xy 3.252126 8.558213)
			(xy 3.32674 8.663616) (xy 3.407701 8.764226) (xy 3.494701 8.859661) (xy 3.587412 8.94956) (xy 3.685482 9.033581)
			(xy 3.788537 9.111405) (xy 3.896188 9.182737) (xy 4.008027 9.247307) (xy 4.123628 9.304869) (xy 4.242553 9.355206)
			(xy 4.364352 9.398126) (xy 4.488562 9.433467) (xy 4.614711 9.461094) (xy 4.742323 9.480903) (xy 4.870912 9.492819)
			(xy 4.99999 9.496796) (xy 5.129068 9.492819) (xy 5.257657 9.480903) (xy 5.385269 9.461094) (xy 5.511418 9.433467)
			(xy 5.635628 9.398126) (xy 5.757427 9.355206) (xy 5.876352 9.304869) (xy 5.991953 9.247307) (xy 6.020338 9.230919)
			(xy 256.921241 9.230919) (xy 256.921241 9.316669) (xy 256.929153 9.402052) (xy 256.944909 9.486342)
			(xy 256.968376 9.568818) (xy 256.999352 9.648777) (xy 257.037574 9.725537) (xy 257.082715 9.798443)
			(xy 257.134391 9.866872) (xy 257.19216 9.930242) (xy 257.25553 9.988011) (xy 257.323959 10.039687)
			(xy 257.396865 10.084828) (xy 257.473625 10.12305) (xy 257.553584 10.154026) (xy 257.63606 10.177493)
			(xy 257.72035 10.193249) (xy 257.805733 10.201161) (xy 257.891483 10.201161) (xy 257.976866 10.193249)
			(xy 258.061156 10.177493) (xy 258.143632 10.154026) (xy 258.223591 10.12305) (xy 258.300351 10.084828)
			(xy 258.373257 10.039687) (xy 258.441686 9.988011) (xy 258.505056 9.930242) (xy 258.562825 9.866872)
			(xy 258.614501 9.798443) (xy 258.659642 9.725537) (xy 258.697864 9.648777) (xy 258.72884 9.568818)
			(xy 258.752307 9.486342) (xy 258.768063 9.402052) (xy 258.775975 9.316669) (xy 258.77647 9.273794)
			(xy 258.775975 9.230919) (xy 263.271241 9.230919) (xy 263.271241 9.316669) (xy 263.279153 9.402052)
			(xy 263.294909 9.486342) (xy 263.318376 9.568818) (xy 263.349352 9.648777) (xy 263.387574 9.725537)
			(xy 263.432715 9.798443) (xy 263.484391 9.866872) (xy 263.54216 9.930242) (xy 263.60553 9.988011)
			(xy 263.673959 10.039687) (xy 263.746865 10.084828) (xy 263.823625 10.12305) (xy 263.903584 10.154026)
			(xy 263.98606 10.177493) (xy 264.07035 10.193249) (xy 264.155733 10.201161) (xy 264.241483 10.201161)
			(xy 264.326866 10.193249) (xy 264.411156 10.177493) (xy 264.493632 10.154026) (xy 264.573591 10.12305)
			(xy 264.650351 10.084828) (xy 264.723257 10.039687) (xy 264.791686 9.988011) (xy 264.855056 9.930242)
			(xy 264.912825 9.866872) (xy 264.964501 9.798443) (xy 265.009642 9.725537) (xy 265.047864 9.648777)
			(xy 265.07884 9.568818) (xy 265.102307 9.486342) (xy 265.118063 9.402052) (xy 265.125975 9.316669)
			(xy 265.12647 9.273794) (xy 265.125975 9.230919) (xy 324.845921 9.230919) (xy 324.845921 9.316669)
			(xy 324.853833 9.402052) (xy 324.869589 9.486342) (xy 324.893056 9.568818) (xy 324.924032 9.648777)
			(xy 324.962254 9.725537) (xy 325.007395 9.798443) (xy 325.059071 9.866872) (xy 325.11684 9.930242)
			(xy 325.18021 9.988011) (xy 325.248639 10.039687) (xy 325.321545 10.084828) (xy 325.398305 10.12305)
			(xy 325.478264 10.154026) (xy 325.56074 10.177493) (xy 325.64503 10.193249) (xy 325.730413 10.201161)
			(xy 325.816163 10.201161) (xy 325.901546 10.193249) (xy 325.985836 10.177493) (xy 326.068312 10.154026)
			(xy 326.148271 10.12305) (xy 326.225031 10.084828) (xy 326.297937 10.039687) (xy 326.366366 9.988011)
			(xy 326.429736 9.930242) (xy 326.487505 9.866872) (xy 326.539181 9.798443) (xy 326.584322 9.725537)
			(xy 326.622544 9.648777) (xy 326.65352 9.568818) (xy 326.676987 9.486342) (xy 326.692743 9.402052)
			(xy 326.700655 9.316669) (xy 326.70115 9.273794) (xy 326.700655 9.230919) (xy 331.195921 9.230919)
			(xy 331.195921 9.316669) (xy 331.203833 9.402052) (xy 331.219589 9.486342) (xy 331.243056 9.568818)
			(xy 331.274032 9.648777) (xy 331.312254 9.725537) (xy 331.357395 9.798443) (xy 331.409071 9.866872)
			(xy 331.46684 9.930242) (xy 331.53021 9.988011) (xy 331.598639 10.039687) (xy 331.671545 10.084828)
			(xy 331.748305 10.12305) (xy 331.828264 10.154026) (xy 331.91074 10.177493) (xy 331.99503 10.193249)
			(xy 332.080413 10.201161) (xy 332.166163 10.201161) (xy 332.251546 10.193249) (xy 332.335836 10.177493)
			(xy 332.418312 10.154026) (xy 332.498271 10.12305) (xy 332.575031 10.084828) (xy 332.647937 10.039687)
			(xy 332.716366 9.988011) (xy 332.779736 9.930242) (xy 332.837505 9.866872) (xy 332.889181 9.798443)
			(xy 332.934322 9.725537) (xy 332.972544 9.648777) (xy 333.00352 9.568818) (xy 333.026987 9.486342)
			(xy 333.042743 9.402052) (xy 333.050655 9.316669) (xy 333.05115 9.273794) (xy 333.050655 9.230919)
			(xy 335.488267 9.230919) (xy 335.488267 9.316669) (xy 335.496179 9.402052) (xy 335.511935 9.486342)
			(xy 335.535402 9.568818) (xy 335.566378 9.648777) (xy 335.6046 9.725537) (xy 335.649741 9.798443)
			(xy 335.701417 9.866872) (xy 335.759186 9.930242) (xy 335.822556 9.988011) (xy 335.890985 10.039687)
			(xy 335.963891 10.084828) (xy 336.040651 10.12305) (xy 336.12061 10.154026) (xy 336.203086 10.177493)
			(xy 336.287376 10.193249) (xy 336.372759 10.201161) (xy 336.458509 10.201161) (xy 336.543892 10.193249)
			(xy 336.628182 10.177493) (xy 336.710658 10.154026) (xy 336.790617 10.12305) (xy 336.867377 10.084828)
			(xy 336.940283 10.039687) (xy 337.008712 9.988011) (xy 337.072082 9.930242) (xy 337.129851 9.866872)
			(xy 337.181527 9.798443) (xy 337.226668 9.725537) (xy 337.26489 9.648777) (xy 337.295866 9.568818)
			(xy 337.319333 9.486342) (xy 337.335089 9.402052) (xy 337.343001 9.316669) (xy 337.343496 9.273794)
			(xy 337.343001 9.230919) (xy 341.838267 9.230919) (xy 341.838267 9.316669) (xy 341.846179 9.402052)
			(xy 341.861935 9.486342) (xy 341.885402 9.568818) (xy 341.916378 9.648777) (xy 341.9546 9.725537)
			(xy 341.999741 9.798443) (xy 342.051417 9.866872) (xy 342.109186 9.930242) (xy 342.172556 9.988011)
			(xy 342.240985 10.039687) (xy 342.313891 10.084828) (xy 342.390651 10.12305) (xy 342.47061 10.154026)
			(xy 342.553086 10.177493) (xy 342.637376 10.193249) (xy 342.722759 10.201161) (xy 342.808509 10.201161)
			(xy 342.893892 10.193249) (xy 342.978182 10.177493) (xy 343.060658 10.154026) (xy 343.140617 10.12305)
			(xy 343.217377 10.084828) (xy 343.290283 10.039687) (xy 343.358712 9.988011) (xy 343.422082 9.930242)
			(xy 343.479851 9.866872) (xy 343.531527 9.798443) (xy 343.576668 9.725537) (xy 343.61489 9.648777)
			(xy 343.645866 9.568818) (xy 343.669333 9.486342) (xy 343.685089 9.402052) (xy 343.693001 9.316669)
			(xy 343.693496 9.273794) (xy 343.693001 9.230919) (xy 373.705107 9.230919) (xy 373.705107 9.316669)
			(xy 373.713019 9.402052) (xy 373.728775 9.486342) (xy 373.752242 9.568818) (xy 373.783218 9.648777)
			(xy 373.82144 9.725537) (xy 373.866581 9.798443) (xy 373.918257 9.866872) (xy 373.976026 9.930242)
			(xy 374.039396 9.988011) (xy 374.107825 10.039687) (xy 374.180731 10.084828) (xy 374.257491 10.12305)
			(xy 374.33745 10.154026) (xy 374.419926 10.177493) (xy 374.504216 10.193249) (xy 374.589599 10.201161)
			(xy 374.675349 10.201161) (xy 374.760732 10.193249) (xy 374.845022 10.177493) (xy 374.927498 10.154026)
			(xy 375.007457 10.12305) (xy 375.084217 10.084828) (xy 375.157123 10.039687) (xy 375.225552 9.988011)
			(xy 375.288922 9.930242) (xy 375.346691 9.866872) (xy 375.398367 9.798443) (xy 375.443508 9.725537)
			(xy 375.48173 9.648777) (xy 375.512706 9.568818) (xy 375.536173 9.486342) (xy 375.551929 9.402052)
			(xy 375.559841 9.316669) (xy 375.560336 9.273794) (xy 375.559841 9.230919) (xy 380.055107 9.230919)
			(xy 380.055107 9.316669) (xy 380.063019 9.402052) (xy 380.078775 9.486342) (xy 380.102242 9.568818)
			(xy 380.133218 9.648777) (xy 380.17144 9.725537) (xy 380.216581 9.798443) (xy 380.268257 9.866872)
			(xy 380.326026 9.930242) (xy 380.389396 9.988011) (xy 380.457825 10.039687) (xy 380.530731 10.084828)
			(xy 380.607491 10.12305) (xy 380.68745 10.154026) (xy 380.769926 10.177493) (xy 380.854216 10.193249)
			(xy 380.939599 10.201161) (xy 381.025349 10.201161) (xy 381.110732 10.193249) (xy 381.195022 10.177493)
			(xy 381.277498 10.154026) (xy 381.357457 10.12305) (xy 381.434217 10.084828) (xy 381.507123 10.039687)
			(xy 381.575552 9.988011) (xy 381.638922 9.930242) (xy 381.696691 9.866872) (xy 381.748367 9.798443)
			(xy 381.793508 9.725537) (xy 381.83173 9.648777) (xy 381.862706 9.568818) (xy 381.886173 9.486342)
			(xy 381.901929 9.402052) (xy 381.909841 9.316669) (xy 381.910336 9.273794) (xy 381.909841 9.230919)
			(xy 381.901929 9.145536) (xy 381.886173 9.061246) (xy 381.862706 8.97877) (xy 381.83173 8.898811)
			(xy 381.793508 8.822051) (xy 381.748367 8.749145) (xy 381.696691 8.680716) (xy 381.638922 8.617346)
			(xy 381.575552 8.559577) (xy 381.507123 8.507901) (xy 381.434217 8.46276) (xy 381.357457 8.424538)
			(xy 381.277498 8.393562) (xy 381.195022 8.370095) (xy 381.110732 8.354339) (xy 381.025349 8.346427)
			(xy 380.939599 8.346427) (xy 380.854216 8.354339) (xy 380.769926 8.370095) (xy 380.68745 8.393562)
			(xy 380.607491 8.424538) (xy 380.530731 8.46276) (xy 380.457825 8.507901) (xy 380.389396 8.559577)
			(xy 380.326026 8.617346) (xy 380.268257 8.680716) (xy 380.216581 8.749145) (xy 380.17144 8.822051)
			(xy 380.133218 8.898811) (xy 380.102242 8.97877) (xy 380.078775 9.061246) (xy 380.063019 9.145536)
			(xy 380.055107 9.230919) (xy 375.559841 9.230919) (xy 375.551929 9.145536) (xy 375.536173 9.061246)
			(xy 375.512706 8.97877) (xy 375.48173 8.898811) (xy 375.443508 8.822051) (xy 375.398367 8.749145)
			(xy 375.346691 8.680716) (xy 375.288922 8.617346) (xy 375.225552 8.559577) (xy 375.157123 8.507901)
			(xy 375.084217 8.46276) (xy 375.007457 8.424538) (xy 374.927498 8.393562) (xy 374.845022 8.370095)
			(xy 374.760732 8.354339) (xy 374.675349 8.346427) (xy 374.589599 8.346427) (xy 374.504216 8.354339)
			(xy 374.419926 8.370095) (xy 374.33745 8.393562) (xy 374.257491 8.424538) (xy 374.180731 8.46276)
			(xy 374.107825 8.507901) (xy 374.039396 8.559577) (xy 373.976026 8.617346) (xy 373.918257 8.680716)
			(xy 373.866581 8.749145) (xy 373.82144 8.822051) (xy 373.783218 8.898811) (xy 373.752242 8.97877)
			(xy 373.728775 9.061246) (xy 373.713019 9.145536) (xy 373.705107 9.230919) (xy 343.693001 9.230919)
			(xy 343.685089 9.145536) (xy 343.669333 9.061246) (xy 343.645866 8.97877) (xy 343.61489 8.898811)
			(xy 343.576668 8.822051) (xy 343.531527 8.749145) (xy 343.479851 8.680716) (xy 343.422082 8.617346)
			(xy 343.358712 8.559577) (xy 343.290283 8.507901) (xy 343.217377 8.46276) (xy 343.140617 8.424538)
			(xy 343.060658 8.393562) (xy 342.978182 8.370095) (xy 342.893892 8.354339) (xy 342.808509 8.346427)
			(xy 342.722759 8.346427) (xy 342.637376 8.354339) (xy 342.553086 8.370095) (xy 342.47061 8.393562)
			(xy 342.390651 8.424538) (xy 342.313891 8.46276) (xy 342.240985 8.507901) (xy 342.172556 8.559577)
			(xy 342.109186 8.617346) (xy 342.051417 8.680716) (xy 341.999741 8.749145) (xy 341.9546 8.822051)
			(xy 341.916378 8.898811) (xy 341.885402 8.97877) (xy 341.861935 9.061246) (xy 341.846179 9.145536)
			(xy 341.838267 9.230919) (xy 337.343001 9.230919) (xy 337.335089 9.145536) (xy 337.319333 9.061246)
			(xy 337.295866 8.97877) (xy 337.26489 8.898811) (xy 337.226668 8.822051) (xy 337.181527 8.749145)
			(xy 337.129851 8.680716) (xy 337.072082 8.617346) (xy 337.008712 8.559577) (xy 336.940283 8.507901)
			(xy 336.867377 8.46276) (xy 336.790617 8.424538) (xy 336.710658 8.393562) (xy 336.628182 8.370095)
			(xy 336.543892 8.354339) (xy 336.458509 8.346427) (xy 336.372759 8.346427) (xy 336.287376 8.354339)
			(xy 336.203086 8.370095) (xy 336.12061 8.393562) (xy 336.040651 8.424538) (xy 335.963891 8.46276)
			(xy 335.890985 8.507901) (xy 335.822556 8.559577) (xy 335.759186 8.617346) (xy 335.701417 8.680716)
			(xy 335.649741 8.749145) (xy 335.6046 8.822051) (xy 335.566378 8.898811) (xy 335.535402 8.97877)
			(xy 335.511935 9.061246) (xy 335.496179 9.145536) (xy 335.488267 9.230919) (xy 333.050655 9.230919)
			(xy 333.042743 9.145536) (xy 333.026987 9.061246) (xy 333.00352 8.97877) (xy 332.972544 8.898811)
			(xy 332.934322 8.822051) (xy 332.889181 8.749145) (xy 332.837505 8.680716) (xy 332.779736 8.617346)
			(xy 332.716366 8.559577) (xy 332.647937 8.507901) (xy 332.575031 8.46276) (xy 332.498271 8.424538)
			(xy 332.418312 8.393562) (xy 332.335836 8.370095) (xy 332.251546 8.354339) (xy 332.166163 8.346427)
			(xy 332.080413 8.346427) (xy 331.99503 8.354339) (xy 331.91074 8.370095) (xy 331.828264 8.393562)
			(xy 331.748305 8.424538) (xy 331.671545 8.46276) (xy 331.598639 8.507901) (xy 331.53021 8.559577)
			(xy 331.46684 8.617346) (xy 331.409071 8.680716) (xy 331.357395 8.749145) (xy 331.312254 8.822051)
			(xy 331.274032 8.898811) (xy 331.243056 8.97877) (xy 331.219589 9.061246) (xy 331.203833 9.145536)
			(xy 331.195921 9.230919) (xy 326.700655 9.230919) (xy 326.692743 9.145536) (xy 326.676987 9.061246)
			(xy 326.65352 8.97877) (xy 326.622544 8.898811) (xy 326.584322 8.822051) (xy 326.539181 8.749145)
			(xy 326.487505 8.680716) (xy 326.429736 8.617346) (xy 326.366366 8.559577) (xy 326.297937 8.507901)
			(xy 326.225031 8.46276) (xy 326.148271 8.424538) (xy 326.068312 8.393562) (xy 325.985836 8.370095)
			(xy 325.901546 8.354339) (xy 325.816163 8.346427) (xy 325.730413 8.346427) (xy 325.64503 8.354339)
			(xy 325.56074 8.370095) (xy 325.478264 8.393562) (xy 325.398305 8.424538) (xy 325.321545 8.46276)
			(xy 325.248639 8.507901) (xy 325.18021 8.559577) (xy 325.11684 8.617346) (xy 325.059071 8.680716)
			(xy 325.007395 8.749145) (xy 324.962254 8.822051) (xy 324.924032 8.898811) (xy 324.893056 8.97877)
			(xy 324.869589 9.061246) (xy 324.853833 9.145536) (xy 324.845921 9.230919) (xy 265.125975 9.230919)
			(xy 265.118063 9.145536) (xy 265.102307 9.061246) (xy 265.07884 8.97877) (xy 265.047864 8.898811)
			(xy 265.009642 8.822051) (xy 264.964501 8.749145) (xy 264.912825 8.680716) (xy 264.855056 8.617346)
			(xy 264.791686 8.559577) (xy 264.723257 8.507901) (xy 264.650351 8.46276) (xy 264.573591 8.424538)
			(xy 264.493632 8.393562) (xy 264.411156 8.370095) (xy 264.326866 8.354339) (xy 264.241483 8.346427)
			(xy 264.155733 8.346427) (xy 264.07035 8.354339) (xy 263.98606 8.370095) (xy 263.903584 8.393562)
			(xy 263.823625 8.424538) (xy 263.746865 8.46276) (xy 263.673959 8.507901) (xy 263.60553 8.559577)
			(xy 263.54216 8.617346) (xy 263.484391 8.680716) (xy 263.432715 8.749145) (xy 263.387574 8.822051)
			(xy 263.349352 8.898811) (xy 263.318376 8.97877) (xy 263.294909 9.061246) (xy 263.279153 9.145536)
			(xy 263.271241 9.230919) (xy 258.775975 9.230919) (xy 258.768063 9.145536) (xy 258.752307 9.061246)
			(xy 258.72884 8.97877) (xy 258.697864 8.898811) (xy 258.659642 8.822051) (xy 258.614501 8.749145)
			(xy 258.562825 8.680716) (xy 258.505056 8.617346) (xy 258.441686 8.559577) (xy 258.373257 8.507901)
			(xy 258.300351 8.46276) (xy 258.223591 8.424538) (xy 258.143632 8.393562) (xy 258.061156 8.370095)
			(xy 257.976866 8.354339) (xy 257.891483 8.346427) (xy 257.805733 8.346427) (xy 257.72035 8.354339)
			(xy 257.63606 8.370095) (xy 257.553584 8.393562) (xy 257.473625 8.424538) (xy 257.396865 8.46276)
			(xy 257.323959 8.507901) (xy 257.25553 8.559577) (xy 257.19216 8.617346) (xy 257.134391 8.680716)
			(xy 257.082715 8.749145) (xy 257.037574 8.822051) (xy 256.999352 8.898811) (xy 256.968376 8.97877)
			(xy 256.944909 9.061246) (xy 256.929153 9.145536) (xy 256.921241 9.230919) (xy 6.020338 9.230919)
			(xy 6.103792 9.182737) (xy 6.211443 9.111405) (xy 6.314498 9.033581) (xy 6.412568 8.94956) (xy 6.505279 8.859661)
			(xy 6.592279 8.764226) (xy 6.67324 8.663616) (xy 6.747854 8.558213) (xy 6.815837 8.448416) (xy 6.876932 8.334642)
			(xy 6.930907 8.217323) (xy 6.977558 8.096904) (xy 7.016707 7.973841) (xy 7.048206 7.848602) (xy 7.071935 7.721661)
			(xy 7.087805 7.593501) (xy 7.095755 7.464606) (xy 7.096252 7.400036) (xy 7.095755 7.335466) (xy 7.087805 7.206571)
			(xy 7.071935 7.078411) (xy 7.048206 6.95147) (xy 7.016707 6.826231) (xy 6.977558 6.703168) (xy 6.97173 6.688125)
			(xy 178.335673 6.688125) (xy 178.335673 6.773875) (xy 178.343585 6.859258) (xy 178.359341 6.943548)
			(xy 178.382808 7.026024) (xy 178.413784 7.105983) (xy 178.452006 7.182743) (xy 178.497147 7.255649)
			(xy 178.548823 7.324078) (xy 178.606592 7.387448) (xy 178.669962 7.445217) (xy 178.738391 7.496893)
			(xy 178.811297 7.542034) (xy 178.888057 7.580256) (xy 178.968016 7.611232) (xy 179.050492 7.634699)
			(xy 179.134782 7.650455) (xy 179.220165 7.658367) (xy 179.305915 7.658367) (xy 179.391298 7.650455)
			(xy 179.475588 7.634699) (xy 179.558064 7.611232) (xy 179.638023 7.580256) (xy 179.714783 7.542034)
			(xy 179.787689 7.496893) (xy 179.856118 7.445217) (xy 179.919488 7.387448) (xy 179.977257 7.324078)
			(xy 180.028933 7.255649) (xy 180.074074 7.182743) (xy 180.112296 7.105983) (xy 180.143272 7.026024)
			(xy 180.166739 6.943548) (xy 180.182495 6.859258) (xy 180.190407 6.773875) (xy 180.190902 6.731)
			(xy 180.190407 6.688125) (xy 184.685673 6.688125) (xy 184.685673 6.773875) (xy 184.693585 6.859258)
			(xy 184.709341 6.943548) (xy 184.732808 7.026024) (xy 184.763784 7.105983) (xy 184.802006 7.182743)
			(xy 184.847147 7.255649) (xy 184.898823 7.324078) (xy 184.956592 7.387448) (xy 185.019962 7.445217)
			(xy 185.088391 7.496893) (xy 185.161297 7.542034) (xy 185.238057 7.580256) (xy 185.318016 7.611232)
			(xy 185.400492 7.634699) (xy 185.484782 7.650455) (xy 185.570165 7.658367) (xy 185.655915 7.658367)
			(xy 185.741298 7.650455) (xy 185.825588 7.634699) (xy 185.908064 7.611232) (xy 185.988023 7.580256)
			(xy 186.064783 7.542034) (xy 186.137689 7.496893) (xy 186.206118 7.445217) (xy 186.269488 7.387448)
			(xy 186.327257 7.324078) (xy 186.378933 7.255649) (xy 186.424074 7.182743) (xy 186.462296 7.105983)
			(xy 186.493272 7.026024) (xy 186.516739 6.943548) (xy 186.532495 6.859258) (xy 186.540407 6.773875)
			(xy 186.540902 6.731) (xy 186.540407 6.688125) (xy 246.260353 6.688125) (xy 246.260353 6.773875)
			(xy 246.268265 6.859258) (xy 246.284021 6.943548) (xy 246.307488 7.026024) (xy 246.338464 7.105983)
			(xy 246.376686 7.182743) (xy 246.421827 7.255649) (xy 246.473503 7.324078) (xy 246.531272 7.387448)
			(xy 246.594642 7.445217) (xy 246.663071 7.496893) (xy 246.735977 7.542034) (xy 246.812737 7.580256)
			(xy 246.892696 7.611232) (xy 246.975172 7.634699) (xy 247.059462 7.650455) (xy 247.144845 7.658367)
			(xy 247.230595 7.658367) (xy 247.315978 7.650455) (xy 247.400268 7.634699) (xy 247.482744 7.611232)
			(xy 247.562703 7.580256) (xy 247.639463 7.542034) (xy 247.712369 7.496893) (xy 247.780798 7.445217)
			(xy 247.844168 7.387448) (xy 247.901937 7.324078) (xy 247.953613 7.255649) (xy 247.998754 7.182743)
			(xy 248.036976 7.105983) (xy 248.067952 7.026024) (xy 248.091419 6.943548) (xy 248.107175 6.859258)
			(xy 248.115087 6.773875) (xy 248.115582 6.731) (xy 248.115087 6.688125) (xy 252.610353 6.688125)
			(xy 252.610353 6.773875) (xy 252.618265 6.859258) (xy 252.634021 6.943548) (xy 252.657488 7.026024)
			(xy 252.688464 7.105983) (xy 252.726686 7.182743) (xy 252.771827 7.255649) (xy 252.823503 7.324078)
			(xy 252.881272 7.387448) (xy 252.944642 7.445217) (xy 253.013071 7.496893) (xy 253.085977 7.542034)
			(xy 253.162737 7.580256) (xy 253.242696 7.611232) (xy 253.325172 7.634699) (xy 253.409462 7.650455)
			(xy 253.494845 7.658367) (xy 253.580595 7.658367) (xy 253.665978 7.650455) (xy 253.750268 7.634699)
			(xy 253.832744 7.611232) (xy 253.912703 7.580256) (xy 253.989463 7.542034) (xy 254.062369 7.496893)
			(xy 254.130798 7.445217) (xy 254.194168 7.387448) (xy 254.251937 7.324078) (xy 254.303613 7.255649)
			(xy 254.348754 7.182743) (xy 254.386976 7.105983) (xy 254.417952 7.026024) (xy 254.441419 6.943548)
			(xy 254.457175 6.859258) (xy 254.465087 6.773875) (xy 254.465582 6.731) (xy 254.465119 6.690919)
			(xy 256.921241 6.690919) (xy 256.921241 6.776669) (xy 256.929153 6.862052) (xy 256.944909 6.946342)
			(xy 256.968376 7.028818) (xy 256.999352 7.108777) (xy 257.037574 7.185537) (xy 257.082715 7.258443)
			(xy 257.134391 7.326872) (xy 257.19216 7.390242) (xy 257.25553 7.448011) (xy 257.323959 7.499687)
			(xy 257.396865 7.544828) (xy 257.473625 7.58305) (xy 257.553584 7.614026) (xy 257.63606 7.637493)
			(xy 257.72035 7.653249) (xy 257.805733 7.661161) (xy 257.891483 7.661161) (xy 257.976866 7.653249)
			(xy 258.061156 7.637493) (xy 258.143632 7.614026) (xy 258.223591 7.58305) (xy 258.245794 7.571994)
			(xy 261.85622 7.571994) (xy 261.85622 8.435594) (xy 261.856706 8.462863) (xy 261.864468 8.516847)
			(xy 261.879833 8.569177) (xy 261.90249 8.618787) (xy 261.931976 8.664668) (xy 261.967691 8.705885)
			(xy 262.008908 8.7416) (xy 262.054789 8.771086) (xy 262.104399 8.793743) (xy 262.156729 8.809108)
			(xy 262.210713 8.81687) (xy 262.265251 8.81687) (xy 262.319235 8.809108) (xy 262.371565 8.793743)
			(xy 262.421175 8.771086) (xy 262.467056 8.7416) (xy 262.508273 8.705885) (xy 262.543988 8.664668)
			(xy 262.573474 8.618787) (xy 262.596131 8.569177) (xy 262.611496 8.516847) (xy 262.619258 8.462863)
			(xy 262.619744 8.435594) (xy 262.619744 7.571994) (xy 262.619258 7.544725) (xy 262.611496 7.490741)
			(xy 262.596131 7.438411) (xy 262.573474 7.388801) (xy 262.543988 7.34292) (xy 262.508273 7.301703)
			(xy 262.467056 7.265988) (xy 262.421175 7.236502) (xy 262.371565 7.213845) (xy 262.319235 7.19848)
			(xy 262.265251 7.190718) (xy 262.210713 7.190718) (xy 262.156729 7.19848) (xy 262.104399 7.213845)
			(xy 262.054789 7.236502) (xy 262.008908 7.265988) (xy 261.967691 7.301703) (xy 261.931976 7.34292)
			(xy 261.90249 7.388801) (xy 261.879833 7.438411) (xy 261.864468 7.490741) (xy 261.856706 7.544725)
			(xy 261.85622 7.571994) (xy 258.245794 7.571994) (xy 258.300351 7.544828) (xy 258.373257 7.499687)
			(xy 258.441686 7.448011) (xy 258.505056 7.390242) (xy 258.562825 7.326872) (xy 258.614501 7.258443)
			(xy 258.659642 7.185537) (xy 258.697864 7.108777) (xy 258.72884 7.028818) (xy 258.752307 6.946342)
			(xy 258.768063 6.862052) (xy 258.775975 6.776669) (xy 258.77647 6.733794) (xy 258.775975 6.690919)
			(xy 263.271241 6.690919) (xy 263.271241 6.776669) (xy 263.279153 6.862052) (xy 263.294909 6.946342)
			(xy 263.318376 7.028818) (xy 263.349352 7.108777) (xy 263.387574 7.185537) (xy 263.432715 7.258443)
			(xy 263.484391 7.326872) (xy 263.54216 7.390242) (xy 263.60553 7.448011) (xy 263.673959 7.499687)
			(xy 263.746865 7.544828) (xy 263.823625 7.58305) (xy 263.903584 7.614026) (xy 263.98606 7.637493)
			(xy 264.07035 7.653249) (xy 264.155733 7.661161) (xy 264.241483 7.661161) (xy 264.326866 7.653249)
			(xy 264.411156 7.637493) (xy 264.493632 7.614026) (xy 264.573591 7.58305) (xy 264.650351 7.544828)
			(xy 264.723257 7.499687) (xy 264.791686 7.448011) (xy 264.855056 7.390242) (xy 264.912825 7.326872)
			(xy 264.964501 7.258443) (xy 265.009642 7.185537) (xy 265.047864 7.108777) (xy 265.07884 7.028818)
			(xy 265.102307 6.946342) (xy 265.118063 6.862052) (xy 265.125975 6.776669) (xy 265.12647 6.733794)
			(xy 265.125975 6.690919) (xy 324.845921 6.690919) (xy 324.845921 6.776669) (xy 324.853833 6.862052)
			(xy 324.869589 6.946342) (xy 324.893056 7.028818) (xy 324.924032 7.108777) (xy 324.962254 7.185537)
			(xy 325.007395 7.258443) (xy 325.059071 7.326872) (xy 325.11684 7.390242) (xy 325.18021 7.448011)
			(xy 325.248639 7.499687) (xy 325.321545 7.544828) (xy 325.398305 7.58305) (xy 325.478264 7.614026)
			(xy 325.56074 7.637493) (xy 325.64503 7.653249) (xy 325.730413 7.661161) (xy 325.816163 7.661161)
			(xy 325.901546 7.653249) (xy 325.985836 7.637493) (xy 326.068312 7.614026) (xy 326.148271 7.58305)
			(xy 326.170474 7.571994) (xy 327.352152 7.571994) (xy 327.352152 8.435594) (xy 327.352638 8.462863)
			(xy 327.3604 8.516847) (xy 327.375765 8.569177) (xy 327.398422 8.618787) (xy 327.427908 8.664668)
			(xy 327.463623 8.705885) (xy 327.50484 8.7416) (xy 327.550721 8.771086) (xy 327.600331 8.793743)
			(xy 327.652661 8.809108) (xy 327.706645 8.81687) (xy 327.761183 8.81687) (xy 327.815167 8.809108)
			(xy 327.867497 8.793743) (xy 327.917107 8.771086) (xy 327.962988 8.7416) (xy 328.004205 8.705885)
			(xy 328.03992 8.664668) (xy 328.069406 8.618787) (xy 328.092063 8.569177) (xy 328.107428 8.516847)
			(xy 328.11519 8.462863) (xy 328.115676 8.435594) (xy 328.115676 7.571994) (xy 328.11519 7.544725)
			(xy 328.107428 7.490741) (xy 328.092063 7.438411) (xy 328.069406 7.388801) (xy 328.03992 7.34292)
			(xy 328.004205 7.301703) (xy 327.962988 7.265988) (xy 327.917107 7.236502) (xy 327.867497 7.213845)
			(xy 327.815167 7.19848) (xy 327.761183 7.190718) (xy 327.706645 7.190718) (xy 327.652661 7.19848)
			(xy 327.600331 7.213845) (xy 327.550721 7.236502) (xy 327.50484 7.265988) (xy 327.463623 7.301703)
			(xy 327.427908 7.34292) (xy 327.398422 7.388801) (xy 327.375765 7.438411) (xy 327.3604 7.490741)
			(xy 327.352638 7.544725) (xy 327.352152 7.571994) (xy 326.170474 7.571994) (xy 326.225031 7.544828)
			(xy 326.297937 7.499687) (xy 326.366366 7.448011) (xy 326.429736 7.390242) (xy 326.487505 7.326872)
			(xy 326.539181 7.258443) (xy 326.584322 7.185537) (xy 326.622544 7.108777) (xy 326.65352 7.028818)
			(xy 326.676987 6.946342) (xy 326.692743 6.862052) (xy 326.700655 6.776669) (xy 326.70115 6.733794)
			(xy 326.700655 6.690919) (xy 331.195921 6.690919) (xy 331.195921 6.776669) (xy 331.203833 6.862052)
			(xy 331.219589 6.946342) (xy 331.243056 7.028818) (xy 331.274032 7.108777) (xy 331.312254 7.185537)
			(xy 331.357395 7.258443) (xy 331.409071 7.326872) (xy 331.46684 7.390242) (xy 331.53021 7.448011)
			(xy 331.598639 7.499687) (xy 331.671545 7.544828) (xy 331.748305 7.58305) (xy 331.828264 7.614026)
			(xy 331.91074 7.637493) (xy 331.99503 7.653249) (xy 332.080413 7.661161) (xy 332.166163 7.661161)
			(xy 332.251546 7.653249) (xy 332.335836 7.637493) (xy 332.418312 7.614026) (xy 332.498271 7.58305)
			(xy 332.575031 7.544828) (xy 332.647937 7.499687) (xy 332.716366 7.448011) (xy 332.779736 7.390242)
			(xy 332.837505 7.326872) (xy 332.889181 7.258443) (xy 332.934322 7.185537) (xy 332.972544 7.108777)
			(xy 333.00352 7.028818) (xy 333.026987 6.946342) (xy 333.042743 6.862052) (xy 333.050655 6.776669)
			(xy 333.05115 6.733794) (xy 333.050655 6.690919) (xy 335.488267 6.690919) (xy 335.488267 6.776669)
			(xy 335.496179 6.862052) (xy 335.511935 6.946342) (xy 335.535402 7.028818) (xy 335.566378 7.108777)
			(xy 335.6046 7.185537) (xy 335.649741 7.258443) (xy 335.701417 7.326872) (xy 335.759186 7.390242)
			(xy 335.822556 7.448011) (xy 335.890985 7.499687) (xy 335.963891 7.544828) (xy 336.040651 7.58305)
			(xy 336.12061 7.614026) (xy 336.203086 7.637493) (xy 336.287376 7.653249) (xy 336.372759 7.661161)
			(xy 336.458509 7.661161) (xy 336.543892 7.653249) (xy 336.628182 7.637493) (xy 336.710658 7.614026)
			(xy 336.790617 7.58305) (xy 336.81282 7.571994) (xy 340.4235 7.571994) (xy 340.4235 8.435594) (xy 340.423986 8.462845)
			(xy 340.431742 8.516793) (xy 340.447097 8.569088) (xy 340.469739 8.618665) (xy 340.499205 8.664515)
			(xy 340.534896 8.705706) (xy 340.576087 8.741397) (xy 340.621937 8.770863) (xy 340.671514 8.793505)
			(xy 340.723809 8.80886) (xy 340.777757 8.816616) (xy 340.832259 8.816616) (xy 340.886207 8.80886)
			(xy 340.938502 8.793505) (xy 340.988079 8.770863) (xy 341.033929 8.741397) (xy 341.07512 8.705706)
			(xy 341.110811 8.664515) (xy 341.140277 8.618665) (xy 341.162919 8.569088) (xy 341.178274 8.516793)
			(xy 341.18603 8.462845) (xy 341.186516 8.435594) (xy 341.186516 7.571994) (xy 341.18603 7.544743)
			(xy 341.178274 7.490795) (xy 341.162919 7.4385) (xy 341.140277 7.388923) (xy 341.110811 7.343073)
			(xy 341.07512 7.301882) (xy 341.033929 7.266191) (xy 340.988079 7.236725) (xy 340.938502 7.214083)
			(xy 340.886207 7.198728) (xy 340.832259 7.190972) (xy 340.777757 7.190972) (xy 340.723809 7.198728)
			(xy 340.671514 7.214083) (xy 340.621937 7.236725) (xy 340.576087 7.266191) (xy 340.534896 7.301882)
			(xy 340.499205 7.343073) (xy 340.469739 7.388923) (xy 340.447097 7.4385) (xy 340.431742 7.490795)
			(xy 340.423986 7.544743) (xy 340.4235 7.571994) (xy 336.81282 7.571994) (xy 336.867377 7.544828)
			(xy 336.940283 7.499687) (xy 337.008712 7.448011) (xy 337.072082 7.390242) (xy 337.129851 7.326872)
			(xy 337.181527 7.258443) (xy 337.226668 7.185537) (xy 337.26489 7.108777) (xy 337.295866 7.028818)
			(xy 337.319333 6.946342) (xy 337.335089 6.862052) (xy 337.343001 6.776669) (xy 337.343496 6.733794)
			(xy 337.343001 6.690919) (xy 341.838267 6.690919) (xy 341.838267 6.776669) (xy 341.846179 6.862052)
			(xy 341.861935 6.946342) (xy 341.885402 7.028818) (xy 341.916378 7.108777) (xy 341.9546 7.185537)
			(xy 341.999741 7.258443) (xy 342.051417 7.326872) (xy 342.109186 7.390242) (xy 342.172556 7.448011)
			(xy 342.240985 7.499687) (xy 342.313891 7.544828) (xy 342.390651 7.58305) (xy 342.47061 7.614026)
			(xy 342.553086 7.637493) (xy 342.637376 7.653249) (xy 342.722759 7.661161) (xy 342.808509 7.661161)
			(xy 342.893892 7.653249) (xy 342.978182 7.637493) (xy 343.060658 7.614026) (xy 343.140617 7.58305)
			(xy 343.217377 7.544828) (xy 343.290283 7.499687) (xy 343.358712 7.448011) (xy 343.422082 7.390242)
			(xy 343.479851 7.326872) (xy 343.531527 7.258443) (xy 343.576668 7.185537) (xy 343.61489 7.108777)
			(xy 343.645866 7.028818) (xy 343.669333 6.946342) (xy 343.685089 6.862052) (xy 343.693001 6.776669)
			(xy 343.693496 6.733794) (xy 343.693001 6.690919) (xy 373.705107 6.690919) (xy 373.705107 6.776669)
			(xy 373.713019 6.862052) (xy 373.728775 6.946342) (xy 373.752242 7.028818) (xy 373.783218 7.108777)
			(xy 373.82144 7.185537) (xy 373.866581 7.258443) (xy 373.918257 7.326872) (xy 373.976026 7.390242)
			(xy 374.039396 7.448011) (xy 374.107825 7.499687) (xy 374.180731 7.544828) (xy 374.257491 7.58305)
			(xy 374.33745 7.614026) (xy 374.419926 7.637493) (xy 374.504216 7.653249) (xy 374.589599 7.661161)
			(xy 374.675349 7.661161) (xy 374.760732 7.653249) (xy 374.845022 7.637493) (xy 374.927498 7.614026)
			(xy 375.007457 7.58305) (xy 375.02966 7.571994) (xy 376.211592 7.571994) (xy 376.211592 8.435594)
			(xy 376.212078 8.462845) (xy 376.219834 8.516793) (xy 376.235189 8.569088) (xy 376.257831 8.618665)
			(xy 376.287297 8.664515) (xy 376.322988 8.705706) (xy 376.364179 8.741397) (xy 376.410029 8.770863)
			(xy 376.459606 8.793505) (xy 376.511901 8.80886) (xy 376.565849 8.816616) (xy 376.620351 8.816616)
			(xy 376.674299 8.80886) (xy 376.726594 8.793505) (xy 376.776171 8.770863) (xy 376.822021 8.741397)
			(xy 376.863212 8.705706) (xy 376.898903 8.664515) (xy 376.928369 8.618665) (xy 376.951011 8.569088)
			(xy 376.966366 8.516793) (xy 376.974122 8.462845) (xy 376.974608 8.435594) (xy 376.974608 7.571994)
			(xy 376.974122 7.544743) (xy 376.966366 7.490795) (xy 376.951011 7.4385) (xy 376.928369 7.388923)
			(xy 376.898903 7.343073) (xy 376.863212 7.301882) (xy 376.822021 7.266191) (xy 376.776171 7.236725)
			(xy 376.726594 7.214083) (xy 376.674299 7.198728) (xy 376.620351 7.190972) (xy 376.565849 7.190972)
			(xy 376.511901 7.198728) (xy 376.459606 7.214083) (xy 376.410029 7.236725) (xy 376.364179 7.266191)
			(xy 376.322988 7.301882) (xy 376.287297 7.343073) (xy 376.257831 7.388923) (xy 376.235189 7.4385)
			(xy 376.219834 7.490795) (xy 376.212078 7.544743) (xy 376.211592 7.571994) (xy 375.02966 7.571994)
			(xy 375.084217 7.544828) (xy 375.157123 7.499687) (xy 375.225552 7.448011) (xy 375.288922 7.390242)
			(xy 375.346691 7.326872) (xy 375.398367 7.258443) (xy 375.443508 7.185537) (xy 375.48173 7.108777)
			(xy 375.512706 7.028818) (xy 375.536173 6.946342) (xy 375.551929 6.862052) (xy 375.559841 6.776669)
			(xy 375.560336 6.733794) (xy 375.559841 6.690919) (xy 380.055107 6.690919) (xy 380.055107 6.776669)
			(xy 380.063019 6.862052) (xy 380.078775 6.946342) (xy 380.102242 7.028818) (xy 380.133218 7.108777)
			(xy 380.17144 7.185537) (xy 380.216581 7.258443) (xy 380.268257 7.326872) (xy 380.326026 7.390242)
			(xy 380.389396 7.448011) (xy 380.457825 7.499687) (xy 380.530731 7.544828) (xy 380.607491 7.58305)
			(xy 380.68745 7.614026) (xy 380.769926 7.637493) (xy 380.854216 7.653249) (xy 380.939599 7.661161)
			(xy 381.025349 7.661161) (xy 381.110732 7.653249) (xy 381.195022 7.637493) (xy 381.277498 7.614026)
			(xy 381.357457 7.58305) (xy 381.434217 7.544828) (xy 381.507123 7.499687) (xy 381.575552 7.448011)
			(xy 381.638922 7.390242) (xy 381.688857 7.335466) (xy 464.704165 7.335466) (xy 464.704165 7.464606)
			(xy 464.712115 7.593501) (xy 464.727985 7.721661) (xy 464.751714 7.848602) (xy 464.783213 7.973841)
			(xy 464.822362 8.096904) (xy 464.869013 8.217323) (xy 464.922988 8.334642) (xy 464.984083 8.448416)
			(xy 465.052066 8.558213) (xy 465.12668 8.663616) (xy 465.207641 8.764226) (xy 465.294641 8.859661)
			(xy 465.387352 8.94956) (xy 465.485422 9.033581) (xy 465.588477 9.111405) (xy 465.696128 9.182737)
			(xy 465.807967 9.247307) (xy 465.923568 9.304869) (xy 466.042493 9.355206) (xy 466.164292 9.398126)
			(xy 466.288502 9.433467) (xy 466.414651 9.461094) (xy 466.542263 9.480903) (xy 466.670852 9.492819)
			(xy 466.79993 9.496796) (xy 466.929008 9.492819) (xy 467.057597 9.480903) (xy 467.185209 9.461094)
			(xy 467.311358 9.433467) (xy 467.435568 9.398126) (xy 467.557367 9.355206) (xy 467.676292 9.304869)
			(xy 467.791893 9.247307) (xy 467.903732 9.182737) (xy 468.011383 9.111405) (xy 468.114438 9.033581)
			(xy 468.212508 8.94956) (xy 468.305219 8.859661) (xy 468.392219 8.764226) (xy 468.47318 8.663616)
			(xy 468.547794 8.558213) (xy 468.615777 8.448416) (xy 468.676872 8.334642) (xy 468.730847 8.217323)
			(xy 468.777498 8.096904) (xy 468.816647 7.973841) (xy 468.848146 7.848602) (xy 468.871875 7.721661)
			(xy 468.887745 7.593501) (xy 468.895695 7.464606) (xy 468.896192 7.400036) (xy 468.895695 7.335466)
			(xy 468.887745 7.206571) (xy 468.871875 7.078411) (xy 468.848146 6.95147) (xy 468.816647 6.826231)
			(xy 468.777498 6.703168) (xy 468.730847 6.582749) (xy 468.676872 6.46543) (xy 468.615777 6.351656)
			(xy 468.547794 6.241859) (xy 468.47318 6.136456) (xy 468.392219 6.035846) (xy 468.305219 5.940411)
			(xy 468.212508 5.850512) (xy 468.114438 5.766491) (xy 468.011383 5.688667) (xy 467.903732 5.617335)
			(xy 467.791893 5.552765) (xy 467.676292 5.495203) (xy 467.557367 5.444866) (xy 467.435568 5.401946)
			(xy 467.311358 5.366605) (xy 467.185209 5.338978) (xy 467.057597 5.319169) (xy 466.929008 5.307253)
			(xy 466.79993 5.303277) (xy 466.670852 5.307253) (xy 466.542263 5.319169) (xy 466.414651 5.338978)
			(xy 466.288502 5.366605) (xy 466.164292 5.401946) (xy 466.042493 5.444866) (xy 465.923568 5.495203)
			(xy 465.807967 5.552765) (xy 465.696128 5.617335) (xy 465.588477 5.688667) (xy 465.485422 5.766491)
			(xy 465.387352 5.850512) (xy 465.294641 5.940411) (xy 465.207641 6.035846) (xy 465.12668 6.136456)
			(xy 465.052066 6.241859) (xy 464.984083 6.351656) (xy 464.922988 6.46543) (xy 464.869013 6.582749)
			(xy 464.822362 6.703168) (xy 464.783213 6.826231) (xy 464.751714 6.95147) (xy 464.727985 7.078411)
			(xy 464.712115 7.206571) (xy 464.704165 7.335466) (xy 381.688857 7.335466) (xy 381.696691 7.326872)
			(xy 381.748367 7.258443) (xy 381.793508 7.185537) (xy 381.83173 7.108777) (xy 381.862706 7.028818)
			(xy 381.886173 6.946342) (xy 381.901929 6.862052) (xy 381.909841 6.776669) (xy 381.910336 6.733794)
			(xy 381.909841 6.690919) (xy 381.901929 6.605536) (xy 381.886173 6.521246) (xy 381.862706 6.43877)
			(xy 381.83173 6.358811) (xy 381.793508 6.282051) (xy 381.748367 6.209145) (xy 381.696691 6.140716)
			(xy 381.638922 6.077346) (xy 381.575552 6.019577) (xy 381.507123 5.967901) (xy 381.434217 5.92276)
			(xy 381.357457 5.884538) (xy 381.277498 5.853562) (xy 381.195022 5.830095) (xy 381.110732 5.814339)
			(xy 381.025349 5.806427) (xy 380.939599 5.806427) (xy 380.854216 5.814339) (xy 380.769926 5.830095)
			(xy 380.68745 5.853562) (xy 380.607491 5.884538) (xy 380.530731 5.92276) (xy 380.457825 5.967901)
			(xy 380.389396 6.019577) (xy 380.326026 6.077346) (xy 380.268257 6.140716) (xy 380.216581 6.209145)
			(xy 380.17144 6.282051) (xy 380.133218 6.358811) (xy 380.102242 6.43877) (xy 380.078775 6.521246)
			(xy 380.063019 6.605536) (xy 380.055107 6.690919) (xy 375.559841 6.690919) (xy 375.551929 6.605536)
			(xy 375.536173 6.521246) (xy 375.512706 6.43877) (xy 375.48173 6.358811) (xy 375.443508 6.282051)
			(xy 375.398367 6.209145) (xy 375.346691 6.140716) (xy 375.288922 6.077346) (xy 375.225552 6.019577)
			(xy 375.157123 5.967901) (xy 375.084217 5.92276) (xy 375.007457 5.884538) (xy 374.927498 5.853562)
			(xy 374.845022 5.830095) (xy 374.760732 5.814339) (xy 374.675349 5.806427) (xy 374.589599 5.806427)
			(xy 374.504216 5.814339) (xy 374.419926 5.830095) (xy 374.33745 5.853562) (xy 374.257491 5.884538)
			(xy 374.180731 5.92276) (xy 374.107825 5.967901) (xy 374.039396 6.019577) (xy 373.976026 6.077346)
			(xy 373.918257 6.140716) (xy 373.866581 6.209145) (xy 373.82144 6.282051) (xy 373.783218 6.358811)
			(xy 373.752242 6.43877) (xy 373.728775 6.521246) (xy 373.713019 6.605536) (xy 373.705107 6.690919)
			(xy 343.693001 6.690919) (xy 343.685089 6.605536) (xy 343.669333 6.521246) (xy 343.645866 6.43877)
			(xy 343.61489 6.358811) (xy 343.576668 6.282051) (xy 343.531527 6.209145) (xy 343.479851 6.140716)
			(xy 343.422082 6.077346) (xy 343.358712 6.019577) (xy 343.290283 5.967901) (xy 343.217377 5.92276)
			(xy 343.140617 5.884538) (xy 343.060658 5.853562) (xy 342.978182 5.830095) (xy 342.893892 5.814339)
			(xy 342.808509 5.806427) (xy 342.722759 5.806427) (xy 342.637376 5.814339) (xy 342.553086 5.830095)
			(xy 342.47061 5.853562) (xy 342.390651 5.884538) (xy 342.313891 5.92276) (xy 342.240985 5.967901)
			(xy 342.172556 6.019577) (xy 342.109186 6.077346) (xy 342.051417 6.140716) (xy 341.999741 6.209145)
			(xy 341.9546 6.282051) (xy 341.916378 6.358811) (xy 341.885402 6.43877) (xy 341.861935 6.521246)
			(xy 341.846179 6.605536) (xy 341.838267 6.690919) (xy 337.343001 6.690919) (xy 337.335089 6.605536)
			(xy 337.319333 6.521246) (xy 337.295866 6.43877) (xy 337.26489 6.358811) (xy 337.226668 6.282051)
			(xy 337.181527 6.209145) (xy 337.129851 6.140716) (xy 337.072082 6.077346) (xy 337.008712 6.019577)
			(xy 336.940283 5.967901) (xy 336.867377 5.92276) (xy 336.790617 5.884538) (xy 336.710658 5.853562)
			(xy 336.628182 5.830095) (xy 336.543892 5.814339) (xy 336.458509 5.806427) (xy 336.372759 5.806427)
			(xy 336.287376 5.814339) (xy 336.203086 5.830095) (xy 336.12061 5.853562) (xy 336.040651 5.884538)
			(xy 335.963891 5.92276) (xy 335.890985 5.967901) (xy 335.822556 6.019577) (xy 335.759186 6.077346)
			(xy 335.701417 6.140716) (xy 335.649741 6.209145) (xy 335.6046 6.282051) (xy 335.566378 6.358811)
			(xy 335.535402 6.43877) (xy 335.511935 6.521246) (xy 335.496179 6.605536) (xy 335.488267 6.690919)
			(xy 333.050655 6.690919) (xy 333.042743 6.605536) (xy 333.026987 6.521246) (xy 333.00352 6.43877)
			(xy 332.972544 6.358811) (xy 332.934322 6.282051) (xy 332.889181 6.209145) (xy 332.837505 6.140716)
			(xy 332.779736 6.077346) (xy 332.716366 6.019577) (xy 332.647937 5.967901) (xy 332.575031 5.92276)
			(xy 332.498271 5.884538) (xy 332.418312 5.853562) (xy 332.335836 5.830095) (xy 332.251546 5.814339)
			(xy 332.166163 5.806427) (xy 332.080413 5.806427) (xy 331.99503 5.814339) (xy 331.91074 5.830095)
			(xy 331.828264 5.853562) (xy 331.748305 5.884538) (xy 331.671545 5.92276) (xy 331.598639 5.967901)
			(xy 331.53021 6.019577) (xy 331.46684 6.077346) (xy 331.409071 6.140716) (xy 331.357395 6.209145)
			(xy 331.312254 6.282051) (xy 331.274032 6.358811) (xy 331.243056 6.43877) (xy 331.219589 6.521246)
			(xy 331.203833 6.605536) (xy 331.195921 6.690919) (xy 326.700655 6.690919) (xy 326.692743 6.605536)
			(xy 326.676987 6.521246) (xy 326.65352 6.43877) (xy 326.622544 6.358811) (xy 326.584322 6.282051)
			(xy 326.539181 6.209145) (xy 326.487505 6.140716) (xy 326.429736 6.077346) (xy 326.366366 6.019577)
			(xy 326.297937 5.967901) (xy 326.225031 5.92276) (xy 326.148271 5.884538) (xy 326.068312 5.853562)
			(xy 325.985836 5.830095) (xy 325.901546 5.814339) (xy 325.816163 5.806427) (xy 325.730413 5.806427)
			(xy 325.64503 5.814339) (xy 325.56074 5.830095) (xy 325.478264 5.853562) (xy 325.398305 5.884538)
			(xy 325.321545 5.92276) (xy 325.248639 5.967901) (xy 325.18021 6.019577) (xy 325.11684 6.077346)
			(xy 325.059071 6.140716) (xy 325.007395 6.209145) (xy 324.962254 6.282051) (xy 324.924032 6.358811)
			(xy 324.893056 6.43877) (xy 324.869589 6.521246) (xy 324.853833 6.605536) (xy 324.845921 6.690919)
			(xy 265.125975 6.690919) (xy 265.118063 6.605536) (xy 265.102307 6.521246) (xy 265.07884 6.43877)
			(xy 265.047864 6.358811) (xy 265.009642 6.282051) (xy 264.964501 6.209145) (xy 264.912825 6.140716)
			(xy 264.855056 6.077346) (xy 264.791686 6.019577) (xy 264.723257 5.967901) (xy 264.650351 5.92276)
			(xy 264.573591 5.884538) (xy 264.493632 5.853562) (xy 264.411156 5.830095) (xy 264.326866 5.814339)
			(xy 264.241483 5.806427) (xy 264.155733 5.806427) (xy 264.07035 5.814339) (xy 263.98606 5.830095)
			(xy 263.903584 5.853562) (xy 263.823625 5.884538) (xy 263.746865 5.92276) (xy 263.673959 5.967901)
			(xy 263.60553 6.019577) (xy 263.54216 6.077346) (xy 263.484391 6.140716) (xy 263.432715 6.209145)
			(xy 263.387574 6.282051) (xy 263.349352 6.358811) (xy 263.318376 6.43877) (xy 263.294909 6.521246)
			(xy 263.279153 6.605536) (xy 263.271241 6.690919) (xy 258.775975 6.690919) (xy 258.768063 6.605536)
			(xy 258.752307 6.521246) (xy 258.72884 6.43877) (xy 258.697864 6.358811) (xy 258.659642 6.282051)
			(xy 258.614501 6.209145) (xy 258.562825 6.140716) (xy 258.505056 6.077346) (xy 258.441686 6.019577)
			(xy 258.373257 5.967901) (xy 258.300351 5.92276) (xy 258.223591 5.884538) (xy 258.143632 5.853562)
			(xy 258.061156 5.830095) (xy 257.976866 5.814339) (xy 257.891483 5.806427) (xy 257.805733 5.806427)
			(xy 257.72035 5.814339) (xy 257.63606 5.830095) (xy 257.553584 5.853562) (xy 257.473625 5.884538)
			(xy 257.396865 5.92276) (xy 257.323959 5.967901) (xy 257.25553 6.019577) (xy 257.19216 6.077346)
			(xy 257.134391 6.140716) (xy 257.082715 6.209145) (xy 257.037574 6.282051) (xy 256.999352 6.358811)
			(xy 256.968376 6.43877) (xy 256.944909 6.521246) (xy 256.929153 6.605536) (xy 256.921241 6.690919)
			(xy 254.465119 6.690919) (xy 254.465087 6.688125) (xy 254.457175 6.602742) (xy 254.441419 6.518452)
			(xy 254.417952 6.435976) (xy 254.386976 6.356017) (xy 254.348754 6.279257) (xy 254.303613 6.206351)
			(xy 254.251937 6.137922) (xy 254.194168 6.074552) (xy 254.130798 6.016783) (xy 254.062369 5.965107)
			(xy 253.989463 5.919966) (xy 253.912703 5.881744) (xy 253.832744 5.850768) (xy 253.750268 5.827301)
			(xy 253.665978 5.811545) (xy 253.580595 5.803633) (xy 253.494845 5.803633) (xy 253.409462 5.811545)
			(xy 253.325172 5.827301) (xy 253.242696 5.850768) (xy 253.162737 5.881744) (xy 253.085977 5.919966)
			(xy 253.013071 5.965107) (xy 252.944642 6.016783) (xy 252.881272 6.074552) (xy 252.823503 6.137922)
			(xy 252.771827 6.206351) (xy 252.726686 6.279257) (xy 252.688464 6.356017) (xy 252.657488 6.435976)
			(xy 252.634021 6.518452) (xy 252.618265 6.602742) (xy 252.610353 6.688125) (xy 248.115087 6.688125)
			(xy 248.107175 6.602742) (xy 248.091419 6.518452) (xy 248.067952 6.435976) (xy 248.036976 6.356017)
			(xy 247.998754 6.279257) (xy 247.953613 6.206351) (xy 247.901937 6.137922) (xy 247.844168 6.074552)
			(xy 247.780798 6.016783) (xy 247.712369 5.965107) (xy 247.639463 5.919966) (xy 247.562703 5.881744)
			(xy 247.482744 5.850768) (xy 247.400268 5.827301) (xy 247.315978 5.811545) (xy 247.230595 5.803633)
			(xy 247.144845 5.803633) (xy 247.059462 5.811545) (xy 246.975172 5.827301) (xy 246.892696 5.850768)
			(xy 246.812737 5.881744) (xy 246.735977 5.919966) (xy 246.663071 5.965107) (xy 246.594642 6.016783)
			(xy 246.531272 6.074552) (xy 246.473503 6.137922) (xy 246.421827 6.206351) (xy 246.376686 6.279257)
			(xy 246.338464 6.356017) (xy 246.307488 6.435976) (xy 246.284021 6.518452) (xy 246.268265 6.602742)
			(xy 246.260353 6.688125) (xy 186.540407 6.688125) (xy 186.532495 6.602742) (xy 186.516739 6.518452)
			(xy 186.493272 6.435976) (xy 186.462296 6.356017) (xy 186.424074 6.279257) (xy 186.378933 6.206351)
			(xy 186.327257 6.137922) (xy 186.269488 6.074552) (xy 186.206118 6.016783) (xy 186.137689 5.965107)
			(xy 186.064783 5.919966) (xy 185.988023 5.881744) (xy 185.908064 5.850768) (xy 185.825588 5.827301)
			(xy 185.741298 5.811545) (xy 185.655915 5.803633) (xy 185.570165 5.803633) (xy 185.484782 5.811545)
			(xy 185.400492 5.827301) (xy 185.318016 5.850768) (xy 185.238057 5.881744) (xy 185.161297 5.919966)
			(xy 185.088391 5.965107) (xy 185.019962 6.016783) (xy 184.956592 6.074552) (xy 184.898823 6.137922)
			(xy 184.847147 6.206351) (xy 184.802006 6.279257) (xy 184.763784 6.356017) (xy 184.732808 6.435976)
			(xy 184.709341 6.518452) (xy 184.693585 6.602742) (xy 184.685673 6.688125) (xy 180.190407 6.688125)
			(xy 180.182495 6.602742) (xy 180.166739 6.518452) (xy 180.143272 6.435976) (xy 180.112296 6.356017)
			(xy 180.074074 6.279257) (xy 180.028933 6.206351) (xy 179.977257 6.137922) (xy 179.919488 6.074552)
			(xy 179.856118 6.016783) (xy 179.787689 5.965107) (xy 179.714783 5.919966) (xy 179.638023 5.881744)
			(xy 179.558064 5.850768) (xy 179.475588 5.827301) (xy 179.391298 5.811545) (xy 179.305915 5.803633)
			(xy 179.220165 5.803633) (xy 179.134782 5.811545) (xy 179.050492 5.827301) (xy 178.968016 5.850768)
			(xy 178.888057 5.881744) (xy 178.811297 5.919966) (xy 178.738391 5.965107) (xy 178.669962 6.016783)
			(xy 178.606592 6.074552) (xy 178.548823 6.137922) (xy 178.497147 6.206351) (xy 178.452006 6.279257)
			(xy 178.413784 6.356017) (xy 178.382808 6.435976) (xy 178.359341 6.518452) (xy 178.343585 6.602742)
			(xy 178.335673 6.688125) (xy 6.97173 6.688125) (xy 6.930907 6.582749) (xy 6.876932 6.46543) (xy 6.815837 6.351656)
			(xy 6.747854 6.241859) (xy 6.67324 6.136456) (xy 6.592279 6.035846) (xy 6.505279 5.940411) (xy 6.412568 5.850512)
			(xy 6.314498 5.766491) (xy 6.211443 5.688667) (xy 6.103792 5.617335) (xy 5.991953 5.552765) (xy 5.876352 5.495203)
			(xy 5.757427 5.444866) (xy 5.635628 5.401946) (xy 5.511418 5.366605) (xy 5.385269 5.338978) (xy 5.257657 5.319169)
			(xy 5.129068 5.307253) (xy 4.99999 5.303277) (xy 4.870912 5.307253) (xy 4.742323 5.319169) (xy 4.614711 5.338978)
			(xy 4.488562 5.366605) (xy 4.364352 5.401946) (xy 4.242553 5.444866) (xy 4.123628 5.495203) (xy 4.008027 5.552765)
			(xy 3.896188 5.617335) (xy 3.788537 5.688667) (xy 3.685482 5.766491) (xy 3.587412 5.850512) (xy 3.494701 5.940411)
			(xy 3.407701 6.035846) (xy 3.32674 6.136456) (xy 3.252126 6.241859) (xy 3.184143 6.351656) (xy 3.123048 6.46543)
			(xy 3.069073 6.582749) (xy 3.022422 6.703168) (xy 2.983273 6.826231) (xy 2.951774 6.95147) (xy 2.928045 7.078411)
			(xy 2.912175 7.206571) (xy 2.904225 7.335466) (xy 0.508 7.335466) (xy 0.508 4.148125) (xy 178.335673 4.148125)
			(xy 178.335673 4.233875) (xy 178.343585 4.319258) (xy 178.359341 4.403548) (xy 178.382808 4.486024)
			(xy 178.413784 4.565983) (xy 178.452006 4.642743) (xy 178.497147 4.715649) (xy 178.548823 4.784078)
			(xy 178.606592 4.847448) (xy 178.669962 4.905217) (xy 178.738391 4.956893) (xy 178.811297 5.002034)
			(xy 178.888057 5.040256) (xy 178.968016 5.071232) (xy 179.050492 5.094699) (xy 179.134782 5.110455)
			(xy 179.220165 5.118367) (xy 179.305915 5.118367) (xy 179.391298 5.110455) (xy 179.475588 5.094699)
			(xy 179.558064 5.071232) (xy 179.638023 5.040256) (xy 179.660226 5.0292) (xy 183.270652 5.0292) (xy 183.270652 5.8928)
			(xy 183.271138 5.920069) (xy 183.2789 5.974053) (xy 183.294265 6.026383) (xy 183.316922 6.075993)
			(xy 183.346408 6.121874) (xy 183.382123 6.163091) (xy 183.42334 6.198806) (xy 183.469221 6.228292)
			(xy 183.518831 6.250949) (xy 183.571161 6.266314) (xy 183.625145 6.274076) (xy 183.679683 6.274076)
			(xy 183.733667 6.266314) (xy 183.785997 6.250949) (xy 183.835607 6.228292) (xy 183.881488 6.198806)
			(xy 183.922705 6.163091) (xy 183.95842 6.121874) (xy 183.987906 6.075993) (xy 184.010563 6.026383)
			(xy 184.025928 5.974053) (xy 184.03369 5.920069) (xy 184.034176 5.8928) (xy 184.034176 5.0292) (xy 184.03369 5.001931)
			(xy 184.025928 4.947947) (xy 184.010563 4.895617) (xy 183.987906 4.846007) (xy 183.95842 4.800126)
			(xy 183.922705 4.758909) (xy 183.881488 4.723194) (xy 183.835607 4.693708) (xy 183.785997 4.671051)
			(xy 183.733667 4.655686) (xy 183.679683 4.647924) (xy 183.625145 4.647924) (xy 183.571161 4.655686)
			(xy 183.518831 4.671051) (xy 183.469221 4.693708) (xy 183.42334 4.723194) (xy 183.382123 4.758909)
			(xy 183.346408 4.800126) (xy 183.316922 4.846007) (xy 183.294265 4.895617) (xy 183.2789 4.947947)
			(xy 183.271138 5.001931) (xy 183.270652 5.0292) (xy 179.660226 5.0292) (xy 179.714783 5.002034) (xy 179.787689 4.956893)
			(xy 179.856118 4.905217) (xy 179.919488 4.847448) (xy 179.977257 4.784078) (xy 180.028933 4.715649)
			(xy 180.074074 4.642743) (xy 180.112296 4.565983) (xy 180.143272 4.486024) (xy 180.166739 4.403548)
			(xy 180.182495 4.319258) (xy 180.190407 4.233875) (xy 180.190902 4.191) (xy 180.190407 4.148125)
			(xy 184.685673 4.148125) (xy 184.685673 4.233875) (xy 184.693585 4.319258) (xy 184.709341 4.403548)
			(xy 184.732808 4.486024) (xy 184.763784 4.565983) (xy 184.802006 4.642743) (xy 184.847147 4.715649)
			(xy 184.898823 4.784078) (xy 184.956592 4.847448) (xy 185.019962 4.905217) (xy 185.088391 4.956893)
			(xy 185.161297 5.002034) (xy 185.238057 5.040256) (xy 185.318016 5.071232) (xy 185.400492 5.094699)
			(xy 185.484782 5.110455) (xy 185.570165 5.118367) (xy 185.655915 5.118367) (xy 185.741298 5.110455)
			(xy 185.825588 5.094699) (xy 185.908064 5.071232) (xy 185.988023 5.040256) (xy 186.064783 5.002034)
			(xy 186.137689 4.956893) (xy 186.206118 4.905217) (xy 186.269488 4.847448) (xy 186.327257 4.784078)
			(xy 186.378933 4.715649) (xy 186.424074 4.642743) (xy 186.462296 4.565983) (xy 186.493272 4.486024)
			(xy 186.516739 4.403548) (xy 186.532495 4.319258) (xy 186.540407 4.233875) (xy 186.540902 4.191)
			(xy 186.540407 4.148125) (xy 246.260353 4.148125) (xy 246.260353 4.233875) (xy 246.268265 4.319258)
			(xy 246.284021 4.403548) (xy 246.307488 4.486024) (xy 246.338464 4.565983) (xy 246.376686 4.642743)
			(xy 246.421827 4.715649) (xy 246.473503 4.784078) (xy 246.531272 4.847448) (xy 246.594642 4.905217)
			(xy 246.663071 4.956893) (xy 246.735977 5.002034) (xy 246.812737 5.040256) (xy 246.892696 5.071232)
			(xy 246.975172 5.094699) (xy 247.059462 5.110455) (xy 247.144845 5.118367) (xy 247.230595 5.118367)
			(xy 247.315978 5.110455) (xy 247.400268 5.094699) (xy 247.482744 5.071232) (xy 247.562703 5.040256)
			(xy 247.584906 5.0292) (xy 248.766584 5.0292) (xy 248.766584 5.8928) (xy 248.76707 5.920069) (xy 248.774832 5.974053)
			(xy 248.790197 6.026383) (xy 248.812854 6.075993) (xy 248.84234 6.121874) (xy 248.878055 6.163091)
			(xy 248.919272 6.198806) (xy 248.965153 6.228292) (xy 249.014763 6.250949) (xy 249.067093 6.266314)
			(xy 249.121077 6.274076) (xy 249.175615 6.274076) (xy 249.229599 6.266314) (xy 249.281929 6.250949)
			(xy 249.331539 6.228292) (xy 249.37742 6.198806) (xy 249.418637 6.163091) (xy 249.454352 6.121874)
			(xy 249.483838 6.075993) (xy 249.506495 6.026383) (xy 249.52186 5.974053) (xy 249.529622 5.920069)
			(xy 249.530108 5.8928) (xy 249.530108 5.0292) (xy 249.529622 5.001931) (xy 249.52186 4.947947) (xy 249.506495 4.895617)
			(xy 249.483838 4.846007) (xy 249.454352 4.800126) (xy 249.418637 4.758909) (xy 249.37742 4.723194)
			(xy 249.331539 4.693708) (xy 249.281929 4.671051) (xy 249.229599 4.655686) (xy 249.175615 4.647924)
			(xy 249.121077 4.647924) (xy 249.067093 4.655686) (xy 249.014763 4.671051) (xy 248.965153 4.693708)
			(xy 248.919272 4.723194) (xy 248.878055 4.758909) (xy 248.84234 4.800126) (xy 248.812854 4.846007)
			(xy 248.790197 4.895617) (xy 248.774832 4.947947) (xy 248.76707 5.001931) (xy 248.766584 5.0292)
			(xy 247.584906 5.0292) (xy 247.639463 5.002034) (xy 247.712369 4.956893) (xy 247.780798 4.905217)
			(xy 247.844168 4.847448) (xy 247.901937 4.784078) (xy 247.953613 4.715649) (xy 247.998754 4.642743)
			(xy 248.036976 4.565983) (xy 248.067952 4.486024) (xy 248.091419 4.403548) (xy 248.107175 4.319258)
			(xy 248.115087 4.233875) (xy 248.115582 4.191) (xy 248.115087 4.148125) (xy 252.610353 4.148125)
			(xy 252.610353 4.233875) (xy 252.618265 4.319258) (xy 252.634021 4.403548) (xy 252.657488 4.486024)
			(xy 252.688464 4.565983) (xy 252.726686 4.642743) (xy 252.771827 4.715649) (xy 252.823503 4.784078)
			(xy 252.881272 4.847448) (xy 252.944642 4.905217) (xy 253.013071 4.956893) (xy 253.085977 5.002034)
			(xy 253.162737 5.040256) (xy 253.242696 5.071232) (xy 253.325172 5.094699) (xy 253.409462 5.110455)
			(xy 253.494845 5.118367) (xy 253.580595 5.118367) (xy 253.665978 5.110455) (xy 253.750268 5.094699)
			(xy 253.832744 5.071232) (xy 253.912703 5.040256) (xy 253.989463 5.002034) (xy 254.062369 4.956893)
			(xy 254.130798 4.905217) (xy 254.194168 4.847448) (xy 254.251937 4.784078) (xy 254.303613 4.715649)
			(xy 254.348754 4.642743) (xy 254.386976 4.565983) (xy 254.417952 4.486024) (xy 254.441419 4.403548)
			(xy 254.457175 4.319258) (xy 254.465087 4.233875) (xy 254.465582 4.191) (xy 254.465119 4.150919)
			(xy 256.921241 4.150919) (xy 256.921241 4.236669) (xy 256.929153 4.322052) (xy 256.944909 4.406342)
			(xy 256.968376 4.488818) (xy 256.999352 4.568777) (xy 257.037574 4.645537) (xy 257.082715 4.718443)
			(xy 257.134391 4.786872) (xy 257.19216 4.850242) (xy 257.25553 4.908011) (xy 257.323959 4.959687)
			(xy 257.396865 5.004828) (xy 257.473625 5.04305) (xy 257.553584 5.074026) (xy 257.63606 5.097493)
			(xy 257.72035 5.113249) (xy 257.805733 5.121161) (xy 257.891483 5.121161) (xy 257.976866 5.113249)
			(xy 258.061156 5.097493) (xy 258.143632 5.074026) (xy 258.223591 5.04305) (xy 258.245794 5.031994)
			(xy 261.85622 5.031994) (xy 261.85622 5.895594) (xy 261.856706 5.922863) (xy 261.864468 5.976847)
			(xy 261.879833 6.029177) (xy 261.90249 6.078787) (xy 261.931976 6.124668) (xy 261.967691 6.165885)
			(xy 262.008908 6.2016) (xy 262.054789 6.231086) (xy 262.104399 6.253743) (xy 262.156729 6.269108)
			(xy 262.210713 6.27687) (xy 262.265251 6.27687) (xy 262.319235 6.269108) (xy 262.371565 6.253743)
			(xy 262.421175 6.231086) (xy 262.467056 6.2016) (xy 262.508273 6.165885) (xy 262.543988 6.124668)
			(xy 262.573474 6.078787) (xy 262.596131 6.029177) (xy 262.611496 5.976847) (xy 262.619258 5.922863)
			(xy 262.619744 5.895594) (xy 262.619744 5.031994) (xy 262.619258 5.004725) (xy 262.611496 4.950741)
			(xy 262.596131 4.898411) (xy 262.573474 4.848801) (xy 262.543988 4.80292) (xy 262.508273 4.761703)
			(xy 262.467056 4.725988) (xy 262.421175 4.696502) (xy 262.371565 4.673845) (xy 262.319235 4.65848)
			(xy 262.265251 4.650718) (xy 262.210713 4.650718) (xy 262.156729 4.65848) (xy 262.104399 4.673845)
			(xy 262.054789 4.696502) (xy 262.008908 4.725988) (xy 261.967691 4.761703) (xy 261.931976 4.80292)
			(xy 261.90249 4.848801) (xy 261.879833 4.898411) (xy 261.864468 4.950741) (xy 261.856706 5.004725)
			(xy 261.85622 5.031994) (xy 258.245794 5.031994) (xy 258.300351 5.004828) (xy 258.373257 4.959687)
			(xy 258.441686 4.908011) (xy 258.505056 4.850242) (xy 258.562825 4.786872) (xy 258.614501 4.718443)
			(xy 258.659642 4.645537) (xy 258.697864 4.568777) (xy 258.72884 4.488818) (xy 258.752307 4.406342)
			(xy 258.768063 4.322052) (xy 258.775975 4.236669) (xy 258.77647 4.193794) (xy 258.775975 4.150919)
			(xy 263.271241 4.150919) (xy 263.271241 4.236669) (xy 263.279153 4.322052) (xy 263.294909 4.406342)
			(xy 263.318376 4.488818) (xy 263.349352 4.568777) (xy 263.387574 4.645537) (xy 263.432715 4.718443)
			(xy 263.484391 4.786872) (xy 263.54216 4.850242) (xy 263.60553 4.908011) (xy 263.673959 4.959687)
			(xy 263.746865 5.004828) (xy 263.823625 5.04305) (xy 263.903584 5.074026) (xy 263.98606 5.097493)
			(xy 264.07035 5.113249) (xy 264.155733 5.121161) (xy 264.241483 5.121161) (xy 264.326866 5.113249)
			(xy 264.411156 5.097493) (xy 264.493632 5.074026) (xy 264.573591 5.04305) (xy 264.650351 5.004828)
			(xy 264.723257 4.959687) (xy 264.791686 4.908011) (xy 264.855056 4.850242) (xy 264.912825 4.786872)
			(xy 264.964501 4.718443) (xy 265.009642 4.645537) (xy 265.047864 4.568777) (xy 265.07884 4.488818)
			(xy 265.102307 4.406342) (xy 265.118063 4.322052) (xy 265.125975 4.236669) (xy 265.12647 4.193794)
			(xy 265.125975 4.150919) (xy 324.845921 4.150919) (xy 324.845921 4.236669) (xy 324.853833 4.322052)
			(xy 324.869589 4.406342) (xy 324.893056 4.488818) (xy 324.924032 4.568777) (xy 324.962254 4.645537)
			(xy 325.007395 4.718443) (xy 325.059071 4.786872) (xy 325.11684 4.850242) (xy 325.18021 4.908011)
			(xy 325.248639 4.959687) (xy 325.321545 5.004828) (xy 325.398305 5.04305) (xy 325.478264 5.074026)
			(xy 325.56074 5.097493) (xy 325.64503 5.113249) (xy 325.730413 5.121161) (xy 325.816163 5.121161)
			(xy 325.901546 5.113249) (xy 325.985836 5.097493) (xy 326.068312 5.074026) (xy 326.148271 5.04305)
			(xy 326.170474 5.031994) (xy 327.352152 5.031994) (xy 327.352152 5.895594) (xy 327.352638 5.922863)
			(xy 327.3604 5.976847) (xy 327.375765 6.029177) (xy 327.398422 6.078787) (xy 327.427908 6.124668)
			(xy 327.463623 6.165885) (xy 327.50484 6.2016) (xy 327.550721 6.231086) (xy 327.600331 6.253743)
			(xy 327.652661 6.269108) (xy 327.706645 6.27687) (xy 327.761183 6.27687) (xy 327.815167 6.269108)
			(xy 327.867497 6.253743) (xy 327.917107 6.231086) (xy 327.962988 6.2016) (xy 328.004205 6.165885)
			(xy 328.03992 6.124668) (xy 328.069406 6.078787) (xy 328.092063 6.029177) (xy 328.107428 5.976847)
			(xy 328.11519 5.922863) (xy 328.115676 5.895594) (xy 328.115676 5.031994) (xy 328.11519 5.004725)
			(xy 328.107428 4.950741) (xy 328.092063 4.898411) (xy 328.069406 4.848801) (xy 328.03992 4.80292)
			(xy 328.004205 4.761703) (xy 327.962988 4.725988) (xy 327.917107 4.696502) (xy 327.867497 4.673845)
			(xy 327.815167 4.65848) (xy 327.761183 4.650718) (xy 327.706645 4.650718) (xy 327.652661 4.65848)
			(xy 327.600331 4.673845) (xy 327.550721 4.696502) (xy 327.50484 4.725988) (xy 327.463623 4.761703)
			(xy 327.427908 4.80292) (xy 327.398422 4.848801) (xy 327.375765 4.898411) (xy 327.3604 4.950741)
			(xy 327.352638 5.004725) (xy 327.352152 5.031994) (xy 326.170474 5.031994) (xy 326.225031 5.004828)
			(xy 326.297937 4.959687) (xy 326.366366 4.908011) (xy 326.429736 4.850242) (xy 326.487505 4.786872)
			(xy 326.539181 4.718443) (xy 326.584322 4.645537) (xy 326.622544 4.568777) (xy 326.65352 4.488818)
			(xy 326.676987 4.406342) (xy 326.692743 4.322052) (xy 326.700655 4.236669) (xy 326.70115 4.193794)
			(xy 326.700655 4.150919) (xy 331.195921 4.150919) (xy 331.195921 4.236669) (xy 331.203833 4.322052)
			(xy 331.219589 4.406342) (xy 331.243056 4.488818) (xy 331.274032 4.568777) (xy 331.312254 4.645537)
			(xy 331.357395 4.718443) (xy 331.409071 4.786872) (xy 331.46684 4.850242) (xy 331.53021 4.908011)
			(xy 331.598639 4.959687) (xy 331.671545 5.004828) (xy 331.748305 5.04305) (xy 331.828264 5.074026)
			(xy 331.91074 5.097493) (xy 331.99503 5.113249) (xy 332.080413 5.121161) (xy 332.166163 5.121161)
			(xy 332.251546 5.113249) (xy 332.335836 5.097493) (xy 332.418312 5.074026) (xy 332.498271 5.04305)
			(xy 332.575031 5.004828) (xy 332.647937 4.959687) (xy 332.716366 4.908011) (xy 332.779736 4.850242)
			(xy 332.837505 4.786872) (xy 332.889181 4.718443) (xy 332.934322 4.645537) (xy 332.972544 4.568777)
			(xy 333.00352 4.488818) (xy 333.026987 4.406342) (xy 333.042743 4.322052) (xy 333.050655 4.236669)
			(xy 333.05115 4.193794) (xy 333.050655 4.150919) (xy 335.488267 4.150919) (xy 335.488267 4.236669)
			(xy 335.496179 4.322052) (xy 335.511935 4.406342) (xy 335.535402 4.488818) (xy 335.566378 4.568777)
			(xy 335.6046 4.645537) (xy 335.649741 4.718443) (xy 335.701417 4.786872) (xy 335.759186 4.850242)
			(xy 335.822556 4.908011) (xy 335.890985 4.959687) (xy 335.963891 5.004828) (xy 336.040651 5.04305)
			(xy 336.12061 5.074026) (xy 336.203086 5.097493) (xy 336.287376 5.113249) (xy 336.372759 5.121161)
			(xy 336.458509 5.121161) (xy 336.543892 5.113249) (xy 336.628182 5.097493) (xy 336.710658 5.074026)
			(xy 336.790617 5.04305) (xy 336.81282 5.031994) (xy 340.4235 5.031994) (xy 340.4235 5.895594) (xy 340.423986 5.922845)
			(xy 340.431742 5.976793) (xy 340.447097 6.029088) (xy 340.469739 6.078665) (xy 340.499205 6.124515)
			(xy 340.534896 6.165706) (xy 340.576087 6.201397) (xy 340.621937 6.230863) (xy 340.671514 6.253505)
			(xy 340.723809 6.26886) (xy 340.777757 6.276616) (xy 340.832259 6.276616) (xy 340.886207 6.26886)
			(xy 340.938502 6.253505) (xy 340.988079 6.230863) (xy 341.033929 6.201397) (xy 341.07512 6.165706)
			(xy 341.110811 6.124515) (xy 341.140277 6.078665) (xy 341.162919 6.029088) (xy 341.178274 5.976793)
			(xy 341.18603 5.922845) (xy 341.186516 5.895594) (xy 341.186516 5.031994) (xy 341.18603 5.004743)
			(xy 341.178274 4.950795) (xy 341.162919 4.8985) (xy 341.140277 4.848923) (xy 341.110811 4.803073)
			(xy 341.07512 4.761882) (xy 341.033929 4.726191) (xy 340.988079 4.696725) (xy 340.938502 4.674083)
			(xy 340.886207 4.658728) (xy 340.832259 4.650972) (xy 340.777757 4.650972) (xy 340.723809 4.658728)
			(xy 340.671514 4.674083) (xy 340.621937 4.696725) (xy 340.576087 4.726191) (xy 340.534896 4.761882)
			(xy 340.499205 4.803073) (xy 340.469739 4.848923) (xy 340.447097 4.8985) (xy 340.431742 4.950795)
			(xy 340.423986 5.004743) (xy 340.4235 5.031994) (xy 336.81282 5.031994) (xy 336.867377 5.004828)
			(xy 336.940283 4.959687) (xy 337.008712 4.908011) (xy 337.072082 4.850242) (xy 337.129851 4.786872)
			(xy 337.181527 4.718443) (xy 337.226668 4.645537) (xy 337.26489 4.568777) (xy 337.295866 4.488818)
			(xy 337.319333 4.406342) (xy 337.335089 4.322052) (xy 337.343001 4.236669) (xy 337.343496 4.193794)
			(xy 337.343001 4.150919) (xy 341.838267 4.150919) (xy 341.838267 4.236669) (xy 341.846179 4.322052)
			(xy 341.861935 4.406342) (xy 341.885402 4.488818) (xy 341.916378 4.568777) (xy 341.9546 4.645537)
			(xy 341.999741 4.718443) (xy 342.051417 4.786872) (xy 342.109186 4.850242) (xy 342.172556 4.908011)
			(xy 342.240985 4.959687) (xy 342.313891 5.004828) (xy 342.390651 5.04305) (xy 342.47061 5.074026)
			(xy 342.553086 5.097493) (xy 342.637376 5.113249) (xy 342.722759 5.121161) (xy 342.808509 5.121161)
			(xy 342.893892 5.113249) (xy 342.978182 5.097493) (xy 343.060658 5.074026) (xy 343.140617 5.04305)
			(xy 343.217377 5.004828) (xy 343.290283 4.959687) (xy 343.358712 4.908011) (xy 343.422082 4.850242)
			(xy 343.479851 4.786872) (xy 343.531527 4.718443) (xy 343.576668 4.645537) (xy 343.61489 4.568777)
			(xy 343.645866 4.488818) (xy 343.669333 4.406342) (xy 343.685089 4.322052) (xy 343.693001 4.236669)
			(xy 343.693496 4.193794) (xy 343.693001 4.150919) (xy 373.705107 4.150919) (xy 373.705107 4.236669)
			(xy 373.713019 4.322052) (xy 373.728775 4.406342) (xy 373.752242 4.488818) (xy 373.783218 4.568777)
			(xy 373.82144 4.645537) (xy 373.866581 4.718443) (xy 373.918257 4.786872) (xy 373.976026 4.850242)
			(xy 374.039396 4.908011) (xy 374.107825 4.959687) (xy 374.180731 5.004828) (xy 374.257491 5.04305)
			(xy 374.33745 5.074026) (xy 374.419926 5.097493) (xy 374.504216 5.113249) (xy 374.589599 5.121161)
			(xy 374.675349 5.121161) (xy 374.760732 5.113249) (xy 374.845022 5.097493) (xy 374.927498 5.074026)
			(xy 375.007457 5.04305) (xy 375.02966 5.031994) (xy 376.211592 5.031994) (xy 376.211592 5.895594)
			(xy 376.212078 5.922845) (xy 376.219834 5.976793) (xy 376.235189 6.029088) (xy 376.257831 6.078665)
			(xy 376.287297 6.124515) (xy 376.322988 6.165706) (xy 376.364179 6.201397) (xy 376.410029 6.230863)
			(xy 376.459606 6.253505) (xy 376.511901 6.26886) (xy 376.565849 6.276616) (xy 376.620351 6.276616)
			(xy 376.674299 6.26886) (xy 376.726594 6.253505) (xy 376.776171 6.230863) (xy 376.822021 6.201397)
			(xy 376.863212 6.165706) (xy 376.898903 6.124515) (xy 376.928369 6.078665) (xy 376.951011 6.029088)
			(xy 376.966366 5.976793) (xy 376.974122 5.922845) (xy 376.974608 5.895594) (xy 376.974608 5.031994)
			(xy 376.974122 5.004743) (xy 376.966366 4.950795) (xy 376.951011 4.8985) (xy 376.928369 4.848923)
			(xy 376.898903 4.803073) (xy 376.863212 4.761882) (xy 376.822021 4.726191) (xy 376.776171 4.696725)
			(xy 376.726594 4.674083) (xy 376.674299 4.658728) (xy 376.620351 4.650972) (xy 376.565849 4.650972)
			(xy 376.511901 4.658728) (xy 376.459606 4.674083) (xy 376.410029 4.696725) (xy 376.364179 4.726191)
			(xy 376.322988 4.761882) (xy 376.287297 4.803073) (xy 376.257831 4.848923) (xy 376.235189 4.8985)
			(xy 376.219834 4.950795) (xy 376.212078 5.004743) (xy 376.211592 5.031994) (xy 375.02966 5.031994)
			(xy 375.084217 5.004828) (xy 375.157123 4.959687) (xy 375.225552 4.908011) (xy 375.288922 4.850242)
			(xy 375.346691 4.786872) (xy 375.398367 4.718443) (xy 375.443508 4.645537) (xy 375.48173 4.568777)
			(xy 375.512706 4.488818) (xy 375.536173 4.406342) (xy 375.551929 4.322052) (xy 375.559841 4.236669)
			(xy 375.560336 4.193794) (xy 375.559841 4.150919) (xy 380.055107 4.150919) (xy 380.055107 4.236669)
			(xy 380.063019 4.322052) (xy 380.078775 4.406342) (xy 380.102242 4.488818) (xy 380.133218 4.568777)
			(xy 380.17144 4.645537) (xy 380.216581 4.718443) (xy 380.268257 4.786872) (xy 380.326026 4.850242)
			(xy 380.389396 4.908011) (xy 380.457825 4.959687) (xy 380.530731 5.004828) (xy 380.607491 5.04305)
			(xy 380.68745 5.074026) (xy 380.769926 5.097493) (xy 380.854216 5.113249) (xy 380.939599 5.121161)
			(xy 381.025349 5.121161) (xy 381.110732 5.113249) (xy 381.195022 5.097493) (xy 381.277498 5.074026)
			(xy 381.357457 5.04305) (xy 381.434217 5.004828) (xy 381.507123 4.959687) (xy 381.575552 4.908011)
			(xy 381.638922 4.850242) (xy 381.696691 4.786872) (xy 381.748367 4.718443) (xy 381.793508 4.645537)
			(xy 381.83173 4.568777) (xy 381.862706 4.488818) (xy 381.886173 4.406342) (xy 381.901929 4.322052)
			(xy 381.909841 4.236669) (xy 381.910336 4.193794) (xy 381.909841 4.150919) (xy 381.901929 4.065536)
			(xy 381.886173 3.981246) (xy 381.862706 3.89877) (xy 381.83173 3.818811) (xy 381.793508 3.742051)
			(xy 381.748367 3.669145) (xy 381.696691 3.600716) (xy 381.638922 3.537346) (xy 381.575552 3.479577)
			(xy 381.507123 3.427901) (xy 381.434217 3.38276) (xy 381.357457 3.344538) (xy 381.277498 3.313562)
			(xy 381.195022 3.290095) (xy 381.110732 3.274339) (xy 381.025349 3.266427) (xy 380.939599 3.266427)
			(xy 380.854216 3.274339) (xy 380.769926 3.290095) (xy 380.68745 3.313562) (xy 380.607491 3.344538)
			(xy 380.530731 3.38276) (xy 380.457825 3.427901) (xy 380.389396 3.479577) (xy 380.326026 3.537346)
			(xy 380.268257 3.600716) (xy 380.216581 3.669145) (xy 380.17144 3.742051) (xy 380.133218 3.818811)
			(xy 380.102242 3.89877) (xy 380.078775 3.981246) (xy 380.063019 4.065536) (xy 380.055107 4.150919)
			(xy 375.559841 4.150919) (xy 375.551929 4.065536) (xy 375.536173 3.981246) (xy 375.512706 3.89877)
			(xy 375.48173 3.818811) (xy 375.443508 3.742051) (xy 375.398367 3.669145) (xy 375.346691 3.600716)
			(xy 375.288922 3.537346) (xy 375.225552 3.479577) (xy 375.157123 3.427901) (xy 375.084217 3.38276)
			(xy 375.007457 3.344538) (xy 374.927498 3.313562) (xy 374.845022 3.290095) (xy 374.760732 3.274339)
			(xy 374.675349 3.266427) (xy 374.589599 3.266427) (xy 374.504216 3.274339) (xy 374.419926 3.290095)
			(xy 374.33745 3.313562) (xy 374.257491 3.344538) (xy 374.180731 3.38276) (xy 374.107825 3.427901)
			(xy 374.039396 3.479577) (xy 373.976026 3.537346) (xy 373.918257 3.600716) (xy 373.866581 3.669145)
			(xy 373.82144 3.742051) (xy 373.783218 3.818811) (xy 373.752242 3.89877) (xy 373.728775 3.981246)
			(xy 373.713019 4.065536) (xy 373.705107 4.150919) (xy 343.693001 4.150919) (xy 343.685089 4.065536)
			(xy 343.669333 3.981246) (xy 343.645866 3.89877) (xy 343.61489 3.818811) (xy 343.576668 3.742051)
			(xy 343.531527 3.669145) (xy 343.479851 3.600716) (xy 343.422082 3.537346) (xy 343.358712 3.479577)
			(xy 343.290283 3.427901) (xy 343.217377 3.38276) (xy 343.140617 3.344538) (xy 343.060658 3.313562)
			(xy 342.978182 3.290095) (xy 342.893892 3.274339) (xy 342.808509 3.266427) (xy 342.722759 3.266427)
			(xy 342.637376 3.274339) (xy 342.553086 3.290095) (xy 342.47061 3.313562) (xy 342.390651 3.344538)
			(xy 342.313891 3.38276) (xy 342.240985 3.427901) (xy 342.172556 3.479577) (xy 342.109186 3.537346)
			(xy 342.051417 3.600716) (xy 341.999741 3.669145) (xy 341.9546 3.742051) (xy 341.916378 3.818811)
			(xy 341.885402 3.89877) (xy 341.861935 3.981246) (xy 341.846179 4.065536) (xy 341.838267 4.150919)
			(xy 337.343001 4.150919) (xy 337.335089 4.065536) (xy 337.319333 3.981246) (xy 337.295866 3.89877)
			(xy 337.26489 3.818811) (xy 337.226668 3.742051) (xy 337.181527 3.669145) (xy 337.129851 3.600716)
			(xy 337.072082 3.537346) (xy 337.008712 3.479577) (xy 336.940283 3.427901) (xy 336.867377 3.38276)
			(xy 336.790617 3.344538) (xy 336.710658 3.313562) (xy 336.628182 3.290095) (xy 336.543892 3.274339)
			(xy 336.458509 3.266427) (xy 336.372759 3.266427) (xy 336.287376 3.274339) (xy 336.203086 3.290095)
			(xy 336.12061 3.313562) (xy 336.040651 3.344538) (xy 335.963891 3.38276) (xy 335.890985 3.427901)
			(xy 335.822556 3.479577) (xy 335.759186 3.537346) (xy 335.701417 3.600716) (xy 335.649741 3.669145)
			(xy 335.6046 3.742051) (xy 335.566378 3.818811) (xy 335.535402 3.89877) (xy 335.511935 3.981246)
			(xy 335.496179 4.065536) (xy 335.488267 4.150919) (xy 333.050655 4.150919) (xy 333.042743 4.065536)
			(xy 333.026987 3.981246) (xy 333.00352 3.89877) (xy 332.972544 3.818811) (xy 332.934322 3.742051)
			(xy 332.889181 3.669145) (xy 332.837505 3.600716) (xy 332.779736 3.537346) (xy 332.716366 3.479577)
			(xy 332.647937 3.427901) (xy 332.575031 3.38276) (xy 332.498271 3.344538) (xy 332.418312 3.313562)
			(xy 332.335836 3.290095) (xy 332.251546 3.274339) (xy 332.166163 3.266427) (xy 332.080413 3.266427)
			(xy 331.99503 3.274339) (xy 331.91074 3.290095) (xy 331.828264 3.313562) (xy 331.748305 3.344538)
			(xy 331.671545 3.38276) (xy 331.598639 3.427901) (xy 331.53021 3.479577) (xy 331.46684 3.537346)
			(xy 331.409071 3.600716) (xy 331.357395 3.669145) (xy 331.312254 3.742051) (xy 331.274032 3.818811)
			(xy 331.243056 3.89877) (xy 331.219589 3.981246) (xy 331.203833 4.065536) (xy 331.195921 4.150919)
			(xy 326.700655 4.150919) (xy 326.692743 4.065536) (xy 326.676987 3.981246) (xy 326.65352 3.89877)
			(xy 326.622544 3.818811) (xy 326.584322 3.742051) (xy 326.539181 3.669145) (xy 326.487505 3.600716)
			(xy 326.429736 3.537346) (xy 326.366366 3.479577) (xy 326.297937 3.427901) (xy 326.225031 3.38276)
			(xy 326.148271 3.344538) (xy 326.068312 3.313562) (xy 325.985836 3.290095) (xy 325.901546 3.274339)
			(xy 325.816163 3.266427) (xy 325.730413 3.266427) (xy 325.64503 3.274339) (xy 325.56074 3.290095)
			(xy 325.478264 3.313562) (xy 325.398305 3.344538) (xy 325.321545 3.38276) (xy 325.248639 3.427901)
			(xy 325.18021 3.479577) (xy 325.11684 3.537346) (xy 325.059071 3.600716) (xy 325.007395 3.669145)
			(xy 324.962254 3.742051) (xy 324.924032 3.818811) (xy 324.893056 3.89877) (xy 324.869589 3.981246)
			(xy 324.853833 4.065536) (xy 324.845921 4.150919) (xy 265.125975 4.150919) (xy 265.118063 4.065536)
			(xy 265.102307 3.981246) (xy 265.07884 3.89877) (xy 265.047864 3.818811) (xy 265.009642 3.742051)
			(xy 264.964501 3.669145) (xy 264.912825 3.600716) (xy 264.855056 3.537346) (xy 264.791686 3.479577)
			(xy 264.723257 3.427901) (xy 264.650351 3.38276) (xy 264.573591 3.344538) (xy 264.493632 3.313562)
			(xy 264.411156 3.290095) (xy 264.326866 3.274339) (xy 264.241483 3.266427) (xy 264.155733 3.266427)
			(xy 264.07035 3.274339) (xy 263.98606 3.290095) (xy 263.903584 3.313562) (xy 263.823625 3.344538)
			(xy 263.746865 3.38276) (xy 263.673959 3.427901) (xy 263.60553 3.479577) (xy 263.54216 3.537346)
			(xy 263.484391 3.600716) (xy 263.432715 3.669145) (xy 263.387574 3.742051) (xy 263.349352 3.818811)
			(xy 263.318376 3.89877) (xy 263.294909 3.981246) (xy 263.279153 4.065536) (xy 263.271241 4.150919)
			(xy 258.775975 4.150919) (xy 258.768063 4.065536) (xy 258.752307 3.981246) (xy 258.72884 3.89877)
			(xy 258.697864 3.818811) (xy 258.659642 3.742051) (xy 258.614501 3.669145) (xy 258.562825 3.600716)
			(xy 258.505056 3.537346) (xy 258.441686 3.479577) (xy 258.373257 3.427901) (xy 258.300351 3.38276)
			(xy 258.223591 3.344538) (xy 258.143632 3.313562) (xy 258.061156 3.290095) (xy 257.976866 3.274339)
			(xy 257.891483 3.266427) (xy 257.805733 3.266427) (xy 257.72035 3.274339) (xy 257.63606 3.290095)
			(xy 257.553584 3.313562) (xy 257.473625 3.344538) (xy 257.396865 3.38276) (xy 257.323959 3.427901)
			(xy 257.25553 3.479577) (xy 257.19216 3.537346) (xy 257.134391 3.600716) (xy 257.082715 3.669145)
			(xy 257.037574 3.742051) (xy 256.999352 3.818811) (xy 256.968376 3.89877) (xy 256.944909 3.981246)
			(xy 256.929153 4.065536) (xy 256.921241 4.150919) (xy 254.465119 4.150919) (xy 254.465087 4.148125)
			(xy 254.457175 4.062742) (xy 254.441419 3.978452) (xy 254.417952 3.895976) (xy 254.386976 3.816017)
			(xy 254.348754 3.739257) (xy 254.303613 3.666351) (xy 254.251937 3.597922) (xy 254.194168 3.534552)
			(xy 254.130798 3.476783) (xy 254.062369 3.425107) (xy 253.989463 3.379966) (xy 253.912703 3.341744)
			(xy 253.832744 3.310768) (xy 253.750268 3.287301) (xy 253.665978 3.271545) (xy 253.580595 3.263633)
			(xy 253.494845 3.263633) (xy 253.409462 3.271545) (xy 253.325172 3.287301) (xy 253.242696 3.310768)
			(xy 253.162737 3.341744) (xy 253.085977 3.379966) (xy 253.013071 3.425107) (xy 252.944642 3.476783)
			(xy 252.881272 3.534552) (xy 252.823503 3.597922) (xy 252.771827 3.666351) (xy 252.726686 3.739257)
			(xy 252.688464 3.816017) (xy 252.657488 3.895976) (xy 252.634021 3.978452) (xy 252.618265 4.062742)
			(xy 252.610353 4.148125) (xy 248.115087 4.148125) (xy 248.107175 4.062742) (xy 248.091419 3.978452)
			(xy 248.067952 3.895976) (xy 248.036976 3.816017) (xy 247.998754 3.739257) (xy 247.953613 3.666351)
			(xy 247.901937 3.597922) (xy 247.844168 3.534552) (xy 247.780798 3.476783) (xy 247.712369 3.425107)
			(xy 247.639463 3.379966) (xy 247.562703 3.341744) (xy 247.482744 3.310768) (xy 247.400268 3.287301)
			(xy 247.315978 3.271545) (xy 247.230595 3.263633) (xy 247.144845 3.263633) (xy 247.059462 3.271545)
			(xy 246.975172 3.287301) (xy 246.892696 3.310768) (xy 246.812737 3.341744) (xy 246.735977 3.379966)
			(xy 246.663071 3.425107) (xy 246.594642 3.476783) (xy 246.531272 3.534552) (xy 246.473503 3.597922)
			(xy 246.421827 3.666351) (xy 246.376686 3.739257) (xy 246.338464 3.816017) (xy 246.307488 3.895976)
			(xy 246.284021 3.978452) (xy 246.268265 4.062742) (xy 246.260353 4.148125) (xy 186.540407 4.148125)
			(xy 186.532495 4.062742) (xy 186.516739 3.978452) (xy 186.493272 3.895976) (xy 186.462296 3.816017)
			(xy 186.424074 3.739257) (xy 186.378933 3.666351) (xy 186.327257 3.597922) (xy 186.269488 3.534552)
			(xy 186.206118 3.476783) (xy 186.137689 3.425107) (xy 186.064783 3.379966) (xy 185.988023 3.341744)
			(xy 185.908064 3.310768) (xy 185.825588 3.287301) (xy 185.741298 3.271545) (xy 185.655915 3.263633)
			(xy 185.570165 3.263633) (xy 185.484782 3.271545) (xy 185.400492 3.287301) (xy 185.318016 3.310768)
			(xy 185.238057 3.341744) (xy 185.161297 3.379966) (xy 185.088391 3.425107) (xy 185.019962 3.476783)
			(xy 184.956592 3.534552) (xy 184.898823 3.597922) (xy 184.847147 3.666351) (xy 184.802006 3.739257)
			(xy 184.763784 3.816017) (xy 184.732808 3.895976) (xy 184.709341 3.978452) (xy 184.693585 4.062742)
			(xy 184.685673 4.148125) (xy 180.190407 4.148125) (xy 180.182495 4.062742) (xy 180.166739 3.978452)
			(xy 180.143272 3.895976) (xy 180.112296 3.816017) (xy 180.074074 3.739257) (xy 180.028933 3.666351)
			(xy 179.977257 3.597922) (xy 179.919488 3.534552) (xy 179.856118 3.476783) (xy 179.787689 3.425107)
			(xy 179.714783 3.379966) (xy 179.638023 3.341744) (xy 179.558064 3.310768) (xy 179.475588 3.287301)
			(xy 179.391298 3.271545) (xy 179.305915 3.263633) (xy 179.220165 3.263633) (xy 179.134782 3.271545)
			(xy 179.050492 3.287301) (xy 178.968016 3.310768) (xy 178.888057 3.341744) (xy 178.811297 3.379966)
			(xy 178.738391 3.425107) (xy 178.669962 3.476783) (xy 178.606592 3.534552) (xy 178.548823 3.597922)
			(xy 178.497147 3.666351) (xy 178.452006 3.739257) (xy 178.413784 3.816017) (xy 178.382808 3.895976)
			(xy 178.359341 3.978452) (xy 178.343585 4.062742) (xy 178.335673 4.148125) (xy 0.508 4.148125) (xy 0.508 -7.78002)
			(xy 0.508522 -7.835827) (xy 0.516863 -7.947129) (xy 0.533498 -8.057497) (xy 0.558334 -8.166312) (xy 0.591233 -8.272968)
			(xy 0.63201 -8.376867) (xy 0.680438 -8.477428) (xy 0.736245 -8.574088) (xy 0.799119 -8.666308) (xy 0.868709 -8.753572)
			(xy 0.944626 -8.835391) (xy 1.026445 -8.911308) (xy 1.113708 -8.980898) (xy 1.205928 -9.043773) (xy 1.302589 -9.09958)
			(xy 1.40315 -9.148008) (xy 1.507048 -9.188786) (xy 1.613704 -9.221685) (xy 1.722519 -9.246521) (xy 1.832887 -9.263157)
			(xy 1.944189 -9.271498) (xy 1.999996 -9.272016) (xy 9.10209 -9.272016) (xy 9.157898 -9.271495) (xy 9.269201 -9.263154)
			(xy 9.379569 -9.24652) (xy 9.488386 -9.221684) (xy 9.595043 -9.188786) (xy 9.698942 -9.148009) (xy 9.799505 -9.099582)
			(xy 9.896167 -9.043775) (xy 9.988388 -8.980901) (xy 10.075653 -8.911311) (xy 10.157473 -8.835394)
			(xy 10.233392 -8.753575) (xy 10.302983 -8.666312) (xy 10.365859 -8.574092) (xy 10.421668 -8.477431)
			(xy 10.470097 -8.37687) (xy 10.510876 -8.272971) (xy 10.543776 -8.166315) (xy 10.568614 -8.057499)
			(xy 10.585251 -7.94713) (xy 10.593594 -7.835828) (xy 10.594086 -7.78002) (xy 10.594086 0.999998)
			(xy 10.59457 1.070352) (xy 10.60246 1.210839) (xy 10.618214 1.350662) (xy 10.641783 1.489382) (xy 10.673094 1.626562)
			(xy 10.712047 1.761771) (xy 10.758519 1.894583) (xy 10.812366 2.02458) (xy 10.873417 2.151354) (xy 10.94148 2.274505)
			(xy 11.016341 2.393646) (xy 11.097765 2.508402) (xy 11.185495 2.618411) (xy 11.279255 2.723329) (xy 11.378751 2.822825)
			(xy 11.483669 2.916585) (xy 11.593678 3.004315) (xy 11.708434 3.085739) (xy 11.827575 3.1606) (xy 11.950726 3.228663)
			(xy 12.0775 3.289714) (xy 12.207497 3.343561) (xy 12.340309 3.390033) (xy 12.475518 3.428986) (xy 12.612698 3.460297)
			(xy 12.751418 3.483866) (xy 12.891241 3.49962) (xy 13.031728 3.50751) (xy 13.102082 3.507994) (xy 81.701894 3.507994)
			(xy 81.772248 3.50751) (xy 81.912735 3.499621) (xy 82.052558 3.483867) (xy 82.191278 3.460297) (xy 82.328459 3.428987)
			(xy 82.463668 3.390034) (xy 82.59648 3.343562) (xy 82.726477 3.289715) (xy 82.853251 3.228664) (xy 82.976402 3.160601)
			(xy 83.095543 3.08574) (xy 83.2103 3.004317) (xy 83.32031 2.916587) (xy 83.425228 2.822826) (xy 83.524724 2.723331)
			(xy 83.618484 2.618413) (xy 83.706214 2.508403) (xy 83.787638 2.393647) (xy 83.862499 2.274506) (xy 83.930563 2.151355)
			(xy 83.991614 2.024581) (xy 84.04546 1.894584) (xy 84.091933 1.761772) (xy 84.130886 1.626563) (xy 84.135094 1.608125)
			(xy 178.335673 1.608125) (xy 178.335673 1.693875) (xy 178.343585 1.779258) (xy 178.359341 1.863548)
			(xy 178.382808 1.946024) (xy 178.413784 2.025983) (xy 178.452006 2.102743) (xy 178.497147 2.175649)
			(xy 178.548823 2.244078) (xy 178.606592 2.307448) (xy 178.669962 2.365217) (xy 178.738391 2.416893)
			(xy 178.811297 2.462034) (xy 178.888057 2.500256) (xy 178.968016 2.531232) (xy 179.050492 2.554699)
			(xy 179.134782 2.570455) (xy 179.220165 2.578367) (xy 179.305915 2.578367) (xy 179.391298 2.570455)
			(xy 179.475588 2.554699) (xy 179.558064 2.531232) (xy 179.638023 2.500256) (xy 179.660226 2.4892)
			(xy 183.270652 2.4892) (xy 183.270652 3.3528) (xy 183.271138 3.380069) (xy 183.2789 3.434053) (xy 183.294265 3.486383)
			(xy 183.316922 3.535993) (xy 183.346408 3.581874) (xy 183.382123 3.623091) (xy 183.42334 3.658806)
			(xy 183.469221 3.688292) (xy 183.518831 3.710949) (xy 183.571161 3.726314) (xy 183.625145 3.734076)
			(xy 183.679683 3.734076) (xy 183.733667 3.726314) (xy 183.785997 3.710949) (xy 183.835607 3.688292)
			(xy 183.881488 3.658806) (xy 183.922705 3.623091) (xy 183.95842 3.581874) (xy 183.987906 3.535993)
			(xy 184.010563 3.486383) (xy 184.025928 3.434053) (xy 184.03369 3.380069) (xy 184.034176 3.3528)
			(xy 184.034176 2.4892) (xy 184.03369 2.461931) (xy 184.025928 2.407947) (xy 184.010563 2.355617)
			(xy 183.987906 2.306007) (xy 183.95842 2.260126) (xy 183.922705 2.218909) (xy 183.881488 2.183194)
			(xy 183.835607 2.153708) (xy 183.785997 2.131051) (xy 183.733667 2.115686) (xy 183.679683 2.107924)
			(xy 183.625145 2.107924) (xy 183.571161 2.115686) (xy 183.518831 2.131051) (xy 183.469221 2.153708)
			(xy 183.42334 2.183194) (xy 183.382123 2.218909) (xy 183.346408 2.260126) (xy 183.316922 2.306007)
			(xy 183.294265 2.355617) (xy 183.2789 2.407947) (xy 183.271138 2.461931) (xy 183.270652 2.4892) (xy 179.660226 2.4892)
			(xy 179.714783 2.462034) (xy 179.787689 2.416893) (xy 179.856118 2.365217) (xy 179.919488 2.307448)
			(xy 179.977257 2.244078) (xy 180.028933 2.175649) (xy 180.074074 2.102743) (xy 180.112296 2.025983)
			(xy 180.143272 1.946024) (xy 180.166739 1.863548) (xy 180.182495 1.779258) (xy 180.190407 1.693875)
			(xy 180.190902 1.651) (xy 180.190407 1.608125) (xy 184.685673 1.608125) (xy 184.685673 1.693875)
			(xy 184.693585 1.779258) (xy 184.709341 1.863548) (xy 184.732808 1.946024) (xy 184.763784 2.025983)
			(xy 184.802006 2.102743) (xy 184.847147 2.175649) (xy 184.898823 2.244078) (xy 184.956592 2.307448)
			(xy 185.019962 2.365217) (xy 185.088391 2.416893) (xy 185.161297 2.462034) (xy 185.238057 2.500256)
			(xy 185.318016 2.531232) (xy 185.400492 2.554699) (xy 185.484782 2.570455) (xy 185.570165 2.578367)
			(xy 185.655915 2.578367) (xy 185.741298 2.570455) (xy 185.825588 2.554699) (xy 185.908064 2.531232)
			(xy 185.988023 2.500256) (xy 186.064783 2.462034) (xy 186.137689 2.416893) (xy 186.206118 2.365217)
			(xy 186.269488 2.307448) (xy 186.327257 2.244078) (xy 186.378933 2.175649) (xy 186.424074 2.102743)
			(xy 186.462296 2.025983) (xy 186.493272 1.946024) (xy 186.516739 1.863548) (xy 186.532495 1.779258)
			(xy 186.540407 1.693875) (xy 186.540902 1.651) (xy 186.540407 1.608125) (xy 246.260353 1.608125)
			(xy 246.260353 1.693875) (xy 246.268265 1.779258) (xy 246.284021 1.863548) (xy 246.307488 1.946024)
			(xy 246.338464 2.025983) (xy 246.376686 2.102743) (xy 246.421827 2.175649) (xy 246.473503 2.244078)
			(xy 246.531272 2.307448) (xy 246.594642 2.365217) (xy 246.663071 2.416893) (xy 246.735977 2.462034)
			(xy 246.812737 2.500256) (xy 246.892696 2.531232) (xy 246.975172 2.554699) (xy 247.059462 2.570455)
			(xy 247.144845 2.578367) (xy 247.230595 2.578367) (xy 247.315978 2.570455) (xy 247.400268 2.554699)
			(xy 247.482744 2.531232) (xy 247.562703 2.500256) (xy 247.584906 2.4892) (xy 248.766584 2.4892) (xy 248.766584 3.3528)
			(xy 248.76707 3.380069) (xy 248.774832 3.434053) (xy 248.790197 3.486383) (xy 248.812854 3.535993)
			(xy 248.84234 3.581874) (xy 248.878055 3.623091) (xy 248.919272 3.658806) (xy 248.965153 3.688292)
			(xy 249.014763 3.710949) (xy 249.067093 3.726314) (xy 249.121077 3.734076) (xy 249.175615 3.734076)
			(xy 249.229599 3.726314) (xy 249.281929 3.710949) (xy 249.331539 3.688292) (xy 249.37742 3.658806)
			(xy 249.418637 3.623091) (xy 249.454352 3.581874) (xy 249.483838 3.535993) (xy 249.506495 3.486383)
			(xy 249.52186 3.434053) (xy 249.529622 3.380069) (xy 249.530108 3.3528) (xy 249.530108 2.4892) (xy 249.529622 2.461931)
			(xy 249.52186 2.407947) (xy 249.506495 2.355617) (xy 249.483838 2.306007) (xy 249.454352 2.260126)
			(xy 249.418637 2.218909) (xy 249.37742 2.183194) (xy 249.331539 2.153708) (xy 249.281929 2.131051)
			(xy 249.229599 2.115686) (xy 249.175615 2.107924) (xy 249.121077 2.107924) (xy 249.067093 2.115686)
			(xy 249.014763 2.131051) (xy 248.965153 2.153708) (xy 248.919272 2.183194) (xy 248.878055 2.218909)
			(xy 248.84234 2.260126) (xy 248.812854 2.306007) (xy 248.790197 2.355617) (xy 248.774832 2.407947)
			(xy 248.76707 2.461931) (xy 248.766584 2.4892) (xy 247.584906 2.4892) (xy 247.639463 2.462034) (xy 247.712369 2.416893)
			(xy 247.780798 2.365217) (xy 247.844168 2.307448) (xy 247.901937 2.244078) (xy 247.953613 2.175649)
			(xy 247.998754 2.102743) (xy 248.036976 2.025983) (xy 248.067952 1.946024) (xy 248.091419 1.863548)
			(xy 248.107175 1.779258) (xy 248.115087 1.693875) (xy 248.115582 1.651) (xy 248.115087 1.608125)
			(xy 252.610353 1.608125) (xy 252.610353 1.693875) (xy 252.618265 1.779258) (xy 252.634021 1.863548)
			(xy 252.657488 1.946024) (xy 252.688464 2.025983) (xy 252.726686 2.102743) (xy 252.771827 2.175649)
			(xy 252.823503 2.244078) (xy 252.881272 2.307448) (xy 252.944642 2.365217) (xy 253.013071 2.416893)
			(xy 253.085977 2.462034) (xy 253.162737 2.500256) (xy 253.242696 2.531232) (xy 253.325172 2.554699)
			(xy 253.409462 2.570455) (xy 253.494845 2.578367) (xy 253.580595 2.578367) (xy 253.665978 2.570455)
			(xy 253.750268 2.554699) (xy 253.832744 2.531232) (xy 253.912703 2.500256) (xy 253.989463 2.462034)
			(xy 254.062369 2.416893) (xy 254.130798 2.365217) (xy 254.194168 2.307448) (xy 254.251937 2.244078)
			(xy 254.303613 2.175649) (xy 254.348754 2.102743) (xy 254.386976 2.025983) (xy 254.417952 1.946024)
			(xy 254.441419 1.863548) (xy 254.457175 1.779258) (xy 254.465087 1.693875) (xy 254.465582 1.651)
			(xy 254.465119 1.610919) (xy 256.921241 1.610919) (xy 256.921241 1.696669) (xy 256.929153 1.782052)
			(xy 256.944909 1.866342) (xy 256.968376 1.948818) (xy 256.999352 2.028777) (xy 257.037574 2.105537)
			(xy 257.082715 2.178443) (xy 257.134391 2.246872) (xy 257.19216 2.310242) (xy 257.25553 2.368011)
			(xy 257.323959 2.419687) (xy 257.396865 2.464828) (xy 257.473625 2.50305) (xy 257.553584 2.534026)
			(xy 257.63606 2.557493) (xy 257.72035 2.573249) (xy 257.805733 2.581161) (xy 257.891483 2.581161)
			(xy 257.976866 2.573249) (xy 258.061156 2.557493) (xy 258.143632 2.534026) (xy 258.223591 2.50305)
			(xy 258.245794 2.491994) (xy 261.85622 2.491994) (xy 261.85622 3.355594) (xy 261.856706 3.382863)
			(xy 261.864468 3.436847) (xy 261.879833 3.489177) (xy 261.90249 3.538787) (xy 261.931976 3.584668)
			(xy 261.967691 3.625885) (xy 262.008908 3.6616) (xy 262.054789 3.691086) (xy 262.104399 3.713743)
			(xy 262.156729 3.729108) (xy 262.210713 3.73687) (xy 262.265251 3.73687) (xy 262.319235 3.729108)
			(xy 262.371565 3.713743) (xy 262.421175 3.691086) (xy 262.467056 3.6616) (xy 262.508273 3.625885)
			(xy 262.543988 3.584668) (xy 262.573474 3.538787) (xy 262.596131 3.489177) (xy 262.611496 3.436847)
			(xy 262.619258 3.382863) (xy 262.619744 3.355594) (xy 262.619744 2.491994) (xy 262.619258 2.464725)
			(xy 262.611496 2.410741) (xy 262.596131 2.358411) (xy 262.573474 2.308801) (xy 262.543988 2.26292)
			(xy 262.508273 2.221703) (xy 262.467056 2.185988) (xy 262.421175 2.156502) (xy 262.371565 2.133845)
			(xy 262.319235 2.11848) (xy 262.265251 2.110718) (xy 262.210713 2.110718) (xy 262.156729 2.11848)
			(xy 262.104399 2.133845) (xy 262.054789 2.156502) (xy 262.008908 2.185988) (xy 261.967691 2.221703)
			(xy 261.931976 2.26292) (xy 261.90249 2.308801) (xy 261.879833 2.358411) (xy 261.864468 2.410741)
			(xy 261.856706 2.464725) (xy 261.85622 2.491994) (xy 258.245794 2.491994) (xy 258.300351 2.464828)
			(xy 258.373257 2.419687) (xy 258.441686 2.368011) (xy 258.505056 2.310242) (xy 258.562825 2.246872)
			(xy 258.614501 2.178443) (xy 258.659642 2.105537) (xy 258.697864 2.028777) (xy 258.72884 1.948818)
			(xy 258.752307 1.866342) (xy 258.768063 1.782052) (xy 258.775975 1.696669) (xy 258.77647 1.653794)
			(xy 258.775975 1.610919) (xy 263.271241 1.610919) (xy 263.271241 1.696669) (xy 263.279153 1.782052)
			(xy 263.294909 1.866342) (xy 263.318376 1.948818) (xy 263.349352 2.028777) (xy 263.387574 2.105537)
			(xy 263.432715 2.178443) (xy 263.484391 2.246872) (xy 263.54216 2.310242) (xy 263.60553 2.368011)
			(xy 263.673959 2.419687) (xy 263.746865 2.464828) (xy 263.823625 2.50305) (xy 263.903584 2.534026)
			(xy 263.98606 2.557493) (xy 264.07035 2.573249) (xy 264.155733 2.581161) (xy 264.241483 2.581161)
			(xy 264.326866 2.573249) (xy 264.411156 2.557493) (xy 264.493632 2.534026) (xy 264.573591 2.50305)
			(xy 264.650351 2.464828) (xy 264.723257 2.419687) (xy 264.791686 2.368011) (xy 264.855056 2.310242)
			(xy 264.912825 2.246872) (xy 264.964501 2.178443) (xy 265.009642 2.105537) (xy 265.047864 2.028777)
			(xy 265.07884 1.948818) (xy 265.102307 1.866342) (xy 265.118063 1.782052) (xy 265.125975 1.696669)
			(xy 265.12647 1.653794) (xy 265.125975 1.610919) (xy 324.845921 1.610919) (xy 324.845921 1.696669)
			(xy 324.853833 1.782052) (xy 324.869589 1.866342) (xy 324.893056 1.948818) (xy 324.924032 2.028777)
			(xy 324.962254 2.105537) (xy 325.007395 2.178443) (xy 325.059071 2.246872) (xy 325.11684 2.310242)
			(xy 325.18021 2.368011) (xy 325.248639 2.419687) (xy 325.321545 2.464828) (xy 325.398305 2.50305)
			(xy 325.478264 2.534026) (xy 325.56074 2.557493) (xy 325.64503 2.573249) (xy 325.730413 2.581161)
			(xy 325.816163 2.581161) (xy 325.901546 2.573249) (xy 325.985836 2.557493) (xy 326.068312 2.534026)
			(xy 326.148271 2.50305) (xy 326.170474 2.491994) (xy 327.352152 2.491994) (xy 327.352152 3.355594)
			(xy 327.352638 3.382863) (xy 327.3604 3.436847) (xy 327.375765 3.489177) (xy 327.398422 3.538787)
			(xy 327.427908 3.584668) (xy 327.463623 3.625885) (xy 327.50484 3.6616) (xy 327.550721 3.691086)
			(xy 327.600331 3.713743) (xy 327.652661 3.729108) (xy 327.706645 3.73687) (xy 327.761183 3.73687)
			(xy 327.815167 3.729108) (xy 327.867497 3.713743) (xy 327.917107 3.691086) (xy 327.962988 3.6616)
			(xy 328.004205 3.625885) (xy 328.03992 3.584668) (xy 328.069406 3.538787) (xy 328.092063 3.489177)
			(xy 328.107428 3.436847) (xy 328.11519 3.382863) (xy 328.115676 3.355594) (xy 328.115676 2.491994)
			(xy 328.11519 2.464725) (xy 328.107428 2.410741) (xy 328.092063 2.358411) (xy 328.069406 2.308801)
			(xy 328.03992 2.26292) (xy 328.004205 2.221703) (xy 327.962988 2.185988) (xy 327.917107 2.156502)
			(xy 327.867497 2.133845) (xy 327.815167 2.11848) (xy 327.761183 2.110718) (xy 327.706645 2.110718)
			(xy 327.652661 2.11848) (xy 327.600331 2.133845) (xy 327.550721 2.156502) (xy 327.50484 2.185988)
			(xy 327.463623 2.221703) (xy 327.427908 2.26292) (xy 327.398422 2.308801) (xy 327.375765 2.358411)
			(xy 327.3604 2.410741) (xy 327.352638 2.464725) (xy 327.352152 2.491994) (xy 326.170474 2.491994)
			(xy 326.225031 2.464828) (xy 326.297937 2.419687) (xy 326.366366 2.368011) (xy 326.429736 2.310242)
			(xy 326.487505 2.246872) (xy 326.539181 2.178443) (xy 326.584322 2.105537) (xy 326.622544 2.028777)
			(xy 326.65352 1.948818) (xy 326.676987 1.866342) (xy 326.692743 1.782052) (xy 326.700655 1.696669)
			(xy 326.70115 1.653794) (xy 326.700655 1.610919) (xy 331.195921 1.610919) (xy 331.195921 1.696669)
			(xy 331.203833 1.782052) (xy 331.219589 1.866342) (xy 331.243056 1.948818) (xy 331.274032 2.028777)
			(xy 331.312254 2.105537) (xy 331.357395 2.178443) (xy 331.409071 2.246872) (xy 331.46684 2.310242)
			(xy 331.53021 2.368011) (xy 331.598639 2.419687) (xy 331.671545 2.464828) (xy 331.748305 2.50305)
			(xy 331.828264 2.534026) (xy 331.91074 2.557493) (xy 331.99503 2.573249) (xy 332.080413 2.581161)
			(xy 332.166163 2.581161) (xy 332.251546 2.573249) (xy 332.335836 2.557493) (xy 332.418312 2.534026)
			(xy 332.498271 2.50305) (xy 332.575031 2.464828) (xy 332.647937 2.419687) (xy 332.716366 2.368011)
			(xy 332.779736 2.310242) (xy 332.837505 2.246872) (xy 332.889181 2.178443) (xy 332.934322 2.105537)
			(xy 332.972544 2.028777) (xy 333.00352 1.948818) (xy 333.026987 1.866342) (xy 333.042743 1.782052)
			(xy 333.050655 1.696669) (xy 333.05115 1.653794) (xy 333.050655 1.610919) (xy 335.488267 1.610919)
			(xy 335.488267 1.696669) (xy 335.496179 1.782052) (xy 335.511935 1.866342) (xy 335.535402 1.948818)
			(xy 335.566378 2.028777) (xy 335.6046 2.105537) (xy 335.649741 2.178443) (xy 335.701417 2.246872)
			(xy 335.759186 2.310242) (xy 335.822556 2.368011) (xy 335.890985 2.419687) (xy 335.963891 2.464828)
			(xy 336.040651 2.50305) (xy 336.12061 2.534026) (xy 336.203086 2.557493) (xy 336.287376 2.573249)
			(xy 336.372759 2.581161) (xy 336.458509 2.581161) (xy 336.543892 2.573249) (xy 336.628182 2.557493)
			(xy 336.710658 2.534026) (xy 336.790617 2.50305) (xy 336.81282 2.491994) (xy 340.4235 2.491994) (xy 340.4235 3.355594)
			(xy 340.423986 3.382845) (xy 340.431742 3.436793) (xy 340.447097 3.489088) (xy 340.469739 3.538665)
			(xy 340.499205 3.584515) (xy 340.534896 3.625706) (xy 340.576087 3.661397) (xy 340.621937 3.690863)
			(xy 340.671514 3.713505) (xy 340.723809 3.72886) (xy 340.777757 3.736616) (xy 340.832259 3.736616)
			(xy 340.886207 3.72886) (xy 340.938502 3.713505) (xy 340.988079 3.690863) (xy 341.033929 3.661397)
			(xy 341.07512 3.625706) (xy 341.110811 3.584515) (xy 341.140277 3.538665) (xy 341.162919 3.489088)
			(xy 341.178274 3.436793) (xy 341.18603 3.382845) (xy 341.186516 3.355594) (xy 341.186516 2.491994)
			(xy 341.18603 2.464743) (xy 341.178274 2.410795) (xy 341.162919 2.3585) (xy 341.140277 2.308923)
			(xy 341.110811 2.263073) (xy 341.07512 2.221882) (xy 341.033929 2.186191) (xy 340.988079 2.156725)
			(xy 340.938502 2.134083) (xy 340.886207 2.118728) (xy 340.832259 2.110972) (xy 340.777757 2.110972)
			(xy 340.723809 2.118728) (xy 340.671514 2.134083) (xy 340.621937 2.156725) (xy 340.576087 2.186191)
			(xy 340.534896 2.221882) (xy 340.499205 2.263073) (xy 340.469739 2.308923) (xy 340.447097 2.3585)
			(xy 340.431742 2.410795) (xy 340.423986 2.464743) (xy 340.4235 2.491994) (xy 336.81282 2.491994)
			(xy 336.867377 2.464828) (xy 336.940283 2.419687) (xy 337.008712 2.368011) (xy 337.072082 2.310242)
			(xy 337.129851 2.246872) (xy 337.181527 2.178443) (xy 337.226668 2.105537) (xy 337.26489 2.028777)
			(xy 337.295866 1.948818) (xy 337.319333 1.866342) (xy 337.335089 1.782052) (xy 337.343001 1.696669)
			(xy 337.343496 1.653794) (xy 337.343001 1.610919) (xy 341.838267 1.610919) (xy 341.838267 1.696669)
			(xy 341.846179 1.782052) (xy 341.861935 1.866342) (xy 341.885402 1.948818) (xy 341.916378 2.028777)
			(xy 341.9546 2.105537) (xy 341.999741 2.178443) (xy 342.051417 2.246872) (xy 342.109186 2.310242)
			(xy 342.172556 2.368011) (xy 342.240985 2.419687) (xy 342.313891 2.464828) (xy 342.390651 2.50305)
			(xy 342.47061 2.534026) (xy 342.553086 2.557493) (xy 342.637376 2.573249) (xy 342.722759 2.581161)
			(xy 342.808509 2.581161) (xy 342.893892 2.573249) (xy 342.978182 2.557493) (xy 343.060658 2.534026)
			(xy 343.140617 2.50305) (xy 343.217377 2.464828) (xy 343.290283 2.419687) (xy 343.358712 2.368011)
			(xy 343.422082 2.310242) (xy 343.479851 2.246872) (xy 343.531527 2.178443) (xy 343.576668 2.105537)
			(xy 343.61489 2.028777) (xy 343.645866 1.948818) (xy 343.669333 1.866342) (xy 343.685089 1.782052)
			(xy 343.693001 1.696669) (xy 343.693496 1.653794) (xy 343.693001 1.610919) (xy 373.705107 1.610919)
			(xy 373.705107 1.696669) (xy 373.713019 1.782052) (xy 373.728775 1.866342) (xy 373.752242 1.948818)
			(xy 373.783218 2.028777) (xy 373.82144 2.105537) (xy 373.866581 2.178443) (xy 373.918257 2.246872)
			(xy 373.976026 2.310242) (xy 374.039396 2.368011) (xy 374.107825 2.419687) (xy 374.180731 2.464828)
			(xy 374.257491 2.50305) (xy 374.33745 2.534026) (xy 374.419926 2.557493) (xy 374.504216 2.573249)
			(xy 374.589599 2.581161) (xy 374.675349 2.581161) (xy 374.760732 2.573249) (xy 374.845022 2.557493)
			(xy 374.927498 2.534026) (xy 375.007457 2.50305) (xy 375.02966 2.491994) (xy 376.211592 2.491994)
			(xy 376.211592 3.355594) (xy 376.212078 3.382845) (xy 376.219834 3.436793) (xy 376.235189 3.489088)
			(xy 376.257831 3.538665) (xy 376.287297 3.584515) (xy 376.322988 3.625706) (xy 376.364179 3.661397)
			(xy 376.410029 3.690863) (xy 376.459606 3.713505) (xy 376.511901 3.72886) (xy 376.565849 3.736616)
			(xy 376.620351 3.736616) (xy 376.674299 3.72886) (xy 376.726594 3.713505) (xy 376.776171 3.690863)
			(xy 376.822021 3.661397) (xy 376.863212 3.625706) (xy 376.898903 3.584515) (xy 376.928369 3.538665)
			(xy 376.951011 3.489088) (xy 376.966366 3.436793) (xy 376.974122 3.382845) (xy 376.974608 3.355594)
			(xy 376.974608 2.491994) (xy 376.974122 2.464743) (xy 376.966366 2.410795) (xy 376.951011 2.3585)
			(xy 376.928369 2.308923) (xy 376.898903 2.263073) (xy 376.863212 2.221882) (xy 376.822021 2.186191)
			(xy 376.776171 2.156725) (xy 376.726594 2.134083) (xy 376.674299 2.118728) (xy 376.620351 2.110972)
			(xy 376.565849 2.110972) (xy 376.511901 2.118728) (xy 376.459606 2.134083) (xy 376.410029 2.156725)
			(xy 376.364179 2.186191) (xy 376.322988 2.221882) (xy 376.287297 2.263073) (xy 376.257831 2.308923)
			(xy 376.235189 2.3585) (xy 376.219834 2.410795) (xy 376.212078 2.464743) (xy 376.211592 2.491994)
			(xy 375.02966 2.491994) (xy 375.084217 2.464828) (xy 375.157123 2.419687) (xy 375.225552 2.368011)
			(xy 375.288922 2.310242) (xy 375.346691 2.246872) (xy 375.398367 2.178443) (xy 375.443508 2.105537)
			(xy 375.48173 2.028777) (xy 375.512706 1.948818) (xy 375.536173 1.866342) (xy 375.551929 1.782052)
			(xy 375.559841 1.696669) (xy 375.560336 1.653794) (xy 375.559841 1.610919) (xy 380.055107 1.610919)
			(xy 380.055107 1.696669) (xy 380.063019 1.782052) (xy 380.078775 1.866342) (xy 380.102242 1.948818)
			(xy 380.133218 2.028777) (xy 380.17144 2.105537) (xy 380.216581 2.178443) (xy 380.268257 2.246872)
			(xy 380.326026 2.310242) (xy 380.389396 2.368011) (xy 380.457825 2.419687) (xy 380.530731 2.464828)
			(xy 380.607491 2.50305) (xy 380.68745 2.534026) (xy 380.769926 2.557493) (xy 380.854216 2.573249)
			(xy 380.939599 2.581161) (xy 381.025349 2.581161) (xy 381.110732 2.573249) (xy 381.195022 2.557493)
			(xy 381.277498 2.534026) (xy 381.357457 2.50305) (xy 381.434217 2.464828) (xy 381.507123 2.419687)
			(xy 381.575552 2.368011) (xy 381.638922 2.310242) (xy 381.696691 2.246872) (xy 381.748367 2.178443)
			(xy 381.793508 2.105537) (xy 381.83173 2.028777) (xy 381.862706 1.948818) (xy 381.886173 1.866342)
			(xy 381.901929 1.782052) (xy 381.909841 1.696669) (xy 381.910336 1.653794) (xy 381.909841 1.610919)
			(xy 381.901929 1.525536) (xy 381.886173 1.441246) (xy 381.862706 1.35877) (xy 381.83173 1.278811)
			(xy 381.793508 1.202051) (xy 381.748367 1.129145) (xy 381.696691 1.060716) (xy 381.638922 0.997346)
			(xy 381.575552 0.939577) (xy 381.507123 0.887901) (xy 381.434217 0.84276) (xy 381.357457 0.804538)
			(xy 381.277498 0.773562) (xy 381.195022 0.750095) (xy 381.110732 0.734339) (xy 381.025349 0.726427)
			(xy 380.939599 0.726427) (xy 380.854216 0.734339) (xy 380.769926 0.750095) (xy 380.68745 0.773562)
			(xy 380.607491 0.804538) (xy 380.530731 0.84276) (xy 380.457825 0.887901) (xy 380.389396 0.939577)
			(xy 380.326026 0.997346) (xy 380.268257 1.060716) (xy 380.216581 1.129145) (xy 380.17144 1.202051)
			(xy 380.133218 1.278811) (xy 380.102242 1.35877) (xy 380.078775 1.441246) (xy 380.063019 1.525536)
			(xy 380.055107 1.610919) (xy 375.559841 1.610919) (xy 375.551929 1.525536) (xy 375.536173 1.441246)
			(xy 375.512706 1.35877) (xy 375.48173 1.278811) (xy 375.443508 1.202051) (xy 375.398367 1.129145)
			(xy 375.346691 1.060716) (xy 375.288922 0.997346) (xy 375.225552 0.939577) (xy 375.157123 0.887901)
			(xy 375.084217 0.84276) (xy 375.007457 0.804538) (xy 374.927498 0.773562) (xy 374.845022 0.750095)
			(xy 374.760732 0.734339) (xy 374.675349 0.726427) (xy 374.589599 0.726427) (xy 374.504216 0.734339)
			(xy 374.419926 0.750095) (xy 374.33745 0.773562) (xy 374.257491 0.804538) (xy 374.180731 0.84276)
			(xy 374.107825 0.887901) (xy 374.039396 0.939577) (xy 373.976026 0.997346) (xy 373.918257 1.060716)
			(xy 373.866581 1.129145) (xy 373.82144 1.202051) (xy 373.783218 1.278811) (xy 373.752242 1.35877)
			(xy 373.728775 1.441246) (xy 373.713019 1.525536) (xy 373.705107 1.610919) (xy 343.693001 1.610919)
			(xy 343.685089 1.525536) (xy 343.669333 1.441246) (xy 343.645866 1.35877) (xy 343.61489 1.278811)
			(xy 343.576668 1.202051) (xy 343.531527 1.129145) (xy 343.479851 1.060716) (xy 343.422082 0.997346)
			(xy 343.358712 0.939577) (xy 343.290283 0.887901) (xy 343.217377 0.84276) (xy 343.140617 0.804538)
			(xy 343.060658 0.773562) (xy 342.978182 0.750095) (xy 342.893892 0.734339) (xy 342.808509 0.726427)
			(xy 342.722759 0.726427) (xy 342.637376 0.734339) (xy 342.553086 0.750095) (xy 342.47061 0.773562)
			(xy 342.390651 0.804538) (xy 342.313891 0.84276) (xy 342.240985 0.887901) (xy 342.172556 0.939577)
			(xy 342.109186 0.997346) (xy 342.051417 1.060716) (xy 341.999741 1.129145) (xy 341.9546 1.202051)
			(xy 341.916378 1.278811) (xy 341.885402 1.35877) (xy 341.861935 1.441246) (xy 341.846179 1.525536)
			(xy 341.838267 1.610919) (xy 337.343001 1.610919) (xy 337.335089 1.525536) (xy 337.319333 1.441246)
			(xy 337.295866 1.35877) (xy 337.26489 1.278811) (xy 337.226668 1.202051) (xy 337.181527 1.129145)
			(xy 337.129851 1.060716) (xy 337.072082 0.997346) (xy 337.008712 0.939577) (xy 336.940283 0.887901)
			(xy 336.867377 0.84276) (xy 336.790617 0.804538) (xy 336.710658 0.773562) (xy 336.628182 0.750095)
			(xy 336.543892 0.734339) (xy 336.458509 0.726427) (xy 336.372759 0.726427) (xy 336.287376 0.734339)
			(xy 336.203086 0.750095) (xy 336.12061 0.773562) (xy 336.040651 0.804538) (xy 335.963891 0.84276)
			(xy 335.890985 0.887901) (xy 335.822556 0.939577) (xy 335.759186 0.997346) (xy 335.701417 1.060716)
			(xy 335.649741 1.129145) (xy 335.6046 1.202051) (xy 335.566378 1.278811) (xy 335.535402 1.35877)
			(xy 335.511935 1.441246) (xy 335.496179 1.525536) (xy 335.488267 1.610919) (xy 333.050655 1.610919)
			(xy 333.042743 1.525536) (xy 333.026987 1.441246) (xy 333.00352 1.35877) (xy 332.972544 1.278811)
			(xy 332.934322 1.202051) (xy 332.889181 1.129145) (xy 332.837505 1.060716) (xy 332.779736 0.997346)
			(xy 332.716366 0.939577) (xy 332.647937 0.887901) (xy 332.575031 0.84276) (xy 332.498271 0.804538)
			(xy 332.418312 0.773562) (xy 332.335836 0.750095) (xy 332.251546 0.734339) (xy 332.166163 0.726427)
			(xy 332.080413 0.726427) (xy 331.99503 0.734339) (xy 331.91074 0.750095) (xy 331.828264 0.773562)
			(xy 331.748305 0.804538) (xy 331.671545 0.84276) (xy 331.598639 0.887901) (xy 331.53021 0.939577)
			(xy 331.46684 0.997346) (xy 331.409071 1.060716) (xy 331.357395 1.129145) (xy 331.312254 1.202051)
			(xy 331.274032 1.278811) (xy 331.243056 1.35877) (xy 331.219589 1.441246) (xy 331.203833 1.525536)
			(xy 331.195921 1.610919) (xy 326.700655 1.610919) (xy 326.692743 1.525536) (xy 326.676987 1.441246)
			(xy 326.65352 1.35877) (xy 326.622544 1.278811) (xy 326.584322 1.202051) (xy 326.539181 1.129145)
			(xy 326.487505 1.060716) (xy 326.429736 0.997346) (xy 326.366366 0.939577) (xy 326.297937 0.887901)
			(xy 326.225031 0.84276) (xy 326.148271 0.804538) (xy 326.068312 0.773562) (xy 325.985836 0.750095)
			(xy 325.901546 0.734339) (xy 325.816163 0.726427) (xy 325.730413 0.726427) (xy 325.64503 0.734339)
			(xy 325.56074 0.750095) (xy 325.478264 0.773562) (xy 325.398305 0.804538) (xy 325.321545 0.84276)
			(xy 325.248639 0.887901) (xy 325.18021 0.939577) (xy 325.11684 0.997346) (xy 325.059071 1.060716)
			(xy 325.007395 1.129145) (xy 324.962254 1.202051) (xy 324.924032 1.278811) (xy 324.893056 1.35877)
			(xy 324.869589 1.441246) (xy 324.853833 1.525536) (xy 324.845921 1.610919) (xy 265.125975 1.610919)
			(xy 265.118063 1.525536) (xy 265.102307 1.441246) (xy 265.07884 1.35877) (xy 265.047864 1.278811)
			(xy 265.009642 1.202051) (xy 264.964501 1.129145) (xy 264.912825 1.060716) (xy 264.855056 0.997346)
			(xy 264.791686 0.939577) (xy 264.723257 0.887901) (xy 264.650351 0.84276) (xy 264.573591 0.804538)
			(xy 264.493632 0.773562) (xy 264.411156 0.750095) (xy 264.326866 0.734339) (xy 264.241483 0.726427)
			(xy 264.155733 0.726427) (xy 264.07035 0.734339) (xy 263.98606 0.750095) (xy 263.903584 0.773562)
			(xy 263.823625 0.804538) (xy 263.746865 0.84276) (xy 263.673959 0.887901) (xy 263.60553 0.939577)
			(xy 263.54216 0.997346) (xy 263.484391 1.060716) (xy 263.432715 1.129145) (xy 263.387574 1.202051)
			(xy 263.349352 1.278811) (xy 263.318376 1.35877) (xy 263.294909 1.441246) (xy 263.279153 1.525536)
			(xy 263.271241 1.610919) (xy 258.775975 1.610919) (xy 258.768063 1.525536) (xy 258.752307 1.441246)
			(xy 258.72884 1.35877) (xy 258.697864 1.278811) (xy 258.659642 1.202051) (xy 258.614501 1.129145)
			(xy 258.562825 1.060716) (xy 258.505056 0.997346) (xy 258.441686 0.939577) (xy 258.373257 0.887901)
			(xy 258.300351 0.84276) (xy 258.223591 0.804538) (xy 258.143632 0.773562) (xy 258.061156 0.750095)
			(xy 257.976866 0.734339) (xy 257.891483 0.726427) (xy 257.805733 0.726427) (xy 257.72035 0.734339)
			(xy 257.63606 0.750095) (xy 257.553584 0.773562) (xy 257.473625 0.804538) (xy 257.396865 0.84276)
			(xy 257.323959 0.887901) (xy 257.25553 0.939577) (xy 257.19216 0.997346) (xy 257.134391 1.060716)
			(xy 257.082715 1.129145) (xy 257.037574 1.202051) (xy 256.999352 1.278811) (xy 256.968376 1.35877)
			(xy 256.944909 1.441246) (xy 256.929153 1.525536) (xy 256.921241 1.610919) (xy 254.465119 1.610919)
			(xy 254.465087 1.608125) (xy 254.457175 1.522742) (xy 254.441419 1.438452) (xy 254.417952 1.355976)
			(xy 254.386976 1.276017) (xy 254.348754 1.199257) (xy 254.303613 1.126351) (xy 254.251937 1.057922)
			(xy 254.194168 0.994552) (xy 254.130798 0.936783) (xy 254.062369 0.885107) (xy 253.989463 0.839966)
			(xy 253.912703 0.801744) (xy 253.832744 0.770768) (xy 253.750268 0.747301) (xy 253.665978 0.731545)
			(xy 253.580595 0.723633) (xy 253.494845 0.723633) (xy 253.409462 0.731545) (xy 253.325172 0.747301)
			(xy 253.242696 0.770768) (xy 253.162737 0.801744) (xy 253.085977 0.839966) (xy 253.013071 0.885107)
			(xy 252.944642 0.936783) (xy 252.881272 0.994552) (xy 252.823503 1.057922) (xy 252.771827 1.126351)
			(xy 252.726686 1.199257) (xy 252.688464 1.276017) (xy 252.657488 1.355976) (xy 252.634021 1.438452)
			(xy 252.618265 1.522742) (xy 252.610353 1.608125) (xy 248.115087 1.608125) (xy 248.107175 1.522742)
			(xy 248.091419 1.438452) (xy 248.067952 1.355976) (xy 248.036976 1.276017) (xy 247.998754 1.199257)
			(xy 247.953613 1.126351) (xy 247.901937 1.057922) (xy 247.844168 0.994552) (xy 247.780798 0.936783)
			(xy 247.712369 0.885107) (xy 247.639463 0.839966) (xy 247.562703 0.801744) (xy 247.482744 0.770768)
			(xy 247.400268 0.747301) (xy 247.315978 0.731545) (xy 247.230595 0.723633) (xy 247.144845 0.723633)
			(xy 247.059462 0.731545) (xy 246.975172 0.747301) (xy 246.892696 0.770768) (xy 246.812737 0.801744)
			(xy 246.735977 0.839966) (xy 246.663071 0.885107) (xy 246.594642 0.936783) (xy 246.531272 0.994552)
			(xy 246.473503 1.057922) (xy 246.421827 1.126351) (xy 246.376686 1.199257) (xy 246.338464 1.276017)
			(xy 246.307488 1.355976) (xy 246.284021 1.438452) (xy 246.268265 1.522742) (xy 246.260353 1.608125)
			(xy 186.540407 1.608125) (xy 186.532495 1.522742) (xy 186.516739 1.438452) (xy 186.493272 1.355976)
			(xy 186.462296 1.276017) (xy 186.424074 1.199257) (xy 186.378933 1.126351) (xy 186.327257 1.057922)
			(xy 186.269488 0.994552) (xy 186.206118 0.936783) (xy 186.137689 0.885107) (xy 186.064783 0.839966)
			(xy 185.988023 0.801744) (xy 185.908064 0.770768) (xy 185.825588 0.747301) (xy 185.741298 0.731545)
			(xy 185.655915 0.723633) (xy 185.570165 0.723633) (xy 185.484782 0.731545) (xy 185.400492 0.747301)
			(xy 185.318016 0.770768) (xy 185.238057 0.801744) (xy 185.161297 0.839966) (xy 185.088391 0.885107)
			(xy 185.019962 0.936783) (xy 184.956592 0.994552) (xy 184.898823 1.057922) (xy 184.847147 1.126351)
			(xy 184.802006 1.199257) (xy 184.763784 1.276017) (xy 184.732808 1.355976) (xy 184.709341 1.438452)
			(xy 184.693585 1.522742) (xy 184.685673 1.608125) (xy 180.190407 1.608125) (xy 180.182495 1.522742)
			(xy 180.166739 1.438452) (xy 180.143272 1.355976) (xy 180.112296 1.276017) (xy 180.074074 1.199257)
			(xy 180.028933 1.126351) (xy 179.977257 1.057922) (xy 179.919488 0.994552) (xy 179.856118 0.936783)
			(xy 179.787689 0.885107) (xy 179.714783 0.839966) (xy 179.638023 0.801744) (xy 179.558064 0.770768)
			(xy 179.475588 0.747301) (xy 179.391298 0.731545) (xy 179.305915 0.723633) (xy 179.220165 0.723633)
			(xy 179.134782 0.731545) (xy 179.050492 0.747301) (xy 178.968016 0.770768) (xy 178.888057 0.801744)
			(xy 178.811297 0.839966) (xy 178.738391 0.885107) (xy 178.669962 0.936783) (xy 178.606592 0.994552)
			(xy 178.548823 1.057922) (xy 178.497147 1.126351) (xy 178.452006 1.199257) (xy 178.413784 1.276017)
			(xy 178.382808 1.355976) (xy 178.359341 1.438452) (xy 178.343585 1.522742) (xy 178.335673 1.608125)
			(xy 84.135094 1.608125) (xy 84.162197 1.489382) (xy 84.185766 1.350662) (xy 84.20152 1.210839) (xy 84.20941 1.070352)
			(xy 84.20989 0.999998) (xy 84.20989 -0.931875) (xy 208.043513 -0.931875) (xy 208.043513 -0.846125)
			(xy 208.051425 -0.760742) (xy 208.067181 -0.676452) (xy 208.090648 -0.593976) (xy 208.121624 -0.514017)
			(xy 208.159846 -0.437257) (xy 208.204987 -0.364351) (xy 208.256663 -0.295922) (xy 208.314432 -0.232552)
			(xy 208.377802 -0.174783) (xy 208.446231 -0.123107) (xy 208.519137 -0.077966) (xy 208.595897 -0.039744)
			(xy 208.675856 -0.008768) (xy 208.758332 0.014699) (xy 208.842622 0.030455) (xy 208.928005 0.038367)
			(xy 209.013755 0.038367) (xy 209.099138 0.030455) (xy 209.183428 0.014699) (xy 209.265904 -0.008768)
			(xy 209.345863 -0.039744) (xy 209.422623 -0.077966) (xy 209.495529 -0.123107) (xy 209.563958 -0.174783)
			(xy 209.627328 -0.232552) (xy 209.685097 -0.295922) (xy 209.736773 -0.364351) (xy 209.781914 -0.437257)
			(xy 209.820136 -0.514017) (xy 209.851112 -0.593976) (xy 209.874579 -0.676452) (xy 209.890335 -0.760742)
			(xy 209.898247 -0.846125) (xy 209.898742 -0.889) (xy 209.898247 -0.931875) (xy 214.393513 -0.931875)
			(xy 214.393513 -0.846125) (xy 214.401425 -0.760742) (xy 214.417181 -0.676452) (xy 214.440648 -0.593976)
			(xy 214.471624 -0.514017) (xy 214.509846 -0.437257) (xy 214.554987 -0.364351) (xy 214.606663 -0.295922)
			(xy 214.664432 -0.232552) (xy 214.727802 -0.174783) (xy 214.796231 -0.123107) (xy 214.869137 -0.077966)
			(xy 214.945897 -0.039744) (xy 215.025856 -0.008768) (xy 215.108332 0.014699) (xy 215.192622 0.030455)
			(xy 215.278005 0.038367) (xy 215.363755 0.038367) (xy 215.449138 0.030455) (xy 215.533428 0.014699)
			(xy 215.615904 -0.008768) (xy 215.695863 -0.039744) (xy 215.772623 -0.077966) (xy 215.845529 -0.123107)
			(xy 215.913958 -0.174783) (xy 215.977328 -0.232552) (xy 216.035097 -0.295922) (xy 216.086773 -0.364351)
			(xy 216.131914 -0.437257) (xy 216.170136 -0.514017) (xy 216.201112 -0.593976) (xy 216.224579 -0.676452)
			(xy 216.240335 -0.760742) (xy 216.248247 -0.846125) (xy 216.248742 -0.889) (xy 216.248247 -0.931875)
			(xy 246.260353 -0.931875) (xy 246.260353 -0.846125) (xy 246.268265 -0.760742) (xy 246.284021 -0.676452)
			(xy 246.307488 -0.593976) (xy 246.338464 -0.514017) (xy 246.376686 -0.437257) (xy 246.421827 -0.364351)
			(xy 246.473503 -0.295922) (xy 246.531272 -0.232552) (xy 246.594642 -0.174783) (xy 246.663071 -0.123107)
			(xy 246.735977 -0.077966) (xy 246.812737 -0.039744) (xy 246.892696 -0.008768) (xy 246.975172 0.014699)
			(xy 247.059462 0.030455) (xy 247.144845 0.038367) (xy 247.230595 0.038367) (xy 247.315978 0.030455)
			(xy 247.400268 0.014699) (xy 247.482744 -0.008768) (xy 247.562703 -0.039744) (xy 247.639463 -0.077966)
			(xy 247.712369 -0.123107) (xy 247.780798 -0.174783) (xy 247.844168 -0.232552) (xy 247.901937 -0.295922)
			(xy 247.953613 -0.364351) (xy 247.998754 -0.437257) (xy 248.036976 -0.514017) (xy 248.067952 -0.593976)
			(xy 248.091419 -0.676452) (xy 248.107175 -0.760742) (xy 248.115087 -0.846125) (xy 248.115582 -0.889)
			(xy 248.115087 -0.931875) (xy 252.610353 -0.931875) (xy 252.610353 -0.846125) (xy 252.618265 -0.760742)
			(xy 252.634021 -0.676452) (xy 252.657488 -0.593976) (xy 252.688464 -0.514017) (xy 252.726686 -0.437257)
			(xy 252.771827 -0.364351) (xy 252.823503 -0.295922) (xy 252.881272 -0.232552) (xy 252.944642 -0.174783)
			(xy 253.013071 -0.123107) (xy 253.085977 -0.077966) (xy 253.162737 -0.039744) (xy 253.242696 -0.008768)
			(xy 253.325172 0.014699) (xy 253.409462 0.030455) (xy 253.494845 0.038367) (xy 253.580595 0.038367)
			(xy 253.665978 0.030455) (xy 253.750268 0.014699) (xy 253.832744 -0.008768) (xy 253.912703 -0.039744)
			(xy 253.989463 -0.077966) (xy 254.062369 -0.123107) (xy 254.130798 -0.174783) (xy 254.194168 -0.232552)
			(xy 254.251937 -0.295922) (xy 254.303613 -0.364351) (xy 254.348754 -0.437257) (xy 254.386976 -0.514017)
			(xy 254.417952 -0.593976) (xy 254.441419 -0.676452) (xy 254.457175 -0.760742) (xy 254.465087 -0.846125)
			(xy 254.465582 -0.889) (xy 254.465119 -0.929081) (xy 256.921241 -0.929081) (xy 256.921241 -0.843331)
			(xy 256.929153 -0.757948) (xy 256.944909 -0.673658) (xy 256.968376 -0.591182) (xy 256.999352 -0.511223)
			(xy 257.037574 -0.434463) (xy 257.082715 -0.361557) (xy 257.134391 -0.293128) (xy 257.19216 -0.229758)
			(xy 257.25553 -0.171989) (xy 257.323959 -0.120313) (xy 257.396865 -0.075172) (xy 257.473625 -0.03695)
			(xy 257.553584 -0.005974) (xy 257.63606 0.017493) (xy 257.72035 0.033249) (xy 257.805733 0.041161)
			(xy 257.891483 0.041161) (xy 257.976866 0.033249) (xy 258.061156 0.017493) (xy 258.143632 -0.005974)
			(xy 258.223591 -0.03695) (xy 258.245794 -0.048006) (xy 261.85622 -0.048006) (xy 261.85622 0.815594)
			(xy 261.856706 0.842863) (xy 261.864468 0.896847) (xy 261.879833 0.949177) (xy 261.90249 0.998787)
			(xy 261.931976 1.044668) (xy 261.967691 1.085885) (xy 262.008908 1.1216) (xy 262.054789 1.151086)
			(xy 262.104399 1.173743) (xy 262.156729 1.189108) (xy 262.210713 1.19687) (xy 262.265251 1.19687)
			(xy 262.319235 1.189108) (xy 262.371565 1.173743) (xy 262.421175 1.151086) (xy 262.467056 1.1216)
			(xy 262.508273 1.085885) (xy 262.543988 1.044668) (xy 262.573474 0.998787) (xy 262.596131 0.949177)
			(xy 262.611496 0.896847) (xy 262.619258 0.842863) (xy 262.619744 0.815594) (xy 262.619744 -0.048006)
			(xy 262.619258 -0.075275) (xy 262.611496 -0.129259) (xy 262.596131 -0.181589) (xy 262.573474 -0.231199)
			(xy 262.543988 -0.27708) (xy 262.508273 -0.318297) (xy 262.467056 -0.354012) (xy 262.421175 -0.383498)
			(xy 262.371565 -0.406155) (xy 262.319235 -0.42152) (xy 262.265251 -0.429282) (xy 262.210713 -0.429282)
			(xy 262.156729 -0.42152) (xy 262.104399 -0.406155) (xy 262.054789 -0.383498) (xy 262.008908 -0.354012)
			(xy 261.967691 -0.318297) (xy 261.931976 -0.27708) (xy 261.90249 -0.231199) (xy 261.879833 -0.181589)
			(xy 261.864468 -0.129259) (xy 261.856706 -0.075275) (xy 261.85622 -0.048006) (xy 258.245794 -0.048006)
			(xy 258.300351 -0.075172) (xy 258.373257 -0.120313) (xy 258.441686 -0.171989) (xy 258.505056 -0.229758)
			(xy 258.562825 -0.293128) (xy 258.614501 -0.361557) (xy 258.659642 -0.434463) (xy 258.697864 -0.511223)
			(xy 258.72884 -0.591182) (xy 258.752307 -0.673658) (xy 258.768063 -0.757948) (xy 258.775975 -0.843331)
			(xy 258.77647 -0.886206) (xy 258.775975 -0.929081) (xy 263.271241 -0.929081) (xy 263.271241 -0.843331)
			(xy 263.279153 -0.757948) (xy 263.294909 -0.673658) (xy 263.318376 -0.591182) (xy 263.349352 -0.511223)
			(xy 263.387574 -0.434463) (xy 263.432715 -0.361557) (xy 263.484391 -0.293128) (xy 263.54216 -0.229758)
			(xy 263.60553 -0.171989) (xy 263.673959 -0.120313) (xy 263.746865 -0.075172) (xy 263.823625 -0.03695)
			(xy 263.903584 -0.005974) (xy 263.98606 0.017493) (xy 264.07035 0.033249) (xy 264.155733 0.041161)
			(xy 264.241483 0.041161) (xy 264.326866 0.033249) (xy 264.411156 0.017493) (xy 264.493632 -0.005974)
			(xy 264.573591 -0.03695) (xy 264.650351 -0.075172) (xy 264.723257 -0.120313) (xy 264.791686 -0.171989)
			(xy 264.855056 -0.229758) (xy 264.912825 -0.293128) (xy 264.964501 -0.361557) (xy 265.009642 -0.434463)
			(xy 265.047864 -0.511223) (xy 265.07884 -0.591182) (xy 265.102307 -0.673658) (xy 265.118063 -0.757948)
			(xy 265.125975 -0.843331) (xy 265.12647 -0.886206) (xy 265.125975 -0.929081) (xy 324.845921 -0.929081)
			(xy 324.845921 -0.843331) (xy 324.853833 -0.757948) (xy 324.869589 -0.673658) (xy 324.893056 -0.591182)
			(xy 324.924032 -0.511223) (xy 324.962254 -0.434463) (xy 325.007395 -0.361557) (xy 325.059071 -0.293128)
			(xy 325.11684 -0.229758) (xy 325.18021 -0.171989) (xy 325.248639 -0.120313) (xy 325.321545 -0.075172)
			(xy 325.398305 -0.03695) (xy 325.478264 -0.005974) (xy 325.56074 0.017493) (xy 325.64503 0.033249)
			(xy 325.730413 0.041161) (xy 325.816163 0.041161) (xy 325.901546 0.033249) (xy 325.985836 0.017493)
			(xy 326.068312 -0.005974) (xy 326.148271 -0.03695) (xy 326.170474 -0.048006) (xy 327.352152 -0.048006)
			(xy 327.352152 0.815594) (xy 327.352638 0.842863) (xy 327.3604 0.896847) (xy 327.375765 0.949177)
			(xy 327.398422 0.998787) (xy 327.427908 1.044668) (xy 327.463623 1.085885) (xy 327.50484 1.1216)
			(xy 327.550721 1.151086) (xy 327.600331 1.173743) (xy 327.652661 1.189108) (xy 327.706645 1.19687)
			(xy 327.761183 1.19687) (xy 327.815167 1.189108) (xy 327.867497 1.173743) (xy 327.917107 1.151086)
			(xy 327.962988 1.1216) (xy 328.004205 1.085885) (xy 328.03992 1.044668) (xy 328.069406 0.998787)
			(xy 328.092063 0.949177) (xy 328.107428 0.896847) (xy 328.11519 0.842863) (xy 328.115676 0.815594)
			(xy 328.115676 -0.048006) (xy 328.11519 -0.075275) (xy 328.107428 -0.129259) (xy 328.092063 -0.181589)
			(xy 328.069406 -0.231199) (xy 328.03992 -0.27708) (xy 328.004205 -0.318297) (xy 327.962988 -0.354012)
			(xy 327.917107 -0.383498) (xy 327.867497 -0.406155) (xy 327.815167 -0.42152) (xy 327.761183 -0.429282)
			(xy 327.706645 -0.429282) (xy 327.652661 -0.42152) (xy 327.600331 -0.406155) (xy 327.550721 -0.383498)
			(xy 327.50484 -0.354012) (xy 327.463623 -0.318297) (xy 327.427908 -0.27708) (xy 327.398422 -0.231199)
			(xy 327.375765 -0.181589) (xy 327.3604 -0.129259) (xy 327.352638 -0.075275) (xy 327.352152 -0.048006)
			(xy 326.170474 -0.048006) (xy 326.225031 -0.075172) (xy 326.297937 -0.120313) (xy 326.366366 -0.171989)
			(xy 326.429736 -0.229758) (xy 326.487505 -0.293128) (xy 326.539181 -0.361557) (xy 326.584322 -0.434463)
			(xy 326.622544 -0.511223) (xy 326.65352 -0.591182) (xy 326.676987 -0.673658) (xy 326.692743 -0.757948)
			(xy 326.700655 -0.843331) (xy 326.70115 -0.886206) (xy 326.700655 -0.929081) (xy 331.195921 -0.929081)
			(xy 331.195921 -0.843331) (xy 331.203833 -0.757948) (xy 331.219589 -0.673658) (xy 331.243056 -0.591182)
			(xy 331.274032 -0.511223) (xy 331.312254 -0.434463) (xy 331.357395 -0.361557) (xy 331.409071 -0.293128)
			(xy 331.46684 -0.229758) (xy 331.53021 -0.171989) (xy 331.598639 -0.120313) (xy 331.671545 -0.075172)
			(xy 331.748305 -0.03695) (xy 331.828264 -0.005974) (xy 331.91074 0.017493) (xy 331.99503 0.033249)
			(xy 332.080413 0.041161) (xy 332.166163 0.041161) (xy 332.251546 0.033249) (xy 332.335836 0.017493)
			(xy 332.418312 -0.005974) (xy 332.498271 -0.03695) (xy 332.575031 -0.075172) (xy 332.647937 -0.120313)
			(xy 332.716366 -0.171989) (xy 332.779736 -0.229758) (xy 332.837505 -0.293128) (xy 332.889181 -0.361557)
			(xy 332.934322 -0.434463) (xy 332.972544 -0.511223) (xy 333.00352 -0.591182) (xy 333.026987 -0.673658)
			(xy 333.042743 -0.757948) (xy 333.050655 -0.843331) (xy 333.05115 -0.886206) (xy 333.050655 -0.929081)
			(xy 335.488267 -0.929081) (xy 335.488267 -0.843331) (xy 335.496179 -0.757948) (xy 335.511935 -0.673658)
			(xy 335.535402 -0.591182) (xy 335.566378 -0.511223) (xy 335.6046 -0.434463) (xy 335.649741 -0.361557)
			(xy 335.701417 -0.293128) (xy 335.759186 -0.229758) (xy 335.822556 -0.171989) (xy 335.890985 -0.120313)
			(xy 335.963891 -0.075172) (xy 336.040651 -0.03695) (xy 336.12061 -0.005974) (xy 336.203086 0.017493)
			(xy 336.287376 0.033249) (xy 336.372759 0.041161) (xy 336.458509 0.041161) (xy 336.543892 0.033249)
			(xy 336.628182 0.017493) (xy 336.710658 -0.005974) (xy 336.790617 -0.03695) (xy 336.81282 -0.048006)
			(xy 340.4235 -0.048006) (xy 340.4235 0.815594) (xy 340.423986 0.842845) (xy 340.431742 0.896793)
			(xy 340.447097 0.949088) (xy 340.469739 0.998665) (xy 340.499205 1.044515) (xy 340.534896 1.085706)
			(xy 340.576087 1.121397) (xy 340.621937 1.150863) (xy 340.671514 1.173505) (xy 340.723809 1.18886)
			(xy 340.777757 1.196616) (xy 340.832259 1.196616) (xy 340.886207 1.18886) (xy 340.938502 1.173505)
			(xy 340.988079 1.150863) (xy 341.033929 1.121397) (xy 341.07512 1.085706) (xy 341.110811 1.044515)
			(xy 341.140277 0.998665) (xy 341.162919 0.949088) (xy 341.178274 0.896793) (xy 341.18603 0.842845)
			(xy 341.186516 0.815594) (xy 341.186516 -0.048006) (xy 341.18603 -0.075257) (xy 341.178274 -0.129205)
			(xy 341.162919 -0.1815) (xy 341.140277 -0.231077) (xy 341.110811 -0.276927) (xy 341.07512 -0.318118)
			(xy 341.033929 -0.353809) (xy 340.988079 -0.383275) (xy 340.938502 -0.405917) (xy 340.886207 -0.421272)
			(xy 340.832259 -0.429028) (xy 340.777757 -0.429028) (xy 340.723809 -0.421272) (xy 340.671514 -0.405917)
			(xy 340.621937 -0.383275) (xy 340.576087 -0.353809) (xy 340.534896 -0.318118) (xy 340.499205 -0.276927)
			(xy 340.469739 -0.231077) (xy 340.447097 -0.1815) (xy 340.431742 -0.129205) (xy 340.423986 -0.075257)
			(xy 340.4235 -0.048006) (xy 336.81282 -0.048006) (xy 336.867377 -0.075172) (xy 336.940283 -0.120313)
			(xy 337.008712 -0.171989) (xy 337.072082 -0.229758) (xy 337.129851 -0.293128) (xy 337.181527 -0.361557)
			(xy 337.226668 -0.434463) (xy 337.26489 -0.511223) (xy 337.295866 -0.591182) (xy 337.319333 -0.673658)
			(xy 337.335089 -0.757948) (xy 337.343001 -0.843331) (xy 337.343496 -0.886206) (xy 337.343001 -0.929081)
			(xy 341.838267 -0.929081) (xy 341.838267 -0.843331) (xy 341.846179 -0.757948) (xy 341.861935 -0.673658)
			(xy 341.885402 -0.591182) (xy 341.916378 -0.511223) (xy 341.9546 -0.434463) (xy 341.999741 -0.361557)
			(xy 342.051417 -0.293128) (xy 342.109186 -0.229758) (xy 342.172556 -0.171989) (xy 342.240985 -0.120313)
			(xy 342.313891 -0.075172) (xy 342.390651 -0.03695) (xy 342.47061 -0.005974) (xy 342.553086 0.017493)
			(xy 342.637376 0.033249) (xy 342.722759 0.041161) (xy 342.808509 0.041161) (xy 342.893892 0.033249)
			(xy 342.978182 0.017493) (xy 343.060658 -0.005974) (xy 343.140617 -0.03695) (xy 343.217377 -0.075172)
			(xy 343.290283 -0.120313) (xy 343.358712 -0.171989) (xy 343.422082 -0.229758) (xy 343.479851 -0.293128)
			(xy 343.531527 -0.361557) (xy 343.576668 -0.434463) (xy 343.61489 -0.511223) (xy 343.645866 -0.591182)
			(xy 343.669333 -0.673658) (xy 343.685089 -0.757948) (xy 343.693001 -0.843331) (xy 343.693496 -0.886206)
			(xy 343.693001 -0.929081) (xy 373.705107 -0.929081) (xy 373.705107 -0.843331) (xy 373.713019 -0.757948)
			(xy 373.728775 -0.673658) (xy 373.752242 -0.591182) (xy 373.783218 -0.511223) (xy 373.82144 -0.434463)
			(xy 373.866581 -0.361557) (xy 373.918257 -0.293128) (xy 373.976026 -0.229758) (xy 374.039396 -0.171989)
			(xy 374.107825 -0.120313) (xy 374.180731 -0.075172) (xy 374.257491 -0.03695) (xy 374.33745 -0.005974)
			(xy 374.419926 0.017493) (xy 374.504216 0.033249) (xy 374.589599 0.041161) (xy 374.675349 0.041161)
			(xy 374.760732 0.033249) (xy 374.845022 0.017493) (xy 374.927498 -0.005974) (xy 375.007457 -0.03695)
			(xy 375.02966 -0.048006) (xy 376.211592 -0.048006) (xy 376.211592 0.815594) (xy 376.212078 0.842845)
			(xy 376.219834 0.896793) (xy 376.235189 0.949088) (xy 376.257831 0.998665) (xy 376.287297 1.044515)
			(xy 376.322988 1.085706) (xy 376.364179 1.121397) (xy 376.410029 1.150863) (xy 376.459606 1.173505)
			(xy 376.511901 1.18886) (xy 376.565849 1.196616) (xy 376.620351 1.196616) (xy 376.674299 1.18886)
			(xy 376.726594 1.173505) (xy 376.776171 1.150863) (xy 376.822021 1.121397) (xy 376.863212 1.085706)
			(xy 376.898903 1.044515) (xy 376.928369 0.998665) (xy 376.951011 0.949088) (xy 376.966366 0.896793)
			(xy 376.974122 0.842845) (xy 376.974608 0.815594) (xy 376.974608 -0.048006) (xy 376.974122 -0.075257)
			(xy 376.966366 -0.129205) (xy 376.951011 -0.1815) (xy 376.928369 -0.231077) (xy 376.898903 -0.276927)
			(xy 376.863212 -0.318118) (xy 376.822021 -0.353809) (xy 376.776171 -0.383275) (xy 376.726594 -0.405917)
			(xy 376.674299 -0.421272) (xy 376.620351 -0.429028) (xy 376.565849 -0.429028) (xy 376.511901 -0.421272)
			(xy 376.459606 -0.405917) (xy 376.410029 -0.383275) (xy 376.364179 -0.353809) (xy 376.322988 -0.318118)
			(xy 376.287297 -0.276927) (xy 376.257831 -0.231077) (xy 376.235189 -0.1815) (xy 376.219834 -0.129205)
			(xy 376.212078 -0.075257) (xy 376.211592 -0.048006) (xy 375.02966 -0.048006) (xy 375.084217 -0.075172)
			(xy 375.157123 -0.120313) (xy 375.225552 -0.171989) (xy 375.288922 -0.229758) (xy 375.346691 -0.293128)
			(xy 375.398367 -0.361557) (xy 375.443508 -0.434463) (xy 375.48173 -0.511223) (xy 375.512706 -0.591182)
			(xy 375.536173 -0.673658) (xy 375.551929 -0.757948) (xy 375.559841 -0.843331) (xy 375.560336 -0.886206)
			(xy 375.559841 -0.929081) (xy 380.055107 -0.929081) (xy 380.055107 -0.843331) (xy 380.063019 -0.757948)
			(xy 380.078775 -0.673658) (xy 380.102242 -0.591182) (xy 380.133218 -0.511223) (xy 380.17144 -0.434463)
			(xy 380.216581 -0.361557) (xy 380.268257 -0.293128) (xy 380.326026 -0.229758) (xy 380.389396 -0.171989)
			(xy 380.457825 -0.120313) (xy 380.530731 -0.075172) (xy 380.607491 -0.03695) (xy 380.68745 -0.005974)
			(xy 380.769926 0.017493) (xy 380.854216 0.033249) (xy 380.939599 0.041161) (xy 381.025349 0.041161)
			(xy 381.110732 0.033249) (xy 381.195022 0.017493) (xy 381.277498 -0.005974) (xy 381.357457 -0.03695)
			(xy 381.434217 -0.075172) (xy 381.507123 -0.120313) (xy 381.575552 -0.171989) (xy 381.638922 -0.229758)
			(xy 381.696691 -0.293128) (xy 381.748367 -0.361557) (xy 381.793508 -0.434463) (xy 381.83173 -0.511223)
			(xy 381.862706 -0.591182) (xy 381.886173 -0.673658) (xy 381.901929 -0.757948) (xy 381.909841 -0.843331)
			(xy 381.910336 -0.886206) (xy 381.909841 -0.929081) (xy 381.901929 -1.014464) (xy 381.886173 -1.098754)
			(xy 381.862706 -1.18123) (xy 381.83173 -1.261189) (xy 381.793508 -1.337949) (xy 381.748367 -1.410855)
			(xy 381.696691 -1.479284) (xy 381.638922 -1.542654) (xy 381.575552 -1.600423) (xy 381.507123 -1.652099)
			(xy 381.434217 -1.69724) (xy 381.357457 -1.735462) (xy 381.277498 -1.766438) (xy 381.195022 -1.789905)
			(xy 381.110732 -1.805661) (xy 381.025349 -1.813573) (xy 380.939599 -1.813573) (xy 380.854216 -1.805661)
			(xy 380.769926 -1.789905) (xy 380.68745 -1.766438) (xy 380.607491 -1.735462) (xy 380.530731 -1.69724)
			(xy 380.457825 -1.652099) (xy 380.389396 -1.600423) (xy 380.326026 -1.542654) (xy 380.268257 -1.479284)
			(xy 380.216581 -1.410855) (xy 380.17144 -1.337949) (xy 380.133218 -1.261189) (xy 380.102242 -1.18123)
			(xy 380.078775 -1.098754) (xy 380.063019 -1.014464) (xy 380.055107 -0.929081) (xy 375.559841 -0.929081)
			(xy 375.551929 -1.014464) (xy 375.536173 -1.098754) (xy 375.512706 -1.18123) (xy 375.48173 -1.261189)
			(xy 375.443508 -1.337949) (xy 375.398367 -1.410855) (xy 375.346691 -1.479284) (xy 375.288922 -1.542654)
			(xy 375.225552 -1.600423) (xy 375.157123 -1.652099) (xy 375.084217 -1.69724) (xy 375.007457 -1.735462)
			(xy 374.927498 -1.766438) (xy 374.845022 -1.789905) (xy 374.760732 -1.805661) (xy 374.675349 -1.813573)
			(xy 374.589599 -1.813573) (xy 374.504216 -1.805661) (xy 374.419926 -1.789905) (xy 374.33745 -1.766438)
			(xy 374.257491 -1.735462) (xy 374.180731 -1.69724) (xy 374.107825 -1.652099) (xy 374.039396 -1.600423)
			(xy 373.976026 -1.542654) (xy 373.918257 -1.479284) (xy 373.866581 -1.410855) (xy 373.82144 -1.337949)
			(xy 373.783218 -1.261189) (xy 373.752242 -1.18123) (xy 373.728775 -1.098754) (xy 373.713019 -1.014464)
			(xy 373.705107 -0.929081) (xy 343.693001 -0.929081) (xy 343.685089 -1.014464) (xy 343.669333 -1.098754)
			(xy 343.645866 -1.18123) (xy 343.61489 -1.261189) (xy 343.576668 -1.337949) (xy 343.531527 -1.410855)
			(xy 343.479851 -1.479284) (xy 343.422082 -1.542654) (xy 343.358712 -1.600423) (xy 343.290283 -1.652099)
			(xy 343.217377 -1.69724) (xy 343.140617 -1.735462) (xy 343.060658 -1.766438) (xy 342.978182 -1.789905)
			(xy 342.893892 -1.805661) (xy 342.808509 -1.813573) (xy 342.722759 -1.813573) (xy 342.637376 -1.805661)
			(xy 342.553086 -1.789905) (xy 342.47061 -1.766438) (xy 342.390651 -1.735462) (xy 342.313891 -1.69724)
			(xy 342.240985 -1.652099) (xy 342.172556 -1.600423) (xy 342.109186 -1.542654) (xy 342.051417 -1.479284)
			(xy 341.999741 -1.410855) (xy 341.9546 -1.337949) (xy 341.916378 -1.261189) (xy 341.885402 -1.18123)
			(xy 341.861935 -1.098754) (xy 341.846179 -1.014464) (xy 341.838267 -0.929081) (xy 337.343001 -0.929081)
			(xy 337.335089 -1.014464) (xy 337.319333 -1.098754) (xy 337.295866 -1.18123) (xy 337.26489 -1.261189)
			(xy 337.226668 -1.337949) (xy 337.181527 -1.410855) (xy 337.129851 -1.479284) (xy 337.072082 -1.542654)
			(xy 337.008712 -1.600423) (xy 336.940283 -1.652099) (xy 336.867377 -1.69724) (xy 336.790617 -1.735462)
			(xy 336.710658 -1.766438) (xy 336.628182 -1.789905) (xy 336.543892 -1.805661) (xy 336.458509 -1.813573)
			(xy 336.372759 -1.813573) (xy 336.287376 -1.805661) (xy 336.203086 -1.789905) (xy 336.12061 -1.766438)
			(xy 336.040651 -1.735462) (xy 335.963891 -1.69724) (xy 335.890985 -1.652099) (xy 335.822556 -1.600423)
			(xy 335.759186 -1.542654) (xy 335.701417 -1.479284) (xy 335.649741 -1.410855) (xy 335.6046 -1.337949)
			(xy 335.566378 -1.261189) (xy 335.535402 -1.18123) (xy 335.511935 -1.098754) (xy 335.496179 -1.014464)
			(xy 335.488267 -0.929081) (xy 333.050655 -0.929081) (xy 333.042743 -1.014464) (xy 333.026987 -1.098754)
			(xy 333.00352 -1.18123) (xy 332.972544 -1.261189) (xy 332.934322 -1.337949) (xy 332.889181 -1.410855)
			(xy 332.837505 -1.479284) (xy 332.779736 -1.542654) (xy 332.716366 -1.600423) (xy 332.647937 -1.652099)
			(xy 332.575031 -1.69724) (xy 332.498271 -1.735462) (xy 332.418312 -1.766438) (xy 332.335836 -1.789905)
			(xy 332.251546 -1.805661) (xy 332.166163 -1.813573) (xy 332.080413 -1.813573) (xy 331.99503 -1.805661)
			(xy 331.91074 -1.789905) (xy 331.828264 -1.766438) (xy 331.748305 -1.735462) (xy 331.671545 -1.69724)
			(xy 331.598639 -1.652099) (xy 331.53021 -1.600423) (xy 331.46684 -1.542654) (xy 331.409071 -1.479284)
			(xy 331.357395 -1.410855) (xy 331.312254 -1.337949) (xy 331.274032 -1.261189) (xy 331.243056 -1.18123)
			(xy 331.219589 -1.098754) (xy 331.203833 -1.014464) (xy 331.195921 -0.929081) (xy 326.700655 -0.929081)
			(xy 326.692743 -1.014464) (xy 326.676987 -1.098754) (xy 326.65352 -1.18123) (xy 326.622544 -1.261189)
			(xy 326.584322 -1.337949) (xy 326.539181 -1.410855) (xy 326.487505 -1.479284) (xy 326.429736 -1.542654)
			(xy 326.366366 -1.600423) (xy 326.297937 -1.652099) (xy 326.225031 -1.69724) (xy 326.148271 -1.735462)
			(xy 326.068312 -1.766438) (xy 325.985836 -1.789905) (xy 325.901546 -1.805661) (xy 325.816163 -1.813573)
			(xy 325.730413 -1.813573) (xy 325.64503 -1.805661) (xy 325.56074 -1.789905) (xy 325.478264 -1.766438)
			(xy 325.398305 -1.735462) (xy 325.321545 -1.69724) (xy 325.248639 -1.652099) (xy 325.18021 -1.600423)
			(xy 325.11684 -1.542654) (xy 325.059071 -1.479284) (xy 325.007395 -1.410855) (xy 324.962254 -1.337949)
			(xy 324.924032 -1.261189) (xy 324.893056 -1.18123) (xy 324.869589 -1.098754) (xy 324.853833 -1.014464)
			(xy 324.845921 -0.929081) (xy 265.125975 -0.929081) (xy 265.118063 -1.014464) (xy 265.102307 -1.098754)
			(xy 265.07884 -1.18123) (xy 265.047864 -1.261189) (xy 265.009642 -1.337949) (xy 264.964501 -1.410855)
			(xy 264.912825 -1.479284) (xy 264.855056 -1.542654) (xy 264.791686 -1.600423) (xy 264.723257 -1.652099)
			(xy 264.650351 -1.69724) (xy 264.573591 -1.735462) (xy 264.493632 -1.766438) (xy 264.411156 -1.789905)
			(xy 264.326866 -1.805661) (xy 264.241483 -1.813573) (xy 264.155733 -1.813573) (xy 264.07035 -1.805661)
			(xy 263.98606 -1.789905) (xy 263.903584 -1.766438) (xy 263.823625 -1.735462) (xy 263.746865 -1.69724)
			(xy 263.673959 -1.652099) (xy 263.60553 -1.600423) (xy 263.54216 -1.542654) (xy 263.484391 -1.479284)
			(xy 263.432715 -1.410855) (xy 263.387574 -1.337949) (xy 263.349352 -1.261189) (xy 263.318376 -1.18123)
			(xy 263.294909 -1.098754) (xy 263.279153 -1.014464) (xy 263.271241 -0.929081) (xy 258.775975 -0.929081)
			(xy 258.768063 -1.014464) (xy 258.752307 -1.098754) (xy 258.72884 -1.18123) (xy 258.697864 -1.261189)
			(xy 258.659642 -1.337949) (xy 258.614501 -1.410855) (xy 258.562825 -1.479284) (xy 258.505056 -1.542654)
			(xy 258.441686 -1.600423) (xy 258.373257 -1.652099) (xy 258.300351 -1.69724) (xy 258.223591 -1.735462)
			(xy 258.143632 -1.766438) (xy 258.061156 -1.789905) (xy 257.976866 -1.805661) (xy 257.891483 -1.813573)
			(xy 257.805733 -1.813573) (xy 257.72035 -1.805661) (xy 257.63606 -1.789905) (xy 257.553584 -1.766438)
			(xy 257.473625 -1.735462) (xy 257.396865 -1.69724) (xy 257.323959 -1.652099) (xy 257.25553 -1.600423)
			(xy 257.19216 -1.542654) (xy 257.134391 -1.479284) (xy 257.082715 -1.410855) (xy 257.037574 -1.337949)
			(xy 256.999352 -1.261189) (xy 256.968376 -1.18123) (xy 256.944909 -1.098754) (xy 256.929153 -1.014464)
			(xy 256.921241 -0.929081) (xy 254.465119 -0.929081) (xy 254.465087 -0.931875) (xy 254.457175 -1.017258)
			(xy 254.441419 -1.101548) (xy 254.417952 -1.184024) (xy 254.386976 -1.263983) (xy 254.348754 -1.340743)
			(xy 254.303613 -1.413649) (xy 254.251937 -1.482078) (xy 254.194168 -1.545448) (xy 254.130798 -1.603217)
			(xy 254.062369 -1.654893) (xy 253.989463 -1.700034) (xy 253.912703 -1.738256) (xy 253.832744 -1.769232)
			(xy 253.750268 -1.792699) (xy 253.665978 -1.808455) (xy 253.580595 -1.816367) (xy 253.494845 -1.816367)
			(xy 253.409462 -1.808455) (xy 253.325172 -1.792699) (xy 253.242696 -1.769232) (xy 253.162737 -1.738256)
			(xy 253.085977 -1.700034) (xy 253.013071 -1.654893) (xy 252.944642 -1.603217) (xy 252.881272 -1.545448)
			(xy 252.823503 -1.482078) (xy 252.771827 -1.413649) (xy 252.726686 -1.340743) (xy 252.688464 -1.263983)
			(xy 252.657488 -1.184024) (xy 252.634021 -1.101548) (xy 252.618265 -1.017258) (xy 252.610353 -0.931875)
			(xy 248.115087 -0.931875) (xy 248.107175 -1.017258) (xy 248.091419 -1.101548) (xy 248.067952 -1.184024)
			(xy 248.036976 -1.263983) (xy 247.998754 -1.340743) (xy 247.953613 -1.413649) (xy 247.901937 -1.482078)
			(xy 247.844168 -1.545448) (xy 247.780798 -1.603217) (xy 247.712369 -1.654893) (xy 247.639463 -1.700034)
			(xy 247.562703 -1.738256) (xy 247.482744 -1.769232) (xy 247.400268 -1.792699) (xy 247.315978 -1.808455)
			(xy 247.230595 -1.816367) (xy 247.144845 -1.816367) (xy 247.059462 -1.808455) (xy 246.975172 -1.792699)
			(xy 246.892696 -1.769232) (xy 246.812737 -1.738256) (xy 246.735977 -1.700034) (xy 246.663071 -1.654893)
			(xy 246.594642 -1.603217) (xy 246.531272 -1.545448) (xy 246.473503 -1.482078) (xy 246.421827 -1.413649)
			(xy 246.376686 -1.340743) (xy 246.338464 -1.263983) (xy 246.307488 -1.184024) (xy 246.284021 -1.101548)
			(xy 246.268265 -1.017258) (xy 246.260353 -0.931875) (xy 216.248247 -0.931875) (xy 216.240335 -1.017258)
			(xy 216.224579 -1.101548) (xy 216.201112 -1.184024) (xy 216.170136 -1.263983) (xy 216.131914 -1.340743)
			(xy 216.086773 -1.413649) (xy 216.035097 -1.482078) (xy 215.977328 -1.545448) (xy 215.913958 -1.603217)
			(xy 215.845529 -1.654893) (xy 215.772623 -1.700034) (xy 215.695863 -1.738256) (xy 215.615904 -1.769232)
			(xy 215.533428 -1.792699) (xy 215.449138 -1.808455) (xy 215.363755 -1.816367) (xy 215.278005 -1.816367)
			(xy 215.192622 -1.808455) (xy 215.108332 -1.792699) (xy 215.025856 -1.769232) (xy 214.945897 -1.738256)
			(xy 214.869137 -1.700034) (xy 214.796231 -1.654893) (xy 214.727802 -1.603217) (xy 214.664432 -1.545448)
			(xy 214.606663 -1.482078) (xy 214.554987 -1.413649) (xy 214.509846 -1.340743) (xy 214.471624 -1.263983)
			(xy 214.440648 -1.184024) (xy 214.417181 -1.101548) (xy 214.401425 -1.017258) (xy 214.393513 -0.931875)
			(xy 209.898247 -0.931875) (xy 209.890335 -1.017258) (xy 209.874579 -1.101548) (xy 209.851112 -1.184024)
			(xy 209.820136 -1.263983) (xy 209.781914 -1.340743) (xy 209.736773 -1.413649) (xy 209.685097 -1.482078)
			(xy 209.627328 -1.545448) (xy 209.563958 -1.603217) (xy 209.495529 -1.654893) (xy 209.422623 -1.700034)
			(xy 209.345863 -1.738256) (xy 209.265904 -1.769232) (xy 209.183428 -1.792699) (xy 209.099138 -1.808455)
			(xy 209.013755 -1.816367) (xy 208.928005 -1.816367) (xy 208.842622 -1.808455) (xy 208.758332 -1.792699)
			(xy 208.675856 -1.769232) (xy 208.595897 -1.738256) (xy 208.519137 -1.700034) (xy 208.446231 -1.654893)
			(xy 208.377802 -1.603217) (xy 208.314432 -1.545448) (xy 208.256663 -1.482078) (xy 208.204987 -1.413649)
			(xy 208.159846 -1.340743) (xy 208.121624 -1.263983) (xy 208.090648 -1.184024) (xy 208.067181 -1.101548)
			(xy 208.051425 -1.017258) (xy 208.043513 -0.931875) (xy 84.20989 -0.931875) (xy 84.20989 -7.78002)
			(xy 84.210412 -7.835827) (xy 84.218755 -7.947128) (xy 84.235391 -8.057495) (xy 84.260229 -8.16631)
			(xy 84.293128 -8.272964) (xy 84.333906 -8.376862) (xy 84.382334 -8.477422) (xy 84.438141 -8.574082)
			(xy 84.501016 -8.666301) (xy 84.570606 -8.753563) (xy 84.646523 -8.835382) (xy 84.728341 -8.911298)
			(xy 84.815604 -8.980888) (xy 84.907824 -9.043762) (xy 85.004484 -9.099569) (xy 85.105044 -9.147996)
			(xy 85.208942 -9.188774) (xy 85.315596 -9.221673) (xy 85.424411 -9.24651) (xy 85.534778 -9.263146)
			(xy 85.646079 -9.271488) (xy 85.701886 -9.272016) (xy 122.102118 -9.272016) (xy 122.157925 -9.271494)
			(xy 122.269226 -9.263152) (xy 122.379593 -9.246515) (xy 122.488409 -9.221678) (xy 122.595063 -9.188778)
			(xy 122.698961 -9.148001) (xy 122.799522 -9.099573) (xy 122.896182 -9.043766) (xy 122.988401 -8.980891)
			(xy 123.075664 -8.911301) (xy 123.157483 -8.835384) (xy 123.2334 -8.753566) (xy 123.30299 -8.666303)
			(xy 123.365865 -8.574084) (xy 123.421672 -8.477423) (xy 123.4701 -8.376863) (xy 123.510878 -8.272965)
			(xy 123.543777 -8.16631) (xy 123.568615 -8.057495) (xy 123.585251 -7.947128) (xy 123.593594 -7.835827)
			(xy 123.594114 -7.78002) (xy 123.594114 -4.2799) (xy 123.594598 -4.209546) (xy 123.602488 -4.06906)
			(xy 123.618242 -3.929237) (xy 123.641812 -3.790517) (xy 123.673122 -3.653337) (xy 123.712075 -3.518129)
			(xy 123.758548 -3.385317) (xy 123.812395 -3.25532) (xy 123.873446 -3.128547) (xy 123.941509 -3.005396)
			(xy 124.01637 -2.886255) (xy 124.097794 -2.7715) (xy 124.185524 -2.66149) (xy 124.279284 -2.556573)
			(xy 124.37878 -2.457077) (xy 124.483698 -2.363317) (xy 124.593708 -2.275588) (xy 124.708464 -2.194165)
			(xy 124.827605 -2.119304) (xy 124.950755 -2.051241) (xy 125.077529 -1.990191) (xy 125.207526 -1.936345)
			(xy 125.340338 -1.889872) (xy 125.475547 -1.85092) (xy 125.612727 -1.81961) (xy 125.751447 -1.796041)
			(xy 125.89127 -1.780287) (xy 126.031756 -1.772398) (xy 126.10211 -1.771904) (xy 194.701922 -1.771904)
			(xy 194.772275 -1.772398) (xy 194.912761 -1.780289) (xy 195.052582 -1.796044) (xy 195.191301 -1.819614)
			(xy 195.32848 -1.850925) (xy 195.463687 -1.889879) (xy 195.596497 -1.936352) (xy 195.726493 -1.990199)
			(xy 195.853265 -2.05125) (xy 195.976414 -2.119314) (xy 196.095554 -2.194175) (xy 196.210308 -2.275598)
			(xy 196.320316 -2.363328) (xy 196.425233 -2.457088) (xy 196.524727 -2.556583) (xy 196.618486 -2.6615)
			(xy 196.706215 -2.77151) (xy 196.787637 -2.886265) (xy 196.862497 -3.005405) (xy 196.93056 -3.128555)
			(xy 196.99161 -3.255327) (xy 197.045455 -3.385323) (xy 197.075741 -3.471875) (xy 208.043513 -3.471875)
			(xy 208.043513 -3.386125) (xy 208.051425 -3.300742) (xy 208.067181 -3.216452) (xy 208.090648 -3.133976)
			(xy 208.121624 -3.054017) (xy 208.159846 -2.977257) (xy 208.204987 -2.904351) (xy 208.256663 -2.835922)
			(xy 208.314432 -2.772552) (xy 208.377802 -2.714783) (xy 208.446231 -2.663107) (xy 208.519137 -2.617966)
			(xy 208.595897 -2.579744) (xy 208.675856 -2.548768) (xy 208.758332 -2.525301) (xy 208.842622 -2.509545)
			(xy 208.928005 -2.501633) (xy 209.013755 -2.501633) (xy 209.099138 -2.509545) (xy 209.183428 -2.525301)
			(xy 209.265904 -2.548768) (xy 209.345863 -2.579744) (xy 209.368066 -2.5908) (xy 212.978492 -2.5908)
			(xy 212.978492 -1.7272) (xy 212.978978 -1.699931) (xy 212.98674 -1.645947) (xy 213.002105 -1.593617)
			(xy 213.024762 -1.544007) (xy 213.054248 -1.498126) (xy 213.089963 -1.456909) (xy 213.13118 -1.421194)
			(xy 213.177061 -1.391708) (xy 213.226671 -1.369051) (xy 213.279001 -1.353686) (xy 213.332985 -1.345924)
			(xy 213.387523 -1.345924) (xy 213.441507 -1.353686) (xy 213.493837 -1.369051) (xy 213.543447 -1.391708)
			(xy 213.589328 -1.421194) (xy 213.630545 -1.456909) (xy 213.66626 -1.498126) (xy 213.695746 -1.544007)
			(xy 213.718403 -1.593617) (xy 213.733768 -1.645947) (xy 213.74153 -1.699931) (xy 213.742016 -1.7272)
			(xy 213.742016 -2.5908) (xy 213.74153 -2.618069) (xy 213.733768 -2.672053) (xy 213.718403 -2.724383)
			(xy 213.695746 -2.773993) (xy 213.66626 -2.819874) (xy 213.630545 -2.861091) (xy 213.589328 -2.896806)
			(xy 213.543447 -2.926292) (xy 213.493837 -2.948949) (xy 213.441507 -2.964314) (xy 213.387523 -2.972076)
			(xy 213.332985 -2.972076) (xy 213.279001 -2.964314) (xy 213.226671 -2.948949) (xy 213.177061 -2.926292)
			(xy 213.13118 -2.896806) (xy 213.089963 -2.861091) (xy 213.054248 -2.819874) (xy 213.024762 -2.773993)
			(xy 213.002105 -2.724383) (xy 212.98674 -2.672053) (xy 212.978978 -2.618069) (xy 212.978492 -2.5908)
			(xy 209.368066 -2.5908) (xy 209.422623 -2.617966) (xy 209.495529 -2.663107) (xy 209.563958 -2.714783)
			(xy 209.627328 -2.772552) (xy 209.685097 -2.835922) (xy 209.736773 -2.904351) (xy 209.781914 -2.977257)
			(xy 209.820136 -3.054017) (xy 209.851112 -3.133976) (xy 209.874579 -3.216452) (xy 209.890335 -3.300742)
			(xy 209.898247 -3.386125) (xy 209.898742 -3.429) (xy 209.898247 -3.471875) (xy 214.393513 -3.471875)
			(xy 214.393513 -3.386125) (xy 214.401425 -3.300742) (xy 214.417181 -3.216452) (xy 214.440648 -3.133976)
			(xy 214.471624 -3.054017) (xy 214.509846 -2.977257) (xy 214.554987 -2.904351) (xy 214.606663 -2.835922)
			(xy 214.664432 -2.772552) (xy 214.727802 -2.714783) (xy 214.796231 -2.663107) (xy 214.869137 -2.617966)
			(xy 214.945897 -2.579744) (xy 215.025856 -2.548768) (xy 215.108332 -2.525301) (xy 215.192622 -2.509545)
			(xy 215.278005 -2.501633) (xy 215.363755 -2.501633) (xy 215.449138 -2.509545) (xy 215.533428 -2.525301)
			(xy 215.615904 -2.548768) (xy 215.695863 -2.579744) (xy 215.772623 -2.617966) (xy 215.845529 -2.663107)
			(xy 215.913958 -2.714783) (xy 215.977328 -2.772552) (xy 216.035097 -2.835922) (xy 216.086773 -2.904351)
			(xy 216.131914 -2.977257) (xy 216.170136 -3.054017) (xy 216.201112 -3.133976) (xy 216.224579 -3.216452)
			(xy 216.240335 -3.300742) (xy 216.248247 -3.386125) (xy 216.248742 -3.429) (xy 216.248247 -3.471875)
			(xy 246.260353 -3.471875) (xy 246.260353 -3.386125) (xy 246.268265 -3.300742) (xy 246.284021 -3.216452)
			(xy 246.307488 -3.133976) (xy 246.338464 -3.054017) (xy 246.376686 -2.977257) (xy 246.421827 -2.904351)
			(xy 246.473503 -2.835922) (xy 246.531272 -2.772552) (xy 246.594642 -2.714783) (xy 246.663071 -2.663107)
			(xy 246.735977 -2.617966) (xy 246.812737 -2.579744) (xy 246.892696 -2.548768) (xy 246.975172 -2.525301)
			(xy 247.059462 -2.509545) (xy 247.144845 -2.501633) (xy 247.230595 -2.501633) (xy 247.315978 -2.509545)
			(xy 247.400268 -2.525301) (xy 247.482744 -2.548768) (xy 247.562703 -2.579744) (xy 247.584906 -2.5908)
			(xy 248.766584 -2.5908) (xy 248.766584 -1.7272) (xy 248.76707 -1.699931) (xy 248.774832 -1.645947)
			(xy 248.790197 -1.593617) (xy 248.812854 -1.544007) (xy 248.84234 -1.498126) (xy 248.878055 -1.456909)
			(xy 248.919272 -1.421194) (xy 248.965153 -1.391708) (xy 249.014763 -1.369051) (xy 249.067093 -1.353686)
			(xy 249.121077 -1.345924) (xy 249.175615 -1.345924) (xy 249.229599 -1.353686) (xy 249.281929 -1.369051)
			(xy 249.331539 -1.391708) (xy 249.37742 -1.421194) (xy 249.418637 -1.456909) (xy 249.454352 -1.498126)
			(xy 249.483838 -1.544007) (xy 249.506495 -1.593617) (xy 249.52186 -1.645947) (xy 249.529622 -1.699931)
			(xy 249.530108 -1.7272) (xy 249.530108 -2.5908) (xy 249.529622 -2.618069) (xy 249.52186 -2.672053)
			(xy 249.506495 -2.724383) (xy 249.483838 -2.773993) (xy 249.454352 -2.819874) (xy 249.418637 -2.861091)
			(xy 249.37742 -2.896806) (xy 249.331539 -2.926292) (xy 249.281929 -2.948949) (xy 249.229599 -2.964314)
			(xy 249.175615 -2.972076) (xy 249.121077 -2.972076) (xy 249.067093 -2.964314) (xy 249.014763 -2.948949)
			(xy 248.965153 -2.926292) (xy 248.919272 -2.896806) (xy 248.878055 -2.861091) (xy 248.84234 -2.819874)
			(xy 248.812854 -2.773993) (xy 248.790197 -2.724383) (xy 248.774832 -2.672053) (xy 248.76707 -2.618069)
			(xy 248.766584 -2.5908) (xy 247.584906 -2.5908) (xy 247.639463 -2.617966) (xy 247.712369 -2.663107)
			(xy 247.780798 -2.714783) (xy 247.844168 -2.772552) (xy 247.901937 -2.835922) (xy 247.953613 -2.904351)
			(xy 247.998754 -2.977257) (xy 248.036976 -3.054017) (xy 248.067952 -3.133976) (xy 248.091419 -3.216452)
			(xy 248.107175 -3.300742) (xy 248.115087 -3.386125) (xy 248.115582 -3.429) (xy 248.115087 -3.471875)
			(xy 252.610353 -3.471875) (xy 252.610353 -3.386125) (xy 252.618265 -3.300742) (xy 252.634021 -3.216452)
			(xy 252.657488 -3.133976) (xy 252.688464 -3.054017) (xy 252.726686 -2.977257) (xy 252.771827 -2.904351)
			(xy 252.823503 -2.835922) (xy 252.881272 -2.772552) (xy 252.944642 -2.714783) (xy 253.013071 -2.663107)
			(xy 253.085977 -2.617966) (xy 253.162737 -2.579744) (xy 253.242696 -2.548768) (xy 253.325172 -2.525301)
			(xy 253.409462 -2.509545) (xy 253.494845 -2.501633) (xy 253.580595 -2.501633) (xy 253.665978 -2.509545)
			(xy 253.750268 -2.525301) (xy 253.832744 -2.548768) (xy 253.912703 -2.579744) (xy 253.989463 -2.617966)
			(xy 254.062369 -2.663107) (xy 254.130798 -2.714783) (xy 254.194168 -2.772552) (xy 254.251937 -2.835922)
			(xy 254.303613 -2.904351) (xy 254.348754 -2.977257) (xy 254.386976 -3.054017) (xy 254.417952 -3.133976)
			(xy 254.441419 -3.216452) (xy 254.457175 -3.300742) (xy 254.465087 -3.386125) (xy 254.465582 -3.429)
			(xy 254.465119 -3.469081) (xy 256.921241 -3.469081) (xy 256.921241 -3.383331) (xy 256.929153 -3.297948)
			(xy 256.944909 -3.213658) (xy 256.968376 -3.131182) (xy 256.999352 -3.051223) (xy 257.037574 -2.974463)
			(xy 257.082715 -2.901557) (xy 257.134391 -2.833128) (xy 257.19216 -2.769758) (xy 257.25553 -2.711989)
			(xy 257.323959 -2.660313) (xy 257.396865 -2.615172) (xy 257.473625 -2.57695) (xy 257.553584 -2.545974)
			(xy 257.63606 -2.522507) (xy 257.72035 -2.506751) (xy 257.805733 -2.498839) (xy 257.891483 -2.498839)
			(xy 257.976866 -2.506751) (xy 258.061156 -2.522507) (xy 258.143632 -2.545974) (xy 258.223591 -2.57695)
			(xy 258.300351 -2.615172) (xy 258.373257 -2.660313) (xy 258.441686 -2.711989) (xy 258.505056 -2.769758)
			(xy 258.562825 -2.833128) (xy 258.614501 -2.901557) (xy 258.659642 -2.974463) (xy 258.697864 -3.051223)
			(xy 258.72884 -3.131182) (xy 258.752307 -3.213658) (xy 258.768063 -3.297948) (xy 258.775975 -3.383331)
			(xy 258.77647 -3.426206) (xy 258.775975 -3.469081) (xy 263.271241 -3.469081) (xy 263.271241 -3.383331)
			(xy 263.279153 -3.297948) (xy 263.294909 -3.213658) (xy 263.318376 -3.131182) (xy 263.349352 -3.051223)
			(xy 263.387574 -2.974463) (xy 263.432715 -2.901557) (xy 263.484391 -2.833128) (xy 263.54216 -2.769758)
			(xy 263.60553 -2.711989) (xy 263.673959 -2.660313) (xy 263.746865 -2.615172) (xy 263.823625 -2.57695)
			(xy 263.903584 -2.545974) (xy 263.98606 -2.522507) (xy 264.07035 -2.506751) (xy 264.155733 -2.498839)
			(xy 264.241483 -2.498839) (xy 264.326866 -2.506751) (xy 264.411156 -2.522507) (xy 264.493632 -2.545974)
			(xy 264.573591 -2.57695) (xy 264.650351 -2.615172) (xy 264.723257 -2.660313) (xy 264.791686 -2.711989)
			(xy 264.855056 -2.769758) (xy 264.912825 -2.833128) (xy 264.964501 -2.901557) (xy 265.009642 -2.974463)
			(xy 265.047864 -3.051223) (xy 265.07884 -3.131182) (xy 265.102307 -3.213658) (xy 265.118063 -3.297948)
			(xy 265.125975 -3.383331) (xy 265.12647 -3.426206) (xy 265.125975 -3.469081) (xy 324.845921 -3.469081)
			(xy 324.845921 -3.383331) (xy 324.853833 -3.297948) (xy 324.869589 -3.213658) (xy 324.893056 -3.131182)
			(xy 324.924032 -3.051223) (xy 324.962254 -2.974463) (xy 325.007395 -2.901557) (xy 325.059071 -2.833128)
			(xy 325.11684 -2.769758) (xy 325.18021 -2.711989) (xy 325.248639 -2.660313) (xy 325.321545 -2.615172)
			(xy 325.398305 -2.57695) (xy 325.478264 -2.545974) (xy 325.56074 -2.522507) (xy 325.64503 -2.506751)
			(xy 325.730413 -2.498839) (xy 325.816163 -2.498839) (xy 325.901546 -2.506751) (xy 325.985836 -2.522507)
			(xy 326.068312 -2.545974) (xy 326.148271 -2.57695) (xy 326.225031 -2.615172) (xy 326.297937 -2.660313)
			(xy 326.366366 -2.711989) (xy 326.429736 -2.769758) (xy 326.487505 -2.833128) (xy 326.539181 -2.901557)
			(xy 326.584322 -2.974463) (xy 326.622544 -3.051223) (xy 326.65352 -3.131182) (xy 326.676987 -3.213658)
			(xy 326.692743 -3.297948) (xy 326.700655 -3.383331) (xy 326.70115 -3.426206) (xy 326.700655 -3.469081)
			(xy 331.195921 -3.469081) (xy 331.195921 -3.383331) (xy 331.203833 -3.297948) (xy 331.219589 -3.213658)
			(xy 331.243056 -3.131182) (xy 331.274032 -3.051223) (xy 331.312254 -2.974463) (xy 331.357395 -2.901557)
			(xy 331.409071 -2.833128) (xy 331.46684 -2.769758) (xy 331.53021 -2.711989) (xy 331.598639 -2.660313)
			(xy 331.671545 -2.615172) (xy 331.748305 -2.57695) (xy 331.828264 -2.545974) (xy 331.91074 -2.522507)
			(xy 331.99503 -2.506751) (xy 332.080413 -2.498839) (xy 332.166163 -2.498839) (xy 332.251546 -2.506751)
			(xy 332.335836 -2.522507) (xy 332.418312 -2.545974) (xy 332.498271 -2.57695) (xy 332.575031 -2.615172)
			(xy 332.647937 -2.660313) (xy 332.716366 -2.711989) (xy 332.779736 -2.769758) (xy 332.837505 -2.833128)
			(xy 332.889181 -2.901557) (xy 332.934322 -2.974463) (xy 332.972544 -3.051223) (xy 333.00352 -3.131182)
			(xy 333.026987 -3.213658) (xy 333.042743 -3.297948) (xy 333.050655 -3.383331) (xy 333.05115 -3.426206)
			(xy 333.050655 -3.469081) (xy 335.488267 -3.469081) (xy 335.488267 -3.383331) (xy 335.496179 -3.297948)
			(xy 335.511935 -3.213658) (xy 335.535402 -3.131182) (xy 335.566378 -3.051223) (xy 335.6046 -2.974463)
			(xy 335.649741 -2.901557) (xy 335.701417 -2.833128) (xy 335.759186 -2.769758) (xy 335.822556 -2.711989)
			(xy 335.890985 -2.660313) (xy 335.963891 -2.615172) (xy 336.040651 -2.57695) (xy 336.12061 -2.545974)
			(xy 336.203086 -2.522507) (xy 336.287376 -2.506751) (xy 336.372759 -2.498839) (xy 336.458509 -2.498839)
			(xy 336.543892 -2.506751) (xy 336.628182 -2.522507) (xy 336.710658 -2.545974) (xy 336.790617 -2.57695)
			(xy 336.867377 -2.615172) (xy 336.940283 -2.660313) (xy 337.008712 -2.711989) (xy 337.072082 -2.769758)
			(xy 337.129851 -2.833128) (xy 337.181527 -2.901557) (xy 337.226668 -2.974463) (xy 337.26489 -3.051223)
			(xy 337.295866 -3.131182) (xy 337.319333 -3.213658) (xy 337.335089 -3.297948) (xy 337.343001 -3.383331)
			(xy 337.343496 -3.426206) (xy 337.343001 -3.469081) (xy 341.838267 -3.469081) (xy 341.838267 -3.383331)
			(xy 341.846179 -3.297948) (xy 341.861935 -3.213658) (xy 341.885402 -3.131182) (xy 341.916378 -3.051223)
			(xy 341.9546 -2.974463) (xy 341.999741 -2.901557) (xy 342.051417 -2.833128) (xy 342.109186 -2.769758)
			(xy 342.172556 -2.711989) (xy 342.240985 -2.660313) (xy 342.313891 -2.615172) (xy 342.390651 -2.57695)
			(xy 342.47061 -2.545974) (xy 342.553086 -2.522507) (xy 342.637376 -2.506751) (xy 342.722759 -2.498839)
			(xy 342.808509 -2.498839) (xy 342.893892 -2.506751) (xy 342.978182 -2.522507) (xy 343.060658 -2.545974)
			(xy 343.140617 -2.57695) (xy 343.217377 -2.615172) (xy 343.290283 -2.660313) (xy 343.358712 -2.711989)
			(xy 343.422082 -2.769758) (xy 343.479851 -2.833128) (xy 343.531527 -2.901557) (xy 343.576668 -2.974463)
			(xy 343.61489 -3.051223) (xy 343.645866 -3.131182) (xy 343.669333 -3.213658) (xy 343.685089 -3.297948)
			(xy 343.693001 -3.383331) (xy 343.693496 -3.426206) (xy 343.693001 -3.469081) (xy 373.705107 -3.469081)
			(xy 373.705107 -3.383331) (xy 373.713019 -3.297948) (xy 373.728775 -3.213658) (xy 373.752242 -3.131182)
			(xy 373.783218 -3.051223) (xy 373.82144 -2.974463) (xy 373.866581 -2.901557) (xy 373.918257 -2.833128)
			(xy 373.976026 -2.769758) (xy 374.039396 -2.711989) (xy 374.107825 -2.660313) (xy 374.180731 -2.615172)
			(xy 374.257491 -2.57695) (xy 374.33745 -2.545974) (xy 374.419926 -2.522507) (xy 374.504216 -2.506751)
			(xy 374.589599 -2.498839) (xy 374.675349 -2.498839) (xy 374.760732 -2.506751) (xy 374.845022 -2.522507)
			(xy 374.927498 -2.545974) (xy 375.007457 -2.57695) (xy 375.084217 -2.615172) (xy 375.157123 -2.660313)
			(xy 375.225552 -2.711989) (xy 375.288922 -2.769758) (xy 375.346691 -2.833128) (xy 375.398367 -2.901557)
			(xy 375.443508 -2.974463) (xy 375.48173 -3.051223) (xy 375.512706 -3.131182) (xy 375.536173 -3.213658)
			(xy 375.551929 -3.297948) (xy 375.559841 -3.383331) (xy 375.560336 -3.426206) (xy 375.559841 -3.469081)
			(xy 380.055107 -3.469081) (xy 380.055107 -3.383331) (xy 380.063019 -3.297948) (xy 380.078775 -3.213658)
			(xy 380.102242 -3.131182) (xy 380.133218 -3.051223) (xy 380.17144 -2.974463) (xy 380.216581 -2.901557)
			(xy 380.268257 -2.833128) (xy 380.326026 -2.769758) (xy 380.389396 -2.711989) (xy 380.457825 -2.660313)
			(xy 380.530731 -2.615172) (xy 380.607491 -2.57695) (xy 380.68745 -2.545974) (xy 380.769926 -2.522507)
			(xy 380.854216 -2.506751) (xy 380.939599 -2.498839) (xy 381.025349 -2.498839) (xy 381.110732 -2.506751)
			(xy 381.195022 -2.522507) (xy 381.277498 -2.545974) (xy 381.357457 -2.57695) (xy 381.434217 -2.615172)
			(xy 381.507123 -2.660313) (xy 381.575552 -2.711989) (xy 381.638922 -2.769758) (xy 381.696691 -2.833128)
			(xy 381.748367 -2.901557) (xy 381.793508 -2.974463) (xy 381.83173 -3.051223) (xy 381.862706 -3.131182)
			(xy 381.886173 -3.213658) (xy 381.901929 -3.297948) (xy 381.909841 -3.383331) (xy 381.910336 -3.426206)
			(xy 381.909841 -3.469081) (xy 381.901929 -3.554464) (xy 381.886173 -3.638754) (xy 381.862706 -3.72123)
			(xy 381.83173 -3.801189) (xy 381.793508 -3.877949) (xy 381.748367 -3.950855) (xy 381.696691 -4.019284)
			(xy 381.638922 -4.082654) (xy 381.575552 -4.140423) (xy 381.507123 -4.192099) (xy 381.434217 -4.23724)
			(xy 381.357457 -4.275462) (xy 381.277498 -4.306438) (xy 381.195022 -4.329905) (xy 381.110732 -4.345661)
			(xy 381.025349 -4.353573) (xy 380.939599 -4.353573) (xy 380.854216 -4.345661) (xy 380.769926 -4.329905)
			(xy 380.68745 -4.306438) (xy 380.607491 -4.275462) (xy 380.530731 -4.23724) (xy 380.457825 -4.192099)
			(xy 380.389396 -4.140423) (xy 380.326026 -4.082654) (xy 380.268257 -4.019284) (xy 380.216581 -3.950855)
			(xy 380.17144 -3.877949) (xy 380.133218 -3.801189) (xy 380.102242 -3.72123) (xy 380.078775 -3.638754)
			(xy 380.063019 -3.554464) (xy 380.055107 -3.469081) (xy 375.559841 -3.469081) (xy 375.551929 -3.554464)
			(xy 375.536173 -3.638754) (xy 375.512706 -3.72123) (xy 375.48173 -3.801189) (xy 375.443508 -3.877949)
			(xy 375.398367 -3.950855) (xy 375.346691 -4.019284) (xy 375.288922 -4.082654) (xy 375.225552 -4.140423)
			(xy 375.157123 -4.192099) (xy 375.084217 -4.23724) (xy 375.007457 -4.275462) (xy 374.927498 -4.306438)
			(xy 374.845022 -4.329905) (xy 374.760732 -4.345661) (xy 374.675349 -4.353573) (xy 374.589599 -4.353573)
			(xy 374.504216 -4.345661) (xy 374.419926 -4.329905) (xy 374.33745 -4.306438) (xy 374.257491 -4.275462)
			(xy 374.180731 -4.23724) (xy 374.107825 -4.192099) (xy 374.039396 -4.140423) (xy 373.976026 -4.082654)
			(xy 373.918257 -4.019284) (xy 373.866581 -3.950855) (xy 373.82144 -3.877949) (xy 373.783218 -3.801189)
			(xy 373.752242 -3.72123) (xy 373.728775 -3.638754) (xy 373.713019 -3.554464) (xy 373.705107 -3.469081)
			(xy 343.693001 -3.469081) (xy 343.685089 -3.554464) (xy 343.669333 -3.638754) (xy 343.645866 -3.72123)
			(xy 343.61489 -3.801189) (xy 343.576668 -3.877949) (xy 343.531527 -3.950855) (xy 343.479851 -4.019284)
			(xy 343.422082 -4.082654) (xy 343.358712 -4.140423) (xy 343.290283 -4.192099) (xy 343.217377 -4.23724)
			(xy 343.140617 -4.275462) (xy 343.060658 -4.306438) (xy 342.978182 -4.329905) (xy 342.893892 -4.345661)
			(xy 342.808509 -4.353573) (xy 342.722759 -4.353573) (xy 342.637376 -4.345661) (xy 342.553086 -4.329905)
			(xy 342.47061 -4.306438) (xy 342.390651 -4.275462) (xy 342.313891 -4.23724) (xy 342.240985 -4.192099)
			(xy 342.172556 -4.140423) (xy 342.109186 -4.082654) (xy 342.051417 -4.019284) (xy 341.999741 -3.950855)
			(xy 341.9546 -3.877949) (xy 341.916378 -3.801189) (xy 341.885402 -3.72123) (xy 341.861935 -3.638754)
			(xy 341.846179 -3.554464) (xy 341.838267 -3.469081) (xy 337.343001 -3.469081) (xy 337.335089 -3.554464)
			(xy 337.319333 -3.638754) (xy 337.295866 -3.72123) (xy 337.26489 -3.801189) (xy 337.226668 -3.877949)
			(xy 337.181527 -3.950855) (xy 337.129851 -4.019284) (xy 337.072082 -4.082654) (xy 337.008712 -4.140423)
			(xy 336.940283 -4.192099) (xy 336.867377 -4.23724) (xy 336.790617 -4.275462) (xy 336.710658 -4.306438)
			(xy 336.628182 -4.329905) (xy 336.543892 -4.345661) (xy 336.458509 -4.353573) (xy 336.372759 -4.353573)
			(xy 336.287376 -4.345661) (xy 336.203086 -4.329905) (xy 336.12061 -4.306438) (xy 336.040651 -4.275462)
			(xy 335.963891 -4.23724) (xy 335.890985 -4.192099) (xy 335.822556 -4.140423) (xy 335.759186 -4.082654)
			(xy 335.701417 -4.019284) (xy 335.649741 -3.950855) (xy 335.6046 -3.877949) (xy 335.566378 -3.801189)
			(xy 335.535402 -3.72123) (xy 335.511935 -3.638754) (xy 335.496179 -3.554464) (xy 335.488267 -3.469081)
			(xy 333.050655 -3.469081) (xy 333.042743 -3.554464) (xy 333.026987 -3.638754) (xy 333.00352 -3.72123)
			(xy 332.972544 -3.801189) (xy 332.934322 -3.877949) (xy 332.889181 -3.950855) (xy 332.837505 -4.019284)
			(xy 332.779736 -4.082654) (xy 332.716366 -4.140423) (xy 332.647937 -4.192099) (xy 332.575031 -4.23724)
			(xy 332.498271 -4.275462) (xy 332.418312 -4.306438) (xy 332.335836 -4.329905) (xy 332.251546 -4.345661)
			(xy 332.166163 -4.353573) (xy 332.080413 -4.353573) (xy 331.99503 -4.345661) (xy 331.91074 -4.329905)
			(xy 331.828264 -4.306438) (xy 331.748305 -4.275462) (xy 331.671545 -4.23724) (xy 331.598639 -4.192099)
			(xy 331.53021 -4.140423) (xy 331.46684 -4.082654) (xy 331.409071 -4.019284) (xy 331.357395 -3.950855)
			(xy 331.312254 -3.877949) (xy 331.274032 -3.801189) (xy 331.243056 -3.72123) (xy 331.219589 -3.638754)
			(xy 331.203833 -3.554464) (xy 331.195921 -3.469081) (xy 326.700655 -3.469081) (xy 326.692743 -3.554464)
			(xy 326.676987 -3.638754) (xy 326.65352 -3.72123) (xy 326.622544 -3.801189) (xy 326.584322 -3.877949)
			(xy 326.539181 -3.950855) (xy 326.487505 -4.019284) (xy 326.429736 -4.082654) (xy 326.366366 -4.140423)
			(xy 326.297937 -4.192099) (xy 326.225031 -4.23724) (xy 326.148271 -4.275462) (xy 326.068312 -4.306438)
			(xy 325.985836 -4.329905) (xy 325.901546 -4.345661) (xy 325.816163 -4.353573) (xy 325.730413 -4.353573)
			(xy 325.64503 -4.345661) (xy 325.56074 -4.329905) (xy 325.478264 -4.306438) (xy 325.398305 -4.275462)
			(xy 325.321545 -4.23724) (xy 325.248639 -4.192099) (xy 325.18021 -4.140423) (xy 325.11684 -4.082654)
			(xy 325.059071 -4.019284) (xy 325.007395 -3.950855) (xy 324.962254 -3.877949) (xy 324.924032 -3.801189)
			(xy 324.893056 -3.72123) (xy 324.869589 -3.638754) (xy 324.853833 -3.554464) (xy 324.845921 -3.469081)
			(xy 265.125975 -3.469081) (xy 265.118063 -3.554464) (xy 265.102307 -3.638754) (xy 265.07884 -3.72123)
			(xy 265.047864 -3.801189) (xy 265.009642 -3.877949) (xy 264.964501 -3.950855) (xy 264.912825 -4.019284)
			(xy 264.855056 -4.082654) (xy 264.791686 -4.140423) (xy 264.723257 -4.192099) (xy 264.650351 -4.23724)
			(xy 264.573591 -4.275462) (xy 264.493632 -4.306438) (xy 264.411156 -4.329905) (xy 264.326866 -4.345661)
			(xy 264.241483 -4.353573) (xy 264.155733 -4.353573) (xy 264.07035 -4.345661) (xy 263.98606 -4.329905)
			(xy 263.903584 -4.306438) (xy 263.823625 -4.275462) (xy 263.746865 -4.23724) (xy 263.673959 -4.192099)
			(xy 263.60553 -4.140423) (xy 263.54216 -4.082654) (xy 263.484391 -4.019284) (xy 263.432715 -3.950855)
			(xy 263.387574 -3.877949) (xy 263.349352 -3.801189) (xy 263.318376 -3.72123) (xy 263.294909 -3.638754)
			(xy 263.279153 -3.554464) (xy 263.271241 -3.469081) (xy 258.775975 -3.469081) (xy 258.768063 -3.554464)
			(xy 258.752307 -3.638754) (xy 258.72884 -3.72123) (xy 258.697864 -3.801189) (xy 258.659642 -3.877949)
			(xy 258.614501 -3.950855) (xy 258.562825 -4.019284) (xy 258.505056 -4.082654) (xy 258.441686 -4.140423)
			(xy 258.373257 -4.192099) (xy 258.300351 -4.23724) (xy 258.223591 -4.275462) (xy 258.143632 -4.306438)
			(xy 258.061156 -4.329905) (xy 257.976866 -4.345661) (xy 257.891483 -4.353573) (xy 257.805733 -4.353573)
			(xy 257.72035 -4.345661) (xy 257.63606 -4.329905) (xy 257.553584 -4.306438) (xy 257.473625 -4.275462)
			(xy 257.396865 -4.23724) (xy 257.323959 -4.192099) (xy 257.25553 -4.140423) (xy 257.19216 -4.082654)
			(xy 257.134391 -4.019284) (xy 257.082715 -3.950855) (xy 257.037574 -3.877949) (xy 256.999352 -3.801189)
			(xy 256.968376 -3.72123) (xy 256.944909 -3.638754) (xy 256.929153 -3.554464) (xy 256.921241 -3.469081)
			(xy 254.465119 -3.469081) (xy 254.465087 -3.471875) (xy 254.457175 -3.557258) (xy 254.441419 -3.641548)
			(xy 254.417952 -3.724024) (xy 254.386976 -3.803983) (xy 254.348754 -3.880743) (xy 254.303613 -3.953649)
			(xy 254.251937 -4.022078) (xy 254.194168 -4.085448) (xy 254.130798 -4.143217) (xy 254.062369 -4.194893)
			(xy 253.989463 -4.240034) (xy 253.912703 -4.278256) (xy 253.832744 -4.309232) (xy 253.750268 -4.332699)
			(xy 253.665978 -4.348455) (xy 253.580595 -4.356367) (xy 253.494845 -4.356367) (xy 253.409462 -4.348455)
			(xy 253.325172 -4.332699) (xy 253.242696 -4.309232) (xy 253.162737 -4.278256) (xy 253.085977 -4.240034)
			(xy 253.013071 -4.194893) (xy 252.944642 -4.143217) (xy 252.881272 -4.085448) (xy 252.823503 -4.022078)
			(xy 252.771827 -3.953649) (xy 252.726686 -3.880743) (xy 252.688464 -3.803983) (xy 252.657488 -3.724024)
			(xy 252.634021 -3.641548) (xy 252.618265 -3.557258) (xy 252.610353 -3.471875) (xy 248.115087 -3.471875)
			(xy 248.107175 -3.557258) (xy 248.091419 -3.641548) (xy 248.067952 -3.724024) (xy 248.036976 -3.803983)
			(xy 247.998754 -3.880743) (xy 247.953613 -3.953649) (xy 247.901937 -4.022078) (xy 247.844168 -4.085448)
			(xy 247.780798 -4.143217) (xy 247.712369 -4.194893) (xy 247.639463 -4.240034) (xy 247.562703 -4.278256)
			(xy 247.482744 -4.309232) (xy 247.400268 -4.332699) (xy 247.315978 -4.348455) (xy 247.230595 -4.356367)
			(xy 247.144845 -4.356367) (xy 247.059462 -4.348455) (xy 246.975172 -4.332699) (xy 246.892696 -4.309232)
			(xy 246.812737 -4.278256) (xy 246.735977 -4.240034) (xy 246.663071 -4.194893) (xy 246.594642 -4.143217)
			(xy 246.531272 -4.085448) (xy 246.473503 -4.022078) (xy 246.421827 -3.953649) (xy 246.376686 -3.880743)
			(xy 246.338464 -3.803983) (xy 246.307488 -3.724024) (xy 246.284021 -3.641548) (xy 246.268265 -3.557258)
			(xy 246.260353 -3.471875) (xy 216.248247 -3.471875) (xy 216.240335 -3.557258) (xy 216.224579 -3.641548)
			(xy 216.201112 -3.724024) (xy 216.170136 -3.803983) (xy 216.131914 -3.880743) (xy 216.086773 -3.953649)
			(xy 216.035097 -4.022078) (xy 215.977328 -4.085448) (xy 215.913958 -4.143217) (xy 215.845529 -4.194893)
			(xy 215.772623 -4.240034) (xy 215.695863 -4.278256) (xy 215.615904 -4.309232) (xy 215.533428 -4.332699)
			(xy 215.449138 -4.348455) (xy 215.363755 -4.356367) (xy 215.278005 -4.356367) (xy 215.192622 -4.348455)
			(xy 215.108332 -4.332699) (xy 215.025856 -4.309232) (xy 214.945897 -4.278256) (xy 214.869137 -4.240034)
			(xy 214.796231 -4.194893) (xy 214.727802 -4.143217) (xy 214.664432 -4.085448) (xy 214.606663 -4.022078)
			(xy 214.554987 -3.953649) (xy 214.509846 -3.880743) (xy 214.471624 -3.803983) (xy 214.440648 -3.724024)
			(xy 214.417181 -3.641548) (xy 214.401425 -3.557258) (xy 214.393513 -3.471875) (xy 209.898247 -3.471875)
			(xy 209.890335 -3.557258) (xy 209.874579 -3.641548) (xy 209.851112 -3.724024) (xy 209.820136 -3.803983)
			(xy 209.781914 -3.880743) (xy 209.736773 -3.953649) (xy 209.685097 -4.022078) (xy 209.627328 -4.085448)
			(xy 209.563958 -4.143217) (xy 209.495529 -4.194893) (xy 209.422623 -4.240034) (xy 209.345863 -4.278256)
			(xy 209.265904 -4.309232) (xy 209.183428 -4.332699) (xy 209.099138 -4.348455) (xy 209.013755 -4.356367)
			(xy 208.928005 -4.356367) (xy 208.842622 -4.348455) (xy 208.758332 -4.332699) (xy 208.675856 -4.309232)
			(xy 208.595897 -4.278256) (xy 208.519137 -4.240034) (xy 208.446231 -4.194893) (xy 208.377802 -4.143217)
			(xy 208.314432 -4.085448) (xy 208.256663 -4.022078) (xy 208.204987 -3.953649) (xy 208.159846 -3.880743)
			(xy 208.121624 -3.803983) (xy 208.090648 -3.724024) (xy 208.067181 -3.641548) (xy 208.051425 -3.557258)
			(xy 208.043513 -3.471875) (xy 197.075741 -3.471875) (xy 197.091928 -3.518134) (xy 197.13088 -3.653342)
			(xy 197.16219 -3.790521) (xy 197.185759 -3.929239) (xy 197.201513 -4.069061) (xy 197.209403 -4.209547)
			(xy 197.209918 -4.2799) (xy 197.209918 -6.011875) (xy 208.043513 -6.011875) (xy 208.043513 -5.926125)
			(xy 208.051425 -5.840742) (xy 208.067181 -5.756452) (xy 208.090648 -5.673976) (xy 208.121624 -5.594017)
			(xy 208.159846 -5.517257) (xy 208.204987 -5.444351) (xy 208.256663 -5.375922) (xy 208.314432 -5.312552)
			(xy 208.377802 -5.254783) (xy 208.446231 -5.203107) (xy 208.519137 -5.157966) (xy 208.595897 -5.119744)
			(xy 208.675856 -5.088768) (xy 208.758332 -5.065301) (xy 208.842622 -5.049545) (xy 208.928005 -5.041633)
			(xy 209.013755 -5.041633) (xy 209.099138 -5.049545) (xy 209.183428 -5.065301) (xy 209.265904 -5.088768)
			(xy 209.345863 -5.119744) (xy 209.368066 -5.1308) (xy 212.978492 -5.1308) (xy 212.978492 -4.2672)
			(xy 212.978978 -4.239931) (xy 212.98674 -4.185947) (xy 213.002105 -4.133617) (xy 213.024762 -4.084007)
			(xy 213.054248 -4.038126) (xy 213.089963 -3.996909) (xy 213.13118 -3.961194) (xy 213.177061 -3.931708)
			(xy 213.226671 -3.909051) (xy 213.279001 -3.893686) (xy 213.332985 -3.885924) (xy 213.387523 -3.885924)
			(xy 213.441507 -3.893686) (xy 213.493837 -3.909051) (xy 213.543447 -3.931708) (xy 213.589328 -3.961194)
			(xy 213.630545 -3.996909) (xy 213.66626 -4.038126) (xy 213.695746 -4.084007) (xy 213.718403 -4.133617)
			(xy 213.733768 -4.185947) (xy 213.74153 -4.239931) (xy 213.742016 -4.2672) (xy 213.742016 -5.1308)
			(xy 213.74153 -5.158069) (xy 213.733768 -5.212053) (xy 213.718403 -5.264383) (xy 213.695746 -5.313993)
			(xy 213.66626 -5.359874) (xy 213.630545 -5.401091) (xy 213.589328 -5.436806) (xy 213.543447 -5.466292)
			(xy 213.493837 -5.488949) (xy 213.441507 -5.504314) (xy 213.387523 -5.512076) (xy 213.332985 -5.512076)
			(xy 213.279001 -5.504314) (xy 213.226671 -5.488949) (xy 213.177061 -5.466292) (xy 213.13118 -5.436806)
			(xy 213.089963 -5.401091) (xy 213.054248 -5.359874) (xy 213.024762 -5.313993) (xy 213.002105 -5.264383)
			(xy 212.98674 -5.212053) (xy 212.978978 -5.158069) (xy 212.978492 -5.1308) (xy 209.368066 -5.1308)
			(xy 209.422623 -5.157966) (xy 209.495529 -5.203107) (xy 209.563958 -5.254783) (xy 209.627328 -5.312552)
			(xy 209.685097 -5.375922) (xy 209.736773 -5.444351) (xy 209.781914 -5.517257) (xy 209.820136 -5.594017)
			(xy 209.851112 -5.673976) (xy 209.874579 -5.756452) (xy 209.890335 -5.840742) (xy 209.898247 -5.926125)
			(xy 209.898742 -5.969) (xy 209.898247 -6.011875) (xy 214.393513 -6.011875) (xy 214.393513 -5.926125)
			(xy 214.401425 -5.840742) (xy 214.417181 -5.756452) (xy 214.440648 -5.673976) (xy 214.471624 -5.594017)
			(xy 214.509846 -5.517257) (xy 214.554987 -5.444351) (xy 214.606663 -5.375922) (xy 214.664432 -5.312552)
			(xy 214.727802 -5.254783) (xy 214.796231 -5.203107) (xy 214.869137 -5.157966) (xy 214.945897 -5.119744)
			(xy 215.025856 -5.088768) (xy 215.108332 -5.065301) (xy 215.192622 -5.049545) (xy 215.278005 -5.041633)
			(xy 215.363755 -5.041633) (xy 215.449138 -5.049545) (xy 215.533428 -5.065301) (xy 215.615904 -5.088768)
			(xy 215.695863 -5.119744) (xy 215.772623 -5.157966) (xy 215.845529 -5.203107) (xy 215.913958 -5.254783)
			(xy 215.977328 -5.312552) (xy 216.035097 -5.375922) (xy 216.086773 -5.444351) (xy 216.131914 -5.517257)
			(xy 216.170136 -5.594017) (xy 216.201112 -5.673976) (xy 216.224579 -5.756452) (xy 216.240335 -5.840742)
			(xy 216.248247 -5.926125) (xy 216.248742 -5.969) (xy 216.248247 -6.011875) (xy 246.260353 -6.011875)
			(xy 246.260353 -5.926125) (xy 246.268265 -5.840742) (xy 246.284021 -5.756452) (xy 246.307488 -5.673976)
			(xy 246.338464 -5.594017) (xy 246.376686 -5.517257) (xy 246.421827 -5.444351) (xy 246.473503 -5.375922)
			(xy 246.531272 -5.312552) (xy 246.594642 -5.254783) (xy 246.663071 -5.203107) (xy 246.735977 -5.157966)
			(xy 246.812737 -5.119744) (xy 246.892696 -5.088768) (xy 246.975172 -5.065301) (xy 247.059462 -5.049545)
			(xy 247.144845 -5.041633) (xy 247.230595 -5.041633) (xy 247.315978 -5.049545) (xy 247.400268 -5.065301)
			(xy 247.482744 -5.088768) (xy 247.562703 -5.119744) (xy 247.584906 -5.1308) (xy 248.766584 -5.1308)
			(xy 248.766584 -4.2672) (xy 248.76707 -4.239931) (xy 248.774832 -4.185947) (xy 248.790197 -4.133617)
			(xy 248.812854 -4.084007) (xy 248.84234 -4.038126) (xy 248.878055 -3.996909) (xy 248.919272 -3.961194)
			(xy 248.965153 -3.931708) (xy 249.014763 -3.909051) (xy 249.067093 -3.893686) (xy 249.121077 -3.885924)
			(xy 249.175615 -3.885924) (xy 249.229599 -3.893686) (xy 249.281929 -3.909051) (xy 249.331539 -3.931708)
			(xy 249.37742 -3.961194) (xy 249.418637 -3.996909) (xy 249.454352 -4.038126) (xy 249.483838 -4.084007)
			(xy 249.506495 -4.133617) (xy 249.52186 -4.185947) (xy 249.529622 -4.239931) (xy 249.530108 -4.2672)
			(xy 249.530108 -5.1308) (xy 249.529622 -5.158069) (xy 249.52186 -5.212053) (xy 249.506495 -5.264383)
			(xy 249.483838 -5.313993) (xy 249.454352 -5.359874) (xy 249.418637 -5.401091) (xy 249.37742 -5.436806)
			(xy 249.331539 -5.466292) (xy 249.281929 -5.488949) (xy 249.229599 -5.504314) (xy 249.175615 -5.512076)
			(xy 249.121077 -5.512076) (xy 249.067093 -5.504314) (xy 249.014763 -5.488949) (xy 248.965153 -5.466292)
			(xy 248.919272 -5.436806) (xy 248.878055 -5.401091) (xy 248.84234 -5.359874) (xy 248.812854 -5.313993)
			(xy 248.790197 -5.264383) (xy 248.774832 -5.212053) (xy 248.76707 -5.158069) (xy 248.766584 -5.1308)
			(xy 247.584906 -5.1308) (xy 247.639463 -5.157966) (xy 247.712369 -5.203107) (xy 247.780798 -5.254783)
			(xy 247.844168 -5.312552) (xy 247.901937 -5.375922) (xy 247.953613 -5.444351) (xy 247.998754 -5.517257)
			(xy 248.036976 -5.594017) (xy 248.067952 -5.673976) (xy 248.091419 -5.756452) (xy 248.107175 -5.840742)
			(xy 248.115087 -5.926125) (xy 248.115582 -5.969) (xy 248.115087 -6.011875) (xy 252.610353 -6.011875)
			(xy 252.610353 -5.926125) (xy 252.618265 -5.840742) (xy 252.634021 -5.756452) (xy 252.657488 -5.673976)
			(xy 252.688464 -5.594017) (xy 252.726686 -5.517257) (xy 252.771827 -5.444351) (xy 252.823503 -5.375922)
			(xy 252.881272 -5.312552) (xy 252.944642 -5.254783) (xy 253.013071 -5.203107) (xy 253.085977 -5.157966)
			(xy 253.162737 -5.119744) (xy 253.242696 -5.088768) (xy 253.325172 -5.065301) (xy 253.409462 -5.049545)
			(xy 253.494845 -5.041633) (xy 253.580595 -5.041633) (xy 253.665978 -5.049545) (xy 253.750268 -5.065301)
			(xy 253.832744 -5.088768) (xy 253.912703 -5.119744) (xy 253.989463 -5.157966) (xy 254.062369 -5.203107)
			(xy 254.130798 -5.254783) (xy 254.194168 -5.312552) (xy 254.251937 -5.375922) (xy 254.303613 -5.444351)
			(xy 254.348754 -5.517257) (xy 254.386976 -5.594017) (xy 254.417952 -5.673976) (xy 254.441419 -5.756452)
			(xy 254.457175 -5.840742) (xy 254.465087 -5.926125) (xy 254.465582 -5.969) (xy 254.465119 -6.009081)
			(xy 256.921241 -6.009081) (xy 256.921241 -5.923331) (xy 256.929153 -5.837948) (xy 256.944909 -5.753658)
			(xy 256.968376 -5.671182) (xy 256.999352 -5.591223) (xy 257.037574 -5.514463) (xy 257.082715 -5.441557)
			(xy 257.134391 -5.373128) (xy 257.19216 -5.309758) (xy 257.25553 -5.251989) (xy 257.323959 -5.200313)
			(xy 257.396865 -5.155172) (xy 257.473625 -5.11695) (xy 257.553584 -5.085974) (xy 257.63606 -5.062507)
			(xy 257.72035 -5.046751) (xy 257.805733 -5.038839) (xy 257.891483 -5.038839) (xy 257.976866 -5.046751)
			(xy 258.061156 -5.062507) (xy 258.143632 -5.085974) (xy 258.223591 -5.11695) (xy 258.300351 -5.155172)
			(xy 258.373257 -5.200313) (xy 258.441686 -5.251989) (xy 258.505056 -5.309758) (xy 258.562825 -5.373128)
			(xy 258.614501 -5.441557) (xy 258.659642 -5.514463) (xy 258.697864 -5.591223) (xy 258.72884 -5.671182)
			(xy 258.752307 -5.753658) (xy 258.768063 -5.837948) (xy 258.775975 -5.923331) (xy 258.77647 -5.966206)
			(xy 258.775975 -6.009081) (xy 263.271241 -6.009081) (xy 263.271241 -5.923331) (xy 263.279153 -5.837948)
			(xy 263.294909 -5.753658) (xy 263.318376 -5.671182) (xy 263.349352 -5.591223) (xy 263.387574 -5.514463)
			(xy 263.432715 -5.441557) (xy 263.484391 -5.373128) (xy 263.54216 -5.309758) (xy 263.60553 -5.251989)
			(xy 263.673959 -5.200313) (xy 263.746865 -5.155172) (xy 263.823625 -5.11695) (xy 263.903584 -5.085974)
			(xy 263.98606 -5.062507) (xy 264.07035 -5.046751) (xy 264.155733 -5.038839) (xy 264.241483 -5.038839)
			(xy 264.326866 -5.046751) (xy 264.411156 -5.062507) (xy 264.493632 -5.085974) (xy 264.573591 -5.11695)
			(xy 264.650351 -5.155172) (xy 264.723257 -5.200313) (xy 264.791686 -5.251989) (xy 264.855056 -5.309758)
			(xy 264.912825 -5.373128) (xy 264.964501 -5.441557) (xy 265.009642 -5.514463) (xy 265.047864 -5.591223)
			(xy 265.07884 -5.671182) (xy 265.102307 -5.753658) (xy 265.118063 -5.837948) (xy 265.125975 -5.923331)
			(xy 265.12647 -5.966206) (xy 265.125975 -6.009081) (xy 324.845921 -6.009081) (xy 324.845921 -5.923331)
			(xy 324.853833 -5.837948) (xy 324.869589 -5.753658) (xy 324.893056 -5.671182) (xy 324.924032 -5.591223)
			(xy 324.962254 -5.514463) (xy 325.007395 -5.441557) (xy 325.059071 -5.373128) (xy 325.11684 -5.309758)
			(xy 325.18021 -5.251989) (xy 325.248639 -5.200313) (xy 325.321545 -5.155172) (xy 325.398305 -5.11695)
			(xy 325.478264 -5.085974) (xy 325.56074 -5.062507) (xy 325.64503 -5.046751) (xy 325.730413 -5.038839)
			(xy 325.816163 -5.038839) (xy 325.901546 -5.046751) (xy 325.985836 -5.062507) (xy 326.068312 -5.085974)
			(xy 326.148271 -5.11695) (xy 326.225031 -5.155172) (xy 326.297937 -5.200313) (xy 326.366366 -5.251989)
			(xy 326.429736 -5.309758) (xy 326.487505 -5.373128) (xy 326.539181 -5.441557) (xy 326.584322 -5.514463)
			(xy 326.622544 -5.591223) (xy 326.65352 -5.671182) (xy 326.676987 -5.753658) (xy 326.692743 -5.837948)
			(xy 326.700655 -5.923331) (xy 326.70115 -5.966206) (xy 326.700655 -6.009081) (xy 331.195921 -6.009081)
			(xy 331.195921 -5.923331) (xy 331.203833 -5.837948) (xy 331.219589 -5.753658) (xy 331.243056 -5.671182)
			(xy 331.274032 -5.591223) (xy 331.312254 -5.514463) (xy 331.357395 -5.441557) (xy 331.409071 -5.373128)
			(xy 331.46684 -5.309758) (xy 331.53021 -5.251989) (xy 331.598639 -5.200313) (xy 331.671545 -5.155172)
			(xy 331.748305 -5.11695) (xy 331.828264 -5.085974) (xy 331.91074 -5.062507) (xy 331.99503 -5.046751)
			(xy 332.080413 -5.038839) (xy 332.166163 -5.038839) (xy 332.251546 -5.046751) (xy 332.335836 -5.062507)
			(xy 332.418312 -5.085974) (xy 332.498271 -5.11695) (xy 332.575031 -5.155172) (xy 332.647937 -5.200313)
			(xy 332.716366 -5.251989) (xy 332.779736 -5.309758) (xy 332.837505 -5.373128) (xy 332.889181 -5.441557)
			(xy 332.934322 -5.514463) (xy 332.972544 -5.591223) (xy 333.00352 -5.671182) (xy 333.026987 -5.753658)
			(xy 333.042743 -5.837948) (xy 333.050655 -5.923331) (xy 333.05115 -5.966206) (xy 333.050655 -6.009081)
			(xy 335.488267 -6.009081) (xy 335.488267 -5.923331) (xy 335.496179 -5.837948) (xy 335.511935 -5.753658)
			(xy 335.535402 -5.671182) (xy 335.566378 -5.591223) (xy 335.6046 -5.514463) (xy 335.649741 -5.441557)
			(xy 335.701417 -5.373128) (xy 335.759186 -5.309758) (xy 335.822556 -5.251989) (xy 335.890985 -5.200313)
			(xy 335.963891 -5.155172) (xy 336.040651 -5.11695) (xy 336.12061 -5.085974) (xy 336.203086 -5.062507)
			(xy 336.287376 -5.046751) (xy 336.372759 -5.038839) (xy 336.458509 -5.038839) (xy 336.543892 -5.046751)
			(xy 336.628182 -5.062507) (xy 336.710658 -5.085974) (xy 336.790617 -5.11695) (xy 336.867377 -5.155172)
			(xy 336.940283 -5.200313) (xy 337.008712 -5.251989) (xy 337.072082 -5.309758) (xy 337.129851 -5.373128)
			(xy 337.181527 -5.441557) (xy 337.226668 -5.514463) (xy 337.26489 -5.591223) (xy 337.295866 -5.671182)
			(xy 337.319333 -5.753658) (xy 337.335089 -5.837948) (xy 337.343001 -5.923331) (xy 337.343496 -5.966206)
			(xy 337.343001 -6.009081) (xy 341.838267 -6.009081) (xy 341.838267 -5.923331) (xy 341.846179 -5.837948)
			(xy 341.861935 -5.753658) (xy 341.885402 -5.671182) (xy 341.916378 -5.591223) (xy 341.9546 -5.514463)
			(xy 341.999741 -5.441557) (xy 342.051417 -5.373128) (xy 342.109186 -5.309758) (xy 342.172556 -5.251989)
			(xy 342.240985 -5.200313) (xy 342.313891 -5.155172) (xy 342.390651 -5.11695) (xy 342.47061 -5.085974)
			(xy 342.553086 -5.062507) (xy 342.637376 -5.046751) (xy 342.722759 -5.038839) (xy 342.808509 -5.038839)
			(xy 342.893892 -5.046751) (xy 342.978182 -5.062507) (xy 343.060658 -5.085974) (xy 343.140617 -5.11695)
			(xy 343.217377 -5.155172) (xy 343.290283 -5.200313) (xy 343.358712 -5.251989) (xy 343.422082 -5.309758)
			(xy 343.479851 -5.373128) (xy 343.531527 -5.441557) (xy 343.576668 -5.514463) (xy 343.61489 -5.591223)
			(xy 343.645866 -5.671182) (xy 343.669333 -5.753658) (xy 343.685089 -5.837948) (xy 343.693001 -5.923331)
			(xy 343.693496 -5.966206) (xy 343.693001 -6.009081) (xy 373.705107 -6.009081) (xy 373.705107 -5.923331)
			(xy 373.713019 -5.837948) (xy 373.728775 -5.753658) (xy 373.752242 -5.671182) (xy 373.783218 -5.591223)
			(xy 373.82144 -5.514463) (xy 373.866581 -5.441557) (xy 373.918257 -5.373128) (xy 373.976026 -5.309758)
			(xy 374.039396 -5.251989) (xy 374.107825 -5.200313) (xy 374.180731 -5.155172) (xy 374.257491 -5.11695)
			(xy 374.33745 -5.085974) (xy 374.419926 -5.062507) (xy 374.504216 -5.046751) (xy 374.589599 -5.038839)
			(xy 374.675349 -5.038839) (xy 374.760732 -5.046751) (xy 374.845022 -5.062507) (xy 374.927498 -5.085974)
			(xy 375.007457 -5.11695) (xy 375.084217 -5.155172) (xy 375.157123 -5.200313) (xy 375.225552 -5.251989)
			(xy 375.288922 -5.309758) (xy 375.346691 -5.373128) (xy 375.398367 -5.441557) (xy 375.443508 -5.514463)
			(xy 375.48173 -5.591223) (xy 375.512706 -5.671182) (xy 375.536173 -5.753658) (xy 375.551929 -5.837948)
			(xy 375.559841 -5.923331) (xy 375.560336 -5.966206) (xy 375.559841 -6.009081) (xy 380.055107 -6.009081)
			(xy 380.055107 -5.923331) (xy 380.063019 -5.837948) (xy 380.078775 -5.753658) (xy 380.102242 -5.671182)
			(xy 380.133218 -5.591223) (xy 380.17144 -5.514463) (xy 380.216581 -5.441557) (xy 380.268257 -5.373128)
			(xy 380.326026 -5.309758) (xy 380.389396 -5.251989) (xy 380.457825 -5.200313) (xy 380.530731 -5.155172)
			(xy 380.607491 -5.11695) (xy 380.68745 -5.085974) (xy 380.769926 -5.062507) (xy 380.854216 -5.046751)
			(xy 380.939599 -5.038839) (xy 381.025349 -5.038839) (xy 381.110732 -5.046751) (xy 381.195022 -5.062507)
			(xy 381.277498 -5.085974) (xy 381.357457 -5.11695) (xy 381.434217 -5.155172) (xy 381.507123 -5.200313)
			(xy 381.575552 -5.251989) (xy 381.638922 -5.309758) (xy 381.696691 -5.373128) (xy 381.748367 -5.441557)
			(xy 381.793508 -5.514463) (xy 381.83173 -5.591223) (xy 381.862706 -5.671182) (xy 381.886173 -5.753658)
			(xy 381.901929 -5.837948) (xy 381.909841 -5.923331) (xy 381.910336 -5.966206) (xy 381.909841 -6.009081)
			(xy 381.901929 -6.094464) (xy 381.886173 -6.178754) (xy 381.862706 -6.26123) (xy 381.83173 -6.341189)
			(xy 381.793508 -6.417949) (xy 381.748367 -6.490855) (xy 381.696691 -6.559284) (xy 381.638922 -6.622654)
			(xy 381.575552 -6.680423) (xy 381.507123 -6.732099) (xy 381.434217 -6.77724) (xy 381.357457 -6.815462)
			(xy 381.277498 -6.846438) (xy 381.195022 -6.869905) (xy 381.110732 -6.885661) (xy 381.025349 -6.893573)
			(xy 380.939599 -6.893573) (xy 380.854216 -6.885661) (xy 380.769926 -6.869905) (xy 380.68745 -6.846438)
			(xy 380.607491 -6.815462) (xy 380.530731 -6.77724) (xy 380.457825 -6.732099) (xy 380.389396 -6.680423)
			(xy 380.326026 -6.622654) (xy 380.268257 -6.559284) (xy 380.216581 -6.490855) (xy 380.17144 -6.417949)
			(xy 380.133218 -6.341189) (xy 380.102242 -6.26123) (xy 380.078775 -6.178754) (xy 380.063019 -6.094464)
			(xy 380.055107 -6.009081) (xy 375.559841 -6.009081) (xy 375.551929 -6.094464) (xy 375.536173 -6.178754)
			(xy 375.512706 -6.26123) (xy 375.48173 -6.341189) (xy 375.443508 -6.417949) (xy 375.398367 -6.490855)
			(xy 375.346691 -6.559284) (xy 375.288922 -6.622654) (xy 375.225552 -6.680423) (xy 375.157123 -6.732099)
			(xy 375.084217 -6.77724) (xy 375.007457 -6.815462) (xy 374.927498 -6.846438) (xy 374.845022 -6.869905)
			(xy 374.760732 -6.885661) (xy 374.675349 -6.893573) (xy 374.589599 -6.893573) (xy 374.504216 -6.885661)
			(xy 374.419926 -6.869905) (xy 374.33745 -6.846438) (xy 374.257491 -6.815462) (xy 374.180731 -6.77724)
			(xy 374.107825 -6.732099) (xy 374.039396 -6.680423) (xy 373.976026 -6.622654) (xy 373.918257 -6.559284)
			(xy 373.866581 -6.490855) (xy 373.82144 -6.417949) (xy 373.783218 -6.341189) (xy 373.752242 -6.26123)
			(xy 373.728775 -6.178754) (xy 373.713019 -6.094464) (xy 373.705107 -6.009081) (xy 343.693001 -6.009081)
			(xy 343.685089 -6.094464) (xy 343.669333 -6.178754) (xy 343.645866 -6.26123) (xy 343.61489 -6.341189)
			(xy 343.576668 -6.417949) (xy 343.531527 -6.490855) (xy 343.479851 -6.559284) (xy 343.422082 -6.622654)
			(xy 343.358712 -6.680423) (xy 343.290283 -6.732099) (xy 343.217377 -6.77724) (xy 343.140617 -6.815462)
			(xy 343.060658 -6.846438) (xy 342.978182 -6.869905) (xy 342.893892 -6.885661) (xy 342.808509 -6.893573)
			(xy 342.722759 -6.893573) (xy 342.637376 -6.885661) (xy 342.553086 -6.869905) (xy 342.47061 -6.846438)
			(xy 342.390651 -6.815462) (xy 342.313891 -6.77724) (xy 342.240985 -6.732099) (xy 342.172556 -6.680423)
			(xy 342.109186 -6.622654) (xy 342.051417 -6.559284) (xy 341.999741 -6.490855) (xy 341.9546 -6.417949)
			(xy 341.916378 -6.341189) (xy 341.885402 -6.26123) (xy 341.861935 -6.178754) (xy 341.846179 -6.094464)
			(xy 341.838267 -6.009081) (xy 337.343001 -6.009081) (xy 337.335089 -6.094464) (xy 337.319333 -6.178754)
			(xy 337.295866 -6.26123) (xy 337.26489 -6.341189) (xy 337.226668 -6.417949) (xy 337.181527 -6.490855)
			(xy 337.129851 -6.559284) (xy 337.072082 -6.622654) (xy 337.008712 -6.680423) (xy 336.940283 -6.732099)
			(xy 336.867377 -6.77724) (xy 336.790617 -6.815462) (xy 336.710658 -6.846438) (xy 336.628182 -6.869905)
			(xy 336.543892 -6.885661) (xy 336.458509 -6.893573) (xy 336.372759 -6.893573) (xy 336.287376 -6.885661)
			(xy 336.203086 -6.869905) (xy 336.12061 -6.846438) (xy 336.040651 -6.815462) (xy 335.963891 -6.77724)
			(xy 335.890985 -6.732099) (xy 335.822556 -6.680423) (xy 335.759186 -6.622654) (xy 335.701417 -6.559284)
			(xy 335.649741 -6.490855) (xy 335.6046 -6.417949) (xy 335.566378 -6.341189) (xy 335.535402 -6.26123)
			(xy 335.511935 -6.178754) (xy 335.496179 -6.094464) (xy 335.488267 -6.009081) (xy 333.050655 -6.009081)
			(xy 333.042743 -6.094464) (xy 333.026987 -6.178754) (xy 333.00352 -6.26123) (xy 332.972544 -6.341189)
			(xy 332.934322 -6.417949) (xy 332.889181 -6.490855) (xy 332.837505 -6.559284) (xy 332.779736 -6.622654)
			(xy 332.716366 -6.680423) (xy 332.647937 -6.732099) (xy 332.575031 -6.77724) (xy 332.498271 -6.815462)
			(xy 332.418312 -6.846438) (xy 332.335836 -6.869905) (xy 332.251546 -6.885661) (xy 332.166163 -6.893573)
			(xy 332.080413 -6.893573) (xy 331.99503 -6.885661) (xy 331.91074 -6.869905) (xy 331.828264 -6.846438)
			(xy 331.748305 -6.815462) (xy 331.671545 -6.77724) (xy 331.598639 -6.732099) (xy 331.53021 -6.680423)
			(xy 331.46684 -6.622654) (xy 331.409071 -6.559284) (xy 331.357395 -6.490855) (xy 331.312254 -6.417949)
			(xy 331.274032 -6.341189) (xy 331.243056 -6.26123) (xy 331.219589 -6.178754) (xy 331.203833 -6.094464)
			(xy 331.195921 -6.009081) (xy 326.700655 -6.009081) (xy 326.692743 -6.094464) (xy 326.676987 -6.178754)
			(xy 326.65352 -6.26123) (xy 326.622544 -6.341189) (xy 326.584322 -6.417949) (xy 326.539181 -6.490855)
			(xy 326.487505 -6.559284) (xy 326.429736 -6.622654) (xy 326.366366 -6.680423) (xy 326.297937 -6.732099)
			(xy 326.225031 -6.77724) (xy 326.148271 -6.815462) (xy 326.068312 -6.846438) (xy 325.985836 -6.869905)
			(xy 325.901546 -6.885661) (xy 325.816163 -6.893573) (xy 325.730413 -6.893573) (xy 325.64503 -6.885661)
			(xy 325.56074 -6.869905) (xy 325.478264 -6.846438) (xy 325.398305 -6.815462) (xy 325.321545 -6.77724)
			(xy 325.248639 -6.732099) (xy 325.18021 -6.680423) (xy 325.11684 -6.622654) (xy 325.059071 -6.559284)
			(xy 325.007395 -6.490855) (xy 324.962254 -6.417949) (xy 324.924032 -6.341189) (xy 324.893056 -6.26123)
			(xy 324.869589 -6.178754) (xy 324.853833 -6.094464) (xy 324.845921 -6.009081) (xy 265.125975 -6.009081)
			(xy 265.118063 -6.094464) (xy 265.102307 -6.178754) (xy 265.07884 -6.26123) (xy 265.047864 -6.341189)
			(xy 265.009642 -6.417949) (xy 264.964501 -6.490855) (xy 264.912825 -6.559284) (xy 264.855056 -6.622654)
			(xy 264.791686 -6.680423) (xy 264.723257 -6.732099) (xy 264.650351 -6.77724) (xy 264.573591 -6.815462)
			(xy 264.493632 -6.846438) (xy 264.411156 -6.869905) (xy 264.326866 -6.885661) (xy 264.241483 -6.893573)
			(xy 264.155733 -6.893573) (xy 264.07035 -6.885661) (xy 263.98606 -6.869905) (xy 263.903584 -6.846438)
			(xy 263.823625 -6.815462) (xy 263.746865 -6.77724) (xy 263.673959 -6.732099) (xy 263.60553 -6.680423)
			(xy 263.54216 -6.622654) (xy 263.484391 -6.559284) (xy 263.432715 -6.490855) (xy 263.387574 -6.417949)
			(xy 263.349352 -6.341189) (xy 263.318376 -6.26123) (xy 263.294909 -6.178754) (xy 263.279153 -6.094464)
			(xy 263.271241 -6.009081) (xy 258.775975 -6.009081) (xy 258.768063 -6.094464) (xy 258.752307 -6.178754)
			(xy 258.72884 -6.26123) (xy 258.697864 -6.341189) (xy 258.659642 -6.417949) (xy 258.614501 -6.490855)
			(xy 258.562825 -6.559284) (xy 258.505056 -6.622654) (xy 258.441686 -6.680423) (xy 258.373257 -6.732099)
			(xy 258.300351 -6.77724) (xy 258.223591 -6.815462) (xy 258.143632 -6.846438) (xy 258.061156 -6.869905)
			(xy 257.976866 -6.885661) (xy 257.891483 -6.893573) (xy 257.805733 -6.893573) (xy 257.72035 -6.885661)
			(xy 257.63606 -6.869905) (xy 257.553584 -6.846438) (xy 257.473625 -6.815462) (xy 257.396865 -6.77724)
			(xy 257.323959 -6.732099) (xy 257.25553 -6.680423) (xy 257.19216 -6.622654) (xy 257.134391 -6.559284)
			(xy 257.082715 -6.490855) (xy 257.037574 -6.417949) (xy 256.999352 -6.341189) (xy 256.968376 -6.26123)
			(xy 256.944909 -6.178754) (xy 256.929153 -6.094464) (xy 256.921241 -6.009081) (xy 254.465119 -6.009081)
			(xy 254.465087 -6.011875) (xy 254.457175 -6.097258) (xy 254.441419 -6.181548) (xy 254.417952 -6.264024)
			(xy 254.386976 -6.343983) (xy 254.348754 -6.420743) (xy 254.303613 -6.493649) (xy 254.251937 -6.562078)
			(xy 254.194168 -6.625448) (xy 254.130798 -6.683217) (xy 254.062369 -6.734893) (xy 253.989463 -6.780034)
			(xy 253.912703 -6.818256) (xy 253.832744 -6.849232) (xy 253.750268 -6.872699) (xy 253.665978 -6.888455)
			(xy 253.580595 -6.896367) (xy 253.494845 -6.896367) (xy 253.409462 -6.888455) (xy 253.325172 -6.872699)
			(xy 253.242696 -6.849232) (xy 253.162737 -6.818256) (xy 253.085977 -6.780034) (xy 253.013071 -6.734893)
			(xy 252.944642 -6.683217) (xy 252.881272 -6.625448) (xy 252.823503 -6.562078) (xy 252.771827 -6.493649)
			(xy 252.726686 -6.420743) (xy 252.688464 -6.343983) (xy 252.657488 -6.264024) (xy 252.634021 -6.181548)
			(xy 252.618265 -6.097258) (xy 252.610353 -6.011875) (xy 248.115087 -6.011875) (xy 248.107175 -6.097258)
			(xy 248.091419 -6.181548) (xy 248.067952 -6.264024) (xy 248.036976 -6.343983) (xy 247.998754 -6.420743)
			(xy 247.953613 -6.493649) (xy 247.901937 -6.562078) (xy 247.844168 -6.625448) (xy 247.780798 -6.683217)
			(xy 247.712369 -6.734893) (xy 247.639463 -6.780034) (xy 247.562703 -6.818256) (xy 247.482744 -6.849232)
			(xy 247.400268 -6.872699) (xy 247.315978 -6.888455) (xy 247.230595 -6.896367) (xy 247.144845 -6.896367)
			(xy 247.059462 -6.888455) (xy 246.975172 -6.872699) (xy 246.892696 -6.849232) (xy 246.812737 -6.818256)
			(xy 246.735977 -6.780034) (xy 246.663071 -6.734893) (xy 246.594642 -6.683217) (xy 246.531272 -6.625448)
			(xy 246.473503 -6.562078) (xy 246.421827 -6.493649) (xy 246.376686 -6.420743) (xy 246.338464 -6.343983)
			(xy 246.307488 -6.264024) (xy 246.284021 -6.181548) (xy 246.268265 -6.097258) (xy 246.260353 -6.011875)
			(xy 216.248247 -6.011875) (xy 216.240335 -6.097258) (xy 216.224579 -6.181548) (xy 216.201112 -6.264024)
			(xy 216.170136 -6.343983) (xy 216.131914 -6.420743) (xy 216.086773 -6.493649) (xy 216.035097 -6.562078)
			(xy 215.977328 -6.625448) (xy 215.913958 -6.683217) (xy 215.845529 -6.734893) (xy 215.772623 -6.780034)
			(xy 215.695863 -6.818256) (xy 215.615904 -6.849232) (xy 215.533428 -6.872699) (xy 215.449138 -6.888455)
			(xy 215.363755 -6.896367) (xy 215.278005 -6.896367) (xy 215.192622 -6.888455) (xy 215.108332 -6.872699)
			(xy 215.025856 -6.849232) (xy 214.945897 -6.818256) (xy 214.869137 -6.780034) (xy 214.796231 -6.734893)
			(xy 214.727802 -6.683217) (xy 214.664432 -6.625448) (xy 214.606663 -6.562078) (xy 214.554987 -6.493649)
			(xy 214.509846 -6.420743) (xy 214.471624 -6.343983) (xy 214.440648 -6.264024) (xy 214.417181 -6.181548)
			(xy 214.401425 -6.097258) (xy 214.393513 -6.011875) (xy 209.898247 -6.011875) (xy 209.890335 -6.097258)
			(xy 209.874579 -6.181548) (xy 209.851112 -6.264024) (xy 209.820136 -6.343983) (xy 209.781914 -6.420743)
			(xy 209.736773 -6.493649) (xy 209.685097 -6.562078) (xy 209.627328 -6.625448) (xy 209.563958 -6.683217)
			(xy 209.495529 -6.734893) (xy 209.422623 -6.780034) (xy 209.345863 -6.818256) (xy 209.265904 -6.849232)
			(xy 209.183428 -6.872699) (xy 209.099138 -6.888455) (xy 209.013755 -6.896367) (xy 208.928005 -6.896367)
			(xy 208.842622 -6.888455) (xy 208.758332 -6.872699) (xy 208.675856 -6.849232) (xy 208.595897 -6.818256)
			(xy 208.519137 -6.780034) (xy 208.446231 -6.734893) (xy 208.377802 -6.683217) (xy 208.314432 -6.625448)
			(xy 208.256663 -6.562078) (xy 208.204987 -6.493649) (xy 208.159846 -6.420743) (xy 208.121624 -6.343983)
			(xy 208.090648 -6.264024) (xy 208.067181 -6.181548) (xy 208.051425 -6.097258) (xy 208.043513 -6.011875)
			(xy 197.209918 -6.011875) (xy 197.209918 -7.78002) (xy 197.21044 -7.835826) (xy 197.218783 -7.947127)
			(xy 197.235419 -8.057493) (xy 197.260257 -8.166307) (xy 197.293157 -8.27296) (xy 197.333935 -8.376857)
			(xy 197.382363 -8.477416) (xy 197.43817 -8.574075) (xy 197.501045 -8.666293) (xy 197.570635 -8.753555)
			(xy 197.646552 -8.835372) (xy 197.728371 -8.911287) (xy 197.815634 -8.980875) (xy 197.907854 -9.043748)
			(xy 198.004514 -9.099553) (xy 198.105074 -9.147979) (xy 198.208972 -9.188755) (xy 198.315626 -9.221652)
			(xy 198.424441 -9.246487) (xy 198.534807 -9.263121) (xy 198.646108 -9.271461) (xy 198.701914 -9.272016)
			(xy 223.300036 -9.272016) (xy 223.370389 -9.27251) (xy 223.510873 -9.280402) (xy 223.650694 -9.296158)
			(xy 223.789412 -9.319729) (xy 223.92659 -9.35104) (xy 224.061796 -9.389995) (xy 224.194606 -9.436468)
			(xy 224.3246 -9.490316) (xy 224.451371 -9.551367) (xy 224.57452 -9.619431) (xy 224.693658 -9.694292)
			(xy 224.808411 -9.775716) (xy 224.918419 -9.863446) (xy 225.023334 -9.957206) (xy 225.122827 -10.056701)
			(xy 225.216585 -10.161618) (xy 225.304313 -10.271627) (xy 225.385734 -10.386382) (xy 225.460594 -10.505522)
			(xy 225.528655 -10.628671) (xy 225.589704 -10.755444) (xy 225.643549 -10.885439) (xy 225.69002 -11.01825)
			(xy 225.728972 -11.153457) (xy 225.760281 -11.290635) (xy 225.783849 -11.429353) (xy 225.799602 -11.569174)
			(xy 225.807491 -11.709659) (xy 225.808032 -11.780012) (xy 225.808032 -31.197296) (xy 227.377752 -32.767016)
			(xy 254.645668 -32.767016)
		)
		(stroke
			(width 0)
			(type solid)
		)
		(fill yes)
		(layer "In9.Cu")
		(net "DELTA_L_GND_1")
	)
	(gr_poly
		(pts
			(xy 58.144156 -440.42203) (xy 58.148885 -440.390461) (xy 58.165188 -440.328742) (xy 58.189058 -440.269538)
			(xy 58.220124 -440.213771) (xy 58.257901 -440.162313) (xy 58.301798 -440.115967) (xy 58.351131 -440.075455)
			(xy 58.40513 -440.04141) (xy 58.462953 -440.014364) (xy 58.523697 -439.994738) (xy 58.586413 -439.982838)
			(xy 58.650124 -439.978851) (xy 58.713835 -439.982838) (xy 58.776551 -439.994738) (xy 58.837295 -440.014364)
			(xy 58.895118 -440.04141) (xy 58.949117 -440.075455) (xy 58.99845 -440.115967) (xy 59.042347 -440.162313)
			(xy 59.080124 -440.213771) (xy 59.11119 -440.269538) (xy 59.13506 -440.328742) (xy 59.151363 -440.390461)
			(xy 59.156092 -440.42203) (xy 59.161934 -440.465972) (xy 62.138306 -440.465972) (xy 62.144148 -440.42203)
			(xy 62.148877 -440.390461) (xy 62.16518 -440.328742) (xy 62.18905 -440.269538) (xy 62.220116 -440.213771)
			(xy 62.257893 -440.162313) (xy 62.30179 -440.115967) (xy 62.351123 -440.075455) (xy 62.405122 -440.04141)
			(xy 62.462945 -440.014364) (xy 62.523689 -439.994738) (xy 62.586405 -439.982838) (xy 62.650116 -439.978851)
			(xy 62.713827 -439.982838) (xy 62.776543 -439.994738) (xy 62.837287 -440.014364) (xy 62.89511 -440.04141)
			(xy 62.949109 -440.075455) (xy 62.998442 -440.115967) (xy 63.042339 -440.162313) (xy 63.080116 -440.213771)
			(xy 63.111182 -440.269538) (xy 63.135052 -440.328742) (xy 63.151355 -440.390461) (xy 63.156084 -440.42203)
			(xy 63.161926 -440.465972) (xy 66.138298 -440.465972) (xy 66.14414 -440.42203) (xy 66.148869 -440.390461)
			(xy 66.165172 -440.328742) (xy 66.189042 -440.269538) (xy 66.220108 -440.213771) (xy 66.257885 -440.162313)
			(xy 66.301782 -440.115967) (xy 66.351115 -440.075455) (xy 66.405114 -440.04141) (xy 66.462937 -440.014364)
			(xy 66.523681 -439.994738) (xy 66.586397 -439.982838) (xy 66.650108 -439.978851) (xy 66.713819 -439.982838)
			(xy 66.776535 -439.994738) (xy 66.837279 -440.014364) (xy 66.895102 -440.04141) (xy 66.949101 -440.075455)
			(xy 66.998434 -440.115967) (xy 67.042331 -440.162313) (xy 67.080108 -440.213771) (xy 67.111174 -440.269538)
			(xy 67.135044 -440.328742) (xy 67.151347 -440.390461) (xy 67.156076 -440.42203) (xy 67.161918 -440.465972)
			(xy 70.13829 -440.465972) (xy 70.144132 -440.42203) (xy 70.148861 -440.390461) (xy 70.165164 -440.328742)
			(xy 70.189034 -440.269538) (xy 70.2201 -440.213771) (xy 70.257877 -440.162313) (xy 70.301774 -440.115967)
			(xy 70.351107 -440.075455) (xy 70.405106 -440.04141) (xy 70.462929 -440.014364) (xy 70.523673 -439.994738)
			(xy 70.586389 -439.982838) (xy 70.6501 -439.978851) (xy 70.713811 -439.982838) (xy 70.776527 -439.994738)
			(xy 70.837271 -440.014364) (xy 70.895094 -440.04141) (xy 70.949093 -440.075455) (xy 70.998426 -440.115967)
			(xy 71.042323 -440.162313) (xy 71.0801 -440.213771) (xy 71.111166 -440.269538) (xy 71.135036 -440.328742)
			(xy 71.151339 -440.390461) (xy 71.156068 -440.42203) (xy 71.16191 -440.465972) (xy 75.13828 -440.465972)
			(xy 75.144122 -440.42203) (xy 75.148851 -440.390461) (xy 75.165154 -440.328742) (xy 75.189024 -440.269538)
			(xy 75.22009 -440.213771) (xy 75.257867 -440.162313) (xy 75.301764 -440.115967) (xy 75.351097 -440.075455)
			(xy 75.405096 -440.04141) (xy 75.462919 -440.014364) (xy 75.523663 -439.994738) (xy 75.586379 -439.982838)
			(xy 75.65009 -439.978851) (xy 75.713801 -439.982838) (xy 75.776517 -439.994738) (xy 75.837261 -440.014364)
			(xy 75.895084 -440.04141) (xy 75.949083 -440.075455) (xy 75.998416 -440.115967) (xy 76.042313 -440.162313)
			(xy 76.08009 -440.213771) (xy 76.111156 -440.269538) (xy 76.135026 -440.328742) (xy 76.151329 -440.390461)
			(xy 76.156058 -440.42203) (xy 76.1619 -440.465972) (xy 79.138272 -440.465972) (xy 79.144114 -440.42203)
			(xy 79.148843 -440.390461) (xy 79.165146 -440.328742) (xy 79.189016 -440.269538) (xy 79.220082 -440.213771)
			(xy 79.257859 -440.162313) (xy 79.301756 -440.115967) (xy 79.351089 -440.075455) (xy 79.405088 -440.04141)
			(xy 79.462911 -440.014364) (xy 79.523655 -439.994738) (xy 79.586371 -439.982838) (xy 79.650082 -439.978851)
			(xy 79.713793 -439.982838) (xy 79.776509 -439.994738) (xy 79.837253 -440.014364) (xy 79.895076 -440.04141)
			(xy 79.949075 -440.075455) (xy 79.998408 -440.115967) (xy 80.042305 -440.162313) (xy 80.080082 -440.213771)
			(xy 80.111148 -440.269538) (xy 80.135018 -440.328742) (xy 80.151321 -440.390461) (xy 80.15605 -440.42203)
			(xy 80.161892 -440.465972) (xy 83.138264 -440.465972) (xy 83.144106 -440.42203) (xy 83.148835 -440.390461)
			(xy 83.165138 -440.328742) (xy 83.189008 -440.269538) (xy 83.220074 -440.213771) (xy 83.257851 -440.162313)
			(xy 83.301748 -440.115967) (xy 83.351081 -440.075455) (xy 83.40508 -440.04141) (xy 83.462903 -440.014364)
			(xy 83.523647 -439.994738) (xy 83.586363 -439.982838) (xy 83.650074 -439.978851) (xy 83.713785 -439.982838)
			(xy 83.776501 -439.994738) (xy 83.837245 -440.014364) (xy 83.895068 -440.04141) (xy 83.949067 -440.075455)
			(xy 83.9984 -440.115967) (xy 84.042297 -440.162313) (xy 84.080074 -440.213771) (xy 84.11114 -440.269538)
			(xy 84.13501 -440.328742) (xy 84.151313 -440.390461) (xy 84.156042 -440.42203) (xy 84.161884 -440.465972)
			(xy 87.138256 -440.465972) (xy 87.144098 -440.42203) (xy 87.148827 -440.390461) (xy 87.16513 -440.328742)
			(xy 87.189 -440.269538) (xy 87.220066 -440.213771) (xy 87.257843 -440.162313) (xy 87.30174 -440.115967)
			(xy 87.351073 -440.075455) (xy 87.405072 -440.04141) (xy 87.462895 -440.014364) (xy 87.523639 -439.994738)
			(xy 87.586355 -439.982838) (xy 87.650066 -439.978851) (xy 87.713777 -439.982838) (xy 87.776493 -439.994738)
			(xy 87.837237 -440.014364) (xy 87.89506 -440.04141) (xy 87.949059 -440.075455) (xy 87.998392 -440.115967)
			(xy 88.042289 -440.162313) (xy 88.080066 -440.213771) (xy 88.111132 -440.269538) (xy 88.135002 -440.328742)
			(xy 88.151305 -440.390461) (xy 88.156034 -440.42203) (xy 88.161876 -440.465972) (xy 98.016822 -440.465972)
			(xy 98.031879 -440.465426) (xy 98.060684 -440.456638) (xy 98.085673 -440.439833) (xy 98.104677 -440.416471)
			(xy 98.116042 -440.388583) (xy 98.11878 -440.358593) (xy 98.112655 -440.329107) (xy 98.098197 -440.30269)
			(xy 98.076665 -440.281636) (xy 98.063558 -440.274202) (xy 97.97279 -440.226317) (xy 97.794627 -440.124416)
			(xy 97.620566 -440.015658) (xy 97.450869 -439.900206) (xy 97.285795 -439.778237) (xy 97.125594 -439.649934)
			(xy 96.970509 -439.515493) (xy 96.820774 -439.375117) (xy 96.676617 -439.22902) (xy 96.538256 -439.077421)
			(xy 96.4059 -438.920552) (xy 96.279751 -438.75865) (xy 96.16 -438.59196) (xy 96.046828 -438.420735)
			(xy 95.940407 -438.245235) (xy 95.840897 -438.065725) (xy 95.74845 -437.882478) (xy 95.663207 -437.695771)
			(xy 95.585295 -437.505888) (xy 95.514834 -437.313116) (xy 95.451929 -437.117747) (xy 95.396677 -436.920078)
			(xy 95.349162 -436.720408) (xy 95.309454 -436.519039) (xy 95.277615 -436.316278) (xy 95.253692 -436.112431)
			(xy 95.237722 -435.907807) (xy 95.229729 -435.702717) (xy 95.229172 -435.600094) (xy 95.229668 -435.497873)
			(xy 95.237595 -435.293583) (xy 95.253438 -435.089755) (xy 95.277172 -434.886695) (xy 95.308762 -434.684707)
			(xy 95.348161 -434.484096) (xy 95.395309 -434.285164) (xy 95.450135 -434.08821) (xy 95.512557 -433.893529)
			(xy 95.58248 -433.701416) (xy 95.659801 -433.512158) (xy 95.744401 -433.326041) (xy 95.836155 -433.143344)
			(xy 95.934924 -432.964342) (xy 96.04056 -432.789305) (xy 96.152903 -432.618495) (xy 96.271785 -432.45217)
			(xy 96.397027 -432.29058) (xy 96.52844 -432.133968) (xy 96.665827 -431.982569) (xy 96.808982 -431.836611)
			(xy 96.957688 -431.696314) (xy 97.111723 -431.561888) (xy 97.270854 -431.433536) (xy 97.434843 -431.311451)
			(xy 97.603441 -431.195817) (xy 97.776397 -431.086807) (xy 97.95345 -430.984586) (xy 98.134334 -430.889306)
			(xy 98.318775 -430.801113) (xy 98.506498 -430.720137) (xy 98.69722 -430.646501) (xy 98.890653 -430.580316)
			(xy 99.086507 -430.521681) (xy 99.284488 -430.470685) (xy 99.484297 -430.427403) (xy 99.685634 -430.391902)
			(xy 99.888196 -430.364235) (xy 100.091678 -430.344442) (xy 100.295775 -430.332555) (xy 100.50018 -430.328591)
			(xy 100.704585 -430.332555) (xy 100.908682 -430.344442) (xy 101.112164 -430.364235) (xy 101.314726 -430.391902)
			(xy 101.516063 -430.427403) (xy 101.715872 -430.470685) (xy 101.913853 -430.521681) (xy 102.109707 -430.580316)
			(xy 102.30314 -430.646501) (xy 102.493862 -430.720137) (xy 102.681585 -430.801113) (xy 102.866026 -430.889306)
			(xy 103.04691 -430.984586) (xy 103.223963 -431.086807) (xy 103.396919 -431.195817) (xy 103.565517 -431.311451)
			(xy 103.729506 -431.433536) (xy 103.888637 -431.561888) (xy 104.042672 -431.696314) (xy 104.191378 -431.836611)
			(xy 104.334533 -431.982569) (xy 104.47192 -432.133968) (xy 104.603333 -432.29058) (xy 104.728575 -432.45217)
			(xy 104.847457 -432.618495) (xy 104.9598 -432.789305) (xy 105.065436 -432.964342) (xy 105.164205 -433.143344)
			(xy 105.255959 -433.326041) (xy 105.340559 -433.512158) (xy 105.41788 -433.701416) (xy 105.487803 -433.893529)
			(xy 105.550225 -434.08821) (xy 105.605051 -434.285164) (xy 105.652199 -434.484096) (xy 105.691598 -434.684707)
			(xy 105.723188 -434.886695) (xy 105.746922 -435.089755) (xy 105.762765 -435.293583) (xy 105.770692 -435.497873)
			(xy 105.771188 -435.600094) (xy 105.770692 -435.702718) (xy 105.762704 -435.907811) (xy 105.746738 -436.112437)
			(xy 105.722819 -436.316287) (xy 105.690982 -436.519052) (xy 105.651277 -436.720423) (xy 105.603763 -436.920096)
			(xy 105.548512 -437.117768) (xy 105.485608 -437.313139) (xy 105.415146 -437.505914) (xy 105.337234 -437.695799)
			(xy 105.251989 -437.882508) (xy 105.15954 -438.065757) (xy 105.060028 -438.245268) (xy 104.953604 -438.420769)
			(xy 104.840428 -438.591995) (xy 104.720673 -438.758685) (xy 104.59452 -438.920587) (xy 104.462159 -439.077455)
			(xy 104.323793 -439.229052) (xy 104.17963 -439.375148) (xy 104.02989 -439.515521) (xy 103.874798 -439.649959)
			(xy 103.714591 -439.778258) (xy 103.549511 -439.900222) (xy 103.379808 -440.015669) (xy 103.20574 -440.124421)
			(xy 103.02757 -440.226316) (xy 102.936802 -440.274202) (xy 102.923684 -440.281619) (xy 102.902154 -440.302681)
			(xy 102.887699 -440.329106) (xy 102.881575 -440.358596) (xy 102.884315 -440.388591) (xy 102.89568 -440.416484)
			(xy 102.914683 -440.439853) (xy 102.939673 -440.456666) (xy 102.968478 -440.465465) (xy 102.983538 -440.465972)
			(xy 108.564172 -440.465972) (xy 108.564172 -433.182268) (xy 108.524442 -433.105807) (xy 108.450941 -432.949936)
			(xy 108.384375 -432.790979) (xy 108.324873 -432.629246) (xy 108.27255 -432.46505) (xy 108.227507 -432.298709)
			(xy 108.189832 -432.130546) (xy 108.159598 -431.960887) (xy 108.136864 -431.790062) (xy 108.121673 -431.618401)
			(xy 108.114056 -431.446238) (xy 108.113576 -431.360072) (xy 108.11405 -431.273905) (xy 108.121648 -431.10174)
			(xy 108.136823 -430.930076) (xy 108.159547 -430.759247) (xy 108.189775 -430.589586) (xy 108.227448 -430.421421)
			(xy 108.272493 -430.255079) (xy 108.324823 -430.090883) (xy 108.384337 -429.929152) (xy 108.450917 -429.770199)
			(xy 108.524436 -429.614335) (xy 108.564172 -429.537876) (xy 108.564172 -420.872412) (xy 115.623848 -420.872412)
			(xy 115.623848 -427.289976) (xy 125.238002 -427.289976) (xy 125.238092 -427.275402) (xy 125.239747 -427.246301)
			(xy 125.241304 -427.23181) (xy 125.241304 -426.147992) (xy 125.239761 -426.1335) (xy 125.238108 -426.1044)
			(xy 125.238002 -426.089826) (xy 125.238097 -426.075252) (xy 125.239748 -426.046151) (xy 125.241304 -426.03166)
			(xy 125.241304 -425.419012) (xy 125.241727 -425.406903) (xy 125.249223 -425.383876) (xy 125.263483 -425.364302)
			(xy 125.283104 -425.350107) (xy 125.306156 -425.342687) (xy 125.318266 -425.342304) (xy 126.258066 -425.342304)
			(xy 126.27015 -425.342836) (xy 126.293144 -425.350279) (xy 126.312721 -425.36445) (xy 126.326974 -425.383968)
			(xy 126.334513 -425.40693) (xy 126.335028 -425.419012) (xy 126.335028 -427.960536) (xy 126.334615 -427.972644)
			(xy 126.327109 -427.995668) (xy 126.312845 -428.015238) (xy 126.293225 -428.029432) (xy 126.270175 -428.036857)
			(xy 126.258066 -428.037244) (xy 125.318266 -428.037244) (xy 125.306173 -428.036821) (xy 125.283169 -428.029353)
			(xy 125.263588 -428.015156) (xy 125.249339 -427.995612) (xy 125.241811 -427.972628) (xy 125.241304 -427.960536)
			(xy 125.241304 -427.348142) (xy 125.239757 -427.33365) (xy 125.238107 -427.30455) (xy 125.238002 -427.289976)
			(xy 115.623848 -427.289976) (xy 115.623848 -428.28972) (xy 127.237998 -428.28972) (xy 127.238092 -428.275146)
			(xy 127.239744 -428.246045) (xy 127.2413 -428.231554) (xy 127.2413 -427.14799) (xy 127.239757 -427.133498)
			(xy 127.238104 -427.104398) (xy 127.237998 -427.089824) (xy 127.238092 -427.07525) (xy 127.239744 -427.046149)
			(xy 127.2413 -427.031658) (xy 127.2413 -426.41901) (xy 127.24182 -426.4069) (xy 127.2493 -426.383863)
			(xy 127.263531 -426.364265) (xy 127.28312 -426.350022) (xy 127.306152 -426.342527) (xy 127.318262 -426.342048)
			(xy 128.258062 -426.342048) (xy 128.270184 -426.342492) (xy 128.293243 -426.349975) (xy 128.31286 -426.36422)
			(xy 128.327112 -426.383832) (xy 128.334603 -426.406888) (xy 128.335024 -426.41901) (xy 128.335024 -427.289976)
			(xy 129.237994 -427.289976) (xy 129.238084 -427.275402) (xy 129.239739 -427.246301) (xy 129.241296 -427.23181)
			(xy 129.241296 -426.147992) (xy 129.239753 -426.1335) (xy 129.2381 -426.1044) (xy 129.237994 -426.089826)
			(xy 129.238089 -426.075252) (xy 129.23974 -426.046151) (xy 129.241296 -426.03166) (xy 129.241296 -425.419012)
			(xy 129.241727 -425.406904) (xy 129.249222 -425.383878) (xy 129.26348 -425.364305) (xy 129.283099 -425.35011)
			(xy 129.306149 -425.342688) (xy 129.318258 -425.342304) (xy 130.258058 -425.342304) (xy 130.270142 -425.342842)
			(xy 130.293135 -425.350283) (xy 130.312713 -425.364453) (xy 130.326966 -425.383969) (xy 130.334505 -425.40693)
			(xy 130.33502 -425.419012) (xy 130.33502 -427.960536) (xy 130.334615 -427.972645) (xy 130.327108 -427.99567)
			(xy 130.312843 -428.01524) (xy 130.29322 -428.029435) (xy 130.270168 -428.036858) (xy 130.258058 -428.037244)
			(xy 129.318258 -428.037244) (xy 129.306165 -428.036828) (xy 129.28316 -428.029358) (xy 129.263579 -428.015159)
			(xy 129.249331 -427.995614) (xy 129.241803 -427.972628) (xy 129.241296 -427.960536) (xy 129.241296 -427.348142)
			(xy 129.239749 -427.33365) (xy 129.238099 -427.30455) (xy 129.237994 -427.289976) (xy 128.335024 -427.289976)
			(xy 128.335024 -428.28972) (xy 131.23799 -428.28972) (xy 131.238084 -428.275146) (xy 131.239736 -428.246045)
			(xy 131.241292 -428.231554) (xy 131.241292 -427.14799) (xy 131.239749 -427.133498) (xy 131.238096 -427.104398)
			(xy 131.23799 -427.089824) (xy 131.238085 -427.07525) (xy 131.239736 -427.046149) (xy 131.241292 -427.031658)
			(xy 131.241292 -426.41901) (xy 131.24182 -426.406901) (xy 131.249299 -426.383865) (xy 131.263528 -426.364268)
			(xy 131.283115 -426.350024) (xy 131.306145 -426.342528) (xy 131.318254 -426.342048) (xy 132.258054 -426.342048)
			(xy 132.270175 -426.342499) (xy 132.293234 -426.34998) (xy 132.312851 -426.364223) (xy 132.327104 -426.383833)
			(xy 132.334595 -426.406889) (xy 132.335016 -426.41901) (xy 132.335016 -427.289976) (xy 133.237986 -427.289976)
			(xy 133.238076 -427.275402) (xy 133.239731 -427.246301) (xy 133.241288 -427.23181) (xy 133.241288 -426.147992)
			(xy 133.239745 -426.1335) (xy 133.238092 -426.1044) (xy 133.237986 -426.089826) (xy 133.238081 -426.075252)
			(xy 133.239732 -426.046151) (xy 133.241288 -426.03166) (xy 133.241288 -425.419012) (xy 133.241727 -425.406905)
			(xy 133.249221 -425.38388) (xy 133.263477 -425.364308) (xy 133.283094 -425.350113) (xy 133.306142 -425.342689)
			(xy 133.31825 -425.342304) (xy 134.25805 -425.342304) (xy 134.270133 -425.342849) (xy 134.293126 -425.350288)
			(xy 134.312704 -425.364455) (xy 134.326958 -425.383971) (xy 134.334497 -425.406931) (xy 134.335012 -425.419012)
			(xy 134.335012 -427.960536) (xy 134.334614 -427.972646) (xy 134.327107 -427.995672) (xy 134.31284 -428.015243)
			(xy 134.293215 -428.029437) (xy 134.270161 -428.036859) (xy 134.25805 -428.037244) (xy 133.31825 -428.037244)
			(xy 133.306161 -428.03675) (xy 133.28316 -428.029305) (xy 133.263578 -428.015126) (xy 133.249326 -427.995597)
			(xy 133.241795 -427.972623) (xy 133.241288 -427.960536) (xy 133.241288 -427.348142) (xy 133.239741 -427.33365)
			(xy 133.238091 -427.30455) (xy 133.237986 -427.289976) (xy 132.335016 -427.289976) (xy 132.335016 -428.28972)
			(xy 135.237982 -428.28972) (xy 135.238076 -428.275146) (xy 135.239728 -428.246045) (xy 135.241284 -428.231554)
			(xy 135.241284 -427.14799) (xy 135.239741 -427.133498) (xy 135.238088 -427.104398) (xy 135.237982 -427.089824)
			(xy 135.238077 -427.07525) (xy 135.239728 -427.046149) (xy 135.241284 -427.031658) (xy 135.241284 -426.41901)
			(xy 135.241669 -426.406883) (xy 135.249164 -426.383817) (xy 135.263423 -426.364198) (xy 135.283049 -426.349948)
			(xy 135.306119 -426.342464) (xy 135.318246 -426.342048) (xy 136.258046 -426.342048) (xy 136.270164 -426.342473)
			(xy 136.29321 -426.349974) (xy 136.312812 -426.364228) (xy 136.327052 -426.38384) (xy 136.334536 -426.406892)
			(xy 136.335008 -426.41901) (xy 136.335008 -427.289976) (xy 137.237978 -427.289976) (xy 137.238068 -427.275402)
			(xy 137.239723 -427.246301) (xy 137.24128 -427.23181) (xy 137.24128 -426.147992) (xy 137.239737 -426.1335)
			(xy 137.238084 -426.1044) (xy 137.237978 -426.089826) (xy 137.238073 -426.075252) (xy 137.239724 -426.046151)
			(xy 137.24128 -426.03166) (xy 137.24128 -425.419012) (xy 137.241727 -425.406906) (xy 137.24922 -425.383882)
			(xy 137.263475 -425.364311) (xy 137.283089 -425.350115) (xy 137.306135 -425.342691) (xy 137.318242 -425.342304)
			(xy 138.258042 -425.342304) (xy 138.27013 -425.342771) (xy 138.293126 -425.350235) (xy 138.312702 -425.364423)
			(xy 138.326953 -425.383953) (xy 138.33449 -425.406925) (xy 138.335004 -425.419012) (xy 138.335004 -427.960536)
			(xy 138.334614 -427.972646) (xy 138.327106 -427.995674) (xy 138.312837 -428.015246) (xy 138.29321 -428.02944)
			(xy 138.270154 -428.03686) (xy 138.258042 -428.037244) (xy 137.318242 -428.037244) (xy 137.306153 -428.036757)
			(xy 137.283151 -428.029309) (xy 137.263569 -428.015129) (xy 137.249318 -427.995598) (xy 137.241787 -427.972623)
			(xy 137.24128 -427.960536) (xy 137.24128 -427.348142) (xy 137.239733 -427.33365) (xy 137.238083 -427.30455)
			(xy 137.237978 -427.289976) (xy 136.335008 -427.289976) (xy 136.335008 -428.28972) (xy 139.237974 -428.28972)
			(xy 139.238068 -428.275146) (xy 139.23972 -428.246045) (xy 139.241276 -428.231554) (xy 139.241276 -427.14799)
			(xy 139.239733 -427.133498) (xy 139.23808 -427.104398) (xy 139.237974 -427.089824) (xy 139.238069 -427.07525)
			(xy 139.23972 -427.046149) (xy 139.241276 -427.031658) (xy 139.241276 -426.41901) (xy 139.241669 -426.406884)
			(xy 139.249163 -426.383819) (xy 139.26342 -426.364201) (xy 139.283044 -426.34995) (xy 139.306112 -426.342465)
			(xy 139.318238 -426.342048) (xy 140.258038 -426.342048) (xy 140.270156 -426.342479) (xy 140.293202 -426.349978)
			(xy 140.312804 -426.36423) (xy 140.327044 -426.383841) (xy 140.334528 -426.406892) (xy 140.335 -426.41901)
			(xy 140.335 -427.289976) (xy 142.237968 -427.289976) (xy 142.238082 -427.274891) (xy 142.23986 -427.244772)
			(xy 142.241524 -427.229778) (xy 142.241524 -426.150024) (xy 142.239855 -426.135031) (xy 142.238077 -426.104912)
			(xy 142.237968 -426.089826) (xy 142.238078 -426.07474) (xy 142.239859 -426.044622) (xy 142.241524 -426.029628)
			(xy 142.241524 -425.419012) (xy 142.241924 -425.406927) (xy 142.249392 -425.383939) (xy 142.2636 -425.364386)
			(xy 142.283157 -425.350183) (xy 142.306147 -425.34272) (xy 142.318232 -425.342304) (xy 143.258032 -425.342304)
			(xy 143.270109 -425.342737) (xy 143.29308 -425.35021) (xy 143.312617 -425.364414) (xy 143.32681 -425.38396)
			(xy 143.33427 -425.406934) (xy 143.33474 -425.419012) (xy 143.33474 -427.960536) (xy 143.334267 -427.972609)
			(xy 143.326799 -427.995572) (xy 143.312603 -428.015106) (xy 143.293069 -428.0293) (xy 143.270105 -428.036768)
			(xy 143.258032 -428.037244) (xy 142.318232 -428.037244) (xy 142.306163 -428.036709) (xy 142.283203 -428.02926)
			(xy 142.263668 -428.01508) (xy 142.249471 -427.995558) (xy 142.242001 -427.972605) (xy 142.241524 -427.960536)
			(xy 142.241524 -427.350174) (xy 142.23986 -427.33518) (xy 142.238078 -427.305062) (xy 142.237968 -427.289976)
			(xy 140.335 -427.289976) (xy 140.335 -428.28972) (xy 144.237964 -428.28972) (xy 144.238073 -428.274634)
			(xy 144.239855 -428.244516) (xy 144.24152 -428.229522) (xy 144.24152 -427.150022) (xy 144.239851 -427.135029)
			(xy 144.238073 -427.10491) (xy 144.237964 -427.089824) (xy 144.238074 -427.074738) (xy 144.239855 -427.04462)
			(xy 144.24152 -427.029626) (xy 144.24152 -426.41901) (xy 144.242016 -426.406923) (xy 144.249467 -426.383926)
			(xy 144.263647 -426.364348) (xy 144.283173 -426.350096) (xy 144.306143 -426.34256) (xy 144.318228 -426.342048)
			(xy 145.258028 -426.342048) (xy 145.270133 -426.342492) (xy 145.293152 -426.349993) (xy 145.312721 -426.364249)
			(xy 145.326916 -426.383861) (xy 145.334345 -426.406904) (xy 145.334736 -426.41901) (xy 145.334736 -427.289976)
			(xy 146.23796 -427.289976) (xy 146.238074 -427.274891) (xy 146.239852 -427.244772) (xy 146.241516 -427.229778)
			(xy 146.241516 -426.150024) (xy 146.239847 -426.135031) (xy 146.238069 -426.104912) (xy 146.23796 -426.089826)
			(xy 146.23807 -426.07474) (xy 146.239851 -426.044622) (xy 146.241516 -426.029628) (xy 146.241516 -425.419012)
			(xy 146.241923 -425.406928) (xy 146.249391 -425.383941) (xy 146.263597 -425.364389) (xy 146.283152 -425.350185)
			(xy 146.306139 -425.342722) (xy 146.318224 -425.342304) (xy 147.258024 -425.342304) (xy 147.270101 -425.342744)
			(xy 147.293071 -425.350215) (xy 147.312609 -425.364417) (xy 147.326802 -425.383961) (xy 147.334261 -425.406935)
			(xy 147.334732 -425.419012) (xy 147.334732 -427.960536) (xy 147.334267 -427.97261) (xy 147.326798 -427.995574)
			(xy 147.3126 -428.015109) (xy 147.293064 -428.029303) (xy 147.270098 -428.036769) (xy 147.258024 -428.037244)
			(xy 146.318224 -428.037244) (xy 146.306154 -428.036716) (xy 146.283194 -428.029264) (xy 146.26366 -428.015083)
			(xy 146.249463 -427.99556) (xy 146.241993 -427.972605) (xy 146.241516 -427.960536) (xy 146.241516 -427.350174)
			(xy 146.239852 -427.33518) (xy 146.23807 -427.305062) (xy 146.23796 -427.289976) (xy 145.334736 -427.289976)
			(xy 145.334736 -428.28972) (xy 148.237956 -428.28972) (xy 148.238066 -428.274634) (xy 148.239847 -428.244516)
			(xy 148.241512 -428.229522) (xy 148.241512 -427.150022) (xy 148.239843 -427.135029) (xy 148.238065 -427.10491)
			(xy 148.237956 -427.089824) (xy 148.238066 -427.074738) (xy 148.239847 -427.04462) (xy 148.241512 -427.029626)
			(xy 148.241512 -426.41901) (xy 148.242015 -426.406924) (xy 148.249466 -426.383928) (xy 148.263644 -426.364351)
			(xy 148.283168 -426.350099) (xy 148.306136 -426.342562) (xy 148.31822 -426.342048) (xy 149.25802 -426.342048)
			(xy 149.270125 -426.342499) (xy 149.293144 -426.349997) (xy 149.312712 -426.364252) (xy 149.326908 -426.383863)
			(xy 149.334337 -426.406904) (xy 149.334728 -426.41901) (xy 149.334728 -427.289976) (xy 150.237952 -427.289976)
			(xy 150.238066 -427.274891) (xy 150.239844 -427.244772) (xy 150.241508 -427.229778) (xy 150.241508 -426.150024)
			(xy 150.239839 -426.135031) (xy 150.238061 -426.104912) (xy 150.237952 -426.089826) (xy 150.238062 -426.07474)
			(xy 150.239843 -426.044622) (xy 150.241508 -426.029628) (xy 150.241508 -425.419012) (xy 150.241923 -425.406928)
			(xy 150.249389 -425.383943) (xy 150.263594 -425.364392) (xy 150.283147 -425.350188) (xy 150.306132 -425.342723)
			(xy 150.318216 -425.342304) (xy 151.258016 -425.342304) (xy 151.270093 -425.342751) (xy 151.293062 -425.350219)
			(xy 151.3126 -425.36442) (xy 151.326794 -425.383963) (xy 151.334253 -425.406935) (xy 151.334724 -425.419012)
			(xy 151.334724 -427.960536) (xy 151.334267 -427.972611) (xy 151.326796 -427.995577) (xy 151.312597 -428.015112)
			(xy 151.293059 -428.029306) (xy 151.270091 -428.03677) (xy 151.258016 -428.037244) (xy 150.318216 -428.037244)
			(xy 150.306146 -428.036723) (xy 150.283185 -428.029269) (xy 150.263651 -428.015086) (xy 150.249455 -427.995561)
			(xy 150.241985 -427.972606) (xy 150.241508 -427.960536) (xy 150.241508 -427.350174) (xy 150.239844 -427.33518)
			(xy 150.238062 -427.305062) (xy 150.237952 -427.289976) (xy 149.334728 -427.289976) (xy 149.334728 -428.28972)
			(xy 152.237948 -428.28972) (xy 152.238058 -428.274634) (xy 152.239839 -428.244516) (xy 152.241504 -428.229522)
			(xy 152.241504 -427.150022) (xy 152.239835 -427.135029) (xy 152.238057 -427.10491) (xy 152.237948 -427.089824)
			(xy 152.238058 -427.074738) (xy 152.239839 -427.04462) (xy 152.241504 -427.029626) (xy 152.241504 -426.41901)
			(xy 152.242015 -426.406925) (xy 152.249465 -426.38393) (xy 152.263641 -426.364353) (xy 152.283163 -426.350101)
			(xy 152.306128 -426.342563) (xy 152.318212 -426.342048) (xy 153.258012 -426.342048) (xy 153.270116 -426.342505)
			(xy 153.293135 -426.350002) (xy 153.312704 -426.364255) (xy 153.3269 -426.383864) (xy 153.334329 -426.406905)
			(xy 153.33472 -426.41901) (xy 153.33472 -427.289976) (xy 154.237944 -427.289976) (xy 154.238059 -427.274891)
			(xy 154.239836 -427.244772) (xy 154.2415 -427.229778) (xy 154.2415 -426.150024) (xy 154.239831 -426.135031)
			(xy 154.238053 -426.104912) (xy 154.237944 -426.089826) (xy 154.238054 -426.07474) (xy 154.239835 -426.044622)
			(xy 154.2415 -426.029628) (xy 154.2415 -425.419012) (xy 154.241923 -425.406929) (xy 154.249388 -425.383946)
			(xy 154.263592 -425.364394) (xy 154.283142 -425.35019) (xy 154.306125 -425.342724) (xy 154.318208 -425.342304)
			(xy 155.258008 -425.342304) (xy 155.270092 -425.342706) (xy 155.293077 -425.350177) (xy 155.312629 -425.364386)
			(xy 155.326832 -425.383941) (xy 155.334297 -425.406928) (xy 155.334716 -425.419012) (xy 155.334716 -427.960536)
			(xy 155.334267 -427.972612) (xy 155.326795 -427.995579) (xy 155.312595 -428.015115) (xy 155.293054 -428.029308)
			(xy 155.270084 -428.036771) (xy 155.258008 -428.037244) (xy 154.318208 -428.037244) (xy 154.306137 -428.03673)
			(xy 154.283177 -428.029274) (xy 154.263643 -428.015089) (xy 154.249447 -427.995563) (xy 154.241977 -427.972606)
			(xy 154.2415 -427.960536) (xy 154.2415 -427.350174) (xy 154.239836 -427.33518) (xy 154.238054 -427.305062)
			(xy 154.237944 -427.289976) (xy 153.33472 -427.289976) (xy 153.33472 -428.28972) (xy 156.23794 -428.28972)
			(xy 156.238052 -428.274634) (xy 156.239833 -428.244516) (xy 156.241496 -428.229522) (xy 156.241496 -427.150022)
			(xy 156.239827 -427.135029) (xy 156.238049 -427.10491) (xy 156.23794 -427.089824) (xy 156.23805 -427.074738)
			(xy 156.239831 -427.04462) (xy 156.241496 -427.029626) (xy 156.241496 -426.41901) (xy 156.242015 -426.406925)
			(xy 156.249464 -426.383932) (xy 156.263639 -426.364356) (xy 156.283158 -426.350104) (xy 156.306121 -426.342564)
			(xy 156.318204 -426.342048) (xy 157.258004 -426.342048) (xy 157.270108 -426.342512) (xy 157.293127 -426.350006)
			(xy 157.312695 -426.364257) (xy 157.326891 -426.383866) (xy 157.334321 -426.406905) (xy 157.334712 -426.41901)
			(xy 157.334712 -428.960534) (xy 157.334321 -428.97263) (xy 157.326849 -428.99564) (xy 157.312644 -429.015223)
			(xy 157.293092 -429.029471) (xy 157.270099 -429.036994) (xy 157.258004 -429.037496) (xy 156.318204 -429.037496)
			(xy 156.306095 -429.03708) (xy 156.283067 -429.029582) (xy 156.263493 -429.01532) (xy 156.249299 -428.995698)
			(xy 156.241879 -428.972644) (xy 156.241496 -428.960534) (xy 156.241496 -428.349918) (xy 156.239827 -428.334925)
			(xy 156.238049 -428.304806) (xy 156.23794 -428.28972) (xy 153.33472 -428.28972) (xy 153.33472 -428.960534)
			(xy 153.334321 -428.972629) (xy 153.32685 -428.995638) (xy 153.312647 -429.015221) (xy 153.293097 -429.029469)
			(xy 153.270106 -429.036993) (xy 153.258012 -429.037496) (xy 152.318212 -429.037496) (xy 152.306103 -429.037073)
			(xy 152.283076 -429.029577) (xy 152.263502 -429.015317) (xy 152.249307 -428.995696) (xy 152.241887 -428.972644)
			(xy 152.241504 -428.960534) (xy 152.241504 -428.349918) (xy 152.239835 -428.334925) (xy 152.238057 -428.304806)
			(xy 152.237948 -428.28972) (xy 149.334728 -428.28972) (xy 149.334728 -428.960534) (xy 149.334321 -428.972629)
			(xy 149.326851 -428.995636) (xy 149.31265 -429.015218) (xy 149.293102 -429.029466) (xy 149.270113 -429.036992)
			(xy 149.25802 -429.037496) (xy 148.31822 -429.037496) (xy 148.306112 -429.037066) (xy 148.283085 -429.029572)
			(xy 148.263511 -429.015314) (xy 148.249316 -428.995695) (xy 148.241895 -428.972643) (xy 148.241512 -428.960534)
			(xy 148.241512 -428.349918) (xy 148.239843 -428.334925) (xy 148.238065 -428.304806) (xy 148.237956 -428.28972)
			(xy 145.334736 -428.28972) (xy 145.334736 -428.960534) (xy 145.334321 -428.972628) (xy 145.326852 -428.995634)
			(xy 145.312653 -429.015215) (xy 145.293107 -429.029464) (xy 145.27012 -429.03699) (xy 145.258028 -429.037496)
			(xy 144.318228 -429.037496) (xy 144.30612 -429.03706) (xy 144.283093 -429.029567) (xy 144.263519 -429.015311)
			(xy 144.249324 -428.995693) (xy 144.241903 -428.972643) (xy 144.24152 -428.960534) (xy 144.24152 -428.349918)
			(xy 144.239851 -428.334925) (xy 144.238073 -428.304806) (xy 144.237964 -428.28972) (xy 140.335 -428.28972)
			(xy 140.335 -428.960534) (xy 140.334518 -428.972647) (xy 140.327026 -428.995684) (xy 140.312785 -429.015282)
			(xy 140.293188 -429.029524) (xy 140.270151 -429.037017) (xy 140.258038 -429.037496) (xy 139.318238 -429.037496)
			(xy 139.306121 -429.037008) (xy 139.283069 -429.029531) (xy 139.263456 -429.015295) (xy 139.249202 -428.995696)
			(xy 139.241703 -428.972651) (xy 139.241276 -428.960534) (xy 139.241276 -428.347886) (xy 139.239733 -428.333394)
			(xy 139.23808 -428.304294) (xy 139.237974 -428.28972) (xy 136.335008 -428.28972) (xy 136.335008 -428.960534)
			(xy 136.334518 -428.972646) (xy 136.327027 -428.995682) (xy 136.312788 -429.01528) (xy 136.293193 -429.029522)
			(xy 136.270158 -429.037016) (xy 136.258046 -429.037496) (xy 135.318246 -429.037496) (xy 135.306129 -429.037002)
			(xy 135.283077 -429.029526) (xy 135.263464 -429.015292) (xy 135.249211 -428.995694) (xy 135.241711 -428.972651)
			(xy 135.241284 -428.960534) (xy 135.241284 -428.347886) (xy 135.239741 -428.333394) (xy 135.238088 -428.304294)
			(xy 135.237982 -428.28972) (xy 132.335016 -428.28972) (xy 132.335016 -428.960534) (xy 132.334668 -428.972663)
			(xy 132.327161 -428.995731) (xy 132.312892 -429.015349) (xy 132.293259 -429.029598) (xy 132.270184 -429.037081)
			(xy 132.258054 -429.037496) (xy 131.318254 -429.037496) (xy 131.30614 -429.037028) (xy 131.283101 -429.029532)
			(xy 131.263503 -429.015288) (xy 131.249262 -428.995688) (xy 131.24177 -428.972648) (xy 131.241292 -428.960534)
			(xy 131.241292 -428.347886) (xy 131.239749 -428.333394) (xy 131.238096 -428.304294) (xy 131.23799 -428.28972)
			(xy 128.335024 -428.28972) (xy 128.335024 -428.960534) (xy 128.334669 -428.972662) (xy 128.327162 -428.995729)
			(xy 128.312895 -429.015347) (xy 128.293264 -429.029595) (xy 128.270191 -429.03708) (xy 128.258062 -429.037496)
			(xy 127.318262 -429.037496) (xy 127.306149 -429.037021) (xy 127.28311 -429.029528) (xy 127.263512 -429.015285)
			(xy 127.24927 -428.995686) (xy 127.241778 -428.972647) (xy 127.2413 -428.960534) (xy 127.2413 -428.347886)
			(xy 127.239757 -428.333394) (xy 127.238104 -428.304294) (xy 127.237998 -428.28972) (xy 115.623848 -428.28972)
			(xy 115.623848 -429.82896) (xy 115.657639 -429.909572) (xy 115.718855 -430.073317) (xy 115.772692 -430.239633)
			(xy 115.819041 -430.40819) (xy 115.85781 -430.57865) (xy 115.888922 -430.750673) (xy 115.907724 -430.889918)
			(xy 125.238002 -430.889918) (xy 125.238096 -430.875344) (xy 125.239748 -430.846243) (xy 125.241304 -430.831752)
			(xy 125.241304 -429.747934) (xy 125.239756 -429.733442) (xy 125.238106 -429.704342) (xy 125.238002 -429.689768)
			(xy 125.2381 -429.675194) (xy 125.23975 -429.646093) (xy 125.241304 -429.631602) (xy 125.241304 -429.018954)
			(xy 125.241772 -429.00684) (xy 125.249268 -428.983801) (xy 125.263512 -428.964203) (xy 125.283112 -428.949962)
			(xy 125.306152 -428.94247) (xy 125.318266 -428.941992) (xy 126.258066 -428.941992) (xy 126.270174 -428.94254)
			(xy 126.293209 -428.950012) (xy 126.312807 -428.964236) (xy 126.327051 -428.98382) (xy 126.334547 -429.006846)
			(xy 126.335028 -429.018954) (xy 126.335028 -431.560478) (xy 126.334621 -431.572603) (xy 126.32713 -431.595667)
			(xy 126.312877 -431.615285) (xy 126.293256 -431.629536) (xy 126.270191 -431.637023) (xy 126.258066 -431.63744)
			(xy 125.318266 -431.63744) (xy 125.306147 -431.637017) (xy 125.283099 -431.629518) (xy 125.263496 -431.615264)
			(xy 125.249257 -431.59565) (xy 125.241774 -431.572597) (xy 125.241304 -431.560478) (xy 125.241304 -430.948084)
			(xy 125.23976 -430.933592) (xy 125.238108 -430.904492) (xy 125.238002 -430.889918) (xy 115.907724 -430.889918)
			(xy 115.912314 -430.923914) (xy 115.92794 -431.098027) (xy 115.935768 -431.272665) (xy 115.936268 -431.360072)
			(xy 115.935765 -431.447478) (xy 115.927918 -431.622114) (xy 115.912279 -431.796225) (xy 115.899624 -431.889916)
			(xy 127.237998 -431.889916) (xy 127.238092 -431.875342) (xy 127.239744 -431.846241) (xy 127.2413 -431.83175)
			(xy 127.2413 -430.747932) (xy 127.239752 -430.73344) (xy 127.238102 -430.70434) (xy 127.237998 -430.689766)
			(xy 127.238096 -430.675192) (xy 127.239746 -430.646091) (xy 127.2413 -430.6316) (xy 127.2413 -430.018952)
			(xy 127.241676 -430.006841) (xy 127.249188 -429.983812) (xy 127.26346 -429.96424) (xy 127.28309 -429.950047)
			(xy 127.306149 -429.942627) (xy 127.318262 -429.942244) (xy 128.258062 -429.942244) (xy 128.27015 -429.94274)
			(xy 128.29315 -429.950187) (xy 128.312731 -429.964366) (xy 128.326983 -429.983894) (xy 128.334515 -430.006866)
			(xy 128.335024 -430.018952) (xy 128.335024 -430.889918) (xy 129.237994 -430.889918) (xy 129.238088 -430.875344)
			(xy 129.23974 -430.846243) (xy 129.241296 -430.831752) (xy 129.241296 -429.747934) (xy 129.239749 -429.733442)
			(xy 129.238098 -429.704342) (xy 129.237994 -429.689768) (xy 129.238092 -429.675194) (xy 129.239742 -429.646093)
			(xy 129.241296 -429.631602) (xy 129.241296 -429.018954) (xy 129.241772 -429.006841) (xy 129.249267 -428.983804)
			(xy 129.263509 -428.964206) (xy 129.283107 -428.949965) (xy 129.306145 -428.942471) (xy 129.318258 -428.941992)
			(xy 130.258058 -428.941992) (xy 130.270166 -428.942547) (xy 130.2932 -428.950017) (xy 130.312798 -428.964239)
			(xy 130.327043 -428.983821) (xy 130.334539 -429.006847) (xy 130.33502 -429.018954) (xy 130.33502 -431.560478)
			(xy 130.334621 -431.572604) (xy 130.327129 -431.595669) (xy 130.312874 -431.615288) (xy 130.293251 -431.629538)
			(xy 130.270184 -431.637024) (xy 130.258058 -431.63744) (xy 129.318258 -431.63744) (xy 129.306139 -431.637024)
			(xy 129.283091 -431.629522) (xy 129.263488 -431.615267) (xy 129.249248 -431.595652) (xy 129.241766 -431.572597)
			(xy 129.241296 -431.560478) (xy 129.241296 -430.948084) (xy 129.239753 -430.933592) (xy 129.2381 -430.904492)
			(xy 129.237994 -430.889918) (xy 128.335024 -430.889918) (xy 128.335024 -431.889916) (xy 131.23799 -431.889916)
			(xy 131.238084 -431.875342) (xy 131.239736 -431.846241) (xy 131.241292 -431.83175) (xy 131.241292 -430.747932)
			(xy 131.239744 -430.73344) (xy 131.238094 -430.70434) (xy 131.23799 -430.689766) (xy 131.238088 -430.675192)
			(xy 131.239738 -430.646091) (xy 131.241292 -430.6316) (xy 131.241292 -430.018952) (xy 131.241675 -430.006841)
			(xy 131.249187 -429.983814) (xy 131.263458 -429.964242) (xy 131.283085 -429.950049) (xy 131.306142 -429.942628)
			(xy 131.318254 -429.942244) (xy 132.258054 -429.942244) (xy 132.270142 -429.942747) (xy 132.293141 -429.950191)
			(xy 132.312722 -429.964368) (xy 132.326974 -429.983895) (xy 132.334507 -430.006866) (xy 132.335016 -430.018952)
			(xy 132.335016 -430.889918) (xy 133.237986 -430.889918) (xy 133.23808 -430.875344) (xy 133.239732 -430.846243)
			(xy 133.241288 -430.831752) (xy 133.241288 -429.747934) (xy 133.239741 -429.733442) (xy 133.23809 -429.704342)
			(xy 133.237986 -429.689768) (xy 133.238084 -429.675194) (xy 133.239734 -429.646093) (xy 133.241288 -429.631602)
			(xy 133.241288 -429.018954) (xy 133.241772 -429.006842) (xy 133.249266 -428.983806) (xy 133.263506 -428.964209)
			(xy 133.283102 -428.949967) (xy 133.306138 -428.942472) (xy 133.31825 -428.941992) (xy 134.25805 -428.941992)
			(xy 134.270163 -428.942468) (xy 134.2932 -428.949964) (xy 134.312797 -428.964206) (xy 134.327038 -428.983804)
			(xy 134.334532 -429.006841) (xy 134.335012 -429.018954) (xy 134.335012 -431.560478) (xy 134.33447 -431.572586)
			(xy 134.326995 -431.59562) (xy 134.312769 -431.615218) (xy 134.293185 -431.629462) (xy 134.270158 -431.636959)
			(xy 134.25805 -431.63744) (xy 133.31825 -431.63744) (xy 133.306131 -431.63703) (xy 133.283082 -431.629527)
			(xy 133.263479 -431.615269) (xy 133.24924 -431.595653) (xy 133.241758 -431.572598) (xy 133.241288 -431.560478)
			(xy 133.241288 -430.948084) (xy 133.239745 -430.933592) (xy 133.238092 -430.904492) (xy 133.237986 -430.889918)
			(xy 132.335016 -430.889918) (xy 132.335016 -431.889916) (xy 135.237982 -431.889916) (xy 135.238076 -431.875342)
			(xy 135.239728 -431.846241) (xy 135.241284 -431.83175) (xy 135.241284 -430.747932) (xy 135.239736 -430.73344)
			(xy 135.238086 -430.70434) (xy 135.237982 -430.689766) (xy 135.23808 -430.675192) (xy 135.23973 -430.646091)
			(xy 135.241284 -430.6316) (xy 135.241284 -430.018952) (xy 135.241675 -430.006842) (xy 135.249186 -429.983816)
			(xy 135.263455 -429.964245) (xy 135.28308 -429.950052) (xy 135.306135 -429.942629) (xy 135.318246 -429.942244)
			(xy 136.258046 -429.942244) (xy 136.270138 -429.942668) (xy 136.293141 -429.950138) (xy 136.312721 -429.964336)
			(xy 136.32697 -429.983878) (xy 136.3345 -430.006861) (xy 136.335008 -430.018952) (xy 136.335008 -430.889918)
			(xy 137.237978 -430.889918) (xy 137.238072 -430.875344) (xy 137.239724 -430.846243) (xy 137.24128 -430.831752)
			(xy 137.24128 -429.747934) (xy 137.239733 -429.733442) (xy 137.238082 -429.704342) (xy 137.237978 -429.689768)
			(xy 137.238076 -429.675194) (xy 137.239726 -429.646093) (xy 137.24128 -429.631602) (xy 137.24128 -429.018954)
			(xy 137.241673 -429.006833) (xy 137.249178 -428.983781) (xy 137.263439 -428.964176) (xy 137.28306 -428.949938)
			(xy 137.30612 -428.942459) (xy 137.318242 -428.941992) (xy 138.258042 -428.941992) (xy 138.270154 -428.942475)
			(xy 138.293191 -428.949968) (xy 138.312788 -428.964209) (xy 138.32703 -428.983805) (xy 138.334524 -429.006842)
			(xy 138.335004 -429.018954) (xy 138.335004 -431.560478) (xy 138.33447 -431.572587) (xy 138.326994 -431.595623)
			(xy 138.312767 -431.615221) (xy 138.29318 -431.629465) (xy 138.270151 -431.63696) (xy 138.258042 -431.63744)
			(xy 137.318242 -431.63744) (xy 137.306119 -431.637004) (xy 137.283058 -431.629521) (xy 137.26344 -431.615274)
			(xy 137.249188 -431.59566) (xy 137.241699 -431.572601) (xy 137.24128 -431.560478) (xy 137.24128 -430.948084)
			(xy 137.239737 -430.933592) (xy 137.238084 -430.904492) (xy 137.237978 -430.889918) (xy 136.335008 -430.889918)
			(xy 136.335008 -431.889916) (xy 139.237974 -431.889916) (xy 139.238068 -431.875342) (xy 139.23972 -431.846241)
			(xy 139.241276 -431.83175) (xy 139.241276 -430.747932) (xy 139.239728 -430.73344) (xy 139.238078 -430.70434)
			(xy 139.237974 -430.689766) (xy 139.238072 -430.675192) (xy 139.239722 -430.646091) (xy 139.241276 -430.6316)
			(xy 139.241276 -430.018952) (xy 139.241675 -430.006843) (xy 139.249185 -429.983818) (xy 139.263452 -429.964248)
			(xy 139.283075 -429.950054) (xy 139.306128 -429.94263) (xy 139.318238 -429.942244) (xy 140.258038 -429.942244)
			(xy 140.27013 -429.942675) (xy 140.293133 -429.950143) (xy 140.312712 -429.964338) (xy 140.326961 -429.983879)
			(xy 140.334492 -430.006861) (xy 140.335 -430.018952) (xy 140.335 -430.889918) (xy 142.237968 -430.889918)
			(xy 142.238077 -430.874832) (xy 142.239859 -430.844714) (xy 142.241524 -430.82972) (xy 142.241524 -429.749966)
			(xy 142.239859 -429.734972) (xy 142.238078 -429.704854) (xy 142.237968 -429.689768) (xy 142.238082 -429.674682)
			(xy 142.23986 -429.644564) (xy 142.241524 -429.62957) (xy 142.241524 -429.018954) (xy 142.241968 -429.006864)
			(xy 142.249435 -428.983864) (xy 142.263628 -428.964286) (xy 142.283165 -428.950037) (xy 142.306143 -428.942503)
			(xy 142.318232 -428.941992) (xy 143.258032 -428.941992) (xy 143.270142 -428.942389) (xy 143.293169 -428.949896)
			(xy 143.312741 -428.964163) (xy 143.326934 -428.983788) (xy 143.334356 -429.006843) (xy 143.33474 -429.018954)
			(xy 143.33474 -431.560478) (xy 143.334273 -431.572568) (xy 143.32682 -431.595572) (xy 143.312634 -431.615154)
			(xy 143.293099 -431.629404) (xy 143.270121 -431.636933) (xy 143.258032 -431.63744) (xy 142.318232 -431.63744)
			(xy 142.306129 -431.636957) (xy 142.283109 -431.629471) (xy 142.263539 -431.615225) (xy 142.249342 -431.59562)
			(xy 142.241913 -431.572582) (xy 142.241524 -431.560478) (xy 142.241524 -430.950116) (xy 142.239855 -430.935123)
			(xy 142.238077 -430.905004) (xy 142.237968 -430.889918) (xy 140.335 -430.889918) (xy 140.335 -431.889916)
			(xy 144.237964 -431.889916) (xy 144.238073 -431.87483) (xy 144.239855 -431.844712) (xy 144.24152 -431.829718)
			(xy 144.24152 -430.749964) (xy 144.239855 -430.73497) (xy 144.238074 -430.704852) (xy 144.237964 -430.689766)
			(xy 144.238078 -430.67468) (xy 144.239856 -430.644562) (xy 144.24152 -430.629568) (xy 144.24152 -430.018952)
			(xy 144.241924 -430.006872) (xy 144.249403 -429.983899) (xy 144.263614 -429.96436) (xy 144.283167 -429.950168)
			(xy 144.306148 -429.942712) (xy 144.318228 -429.942244) (xy 145.258028 -429.942244) (xy 145.270099 -429.942739)
			(xy 145.293059 -429.950204) (xy 145.312592 -429.964394) (xy 145.326787 -429.983923) (xy 145.334258 -430.006881)
			(xy 145.334736 -430.018952) (xy 145.334736 -430.889918) (xy 146.23796 -430.889918) (xy 146.238069 -430.874832)
			(xy 146.239851 -430.844714) (xy 146.241516 -430.82972) (xy 146.241516 -429.749966) (xy 146.239851 -429.734972)
			(xy 146.23807 -429.704854) (xy 146.23796 -429.689768) (xy 146.238074 -429.674682) (xy 146.239852 -429.644564)
			(xy 146.241516 -429.62957) (xy 146.241516 -429.018954) (xy 146.241968 -429.006864) (xy 146.249434 -428.983866)
			(xy 146.263626 -428.964289) (xy 146.28316 -428.950039) (xy 146.306136 -428.942504) (xy 146.318224 -428.941992)
			(xy 147.258024 -428.941992) (xy 147.270133 -428.942396) (xy 147.29316 -428.949901) (xy 147.312732 -428.964166)
			(xy 147.326926 -428.983789) (xy 147.334348 -429.006843) (xy 147.334732 -429.018954) (xy 147.334732 -431.560478)
			(xy 147.334273 -431.572569) (xy 147.326819 -431.595574) (xy 147.312632 -431.615156) (xy 147.293094 -431.629407)
			(xy 147.270114 -431.636934) (xy 147.258024 -431.63744) (xy 146.318224 -431.63744) (xy 146.30612 -431.636964)
			(xy 146.283101 -431.629476) (xy 146.263531 -431.615228) (xy 146.249334 -431.595622) (xy 146.241905 -431.572583)
			(xy 146.241516 -431.560478) (xy 146.241516 -430.950116) (xy 146.239847 -430.935123) (xy 146.238069 -430.905004)
			(xy 146.23796 -430.889918) (xy 145.334736 -430.889918) (xy 145.334736 -431.889916) (xy 148.237956 -431.889916)
			(xy 148.238065 -431.87483) (xy 148.239847 -431.844712) (xy 148.241512 -431.829718) (xy 148.241512 -430.749964)
			(xy 148.239847 -430.73497) (xy 148.238066 -430.704852) (xy 148.237956 -430.689766) (xy 148.23807 -430.67468)
			(xy 148.239848 -430.644562) (xy 148.241512 -430.629568) (xy 148.241512 -430.018952) (xy 148.241924 -430.006873)
			(xy 148.249402 -429.983901) (xy 148.263611 -429.964363) (xy 148.283162 -429.950171) (xy 148.306141 -429.942713)
			(xy 148.31822 -429.942244) (xy 149.25802 -429.942244) (xy 149.270091 -429.942747) (xy 149.29305 -429.950209)
			(xy 149.312583 -429.964397) (xy 149.326778 -429.983924) (xy 149.334249 -430.006881) (xy 149.334728 -430.018952)
			(xy 149.334728 -430.889918) (xy 150.237952 -430.889918) (xy 150.238061 -430.874832) (xy 150.239843 -430.844714)
			(xy 150.241508 -430.82972) (xy 150.241508 -429.749966) (xy 150.239843 -429.734972) (xy 150.238062 -429.704854)
			(xy 150.237952 -429.689768) (xy 150.238066 -429.674682) (xy 150.239844 -429.644564) (xy 150.241508 -429.62957)
			(xy 150.241508 -429.018954) (xy 150.241968 -429.006865) (xy 150.249433 -428.983868) (xy 150.263623 -428.964292)
			(xy 150.283155 -428.950042) (xy 150.306129 -428.942505) (xy 150.318216 -428.941992) (xy 151.258016 -428.941992)
			(xy 151.270125 -428.942402) (xy 151.293151 -428.949905) (xy 151.312724 -428.964169) (xy 151.326918 -428.983791)
			(xy 151.33434 -429.006844) (xy 151.334724 -429.018954) (xy 151.334724 -431.560478) (xy 151.334273 -431.57257)
			(xy 151.326818 -431.595576) (xy 151.312629 -431.615159) (xy 151.293089 -431.629409) (xy 151.270106 -431.636935)
			(xy 151.258016 -431.63744) (xy 150.318216 -431.63744) (xy 150.306112 -431.63697) (xy 150.283092 -431.62948)
			(xy 150.263522 -431.615231) (xy 150.249326 -431.595623) (xy 150.241897 -431.572583) (xy 150.241508 -431.560478)
			(xy 150.241508 -430.950116) (xy 150.239839 -430.935123) (xy 150.238061 -430.905004) (xy 150.237952 -430.889918)
			(xy 149.334728 -430.889918) (xy 149.334728 -431.889916) (xy 152.237948 -431.889916) (xy 152.238057 -431.87483)
			(xy 152.239839 -431.844712) (xy 152.241504 -431.829718) (xy 152.241504 -430.749964) (xy 152.239839 -430.73497)
			(xy 152.238058 -430.704852) (xy 152.237948 -430.689766) (xy 152.238062 -430.67468) (xy 152.23984 -430.644562)
			(xy 152.241504 -430.629568) (xy 152.241504 -430.018952) (xy 152.241923 -430.006874) (xy 152.249401 -429.983903)
			(xy 152.263608 -429.964366) (xy 152.283157 -429.950173) (xy 152.306133 -429.942714) (xy 152.318212 -429.942244)
			(xy 153.258012 -429.942244) (xy 153.270082 -429.942753) (xy 153.293042 -429.950213) (xy 153.312574 -429.9644)
			(xy 153.32677 -429.983926) (xy 153.334241 -430.006882) (xy 153.33472 -430.018952) (xy 153.33472 -430.889918)
			(xy 154.237944 -430.889918) (xy 154.238053 -430.874832) (xy 154.239835 -430.844714) (xy 154.2415 -430.82972)
			(xy 154.2415 -429.749966) (xy 154.239835 -429.734972) (xy 154.238054 -429.704854) (xy 154.237944 -429.689768)
			(xy 154.238058 -429.674682) (xy 154.239836 -429.644564) (xy 154.2415 -429.62957) (xy 154.2415 -429.018954)
			(xy 154.241967 -429.006866) (xy 154.249432 -428.983871) (xy 154.26362 -428.964295) (xy 154.28315 -428.950044)
			(xy 154.306122 -428.942507) (xy 154.318208 -428.941992) (xy 155.258008 -428.941992) (xy 155.270117 -428.942409)
			(xy 155.293143 -428.94991) (xy 155.312715 -428.964172) (xy 155.32691 -428.983792) (xy 155.334332 -429.006844)
			(xy 155.334716 -429.018954) (xy 155.334716 -431.560478) (xy 155.334273 -431.572571) (xy 155.326817 -431.595578)
			(xy 155.312626 -431.615162) (xy 155.293084 -431.629412) (xy 155.270099 -431.636937) (xy 155.258008 -431.63744)
			(xy 154.318208 -431.63744) (xy 154.306104 -431.636978) (xy 154.283083 -431.629485) (xy 154.263513 -431.615234)
			(xy 154.249317 -431.595625) (xy 154.241889 -431.572584) (xy 154.2415 -431.560478) (xy 154.2415 -430.950116)
			(xy 154.239831 -430.935123) (xy 154.238053 -430.905004) (xy 154.237944 -430.889918) (xy 153.33472 -430.889918)
			(xy 153.33472 -431.889916) (xy 156.23794 -431.889916) (xy 156.238051 -431.87483) (xy 156.239833 -431.844712)
			(xy 156.241496 -431.829718) (xy 156.241496 -430.749964) (xy 156.239831 -430.73497) (xy 156.23805 -430.704852)
			(xy 156.23794 -430.689766) (xy 156.238054 -430.67468) (xy 156.239832 -430.644562) (xy 156.241496 -430.629568)
			(xy 156.241496 -430.018952) (xy 156.241923 -430.006875) (xy 156.249399 -429.983905) (xy 156.263605 -429.964368)
			(xy 156.283152 -429.950176) (xy 156.306126 -429.942715) (xy 156.318204 -429.942244) (xy 157.258004 -429.942244)
			(xy 157.270074 -429.94276) (xy 157.293033 -429.950218) (xy 157.312566 -429.964403) (xy 157.326762 -429.983927)
			(xy 157.334233 -430.006882) (xy 157.334712 -430.018952) (xy 157.334712 -432.560476) (xy 157.334267 -432.572557)
			(xy 157.326806 -432.595538) (xy 157.312609 -432.615089) (xy 157.293063 -432.629294) (xy 157.270085 -432.636762)
			(xy 157.258004 -432.637184) (xy 156.318204 -432.637184) (xy 156.306119 -432.636784) (xy 156.283132 -432.629314)
			(xy 156.26358 -432.615106) (xy 156.249376 -432.59555) (xy 156.241913 -432.572561) (xy 156.241496 -432.560476)
			(xy 156.241496 -431.950114) (xy 156.239826 -431.935121) (xy 156.238049 -431.905002) (xy 156.23794 -431.889916)
			(xy 153.33472 -431.889916) (xy 153.33472 -432.560476) (xy 153.334267 -432.572556) (xy 153.326807 -432.595536)
			(xy 153.312611 -432.615086) (xy 153.293068 -432.629291) (xy 153.270092 -432.636761) (xy 153.258012 -432.637184)
			(xy 152.318212 -432.637184) (xy 152.306128 -432.636777) (xy 152.283141 -432.629309) (xy 152.263589 -432.615103)
			(xy 152.249385 -432.595548) (xy 152.241922 -432.572561) (xy 152.241504 -432.560476) (xy 152.241504 -431.950114)
			(xy 152.239834 -431.935121) (xy 152.238057 -431.905002) (xy 152.237948 -431.889916) (xy 149.334728 -431.889916)
			(xy 149.334728 -432.560476) (xy 149.334267 -432.572555) (xy 149.326809 -432.595534) (xy 149.312614 -432.615083)
			(xy 149.293073 -432.629288) (xy 149.270099 -432.63676) (xy 149.25802 -432.637184) (xy 148.31822 -432.637184)
			(xy 148.306136 -432.63677) (xy 148.28315 -432.629305) (xy 148.263597 -432.6151) (xy 148.249393 -432.595547)
			(xy 148.24193 -432.57256) (xy 148.241512 -432.560476) (xy 148.241512 -431.950114) (xy 148.239842 -431.935121)
			(xy 148.238065 -431.905002) (xy 148.237956 -431.889916) (xy 145.334736 -431.889916) (xy 145.334736 -432.560476)
			(xy 145.334216 -432.572547) (xy 145.326763 -432.595508) (xy 145.31258 -432.615043) (xy 145.293055 -432.62924)
			(xy 145.270098 -432.636708) (xy 145.258028 -432.637184) (xy 144.318228 -432.637184) (xy 144.306144 -432.636763)
			(xy 144.283159 -432.6293) (xy 144.263606 -432.615097) (xy 144.249402 -432.595545) (xy 144.241938 -432.57256)
			(xy 144.24152 -432.560476) (xy 144.24152 -431.950114) (xy 144.23985 -431.935121) (xy 144.238073 -431.905002)
			(xy 144.237964 -431.889916) (xy 140.335 -431.889916) (xy 140.335 -432.560476) (xy 140.334563 -432.572584)
			(xy 140.32707 -432.59561) (xy 140.312814 -432.615184) (xy 140.293196 -432.629379) (xy 140.270147 -432.6368)
			(xy 140.258038 -432.637184) (xy 139.318238 -432.637184) (xy 139.306153 -432.636661) (xy 139.283157 -432.629217)
			(xy 139.263579 -432.615044) (xy 139.249326 -432.595524) (xy 139.241789 -432.572559) (xy 139.241276 -432.560476)
			(xy 139.241276 -431.948082) (xy 139.239733 -431.93359) (xy 139.23808 -431.90449) (xy 139.237974 -431.889916)
			(xy 136.335008 -431.889916) (xy 136.335008 -432.560476) (xy 136.334563 -432.572583) (xy 136.327071 -432.595608)
			(xy 136.312817 -432.615181) (xy 136.293201 -432.629376) (xy 136.270154 -432.636799) (xy 136.258046 -432.637184)
			(xy 135.318246 -432.637184) (xy 135.306161 -432.636654) (xy 135.283166 -432.629213) (xy 135.263587 -432.615042)
			(xy 135.249334 -432.595522) (xy 135.241797 -432.572559) (xy 135.241284 -432.560476) (xy 135.241284 -431.948082)
			(xy 135.239741 -431.93359) (xy 135.238088 -431.90449) (xy 135.237982 -431.889916) (xy 132.335016 -431.889916)
			(xy 132.335016 -432.560476) (xy 132.334563 -432.572582) (xy 132.327072 -432.595606) (xy 132.31282 -432.615178)
			(xy 132.293206 -432.629374) (xy 132.270161 -432.636798) (xy 132.258054 -432.637184) (xy 131.318254 -432.637184)
			(xy 131.306164 -432.636732) (xy 131.283166 -432.629266) (xy 131.263589 -432.615074) (xy 131.249339 -432.59554)
			(xy 131.241804 -432.572564) (xy 131.241292 -432.560476) (xy 131.241292 -431.948082) (xy 131.239749 -431.93359)
			(xy 131.238096 -431.90449) (xy 131.23799 -431.889916) (xy 128.335024 -431.889916) (xy 128.335024 -432.560476)
			(xy 128.334563 -432.572581) (xy 128.327074 -432.595604) (xy 128.312823 -432.615175) (xy 128.293212 -432.629371)
			(xy 128.270168 -432.636797) (xy 128.258062 -432.637184) (xy 127.318262 -432.637184) (xy 127.306173 -432.636726)
			(xy 127.283175 -432.629261) (xy 127.263598 -432.615072) (xy 127.249348 -432.595538) (xy 127.241812 -432.572564)
			(xy 127.2413 -432.560476) (xy 127.2413 -431.948082) (xy 127.239756 -431.93359) (xy 127.238104 -431.90449)
			(xy 127.237998 -431.889916) (xy 115.899624 -431.889916) (xy 115.888879 -431.969464) (xy 115.857765 -432.141485)
			(xy 115.819 -432.311944) (xy 115.772659 -432.480502) (xy 115.718836 -432.646822) (xy 115.657638 -432.810572)
			(xy 115.623848 -432.891184) (xy 115.623848 -434.48986) (xy 125.238002 -434.48986) (xy 125.2381 -434.475286)
			(xy 125.239749 -434.446185) (xy 125.241304 -434.431694) (xy 125.241304 -433.34813) (xy 125.239756 -433.333638)
			(xy 125.238106 -433.304538) (xy 125.238002 -433.289964) (xy 125.2381 -433.27539) (xy 125.239749 -433.246289)
			(xy 125.241304 -433.231798) (xy 125.241304 -432.618896) (xy 125.241713 -432.606787) (xy 125.249214 -432.583758)
			(xy 125.263477 -432.564185) (xy 125.283101 -432.549991) (xy 125.306155 -432.542571) (xy 125.318266 -432.542188)
			(xy 126.258066 -432.542188) (xy 126.270159 -432.542637) (xy 126.293166 -432.55009) (xy 126.312751 -432.56428)
			(xy 126.327001 -432.583821) (xy 126.334525 -432.606805) (xy 126.335028 -432.618896) (xy 126.335028 -435.16042)
			(xy 126.334601 -435.172527) (xy 126.3271 -435.19555) (xy 126.31284 -435.215121) (xy 126.293222 -435.229316)
			(xy 126.270174 -435.236741) (xy 126.258066 -435.237128) (xy 125.318266 -435.237128) (xy 125.306171 -435.236721)
			(xy 125.283164 -435.229251) (xy 125.263582 -435.21505) (xy 125.249334 -435.195502) (xy 125.241808 -435.172513)
			(xy 125.241304 -435.16042) (xy 125.241304 -434.548026) (xy 125.239756 -434.533534) (xy 125.238106 -434.504434)
			(xy 125.238002 -434.48986) (xy 115.623848 -434.48986) (xy 115.623848 -435.489858) (xy 127.237998 -435.489858)
			(xy 127.238095 -435.475284) (xy 127.239745 -435.446183) (xy 127.2413 -435.431692) (xy 127.2413 -434.348128)
			(xy 127.239752 -434.333636) (xy 127.238102 -434.304536) (xy 127.237998 -434.289962) (xy 127.238096 -434.275388)
			(xy 127.239745 -434.246287) (xy 127.2413 -434.231796) (xy 127.2413 -433.618894) (xy 127.241806 -433.606783)
			(xy 127.24929 -433.583746) (xy 127.263525 -433.564148) (xy 127.283117 -433.549905) (xy 127.306151 -433.542411)
			(xy 127.318262 -433.541932) (xy 128.258062 -433.541932) (xy 128.270182 -433.542392) (xy 128.293239 -433.549873)
			(xy 128.312854 -433.564115) (xy 128.327107 -433.583722) (xy 128.334601 -433.606774) (xy 128.335024 -433.618894)
			(xy 128.335024 -434.48986) (xy 129.237994 -434.48986) (xy 129.238092 -434.475286) (xy 129.239741 -434.446185)
			(xy 129.241296 -434.431694) (xy 129.241296 -433.34813) (xy 129.239748 -433.333638) (xy 129.238098 -433.304538)
			(xy 129.237994 -433.289964) (xy 129.238092 -433.27539) (xy 129.239741 -433.246289) (xy 129.241296 -433.231798)
			(xy 129.241296 -432.618896) (xy 129.241713 -432.606787) (xy 129.249213 -432.583761) (xy 129.263474 -432.564188)
			(xy 129.283096 -432.549993) (xy 129.306148 -432.542572) (xy 129.318258 -432.542188) (xy 130.258058 -432.542188)
			(xy 130.27015 -432.542644) (xy 130.293158 -432.550095) (xy 130.312742 -432.564283) (xy 130.326993 -432.583822)
			(xy 130.334517 -432.606805) (xy 130.33502 -432.618896) (xy 130.33502 -435.16042) (xy 130.334601 -435.172528)
			(xy 130.327099 -435.195552) (xy 130.312837 -435.215123) (xy 130.293217 -435.229318) (xy 130.270167 -435.236742)
			(xy 130.258058 -435.237128) (xy 129.318258 -435.237128) (xy 129.306163 -435.236728) (xy 129.283156 -435.229256)
			(xy 129.263574 -435.215053) (xy 129.249326 -435.195504) (xy 129.2418 -435.172514) (xy 129.241296 -435.16042)
			(xy 129.241296 -434.548026) (xy 129.239748 -434.533534) (xy 129.238098 -434.504434) (xy 129.237994 -434.48986)
			(xy 128.335024 -434.48986) (xy 128.335024 -435.489858) (xy 131.23799 -435.489858) (xy 131.238087 -435.475284)
			(xy 131.239737 -435.446183) (xy 131.241292 -435.431692) (xy 131.241292 -434.348128) (xy 131.239744 -434.333636)
			(xy 131.238094 -434.304536) (xy 131.23799 -434.289962) (xy 131.238088 -434.275388) (xy 131.239737 -434.246287)
			(xy 131.241292 -434.231796) (xy 131.241292 -433.618894) (xy 131.241806 -433.606784) (xy 131.249289 -433.583748)
			(xy 131.263522 -433.564151) (xy 131.283112 -433.549908) (xy 131.306144 -433.542412) (xy 131.318254 -433.541932)
			(xy 132.258054 -433.541932) (xy 132.270174 -433.542399) (xy 132.29323 -433.549878) (xy 132.312846 -433.564117)
			(xy 132.327098 -433.583723) (xy 132.334593 -433.606775) (xy 132.335016 -433.618894) (xy 132.335016 -434.48986)
			(xy 133.237986 -434.48986) (xy 133.238084 -434.475286) (xy 133.239733 -434.446185) (xy 133.241288 -434.431694)
			(xy 133.241288 -433.34813) (xy 133.23974 -433.333638) (xy 133.23809 -433.304538) (xy 133.237986 -433.289964)
			(xy 133.238084 -433.27539) (xy 133.239733 -433.246289) (xy 133.241288 -433.231798) (xy 133.241288 -432.618896)
			(xy 133.241713 -432.606788) (xy 133.249212 -432.583763) (xy 133.263472 -432.564191) (xy 133.283091 -432.549996)
			(xy 133.306141 -432.542573) (xy 133.31825 -432.542188) (xy 134.25805 -432.542188) (xy 134.270142 -432.542651)
			(xy 134.293149 -432.5501) (xy 134.312734 -432.564285) (xy 134.326984 -432.583823) (xy 134.334509 -432.606806)
			(xy 134.335012 -432.618896) (xy 134.335012 -435.16042) (xy 134.334601 -435.172529) (xy 134.327097 -435.195555)
			(xy 134.312834 -435.215126) (xy 134.293212 -435.229321) (xy 134.27016 -435.236743) (xy 134.25805 -435.237128)
			(xy 133.31825 -435.237128) (xy 133.30616 -435.23665) (xy 133.283155 -435.229203) (xy 133.263572 -435.21502)
			(xy 133.249321 -435.195487) (xy 133.241793 -435.172508) (xy 133.241288 -435.16042) (xy 133.241288 -434.548026)
			(xy 133.23974 -434.533534) (xy 133.23809 -434.504434) (xy 133.237986 -434.48986) (xy 132.335016 -434.48986)
			(xy 132.335016 -435.489858) (xy 135.237982 -435.489858) (xy 135.238079 -435.475284) (xy 135.239729 -435.446183)
			(xy 135.241284 -435.431692) (xy 135.241284 -434.348128) (xy 135.239736 -434.333636) (xy 135.238086 -434.304536)
			(xy 135.237982 -434.289962) (xy 135.23808 -434.275388) (xy 135.239729 -434.246287) (xy 135.241284 -434.231796)
			(xy 135.241284 -433.618894) (xy 135.241656 -433.606766) (xy 135.249155 -433.5837) (xy 135.263418 -433.564081)
			(xy 135.283046 -433.549831) (xy 135.306118 -433.542348) (xy 135.318246 -433.541932) (xy 136.258046 -433.541932)
			(xy 136.270162 -433.542372) (xy 136.293206 -433.549872) (xy 136.312807 -433.564122) (xy 136.327047 -433.58373)
			(xy 136.334534 -433.606777) (xy 136.335008 -433.618894) (xy 136.335008 -434.48986) (xy 137.237978 -434.48986)
			(xy 137.238076 -434.475286) (xy 137.239725 -434.446185) (xy 137.24128 -434.431694) (xy 137.24128 -433.34813)
			(xy 137.239732 -433.333638) (xy 137.238082 -433.304538) (xy 137.237978 -433.289964) (xy 137.238076 -433.27539)
			(xy 137.239726 -433.246289) (xy 137.24128 -433.231798) (xy 137.24128 -432.618896) (xy 137.241712 -432.606789)
			(xy 137.249211 -432.583765) (xy 137.263469 -432.564194) (xy 137.283086 -432.549998) (xy 137.306134 -432.542574)
			(xy 137.318242 -432.542188) (xy 138.258042 -432.542188) (xy 138.270139 -432.542572) (xy 138.293149 -432.550047)
			(xy 138.312732 -432.564253) (xy 138.326979 -432.583806) (xy 138.334502 -432.606801) (xy 138.335004 -432.618896)
			(xy 138.335004 -435.16042) (xy 138.334601 -435.17253) (xy 138.327096 -435.195557) (xy 138.312831 -435.215129)
			(xy 138.293207 -435.229323) (xy 138.270153 -435.236744) (xy 138.258042 -435.237128) (xy 137.318242 -435.237128)
			(xy 137.306151 -435.236656) (xy 137.283147 -435.229207) (xy 137.263563 -435.215023) (xy 137.249313 -435.195488)
			(xy 137.241785 -435.172509) (xy 137.24128 -435.16042) (xy 137.24128 -434.548026) (xy 137.239732 -434.533534)
			(xy 137.238082 -434.504434) (xy 137.237978 -434.48986) (xy 136.335008 -434.48986) (xy 136.335008 -435.489858)
			(xy 139.237974 -435.489858) (xy 139.238072 -435.475284) (xy 139.239721 -435.446183) (xy 139.241276 -435.431692)
			(xy 139.241276 -434.348128) (xy 139.239728 -434.333636) (xy 139.238078 -434.304536) (xy 139.237974 -434.289962)
			(xy 139.238072 -434.275388) (xy 139.239721 -434.246287) (xy 139.241276 -434.231796) (xy 139.241276 -433.618894)
			(xy 139.241656 -433.606767) (xy 139.249154 -433.583702) (xy 139.263415 -433.564084) (xy 139.283041 -433.549834)
			(xy 139.306111 -433.542349) (xy 139.318238 -433.541932) (xy 140.258038 -433.541932) (xy 140.270154 -433.542379)
			(xy 140.293197 -433.549876) (xy 140.312798 -433.564125) (xy 140.327038 -433.583731) (xy 140.334526 -433.606778)
			(xy 140.335 -433.618894) (xy 140.335 -434.48986) (xy 142.237968 -434.48986) (xy 142.238081 -434.474774)
			(xy 142.23986 -434.444656) (xy 142.241524 -434.429662) (xy 142.241524 -433.350162) (xy 142.239859 -433.335168)
			(xy 142.238078 -433.30505) (xy 142.237968 -433.289964) (xy 142.238081 -433.274878) (xy 142.23986 -433.24476)
			(xy 142.241524 -433.229766) (xy 142.241524 -432.618896) (xy 142.24191 -432.60681) (xy 142.249382 -432.583822)
			(xy 142.263594 -432.564268) (xy 142.283154 -432.550066) (xy 142.306146 -432.542604) (xy 142.318232 -432.542188)
			(xy 143.258032 -432.542188) (xy 143.270108 -432.542637) (xy 143.293075 -432.550108) (xy 143.312612 -432.564308)
			(xy 143.326805 -432.58385) (xy 143.334268 -432.60682) (xy 143.33474 -432.618896) (xy 143.33474 -435.16042)
			(xy 143.334253 -435.172492) (xy 143.326789 -435.195455) (xy 143.312597 -435.214989) (xy 143.293065 -435.229184)
			(xy 143.270104 -435.236651) (xy 143.258032 -435.237128) (xy 142.318232 -435.237128) (xy 142.306153 -435.23666)
			(xy 142.283175 -435.229204) (xy 142.263626 -435.215011) (xy 142.24942 -435.195472) (xy 142.241948 -435.172499)
			(xy 142.241524 -435.16042) (xy 142.241524 -434.550058) (xy 142.239858 -434.535064) (xy 142.238078 -434.504946)
			(xy 142.237968 -434.48986) (xy 140.335 -434.48986) (xy 140.335 -435.489858) (xy 144.237964 -435.489858)
			(xy 144.238077 -435.474772) (xy 144.239856 -435.444654) (xy 144.24152 -435.42966) (xy 144.24152 -434.35016)
			(xy 144.239855 -434.335166) (xy 144.238074 -434.305048) (xy 144.237964 -434.289962) (xy 144.238077 -434.274876)
			(xy 144.239856 -434.244758) (xy 144.24152 -434.229764) (xy 144.24152 -433.618894) (xy 144.242002 -433.606806)
			(xy 144.249458 -433.583809) (xy 144.263641 -433.564231) (xy 144.28317 -433.54998) (xy 144.306142 -433.542444)
			(xy 144.318228 -433.541932) (xy 145.258028 -433.541932) (xy 145.270142 -433.542293) (xy 145.293175 -433.549804)
			(xy 145.312751 -433.564079) (xy 145.326943 -433.583714) (xy 145.334357 -433.606779) (xy 145.334736 -433.618894)
			(xy 145.334736 -434.48986) (xy 146.23796 -434.48986) (xy 146.238073 -434.474774) (xy 146.239852 -434.444656)
			(xy 146.241516 -434.429662) (xy 146.241516 -433.350162) (xy 146.239851 -433.335168) (xy 146.23807 -433.30505)
			(xy 146.23796 -433.289964) (xy 146.238073 -433.274878) (xy 146.239852 -433.24476) (xy 146.241516 -433.229766)
			(xy 146.241516 -432.618896) (xy 146.241909 -432.606811) (xy 146.249381 -432.583824) (xy 146.263591 -432.564271)
			(xy 146.283149 -432.550068) (xy 146.306138 -432.542605) (xy 146.318224 -432.542188) (xy 147.258024 -432.542188)
			(xy 147.270099 -432.542644) (xy 147.293067 -432.550113) (xy 147.312603 -432.564311) (xy 147.326797 -432.583851)
			(xy 147.334259 -432.606821) (xy 147.334732 -432.618896) (xy 147.334732 -435.16042) (xy 147.334253 -435.172493)
			(xy 147.326788 -435.195457) (xy 147.312594 -435.214991) (xy 147.29306 -435.229186) (xy 147.270097 -435.236652)
			(xy 147.258024 -435.237128) (xy 146.318224 -435.237128) (xy 146.306145 -435.236667) (xy 146.283166 -435.229209)
			(xy 146.263617 -435.215014) (xy 146.249412 -435.195473) (xy 146.24194 -435.172499) (xy 146.241516 -435.16042)
			(xy 146.241516 -434.550058) (xy 146.23985 -434.535064) (xy 146.23807 -434.504946) (xy 146.23796 -434.48986)
			(xy 145.334736 -434.48986) (xy 145.334736 -435.489858) (xy 148.237956 -435.489858) (xy 148.238069 -435.474772)
			(xy 148.239848 -435.444654) (xy 148.241512 -435.42966) (xy 148.241512 -434.35016) (xy 148.239847 -434.335166)
			(xy 148.238066 -434.305048) (xy 148.237956 -434.289962) (xy 148.238069 -434.274876) (xy 148.239848 -434.244758)
			(xy 148.241512 -434.229764) (xy 148.241512 -433.618894) (xy 148.242002 -433.606807) (xy 148.249457 -433.583811)
			(xy 148.263639 -433.564234) (xy 148.283165 -433.549982) (xy 148.306135 -433.542445) (xy 148.31822 -433.541932)
			(xy 149.25802 -433.541932) (xy 149.270133 -433.5423) (xy 149.293167 -433.549808) (xy 149.312742 -433.564081)
			(xy 149.326935 -433.583715) (xy 149.334349 -433.606779) (xy 149.334728 -433.618894) (xy 149.334728 -434.48986)
			(xy 150.237952 -434.48986) (xy 150.238065 -434.474774) (xy 150.239844 -434.444656) (xy 150.241508 -434.429662)
			(xy 150.241508 -433.350162) (xy 150.239843 -433.335168) (xy 150.238062 -433.30505) (xy 150.237952 -433.289964)
			(xy 150.238065 -433.274878) (xy 150.239844 -433.24476) (xy 150.241508 -433.229766) (xy 150.241508 -432.618896)
			(xy 150.241909 -432.606811) (xy 150.24938 -432.583826) (xy 150.263588 -432.564274) (xy 150.283144 -432.550071)
			(xy 150.306131 -432.542606) (xy 150.318216 -432.542188) (xy 151.258016 -432.542188) (xy 151.270091 -432.542651)
			(xy 151.293058 -432.550117) (xy 151.312594 -432.564314) (xy 151.326788 -432.583853) (xy 151.334251 -432.606821)
			(xy 151.334724 -432.618896) (xy 151.334724 -435.16042) (xy 151.334253 -435.172494) (xy 151.326787 -435.195459)
			(xy 151.312591 -435.214994) (xy 151.293055 -435.229189) (xy 151.27009 -435.236654) (xy 151.258016 -435.237128)
			(xy 150.318216 -435.237128) (xy 150.306144 -435.236622) (xy 150.283181 -435.229167) (xy 150.263645 -435.21498)
			(xy 150.24945 -435.195451) (xy 150.241983 -435.172492) (xy 150.241508 -435.16042) (xy 150.241508 -434.550058)
			(xy 150.239842 -434.535064) (xy 150.238062 -434.504946) (xy 150.237952 -434.48986) (xy 149.334728 -434.48986)
			(xy 149.334728 -435.489858) (xy 152.237948 -435.489858) (xy 152.238061 -435.474772) (xy 152.23984 -435.444654)
			(xy 152.241504 -435.42966) (xy 152.241504 -434.35016) (xy 152.239838 -434.335166) (xy 152.238058 -434.305048)
			(xy 152.237948 -434.289962) (xy 152.238061 -434.274876) (xy 152.23984 -434.244758) (xy 152.241504 -434.229764)
			(xy 152.241504 -433.618894) (xy 152.242002 -433.606808) (xy 152.249456 -433.583813) (xy 152.263636 -433.564236)
			(xy 152.28316 -433.549985) (xy 152.306128 -433.542447) (xy 152.318212 -433.541932) (xy 153.258012 -433.541932)
			(xy 153.270125 -433.542306) (xy 153.293158 -433.549813) (xy 153.312734 -433.564084) (xy 153.326927 -433.583717)
			(xy 153.334341 -433.60678) (xy 153.33472 -433.618894) (xy 153.33472 -434.48986) (xy 154.237944 -434.48986)
			(xy 154.238057 -434.474774) (xy 154.239836 -434.444656) (xy 154.2415 -434.429662) (xy 154.2415 -433.350162)
			(xy 154.239835 -433.335168) (xy 154.238054 -433.30505) (xy 154.237944 -433.289964) (xy 154.238057 -433.274878)
			(xy 154.239836 -433.24476) (xy 154.2415 -433.229766) (xy 154.2415 -432.618896) (xy 154.241909 -432.606812)
			(xy 154.249379 -432.583828) (xy 154.263586 -432.564277) (xy 154.283139 -432.550073) (xy 154.306124 -432.542607)
			(xy 154.318208 -432.542188) (xy 155.258008 -432.542188) (xy 155.270083 -432.542657) (xy 155.293049 -432.550122)
			(xy 155.312586 -432.564317) (xy 155.32678 -432.583854) (xy 155.334243 -432.606821) (xy 155.334716 -432.618896)
			(xy 155.334716 -435.16042) (xy 155.334253 -435.172495) (xy 155.326786 -435.195461) (xy 155.312589 -435.214997)
			(xy 155.29305 -435.229191) (xy 155.270083 -435.236655) (xy 155.258008 -435.237128) (xy 154.318208 -435.237128)
			(xy 154.306136 -435.236629) (xy 154.283172 -435.229171) (xy 154.263637 -435.214983) (xy 154.249441 -435.195453)
			(xy 154.241975 -435.172492) (xy 154.2415 -435.16042) (xy 154.2415 -434.550058) (xy 154.239834 -434.535064)
			(xy 154.238054 -434.504946) (xy 154.237944 -434.48986) (xy 153.33472 -434.48986) (xy 153.33472 -435.489858)
			(xy 156.23794 -435.489858) (xy 156.238053 -435.474772) (xy 156.239832 -435.444654) (xy 156.241496 -435.42966)
			(xy 156.241496 -434.35016) (xy 156.23983 -434.335166) (xy 156.23805 -434.305048) (xy 156.23794 -434.289962)
			(xy 156.238053 -434.274876) (xy 156.239832 -434.244758) (xy 156.241496 -434.229764) (xy 156.241496 -433.618894)
			(xy 156.242002 -433.606809) (xy 156.249455 -433.583815) (xy 156.263633 -433.564239) (xy 156.283155 -433.549987)
			(xy 156.30612 -433.542448) (xy 156.318204 -433.541932) (xy 157.258004 -433.541932) (xy 157.270116 -433.542313)
			(xy 157.293149 -433.549818) (xy 157.312725 -433.564087) (xy 157.326918 -433.583718) (xy 157.334333 -433.60678)
			(xy 157.334712 -433.618894) (xy 157.334712 -436.160418) (xy 157.334307 -436.172513) (xy 157.32684 -436.195523)
			(xy 157.312639 -436.215106) (xy 157.293089 -436.229355) (xy 157.270098 -436.236878) (xy 157.258004 -436.23738)
			(xy 156.318204 -436.23738) (xy 156.306093 -436.23698) (xy 156.283063 -436.229479) (xy 156.263488 -436.215214)
			(xy 156.249294 -436.195588) (xy 156.241876 -436.17253) (xy 156.241496 -436.160418) (xy 156.241496 -435.550056)
			(xy 156.23983 -435.535062) (xy 156.23805 -435.504944) (xy 156.23794 -435.489858) (xy 153.33472 -435.489858)
			(xy 153.33472 -436.160418) (xy 153.334307 -436.172513) (xy 153.326841 -436.195521) (xy 153.312642 -436.215104)
			(xy 153.293094 -436.229352) (xy 153.270105 -436.236877) (xy 153.258012 -436.23738) (xy 152.318212 -436.23738)
			(xy 152.306102 -436.236973) (xy 152.283072 -436.229474) (xy 152.263497 -436.215211) (xy 152.249302 -436.195586)
			(xy 152.241885 -436.17253) (xy 152.241504 -436.160418) (xy 152.241504 -435.550056) (xy 152.239838 -435.535062)
			(xy 152.238058 -435.504944) (xy 152.237948 -435.489858) (xy 149.334728 -435.489858) (xy 149.334728 -436.160418)
			(xy 149.334308 -436.172512) (xy 149.326842 -436.195518) (xy 149.312645 -436.215101) (xy 149.293099 -436.22935)
			(xy 149.270112 -436.236876) (xy 149.25802 -436.23738) (xy 148.31822 -436.23738) (xy 148.30611 -436.236966)
			(xy 148.28308 -436.22947) (xy 148.263505 -436.215208) (xy 148.249311 -436.195585) (xy 148.241893 -436.172529)
			(xy 148.241512 -436.160418) (xy 148.241512 -435.550056) (xy 148.239846 -435.535062) (xy 148.238066 -435.504944)
			(xy 148.237956 -435.489858) (xy 145.334736 -435.489858) (xy 145.334736 -436.160418) (xy 145.334308 -436.172511)
			(xy 145.326843 -436.195516) (xy 145.312647 -436.215098) (xy 145.293104 -436.229347) (xy 145.27012 -436.236874)
			(xy 145.258028 -436.23738) (xy 144.318228 -436.23738) (xy 144.306119 -436.236959) (xy 144.283089 -436.229465)
			(xy 144.263514 -436.215206) (xy 144.249319 -436.195583) (xy 144.241901 -436.172529) (xy 144.24152 -436.160418)
			(xy 144.24152 -435.550056) (xy 144.239854 -435.535062) (xy 144.238074 -435.504944) (xy 144.237964 -435.489858)
			(xy 140.335 -435.489858) (xy 140.335 -436.160418) (xy 140.334504 -436.17253) (xy 140.327017 -436.195567)
			(xy 140.31278 -436.215165) (xy 140.293185 -436.229408) (xy 140.27015 -436.236901) (xy 140.258038 -436.23738)
			(xy 139.318238 -436.23738) (xy 139.306119 -436.236908) (xy 139.283064 -436.229428) (xy 139.26345 -436.21519)
			(xy 139.249197 -436.195586) (xy 139.241701 -436.172537) (xy 139.241276 -436.160418) (xy 139.241276 -435.548024)
			(xy 139.239728 -435.533532) (xy 139.238078 -435.504432) (xy 139.237974 -435.489858) (xy 136.335008 -435.489858)
			(xy 136.335008 -436.160418) (xy 136.334505 -436.172529) (xy 136.327018 -436.195565) (xy 136.312782 -436.215163)
			(xy 136.29319 -436.229405) (xy 136.270157 -436.2369) (xy 136.258046 -436.23738) (xy 135.318246 -436.23738)
			(xy 135.306127 -436.236901) (xy 135.283073 -436.229424) (xy 135.263459 -436.215187) (xy 135.249205 -436.195584)
			(xy 135.241709 -436.172536) (xy 135.241284 -436.160418) (xy 135.241284 -435.548024) (xy 135.239736 -435.533532)
			(xy 135.238086 -435.504432) (xy 135.237982 -435.489858) (xy 132.335016 -435.489858) (xy 132.335016 -436.160418)
			(xy 132.334654 -436.172546) (xy 132.327152 -436.195613) (xy 132.312886 -436.215232) (xy 132.293256 -436.229481)
			(xy 132.270183 -436.236965) (xy 132.258054 -436.23738) (xy 131.318254 -436.23738) (xy 131.306139 -436.236928)
			(xy 131.283097 -436.22943) (xy 131.263498 -436.215182) (xy 131.249257 -436.195578) (xy 131.241768 -436.172533)
			(xy 131.241292 -436.160418) (xy 131.241292 -435.548024) (xy 131.239744 -435.533532) (xy 131.238094 -435.504432)
			(xy 131.23799 -435.489858) (xy 128.335024 -435.489858) (xy 128.335024 -436.160418) (xy 128.334655 -436.172545)
			(xy 128.327153 -436.195611) (xy 128.312889 -436.215229) (xy 128.293261 -436.229478) (xy 128.27019 -436.236963)
			(xy 128.258062 -436.23738) (xy 127.318262 -436.23738) (xy 127.306147 -436.236921) (xy 127.283106 -436.229425)
			(xy 127.263506 -436.21518) (xy 127.249265 -436.195576) (xy 127.241776 -436.172533) (xy 127.2413 -436.160418)
			(xy 127.2413 -435.548024) (xy 127.239751 -435.533532) (xy 127.238102 -435.504432) (xy 127.237998 -435.489858)
			(xy 115.623848 -435.489858) (xy 115.623848 -438.089802) (xy 125.238002 -438.089802) (xy 125.238095 -438.075228)
			(xy 125.239748 -438.046127) (xy 125.241304 -438.031636) (xy 125.241304 -436.948072) (xy 125.239759 -436.93358)
			(xy 125.238107 -436.90448) (xy 125.238002 -436.889906) (xy 125.238095 -436.875332) (xy 125.239748 -436.846231)
			(xy 125.241304 -436.83174) (xy 125.241304 -436.219092) (xy 125.241709 -436.206982) (xy 125.249212 -436.183954)
			(xy 125.263476 -436.164381) (xy 125.2831 -436.150186) (xy 125.306155 -436.142767) (xy 125.318266 -436.142384)
			(xy 126.258066 -436.142384) (xy 126.270158 -436.142837) (xy 126.293165 -436.15029) (xy 126.312749 -436.164478)
			(xy 126.327 -436.184018) (xy 126.334525 -436.207001) (xy 126.335028 -436.219092) (xy 126.335028 -438.760616)
			(xy 126.334598 -438.772723) (xy 126.327097 -438.795746) (xy 126.312838 -438.815316) (xy 126.293222 -438.829511)
			(xy 126.270174 -438.836937) (xy 126.258066 -438.837324) (xy 125.318266 -438.837324) (xy 125.306171 -438.836921)
			(xy 125.283163 -438.829451) (xy 125.263581 -438.815249) (xy 125.249333 -438.7957) (xy 125.241808 -438.77271)
			(xy 125.241304 -438.760616) (xy 125.241304 -438.147968) (xy 125.239759 -438.133476) (xy 125.238107 -438.104376)
			(xy 125.238002 -438.089802) (xy 115.623848 -438.089802) (xy 115.623848 -439.0898) (xy 127.237998 -439.0898)
			(xy 127.23809 -439.075226) (xy 127.239744 -439.046125) (xy 127.2413 -439.031634) (xy 127.2413 -437.94807)
			(xy 127.239755 -437.933578) (xy 127.238103 -437.904478) (xy 127.237998 -437.889904) (xy 127.238091 -437.87533)
			(xy 127.239744 -437.846229) (xy 127.2413 -437.831738) (xy 127.2413 -437.21909) (xy 127.241803 -437.206979)
			(xy 127.249288 -437.183942) (xy 127.263524 -437.164343) (xy 127.283117 -437.150101) (xy 127.306151 -437.142607)
			(xy 127.318262 -437.142128) (xy 128.258062 -437.142128) (xy 128.270182 -437.142592) (xy 128.293238 -437.150073)
			(xy 128.312853 -437.164313) (xy 128.327105 -437.183919) (xy 128.3346 -437.20697) (xy 128.335024 -437.21909)
			(xy 128.335024 -438.089802) (xy 129.237994 -438.089802) (xy 129.238087 -438.075228) (xy 129.23974 -438.046127)
			(xy 129.241296 -438.031636) (xy 129.241296 -436.948072) (xy 129.239752 -436.93358) (xy 129.238099 -436.90448)
			(xy 129.237994 -436.889906) (xy 129.238087 -436.875332) (xy 129.23974 -436.846231) (xy 129.241296 -436.83174)
			(xy 129.241296 -436.219092) (xy 129.241709 -436.206983) (xy 129.24921 -436.183956) (xy 129.263473 -436.164384)
			(xy 129.283095 -436.150189) (xy 129.306148 -436.142768) (xy 129.318258 -436.142384) (xy 130.258058 -436.142384)
			(xy 130.27015 -436.142844) (xy 130.293156 -436.150294) (xy 130.312741 -436.164481) (xy 130.326991 -436.184019)
			(xy 130.334516 -436.207002) (xy 130.33502 -436.219092) (xy 130.33502 -438.760616) (xy 130.334598 -438.772724)
			(xy 130.327096 -438.795748) (xy 130.312836 -438.815319) (xy 130.293217 -438.829514) (xy 130.270167 -438.836938)
			(xy 130.258058 -438.837324) (xy 129.318258 -438.837324) (xy 129.306163 -438.836928) (xy 129.283155 -438.829455)
			(xy 129.263572 -438.815252) (xy 129.249324 -438.795701) (xy 129.2418 -438.77271) (xy 129.241296 -438.760616)
			(xy 129.241296 -438.147968) (xy 129.239751 -438.133476) (xy 129.238099 -438.104376) (xy 129.237994 -438.089802)
			(xy 128.335024 -438.089802) (xy 128.335024 -439.0898) (xy 131.23799 -439.0898) (xy 131.238082 -439.075226)
			(xy 131.239736 -439.046125) (xy 131.241292 -439.031634) (xy 131.241292 -437.94807) (xy 131.239748 -437.933578)
			(xy 131.238095 -437.904478) (xy 131.23799 -437.889904) (xy 131.238083 -437.87533) (xy 131.239736 -437.846229)
			(xy 131.241292 -437.831738) (xy 131.241292 -437.21909) (xy 131.241803 -437.20698) (xy 131.249287 -437.183944)
			(xy 131.263521 -437.164346) (xy 131.283112 -437.150104) (xy 131.306144 -437.142608) (xy 131.318254 -437.142128)
			(xy 132.258054 -437.142128) (xy 132.270173 -437.142599) (xy 132.293229 -437.150077) (xy 132.312844 -437.164316)
			(xy 132.327097 -437.183921) (xy 132.334592 -437.206971) (xy 132.335016 -437.21909) (xy 132.335016 -438.089802)
			(xy 133.237986 -438.089802) (xy 133.238079 -438.075228) (xy 133.239732 -438.046127) (xy 133.241288 -438.031636)
			(xy 133.241288 -436.948072) (xy 133.239744 -436.93358) (xy 133.238091 -436.90448) (xy 133.237986 -436.889906)
			(xy 133.238079 -436.875332) (xy 133.239732 -436.846231) (xy 133.241288 -436.83174) (xy 133.241288 -436.219092)
			(xy 133.241709 -436.206984) (xy 133.249209 -436.183958) (xy 133.26347 -436.164386) (xy 133.28309 -436.150192)
			(xy 133.306141 -436.142769) (xy 133.31825 -436.142384) (xy 134.25805 -436.142384) (xy 134.270141 -436.142851)
			(xy 134.293148 -436.150299) (xy 134.312732 -436.164484) (xy 134.326983 -436.184021) (xy 134.334508 -436.207002)
			(xy 134.335012 -436.219092) (xy 134.335012 -438.760616) (xy 134.334598 -438.772725) (xy 134.327095 -438.79575)
			(xy 134.312833 -438.815322) (xy 134.293212 -438.829517) (xy 134.27016 -438.836939) (xy 134.25805 -438.837324)
			(xy 133.31825 -438.837324) (xy 133.306159 -438.836849) (xy 133.283154 -438.829402) (xy 133.26357 -438.815219)
			(xy 133.249319 -438.795684) (xy 133.241793 -438.772705) (xy 133.241288 -438.760616) (xy 133.241288 -438.147968)
			(xy 133.239743 -438.133476) (xy 133.238091 -438.104376) (xy 133.237986 -438.089802) (xy 132.335016 -438.089802)
			(xy 132.335016 -439.0898) (xy 135.237982 -439.0898) (xy 135.238075 -439.075226) (xy 135.239728 -439.046125)
			(xy 135.241284 -439.031634) (xy 135.241284 -437.94807) (xy 135.23974 -437.933578) (xy 135.238087 -437.904478)
			(xy 135.237982 -437.889904) (xy 135.238075 -437.87533) (xy 135.239728 -437.846229) (xy 135.241284 -437.831738)
			(xy 135.241284 -437.21909) (xy 135.241652 -437.206962) (xy 135.249153 -437.183895) (xy 135.263416 -437.164276)
			(xy 135.283045 -437.150027) (xy 135.306118 -437.142544) (xy 135.318246 -437.142128) (xy 136.258046 -437.142128)
			(xy 136.270162 -437.142572) (xy 136.293205 -437.150071) (xy 136.312805 -437.164321) (xy 136.327045 -437.183927)
			(xy 136.334533 -437.206974) (xy 136.335008 -437.21909) (xy 136.335008 -438.089802) (xy 137.237978 -438.089802)
			(xy 137.238071 -438.075228) (xy 137.239724 -438.046127) (xy 137.24128 -438.031636) (xy 137.24128 -436.948072)
			(xy 137.239736 -436.93358) (xy 137.238083 -436.90448) (xy 137.237978 -436.889906) (xy 137.238071 -436.875332)
			(xy 137.239724 -436.846231) (xy 137.24128 -436.83174) (xy 137.24128 -436.219092) (xy 137.241709 -436.206985)
			(xy 137.249208 -436.183961) (xy 137.263467 -436.164389) (xy 137.283085 -436.150194) (xy 137.306133 -436.14277)
			(xy 137.318242 -436.142384) (xy 138.258042 -436.142384) (xy 138.270138 -436.142772) (xy 138.293148 -436.150246)
			(xy 138.312731 -436.164451) (xy 138.326978 -436.184004) (xy 138.334501 -436.206997) (xy 138.335004 -436.219092)
			(xy 138.335004 -438.760616) (xy 138.334597 -438.772725) (xy 138.327094 -438.795752) (xy 138.31283 -438.815325)
			(xy 138.293207 -438.829519) (xy 138.270153 -438.83694) (xy 138.258042 -438.837324) (xy 137.318242 -438.837324)
			(xy 137.306151 -438.836856) (xy 137.283146 -438.829407) (xy 137.263562 -438.815222) (xy 137.249311 -438.795686)
			(xy 137.241785 -438.772705) (xy 137.24128 -438.760616) (xy 137.24128 -438.147968) (xy 137.239735 -438.133476)
			(xy 137.238083 -438.104376) (xy 137.237978 -438.089802) (xy 136.335008 -438.089802) (xy 136.335008 -439.0898)
			(xy 139.237974 -439.0898) (xy 139.238067 -439.075226) (xy 139.23972 -439.046125) (xy 139.241276 -439.031634)
			(xy 139.241276 -437.94807) (xy 139.239732 -437.933578) (xy 139.238079 -437.904478) (xy 139.237974 -437.889904)
			(xy 139.238067 -437.87533) (xy 139.23972 -437.846229) (xy 139.241276 -437.831738) (xy 139.241276 -437.21909)
			(xy 139.241652 -437.206963) (xy 139.249152 -437.183897) (xy 139.263413 -437.164279) (xy 139.28304 -437.15003)
			(xy 139.306111 -437.142545) (xy 139.318238 -437.142128) (xy 140.258038 -437.142128) (xy 140.270154 -437.142579)
			(xy 140.293196 -437.150076) (xy 140.312797 -437.164323) (xy 140.327037 -437.183929) (xy 140.334525 -437.206974)
			(xy 140.335 -437.21909) (xy 140.335 -438.089802) (xy 142.237968 -438.089802) (xy 142.238085 -438.074717)
			(xy 142.239861 -438.044598) (xy 142.241524 -438.029604) (xy 142.241524 -436.950104) (xy 142.239854 -436.935111)
			(xy 142.238076 -436.904992) (xy 142.237968 -436.889906) (xy 142.238076 -436.87482) (xy 142.239858 -436.844702)
			(xy 142.241524 -436.829708) (xy 142.241524 -436.219092) (xy 142.241906 -436.207006) (xy 142.24938 -436.184017)
			(xy 142.263593 -436.164464) (xy 142.283153 -436.150262) (xy 142.306145 -436.1428) (xy 142.318232 -436.142384)
			(xy 143.258032 -436.142384) (xy 143.270107 -436.142837) (xy 143.293074 -436.150307) (xy 143.31261 -436.164507)
			(xy 143.326804 -436.184047) (xy 143.334267 -436.207016) (xy 143.33474 -436.219092) (xy 143.33474 -438.760616)
			(xy 143.33425 -438.772688) (xy 143.326787 -438.79565) (xy 143.312596 -438.815184) (xy 143.293065 -438.829379)
			(xy 143.270104 -438.836847) (xy 143.258032 -438.837324) (xy 142.318232 -438.837324) (xy 142.306153 -438.83686)
			(xy 142.283174 -438.829403) (xy 142.263624 -438.81521) (xy 142.249418 -438.795669) (xy 142.241947 -438.772695)
			(xy 142.241524 -438.760616) (xy 142.241524 -438.15) (xy 142.239853 -438.135007) (xy 142.238076 -438.104888)
			(xy 142.237968 -438.089802) (xy 140.335 -438.089802) (xy 140.335 -439.0898) (xy 144.237964 -439.0898)
			(xy 144.23808 -439.074715) (xy 144.239857 -439.044596) (xy 144.24152 -439.029602) (xy 144.24152 -437.950102)
			(xy 144.239849 -437.935109) (xy 144.238072 -437.90499) (xy 144.237964 -437.889904) (xy 144.238081 -437.874819)
			(xy 144.239857 -437.8447) (xy 144.24152 -437.829706) (xy 144.24152 -437.21909) (xy 144.241999 -437.207002)
			(xy 144.249456 -437.184004) (xy 144.26364 -437.164426) (xy 144.28317 -437.150176) (xy 144.306142 -437.14264)
			(xy 144.318228 -437.142128) (xy 145.258028 -437.142128) (xy 145.270141 -437.142493) (xy 145.293174 -437.150003)
			(xy 145.312749 -437.164277) (xy 145.326942 -437.183911) (xy 145.334357 -437.206975) (xy 145.334736 -437.21909)
			(xy 145.334736 -438.089802) (xy 146.23796 -438.089802) (xy 146.238077 -438.074717) (xy 146.239853 -438.044598)
			(xy 146.241516 -438.029604) (xy 146.241516 -436.950104) (xy 146.239846 -436.935111) (xy 146.238068 -436.904992)
			(xy 146.23796 -436.889906) (xy 146.238068 -436.87482) (xy 146.23985 -436.844702) (xy 146.241516 -436.829708)
			(xy 146.241516 -436.219092) (xy 146.241906 -436.207006) (xy 146.249379 -436.184019) (xy 146.26359 -436.164467)
			(xy 146.283148 -436.150264) (xy 146.306138 -436.142801) (xy 146.318224 -436.142384) (xy 147.258024 -436.142384)
			(xy 147.270099 -436.142844) (xy 147.293066 -436.150312) (xy 147.312601 -436.16451) (xy 147.326795 -436.184049)
			(xy 147.334259 -436.207017) (xy 147.334732 -436.219092) (xy 147.334732 -438.760616) (xy 147.33425 -438.772689)
			(xy 147.326786 -438.795653) (xy 147.312593 -438.815187) (xy 147.29306 -438.829382) (xy 147.270097 -438.836848)
			(xy 147.258024 -438.837324) (xy 146.318224 -438.837324) (xy 146.306144 -438.836867) (xy 146.283165 -438.829408)
			(xy 146.263616 -438.815213) (xy 146.24941 -438.795671) (xy 146.241939 -438.772696) (xy 146.241516 -438.760616)
			(xy 146.241516 -438.15) (xy 146.239845 -438.135007) (xy 146.238068 -438.104888) (xy 146.23796 -438.089802)
			(xy 145.334736 -438.089802) (xy 145.334736 -439.0898) (xy 148.237956 -439.0898) (xy 148.238073 -439.074715)
			(xy 148.239849 -439.044596) (xy 148.241512 -439.029602) (xy 148.241512 -437.950102) (xy 148.239841 -437.935109)
			(xy 148.238064 -437.90499) (xy 148.237956 -437.889904) (xy 148.238073 -437.874819) (xy 148.239849 -437.8447)
			(xy 148.241512 -437.829706) (xy 148.241512 -437.21909) (xy 148.241999 -437.207003) (xy 148.249455 -437.184007)
			(xy 148.263637 -437.164429) (xy 148.283165 -437.150178) (xy 148.306134 -437.142641) (xy 148.31822 -437.142128)
			(xy 149.25802 -437.142128) (xy 149.270133 -437.1425) (xy 149.293165 -437.150008) (xy 149.312741 -437.16428)
			(xy 149.326934 -437.183913) (xy 149.334349 -437.206976) (xy 149.334728 -437.21909) (xy 149.334728 -438.089802)
			(xy 150.237952 -438.089802) (xy 150.238069 -438.074717) (xy 150.239845 -438.044598) (xy 150.241508 -438.029604)
			(xy 150.241508 -436.950104) (xy 150.239838 -436.935111) (xy 150.23806 -436.904992) (xy 150.237952 -436.889906)
			(xy 150.23806 -436.87482) (xy 150.239842 -436.844702) (xy 150.241508 -436.829708) (xy 150.241508 -436.219092)
			(xy 150.241906 -436.207007) (xy 150.249378 -436.184021) (xy 150.263587 -436.16447) (xy 150.283143 -436.150267)
			(xy 150.306131 -436.142802) (xy 150.318216 -436.142384) (xy 151.258016 -436.142384) (xy 151.270091 -436.142851)
			(xy 151.293057 -436.150317) (xy 151.312593 -436.164513) (xy 151.326787 -436.18405) (xy 151.334251 -436.207017)
			(xy 151.334724 -436.219092) (xy 151.334724 -438.760616) (xy 151.33425 -438.77269) (xy 151.326785 -438.795655)
			(xy 151.31259 -438.81519) (xy 151.293055 -438.829385) (xy 151.27009 -438.83685) (xy 151.258016 -438.837324)
			(xy 150.318216 -438.837324) (xy 150.306144 -438.836822) (xy 150.28318 -438.829366) (xy 150.263644 -438.815179)
			(xy 150.249448 -438.795649) (xy 150.241983 -438.772688) (xy 150.241508 -438.760616) (xy 150.241508 -438.15)
			(xy 150.239837 -438.135007) (xy 150.23806 -438.104888) (xy 150.237952 -438.089802) (xy 149.334728 -438.089802)
			(xy 149.334728 -439.0898) (xy 152.237948 -439.0898) (xy 152.238065 -439.074715) (xy 152.239841 -439.044596)
			(xy 152.241504 -439.029602) (xy 152.241504 -437.950102) (xy 152.239833 -437.935109) (xy 152.238056 -437.90499)
			(xy 152.237948 -437.889904) (xy 152.238065 -437.874819) (xy 152.239841 -437.8447) (xy 152.241504 -437.829706)
			(xy 152.241504 -437.21909) (xy 152.241998 -437.207004) (xy 152.249453 -437.184009) (xy 152.263634 -437.164432)
			(xy 152.28316 -437.150181) (xy 152.306127 -437.142643) (xy 152.318212 -437.142128) (xy 153.258012 -437.142128)
			(xy 153.270124 -437.142506) (xy 153.293157 -437.150012) (xy 153.312732 -437.164283) (xy 153.326925 -437.183914)
			(xy 153.334341 -437.206976) (xy 153.33472 -437.21909) (xy 153.33472 -438.089802) (xy 154.237944 -438.089802)
			(xy 154.238061 -438.074717) (xy 154.239837 -438.044598) (xy 154.2415 -438.029604) (xy 154.2415 -436.950104)
			(xy 154.23983 -436.935111) (xy 154.238052 -436.904992) (xy 154.237944 -436.889906) (xy 154.238052 -436.87482)
			(xy 154.239834 -436.844702) (xy 154.2415 -436.829708) (xy 154.2415 -436.219092) (xy 154.241958 -436.207016)
			(xy 154.249423 -436.184047) (xy 154.263621 -436.16451) (xy 154.283162 -436.150316) (xy 154.306132 -436.142855)
			(xy 154.318208 -436.142384) (xy 155.258008 -436.142384) (xy 155.270082 -436.142857) (xy 155.293048 -436.150321)
			(xy 155.312584 -436.164516) (xy 155.326779 -436.184052) (xy 155.334243 -436.207018) (xy 155.334716 -436.219092)
			(xy 155.334716 -438.760616) (xy 155.334249 -438.772691) (xy 155.326783 -438.795657) (xy 155.312587 -438.815193)
			(xy 155.29305 -438.829387) (xy 155.270083 -438.836851) (xy 155.258008 -438.837324) (xy 154.318208 -438.837324)
			(xy 154.306135 -438.836829) (xy 154.283171 -438.829371) (xy 154.263635 -438.815182) (xy 154.24944 -438.79565)
			(xy 154.241975 -438.772688) (xy 154.2415 -438.760616) (xy 154.2415 -438.15) (xy 154.239829 -438.135007)
			(xy 154.238052 -438.104888) (xy 154.237944 -438.089802) (xy 153.33472 -438.089802) (xy 153.33472 -439.0898)
			(xy 156.23794 -439.0898) (xy 156.238057 -439.074715) (xy 156.239833 -439.044596) (xy 156.241496 -439.029602)
			(xy 156.241496 -437.950102) (xy 156.239825 -437.935109) (xy 156.238048 -437.90499) (xy 156.23794 -437.889904)
			(xy 156.238057 -437.874819) (xy 156.239833 -437.8447) (xy 156.241496 -437.829706) (xy 156.241496 -437.21909)
			(xy 156.241998 -437.207004) (xy 156.249452 -437.184011) (xy 156.263631 -437.164435) (xy 156.283155 -437.150183)
			(xy 156.30612 -437.142644) (xy 156.318204 -437.142128) (xy 157.258004 -437.142128) (xy 157.270116 -437.142513)
			(xy 157.293148 -437.150017) (xy 157.312724 -437.164286) (xy 157.326917 -437.183916) (xy 157.334333 -437.206977)
			(xy 157.334712 -437.21909) (xy 157.334712 -439.760614) (xy 157.334304 -439.772709) (xy 157.326838 -439.795718)
			(xy 157.312637 -439.815302) (xy 157.293089 -439.829551) (xy 157.270098 -439.837074) (xy 157.258004 -439.837576)
			(xy 156.318204 -439.837576) (xy 156.306093 -439.83718) (xy 156.283062 -439.829679) (xy 156.263486 -439.815413)
			(xy 156.249292 -439.795785) (xy 156.241876 -439.772727) (xy 156.241496 -439.760614) (xy 156.241496 -439.149998)
			(xy 156.239825 -439.135005) (xy 156.238048 -439.104886) (xy 156.23794 -439.0898) (xy 153.33472 -439.0898)
			(xy 153.33472 -439.760614) (xy 153.334304 -439.772708) (xy 153.326839 -439.795716) (xy 153.31264 -439.815299)
			(xy 153.293094 -439.829548) (xy 153.270105 -439.837073) (xy 153.258012 -439.837576) (xy 152.318212 -439.837576)
			(xy 152.306101 -439.837173) (xy 152.28307 -439.829674) (xy 152.263495 -439.81541) (xy 152.249301 -439.795784)
			(xy 152.241884 -439.772726) (xy 152.241504 -439.760614) (xy 152.241504 -439.149998) (xy 152.239833 -439.135005)
			(xy 152.238056 -439.104886) (xy 152.237948 -439.0898) (xy 149.334728 -439.0898) (xy 149.334728 -439.760614)
			(xy 149.334304 -439.772708) (xy 149.32684 -439.795714) (xy 149.312643 -439.815297) (xy 149.293099 -439.829546)
			(xy 149.270112 -439.837072) (xy 149.25802 -439.837576) (xy 148.31822 -439.837576) (xy 148.30611 -439.837166)
			(xy 148.283079 -439.829669) (xy 148.263504 -439.815407) (xy 148.249309 -439.795782) (xy 148.241892 -439.772726)
			(xy 148.241512 -439.760614) (xy 148.241512 -439.149998) (xy 148.239841 -439.135005) (xy 148.238064 -439.104886)
			(xy 148.237956 -439.0898) (xy 145.334736 -439.0898) (xy 145.334736 -439.760614) (xy 145.334304 -439.772707)
			(xy 145.326841 -439.795712) (xy 145.312646 -439.815294) (xy 145.293104 -439.829543) (xy 145.270119 -439.83707)
			(xy 145.258028 -439.837576) (xy 144.318228 -439.837576) (xy 144.306118 -439.837159) (xy 144.283088 -439.829665)
			(xy 144.263512 -439.815404) (xy 144.249317 -439.795781) (xy 144.2419 -439.772725) (xy 144.24152 -439.760614)
			(xy 144.24152 -439.149998) (xy 144.239849 -439.135005) (xy 144.238072 -439.104886) (xy 144.237964 -439.0898)
			(xy 140.335 -439.0898) (xy 140.335 -439.760614) (xy 140.334501 -439.772726) (xy 140.327015 -439.795763)
			(xy 140.312778 -439.815361) (xy 140.293184 -439.829604) (xy 140.270149 -439.837097) (xy 140.258038 -439.837576)
			(xy 139.318238 -439.837576) (xy 139.306119 -439.837108) (xy 139.283063 -439.829628) (xy 139.263449 -439.815388)
			(xy 139.249196 -439.795783) (xy 139.2417 -439.772733) (xy 139.241276 -439.760614) (xy 139.241276 -439.147966)
			(xy 139.239731 -439.133474) (xy 139.238079 -439.104374) (xy 139.237974 -439.0898) (xy 136.335008 -439.0898)
			(xy 136.335008 -439.760614) (xy 136.334501 -439.772725) (xy 136.327016 -439.795761) (xy 136.312781 -439.815358)
			(xy 136.293189 -439.829601) (xy 136.270157 -439.837096) (xy 136.258046 -439.837576) (xy 135.318246 -439.837576)
			(xy 135.306127 -439.837101) (xy 135.283072 -439.829623) (xy 135.263457 -439.815385) (xy 135.249204 -439.795782)
			(xy 135.241708 -439.772733) (xy 135.241284 -439.760614) (xy 135.241284 -439.147966) (xy 135.239739 -439.133474)
			(xy 135.238087 -439.104374) (xy 135.237982 -439.0898) (xy 132.335016 -439.0898) (xy 132.335016 -439.760614)
			(xy 132.334651 -439.772742) (xy 132.327149 -439.795809) (xy 132.312885 -439.815428) (xy 132.293255 -439.829677)
			(xy 132.270182 -439.83716) (xy 132.258054 -439.837576) (xy 131.318254 -439.837576) (xy 131.306138 -439.837128)
			(xy 131.283096 -439.82963) (xy 131.263496 -439.815381) (xy 131.249256 -439.795775) (xy 131.241767 -439.77273)
			(xy 131.241292 -439.760614) (xy 131.241292 -439.147966) (xy 131.239747 -439.133474) (xy 131.238095 -439.104374)
			(xy 131.23799 -439.0898) (xy 128.335024 -439.0898) (xy 128.335024 -439.760614) (xy 128.334651 -439.772741)
			(xy 128.32715 -439.795807) (xy 128.312888 -439.815425) (xy 128.29326 -439.829674) (xy 128.27019 -439.837159)
			(xy 128.258062 -439.837576) (xy 127.318262 -439.837576) (xy 127.306147 -439.837121) (xy 127.283105 -439.829625)
			(xy 127.263505 -439.815378) (xy 127.249264 -439.795774) (xy 127.241775 -439.772729) (xy 127.2413 -439.760614)
			(xy 127.2413 -439.147966) (xy 127.239755 -439.133474) (xy 127.238103 -439.104374) (xy 127.237998 -439.0898)
			(xy 115.623848 -439.0898) (xy 115.623848 -440.465972) (xy 125.238256 -440.465972) (xy 125.244098 -440.42203)
			(xy 125.248827 -440.390461) (xy 125.26513 -440.328742) (xy 125.289 -440.269538) (xy 125.320066 -440.213771)
			(xy 125.357843 -440.162313) (xy 125.40174 -440.115967) (xy 125.451073 -440.075455) (xy 125.505072 -440.04141)
			(xy 125.562895 -440.014364) (xy 125.623639 -439.994738) (xy 125.686355 -439.982838) (xy 125.750066 -439.978851)
			(xy 125.813777 -439.982838) (xy 125.876493 -439.994738) (xy 125.937237 -440.014364) (xy 125.99506 -440.04141)
			(xy 126.049059 -440.075455) (xy 126.098392 -440.115967) (xy 126.142289 -440.162313) (xy 126.180066 -440.213771)
			(xy 126.211132 -440.269538) (xy 126.235002 -440.328742) (xy 126.251305 -440.390461) (xy 126.256034 -440.42203)
			(xy 126.261876 -440.465972) (xy 129.238248 -440.465972) (xy 129.24409 -440.42203) (xy 129.248819 -440.390461)
			(xy 129.265122 -440.328742) (xy 129.288992 -440.269538) (xy 129.320058 -440.213771) (xy 129.357835 -440.162313)
			(xy 129.401732 -440.115967) (xy 129.451065 -440.075455) (xy 129.505064 -440.04141) (xy 129.562887 -440.014364)
			(xy 129.623631 -439.994738) (xy 129.686347 -439.982838) (xy 129.750058 -439.978851) (xy 129.813769 -439.982838)
			(xy 129.876485 -439.994738) (xy 129.937229 -440.014364) (xy 129.995052 -440.04141) (xy 130.049051 -440.075455)
			(xy 130.098384 -440.115967) (xy 130.142281 -440.162313) (xy 130.180058 -440.213771) (xy 130.211124 -440.269538)
			(xy 130.234994 -440.328742) (xy 130.251297 -440.390461) (xy 130.256026 -440.42203) (xy 130.261868 -440.465972)
			(xy 133.23824 -440.465972) (xy 133.244082 -440.42203) (xy 133.248811 -440.390461) (xy 133.265114 -440.328742)
			(xy 133.288984 -440.269538) (xy 133.32005 -440.213771) (xy 133.357827 -440.162313) (xy 133.401724 -440.115967)
			(xy 133.451057 -440.075455) (xy 133.505056 -440.04141) (xy 133.562879 -440.014364) (xy 133.623623 -439.994738)
			(xy 133.686339 -439.982838) (xy 133.75005 -439.978851) (xy 133.813761 -439.982838) (xy 133.876477 -439.994738)
			(xy 133.937221 -440.014364) (xy 133.995044 -440.04141) (xy 134.049043 -440.075455) (xy 134.098376 -440.115967)
			(xy 134.142273 -440.162313) (xy 134.18005 -440.213771) (xy 134.211116 -440.269538) (xy 134.234986 -440.328742)
			(xy 134.251289 -440.390461) (xy 134.256018 -440.42203) (xy 134.26186 -440.465972) (xy 137.238232 -440.465972)
			(xy 137.244074 -440.42203) (xy 137.248803 -440.390461) (xy 137.265106 -440.328742) (xy 137.288976 -440.269538)
			(xy 137.320042 -440.213771) (xy 137.357819 -440.162313) (xy 137.401716 -440.115967) (xy 137.451049 -440.075455)
			(xy 137.505048 -440.04141) (xy 137.562871 -440.014364) (xy 137.623615 -439.994738) (xy 137.686331 -439.982838)
			(xy 137.750042 -439.978851) (xy 137.813753 -439.982838) (xy 137.876469 -439.994738) (xy 137.937213 -440.014364)
			(xy 137.995036 -440.04141) (xy 138.049035 -440.075455) (xy 138.098368 -440.115967) (xy 138.142265 -440.162313)
			(xy 138.180042 -440.213771) (xy 138.211108 -440.269538) (xy 138.234978 -440.328742) (xy 138.251281 -440.390461)
			(xy 138.25601 -440.42203) (xy 138.261852 -440.465972) (xy 142.238222 -440.465972) (xy 142.244064 -440.42203)
			(xy 142.248793 -440.390461) (xy 142.265096 -440.328742) (xy 142.288966 -440.269538) (xy 142.320032 -440.213771)
			(xy 142.357809 -440.162313) (xy 142.401706 -440.115967) (xy 142.451039 -440.075455) (xy 142.505038 -440.04141)
			(xy 142.562861 -440.014364) (xy 142.623605 -439.994738) (xy 142.686321 -439.982838) (xy 142.750032 -439.978851)
			(xy 142.813743 -439.982838) (xy 142.876459 -439.994738) (xy 142.937203 -440.014364) (xy 142.995026 -440.04141)
			(xy 143.049025 -440.075455) (xy 143.098358 -440.115967) (xy 143.142255 -440.162313) (xy 143.180032 -440.213771)
			(xy 143.211098 -440.269538) (xy 143.234968 -440.328742) (xy 143.251271 -440.390461) (xy 143.256 -440.42203)
			(xy 143.261842 -440.465972) (xy 146.238214 -440.465972) (xy 146.244056 -440.42203) (xy 146.248785 -440.390461)
			(xy 146.265088 -440.328742) (xy 146.288958 -440.269538) (xy 146.320024 -440.213771) (xy 146.357801 -440.162313)
			(xy 146.401698 -440.115967) (xy 146.451031 -440.075455) (xy 146.50503 -440.04141) (xy 146.562853 -440.014364)
			(xy 146.623597 -439.994738) (xy 146.686313 -439.982838) (xy 146.750024 -439.978851) (xy 146.813735 -439.982838)
			(xy 146.876451 -439.994738) (xy 146.937195 -440.014364) (xy 146.995018 -440.04141) (xy 147.049017 -440.075455)
			(xy 147.09835 -440.115967) (xy 147.142247 -440.162313) (xy 147.180024 -440.213771) (xy 147.21109 -440.269538)
			(xy 147.23496 -440.328742) (xy 147.251263 -440.390461) (xy 147.255992 -440.42203) (xy 147.261834 -440.465972)
			(xy 150.238206 -440.465972) (xy 150.244048 -440.42203) (xy 150.248777 -440.390461) (xy 150.26508 -440.328742)
			(xy 150.28895 -440.269538) (xy 150.320016 -440.213771) (xy 150.357793 -440.162313) (xy 150.40169 -440.115967)
			(xy 150.451023 -440.075455) (xy 150.505022 -440.04141) (xy 150.562845 -440.014364) (xy 150.623589 -439.994738)
			(xy 150.686305 -439.982838) (xy 150.750016 -439.978851) (xy 150.813727 -439.982838) (xy 150.876443 -439.994738)
			(xy 150.937187 -440.014364) (xy 150.99501 -440.04141) (xy 151.049009 -440.075455) (xy 151.098342 -440.115967)
			(xy 151.142239 -440.162313) (xy 151.180016 -440.213771) (xy 151.211082 -440.269538) (xy 151.234952 -440.328742)
			(xy 151.251255 -440.390461) (xy 151.255984 -440.42203) (xy 151.261826 -440.465972) (xy 154.238198 -440.465972)
			(xy 154.24404 -440.42203) (xy 154.248769 -440.390461) (xy 154.265072 -440.328742) (xy 154.288942 -440.269538)
			(xy 154.320008 -440.213771) (xy 154.357785 -440.162313) (xy 154.401682 -440.115967) (xy 154.451015 -440.075455)
			(xy 154.505014 -440.04141) (xy 154.562837 -440.014364) (xy 154.623581 -439.994738) (xy 154.686297 -439.982838)
			(xy 154.750008 -439.978851) (xy 154.813719 -439.982838) (xy 154.876435 -439.994738) (xy 154.937179 -440.014364)
			(xy 154.995002 -440.04141) (xy 155.049001 -440.075455) (xy 155.098334 -440.115967) (xy 155.142231 -440.162313)
			(xy 155.180008 -440.213771) (xy 155.211074 -440.269538) (xy 155.234944 -440.328742) (xy 155.251247 -440.390461)
			(xy 155.255976 -440.42203) (xy 155.261818 -440.465972) (xy 166.734236 -440.465972) (xy 167.27424 -439.925968)
			(xy 167.27424 -416.88258) (xy 167.274723 -416.857628) (xy 167.282517 -416.808336) (xy 167.297925 -416.76087)
			(xy 167.320568 -416.716398) (xy 167.349889 -416.676016) (xy 167.367204 -416.658044) (xy 170.240452 -413.784796)
			(xy 170.258451 -413.767514) (xy 170.298835 -413.738208) (xy 170.343302 -413.71557) (xy 170.390758 -413.700156)
			(xy 170.44004 -413.692344) (xy 170.464988 -413.691832) (xy 180.29809 -413.691832) (xy 180.322247 -413.677438)
			(xy 180.37409 -413.655663) (xy 180.428728 -413.642375) (xy 180.48478 -413.637907) (xy 180.540832 -413.642375)
			(xy 180.59547 -413.655663) (xy 180.647313 -413.677438) (xy 180.67147 -413.691832) (xy 181.045358 -413.691832)
			(xy 181.066573 -413.673113) (xy 181.113492 -413.641501) (xy 181.164565 -413.617164) (xy 181.218672 -413.600637)
			(xy 181.274626 -413.592282) (xy 181.331202 -413.592282) (xy 181.387156 -413.600637) (xy 181.441263 -413.617164)
			(xy 181.492336 -413.641501) (xy 181.539255 -413.673113) (xy 181.56047 -413.691832) (xy 184.688988 -413.691832)
			(xy 184.688988 -408.491182) (xy 184.689446 -408.466228) (xy 184.697241 -408.416933) (xy 184.712652 -408.369464)
			(xy 184.735299 -408.324991) (xy 184.764625 -408.284609) (xy 184.781952 -408.266646) (xy 184.892188 -408.15641)
			(xy 184.892188 -407.290778) (xy 184.874469 -407.269822) (xy 184.844603 -407.223784) (xy 184.821645 -407.17394)
			(xy 184.806067 -407.12132) (xy 184.798191 -407.067011) (xy 184.7977 -407.039572) (xy 184.798716 -407.013918)
			(xy 184.80024 -406.99055) (xy 184.654952 -406.845262) (xy 184.637666 -406.827264) (xy 184.608353 -406.786882)
			(xy 184.585709 -406.742416) (xy 184.57029 -406.694959) (xy 184.562475 -406.645675) (xy 184.561988 -406.620726)
			(xy 184.561988 -400.685254) (xy 184.562481 -400.660307) (xy 184.570292 -400.611027) (xy 184.585716 -400.563576)
			(xy 184.608371 -400.519122) (xy 184.637702 -400.478758) (xy 184.672984 -400.443479) (xy 184.713351 -400.414154)
			(xy 184.757808 -400.391503) (xy 184.80526 -400.376084) (xy 184.854541 -400.368278) (xy 184.879488 -400.367754)
			(xy 188.73343 -400.367754) (xy 188.758607 -400.36826) (xy 188.808324 -400.376252) (xy 188.856159 -400.391982)
			(xy 188.900915 -400.415058) (xy 188.941474 -400.444902) (xy 188.95949 -400.462496) (xy 189.16142 -400.667474)
			(xy 189.178441 -400.685395) (xy 189.207278 -400.725532) (xy 189.229543 -400.769656) (xy 189.244696 -400.816698)
			(xy 189.252371 -400.865521) (xy 189.25286 -400.890232) (xy 189.25286 -403.517354) (xy 189.46876 -403.517354)
			(xy 189.493711 -403.51784) (xy 189.542999 -403.52564) (xy 189.590461 -403.541053) (xy 189.634927 -403.5637)
			(xy 189.675304 -403.593025) (xy 189.693296 -403.610318) (xy 189.904624 -403.821646) (xy 189.921911 -403.839643)
			(xy 189.951225 -403.880025) (xy 189.973869 -403.924491) (xy 189.989288 -403.971948) (xy 189.997103 -404.021232)
			(xy 189.997588 -404.046182) (xy 189.997588 -404.34641) (xy 190.325756 -404.674578) (xy 190.350394 -404.671276)
			(xy 190.363099 -404.669705) (xy 190.388647 -404.668052) (xy 190.401448 -404.667974) (xy 190.428697 -404.668463)
			(xy 190.482641 -404.676225) (xy 190.534931 -404.691584) (xy 190.584503 -404.714228) (xy 190.630349 -404.743695)
			(xy 190.671535 -404.779386) (xy 190.707223 -404.820575) (xy 190.736687 -404.866423) (xy 190.759326 -404.915997)
			(xy 190.774681 -404.968288) (xy 190.782439 -405.022232) (xy 190.782956 -405.049482) (xy 190.782886 -405.062283)
			(xy 190.781237 -405.087833) (xy 190.779654 -405.100536) (xy 190.776352 -405.125428) (xy 191.001904 -405.35098)
			(xy 196.838316 -405.35098) (xy 197.83298 -404.356316) (xy 197.83298 -400.893788) (xy 197.833437 -400.868834)
			(xy 197.841231 -400.819538) (xy 197.856641 -400.772069) (xy 197.879288 -400.727595) (xy 197.908613 -400.687211)
			(xy 197.925944 -400.669252) (xy 198.116952 -400.478244) (xy 198.13495 -400.460959) (xy 198.175333 -400.431649)
			(xy 198.219799 -400.409008) (xy 198.267256 -400.393591) (xy 198.316539 -400.385778) (xy 198.341488 -400.38528)
			(xy 201.995532 -400.38528) (xy 202.020486 -400.385739) (xy 202.06978 -400.393535) (xy 202.117247 -400.408948)
			(xy 202.161719 -400.431596) (xy 202.2021 -400.460922) (xy 202.220068 -400.478244) (xy 202.418696 -400.676872)
			(xy 202.435978 -400.694872) (xy 202.465282 -400.735256) (xy 202.487917 -400.779722) (xy 202.503329 -400.827179)
			(xy 202.511138 -400.87646) (xy 202.51166 -400.901408) (xy 202.51166 -404.330916) (xy 202.604624 -404.42388)
			(xy 202.621909 -404.441878) (xy 202.651218 -404.482261) (xy 202.673858 -404.526727) (xy 202.689272 -404.574184)
			(xy 202.697082 -404.623467) (xy 202.697588 -404.648416) (xy 202.697588 -407.475436) (xy 204.291692 -409.06954)
			(xy 206.414116 -409.06954) (xy 208.310988 -407.172668) (xy 208.310988 -404.642828) (xy 208.311475 -404.617878)
			(xy 208.319277 -404.568591) (xy 208.334693 -404.521132) (xy 208.357343 -404.476668) (xy 208.38667 -404.436295)
			(xy 208.403952 -404.418292) (xy 208.50098 -404.321264) (xy 208.50098 -400.893788) (xy 208.501437 -400.868834)
			(xy 208.509231 -400.819538) (xy 208.524641 -400.772069) (xy 208.547288 -400.727595) (xy 208.576613 -400.687211)
			(xy 208.593944 -400.669252) (xy 208.784952 -400.478244) (xy 208.80295 -400.460959) (xy 208.843333 -400.431649)
			(xy 208.887799 -400.409008) (xy 208.935256 -400.393591) (xy 208.984539 -400.385778) (xy 209.009488 -400.38528)
			(xy 212.668612 -400.38528) (xy 212.693566 -400.385737) (xy 212.742862 -400.393531) (xy 212.790331 -400.408941)
			(xy 212.834805 -400.431588) (xy 212.875189 -400.460913) (xy 212.893148 -400.478244) (xy 213.084156 -400.669252)
			(xy 213.101441 -400.68725) (xy 213.130751 -400.727633) (xy 213.153392 -400.772099) (xy 213.168809 -400.819556)
			(xy 213.176622 -400.868839) (xy 213.17712 -400.893788) (xy 213.17712 -404.353776) (xy 213.261956 -404.438612)
			(xy 213.279243 -404.456609) (xy 213.308558 -404.496991) (xy 213.331205 -404.541456) (xy 213.346628 -404.588914)
			(xy 213.354447 -404.638198) (xy 213.35492 -404.663148) (xy 213.35492 -407.394156) (xy 214.926164 -408.9654)
			(xy 217.141044 -408.9654) (xy 218.978988 -407.127456) (xy 218.978988 -404.673308) (xy 218.979477 -404.648358)
			(xy 218.987281 -404.599073) (xy 219.002699 -404.551616) (xy 219.025351 -404.507154) (xy 219.05468 -404.466784)
			(xy 219.071952 -404.448772) (xy 219.16136 -404.359364) (xy 219.16136 -400.906488) (xy 219.161842 -400.881536)
			(xy 219.169635 -400.832244) (xy 219.185043 -400.784777) (xy 219.207687 -400.740306) (xy 219.237009 -400.699924)
			(xy 219.254324 -400.681952) (xy 219.458032 -400.478244) (xy 219.47603 -400.460958) (xy 219.516412 -400.431645)
			(xy 219.560878 -400.409001) (xy 219.608335 -400.393582) (xy 219.657618 -400.385766) (xy 219.682568 -400.38528)
			(xy 223.323912 -400.38528) (xy 223.348866 -400.385737) (xy 223.398162 -400.393531) (xy 223.445631 -400.408941)
			(xy 223.490105 -400.431588) (xy 223.530489 -400.460913) (xy 223.548448 -400.478244) (xy 223.759776 -400.689572)
			(xy 223.777059 -400.707571) (xy 223.806365 -400.747955) (xy 223.829002 -400.792421) (xy 223.844414 -400.839878)
			(xy 223.852224 -400.88916) (xy 223.85274 -400.914108) (xy 223.85274 -404.348188) (xy 223.940624 -404.436072)
			(xy 223.957909 -404.45407) (xy 223.98722 -404.494452) (xy 224.009861 -404.538918) (xy 224.025276 -404.586376)
			(xy 224.033087 -404.635659) (xy 224.033588 -404.660608) (xy 224.033588 -407.272236) (xy 225.838512 -409.07716)
			(xy 227.803456 -409.07716) (xy 229.621588 -407.259028) (xy 229.621588 -404.678388) (xy 229.622045 -404.653434)
			(xy 229.629839 -404.604138) (xy 229.64525 -404.556669) (xy 229.667896 -404.512195) (xy 229.697222 -404.471812)
			(xy 229.714552 -404.453852) (xy 229.82682 -404.341584) (xy 229.82682 -400.901408) (xy 229.827308 -400.876458)
			(xy 229.835112 -400.827171) (xy 229.850527 -400.779712) (xy 229.873176 -400.735248) (xy 229.9025 -400.694873)
			(xy 229.919784 -400.676872) (xy 230.120952 -400.475704) (xy 230.138951 -400.458421) (xy 230.179335 -400.429115)
			(xy 230.223801 -400.406476) (xy 230.271258 -400.391062) (xy 230.32054 -400.38325) (xy 230.345488 -400.38274)
			(xy 233.996992 -400.38274) (xy 234.021942 -400.383229) (xy 234.071228 -400.391032) (xy 234.118687 -400.406448)
			(xy 234.16315 -400.429098) (xy 234.203524 -400.458423) (xy 234.221528 -400.475704) (xy 234.422696 -400.676872)
			(xy 234.439978 -400.694872) (xy 234.469282 -400.735256) (xy 234.491917 -400.779722) (xy 234.507329 -400.827179)
			(xy 234.515138 -400.87646) (xy 234.51566 -400.901408) (xy 234.51566 -404.346156) (xy 235.652564 -405.48306)
			(xy 237.746032 -405.48306) (xy 237.770984 -405.483544) (xy 237.820274 -405.49134) (xy 237.867738 -405.50675)
			(xy 237.912208 -405.529395) (xy 237.952587 -405.558718) (xy 237.970568 -405.576024) (xy 238.814356 -406.419812)
			(xy 238.968788 -406.419812) (xy 239.014 -406.3746) (xy 239.014 -397.839946) (xy 239.014737 -397.809321)
			(xy 239.026508 -397.749211) (xy 239.037368 -397.720566) (xy 239.093502 -397.582136) (xy 239.102129 -397.561823)
			(xy 239.124186 -397.523598) (xy 239.151321 -397.488794) (xy 239.166908 -397.47317) (xy 239.218978 -397.423132)
			(xy 239.692688 -396.949422) (xy 239.720266 -396.92256) (xy 239.780416 -396.874505) (xy 239.845566 -396.833485)
			(xy 239.914899 -396.800015) (xy 239.987543 -396.774516) (xy 240.062584 -396.75731) (xy 240.13908 -396.748611)
			(xy 240.177574 -396.748) (xy 274.117054 -396.748) (xy 274.147679 -396.748737) (xy 274.207789 -396.760508)
			(xy 274.236434 -396.771368) (xy 274.374864 -396.827502) (xy 274.395177 -396.836129) (xy 274.433402 -396.858186)
			(xy 274.468206 -396.885321) (xy 274.48383 -396.900908) (xy 274.533868 -396.952978) (xy 274.753578 -397.172688)
			(xy 274.777454 -397.19758) (xy 274.78702 -397.207439) (xy 274.810234 -397.222108) (xy 274.836516 -397.230063)
			(xy 274.863968 -397.23073) (xy 274.890605 -397.22406) (xy 274.914503 -397.210536) (xy 274.92452 -397.201136)
			(xy 275.284692 -396.840964) (xy 275.302691 -396.823681) (xy 275.343074 -396.794374) (xy 275.38754 -396.771736)
			(xy 275.434997 -396.756325) (xy 275.48428 -396.748517) (xy 275.509228 -396.748) (xy 280.83764 -396.748)
			(xy 280.862593 -396.748459) (xy 280.911886 -396.756258) (xy 280.959352 -396.771671) (xy 281.003822 -396.794321)
			(xy 281.044202 -396.82365) (xy 281.062176 -396.840964) (xy 281.593544 -397.372332) (xy 281.61083 -397.39033)
			(xy 281.640144 -397.430711) (xy 281.662789 -397.475177) (xy 281.678209 -397.522634) (xy 281.686026 -397.571918)
			(xy 281.686508 -397.596868) (xy 281.686508 -398.65534) (xy 457.185003 -398.65534) (xy 457.185003 -398.5262)
			(xy 457.192953 -398.397305) (xy 457.208823 -398.269145) (xy 457.232552 -398.142204) (xy 457.264051 -398.016965)
			(xy 457.3032 -397.893902) (xy 457.349851 -397.773483) (xy 457.403826 -397.656164) (xy 457.464921 -397.54239)
			(xy 457.532904 -397.432593) (xy 457.607518 -397.32719) (xy 457.688479 -397.22658) (xy 457.775479 -397.131145)
			(xy 457.86819 -397.041246) (xy 457.96626 -396.957225) (xy 458.069315 -396.879401) (xy 458.176966 -396.808069)
			(xy 458.288805 -396.743499) (xy 458.404406 -396.685937) (xy 458.523331 -396.6356) (xy 458.64513 -396.59268)
			(xy 458.76934 -396.557339) (xy 458.895489 -396.529712) (xy 459.023101 -396.509903) (xy 459.15169 -396.497987)
			(xy 459.280768 -396.494011) (xy 459.409846 -396.497987) (xy 459.538435 -396.509903) (xy 459.666047 -396.529712)
			(xy 459.792196 -396.557339) (xy 459.916406 -396.59268) (xy 460.038205 -396.6356) (xy 460.15713 -396.685937)
			(xy 460.272731 -396.743499) (xy 460.38457 -396.808069) (xy 460.492221 -396.879401) (xy 460.595276 -396.957225)
			(xy 460.693346 -397.041246) (xy 460.786057 -397.131145) (xy 460.873057 -397.22658) (xy 460.954018 -397.32719)
			(xy 461.028632 -397.432593) (xy 461.096615 -397.54239) (xy 461.15771 -397.656164) (xy 461.211685 -397.773483)
			(xy 461.258336 -397.893902) (xy 461.297485 -398.016965) (xy 461.328984 -398.142204) (xy 461.352713 -398.269145)
			(xy 461.368583 -398.397305) (xy 461.376533 -398.5262) (xy 461.37703 -398.59077) (xy 461.376533 -398.65534)
			(xy 461.368583 -398.784235) (xy 461.352713 -398.912395) (xy 461.328984 -399.039336) (xy 461.297485 -399.164575)
			(xy 461.258336 -399.287638) (xy 461.211685 -399.408057) (xy 461.15771 -399.525376) (xy 461.096615 -399.63915)
			(xy 461.028632 -399.748947) (xy 460.954018 -399.85435) (xy 460.873057 -399.95496) (xy 460.786057 -400.050395)
			(xy 460.693346 -400.140294) (xy 460.595276 -400.224315) (xy 460.492221 -400.302139) (xy 460.38457 -400.373471)
			(xy 460.272731 -400.438041) (xy 460.15713 -400.495603) (xy 460.038205 -400.54594) (xy 459.916406 -400.58886)
			(xy 459.792196 -400.624201) (xy 459.666047 -400.651828) (xy 459.538435 -400.671637) (xy 459.409846 -400.683553)
			(xy 459.280768 -400.68753) (xy 459.15169 -400.683553) (xy 459.023101 -400.671637) (xy 458.895489 -400.651828)
			(xy 458.76934 -400.624201) (xy 458.64513 -400.58886) (xy 458.523331 -400.54594) (xy 458.404406 -400.495603)
			(xy 458.288805 -400.438041) (xy 458.176966 -400.373471) (xy 458.069315 -400.302139) (xy 457.96626 -400.224315)
			(xy 457.86819 -400.140294) (xy 457.775479 -400.050395) (xy 457.688479 -399.95496) (xy 457.607518 -399.85435)
			(xy 457.532904 -399.748947) (xy 457.464921 -399.63915) (xy 457.403826 -399.525376) (xy 457.349851 -399.408057)
			(xy 457.3032 -399.287638) (xy 457.264051 -399.164575) (xy 457.232552 -399.039336) (xy 457.208823 -398.912395)
			(xy 457.192953 -398.784235) (xy 457.185003 -398.65534) (xy 281.686508 -398.65534) (xy 281.686508 -399.9835)
			(xy 289.606441 -399.9835) (xy 289.610455 -399.919698) (xy 289.622434 -399.856902) (xy 289.642189 -399.796103)
			(xy 289.669408 -399.73826) (xy 289.703662 -399.684283) (xy 289.744411 -399.635026) (xy 289.791013 -399.591264)
			(xy 289.842731 -399.553688) (xy 289.898752 -399.52289) (xy 289.958191 -399.499357) (xy 290.02011 -399.483458)
			(xy 290.083534 -399.475446) (xy 290.115498 -399.474944) (xy 290.115752 -399.474944) (xy 290.147498 -399.475464)
			(xy 290.210494 -399.483393) (xy 290.272014 -399.499096) (xy 290.331102 -399.52233) (xy 290.386842 -399.552733)
			(xy 290.438367 -399.589834) (xy 290.461954 -399.611088) (xy 290.469217 -399.617272) (xy 290.486967 -399.624223)
			(xy 290.506029 -399.624223) (xy 290.523779 -399.617272) (xy 290.531042 -399.611088) (xy 290.554631 -399.589832)
			(xy 290.60614 -399.5527) (xy 290.661874 -399.522276) (xy 290.720965 -399.499035) (xy 290.782492 -399.483338)
			(xy 290.845495 -399.475431) (xy 290.877244 -399.474944) (xy 290.877498 -399.474944) (xy 290.909457 -399.475521)
			(xy 290.972872 -399.483532) (xy 291.034783 -399.499427) (xy 291.094213 -399.522957) (xy 291.150226 -399.55375)
			(xy 291.201937 -399.591321) (xy 291.248532 -399.635076) (xy 291.289276 -399.684326) (xy 291.323525 -399.738295)
			(xy 291.350741 -399.79613) (xy 291.370493 -399.856921) (xy 291.38247 -399.919707) (xy 291.386484 -399.9835)
			(xy 292.146441 -399.9835) (xy 292.150455 -399.919698) (xy 292.162434 -399.856902) (xy 292.182189 -399.796103)
			(xy 292.209408 -399.73826) (xy 292.243662 -399.684283) (xy 292.284411 -399.635026) (xy 292.331013 -399.591264)
			(xy 292.382731 -399.553688) (xy 292.438752 -399.52289) (xy 292.498191 -399.499357) (xy 292.56011 -399.483458)
			(xy 292.623534 -399.475446) (xy 292.655498 -399.474944) (xy 292.655752 -399.474944) (xy 292.687498 -399.475464)
			(xy 292.750494 -399.483393) (xy 292.812014 -399.499096) (xy 292.871102 -399.52233) (xy 292.926842 -399.552733)
			(xy 292.978367 -399.589834) (xy 293.001954 -399.611088) (xy 293.009217 -399.617272) (xy 293.026967 -399.624223)
			(xy 293.046029 -399.624223) (xy 293.063779 -399.617272) (xy 293.071042 -399.611088) (xy 293.094631 -399.589832)
			(xy 293.14614 -399.5527) (xy 293.201874 -399.522276) (xy 293.260965 -399.499035) (xy 293.322492 -399.483338)
			(xy 293.385495 -399.475431) (xy 293.417244 -399.474944) (xy 293.417498 -399.474944) (xy 293.449457 -399.475521)
			(xy 293.512872 -399.483532) (xy 293.574783 -399.499427) (xy 293.634213 -399.522957) (xy 293.690226 -399.55375)
			(xy 293.741937 -399.591321) (xy 293.788532 -399.635076) (xy 293.829276 -399.684326) (xy 293.863525 -399.738295)
			(xy 293.890741 -399.79613) (xy 293.910493 -399.856921) (xy 293.92247 -399.919707) (xy 293.926484 -399.9835)
			(xy 294.53602 -399.9835) (xy 294.540035 -399.919693) (xy 294.552015 -399.856892) (xy 294.571773 -399.796089)
			(xy 294.598995 -399.738241) (xy 294.633253 -399.684261) (xy 294.674007 -399.635001) (xy 294.720613 -399.591237)
			(xy 294.772338 -399.55366) (xy 294.828364 -399.522862) (xy 294.887809 -399.499329) (xy 294.949734 -399.483433)
			(xy 295.013163 -399.475423) (xy 295.04513 -399.474944) (xy 295.045384 -399.474944) (xy 295.077131 -399.475444)
			(xy 295.140127 -399.483377) (xy 295.201647 -399.499084) (xy 295.260736 -399.522322) (xy 295.316476 -399.552728)
			(xy 295.368 -399.589832) (xy 295.391586 -399.611088) (xy 295.398849 -399.617272) (xy 295.416599 -399.624223)
			(xy 295.435661 -399.624223) (xy 295.453411 -399.617272) (xy 295.460674 -399.611088) (xy 295.48425 -399.589817)
			(xy 295.535761 -399.552686) (xy 295.591498 -399.522265) (xy 295.650592 -399.499026) (xy 295.712121 -399.483332)
			(xy 295.775126 -399.475429) (xy 295.806876 -399.474944) (xy 295.80713 -399.474944) (xy 295.839087 -399.475544)
			(xy 295.902496 -399.483558) (xy 295.964401 -399.499455) (xy 296.023825 -399.522986) (xy 296.079832 -399.553779)
			(xy 296.131538 -399.591348) (xy 296.178128 -399.635102) (xy 296.218866 -399.684349) (xy 296.253112 -399.738314)
			(xy 296.280324 -399.796145) (xy 296.300074 -399.856931) (xy 296.312049 -399.919712) (xy 296.316063 -399.9835)
			(xy 297.07602 -399.9835) (xy 297.080035 -399.919693) (xy 297.092015 -399.856892) (xy 297.111773 -399.796089)
			(xy 297.138995 -399.738241) (xy 297.173253 -399.684261) (xy 297.214007 -399.635001) (xy 297.260613 -399.591237)
			(xy 297.312338 -399.55366) (xy 297.368364 -399.522862) (xy 297.427809 -399.499329) (xy 297.489734 -399.483433)
			(xy 297.553163 -399.475423) (xy 297.58513 -399.474944) (xy 297.585384 -399.474944) (xy 297.617131 -399.475444)
			(xy 297.680127 -399.483377) (xy 297.741647 -399.499084) (xy 297.800736 -399.522322) (xy 297.856476 -399.552728)
			(xy 297.908 -399.589832) (xy 297.931586 -399.611088) (xy 297.938849 -399.617272) (xy 297.956599 -399.624223)
			(xy 297.975661 -399.624223) (xy 297.993411 -399.617272) (xy 298.000674 -399.611088) (xy 298.02425 -399.589817)
			(xy 298.075761 -399.552686) (xy 298.131498 -399.522265) (xy 298.190592 -399.499026) (xy 298.252121 -399.483332)
			(xy 298.315126 -399.475429) (xy 298.346876 -399.474944) (xy 298.34713 -399.474944) (xy 298.379087 -399.475544)
			(xy 298.442496 -399.483558) (xy 298.504401 -399.499455) (xy 298.563825 -399.522986) (xy 298.619832 -399.553779)
			(xy 298.671538 -399.591348) (xy 298.718128 -399.635102) (xy 298.758866 -399.684349) (xy 298.793112 -399.738314)
			(xy 298.820324 -399.796145) (xy 298.840074 -399.856931) (xy 298.852049 -399.919712) (xy 298.856063 -399.9835)
			(xy 298.852049 -400.047288) (xy 298.840074 -400.110069) (xy 298.820324 -400.170855) (xy 298.793112 -400.228686)
			(xy 298.758866 -400.282651) (xy 298.718128 -400.331898) (xy 298.671538 -400.375652) (xy 298.619832 -400.413221)
			(xy 298.563825 -400.444014) (xy 298.504401 -400.467545) (xy 298.442496 -400.483442) (xy 298.379087 -400.491456)
			(xy 298.34713 -400.49196) (xy 298.346876 -400.49196) (xy 298.315131 -400.491422) (xy 298.252136 -400.483497)
			(xy 298.190616 -400.467797) (xy 298.131527 -400.444566) (xy 298.075787 -400.414166) (xy 298.024261 -400.377069)
			(xy 298.000674 -400.355816) (xy 297.993411 -400.349632) (xy 297.975661 -400.342681) (xy 297.956599 -400.342681)
			(xy 297.938849 -400.349632) (xy 297.931586 -400.355816) (xy 297.908028 -400.377107) (xy 297.856512 -400.414235)
			(xy 297.800771 -400.444654) (xy 297.741674 -400.467889) (xy 297.680142 -400.483579) (xy 297.617135 -400.491478)
			(xy 297.585384 -400.49196) (xy 297.58513 -400.49196) (xy 297.553163 -400.491577) (xy 297.489734 -400.483567)
			(xy 297.427809 -400.467671) (xy 297.368364 -400.444138) (xy 297.312338 -400.41334) (xy 297.260613 -400.375763)
			(xy 297.214007 -400.331999) (xy 297.173253 -400.282739) (xy 297.138995 -400.228759) (xy 297.111773 -400.170911)
			(xy 297.092015 -400.110108) (xy 297.080035 -400.047307) (xy 297.07602 -399.9835) (xy 296.316063 -399.9835)
			(xy 296.312049 -400.047288) (xy 296.300074 -400.110069) (xy 296.280324 -400.170855) (xy 296.253112 -400.228686)
			(xy 296.218866 -400.282651) (xy 296.178128 -400.331898) (xy 296.131538 -400.375652) (xy 296.079832 -400.413221)
			(xy 296.023825 -400.444014) (xy 295.964401 -400.467545) (xy 295.902496 -400.483442) (xy 295.839087 -400.491456)
			(xy 295.80713 -400.49196) (xy 295.806876 -400.49196) (xy 295.775131 -400.491422) (xy 295.712136 -400.483497)
			(xy 295.650616 -400.467797) (xy 295.591527 -400.444566) (xy 295.535787 -400.414166) (xy 295.484261 -400.377069)
			(xy 295.460674 -400.355816) (xy 295.453411 -400.349632) (xy 295.435661 -400.342681) (xy 295.416599 -400.342681)
			(xy 295.398849 -400.349632) (xy 295.391586 -400.355816) (xy 295.368028 -400.377107) (xy 295.316512 -400.414235)
			(xy 295.260771 -400.444654) (xy 295.201674 -400.467889) (xy 295.140142 -400.483579) (xy 295.077135 -400.491478)
			(xy 295.045384 -400.49196) (xy 295.04513 -400.49196) (xy 295.013163 -400.491577) (xy 294.949734 -400.483567)
			(xy 294.887809 -400.467671) (xy 294.828364 -400.444138) (xy 294.772338 -400.41334) (xy 294.720613 -400.375763)
			(xy 294.674007 -400.331999) (xy 294.633253 -400.282739) (xy 294.598995 -400.228759) (xy 294.571773 -400.170911)
			(xy 294.552015 -400.110108) (xy 294.540035 -400.047307) (xy 294.53602 -399.9835) (xy 293.926484 -399.9835)
			(xy 293.92247 -400.047293) (xy 293.910493 -400.110079) (xy 293.890741 -400.17087) (xy 293.863525 -400.228705)
			(xy 293.829276 -400.282674) (xy 293.788532 -400.331924) (xy 293.741937 -400.375679) (xy 293.690226 -400.41325)
			(xy 293.634213 -400.444043) (xy 293.574783 -400.467573) (xy 293.512872 -400.483468) (xy 293.449457 -400.491479)
			(xy 293.417498 -400.49196) (xy 293.417244 -400.49196) (xy 293.385498 -400.491442) (xy 293.322502 -400.483512)
			(xy 293.260982 -400.467809) (xy 293.201894 -400.444575) (xy 293.146154 -400.414171) (xy 293.094629 -400.37707)
			(xy 293.071042 -400.355816) (xy 293.063779 -400.349632) (xy 293.046029 -400.342681) (xy 293.026967 -400.342681)
			(xy 293.009217 -400.349632) (xy 293.001954 -400.355816) (xy 292.978367 -400.377074) (xy 292.926858 -400.414206)
			(xy 292.871123 -400.44463) (xy 292.812032 -400.467871) (xy 292.750504 -400.483567) (xy 292.687501 -400.491474)
			(xy 292.655752 -400.49196) (xy 292.655498 -400.49196) (xy 292.623534 -400.491554) (xy 292.56011 -400.483542)
			(xy 292.498191 -400.467643) (xy 292.438752 -400.44411) (xy 292.382731 -400.413312) (xy 292.331013 -400.375736)
			(xy 292.284411 -400.331974) (xy 292.243662 -400.282717) (xy 292.209408 -400.22874) (xy 292.182189 -400.170897)
			(xy 292.162434 -400.110098) (xy 292.150455 -400.047302) (xy 292.146441 -399.9835) (xy 291.386484 -399.9835)
			(xy 291.38247 -400.047293) (xy 291.370493 -400.110079) (xy 291.350741 -400.17087) (xy 291.323525 -400.228705)
			(xy 291.289276 -400.282674) (xy 291.248532 -400.331924) (xy 291.201937 -400.375679) (xy 291.150226 -400.41325)
			(xy 291.094213 -400.444043) (xy 291.034783 -400.467573) (xy 290.972872 -400.483468) (xy 290.909457 -400.491479)
			(xy 290.877498 -400.49196) (xy 290.877244 -400.49196) (xy 290.845498 -400.491442) (xy 290.782502 -400.483512)
			(xy 290.720982 -400.467809) (xy 290.661894 -400.444575) (xy 290.606154 -400.414171) (xy 290.554629 -400.37707)
			(xy 290.531042 -400.355816) (xy 290.523779 -400.349632) (xy 290.506029 -400.342681) (xy 290.486967 -400.342681)
			(xy 290.469217 -400.349632) (xy 290.461954 -400.355816) (xy 290.438367 -400.377074) (xy 290.386858 -400.414206)
			(xy 290.331123 -400.44463) (xy 290.272032 -400.467871) (xy 290.210504 -400.483567) (xy 290.147501 -400.491474)
			(xy 290.115752 -400.49196) (xy 290.115498 -400.49196) (xy 290.083534 -400.491554) (xy 290.02011 -400.483542)
			(xy 289.958191 -400.467643) (xy 289.898752 -400.44411) (xy 289.842731 -400.413312) (xy 289.791013 -400.375736)
			(xy 289.744411 -400.331974) (xy 289.703662 -400.282717) (xy 289.669408 -400.22874) (xy 289.642189 -400.170897)
			(xy 289.622434 -400.110098) (xy 289.610455 -400.047302) (xy 289.606441 -399.9835) (xy 281.686508 -399.9835)
			(xy 281.686508 -400.885449) (xy 303.599106 -400.885449) (xy 303.599106 -400.830951) (xy 303.606862 -400.777009)
			(xy 303.622215 -400.724719) (xy 303.644854 -400.675146) (xy 303.674317 -400.6293) (xy 303.710004 -400.588113)
			(xy 303.75119 -400.552424) (xy 303.797036 -400.52296) (xy 303.846608 -400.500319) (xy 303.898897 -400.484964)
			(xy 303.952839 -400.477207) (xy 303.980088 -400.47672) (xy 304.843688 -400.47672) (xy 304.870943 -400.477126)
			(xy 304.9249 -400.484882) (xy 304.977203 -400.500238) (xy 305.026788 -400.522882) (xy 305.072646 -400.552352)
			(xy 305.113843 -400.588048) (xy 305.149541 -400.629244) (xy 305.179012 -400.675101) (xy 305.201657 -400.724686)
			(xy 305.217015 -400.776989) (xy 305.224773 -400.830945) (xy 305.224773 -400.885452) (xy 306.662283 -400.885452)
			(xy 306.662283 -400.830948) (xy 306.67004 -400.776998) (xy 306.685397 -400.724702) (xy 306.70804 -400.675124)
			(xy 306.737508 -400.629273) (xy 306.773202 -400.588082) (xy 306.814395 -400.552391) (xy 306.860248 -400.522926)
			(xy 306.909828 -400.500287) (xy 306.962126 -400.484935) (xy 307.016076 -400.477181) (xy 307.043328 -400.47672)
			(xy 307.906928 -400.47672) (xy 307.93418 -400.477152) (xy 307.988129 -400.484912) (xy 308.040424 -400.500271)
			(xy 308.090001 -400.522915) (xy 308.135851 -400.552384) (xy 308.177041 -400.588079) (xy 308.212732 -400.629271)
			(xy 308.242198 -400.675123) (xy 308.264839 -400.724702) (xy 308.280194 -400.776999) (xy 308.28795 -400.830948)
			(xy 308.28795 -400.885448) (xy 309.725606 -400.885448) (xy 309.725606 -400.830952) (xy 309.733361 -400.777011)
			(xy 309.748714 -400.724723) (xy 309.771351 -400.675152) (xy 309.800812 -400.629306) (xy 309.836497 -400.58812)
			(xy 309.877681 -400.552431) (xy 309.923524 -400.522966) (xy 309.973093 -400.500325) (xy 310.02538 -400.484968)
			(xy 310.07932 -400.477208) (xy 310.106568 -400.47672) (xy 310.970168 -400.47672) (xy 310.997424 -400.477125)
			(xy 311.051383 -400.484879) (xy 311.103688 -400.500233) (xy 311.153276 -400.522875) (xy 311.199137 -400.552345)
			(xy 311.240336 -400.588041) (xy 311.276036 -400.629238) (xy 311.305509 -400.675096) (xy 311.328156 -400.724682)
			(xy 311.343515 -400.776986) (xy 311.351273 -400.830944) (xy 311.351273 -400.885451) (xy 312.788783 -400.885451)
			(xy 312.788783 -400.830949) (xy 312.79654 -400.777001) (xy 312.811895 -400.724706) (xy 312.834537 -400.675129)
			(xy 312.864003 -400.629279) (xy 312.899695 -400.588089) (xy 312.940886 -400.552398) (xy 312.986736 -400.522933)
			(xy 313.036314 -400.500292) (xy 313.088609 -400.484938) (xy 313.142557 -400.477183) (xy 313.169808 -400.47672)
			(xy 314.033408 -400.47672) (xy 314.060661 -400.47715) (xy 314.114612 -400.484908) (xy 314.166909 -400.500265)
			(xy 314.216489 -400.522909) (xy 314.262342 -400.552377) (xy 314.303534 -400.588071) (xy 314.339228 -400.629264)
			(xy 314.368695 -400.675118) (xy 314.391337 -400.724698) (xy 314.406693 -400.776996) (xy 314.41445 -400.830947)
			(xy 314.41445 -400.885453) (xy 315.851983 -400.885453) (xy 315.851983 -400.830947) (xy 315.859741 -400.776996)
			(xy 315.875098 -400.724698) (xy 315.897743 -400.675118) (xy 315.927213 -400.629266) (xy 315.962909 -400.588075)
			(xy 316.004105 -400.552384) (xy 316.04996 -400.52292) (xy 316.099543 -400.500282) (xy 316.151843 -400.484931)
			(xy 316.205795 -400.47718) (xy 316.233048 -400.47672) (xy 317.096648 -400.47672) (xy 317.123899 -400.477153)
			(xy 317.177846 -400.484916) (xy 317.230138 -400.500276) (xy 317.279713 -400.522922) (xy 317.325561 -400.552391)
			(xy 317.366748 -400.588086) (xy 317.402437 -400.629278) (xy 317.431901 -400.675129) (xy 317.454541 -400.724707)
			(xy 317.469894 -400.777001) (xy 317.47765 -400.830949) (xy 317.47765 -400.885449) (xy 318.915306 -400.885449)
			(xy 318.915306 -400.830951) (xy 318.923062 -400.777009) (xy 318.938415 -400.724719) (xy 318.961054 -400.675146)
			(xy 318.990517 -400.6293) (xy 319.026204 -400.588113) (xy 319.06739 -400.552424) (xy 319.113236 -400.52296)
			(xy 319.162808 -400.500319) (xy 319.215097 -400.484964) (xy 319.269039 -400.477207) (xy 319.296288 -400.47672)
			(xy 320.159888 -400.47672) (xy 320.187143 -400.477126) (xy 320.2411 -400.484882) (xy 320.293403 -400.500238)
			(xy 320.342988 -400.522882) (xy 320.388846 -400.552352) (xy 320.430043 -400.588048) (xy 320.465741 -400.629244)
			(xy 320.495212 -400.675101) (xy 320.517857 -400.724686) (xy 320.533215 -400.776989) (xy 320.540973 -400.830945)
			(xy 320.540973 -400.885452) (xy 321.978483 -400.885452) (xy 321.978483 -400.830948) (xy 321.98624 -400.776998)
			(xy 322.001597 -400.724702) (xy 322.02424 -400.675124) (xy 322.053708 -400.629273) (xy 322.089402 -400.588082)
			(xy 322.130595 -400.552391) (xy 322.176448 -400.522926) (xy 322.226028 -400.500287) (xy 322.278326 -400.484935)
			(xy 322.332276 -400.477181) (xy 322.359528 -400.47672) (xy 323.223128 -400.47672) (xy 323.25038 -400.477152)
			(xy 323.304329 -400.484912) (xy 323.356624 -400.500271) (xy 323.406201 -400.522915) (xy 323.452051 -400.552384)
			(xy 323.493241 -400.588079) (xy 323.528932 -400.629271) (xy 323.558398 -400.675123) (xy 323.581039 -400.724702)
			(xy 323.596394 -400.776999) (xy 323.60415 -400.830948) (xy 323.60415 -400.885448) (xy 325.041806 -400.885448)
			(xy 325.041806 -400.830952) (xy 325.049561 -400.777011) (xy 325.064914 -400.724723) (xy 325.087551 -400.675152)
			(xy 325.117012 -400.629306) (xy 325.152697 -400.58812) (xy 325.193881 -400.552431) (xy 325.239724 -400.522966)
			(xy 325.289293 -400.500325) (xy 325.34158 -400.484968) (xy 325.39552 -400.477208) (xy 325.422768 -400.47672)
			(xy 326.286368 -400.47672) (xy 326.313624 -400.477125) (xy 326.367583 -400.484879) (xy 326.419888 -400.500233)
			(xy 326.469476 -400.522875) (xy 326.515337 -400.552345) (xy 326.556536 -400.588041) (xy 326.592236 -400.629238)
			(xy 326.621709 -400.675096) (xy 326.644356 -400.724682) (xy 326.659715 -400.776986) (xy 326.667473 -400.830944)
			(xy 326.667473 -400.885451) (xy 328.104983 -400.885451) (xy 328.104983 -400.830949) (xy 328.11274 -400.777001)
			(xy 328.128095 -400.724706) (xy 328.150737 -400.675129) (xy 328.180203 -400.629279) (xy 328.215895 -400.588089)
			(xy 328.257086 -400.552398) (xy 328.302936 -400.522933) (xy 328.352514 -400.500292) (xy 328.404809 -400.484938)
			(xy 328.458757 -400.477183) (xy 328.486008 -400.47672) (xy 329.349608 -400.47672) (xy 329.376861 -400.47715)
			(xy 329.430812 -400.484908) (xy 329.483109 -400.500265) (xy 329.532689 -400.522909) (xy 329.578542 -400.552377)
			(xy 329.619734 -400.588071) (xy 329.655428 -400.629264) (xy 329.684895 -400.675118) (xy 329.707537 -400.724698)
			(xy 329.722893 -400.776996) (xy 329.73065 -400.830947) (xy 329.73065 -400.885453) (xy 331.168183 -400.885453)
			(xy 331.168183 -400.830947) (xy 331.175941 -400.776996) (xy 331.191298 -400.724698) (xy 331.213943 -400.675118)
			(xy 331.243413 -400.629266) (xy 331.279109 -400.588075) (xy 331.320305 -400.552384) (xy 331.36616 -400.52292)
			(xy 331.415743 -400.500282) (xy 331.468043 -400.484931) (xy 331.521995 -400.47718) (xy 331.549248 -400.47672)
			(xy 332.412848 -400.47672) (xy 332.440099 -400.477153) (xy 332.494046 -400.484916) (xy 332.546338 -400.500276)
			(xy 332.595913 -400.522922) (xy 332.641761 -400.552391) (xy 332.682948 -400.588086) (xy 332.718637 -400.629278)
			(xy 332.748101 -400.675129) (xy 332.770741 -400.724707) (xy 332.786094 -400.777001) (xy 332.79385 -400.830949)
			(xy 332.79385 -400.885449) (xy 334.231506 -400.885449) (xy 334.231506 -400.830951) (xy 334.239262 -400.777009)
			(xy 334.254615 -400.724719) (xy 334.277254 -400.675146) (xy 334.306717 -400.6293) (xy 334.342404 -400.588113)
			(xy 334.38359 -400.552424) (xy 334.429436 -400.52296) (xy 334.479008 -400.500319) (xy 334.531297 -400.484964)
			(xy 334.585239 -400.477207) (xy 334.612488 -400.47672) (xy 335.476088 -400.47672) (xy 335.503343 -400.477126)
			(xy 335.5573 -400.484882) (xy 335.609603 -400.500238) (xy 335.659188 -400.522882) (xy 335.705046 -400.552352)
			(xy 335.746243 -400.588048) (xy 335.781941 -400.629244) (xy 335.811412 -400.675101) (xy 335.834057 -400.724686)
			(xy 335.849415 -400.776989) (xy 335.857173 -400.830945) (xy 335.857173 -400.885452) (xy 337.294683 -400.885452)
			(xy 337.294683 -400.830948) (xy 337.30244 -400.776998) (xy 337.317797 -400.724702) (xy 337.34044 -400.675124)
			(xy 337.369908 -400.629273) (xy 337.405602 -400.588082) (xy 337.446795 -400.552391) (xy 337.492648 -400.522926)
			(xy 337.542228 -400.500287) (xy 337.594526 -400.484935) (xy 337.648476 -400.477181) (xy 337.675728 -400.47672)
			(xy 338.539328 -400.47672) (xy 338.56658 -400.477152) (xy 338.620529 -400.484912) (xy 338.672824 -400.500271)
			(xy 338.722401 -400.522915) (xy 338.768251 -400.552384) (xy 338.809441 -400.588079) (xy 338.845132 -400.629271)
			(xy 338.874598 -400.675123) (xy 338.897239 -400.724702) (xy 338.912594 -400.776999) (xy 338.92035 -400.830948)
			(xy 338.92035 -400.885448) (xy 340.358006 -400.885448) (xy 340.358006 -400.830952) (xy 340.365761 -400.777011)
			(xy 340.381114 -400.724723) (xy 340.403751 -400.675152) (xy 340.433212 -400.629306) (xy 340.468897 -400.58812)
			(xy 340.510081 -400.552431) (xy 340.555924 -400.522966) (xy 340.605493 -400.500325) (xy 340.65778 -400.484968)
			(xy 340.71172 -400.477208) (xy 340.738968 -400.47672) (xy 341.602568 -400.47672) (xy 341.629824 -400.477125)
			(xy 341.683783 -400.484879) (xy 341.736088 -400.500233) (xy 341.785676 -400.522875) (xy 341.831537 -400.552345)
			(xy 341.872736 -400.588041) (xy 341.908436 -400.629238) (xy 341.937909 -400.675096) (xy 341.960556 -400.724682)
			(xy 341.975915 -400.776986) (xy 341.983673 -400.830944) (xy 341.983673 -400.885451) (xy 343.421183 -400.885451)
			(xy 343.421183 -400.830949) (xy 343.42894 -400.777001) (xy 343.444295 -400.724706) (xy 343.466937 -400.675129)
			(xy 343.496403 -400.629279) (xy 343.532095 -400.588089) (xy 343.573286 -400.552398) (xy 343.619136 -400.522933)
			(xy 343.668714 -400.500292) (xy 343.721009 -400.484938) (xy 343.774957 -400.477183) (xy 343.802208 -400.47672)
			(xy 344.665808 -400.47672) (xy 344.693061 -400.47715) (xy 344.747012 -400.484908) (xy 344.799309 -400.500265)
			(xy 344.848889 -400.522909) (xy 344.894742 -400.552377) (xy 344.935934 -400.588071) (xy 344.971628 -400.629264)
			(xy 345.001095 -400.675118) (xy 345.023737 -400.724698) (xy 345.039093 -400.776996) (xy 345.04685 -400.830947)
			(xy 345.04685 -400.885453) (xy 346.484383 -400.885453) (xy 346.484383 -400.830947) (xy 346.492141 -400.776996)
			(xy 346.507498 -400.724698) (xy 346.530143 -400.675118) (xy 346.559613 -400.629266) (xy 346.595309 -400.588075)
			(xy 346.636505 -400.552384) (xy 346.68236 -400.52292) (xy 346.731943 -400.500282) (xy 346.784243 -400.484931)
			(xy 346.838195 -400.47718) (xy 346.865448 -400.47672) (xy 347.729048 -400.47672) (xy 347.756299 -400.477153)
			(xy 347.810246 -400.484916) (xy 347.862538 -400.500276) (xy 347.912113 -400.522922) (xy 347.957961 -400.552391)
			(xy 347.999148 -400.588086) (xy 348.034837 -400.629278) (xy 348.064301 -400.675129) (xy 348.086941 -400.724707)
			(xy 348.102294 -400.777001) (xy 348.11005 -400.830949) (xy 348.11005 -400.885449) (xy 349.547706 -400.885449)
			(xy 349.547706 -400.830951) (xy 349.555462 -400.777009) (xy 349.570815 -400.724719) (xy 349.593454 -400.675146)
			(xy 349.622917 -400.6293) (xy 349.658604 -400.588113) (xy 349.69979 -400.552424) (xy 349.745636 -400.52296)
			(xy 349.795208 -400.500319) (xy 349.847497 -400.484964) (xy 349.901439 -400.477207) (xy 349.928688 -400.47672)
			(xy 350.792288 -400.47672) (xy 350.819543 -400.477126) (xy 350.8735 -400.484882) (xy 350.925803 -400.500238)
			(xy 350.975388 -400.522882) (xy 351.021246 -400.552352) (xy 351.062443 -400.588048) (xy 351.098141 -400.629244)
			(xy 351.127612 -400.675101) (xy 351.150257 -400.724686) (xy 351.165615 -400.776989) (xy 351.173373 -400.830945)
			(xy 351.173373 -400.885452) (xy 371.041883 -400.885452) (xy 371.041883 -400.830948) (xy 371.049641 -400.776998)
			(xy 371.064997 -400.724702) (xy 371.08764 -400.675123) (xy 371.117109 -400.629272) (xy 371.152803 -400.588082)
			(xy 371.193996 -400.552391) (xy 371.23985 -400.522926) (xy 371.28943 -400.500286) (xy 371.341728 -400.484934)
			(xy 371.395678 -400.477181) (xy 371.42293 -400.47672) (xy 372.28653 -400.47672) (xy 372.313782 -400.477152)
			(xy 372.36773 -400.484912) (xy 372.420025 -400.500271) (xy 372.469602 -400.522916) (xy 372.515452 -400.552385)
			(xy 372.556642 -400.588079) (xy 372.592333 -400.629272) (xy 372.621799 -400.675124) (xy 372.644439 -400.724703)
			(xy 372.659794 -400.776999) (xy 372.66755 -400.830948) (xy 372.66755 -400.885448) (xy 374.105206 -400.885448)
			(xy 374.105206 -400.830952) (xy 374.112961 -400.777011) (xy 374.128314 -400.724723) (xy 374.150951 -400.675151)
			(xy 374.180412 -400.629306) (xy 374.216098 -400.588119) (xy 374.257281 -400.55243) (xy 374.303125 -400.522965)
			(xy 374.352694 -400.500324) (xy 374.404982 -400.484968) (xy 374.458922 -400.477208) (xy 374.48617 -400.47672)
			(xy 375.34977 -400.47672) (xy 375.377026 -400.477125) (xy 375.430984 -400.484879) (xy 375.48329 -400.500234)
			(xy 375.532877 -400.522876) (xy 375.578738 -400.552345) (xy 375.619937 -400.588042) (xy 375.655637 -400.629238)
			(xy 375.68511 -400.675096) (xy 375.707756 -400.724682) (xy 375.723115 -400.776986) (xy 375.730873 -400.830944)
			(xy 375.730873 -400.885451) (xy 377.168383 -400.885451) (xy 377.168383 -400.830949) (xy 377.17614 -400.777001)
			(xy 377.191495 -400.724706) (xy 377.214137 -400.675129) (xy 377.243604 -400.629279) (xy 377.279296 -400.588089)
			(xy 377.320487 -400.552398) (xy 377.366338 -400.522932) (xy 377.415915 -400.500292) (xy 377.468211 -400.484938)
			(xy 377.522159 -400.477183) (xy 377.54941 -400.47672) (xy 378.41301 -400.47672) (xy 378.440263 -400.477151)
			(xy 378.494213 -400.484909) (xy 378.546511 -400.500266) (xy 378.59609 -400.522909) (xy 378.641943 -400.552378)
			(xy 378.683135 -400.588072) (xy 378.718828 -400.629265) (xy 378.748296 -400.675118) (xy 378.770938 -400.724699)
			(xy 378.786293 -400.776996) (xy 378.79405 -400.830947) (xy 378.79405 -400.885447) (xy 380.231706 -400.885447)
			(xy 380.231706 -400.830953) (xy 380.239461 -400.777014) (xy 380.254812 -400.724727) (xy 380.277448 -400.675157)
			(xy 380.306907 -400.629312) (xy 380.342591 -400.588126) (xy 380.383772 -400.552437) (xy 380.429613 -400.522972)
			(xy 380.47918 -400.50033) (xy 380.531465 -400.484971) (xy 380.585403 -400.47721) (xy 380.61265 -400.47672)
			(xy 381.47625 -400.47672) (xy 381.503507 -400.477124) (xy 381.557468 -400.484875) (xy 381.609775 -400.500228)
			(xy 381.659365 -400.522869) (xy 381.705228 -400.552338) (xy 381.74643 -400.588035) (xy 381.782132 -400.629232)
			(xy 381.811607 -400.675091) (xy 381.834254 -400.724678) (xy 381.849614 -400.776983) (xy 381.857373 -400.830943)
			(xy 381.857373 -400.885449) (xy 383.294906 -400.885449) (xy 383.294906 -400.830951) (xy 383.302662 -400.777008)
			(xy 383.318015 -400.724718) (xy 383.340654 -400.675145) (xy 383.370117 -400.629299) (xy 383.405805 -400.588112)
			(xy 383.446991 -400.552423) (xy 383.492837 -400.522959) (xy 383.542409 -400.500319) (xy 383.594699 -400.484964)
			(xy 383.648641 -400.477207) (xy 383.67589 -400.47672) (xy 384.53949 -400.47672) (xy 384.566745 -400.477126)
			(xy 384.620701 -400.484883) (xy 384.673004 -400.500239) (xy 384.722589 -400.522883) (xy 384.768447 -400.552352)
			(xy 384.809644 -400.588049) (xy 384.845342 -400.629245) (xy 384.874813 -400.675102) (xy 384.897458 -400.724686)
			(xy 384.912815 -400.776989) (xy 384.920573 -400.830945) (xy 384.920573 -400.885452) (xy 386.358083 -400.885452)
			(xy 386.358083 -400.830948) (xy 386.365841 -400.776998) (xy 386.381197 -400.724702) (xy 386.40384 -400.675123)
			(xy 386.433309 -400.629272) (xy 386.469003 -400.588082) (xy 386.510196 -400.552391) (xy 386.55605 -400.522926)
			(xy 386.60563 -400.500286) (xy 386.657928 -400.484934) (xy 386.711878 -400.477181) (xy 386.73913 -400.47672)
			(xy 387.60273 -400.47672) (xy 387.629982 -400.477152) (xy 387.68393 -400.484912) (xy 387.736225 -400.500271)
			(xy 387.785802 -400.522916) (xy 387.831652 -400.552385) (xy 387.872842 -400.588079) (xy 387.908533 -400.629272)
			(xy 387.937999 -400.675124) (xy 387.960639 -400.724703) (xy 387.975994 -400.776999) (xy 387.98375 -400.830948)
			(xy 387.98375 -400.885448) (xy 389.421406 -400.885448) (xy 389.421406 -400.830952) (xy 389.429161 -400.777011)
			(xy 389.444514 -400.724723) (xy 389.467151 -400.675151) (xy 389.496612 -400.629306) (xy 389.532298 -400.588119)
			(xy 389.573481 -400.55243) (xy 389.619325 -400.522965) (xy 389.668894 -400.500324) (xy 389.721182 -400.484968)
			(xy 389.775122 -400.477208) (xy 389.80237 -400.47672) (xy 390.66597 -400.47672) (xy 390.693226 -400.477125)
			(xy 390.747184 -400.484879) (xy 390.79949 -400.500234) (xy 390.849077 -400.522876) (xy 390.894938 -400.552345)
			(xy 390.936137 -400.588042) (xy 390.971837 -400.629238) (xy 391.00131 -400.675096) (xy 391.023956 -400.724682)
			(xy 391.039315 -400.776986) (xy 391.047073 -400.830944) (xy 391.047073 -400.885451) (xy 392.484583 -400.885451)
			(xy 392.484583 -400.830949) (xy 392.49234 -400.777001) (xy 392.507695 -400.724706) (xy 392.530337 -400.675129)
			(xy 392.559804 -400.629279) (xy 392.595496 -400.588089) (xy 392.636687 -400.552398) (xy 392.682538 -400.522932)
			(xy 392.732115 -400.500292) (xy 392.784411 -400.484938) (xy 392.838359 -400.477183) (xy 392.86561 -400.47672)
			(xy 393.72921 -400.47672) (xy 393.756463 -400.477151) (xy 393.810413 -400.484909) (xy 393.862711 -400.500266)
			(xy 393.91229 -400.522909) (xy 393.958143 -400.552378) (xy 393.999335 -400.588072) (xy 394.035028 -400.629265)
			(xy 394.064496 -400.675118) (xy 394.087138 -400.724699) (xy 394.102493 -400.776996) (xy 394.11025 -400.830947)
			(xy 394.11025 -400.885447) (xy 395.547906 -400.885447) (xy 395.547906 -400.830953) (xy 395.555661 -400.777014)
			(xy 395.571012 -400.724727) (xy 395.593648 -400.675157) (xy 395.623107 -400.629312) (xy 395.658791 -400.588126)
			(xy 395.699972 -400.552437) (xy 395.745813 -400.522972) (xy 395.79538 -400.50033) (xy 395.847665 -400.484971)
			(xy 395.901603 -400.47721) (xy 395.92885 -400.47672) (xy 396.79245 -400.47672) (xy 396.819707 -400.477124)
			(xy 396.873668 -400.484875) (xy 396.925975 -400.500228) (xy 396.975565 -400.522869) (xy 397.021428 -400.552338)
			(xy 397.06263 -400.588035) (xy 397.098332 -400.629232) (xy 397.127807 -400.675091) (xy 397.150454 -400.724678)
			(xy 397.165814 -400.776983) (xy 397.173573 -400.830943) (xy 397.173573 -400.885449) (xy 398.611106 -400.885449)
			(xy 398.611106 -400.830951) (xy 398.618862 -400.777008) (xy 398.634215 -400.724718) (xy 398.656854 -400.675145)
			(xy 398.686317 -400.629299) (xy 398.722005 -400.588112) (xy 398.763191 -400.552423) (xy 398.809037 -400.522959)
			(xy 398.858609 -400.500319) (xy 398.910899 -400.484964) (xy 398.964841 -400.477207) (xy 398.99209 -400.47672)
			(xy 399.85569 -400.47672) (xy 399.882945 -400.477126) (xy 399.936901 -400.484883) (xy 399.989204 -400.500239)
			(xy 400.038789 -400.522883) (xy 400.084647 -400.552352) (xy 400.125844 -400.588049) (xy 400.161542 -400.629245)
			(xy 400.191013 -400.675102) (xy 400.213658 -400.724686) (xy 400.229015 -400.776989) (xy 400.236773 -400.830945)
			(xy 400.236773 -400.885452) (xy 401.674283 -400.885452) (xy 401.674283 -400.830948) (xy 401.682041 -400.776998)
			(xy 401.697397 -400.724702) (xy 401.72004 -400.675123) (xy 401.749509 -400.629272) (xy 401.785203 -400.588082)
			(xy 401.826396 -400.552391) (xy 401.87225 -400.522926) (xy 401.92183 -400.500286) (xy 401.974128 -400.484934)
			(xy 402.028078 -400.477181) (xy 402.05533 -400.47672) (xy 402.91893 -400.47672) (xy 402.946182 -400.477152)
			(xy 403.00013 -400.484912) (xy 403.052425 -400.500271) (xy 403.102002 -400.522916) (xy 403.147852 -400.552385)
			(xy 403.189042 -400.588079) (xy 403.224733 -400.629272) (xy 403.254199 -400.675124) (xy 403.276839 -400.724703)
			(xy 403.292194 -400.776999) (xy 403.29995 -400.830948) (xy 403.29995 -400.885448) (xy 404.737606 -400.885448)
			(xy 404.737606 -400.830952) (xy 404.745361 -400.777011) (xy 404.760714 -400.724723) (xy 404.783351 -400.675151)
			(xy 404.812812 -400.629306) (xy 404.848498 -400.588119) (xy 404.889681 -400.55243) (xy 404.935525 -400.522965)
			(xy 404.985094 -400.500324) (xy 405.037382 -400.484968) (xy 405.091322 -400.477208) (xy 405.11857 -400.47672)
			(xy 405.98217 -400.47672) (xy 406.009426 -400.477125) (xy 406.063384 -400.484879) (xy 406.11569 -400.500234)
			(xy 406.165277 -400.522876) (xy 406.211138 -400.552345) (xy 406.252337 -400.588042) (xy 406.288037 -400.629238)
			(xy 406.31751 -400.675096) (xy 406.340156 -400.724682) (xy 406.355515 -400.776986) (xy 406.363273 -400.830944)
			(xy 406.363273 -400.885451) (xy 407.800783 -400.885451) (xy 407.800783 -400.830949) (xy 407.80854 -400.777001)
			(xy 407.823895 -400.724706) (xy 407.846537 -400.675129) (xy 407.876004 -400.629279) (xy 407.911696 -400.588089)
			(xy 407.952887 -400.552398) (xy 407.998738 -400.522932) (xy 408.048315 -400.500292) (xy 408.100611 -400.484938)
			(xy 408.154559 -400.477183) (xy 408.18181 -400.47672) (xy 409.04541 -400.47672) (xy 409.072663 -400.477151)
			(xy 409.126613 -400.484909) (xy 409.178911 -400.500266) (xy 409.22849 -400.522909) (xy 409.274343 -400.552378)
			(xy 409.315535 -400.588072) (xy 409.351228 -400.629265) (xy 409.380696 -400.675118) (xy 409.403338 -400.724699)
			(xy 409.418693 -400.776996) (xy 409.42645 -400.830947) (xy 409.42645 -400.885447) (xy 410.864106 -400.885447)
			(xy 410.864106 -400.830953) (xy 410.871861 -400.777014) (xy 410.887212 -400.724727) (xy 410.909848 -400.675157)
			(xy 410.939307 -400.629312) (xy 410.974991 -400.588126) (xy 411.016172 -400.552437) (xy 411.062013 -400.522972)
			(xy 411.11158 -400.50033) (xy 411.163865 -400.484971) (xy 411.217803 -400.47721) (xy 411.24505 -400.47672)
			(xy 412.10865 -400.47672) (xy 412.135907 -400.477124) (xy 412.189868 -400.484875) (xy 412.242175 -400.500228)
			(xy 412.291765 -400.522869) (xy 412.337628 -400.552338) (xy 412.37883 -400.588035) (xy 412.414532 -400.629232)
			(xy 412.444007 -400.675091) (xy 412.466654 -400.724678) (xy 412.482014 -400.776983) (xy 412.489773 -400.830943)
			(xy 412.489773 -400.885449) (xy 413.927306 -400.885449) (xy 413.927306 -400.830951) (xy 413.935062 -400.777008)
			(xy 413.950415 -400.724718) (xy 413.973054 -400.675145) (xy 414.002517 -400.629299) (xy 414.038205 -400.588112)
			(xy 414.079391 -400.552423) (xy 414.125237 -400.522959) (xy 414.174809 -400.500319) (xy 414.227099 -400.484964)
			(xy 414.281041 -400.477207) (xy 414.30829 -400.47672) (xy 415.17189 -400.47672) (xy 415.199145 -400.477126)
			(xy 415.253101 -400.484883) (xy 415.305404 -400.500239) (xy 415.354989 -400.522883) (xy 415.400847 -400.552352)
			(xy 415.442044 -400.588049) (xy 415.477742 -400.629245) (xy 415.507213 -400.675102) (xy 415.529858 -400.724686)
			(xy 415.545215 -400.776989) (xy 415.552973 -400.830945) (xy 415.552973 -400.885452) (xy 416.990483 -400.885452)
			(xy 416.990483 -400.830948) (xy 416.998241 -400.776998) (xy 417.013597 -400.724702) (xy 417.03624 -400.675123)
			(xy 417.065709 -400.629272) (xy 417.101403 -400.588082) (xy 417.142596 -400.552391) (xy 417.18845 -400.522926)
			(xy 417.23803 -400.500286) (xy 417.290328 -400.484934) (xy 417.344278 -400.477181) (xy 417.37153 -400.47672)
			(xy 418.23513 -400.47672) (xy 418.262382 -400.477152) (xy 418.31633 -400.484912) (xy 418.368625 -400.500271)
			(xy 418.418202 -400.522916) (xy 418.464052 -400.552385) (xy 418.505242 -400.588079) (xy 418.540933 -400.629272)
			(xy 418.570399 -400.675124) (xy 418.593039 -400.724703) (xy 418.608394 -400.776999) (xy 418.61615 -400.830948)
			(xy 418.61615 -400.885452) (xy 418.608394 -400.939401) (xy 418.593039 -400.991697) (xy 418.570399 -401.041276)
			(xy 418.540933 -401.087128) (xy 418.505242 -401.128321) (xy 418.464052 -401.164015) (xy 418.418202 -401.193484)
			(xy 418.368625 -401.216129) (xy 418.31633 -401.231488) (xy 418.262382 -401.239248) (xy 418.23513 -401.239736)
			(xy 417.37153 -401.239736) (xy 417.344278 -401.239219) (xy 417.290328 -401.231466) (xy 417.23803 -401.216114)
			(xy 417.18845 -401.193474) (xy 417.142596 -401.164009) (xy 417.101403 -401.128318) (xy 417.065709 -401.087128)
			(xy 417.03624 -401.041277) (xy 417.013597 -400.991698) (xy 416.998241 -400.939402) (xy 416.990483 -400.885452)
			(xy 415.552973 -400.885452) (xy 415.552973 -400.885455) (xy 415.545215 -400.939411) (xy 415.529858 -400.991714)
			(xy 415.507213 -401.041298) (xy 415.477742 -401.087155) (xy 415.442044 -401.128351) (xy 415.400847 -401.164048)
			(xy 415.354989 -401.193517) (xy 415.305404 -401.216161) (xy 415.253101 -401.231517) (xy 415.199145 -401.239274)
			(xy 415.17189 -401.239736) (xy 414.30829 -401.239736) (xy 414.281041 -401.239193) (xy 414.227099 -401.231436)
			(xy 414.174809 -401.216081) (xy 414.125237 -401.193441) (xy 414.079391 -401.163977) (xy 414.038205 -401.128288)
			(xy 414.002517 -401.087101) (xy 413.973054 -401.041255) (xy 413.950415 -400.991682) (xy 413.935062 -400.939392)
			(xy 413.927306 -400.885449) (xy 412.489773 -400.885449) (xy 412.489773 -400.885457) (xy 412.482014 -400.939416)
			(xy 412.466654 -400.991722) (xy 412.444007 -401.041309) (xy 412.414532 -401.087168) (xy 412.37883 -401.128365)
			(xy 412.337628 -401.164062) (xy 412.291765 -401.193531) (xy 412.242175 -401.216172) (xy 412.189868 -401.231525)
			(xy 412.135907 -401.239276) (xy 412.10865 -401.239736) (xy 411.24505 -401.239736) (xy 411.217803 -401.23919)
			(xy 411.163865 -401.231429) (xy 411.11158 -401.21607) (xy 411.062013 -401.193428) (xy 411.016172 -401.163963)
			(xy 410.974991 -401.128274) (xy 410.939307 -401.087088) (xy 410.909848 -401.041243) (xy 410.887212 -400.991673)
			(xy 410.871861 -400.939386) (xy 410.864106 -400.885447) (xy 409.42645 -400.885447) (xy 409.42645 -400.885453)
			(xy 409.418693 -400.939404) (xy 409.403338 -400.991701) (xy 409.380696 -401.041282) (xy 409.351228 -401.087135)
			(xy 409.315535 -401.128328) (xy 409.274343 -401.164022) (xy 409.22849 -401.193491) (xy 409.178911 -401.216134)
			(xy 409.126613 -401.231491) (xy 409.072663 -401.239249) (xy 409.04541 -401.239736) (xy 408.18181 -401.239736)
			(xy 408.154559 -401.239217) (xy 408.100611 -401.231462) (xy 408.048315 -401.216108) (xy 407.998738 -401.193468)
			(xy 407.952887 -401.164002) (xy 407.911696 -401.128311) (xy 407.876004 -401.087121) (xy 407.846537 -401.041271)
			(xy 407.823895 -400.991694) (xy 407.80854 -400.939399) (xy 407.800783 -400.885451) (xy 406.363273 -400.885451)
			(xy 406.363273 -400.885456) (xy 406.355515 -400.939414) (xy 406.340156 -400.991718) (xy 406.31751 -401.041304)
			(xy 406.288037 -401.087162) (xy 406.252337 -401.128358) (xy 406.211138 -401.164055) (xy 406.165277 -401.193524)
			(xy 406.11569 -401.216166) (xy 406.063384 -401.231521) (xy 406.009426 -401.239275) (xy 405.98217 -401.239736)
			(xy 405.11857 -401.239736) (xy 405.091322 -401.239192) (xy 405.037382 -401.231432) (xy 404.985094 -401.216076)
			(xy 404.935525 -401.193435) (xy 404.889682 -401.16397) (xy 404.848498 -401.128281) (xy 404.812812 -401.087094)
			(xy 404.783351 -401.041249) (xy 404.760714 -400.991677) (xy 404.745361 -400.939389) (xy 404.737606 -400.885448)
			(xy 403.29995 -400.885448) (xy 403.29995 -400.885452) (xy 403.292194 -400.939401) (xy 403.276839 -400.991697)
			(xy 403.254199 -401.041276) (xy 403.224733 -401.087128) (xy 403.189042 -401.128321) (xy 403.147852 -401.164015)
			(xy 403.102002 -401.193484) (xy 403.052425 -401.216129) (xy 403.00013 -401.231488) (xy 402.946182 -401.239248)
			(xy 402.91893 -401.239736) (xy 402.05533 -401.239736) (xy 402.028078 -401.239219) (xy 401.974128 -401.231466)
			(xy 401.92183 -401.216114) (xy 401.87225 -401.193474) (xy 401.826396 -401.164009) (xy 401.785203 -401.128318)
			(xy 401.749509 -401.087128) (xy 401.72004 -401.041277) (xy 401.697397 -400.991698) (xy 401.682041 -400.939402)
			(xy 401.674283 -400.885452) (xy 400.236773 -400.885452) (xy 400.236773 -400.885455) (xy 400.229015 -400.939411)
			(xy 400.213658 -400.991714) (xy 400.191013 -401.041298) (xy 400.161542 -401.087155) (xy 400.125844 -401.128351)
			(xy 400.084647 -401.164048) (xy 400.038789 -401.193517) (xy 399.989204 -401.216161) (xy 399.936901 -401.231517)
			(xy 399.882945 -401.239274) (xy 399.85569 -401.239736) (xy 398.99209 -401.239736) (xy 398.964841 -401.239193)
			(xy 398.910899 -401.231436) (xy 398.858609 -401.216081) (xy 398.809037 -401.193441) (xy 398.763191 -401.163977)
			(xy 398.722005 -401.128288) (xy 398.686317 -401.087101) (xy 398.656854 -401.041255) (xy 398.634215 -400.991682)
			(xy 398.618862 -400.939392) (xy 398.611106 -400.885449) (xy 397.173573 -400.885449) (xy 397.173573 -400.885457)
			(xy 397.165814 -400.939416) (xy 397.150454 -400.991722) (xy 397.127807 -401.041309) (xy 397.098332 -401.087168)
			(xy 397.06263 -401.128365) (xy 397.021428 -401.164062) (xy 396.975565 -401.193531) (xy 396.925975 -401.216172)
			(xy 396.873668 -401.231525) (xy 396.819707 -401.239276) (xy 396.79245 -401.239736) (xy 395.92885 -401.239736)
			(xy 395.901603 -401.23919) (xy 395.847665 -401.231429) (xy 395.79538 -401.21607) (xy 395.745813 -401.193428)
			(xy 395.699972 -401.163963) (xy 395.658791 -401.128274) (xy 395.623107 -401.087088) (xy 395.593648 -401.041243)
			(xy 395.571012 -400.991673) (xy 395.555661 -400.939386) (xy 395.547906 -400.885447) (xy 394.11025 -400.885447)
			(xy 394.11025 -400.885453) (xy 394.102493 -400.939404) (xy 394.087138 -400.991701) (xy 394.064496 -401.041282)
			(xy 394.035028 -401.087135) (xy 393.999335 -401.128328) (xy 393.958143 -401.164022) (xy 393.91229 -401.193491)
			(xy 393.862711 -401.216134) (xy 393.810413 -401.231491) (xy 393.756463 -401.239249) (xy 393.72921 -401.239736)
			(xy 392.86561 -401.239736) (xy 392.838359 -401.239217) (xy 392.784411 -401.231462) (xy 392.732115 -401.216108)
			(xy 392.682538 -401.193468) (xy 392.636687 -401.164002) (xy 392.595496 -401.128311) (xy 392.559804 -401.087121)
			(xy 392.530337 -401.041271) (xy 392.507695 -400.991694) (xy 392.49234 -400.939399) (xy 392.484583 -400.885451)
			(xy 391.047073 -400.885451) (xy 391.047073 -400.885456) (xy 391.039315 -400.939414) (xy 391.023956 -400.991718)
			(xy 391.00131 -401.041304) (xy 390.971837 -401.087162) (xy 390.936137 -401.128358) (xy 390.894938 -401.164055)
			(xy 390.849077 -401.193524) (xy 390.79949 -401.216166) (xy 390.747184 -401.231521) (xy 390.693226 -401.239275)
			(xy 390.66597 -401.239736) (xy 389.80237 -401.239736) (xy 389.775122 -401.239192) (xy 389.721182 -401.231432)
			(xy 389.668894 -401.216076) (xy 389.619325 -401.193435) (xy 389.573482 -401.16397) (xy 389.532298 -401.128281)
			(xy 389.496612 -401.087094) (xy 389.467151 -401.041249) (xy 389.444514 -400.991677) (xy 389.429161 -400.939389)
			(xy 389.421406 -400.885448) (xy 387.98375 -400.885448) (xy 387.98375 -400.885452) (xy 387.975994 -400.939401)
			(xy 387.960639 -400.991697) (xy 387.937999 -401.041276) (xy 387.908533 -401.087128) (xy 387.872842 -401.128321)
			(xy 387.831652 -401.164015) (xy 387.785802 -401.193484) (xy 387.736225 -401.216129) (xy 387.68393 -401.231488)
			(xy 387.629982 -401.239248) (xy 387.60273 -401.239736) (xy 386.73913 -401.239736) (xy 386.711878 -401.239219)
			(xy 386.657928 -401.231466) (xy 386.60563 -401.216114) (xy 386.55605 -401.193474) (xy 386.510196 -401.164009)
			(xy 386.469003 -401.128318) (xy 386.433309 -401.087128) (xy 386.40384 -401.041277) (xy 386.381197 -400.991698)
			(xy 386.365841 -400.939402) (xy 386.358083 -400.885452) (xy 384.920573 -400.885452) (xy 384.920573 -400.885455)
			(xy 384.912815 -400.939411) (xy 384.897458 -400.991714) (xy 384.874813 -401.041298) (xy 384.845342 -401.087155)
			(xy 384.809644 -401.128351) (xy 384.768447 -401.164048) (xy 384.722589 -401.193517) (xy 384.673004 -401.216161)
			(xy 384.620701 -401.231517) (xy 384.566745 -401.239274) (xy 384.53949 -401.239736) (xy 383.67589 -401.239736)
			(xy 383.648641 -401.239193) (xy 383.594699 -401.231436) (xy 383.542409 -401.216081) (xy 383.492837 -401.193441)
			(xy 383.446991 -401.163977) (xy 383.405805 -401.128288) (xy 383.370117 -401.087101) (xy 383.340654 -401.041255)
			(xy 383.318015 -400.991682) (xy 383.302662 -400.939392) (xy 383.294906 -400.885449) (xy 381.857373 -400.885449)
			(xy 381.857373 -400.885457) (xy 381.849614 -400.939416) (xy 381.834254 -400.991722) (xy 381.811607 -401.041309)
			(xy 381.782132 -401.087168) (xy 381.74643 -401.128365) (xy 381.705228 -401.164062) (xy 381.659365 -401.193531)
			(xy 381.609775 -401.216172) (xy 381.557468 -401.231525) (xy 381.503507 -401.239276) (xy 381.47625 -401.239736)
			(xy 380.61265 -401.239736) (xy 380.585403 -401.23919) (xy 380.531465 -401.231429) (xy 380.47918 -401.21607)
			(xy 380.429613 -401.193428) (xy 380.383772 -401.163963) (xy 380.342591 -401.128274) (xy 380.306907 -401.087088)
			(xy 380.277448 -401.041243) (xy 380.254812 -400.991673) (xy 380.239461 -400.939386) (xy 380.231706 -400.885447)
			(xy 378.79405 -400.885447) (xy 378.79405 -400.885453) (xy 378.786293 -400.939404) (xy 378.770938 -400.991701)
			(xy 378.748296 -401.041282) (xy 378.718828 -401.087135) (xy 378.683135 -401.128328) (xy 378.641943 -401.164022)
			(xy 378.59609 -401.193491) (xy 378.546511 -401.216134) (xy 378.494213 -401.231491) (xy 378.440263 -401.239249)
			(xy 378.41301 -401.239736) (xy 377.54941 -401.239736) (xy 377.522159 -401.239217) (xy 377.468211 -401.231462)
			(xy 377.415915 -401.216108) (xy 377.366338 -401.193468) (xy 377.320487 -401.164002) (xy 377.279296 -401.128311)
			(xy 377.243604 -401.087121) (xy 377.214137 -401.041271) (xy 377.191495 -400.991694) (xy 377.17614 -400.939399)
			(xy 377.168383 -400.885451) (xy 375.730873 -400.885451) (xy 375.730873 -400.885456) (xy 375.723115 -400.939414)
			(xy 375.707756 -400.991718) (xy 375.68511 -401.041304) (xy 375.655637 -401.087162) (xy 375.619937 -401.128358)
			(xy 375.578738 -401.164055) (xy 375.532877 -401.193524) (xy 375.48329 -401.216166) (xy 375.430984 -401.231521)
			(xy 375.377026 -401.239275) (xy 375.34977 -401.239736) (xy 374.48617 -401.239736) (xy 374.458922 -401.239192)
			(xy 374.404982 -401.231432) (xy 374.352694 -401.216076) (xy 374.303125 -401.193435) (xy 374.257282 -401.16397)
			(xy 374.216098 -401.128281) (xy 374.180412 -401.087094) (xy 374.150951 -401.041249) (xy 374.128314 -400.991677)
			(xy 374.112961 -400.939389) (xy 374.105206 -400.885448) (xy 372.66755 -400.885448) (xy 372.66755 -400.885452)
			(xy 372.659794 -400.939401) (xy 372.644439 -400.991697) (xy 372.621799 -401.041276) (xy 372.592333 -401.087128)
			(xy 372.556642 -401.128321) (xy 372.515452 -401.164015) (xy 372.469602 -401.193484) (xy 372.420025 -401.216129)
			(xy 372.36773 -401.231488) (xy 372.313782 -401.239248) (xy 372.28653 -401.239736) (xy 371.42293 -401.239736)
			(xy 371.395678 -401.239219) (xy 371.341728 -401.231466) (xy 371.28943 -401.216114) (xy 371.23985 -401.193474)
			(xy 371.193996 -401.164009) (xy 371.152803 -401.128318) (xy 371.117109 -401.087128) (xy 371.08764 -401.041277)
			(xy 371.064997 -400.991698) (xy 371.049641 -400.939402) (xy 371.041883 -400.885452) (xy 351.173373 -400.885452)
			(xy 351.173373 -400.885455) (xy 351.165615 -400.939411) (xy 351.150257 -400.991714) (xy 351.127612 -401.041299)
			(xy 351.098141 -401.087156) (xy 351.062443 -401.128352) (xy 351.021246 -401.164048) (xy 350.975388 -401.193518)
			(xy 350.925803 -401.216162) (xy 350.8735 -401.231518) (xy 350.819543 -401.239274) (xy 350.792288 -401.239736)
			(xy 349.928688 -401.239736) (xy 349.901439 -401.239193) (xy 349.847497 -401.231436) (xy 349.795208 -401.216081)
			(xy 349.745636 -401.19344) (xy 349.69979 -401.163976) (xy 349.658604 -401.128287) (xy 349.622917 -401.0871)
			(xy 349.593454 -401.041254) (xy 349.570815 -400.991681) (xy 349.555462 -400.939391) (xy 349.547706 -400.885449)
			(xy 348.11005 -400.885449) (xy 348.11005 -400.885451) (xy 348.102294 -400.939399) (xy 348.086941 -400.991693)
			(xy 348.064301 -401.041271) (xy 348.034837 -401.087122) (xy 347.999148 -401.128314) (xy 347.957961 -401.164009)
			(xy 347.912113 -401.193478) (xy 347.862538 -401.216124) (xy 347.810245 -401.231484) (xy 347.756299 -401.239247)
			(xy 347.729048 -401.239736) (xy 346.865448 -401.239736) (xy 346.838195 -401.23922) (xy 346.784243 -401.231469)
			(xy 346.731943 -401.216118) (xy 346.68236 -401.19348) (xy 346.636505 -401.164016) (xy 346.595309 -401.128325)
			(xy 346.559613 -401.087134) (xy 346.530143 -401.041282) (xy 346.507498 -400.991702) (xy 346.492141 -400.939404)
			(xy 346.484383 -400.885453) (xy 345.04685 -400.885453) (xy 345.039093 -400.939404) (xy 345.023737 -400.991702)
			(xy 345.001095 -401.041282) (xy 344.971628 -401.087136) (xy 344.935934 -401.128329) (xy 344.894742 -401.164023)
			(xy 344.848889 -401.193491) (xy 344.799309 -401.216135) (xy 344.747012 -401.231492) (xy 344.693061 -401.23925)
			(xy 344.665808 -401.239736) (xy 343.802208 -401.239736) (xy 343.774957 -401.239217) (xy 343.721009 -401.231462)
			(xy 343.668714 -401.216108) (xy 343.619136 -401.193467) (xy 343.573286 -401.164002) (xy 343.532095 -401.128311)
			(xy 343.496403 -401.087121) (xy 343.466937 -401.041271) (xy 343.444295 -400.991694) (xy 343.42894 -400.939399)
			(xy 343.421183 -400.885451) (xy 341.983673 -400.885451) (xy 341.983673 -400.885456) (xy 341.975915 -400.939414)
			(xy 341.960556 -400.991718) (xy 341.937909 -401.041304) (xy 341.908436 -401.087162) (xy 341.872736 -401.128359)
			(xy 341.831537 -401.164055) (xy 341.785676 -401.193525) (xy 341.736088 -401.216167) (xy 341.683783 -401.231521)
			(xy 341.629824 -401.239275) (xy 341.602568 -401.239736) (xy 340.738968 -401.239736) (xy 340.71172 -401.239192)
			(xy 340.65778 -401.231432) (xy 340.605493 -401.216075) (xy 340.555924 -401.193434) (xy 340.510081 -401.163969)
			(xy 340.468897 -401.12828) (xy 340.433212 -401.087094) (xy 340.403751 -401.041248) (xy 340.381114 -400.991677)
			(xy 340.365761 -400.939389) (xy 340.358006 -400.885448) (xy 338.92035 -400.885448) (xy 338.92035 -400.885452)
			(xy 338.912594 -400.939401) (xy 338.897239 -400.991698) (xy 338.874598 -401.041277) (xy 338.845132 -401.087129)
			(xy 338.809441 -401.128321) (xy 338.768251 -401.164016) (xy 338.722401 -401.193485) (xy 338.672824 -401.216129)
			(xy 338.620529 -401.231488) (xy 338.56658 -401.239248) (xy 338.539328 -401.239736) (xy 337.675728 -401.239736)
			(xy 337.648476 -401.239219) (xy 337.594526 -401.231465) (xy 337.542228 -401.216113) (xy 337.492648 -401.193474)
			(xy 337.446795 -401.164009) (xy 337.405602 -401.128318) (xy 337.369908 -401.087127) (xy 337.34044 -401.041276)
			(xy 337.317797 -400.991698) (xy 337.30244 -400.939402) (xy 337.294683 -400.885452) (xy 335.857173 -400.885452)
			(xy 335.857173 -400.885455) (xy 335.849415 -400.939411) (xy 335.834057 -400.991714) (xy 335.811412 -401.041299)
			(xy 335.781941 -401.087156) (xy 335.746243 -401.128352) (xy 335.705046 -401.164048) (xy 335.659188 -401.193518)
			(xy 335.609603 -401.216162) (xy 335.5573 -401.231518) (xy 335.503343 -401.239274) (xy 335.476088 -401.239736)
			(xy 334.612488 -401.239736) (xy 334.585239 -401.239193) (xy 334.531297 -401.231436) (xy 334.479008 -401.216081)
			(xy 334.429436 -401.19344) (xy 334.38359 -401.163976) (xy 334.342404 -401.128287) (xy 334.306717 -401.0871)
			(xy 334.277254 -401.041254) (xy 334.254615 -400.991681) (xy 334.239262 -400.939391) (xy 334.231506 -400.885449)
			(xy 332.79385 -400.885449) (xy 332.79385 -400.885451) (xy 332.786094 -400.939399) (xy 332.770741 -400.991693)
			(xy 332.748101 -401.041271) (xy 332.718637 -401.087122) (xy 332.682948 -401.128314) (xy 332.641761 -401.164009)
			(xy 332.595913 -401.193478) (xy 332.546338 -401.216124) (xy 332.494045 -401.231484) (xy 332.440099 -401.239247)
			(xy 332.412848 -401.239736) (xy 331.549248 -401.239736) (xy 331.521995 -401.23922) (xy 331.468043 -401.231469)
			(xy 331.415743 -401.216118) (xy 331.36616 -401.19348) (xy 331.320305 -401.164016) (xy 331.279109 -401.128325)
			(xy 331.243413 -401.087134) (xy 331.213943 -401.041282) (xy 331.191298 -400.991702) (xy 331.175941 -400.939404)
			(xy 331.168183 -400.885453) (xy 329.73065 -400.885453) (xy 329.722893 -400.939404) (xy 329.707537 -400.991702)
			(xy 329.684895 -401.041282) (xy 329.655428 -401.087136) (xy 329.619734 -401.128329) (xy 329.578542 -401.164023)
			(xy 329.532689 -401.193491) (xy 329.483109 -401.216135) (xy 329.430812 -401.231492) (xy 329.376861 -401.23925)
			(xy 329.349608 -401.239736) (xy 328.486008 -401.239736) (xy 328.458757 -401.239217) (xy 328.404809 -401.231462)
			(xy 328.352514 -401.216108) (xy 328.302936 -401.193467) (xy 328.257086 -401.164002) (xy 328.215895 -401.128311)
			(xy 328.180203 -401.087121) (xy 328.150737 -401.041271) (xy 328.128095 -400.991694) (xy 328.11274 -400.939399)
			(xy 328.104983 -400.885451) (xy 326.667473 -400.885451) (xy 326.667473 -400.885456) (xy 326.659715 -400.939414)
			(xy 326.644356 -400.991718) (xy 326.621709 -401.041304) (xy 326.592236 -401.087162) (xy 326.556536 -401.128359)
			(xy 326.515337 -401.164055) (xy 326.469476 -401.193525) (xy 326.419888 -401.216167) (xy 326.367583 -401.231521)
			(xy 326.313624 -401.239275) (xy 326.286368 -401.239736) (xy 325.422768 -401.239736) (xy 325.39552 -401.239192)
			(xy 325.34158 -401.231432) (xy 325.289293 -401.216075) (xy 325.239724 -401.193434) (xy 325.193881 -401.163969)
			(xy 325.152697 -401.12828) (xy 325.117012 -401.087094) (xy 325.087551 -401.041248) (xy 325.064914 -400.991677)
			(xy 325.049561 -400.939389) (xy 325.041806 -400.885448) (xy 323.60415 -400.885448) (xy 323.60415 -400.885452)
			(xy 323.596394 -400.939401) (xy 323.581039 -400.991698) (xy 323.558398 -401.041277) (xy 323.528932 -401.087129)
			(xy 323.493241 -401.128321) (xy 323.452051 -401.164016) (xy 323.406201 -401.193485) (xy 323.356624 -401.216129)
			(xy 323.304329 -401.231488) (xy 323.25038 -401.239248) (xy 323.223128 -401.239736) (xy 322.359528 -401.239736)
			(xy 322.332276 -401.239219) (xy 322.278326 -401.231465) (xy 322.226028 -401.216113) (xy 322.176448 -401.193474)
			(xy 322.130595 -401.164009) (xy 322.089402 -401.128318) (xy 322.053708 -401.087127) (xy 322.02424 -401.041276)
			(xy 322.001597 -400.991698) (xy 321.98624 -400.939402) (xy 321.978483 -400.885452) (xy 320.540973 -400.885452)
			(xy 320.540973 -400.885455) (xy 320.533215 -400.939411) (xy 320.517857 -400.991714) (xy 320.495212 -401.041299)
			(xy 320.465741 -401.087156) (xy 320.430043 -401.128352) (xy 320.388846 -401.164048) (xy 320.342988 -401.193518)
			(xy 320.293403 -401.216162) (xy 320.2411 -401.231518) (xy 320.187143 -401.239274) (xy 320.159888 -401.239736)
			(xy 319.296288 -401.239736) (xy 319.269039 -401.239193) (xy 319.215097 -401.231436) (xy 319.162808 -401.216081)
			(xy 319.113236 -401.19344) (xy 319.06739 -401.163976) (xy 319.026204 -401.128287) (xy 318.990517 -401.0871)
			(xy 318.961054 -401.041254) (xy 318.938415 -400.991681) (xy 318.923062 -400.939391) (xy 318.915306 -400.885449)
			(xy 317.47765 -400.885449) (xy 317.47765 -400.885451) (xy 317.469894 -400.939399) (xy 317.454541 -400.991693)
			(xy 317.431901 -401.041271) (xy 317.402437 -401.087122) (xy 317.366748 -401.128314) (xy 317.325561 -401.164009)
			(xy 317.279713 -401.193478) (xy 317.230138 -401.216124) (xy 317.177845 -401.231484) (xy 317.123899 -401.239247)
			(xy 317.096648 -401.239736) (xy 316.233048 -401.239736) (xy 316.205795 -401.23922) (xy 316.151843 -401.231469)
			(xy 316.099543 -401.216118) (xy 316.04996 -401.19348) (xy 316.004105 -401.164016) (xy 315.962909 -401.128325)
			(xy 315.927213 -401.087134) (xy 315.897743 -401.041282) (xy 315.875098 -400.991702) (xy 315.859741 -400.939404)
			(xy 315.851983 -400.885453) (xy 314.41445 -400.885453) (xy 314.406693 -400.939404) (xy 314.391337 -400.991702)
			(xy 314.368695 -401.041282) (xy 314.339228 -401.087136) (xy 314.303534 -401.128329) (xy 314.262342 -401.164023)
			(xy 314.216489 -401.193491) (xy 314.166909 -401.216135) (xy 314.114612 -401.231492) (xy 314.060661 -401.23925)
			(xy 314.033408 -401.239736) (xy 313.169808 -401.239736) (xy 313.142557 -401.239217) (xy 313.088609 -401.231462)
			(xy 313.036314 -401.216108) (xy 312.986736 -401.193467) (xy 312.940886 -401.164002) (xy 312.899695 -401.128311)
			(xy 312.864003 -401.087121) (xy 312.834537 -401.041271) (xy 312.811895 -400.991694) (xy 312.79654 -400.939399)
			(xy 312.788783 -400.885451) (xy 311.351273 -400.885451) (xy 311.351273 -400.885456) (xy 311.343515 -400.939414)
			(xy 311.328156 -400.991718) (xy 311.305509 -401.041304) (xy 311.276036 -401.087162) (xy 311.240336 -401.128359)
			(xy 311.199137 -401.164055) (xy 311.153276 -401.193525) (xy 311.103688 -401.216167) (xy 311.051383 -401.231521)
			(xy 310.997424 -401.239275) (xy 310.970168 -401.239736) (xy 310.106568 -401.239736) (xy 310.07932 -401.239192)
			(xy 310.02538 -401.231432) (xy 309.973093 -401.216075) (xy 309.923524 -401.193434) (xy 309.877681 -401.163969)
			(xy 309.836497 -401.12828) (xy 309.800812 -401.087094) (xy 309.771351 -401.041248) (xy 309.748714 -400.991677)
			(xy 309.733361 -400.939389) (xy 309.725606 -400.885448) (xy 308.28795 -400.885448) (xy 308.28795 -400.885452)
			(xy 308.280194 -400.939401) (xy 308.264839 -400.991698) (xy 308.242198 -401.041277) (xy 308.212732 -401.087129)
			(xy 308.177041 -401.128321) (xy 308.135851 -401.164016) (xy 308.090001 -401.193485) (xy 308.040424 -401.216129)
			(xy 307.988129 -401.231488) (xy 307.93418 -401.239248) (xy 307.906928 -401.239736) (xy 307.043328 -401.239736)
			(xy 307.016076 -401.239219) (xy 306.962126 -401.231465) (xy 306.909828 -401.216113) (xy 306.860248 -401.193474)
			(xy 306.814395 -401.164009) (xy 306.773202 -401.128318) (xy 306.737508 -401.087127) (xy 306.70804 -401.041276)
			(xy 306.685397 -400.991698) (xy 306.67004 -400.939402) (xy 306.662283 -400.885452) (xy 305.224773 -400.885452)
			(xy 305.224773 -400.885455) (xy 305.217015 -400.939411) (xy 305.201657 -400.991714) (xy 305.179012 -401.041299)
			(xy 305.149541 -401.087156) (xy 305.113843 -401.128352) (xy 305.072646 -401.164048) (xy 305.026788 -401.193518)
			(xy 304.977203 -401.216162) (xy 304.9249 -401.231518) (xy 304.870943 -401.239274) (xy 304.843688 -401.239736)
			(xy 303.980088 -401.239736) (xy 303.952839 -401.239193) (xy 303.898897 -401.231436) (xy 303.846608 -401.216081)
			(xy 303.797036 -401.19344) (xy 303.75119 -401.163976) (xy 303.710004 -401.128287) (xy 303.674317 -401.0871)
			(xy 303.644854 -401.041254) (xy 303.622215 -400.991681) (xy 303.606862 -400.939391) (xy 303.599106 -400.885449)
			(xy 281.686508 -400.885449) (xy 281.686508 -402.0155) (xy 287.066441 -402.0155) (xy 287.070455 -401.951698)
			(xy 287.082434 -401.888902) (xy 287.102189 -401.828103) (xy 287.129408 -401.77026) (xy 287.163662 -401.716283)
			(xy 287.204411 -401.667026) (xy 287.251013 -401.623264) (xy 287.302731 -401.585688) (xy 287.358752 -401.55489)
			(xy 287.418191 -401.531357) (xy 287.48011 -401.515458) (xy 287.543534 -401.507446) (xy 287.575498 -401.506944)
			(xy 287.575752 -401.506944) (xy 287.607498 -401.507464) (xy 287.670494 -401.515393) (xy 287.732014 -401.531096)
			(xy 287.791102 -401.55433) (xy 287.846842 -401.584733) (xy 287.898367 -401.621834) (xy 287.921954 -401.643088)
			(xy 287.929217 -401.649272) (xy 287.946967 -401.656223) (xy 287.966029 -401.656223) (xy 287.983779 -401.649272)
			(xy 287.991042 -401.643088) (xy 288.014631 -401.621832) (xy 288.06614 -401.5847) (xy 288.121874 -401.554276)
			(xy 288.180965 -401.531035) (xy 288.242492 -401.515338) (xy 288.305495 -401.507431) (xy 288.337244 -401.506944)
			(xy 288.337498 -401.506944) (xy 288.369457 -401.507521) (xy 288.432872 -401.515532) (xy 288.494783 -401.531427)
			(xy 288.554213 -401.554957) (xy 288.610226 -401.58575) (xy 288.661937 -401.623321) (xy 288.708532 -401.667076)
			(xy 288.749276 -401.716326) (xy 288.783525 -401.770295) (xy 288.810741 -401.82813) (xy 288.830493 -401.888921)
			(xy 288.84247 -401.951707) (xy 288.846484 -402.0155) (xy 289.606441 -402.0155) (xy 289.610455 -401.951698)
			(xy 289.622434 -401.888902) (xy 289.642189 -401.828103) (xy 289.669408 -401.77026) (xy 289.703662 -401.716283)
			(xy 289.744411 -401.667026) (xy 289.791013 -401.623264) (xy 289.842731 -401.585688) (xy 289.898752 -401.55489)
			(xy 289.958191 -401.531357) (xy 290.02011 -401.515458) (xy 290.083534 -401.507446) (xy 290.115498 -401.506944)
			(xy 290.115752 -401.506944) (xy 290.147498 -401.507464) (xy 290.210494 -401.515393) (xy 290.272014 -401.531096)
			(xy 290.331102 -401.55433) (xy 290.386842 -401.584733) (xy 290.438367 -401.621834) (xy 290.461954 -401.643088)
			(xy 290.469217 -401.649272) (xy 290.486967 -401.656223) (xy 290.506029 -401.656223) (xy 290.523779 -401.649272)
			(xy 290.531042 -401.643088) (xy 290.554631 -401.621832) (xy 290.60614 -401.5847) (xy 290.661874 -401.554276)
			(xy 290.720965 -401.531035) (xy 290.782492 -401.515338) (xy 290.845495 -401.507431) (xy 290.877244 -401.506944)
			(xy 290.877498 -401.506944) (xy 290.909457 -401.507521) (xy 290.972872 -401.515532) (xy 291.034783 -401.531427)
			(xy 291.094213 -401.554957) (xy 291.150226 -401.58575) (xy 291.201937 -401.623321) (xy 291.248532 -401.667076)
			(xy 291.289276 -401.716326) (xy 291.323525 -401.770295) (xy 291.350741 -401.82813) (xy 291.370493 -401.888921)
			(xy 291.38247 -401.951707) (xy 291.386484 -402.0155) (xy 292.146441 -402.0155) (xy 292.150455 -401.951698)
			(xy 292.162434 -401.888902) (xy 292.182189 -401.828103) (xy 292.209408 -401.77026) (xy 292.243662 -401.716283)
			(xy 292.284411 -401.667026) (xy 292.331013 -401.623264) (xy 292.382731 -401.585688) (xy 292.438752 -401.55489)
			(xy 292.498191 -401.531357) (xy 292.56011 -401.515458) (xy 292.623534 -401.507446) (xy 292.655498 -401.506944)
			(xy 292.655752 -401.506944) (xy 292.687498 -401.507464) (xy 292.750494 -401.515393) (xy 292.812014 -401.531096)
			(xy 292.871102 -401.55433) (xy 292.926842 -401.584733) (xy 292.978367 -401.621834) (xy 293.001954 -401.643088)
			(xy 293.009217 -401.649272) (xy 293.026967 -401.656223) (xy 293.046029 -401.656223) (xy 293.063779 -401.649272)
			(xy 293.071042 -401.643088) (xy 293.094631 -401.621832) (xy 293.14614 -401.5847) (xy 293.201874 -401.554276)
			(xy 293.260965 -401.531035) (xy 293.322492 -401.515338) (xy 293.385495 -401.507431) (xy 293.417244 -401.506944)
			(xy 293.417498 -401.506944) (xy 293.449457 -401.507521) (xy 293.512872 -401.515532) (xy 293.574783 -401.531427)
			(xy 293.634213 -401.554957) (xy 293.690226 -401.58575) (xy 293.741937 -401.623321) (xy 293.788532 -401.667076)
			(xy 293.829276 -401.716326) (xy 293.863525 -401.770295) (xy 293.890741 -401.82813) (xy 293.910493 -401.888921)
			(xy 293.92247 -401.951707) (xy 293.926484 -402.0155) (xy 294.53602 -402.0155) (xy 294.540035 -401.951693)
			(xy 294.552015 -401.888892) (xy 294.571773 -401.828089) (xy 294.598995 -401.770241) (xy 294.633253 -401.716261)
			(xy 294.674007 -401.667001) (xy 294.720613 -401.623237) (xy 294.772338 -401.58566) (xy 294.828364 -401.554862)
			(xy 294.887809 -401.531329) (xy 294.949734 -401.515433) (xy 295.013163 -401.507423) (xy 295.04513 -401.506944)
			(xy 295.045384 -401.506944) (xy 295.077131 -401.507444) (xy 295.140127 -401.515377) (xy 295.201647 -401.531084)
			(xy 295.260736 -401.554322) (xy 295.316476 -401.584728) (xy 295.368 -401.621832) (xy 295.391586 -401.643088)
			(xy 295.398849 -401.649272) (xy 295.416599 -401.656223) (xy 295.435661 -401.656223) (xy 295.453411 -401.649272)
			(xy 295.460674 -401.643088) (xy 295.48425 -401.621817) (xy 295.535761 -401.584686) (xy 295.591498 -401.554265)
			(xy 295.650592 -401.531026) (xy 295.712121 -401.515332) (xy 295.775126 -401.507429) (xy 295.806876 -401.506944)
			(xy 295.80713 -401.506944) (xy 295.839087 -401.507544) (xy 295.902496 -401.515558) (xy 295.964401 -401.531455)
			(xy 296.023825 -401.554986) (xy 296.079832 -401.585779) (xy 296.131538 -401.623348) (xy 296.178128 -401.667102)
			(xy 296.218866 -401.716349) (xy 296.253112 -401.770314) (xy 296.280324 -401.828145) (xy 296.300074 -401.888931)
			(xy 296.312049 -401.951712) (xy 296.316063 -402.0155) (xy 297.07602 -402.0155) (xy 297.080035 -401.951693)
			(xy 297.092015 -401.888892) (xy 297.111773 -401.828089) (xy 297.138995 -401.770241) (xy 297.173253 -401.716261)
			(xy 297.214007 -401.667001) (xy 297.260613 -401.623237) (xy 297.312338 -401.58566) (xy 297.368364 -401.554862)
			(xy 297.427809 -401.531329) (xy 297.489734 -401.515433) (xy 297.553163 -401.507423) (xy 297.58513 -401.506944)
			(xy 297.585384 -401.506944) (xy 297.617131 -401.507444) (xy 297.680127 -401.515377) (xy 297.741647 -401.531084)
			(xy 297.800736 -401.554322) (xy 297.856476 -401.584728) (xy 297.908 -401.621832) (xy 297.931586 -401.643088)
			(xy 297.938849 -401.649272) (xy 297.956599 -401.656223) (xy 297.975661 -401.656223) (xy 297.993411 -401.649272)
			(xy 298.000674 -401.643088) (xy 298.02425 -401.621817) (xy 298.075761 -401.584686) (xy 298.131498 -401.554265)
			(xy 298.190592 -401.531026) (xy 298.252121 -401.515332) (xy 298.315126 -401.507429) (xy 298.346876 -401.506944)
			(xy 298.34713 -401.506944) (xy 298.379087 -401.507544) (xy 298.442496 -401.515558) (xy 298.504401 -401.531455)
			(xy 298.563825 -401.554986) (xy 298.619832 -401.585779) (xy 298.671538 -401.623348) (xy 298.718128 -401.667102)
			(xy 298.758866 -401.716349) (xy 298.793112 -401.770314) (xy 298.820324 -401.828145) (xy 298.840074 -401.888931)
			(xy 298.852049 -401.951712) (xy 298.856063 -402.0155) (xy 298.852049 -402.079288) (xy 298.840074 -402.142069)
			(xy 298.820324 -402.202855) (xy 298.793112 -402.260686) (xy 298.758866 -402.314651) (xy 298.718128 -402.363898)
			(xy 298.671538 -402.407652) (xy 298.619832 -402.445221) (xy 298.563825 -402.476014) (xy 298.504401 -402.499545)
			(xy 298.442496 -402.515442) (xy 298.379087 -402.523456) (xy 298.34713 -402.52396) (xy 298.346876 -402.52396)
			(xy 298.315131 -402.523422) (xy 298.252136 -402.515497) (xy 298.190616 -402.499797) (xy 298.131527 -402.476566)
			(xy 298.075787 -402.446166) (xy 298.024261 -402.409069) (xy 298.000674 -402.387816) (xy 297.993411 -402.381632)
			(xy 297.975661 -402.374681) (xy 297.956599 -402.374681) (xy 297.938849 -402.381632) (xy 297.931586 -402.387816)
			(xy 297.908028 -402.409107) (xy 297.856512 -402.446235) (xy 297.800771 -402.476654) (xy 297.741674 -402.499889)
			(xy 297.680142 -402.515579) (xy 297.617135 -402.523478) (xy 297.585384 -402.52396) (xy 297.58513 -402.52396)
			(xy 297.553163 -402.523577) (xy 297.489734 -402.515567) (xy 297.427809 -402.499671) (xy 297.368364 -402.476138)
			(xy 297.312338 -402.44534) (xy 297.260613 -402.407763) (xy 297.214007 -402.363999) (xy 297.173253 -402.314739)
			(xy 297.138995 -402.260759) (xy 297.111773 -402.202911) (xy 297.092015 -402.142108) (xy 297.080035 -402.079307)
			(xy 297.07602 -402.0155) (xy 296.316063 -402.0155) (xy 296.312049 -402.079288) (xy 296.300074 -402.142069)
			(xy 296.280324 -402.202855) (xy 296.253112 -402.260686) (xy 296.218866 -402.314651) (xy 296.178128 -402.363898)
			(xy 296.131538 -402.407652) (xy 296.079832 -402.445221) (xy 296.023825 -402.476014) (xy 295.964401 -402.499545)
			(xy 295.902496 -402.515442) (xy 295.839087 -402.523456) (xy 295.80713 -402.52396) (xy 295.806876 -402.52396)
			(xy 295.775131 -402.523422) (xy 295.712136 -402.515497) (xy 295.650616 -402.499797) (xy 295.591527 -402.476566)
			(xy 295.535787 -402.446166) (xy 295.484261 -402.409069) (xy 295.460674 -402.387816) (xy 295.453411 -402.381632)
			(xy 295.435661 -402.374681) (xy 295.416599 -402.374681) (xy 295.398849 -402.381632) (xy 295.391586 -402.387816)
			(xy 295.368028 -402.409107) (xy 295.316512 -402.446235) (xy 295.260771 -402.476654) (xy 295.201674 -402.499889)
			(xy 295.140142 -402.515579) (xy 295.077135 -402.523478) (xy 295.045384 -402.52396) (xy 295.04513 -402.52396)
			(xy 295.013163 -402.523577) (xy 294.949734 -402.515567) (xy 294.887809 -402.499671) (xy 294.828364 -402.476138)
			(xy 294.772338 -402.44534) (xy 294.720613 -402.407763) (xy 294.674007 -402.363999) (xy 294.633253 -402.314739)
			(xy 294.598995 -402.260759) (xy 294.571773 -402.202911) (xy 294.552015 -402.142108) (xy 294.540035 -402.079307)
			(xy 294.53602 -402.0155) (xy 293.926484 -402.0155) (xy 293.92247 -402.079293) (xy 293.910493 -402.142079)
			(xy 293.890741 -402.20287) (xy 293.863525 -402.260705) (xy 293.829276 -402.314674) (xy 293.788532 -402.363924)
			(xy 293.741937 -402.407679) (xy 293.690226 -402.44525) (xy 293.634213 -402.476043) (xy 293.574783 -402.499573)
			(xy 293.512872 -402.515468) (xy 293.449457 -402.523479) (xy 293.417498 -402.52396) (xy 293.417244 -402.52396)
			(xy 293.385498 -402.523442) (xy 293.322502 -402.515512) (xy 293.260982 -402.499809) (xy 293.201894 -402.476575)
			(xy 293.146154 -402.446171) (xy 293.094629 -402.40907) (xy 293.071042 -402.387816) (xy 293.063779 -402.381632)
			(xy 293.046029 -402.374681) (xy 293.026967 -402.374681) (xy 293.009217 -402.381632) (xy 293.001954 -402.387816)
			(xy 292.978367 -402.409074) (xy 292.926858 -402.446206) (xy 292.871123 -402.47663) (xy 292.812032 -402.499871)
			(xy 292.750504 -402.515567) (xy 292.687501 -402.523474) (xy 292.655752 -402.52396) (xy 292.655498 -402.52396)
			(xy 292.623534 -402.523554) (xy 292.56011 -402.515542) (xy 292.498191 -402.499643) (xy 292.438752 -402.47611)
			(xy 292.382731 -402.445312) (xy 292.331013 -402.407736) (xy 292.284411 -402.363974) (xy 292.243662 -402.314717)
			(xy 292.209408 -402.26074) (xy 292.182189 -402.202897) (xy 292.162434 -402.142098) (xy 292.150455 -402.079302)
			(xy 292.146441 -402.0155) (xy 291.386484 -402.0155) (xy 291.38247 -402.079293) (xy 291.370493 -402.142079)
			(xy 291.350741 -402.20287) (xy 291.323525 -402.260705) (xy 291.289276 -402.314674) (xy 291.248532 -402.363924)
			(xy 291.201937 -402.407679) (xy 291.150226 -402.44525) (xy 291.094213 -402.476043) (xy 291.034783 -402.499573)
			(xy 290.972872 -402.515468) (xy 290.909457 -402.523479) (xy 290.877498 -402.52396) (xy 290.877244 -402.52396)
			(xy 290.845498 -402.523442) (xy 290.782502 -402.515512) (xy 290.720982 -402.499809) (xy 290.661894 -402.476575)
			(xy 290.606154 -402.446171) (xy 290.554629 -402.40907) (xy 290.531042 -402.387816) (xy 290.523779 -402.381632)
			(xy 290.506029 -402.374681) (xy 290.486967 -402.374681) (xy 290.469217 -402.381632) (xy 290.461954 -402.387816)
			(xy 290.438367 -402.409074) (xy 290.386858 -402.446206) (xy 290.331123 -402.47663) (xy 290.272032 -402.499871)
			(xy 290.210504 -402.515567) (xy 290.147501 -402.523474) (xy 290.115752 -402.52396) (xy 290.115498 -402.52396)
			(xy 290.083534 -402.523554) (xy 290.02011 -402.515542) (xy 289.958191 -402.499643) (xy 289.898752 -402.47611)
			(xy 289.842731 -402.445312) (xy 289.791013 -402.407736) (xy 289.744411 -402.363974) (xy 289.703662 -402.314717)
			(xy 289.669408 -402.26074) (xy 289.642189 -402.202897) (xy 289.622434 -402.142098) (xy 289.610455 -402.079302)
			(xy 289.606441 -402.0155) (xy 288.846484 -402.0155) (xy 288.84247 -402.079293) (xy 288.830493 -402.142079)
			(xy 288.810741 -402.20287) (xy 288.783525 -402.260705) (xy 288.749276 -402.314674) (xy 288.708532 -402.363924)
			(xy 288.661937 -402.407679) (xy 288.610226 -402.44525) (xy 288.554213 -402.476043) (xy 288.494783 -402.499573)
			(xy 288.432872 -402.515468) (xy 288.369457 -402.523479) (xy 288.337498 -402.52396) (xy 288.337244 -402.52396)
			(xy 288.305498 -402.523442) (xy 288.242502 -402.515512) (xy 288.180982 -402.499809) (xy 288.121894 -402.476575)
			(xy 288.066154 -402.446171) (xy 288.014629 -402.40907) (xy 287.991042 -402.387816) (xy 287.983779 -402.381632)
			(xy 287.966029 -402.374681) (xy 287.946967 -402.374681) (xy 287.929217 -402.381632) (xy 287.921954 -402.387816)
			(xy 287.898367 -402.409074) (xy 287.846858 -402.446206) (xy 287.791123 -402.47663) (xy 287.732032 -402.499871)
			(xy 287.670504 -402.515567) (xy 287.607501 -402.523474) (xy 287.575752 -402.52396) (xy 287.575498 -402.52396)
			(xy 287.543534 -402.523554) (xy 287.48011 -402.515542) (xy 287.418191 -402.499643) (xy 287.358752 -402.47611)
			(xy 287.302731 -402.445312) (xy 287.251013 -402.407736) (xy 287.204411 -402.363974) (xy 287.163662 -402.314717)
			(xy 287.129408 -402.26074) (xy 287.102189 -402.202897) (xy 287.082434 -402.142098) (xy 287.070455 -402.079302)
			(xy 287.066441 -402.0155) (xy 281.686508 -402.0155) (xy 281.686508 -404.0475) (xy 287.066441 -404.0475)
			(xy 287.070455 -403.983698) (xy 287.082434 -403.920902) (xy 287.102189 -403.860103) (xy 287.129408 -403.80226)
			(xy 287.163662 -403.748283) (xy 287.204411 -403.699026) (xy 287.251013 -403.655264) (xy 287.302731 -403.617688)
			(xy 287.358752 -403.58689) (xy 287.418191 -403.563357) (xy 287.48011 -403.547458) (xy 287.543534 -403.539446)
			(xy 287.575498 -403.538944) (xy 287.575752 -403.538944) (xy 287.607498 -403.539464) (xy 287.670494 -403.547393)
			(xy 287.732014 -403.563096) (xy 287.791102 -403.58633) (xy 287.846842 -403.616733) (xy 287.898367 -403.653834)
			(xy 287.921954 -403.675088) (xy 287.929217 -403.681272) (xy 287.946967 -403.688223) (xy 287.966029 -403.688223)
			(xy 287.983779 -403.681272) (xy 287.991042 -403.675088) (xy 288.014631 -403.653832) (xy 288.06614 -403.6167)
			(xy 288.121874 -403.586276) (xy 288.180965 -403.563035) (xy 288.242492 -403.547338) (xy 288.305495 -403.539431)
			(xy 288.337244 -403.538944) (xy 288.337498 -403.538944) (xy 288.369457 -403.539521) (xy 288.432872 -403.547532)
			(xy 288.494783 -403.563427) (xy 288.554213 -403.586957) (xy 288.610226 -403.61775) (xy 288.661937 -403.655321)
			(xy 288.708532 -403.699076) (xy 288.749276 -403.748326) (xy 288.783525 -403.802295) (xy 288.810741 -403.86013)
			(xy 288.830493 -403.920921) (xy 288.84247 -403.983707) (xy 288.846484 -404.0475) (xy 289.606441 -404.0475)
			(xy 289.610455 -403.983698) (xy 289.622434 -403.920902) (xy 289.642189 -403.860103) (xy 289.669408 -403.80226)
			(xy 289.703662 -403.748283) (xy 289.744411 -403.699026) (xy 289.791013 -403.655264) (xy 289.842731 -403.617688)
			(xy 289.898752 -403.58689) (xy 289.958191 -403.563357) (xy 290.02011 -403.547458) (xy 290.083534 -403.539446)
			(xy 290.115498 -403.538944) (xy 290.115752 -403.538944) (xy 290.147498 -403.539464) (xy 290.210494 -403.547393)
			(xy 290.272014 -403.563096) (xy 290.331102 -403.58633) (xy 290.386842 -403.616733) (xy 290.438367 -403.653834)
			(xy 290.461954 -403.675088) (xy 290.469217 -403.681272) (xy 290.486967 -403.688223) (xy 290.506029 -403.688223)
			(xy 290.523779 -403.681272) (xy 290.531042 -403.675088) (xy 290.554631 -403.653832) (xy 290.60614 -403.6167)
			(xy 290.661874 -403.586276) (xy 290.720965 -403.563035) (xy 290.782492 -403.547338) (xy 290.845495 -403.539431)
			(xy 290.877244 -403.538944) (xy 290.877498 -403.538944) (xy 290.909457 -403.539521) (xy 290.972872 -403.547532)
			(xy 291.034783 -403.563427) (xy 291.094213 -403.586957) (xy 291.150226 -403.61775) (xy 291.201937 -403.655321)
			(xy 291.248532 -403.699076) (xy 291.289276 -403.748326) (xy 291.323525 -403.802295) (xy 291.350741 -403.86013)
			(xy 291.370493 -403.920921) (xy 291.38247 -403.983707) (xy 291.386484 -404.0475) (xy 292.146441 -404.0475)
			(xy 292.150455 -403.983698) (xy 292.162434 -403.920902) (xy 292.182189 -403.860103) (xy 292.209408 -403.80226)
			(xy 292.243662 -403.748283) (xy 292.284411 -403.699026) (xy 292.331013 -403.655264) (xy 292.382731 -403.617688)
			(xy 292.438752 -403.58689) (xy 292.498191 -403.563357) (xy 292.56011 -403.547458) (xy 292.623534 -403.539446)
			(xy 292.655498 -403.538944) (xy 292.655752 -403.538944) (xy 292.687498 -403.539464) (xy 292.750494 -403.547393)
			(xy 292.812014 -403.563096) (xy 292.871102 -403.58633) (xy 292.926842 -403.616733) (xy 292.978367 -403.653834)
			(xy 293.001954 -403.675088) (xy 293.009217 -403.681272) (xy 293.026967 -403.688223) (xy 293.046029 -403.688223)
			(xy 293.063779 -403.681272) (xy 293.071042 -403.675088) (xy 293.094631 -403.653832) (xy 293.14614 -403.6167)
			(xy 293.201874 -403.586276) (xy 293.260965 -403.563035) (xy 293.322492 -403.547338) (xy 293.385495 -403.539431)
			(xy 293.417244 -403.538944) (xy 293.417498 -403.538944) (xy 293.449457 -403.539521) (xy 293.512872 -403.547532)
			(xy 293.574783 -403.563427) (xy 293.634213 -403.586957) (xy 293.690226 -403.61775) (xy 293.741937 -403.655321)
			(xy 293.788532 -403.699076) (xy 293.829276 -403.748326) (xy 293.863525 -403.802295) (xy 293.890741 -403.86013)
			(xy 293.910493 -403.920921) (xy 293.92247 -403.983707) (xy 293.926484 -404.0475) (xy 294.53602 -404.0475)
			(xy 294.540035 -403.983693) (xy 294.552015 -403.920892) (xy 294.571773 -403.860089) (xy 294.598995 -403.802241)
			(xy 294.633253 -403.748261) (xy 294.674007 -403.699001) (xy 294.720613 -403.655237) (xy 294.772338 -403.61766)
			(xy 294.828364 -403.586862) (xy 294.887809 -403.563329) (xy 294.949734 -403.547433) (xy 295.013163 -403.539423)
			(xy 295.04513 -403.538944) (xy 295.045384 -403.538944) (xy 295.077131 -403.539444) (xy 295.140127 -403.547377)
			(xy 295.201647 -403.563084) (xy 295.260736 -403.586322) (xy 295.316476 -403.616728) (xy 295.368 -403.653832)
			(xy 295.391586 -403.675088) (xy 295.398849 -403.681272) (xy 295.416599 -403.688223) (xy 295.435661 -403.688223)
			(xy 295.453411 -403.681272) (xy 295.460674 -403.675088) (xy 295.48425 -403.653817) (xy 295.535761 -403.616686)
			(xy 295.591498 -403.586265) (xy 295.650592 -403.563026) (xy 295.712121 -403.547332) (xy 295.775126 -403.539429)
			(xy 295.806876 -403.538944) (xy 295.80713 -403.538944) (xy 295.839087 -403.539544) (xy 295.902496 -403.547558)
			(xy 295.964401 -403.563455) (xy 296.023825 -403.586986) (xy 296.079832 -403.617779) (xy 296.131538 -403.655348)
			(xy 296.178128 -403.699102) (xy 296.218866 -403.748349) (xy 296.253112 -403.802314) (xy 296.280324 -403.860145)
			(xy 296.300074 -403.920931) (xy 296.312049 -403.983712) (xy 296.316063 -404.0475) (xy 297.07602 -404.0475)
			(xy 297.080035 -403.983693) (xy 297.092015 -403.920892) (xy 297.111773 -403.860089) (xy 297.138995 -403.802241)
			(xy 297.173253 -403.748261) (xy 297.214007 -403.699001) (xy 297.260613 -403.655237) (xy 297.312338 -403.61766)
			(xy 297.368364 -403.586862) (xy 297.427809 -403.563329) (xy 297.489734 -403.547433) (xy 297.553163 -403.539423)
			(xy 297.58513 -403.538944) (xy 297.585384 -403.538944) (xy 297.617131 -403.539444) (xy 297.680127 -403.547377)
			(xy 297.741647 -403.563084) (xy 297.800736 -403.586322) (xy 297.856476 -403.616728) (xy 297.908 -403.653832)
			(xy 297.931586 -403.675088) (xy 297.938849 -403.681272) (xy 297.956599 -403.688223) (xy 297.975661 -403.688223)
			(xy 297.993411 -403.681272) (xy 298.000674 -403.675088) (xy 298.02425 -403.653817) (xy 298.075761 -403.616686)
			(xy 298.131498 -403.586265) (xy 298.190592 -403.563026) (xy 298.252121 -403.547332) (xy 298.315126 -403.539429)
			(xy 298.346876 -403.538944) (xy 298.34713 -403.538944) (xy 298.379087 -403.539544) (xy 298.442496 -403.547558)
			(xy 298.504401 -403.563455) (xy 298.563825 -403.586986) (xy 298.619832 -403.617779) (xy 298.671538 -403.655348)
			(xy 298.718128 -403.699102) (xy 298.758866 -403.748349) (xy 298.793112 -403.802314) (xy 298.820324 -403.860145)
			(xy 298.836897 -403.911152) (xy 303.599054 -403.911152) (xy 303.599054 -403.856648) (xy 303.60681 -403.802698)
			(xy 303.622166 -403.7504) (xy 303.644808 -403.700821) (xy 303.674275 -403.654968) (xy 303.709967 -403.613776)
			(xy 303.751159 -403.578082) (xy 303.79701 -403.548613) (xy 303.846589 -403.52597) (xy 303.898886 -403.510613)
			(xy 303.952836 -403.502855) (xy 303.980088 -403.502368) (xy 304.843688 -403.502368) (xy 304.87094 -403.502878)
			(xy 304.924889 -403.510634) (xy 304.977185 -403.525988) (xy 305.026763 -403.548628) (xy 305.072615 -403.578094)
			(xy 305.113806 -403.613785) (xy 305.149499 -403.654976) (xy 305.178966 -403.700826) (xy 305.201608 -403.750404)
			(xy 305.216964 -403.8027) (xy 305.224721 -403.856648) (xy 305.224721 -403.911152) (xy 305.22472 -403.911156)
			(xy 306.662231 -403.911156) (xy 306.662231 -403.856644) (xy 306.669989 -403.802687) (xy 306.685348 -403.750384)
			(xy 306.707994 -403.700799) (xy 306.737466 -403.654941) (xy 306.773165 -403.613745) (xy 306.814364 -403.578049)
			(xy 306.860223 -403.54858) (xy 306.90981 -403.525938) (xy 306.962115 -403.510583) (xy 307.016072 -403.502829)
			(xy 307.043328 -403.502368) (xy 307.906928 -403.502368) (xy 307.934176 -403.502904) (xy 307.988117 -403.510663)
			(xy 308.040405 -403.52602) (xy 308.089976 -403.548661) (xy 308.13582 -403.578126) (xy 308.177004 -403.613816)
			(xy 308.21269 -403.655002) (xy 308.242152 -403.700849) (xy 308.26479 -403.750421) (xy 308.280143 -403.80271)
			(xy 308.287898 -403.856652) (xy 308.287898 -403.911148) (xy 308.287897 -403.911152) (xy 309.725554 -403.911152)
			(xy 309.725554 -403.856648) (xy 309.73331 -403.8027) (xy 309.748664 -403.750405) (xy 309.771305 -403.700826)
			(xy 309.80077 -403.654975) (xy 309.83646 -403.613783) (xy 309.877649 -403.578089) (xy 309.923498 -403.54862)
			(xy 309.973075 -403.525976) (xy 310.025369 -403.510617) (xy 310.079317 -403.502856) (xy 310.106568 -403.502368)
			(xy 310.970168 -403.502368) (xy 310.997421 -403.502877) (xy 311.051372 -403.51063) (xy 311.10367 -403.525982)
			(xy 311.153251 -403.548621) (xy 311.199105 -403.578087) (xy 311.240299 -403.613778) (xy 311.275994 -403.654969)
			(xy 311.305463 -403.700821) (xy 311.328107 -403.7504) (xy 311.343463 -403.802697) (xy 311.351221 -403.856647)
			(xy 311.351221 -403.911153) (xy 311.351221 -403.911155) (xy 312.788731 -403.911155) (xy 312.788731 -403.856645)
			(xy 312.796489 -403.80269) (xy 312.811846 -403.750388) (xy 312.834491 -403.700804) (xy 312.863961 -403.654948)
			(xy 312.899658 -403.613752) (xy 312.940854 -403.578056) (xy 312.986711 -403.548587) (xy 313.036296 -403.525943)
			(xy 313.088598 -403.510587) (xy 313.142553 -403.50283) (xy 313.169808 -403.502368) (xy 314.033408 -403.502368)
			(xy 314.060657 -403.502903) (xy 314.114601 -403.51066) (xy 314.166891 -403.526015) (xy 314.216464 -403.548655)
			(xy 314.26231 -403.578119) (xy 314.303497 -403.613809) (xy 314.339186 -403.654996) (xy 314.368649 -403.700843)
			(xy 314.391288 -403.750417) (xy 314.406642 -403.802707) (xy 314.414398 -403.856651) (xy 314.414398 -403.911149)
			(xy 314.414397 -403.911157) (xy 315.851931 -403.911157) (xy 315.851931 -403.856643) (xy 315.85969 -403.802685)
			(xy 315.875049 -403.75038) (xy 315.897697 -403.700793) (xy 315.927171 -403.654935) (xy 315.962872 -403.613738)
			(xy 316.004073 -403.578042) (xy 316.049935 -403.548574) (xy 316.099525 -403.525932) (xy 316.151832 -403.51058)
			(xy 316.205791 -403.502828) (xy 316.233048 -403.502368) (xy 317.096648 -403.502368) (xy 317.123895 -403.502905)
			(xy 317.177834 -403.510667) (xy 317.23012 -403.526025) (xy 317.279688 -403.548668) (xy 317.325529 -403.578133)
			(xy 317.366711 -403.613823) (xy 317.402395 -403.655009) (xy 317.431855 -403.700854) (xy 317.454491 -403.750425)
			(xy 317.469843 -403.802713) (xy 317.477598 -403.856653) (xy 317.477598 -403.911147) (xy 317.477597 -403.911152)
			(xy 318.915254 -403.911152) (xy 318.915254 -403.856648) (xy 318.92301 -403.802698) (xy 318.938366 -403.7504)
			(xy 318.961008 -403.700821) (xy 318.990475 -403.654968) (xy 319.026167 -403.613776) (xy 319.067359 -403.578082)
			(xy 319.11321 -403.548613) (xy 319.162789 -403.52597) (xy 319.215086 -403.510613) (xy 319.269036 -403.502855)
			(xy 319.296288 -403.502368) (xy 320.159888 -403.502368) (xy 320.18714 -403.502878) (xy 320.241089 -403.510634)
			(xy 320.293385 -403.525988) (xy 320.342963 -403.548628) (xy 320.388815 -403.578094) (xy 320.430006 -403.613785)
			(xy 320.465699 -403.654976) (xy 320.495166 -403.700826) (xy 320.517808 -403.750404) (xy 320.533164 -403.8027)
			(xy 320.540921 -403.856648) (xy 320.540921 -403.911152) (xy 320.54092 -403.911156) (xy 321.978431 -403.911156)
			(xy 321.978431 -403.856644) (xy 321.986189 -403.802687) (xy 322.001548 -403.750384) (xy 322.024194 -403.700799)
			(xy 322.053666 -403.654941) (xy 322.089365 -403.613745) (xy 322.130564 -403.578049) (xy 322.176423 -403.54858)
			(xy 322.22601 -403.525938) (xy 322.278315 -403.510583) (xy 322.332272 -403.502829) (xy 322.359528 -403.502368)
			(xy 323.223128 -403.502368) (xy 323.250376 -403.502904) (xy 323.304317 -403.510663) (xy 323.356605 -403.52602)
			(xy 323.406176 -403.548661) (xy 323.45202 -403.578126) (xy 323.493204 -403.613816) (xy 323.52889 -403.655002)
			(xy 323.558352 -403.700849) (xy 323.58099 -403.750421) (xy 323.596343 -403.80271) (xy 323.604098 -403.856652)
			(xy 323.604098 -403.911148) (xy 323.604097 -403.911152) (xy 325.041754 -403.911152) (xy 325.041754 -403.856648)
			(xy 325.04951 -403.8027) (xy 325.064864 -403.750405) (xy 325.087505 -403.700826) (xy 325.11697 -403.654975)
			(xy 325.15266 -403.613783) (xy 325.193849 -403.578089) (xy 325.239698 -403.54862) (xy 325.289275 -403.525976)
			(xy 325.341569 -403.510617) (xy 325.395517 -403.502856) (xy 325.422768 -403.502368) (xy 326.286368 -403.502368)
			(xy 326.313621 -403.502877) (xy 326.367572 -403.51063) (xy 326.41987 -403.525982) (xy 326.469451 -403.548621)
			(xy 326.515305 -403.578087) (xy 326.556499 -403.613778) (xy 326.592194 -403.654969) (xy 326.621663 -403.700821)
			(xy 326.644307 -403.7504) (xy 326.659663 -403.802697) (xy 326.667421 -403.856647) (xy 326.667421 -403.911153)
			(xy 326.667421 -403.911155) (xy 328.104931 -403.911155) (xy 328.104931 -403.856645) (xy 328.112689 -403.80269)
			(xy 328.128046 -403.750388) (xy 328.150691 -403.700804) (xy 328.180161 -403.654948) (xy 328.215858 -403.613752)
			(xy 328.257054 -403.578056) (xy 328.302911 -403.548587) (xy 328.352496 -403.525943) (xy 328.404798 -403.510587)
			(xy 328.458753 -403.50283) (xy 328.486008 -403.502368) (xy 329.349608 -403.502368) (xy 329.376857 -403.502903)
			(xy 329.430801 -403.51066) (xy 329.483091 -403.526015) (xy 329.532664 -403.548655) (xy 329.57851 -403.578119)
			(xy 329.619697 -403.613809) (xy 329.655386 -403.654996) (xy 329.684849 -403.700843) (xy 329.707488 -403.750417)
			(xy 329.722842 -403.802707) (xy 329.730598 -403.856651) (xy 329.730598 -403.911149) (xy 329.730597 -403.911157)
			(xy 331.168131 -403.911157) (xy 331.168131 -403.856643) (xy 331.17589 -403.802685) (xy 331.191249 -403.75038)
			(xy 331.213897 -403.700793) (xy 331.243371 -403.654935) (xy 331.279072 -403.613738) (xy 331.320273 -403.578042)
			(xy 331.366135 -403.548574) (xy 331.415725 -403.525932) (xy 331.468032 -403.51058) (xy 331.521991 -403.502828)
			(xy 331.549248 -403.502368) (xy 332.412848 -403.502368) (xy 332.440095 -403.502905) (xy 332.494034 -403.510667)
			(xy 332.54632 -403.526025) (xy 332.595888 -403.548668) (xy 332.641729 -403.578133) (xy 332.682911 -403.613823)
			(xy 332.718595 -403.655009) (xy 332.748055 -403.700854) (xy 332.770691 -403.750425) (xy 332.786043 -403.802713)
			(xy 332.793798 -403.856653) (xy 332.793798 -403.911147) (xy 332.793797 -403.911152) (xy 334.231454 -403.911152)
			(xy 334.231454 -403.856648) (xy 334.23921 -403.802698) (xy 334.254566 -403.7504) (xy 334.277208 -403.700821)
			(xy 334.306675 -403.654968) (xy 334.342367 -403.613776) (xy 334.383559 -403.578082) (xy 334.42941 -403.548613)
			(xy 334.478989 -403.52597) (xy 334.531286 -403.510613) (xy 334.585236 -403.502855) (xy 334.612488 -403.502368)
			(xy 335.476088 -403.502368) (xy 335.50334 -403.502878) (xy 335.557289 -403.510634) (xy 335.609585 -403.525988)
			(xy 335.659163 -403.548628) (xy 335.705015 -403.578094) (xy 335.746206 -403.613785) (xy 335.781899 -403.654976)
			(xy 335.811366 -403.700826) (xy 335.834008 -403.750404) (xy 335.849364 -403.8027) (xy 335.857121 -403.856648)
			(xy 335.857121 -403.911152) (xy 335.85712 -403.911156) (xy 337.294631 -403.911156) (xy 337.294631 -403.856644)
			(xy 337.302389 -403.802687) (xy 337.317748 -403.750384) (xy 337.340394 -403.700799) (xy 337.369866 -403.654941)
			(xy 337.405565 -403.613745) (xy 337.446764 -403.578049) (xy 337.492623 -403.54858) (xy 337.54221 -403.525938)
			(xy 337.594515 -403.510583) (xy 337.648472 -403.502829) (xy 337.675728 -403.502368) (xy 338.539328 -403.502368)
			(xy 338.566576 -403.502904) (xy 338.620517 -403.510663) (xy 338.672805 -403.52602) (xy 338.722376 -403.548661)
			(xy 338.76822 -403.578126) (xy 338.809404 -403.613816) (xy 338.84509 -403.655002) (xy 338.874552 -403.700849)
			(xy 338.89719 -403.750421) (xy 338.912543 -403.80271) (xy 338.920298 -403.856652) (xy 338.920298 -403.911148)
			(xy 338.920297 -403.911152) (xy 340.357954 -403.911152) (xy 340.357954 -403.856648) (xy 340.36571 -403.8027)
			(xy 340.381064 -403.750405) (xy 340.403705 -403.700826) (xy 340.43317 -403.654975) (xy 340.46886 -403.613783)
			(xy 340.510049 -403.578089) (xy 340.555898 -403.54862) (xy 340.605475 -403.525976) (xy 340.657769 -403.510617)
			(xy 340.711717 -403.502856) (xy 340.738968 -403.502368) (xy 341.602568 -403.502368) (xy 341.629821 -403.502877)
			(xy 341.683772 -403.51063) (xy 341.73607 -403.525982) (xy 341.785651 -403.548621) (xy 341.831505 -403.578087)
			(xy 341.872699 -403.613778) (xy 341.908394 -403.654969) (xy 341.937863 -403.700821) (xy 341.960507 -403.7504)
			(xy 341.975863 -403.802697) (xy 341.983621 -403.856647) (xy 341.983621 -403.911153) (xy 341.983621 -403.911155)
			(xy 343.421131 -403.911155) (xy 343.421131 -403.856645) (xy 343.428889 -403.80269) (xy 343.444246 -403.750388)
			(xy 343.466891 -403.700804) (xy 343.496361 -403.654948) (xy 343.532058 -403.613752) (xy 343.573254 -403.578056)
			(xy 343.619111 -403.548587) (xy 343.668696 -403.525943) (xy 343.720998 -403.510587) (xy 343.774953 -403.50283)
			(xy 343.802208 -403.502368) (xy 344.665808 -403.502368) (xy 344.693057 -403.502903) (xy 344.747001 -403.51066)
			(xy 344.799291 -403.526015) (xy 344.848864 -403.548655) (xy 344.89471 -403.578119) (xy 344.935897 -403.613809)
			(xy 344.971586 -403.654996) (xy 345.001049 -403.700843) (xy 345.023688 -403.750417) (xy 345.039042 -403.802707)
			(xy 345.046798 -403.856651) (xy 345.046798 -403.911149) (xy 345.046797 -403.911157) (xy 346.484331 -403.911157)
			(xy 346.484331 -403.856643) (xy 346.49209 -403.802685) (xy 346.507449 -403.75038) (xy 346.530097 -403.700793)
			(xy 346.559571 -403.654935) (xy 346.595272 -403.613738) (xy 346.636473 -403.578042) (xy 346.682335 -403.548574)
			(xy 346.731925 -403.525932) (xy 346.784232 -403.51058) (xy 346.838191 -403.502828) (xy 346.865448 -403.502368)
			(xy 347.729048 -403.502368) (xy 347.756295 -403.502905) (xy 347.810234 -403.510667) (xy 347.86252 -403.526025)
			(xy 347.912088 -403.548668) (xy 347.957929 -403.578133) (xy 347.999111 -403.613823) (xy 348.034795 -403.655009)
			(xy 348.064255 -403.700854) (xy 348.086891 -403.750425) (xy 348.102243 -403.802713) (xy 348.109998 -403.856653)
			(xy 348.109998 -403.911147) (xy 348.109997 -403.911152) (xy 349.547654 -403.911152) (xy 349.547654 -403.856648)
			(xy 349.55541 -403.802698) (xy 349.570766 -403.7504) (xy 349.593408 -403.700821) (xy 349.622875 -403.654968)
			(xy 349.658567 -403.613776) (xy 349.699759 -403.578082) (xy 349.74561 -403.548613) (xy 349.795189 -403.52597)
			(xy 349.847486 -403.510613) (xy 349.901436 -403.502855) (xy 349.928688 -403.502368) (xy 350.792288 -403.502368)
			(xy 350.81954 -403.502878) (xy 350.873489 -403.510634) (xy 350.925785 -403.525988) (xy 350.975363 -403.548628)
			(xy 351.021215 -403.578094) (xy 351.062406 -403.613785) (xy 351.098099 -403.654976) (xy 351.127566 -403.700826)
			(xy 351.150208 -403.750404) (xy 351.165564 -403.8027) (xy 351.173321 -403.856648) (xy 351.173321 -403.911152)
			(xy 351.17332 -403.911156) (xy 371.041831 -403.911156) (xy 371.041831 -403.856644) (xy 371.049589 -403.802687)
			(xy 371.064948 -403.750383) (xy 371.087594 -403.700798) (xy 371.117067 -403.654941) (xy 371.152766 -403.613745)
			(xy 371.193965 -403.578049) (xy 371.239824 -403.54858) (xy 371.289412 -403.525937) (xy 371.341716 -403.510583)
			(xy 371.395674 -403.502829) (xy 371.42293 -403.502368) (xy 372.28653 -403.502368) (xy 372.313778 -403.502904)
			(xy 372.367719 -403.510664) (xy 372.420007 -403.52602) (xy 372.469577 -403.548662) (xy 372.515421 -403.578127)
			(xy 372.556605 -403.613816) (xy 372.592291 -403.655003) (xy 372.621753 -403.700849) (xy 372.64439 -403.750421)
			(xy 372.659743 -403.80271) (xy 372.667498 -403.856652) (xy 372.667498 -403.911148) (xy 372.667497 -403.911152)
			(xy 374.105154 -403.911152) (xy 374.105154 -403.856648) (xy 374.11291 -403.8027) (xy 374.128265 -403.750404)
			(xy 374.150905 -403.700826) (xy 374.18037 -403.654974) (xy 374.216061 -403.613782) (xy 374.25725 -403.578088)
			(xy 374.3031 -403.548619) (xy 374.352676 -403.525975) (xy 374.404971 -403.510616) (xy 374.458918 -403.502856)
			(xy 374.48617 -403.502368) (xy 375.34977 -403.502368) (xy 375.377023 -403.502877) (xy 375.430973 -403.51063)
			(xy 375.483271 -403.525983) (xy 375.532852 -403.548622) (xy 375.578706 -403.578087) (xy 375.6199 -403.613779)
			(xy 375.655595 -403.65497) (xy 375.685064 -403.700821) (xy 375.707707 -403.7504) (xy 375.723063 -403.802697)
			(xy 375.730821 -403.856647) (xy 375.730821 -403.911153) (xy 375.730821 -403.911155) (xy 377.168331 -403.911155)
			(xy 377.168331 -403.856645) (xy 377.176089 -403.80269) (xy 377.191446 -403.750388) (xy 377.214091 -403.700804)
			(xy 377.243562 -403.654947) (xy 377.279259 -403.613752) (xy 377.320455 -403.578056) (xy 377.366313 -403.548586)
			(xy 377.415897 -403.525943) (xy 377.468199 -403.510587) (xy 377.522155 -403.50283) (xy 377.54941 -403.502368)
			(xy 378.41301 -403.502368) (xy 378.440259 -403.502903) (xy 378.494202 -403.51066) (xy 378.546492 -403.526015)
			(xy 378.596065 -403.548655) (xy 378.641911 -403.57812) (xy 378.683098 -403.613809) (xy 378.718786 -403.654997)
			(xy 378.748249 -403.700844) (xy 378.770888 -403.750417) (xy 378.786242 -403.802708) (xy 378.793998 -403.856651)
			(xy 378.793998 -403.911149) (xy 378.793998 -403.911151) (xy 380.231654 -403.911151) (xy 380.231654 -403.856649)
			(xy 380.239409 -403.802703) (xy 380.254763 -403.750409) (xy 380.277402 -403.700832) (xy 380.306865 -403.654981)
			(xy 380.342554 -403.613789) (xy 380.383741 -403.578095) (xy 380.429588 -403.548626) (xy 380.479162 -403.52598)
			(xy 380.531454 -403.51062) (xy 380.585399 -403.502857) (xy 380.61265 -403.502368) (xy 381.47625 -403.502368)
			(xy 381.503503 -403.502876) (xy 381.557456 -403.510627) (xy 381.609757 -403.525977) (xy 381.65934 -403.548616)
			(xy 381.705197 -403.57808) (xy 381.746393 -403.613772) (xy 381.78209 -403.654963) (xy 381.81156 -403.700816)
			(xy 381.834205 -403.750396) (xy 381.849563 -403.802695) (xy 381.857321 -403.856647) (xy 381.857321 -403.911153)
			(xy 383.294854 -403.911153) (xy 383.294854 -403.856647) (xy 383.302611 -403.802697) (xy 383.317966 -403.7504)
			(xy 383.340608 -403.70082) (xy 383.370075 -403.654968) (xy 383.405768 -403.613775) (xy 383.44696 -403.578081)
			(xy 383.492812 -403.548613) (xy 383.542391 -403.52597) (xy 383.594687 -403.510613) (xy 383.648638 -403.502855)
			(xy 383.67589 -403.502368) (xy 384.53949 -403.502368) (xy 384.566742 -403.502879) (xy 384.62069 -403.510634)
			(xy 384.672986 -403.525988) (xy 384.722564 -403.548629) (xy 384.768416 -403.578095) (xy 384.809607 -403.613786)
			(xy 384.845299 -403.654976) (xy 384.874767 -403.700827) (xy 384.897408 -403.750405) (xy 384.912764 -403.8027)
			(xy 384.920521 -403.856648) (xy 384.920521 -403.911152) (xy 384.92052 -403.911156) (xy 386.358031 -403.911156)
			(xy 386.358031 -403.856644) (xy 386.365789 -403.802687) (xy 386.381148 -403.750383) (xy 386.403794 -403.700798)
			(xy 386.433267 -403.654941) (xy 386.468966 -403.613745) (xy 386.510165 -403.578049) (xy 386.556024 -403.54858)
			(xy 386.605612 -403.525937) (xy 386.657916 -403.510583) (xy 386.711874 -403.502829) (xy 386.73913 -403.502368)
			(xy 387.60273 -403.502368) (xy 387.629978 -403.502904) (xy 387.683919 -403.510664) (xy 387.736207 -403.52602)
			(xy 387.785777 -403.548662) (xy 387.831621 -403.578127) (xy 387.872805 -403.613816) (xy 387.908491 -403.655003)
			(xy 387.937953 -403.700849) (xy 387.96059 -403.750421) (xy 387.975943 -403.80271) (xy 387.983698 -403.856652)
			(xy 387.983698 -403.911148) (xy 387.983697 -403.911152) (xy 389.421354 -403.911152) (xy 389.421354 -403.856648)
			(xy 389.42911 -403.8027) (xy 389.444465 -403.750404) (xy 389.467105 -403.700826) (xy 389.49657 -403.654974)
			(xy 389.532261 -403.613782) (xy 389.57345 -403.578088) (xy 389.6193 -403.548619) (xy 389.668876 -403.525975)
			(xy 389.721171 -403.510616) (xy 389.775118 -403.502856) (xy 389.80237 -403.502368) (xy 390.66597 -403.502368)
			(xy 390.693223 -403.502877) (xy 390.747173 -403.51063) (xy 390.799471 -403.525983) (xy 390.849052 -403.548622)
			(xy 390.894906 -403.578087) (xy 390.9361 -403.613779) (xy 390.971795 -403.65497) (xy 391.001264 -403.700821)
			(xy 391.023907 -403.7504) (xy 391.039263 -403.802697) (xy 391.047021 -403.856647) (xy 391.047021 -403.911153)
			(xy 391.047021 -403.911155) (xy 392.484531 -403.911155) (xy 392.484531 -403.856645) (xy 392.492289 -403.80269)
			(xy 392.507646 -403.750388) (xy 392.530291 -403.700804) (xy 392.559762 -403.654947) (xy 392.595459 -403.613752)
			(xy 392.636655 -403.578056) (xy 392.682513 -403.548586) (xy 392.732097 -403.525943) (xy 392.784399 -403.510587)
			(xy 392.838355 -403.50283) (xy 392.86561 -403.502368) (xy 393.72921 -403.502368) (xy 393.756459 -403.502903)
			(xy 393.810402 -403.51066) (xy 393.862692 -403.526015) (xy 393.912265 -403.548655) (xy 393.958111 -403.57812)
			(xy 393.999298 -403.613809) (xy 394.034986 -403.654997) (xy 394.064449 -403.700844) (xy 394.087088 -403.750417)
			(xy 394.102442 -403.802708) (xy 394.110198 -403.856651) (xy 394.110198 -403.911149) (xy 394.110198 -403.911151)
			(xy 395.547854 -403.911151) (xy 395.547854 -403.856649) (xy 395.555609 -403.802703) (xy 395.570963 -403.750409)
			(xy 395.593602 -403.700832) (xy 395.623065 -403.654981) (xy 395.658754 -403.613789) (xy 395.699941 -403.578095)
			(xy 395.745788 -403.548626) (xy 395.795362 -403.52598) (xy 395.847654 -403.51062) (xy 395.901599 -403.502857)
			(xy 395.92885 -403.502368) (xy 396.79245 -403.502368) (xy 396.819703 -403.502876) (xy 396.873656 -403.510627)
			(xy 396.925957 -403.525977) (xy 396.97554 -403.548616) (xy 397.021397 -403.57808) (xy 397.062593 -403.613772)
			(xy 397.09829 -403.654963) (xy 397.12776 -403.700816) (xy 397.150405 -403.750396) (xy 397.165763 -403.802695)
			(xy 397.173521 -403.856647) (xy 397.173521 -403.911153) (xy 398.611054 -403.911153) (xy 398.611054 -403.856647)
			(xy 398.618811 -403.802697) (xy 398.634166 -403.7504) (xy 398.656808 -403.70082) (xy 398.686275 -403.654968)
			(xy 398.721968 -403.613775) (xy 398.76316 -403.578081) (xy 398.809012 -403.548613) (xy 398.858591 -403.52597)
			(xy 398.910887 -403.510613) (xy 398.964838 -403.502855) (xy 398.99209 -403.502368) (xy 399.85569 -403.502368)
			(xy 399.882942 -403.502879) (xy 399.93689 -403.510634) (xy 399.989186 -403.525988) (xy 400.038764 -403.548629)
			(xy 400.084616 -403.578095) (xy 400.125807 -403.613786) (xy 400.161499 -403.654976) (xy 400.190967 -403.700827)
			(xy 400.213608 -403.750405) (xy 400.228964 -403.8027) (xy 400.236721 -403.856648) (xy 400.236721 -403.911152)
			(xy 400.23672 -403.911156) (xy 401.674231 -403.911156) (xy 401.674231 -403.856644) (xy 401.681989 -403.802687)
			(xy 401.697348 -403.750383) (xy 401.719994 -403.700798) (xy 401.749467 -403.654941) (xy 401.785166 -403.613745)
			(xy 401.826365 -403.578049) (xy 401.872224 -403.54858) (xy 401.921812 -403.525937) (xy 401.974116 -403.510583)
			(xy 402.028074 -403.502829) (xy 402.05533 -403.502368) (xy 402.91893 -403.502368) (xy 402.946178 -403.502904)
			(xy 403.000119 -403.510664) (xy 403.052407 -403.52602) (xy 403.101977 -403.548662) (xy 403.147821 -403.578127)
			(xy 403.189005 -403.613816) (xy 403.224691 -403.655003) (xy 403.254153 -403.700849) (xy 403.27679 -403.750421)
			(xy 403.292143 -403.80271) (xy 403.299898 -403.856652) (xy 403.299898 -403.911148) (xy 403.299897 -403.911152)
			(xy 404.737554 -403.911152) (xy 404.737554 -403.856648) (xy 404.74531 -403.8027) (xy 404.760665 -403.750404)
			(xy 404.783305 -403.700826) (xy 404.81277 -403.654974) (xy 404.848461 -403.613782) (xy 404.88965 -403.578088)
			(xy 404.9355 -403.548619) (xy 404.985076 -403.525975) (xy 405.037371 -403.510616) (xy 405.091318 -403.502856)
			(xy 405.11857 -403.502368) (xy 405.98217 -403.502368) (xy 406.009423 -403.502877) (xy 406.063373 -403.51063)
			(xy 406.115671 -403.525983) (xy 406.165252 -403.548622) (xy 406.211106 -403.578087) (xy 406.2523 -403.613779)
			(xy 406.287995 -403.65497) (xy 406.317464 -403.700821) (xy 406.340107 -403.7504) (xy 406.355463 -403.802697)
			(xy 406.363221 -403.856647) (xy 406.363221 -403.911153) (xy 406.363221 -403.911155) (xy 407.800731 -403.911155)
			(xy 407.800731 -403.856645) (xy 407.808489 -403.80269) (xy 407.823846 -403.750388) (xy 407.846491 -403.700804)
			(xy 407.875962 -403.654947) (xy 407.911659 -403.613752) (xy 407.952855 -403.578056) (xy 407.998713 -403.548586)
			(xy 408.048297 -403.525943) (xy 408.100599 -403.510587) (xy 408.154555 -403.50283) (xy 408.18181 -403.502368)
			(xy 409.04541 -403.502368) (xy 409.072659 -403.502903) (xy 409.126602 -403.51066) (xy 409.178892 -403.526015)
			(xy 409.228465 -403.548655) (xy 409.274311 -403.57812) (xy 409.315498 -403.613809) (xy 409.351186 -403.654997)
			(xy 409.380649 -403.700844) (xy 409.403288 -403.750417) (xy 409.418642 -403.802708) (xy 409.426398 -403.856651)
			(xy 409.426398 -403.911149) (xy 409.426398 -403.911151) (xy 410.864054 -403.911151) (xy 410.864054 -403.856649)
			(xy 410.871809 -403.802703) (xy 410.887163 -403.750409) (xy 410.909802 -403.700832) (xy 410.939265 -403.654981)
			(xy 410.974954 -403.613789) (xy 411.016141 -403.578095) (xy 411.061988 -403.548626) (xy 411.111562 -403.52598)
			(xy 411.163854 -403.51062) (xy 411.217799 -403.502857) (xy 411.24505 -403.502368) (xy 412.10865 -403.502368)
			(xy 412.135903 -403.502876) (xy 412.189856 -403.510627) (xy 412.242157 -403.525977) (xy 412.29174 -403.548616)
			(xy 412.337597 -403.57808) (xy 412.378793 -403.613772) (xy 412.41449 -403.654963) (xy 412.44396 -403.700816)
			(xy 412.466605 -403.750396) (xy 412.481963 -403.802695) (xy 412.489721 -403.856647) (xy 412.489721 -403.911153)
			(xy 413.927254 -403.911153) (xy 413.927254 -403.856647) (xy 413.935011 -403.802697) (xy 413.950366 -403.7504)
			(xy 413.973008 -403.70082) (xy 414.002475 -403.654968) (xy 414.038168 -403.613775) (xy 414.07936 -403.578081)
			(xy 414.125212 -403.548613) (xy 414.174791 -403.52597) (xy 414.227087 -403.510613) (xy 414.281038 -403.502855)
			(xy 414.30829 -403.502368) (xy 415.17189 -403.502368) (xy 415.199142 -403.502879) (xy 415.25309 -403.510634)
			(xy 415.305386 -403.525988) (xy 415.354964 -403.548629) (xy 415.400816 -403.578095) (xy 415.442007 -403.613786)
			(xy 415.477699 -403.654976) (xy 415.507167 -403.700827) (xy 415.529808 -403.750405) (xy 415.545164 -403.8027)
			(xy 415.552921 -403.856648) (xy 415.552921 -403.911152) (xy 415.55292 -403.911156) (xy 416.990431 -403.911156)
			(xy 416.990431 -403.856644) (xy 416.998189 -403.802687) (xy 417.013548 -403.750383) (xy 417.036194 -403.700798)
			(xy 417.065667 -403.654941) (xy 417.101366 -403.613745) (xy 417.142565 -403.578049) (xy 417.188424 -403.54858)
			(xy 417.238012 -403.525937) (xy 417.290316 -403.510583) (xy 417.344274 -403.502829) (xy 417.37153 -403.502368)
			(xy 418.23513 -403.502368) (xy 418.262378 -403.502904) (xy 418.316319 -403.510664) (xy 418.368607 -403.52602)
			(xy 418.418177 -403.548662) (xy 418.464021 -403.578127) (xy 418.505205 -403.613816) (xy 418.540891 -403.655003)
			(xy 418.570353 -403.700849) (xy 418.59299 -403.750421) (xy 418.608343 -403.80271) (xy 418.616098 -403.856652)
			(xy 418.616098 -403.911148) (xy 418.608343 -403.96509) (xy 418.59299 -404.017379) (xy 418.570353 -404.066951)
			(xy 418.540891 -404.112797) (xy 418.505205 -404.153984) (xy 418.464021 -404.189673) (xy 418.418177 -404.219138)
			(xy 418.368607 -404.24178) (xy 418.316319 -404.257136) (xy 418.262378 -404.264896) (xy 418.23513 -404.265384)
			(xy 417.37153 -404.265384) (xy 417.344274 -404.264971) (xy 417.290316 -404.257217) (xy 417.238012 -404.241863)
			(xy 417.188424 -404.21922) (xy 417.142565 -404.189751) (xy 417.101366 -404.154055) (xy 417.065667 -404.112859)
			(xy 417.036194 -404.067002) (xy 417.013548 -404.017417) (xy 416.998189 -403.965113) (xy 416.990431 -403.911156)
			(xy 415.55292 -403.911156) (xy 415.545164 -403.9651) (xy 415.529808 -404.017395) (xy 415.507167 -404.066973)
			(xy 415.477699 -404.112824) (xy 415.442007 -404.154014) (xy 415.400816 -404.189705) (xy 415.354964 -404.219171)
			(xy 415.305386 -404.241812) (xy 415.25309 -404.257166) (xy 415.199142 -404.264921) (xy 415.17189 -404.265384)
			(xy 414.30829 -404.265384) (xy 414.281038 -404.264945) (xy 414.227087 -404.257187) (xy 414.174791 -404.24183)
			(xy 414.125212 -404.219187) (xy 414.07936 -404.189719) (xy 414.038168 -404.154025) (xy 414.002475 -404.112832)
			(xy 413.973008 -404.06698) (xy 413.950366 -404.0174) (xy 413.935011 -403.965103) (xy 413.927254 -403.911153)
			(xy 412.489721 -403.911153) (xy 412.481963 -403.965105) (xy 412.466605 -404.017404) (xy 412.44396 -404.066984)
			(xy 412.41449 -404.112837) (xy 412.378793 -404.154028) (xy 412.337597 -404.18972) (xy 412.29174 -404.219184)
			(xy 412.242157 -404.241823) (xy 412.189856 -404.257173) (xy 412.135903 -404.264924) (xy 412.10865 -404.265384)
			(xy 411.24505 -404.265384) (xy 411.217799 -404.264943) (xy 411.163854 -404.25718) (xy 411.111562 -404.24182)
			(xy 411.061988 -404.219174) (xy 411.016141 -404.189705) (xy 410.974954 -404.154011) (xy 410.939265 -404.112819)
			(xy 410.909802 -404.066968) (xy 410.887163 -404.017391) (xy 410.871809 -403.965097) (xy 410.864054 -403.911151)
			(xy 409.426398 -403.911151) (xy 409.418642 -403.965092) (xy 409.403288 -404.017383) (xy 409.380649 -404.066956)
			(xy 409.351186 -404.112803) (xy 409.315498 -404.153991) (xy 409.274311 -404.18968) (xy 409.228465 -404.219145)
			(xy 409.178892 -404.241785) (xy 409.126602 -404.25714) (xy 409.072659 -404.264897) (xy 409.04541 -404.265384)
			(xy 408.18181 -404.265384) (xy 408.154555 -404.26497) (xy 408.100599 -404.257213) (xy 408.048297 -404.241857)
			(xy 407.998713 -404.219214) (xy 407.952855 -404.189744) (xy 407.911659 -404.154048) (xy 407.875962 -404.112853)
			(xy 407.846491 -404.066996) (xy 407.823846 -404.017412) (xy 407.808489 -403.96511) (xy 407.800731 -403.911155)
			(xy 406.363221 -403.911155) (xy 406.355463 -403.965103) (xy 406.340107 -404.0174) (xy 406.317464 -404.066979)
			(xy 406.287995 -404.11283) (xy 406.2523 -404.154021) (xy 406.211106 -404.189713) (xy 406.165252 -404.219178)
			(xy 406.115671 -404.241817) (xy 406.063373 -404.25717) (xy 406.009423 -404.264923) (xy 405.98217 -404.265384)
			(xy 405.11857 -404.265384) (xy 405.091318 -404.264944) (xy 405.037371 -404.257184) (xy 404.985076 -404.241825)
			(xy 404.9355 -404.219181) (xy 404.88965 -404.189712) (xy 404.848461 -404.154018) (xy 404.81277 -404.112826)
			(xy 404.783305 -404.066974) (xy 404.760665 -404.017396) (xy 404.74531 -403.9651) (xy 404.737554 -403.911152)
			(xy 403.299897 -403.911152) (xy 403.292143 -403.96509) (xy 403.27679 -404.017379) (xy 403.254153 -404.066951)
			(xy 403.224691 -404.112797) (xy 403.189005 -404.153984) (xy 403.147821 -404.189673) (xy 403.101977 -404.219138)
			(xy 403.052407 -404.24178) (xy 403.000119 -404.257136) (xy 402.946178 -404.264896) (xy 402.91893 -404.265384)
			(xy 402.05533 -404.265384) (xy 402.028074 -404.264971) (xy 401.974116 -404.257217) (xy 401.921812 -404.241863)
			(xy 401.872224 -404.21922) (xy 401.826365 -404.189751) (xy 401.785166 -404.154055) (xy 401.749467 -404.112859)
			(xy 401.719994 -404.067002) (xy 401.697348 -404.017417) (xy 401.681989 -403.965113) (xy 401.674231 -403.911156)
			(xy 400.23672 -403.911156) (xy 400.228964 -403.9651) (xy 400.213608 -404.017395) (xy 400.190967 -404.066973)
			(xy 400.161499 -404.112824) (xy 400.125807 -404.154014) (xy 400.084616 -404.189705) (xy 400.038764 -404.219171)
			(xy 399.989186 -404.241812) (xy 399.93689 -404.257166) (xy 399.882942 -404.264921) (xy 399.85569 -404.265384)
			(xy 398.99209 -404.265384) (xy 398.964838 -404.264945) (xy 398.910887 -404.257187) (xy 398.858591 -404.24183)
			(xy 398.809012 -404.219187) (xy 398.76316 -404.189719) (xy 398.721968 -404.154025) (xy 398.686275 -404.112832)
			(xy 398.656808 -404.06698) (xy 398.634166 -404.0174) (xy 398.618811 -403.965103) (xy 398.611054 -403.911153)
			(xy 397.173521 -403.911153) (xy 397.165763 -403.965105) (xy 397.150405 -404.017404) (xy 397.12776 -404.066984)
			(xy 397.09829 -404.112837) (xy 397.062593 -404.154028) (xy 397.021397 -404.18972) (xy 396.97554 -404.219184)
			(xy 396.925957 -404.241823) (xy 396.873656 -404.257173) (xy 396.819703 -404.264924) (xy 396.79245 -404.265384)
			(xy 395.92885 -404.265384) (xy 395.901599 -404.264943) (xy 395.847654 -404.25718) (xy 395.795362 -404.24182)
			(xy 395.745788 -404.219174) (xy 395.699941 -404.189705) (xy 395.658754 -404.154011) (xy 395.623065 -404.112819)
			(xy 395.593602 -404.066968) (xy 395.570963 -404.017391) (xy 395.555609 -403.965097) (xy 395.547854 -403.911151)
			(xy 394.110198 -403.911151) (xy 394.102442 -403.965092) (xy 394.087088 -404.017383) (xy 394.064449 -404.066956)
			(xy 394.034986 -404.112803) (xy 393.999298 -404.153991) (xy 393.958111 -404.18968) (xy 393.912265 -404.219145)
			(xy 393.862692 -404.241785) (xy 393.810402 -404.25714) (xy 393.756459 -404.264897) (xy 393.72921 -404.265384)
			(xy 392.86561 -404.265384) (xy 392.838355 -404.26497) (xy 392.784399 -404.257213) (xy 392.732097 -404.241857)
			(xy 392.682513 -404.219214) (xy 392.636655 -404.189744) (xy 392.595459 -404.154048) (xy 392.559762 -404.112853)
			(xy 392.530291 -404.066996) (xy 392.507646 -404.017412) (xy 392.492289 -403.96511) (xy 392.484531 -403.911155)
			(xy 391.047021 -403.911155) (xy 391.039263 -403.965103) (xy 391.023907 -404.0174) (xy 391.001264 -404.066979)
			(xy 390.971795 -404.11283) (xy 390.9361 -404.154021) (xy 390.894906 -404.189713) (xy 390.849052 -404.219178)
			(xy 390.799471 -404.241817) (xy 390.747173 -404.25717) (xy 390.693223 -404.264923) (xy 390.66597 -404.265384)
			(xy 389.80237 -404.265384) (xy 389.775118 -404.264944) (xy 389.721171 -404.257184) (xy 389.668876 -404.241825)
			(xy 389.6193 -404.219181) (xy 389.57345 -404.189712) (xy 389.532261 -404.154018) (xy 389.49657 -404.112826)
			(xy 389.467105 -404.066974) (xy 389.444465 -404.017396) (xy 389.42911 -403.9651) (xy 389.421354 -403.911152)
			(xy 387.983697 -403.911152) (xy 387.975943 -403.96509) (xy 387.96059 -404.017379) (xy 387.937953 -404.066951)
			(xy 387.908491 -404.112797) (xy 387.872805 -404.153984) (xy 387.831621 -404.189673) (xy 387.785777 -404.219138)
			(xy 387.736207 -404.24178) (xy 387.683919 -404.257136) (xy 387.629978 -404.264896) (xy 387.60273 -404.265384)
			(xy 386.73913 -404.265384) (xy 386.711874 -404.264971) (xy 386.657916 -404.257217) (xy 386.605612 -404.241863)
			(xy 386.556024 -404.21922) (xy 386.510165 -404.189751) (xy 386.468966 -404.154055) (xy 386.433267 -404.112859)
			(xy 386.403794 -404.067002) (xy 386.381148 -404.017417) (xy 386.365789 -403.965113) (xy 386.358031 -403.911156)
			(xy 384.92052 -403.911156) (xy 384.912764 -403.9651) (xy 384.897408 -404.017395) (xy 384.874767 -404.066973)
			(xy 384.845299 -404.112824) (xy 384.809607 -404.154014) (xy 384.768416 -404.189705) (xy 384.722564 -404.219171)
			(xy 384.672986 -404.241812) (xy 384.62069 -404.257166) (xy 384.566742 -404.264921) (xy 384.53949 -404.265384)
			(xy 383.67589 -404.265384) (xy 383.648638 -404.264945) (xy 383.594687 -404.257187) (xy 383.542391 -404.24183)
			(xy 383.492812 -404.219187) (xy 383.44696 -404.189719) (xy 383.405768 -404.154025) (xy 383.370075 -404.112832)
			(xy 383.340608 -404.06698) (xy 383.317966 -404.0174) (xy 383.302611 -403.965103) (xy 383.294854 -403.911153)
			(xy 381.857321 -403.911153) (xy 381.849563 -403.965105) (xy 381.834205 -404.017404) (xy 381.81156 -404.066984)
			(xy 381.78209 -404.112837) (xy 381.746393 -404.154028) (xy 381.705197 -404.18972) (xy 381.65934 -404.219184)
			(xy 381.609757 -404.241823) (xy 381.557456 -404.257173) (xy 381.503503 -404.264924) (xy 381.47625 -404.265384)
			(xy 380.61265 -404.265384) (xy 380.585399 -404.264943) (xy 380.531454 -404.25718) (xy 380.479162 -404.24182)
			(xy 380.429588 -404.219174) (xy 380.383741 -404.189705) (xy 380.342554 -404.154011) (xy 380.306865 -404.112819)
			(xy 380.277402 -404.066968) (xy 380.254763 -404.017391) (xy 380.239409 -403.965097) (xy 380.231654 -403.911151)
			(xy 378.793998 -403.911151) (xy 378.786242 -403.965092) (xy 378.770888 -404.017383) (xy 378.748249 -404.066956)
			(xy 378.718786 -404.112803) (xy 378.683098 -404.153991) (xy 378.641911 -404.18968) (xy 378.596065 -404.219145)
			(xy 378.546492 -404.241785) (xy 378.494202 -404.25714) (xy 378.440259 -404.264897) (xy 378.41301 -404.265384)
			(xy 377.54941 -404.265384) (xy 377.522155 -404.26497) (xy 377.468199 -404.257213) (xy 377.415897 -404.241857)
			(xy 377.366313 -404.219214) (xy 377.320455 -404.189744) (xy 377.279259 -404.154048) (xy 377.243562 -404.112853)
			(xy 377.214091 -404.066996) (xy 377.191446 -404.017412) (xy 377.176089 -403.96511) (xy 377.168331 -403.911155)
			(xy 375.730821 -403.911155) (xy 375.723063 -403.965103) (xy 375.707707 -404.0174) (xy 375.685064 -404.066979)
			(xy 375.655595 -404.11283) (xy 375.6199 -404.154021) (xy 375.578706 -404.189713) (xy 375.532852 -404.219178)
			(xy 375.483271 -404.241817) (xy 375.430973 -404.25717) (xy 375.377023 -404.264923) (xy 375.34977 -404.265384)
			(xy 374.48617 -404.265384) (xy 374.458918 -404.264944) (xy 374.404971 -404.257184) (xy 374.352676 -404.241825)
			(xy 374.3031 -404.219181) (xy 374.25725 -404.189712) (xy 374.216061 -404.154018) (xy 374.18037 -404.112826)
			(xy 374.150905 -404.066974) (xy 374.128265 -404.017396) (xy 374.11291 -403.9651) (xy 374.105154 -403.911152)
			(xy 372.667497 -403.911152) (xy 372.659743 -403.96509) (xy 372.64439 -404.017379) (xy 372.621753 -404.066951)
			(xy 372.592291 -404.112797) (xy 372.556605 -404.153984) (xy 372.515421 -404.189673) (xy 372.469577 -404.219138)
			(xy 372.420007 -404.24178) (xy 372.367719 -404.257136) (xy 372.313778 -404.264896) (xy 372.28653 -404.265384)
			(xy 371.42293 -404.265384) (xy 371.395674 -404.264971) (xy 371.341716 -404.257217) (xy 371.289412 -404.241863)
			(xy 371.239824 -404.21922) (xy 371.193965 -404.189751) (xy 371.152766 -404.154055) (xy 371.117067 -404.112859)
			(xy 371.087594 -404.067002) (xy 371.064948 -404.017417) (xy 371.049589 -403.965113) (xy 371.041831 -403.911156)
			(xy 351.17332 -403.911156) (xy 351.165564 -403.9651) (xy 351.150208 -404.017396) (xy 351.127566 -404.066974)
			(xy 351.098099 -404.112824) (xy 351.062406 -404.154015) (xy 351.021215 -404.189706) (xy 350.975363 -404.219172)
			(xy 350.925785 -404.241812) (xy 350.873489 -404.257166) (xy 350.81954 -404.264922) (xy 350.792288 -404.265384)
			(xy 349.928688 -404.265384) (xy 349.901436 -404.264945) (xy 349.847486 -404.257187) (xy 349.795189 -404.24183)
			(xy 349.74561 -404.219187) (xy 349.699759 -404.189718) (xy 349.658567 -404.154024) (xy 349.622875 -404.112832)
			(xy 349.593408 -404.066979) (xy 349.570766 -404.0174) (xy 349.55541 -403.965102) (xy 349.547654 -403.911152)
			(xy 348.109997 -403.911152) (xy 348.102243 -403.965087) (xy 348.086891 -404.017375) (xy 348.064255 -404.066946)
			(xy 348.034795 -404.112791) (xy 347.999111 -404.153977) (xy 347.957929 -404.189667) (xy 347.912088 -404.219132)
			(xy 347.86252 -404.241775) (xy 347.810234 -404.257133) (xy 347.756295 -404.264895) (xy 347.729048 -404.265384)
			(xy 346.865448 -404.265384) (xy 346.838191 -404.264972) (xy 346.784232 -404.25722) (xy 346.731925 -404.241868)
			(xy 346.682335 -404.219226) (xy 346.636473 -404.189758) (xy 346.595272 -404.154062) (xy 346.559571 -404.112865)
			(xy 346.530097 -404.067007) (xy 346.507449 -404.01742) (xy 346.49209 -403.965115) (xy 346.484331 -403.911157)
			(xy 345.046797 -403.911157) (xy 345.039042 -403.965093) (xy 345.023688 -404.017383) (xy 345.001049 -404.066957)
			(xy 344.971586 -404.112804) (xy 344.935897 -404.153991) (xy 344.89471 -404.189681) (xy 344.848864 -404.219145)
			(xy 344.799291 -404.241785) (xy 344.747001 -404.25714) (xy 344.693057 -404.264897) (xy 344.665808 -404.265384)
			(xy 343.802208 -404.265384) (xy 343.774953 -404.26497) (xy 343.720998 -404.257213) (xy 343.668696 -404.241857)
			(xy 343.619111 -404.219213) (xy 343.573254 -404.189744) (xy 343.532058 -404.154048) (xy 343.496361 -404.112852)
			(xy 343.466891 -404.066996) (xy 343.444246 -404.017412) (xy 343.428889 -403.96511) (xy 343.421131 -403.911155)
			(xy 341.983621 -403.911155) (xy 341.975863 -403.965103) (xy 341.960507 -404.0174) (xy 341.937863 -404.066979)
			(xy 341.908394 -404.112831) (xy 341.872699 -404.154022) (xy 341.831505 -404.189713) (xy 341.785651 -404.219179)
			(xy 341.73607 -404.241818) (xy 341.683772 -404.25717) (xy 341.629821 -404.264923) (xy 341.602568 -404.265384)
			(xy 340.738968 -404.265384) (xy 340.711717 -404.264944) (xy 340.657769 -404.257183) (xy 340.605475 -404.241824)
			(xy 340.555898 -404.21918) (xy 340.510049 -404.189711) (xy 340.46886 -404.154017) (xy 340.43317 -404.112825)
			(xy 340.403705 -404.066974) (xy 340.381064 -404.017395) (xy 340.36571 -403.9651) (xy 340.357954 -403.911152)
			(xy 338.920297 -403.911152) (xy 338.912543 -403.96509) (xy 338.89719 -404.017379) (xy 338.874552 -404.066951)
			(xy 338.84509 -404.112798) (xy 338.809404 -404.153984) (xy 338.76822 -404.189674) (xy 338.722376 -404.219139)
			(xy 338.672805 -404.24178) (xy 338.620517 -404.257137) (xy 338.566576 -404.264896) (xy 338.539328 -404.265384)
			(xy 337.675728 -404.265384) (xy 337.648472 -404.264971) (xy 337.594515 -404.257217) (xy 337.54221 -404.241862)
			(xy 337.492623 -404.21922) (xy 337.446764 -404.189751) (xy 337.405565 -404.154055) (xy 337.369866 -404.112859)
			(xy 337.340394 -404.067001) (xy 337.317748 -404.017416) (xy 337.302389 -403.965113) (xy 337.294631 -403.911156)
			(xy 335.85712 -403.911156) (xy 335.849364 -403.9651) (xy 335.834008 -404.017396) (xy 335.811366 -404.066974)
			(xy 335.781899 -404.112824) (xy 335.746206 -404.154015) (xy 335.705015 -404.189706) (xy 335.659163 -404.219172)
			(xy 335.609585 -404.241812) (xy 335.557289 -404.257166) (xy 335.50334 -404.264922) (xy 335.476088 -404.265384)
			(xy 334.612488 -404.265384) (xy 334.585236 -404.264945) (xy 334.531286 -404.257187) (xy 334.478989 -404.24183)
			(xy 334.42941 -404.219187) (xy 334.383559 -404.189718) (xy 334.342367 -404.154024) (xy 334.306675 -404.112832)
			(xy 334.277208 -404.066979) (xy 334.254566 -404.0174) (xy 334.23921 -403.965102) (xy 334.231454 -403.911152)
			(xy 332.793797 -403.911152) (xy 332.786043 -403.965087) (xy 332.770691 -404.017375) (xy 332.748055 -404.066946)
			(xy 332.718595 -404.112791) (xy 332.682911 -404.153977) (xy 332.641729 -404.189667) (xy 332.595888 -404.219132)
			(xy 332.54632 -404.241775) (xy 332.494034 -404.257133) (xy 332.440095 -404.264895) (xy 332.412848 -404.265384)
			(xy 331.549248 -404.265384) (xy 331.521991 -404.264972) (xy 331.468032 -404.25722) (xy 331.415725 -404.241868)
			(xy 331.366135 -404.219226) (xy 331.320273 -404.189758) (xy 331.279072 -404.154062) (xy 331.243371 -404.112865)
			(xy 331.213897 -404.067007) (xy 331.191249 -404.01742) (xy 331.17589 -403.965115) (xy 331.168131 -403.911157)
			(xy 329.730597 -403.911157) (xy 329.722842 -403.965093) (xy 329.707488 -404.017383) (xy 329.684849 -404.066957)
			(xy 329.655386 -404.112804) (xy 329.619697 -404.153991) (xy 329.57851 -404.189681) (xy 329.532664 -404.219145)
			(xy 329.483091 -404.241785) (xy 329.430801 -404.25714) (xy 329.376857 -404.264897) (xy 329.349608 -404.265384)
			(xy 328.486008 -404.265384) (xy 328.458753 -404.26497) (xy 328.404798 -404.257213) (xy 328.352496 -404.241857)
			(xy 328.302911 -404.219213) (xy 328.257054 -404.189744) (xy 328.215858 -404.154048) (xy 328.180161 -404.112852)
			(xy 328.150691 -404.066996) (xy 328.128046 -404.017412) (xy 328.112689 -403.96511) (xy 328.104931 -403.911155)
			(xy 326.667421 -403.911155) (xy 326.659663 -403.965103) (xy 326.644307 -404.0174) (xy 326.621663 -404.066979)
			(xy 326.592194 -404.112831) (xy 326.556499 -404.154022) (xy 326.515305 -404.189713) (xy 326.469451 -404.219179)
			(xy 326.41987 -404.241818) (xy 326.367572 -404.25717) (xy 326.313621 -404.264923) (xy 326.286368 -404.265384)
			(xy 325.422768 -404.265384) (xy 325.395517 -404.264944) (xy 325.341569 -404.257183) (xy 325.289275 -404.241824)
			(xy 325.239698 -404.21918) (xy 325.193849 -404.189711) (xy 325.15266 -404.154017) (xy 325.11697 -404.112825)
			(xy 325.087505 -404.066974) (xy 325.064864 -404.017395) (xy 325.04951 -403.9651) (xy 325.041754 -403.911152)
			(xy 323.604097 -403.911152) (xy 323.596343 -403.96509) (xy 323.58099 -404.017379) (xy 323.558352 -404.066951)
			(xy 323.52889 -404.112798) (xy 323.493204 -404.153984) (xy 323.45202 -404.189674) (xy 323.406176 -404.219139)
			(xy 323.356605 -404.24178) (xy 323.304317 -404.257137) (xy 323.250376 -404.264896) (xy 323.223128 -404.265384)
			(xy 322.359528 -404.265384) (xy 322.332272 -404.264971) (xy 322.278315 -404.257217) (xy 322.22601 -404.241862)
			(xy 322.176423 -404.21922) (xy 322.130564 -404.189751) (xy 322.089365 -404.154055) (xy 322.053666 -404.112859)
			(xy 322.024194 -404.067001) (xy 322.001548 -404.017416) (xy 321.986189 -403.965113) (xy 321.978431 -403.911156)
			(xy 320.54092 -403.911156) (xy 320.533164 -403.9651) (xy 320.517808 -404.017396) (xy 320.495166 -404.066974)
			(xy 320.465699 -404.112824) (xy 320.430006 -404.154015) (xy 320.388815 -404.189706) (xy 320.342963 -404.219172)
			(xy 320.293385 -404.241812) (xy 320.241089 -404.257166) (xy 320.18714 -404.264922) (xy 320.159888 -404.265384)
			(xy 319.296288 -404.265384) (xy 319.269036 -404.264945) (xy 319.215086 -404.257187) (xy 319.162789 -404.24183)
			(xy 319.11321 -404.219187) (xy 319.067359 -404.189718) (xy 319.026167 -404.154024) (xy 318.990475 -404.112832)
			(xy 318.961008 -404.066979) (xy 318.938366 -404.0174) (xy 318.92301 -403.965102) (xy 318.915254 -403.911152)
			(xy 317.477597 -403.911152) (xy 317.469843 -403.965087) (xy 317.454491 -404.017375) (xy 317.431855 -404.066946)
			(xy 317.402395 -404.112791) (xy 317.366711 -404.153977) (xy 317.325529 -404.189667) (xy 317.279688 -404.219132)
			(xy 317.23012 -404.241775) (xy 317.177834 -404.257133) (xy 317.123895 -404.264895) (xy 317.096648 -404.265384)
			(xy 316.233048 -404.265384) (xy 316.205791 -404.264972) (xy 316.151832 -404.25722) (xy 316.099525 -404.241868)
			(xy 316.049935 -404.219226) (xy 316.004073 -404.189758) (xy 315.962872 -404.154062) (xy 315.927171 -404.112865)
			(xy 315.897697 -404.067007) (xy 315.875049 -404.01742) (xy 315.85969 -403.965115) (xy 315.851931 -403.911157)
			(xy 314.414397 -403.911157) (xy 314.406642 -403.965093) (xy 314.391288 -404.017383) (xy 314.368649 -404.066957)
			(xy 314.339186 -404.112804) (xy 314.303497 -404.153991) (xy 314.26231 -404.189681) (xy 314.216464 -404.219145)
			(xy 314.166891 -404.241785) (xy 314.114601 -404.25714) (xy 314.060657 -404.264897) (xy 314.033408 -404.265384)
			(xy 313.169808 -404.265384) (xy 313.142553 -404.26497) (xy 313.088598 -404.257213) (xy 313.036296 -404.241857)
			(xy 312.986711 -404.219213) (xy 312.940854 -404.189744) (xy 312.899658 -404.154048) (xy 312.863961 -404.112852)
			(xy 312.834491 -404.066996) (xy 312.811846 -404.017412) (xy 312.796489 -403.96511) (xy 312.788731 -403.911155)
			(xy 311.351221 -403.911155) (xy 311.343463 -403.965103) (xy 311.328107 -404.0174) (xy 311.305463 -404.066979)
			(xy 311.275994 -404.112831) (xy 311.240299 -404.154022) (xy 311.199105 -404.189713) (xy 311.153251 -404.219179)
			(xy 311.10367 -404.241818) (xy 311.051372 -404.25717) (xy 310.997421 -404.264923) (xy 310.970168 -404.265384)
			(xy 310.106568 -404.265384) (xy 310.079317 -404.264944) (xy 310.025369 -404.257183) (xy 309.973075 -404.241824)
			(xy 309.923498 -404.21918) (xy 309.877649 -404.189711) (xy 309.83646 -404.154017) (xy 309.80077 -404.112825)
			(xy 309.771305 -404.066974) (xy 309.748664 -404.017395) (xy 309.73331 -403.9651) (xy 309.725554 -403.911152)
			(xy 308.287897 -403.911152) (xy 308.280143 -403.96509) (xy 308.26479 -404.017379) (xy 308.242152 -404.066951)
			(xy 308.21269 -404.112798) (xy 308.177004 -404.153984) (xy 308.13582 -404.189674) (xy 308.089976 -404.219139)
			(xy 308.040405 -404.24178) (xy 307.988117 -404.257137) (xy 307.934176 -404.264896) (xy 307.906928 -404.265384)
			(xy 307.043328 -404.265384) (xy 307.016072 -404.264971) (xy 306.962115 -404.257217) (xy 306.90981 -404.241862)
			(xy 306.860223 -404.21922) (xy 306.814364 -404.189751) (xy 306.773165 -404.154055) (xy 306.737466 -404.112859)
			(xy 306.707994 -404.067001) (xy 306.685348 -404.017416) (xy 306.669989 -403.965113) (xy 306.662231 -403.911156)
			(xy 305.22472 -403.911156) (xy 305.216964 -403.9651) (xy 305.201608 -404.017396) (xy 305.178966 -404.066974)
			(xy 305.149499 -404.112824) (xy 305.113806 -404.154015) (xy 305.072615 -404.189706) (xy 305.026763 -404.219172)
			(xy 304.977185 -404.241812) (xy 304.924889 -404.257166) (xy 304.87094 -404.264922) (xy 304.843688 -404.265384)
			(xy 303.980088 -404.265384) (xy 303.952836 -404.264945) (xy 303.898886 -404.257187) (xy 303.846589 -404.24183)
			(xy 303.79701 -404.219187) (xy 303.751159 -404.189718) (xy 303.709967 -404.154024) (xy 303.674275 -404.112832)
			(xy 303.644808 -404.066979) (xy 303.622166 -404.0174) (xy 303.60681 -403.965102) (xy 303.599054 -403.911152)
			(xy 298.836897 -403.911152) (xy 298.840074 -403.920931) (xy 298.852049 -403.983712) (xy 298.856063 -404.0475)
			(xy 298.852049 -404.111288) (xy 298.840074 -404.174069) (xy 298.820324 -404.234855) (xy 298.793112 -404.292686)
			(xy 298.758866 -404.346651) (xy 298.718128 -404.395898) (xy 298.671538 -404.439652) (xy 298.619832 -404.477221)
			(xy 298.563825 -404.508014) (xy 298.504401 -404.531545) (xy 298.442496 -404.547442) (xy 298.379087 -404.555456)
			(xy 298.34713 -404.55596) (xy 298.346876 -404.55596) (xy 298.315131 -404.555422) (xy 298.252136 -404.547497)
			(xy 298.190616 -404.531797) (xy 298.131527 -404.508566) (xy 298.075787 -404.478166) (xy 298.024261 -404.441069)
			(xy 298.000674 -404.419816) (xy 297.993411 -404.413632) (xy 297.975661 -404.406681) (xy 297.956599 -404.406681)
			(xy 297.938849 -404.413632) (xy 297.931586 -404.419816) (xy 297.908028 -404.441107) (xy 297.856512 -404.478235)
			(xy 297.800771 -404.508654) (xy 297.741674 -404.531889) (xy 297.680142 -404.547579) (xy 297.617135 -404.555478)
			(xy 297.585384 -404.55596) (xy 297.58513 -404.55596) (xy 297.553163 -404.555577) (xy 297.489734 -404.547567)
			(xy 297.427809 -404.531671) (xy 297.368364 -404.508138) (xy 297.312338 -404.47734) (xy 297.260613 -404.439763)
			(xy 297.214007 -404.395999) (xy 297.173253 -404.346739) (xy 297.138995 -404.292759) (xy 297.111773 -404.234911)
			(xy 297.092015 -404.174108) (xy 297.080035 -404.111307) (xy 297.07602 -404.0475) (xy 296.316063 -404.0475)
			(xy 296.312049 -404.111288) (xy 296.300074 -404.174069) (xy 296.280324 -404.234855) (xy 296.253112 -404.292686)
			(xy 296.218866 -404.346651) (xy 296.178128 -404.395898) (xy 296.131538 -404.439652) (xy 296.079832 -404.477221)
			(xy 296.023825 -404.508014) (xy 295.964401 -404.531545) (xy 295.902496 -404.547442) (xy 295.839087 -404.555456)
			(xy 295.80713 -404.55596) (xy 295.806876 -404.55596) (xy 295.775131 -404.555422) (xy 295.712136 -404.547497)
			(xy 295.650616 -404.531797) (xy 295.591527 -404.508566) (xy 295.535787 -404.478166) (xy 295.484261 -404.441069)
			(xy 295.460674 -404.419816) (xy 295.453411 -404.413632) (xy 295.435661 -404.406681) (xy 295.416599 -404.406681)
			(xy 295.398849 -404.413632) (xy 295.391586 -404.419816) (xy 295.368028 -404.441107) (xy 295.316512 -404.478235)
			(xy 295.260771 -404.508654) (xy 295.201674 -404.531889) (xy 295.140142 -404.547579) (xy 295.077135 -404.555478)
			(xy 295.045384 -404.55596) (xy 295.04513 -404.55596) (xy 295.013163 -404.555577) (xy 294.949734 -404.547567)
			(xy 294.887809 -404.531671) (xy 294.828364 -404.508138) (xy 294.772338 -404.47734) (xy 294.720613 -404.439763)
			(xy 294.674007 -404.395999) (xy 294.633253 -404.346739) (xy 294.598995 -404.292759) (xy 294.571773 -404.234911)
			(xy 294.552015 -404.174108) (xy 294.540035 -404.111307) (xy 294.53602 -404.0475) (xy 293.926484 -404.0475)
			(xy 293.92247 -404.111293) (xy 293.910493 -404.174079) (xy 293.890741 -404.23487) (xy 293.863525 -404.292705)
			(xy 293.829276 -404.346674) (xy 293.788532 -404.395924) (xy 293.741937 -404.439679) (xy 293.690226 -404.47725)
			(xy 293.634213 -404.508043) (xy 293.574783 -404.531573) (xy 293.512872 -404.547468) (xy 293.449457 -404.555479)
			(xy 293.417498 -404.55596) (xy 293.417244 -404.55596) (xy 293.385498 -404.555442) (xy 293.322502 -404.547512)
			(xy 293.260982 -404.531809) (xy 293.201894 -404.508575) (xy 293.146154 -404.478171) (xy 293.094629 -404.44107)
			(xy 293.071042 -404.419816) (xy 293.063779 -404.413632) (xy 293.046029 -404.406681) (xy 293.026967 -404.406681)
			(xy 293.009217 -404.413632) (xy 293.001954 -404.419816) (xy 292.978367 -404.441074) (xy 292.926858 -404.478206)
			(xy 292.871123 -404.50863) (xy 292.812032 -404.531871) (xy 292.750504 -404.547567) (xy 292.687501 -404.555474)
			(xy 292.655752 -404.55596) (xy 292.655498 -404.55596) (xy 292.623534 -404.555554) (xy 292.56011 -404.547542)
			(xy 292.498191 -404.531643) (xy 292.438752 -404.50811) (xy 292.382731 -404.477312) (xy 292.331013 -404.439736)
			(xy 292.284411 -404.395974) (xy 292.243662 -404.346717) (xy 292.209408 -404.29274) (xy 292.182189 -404.234897)
			(xy 292.162434 -404.174098) (xy 292.150455 -404.111302) (xy 292.146441 -404.0475) (xy 291.386484 -404.0475)
			(xy 291.38247 -404.111293) (xy 291.370493 -404.174079) (xy 291.350741 -404.23487) (xy 291.323525 -404.292705)
			(xy 291.289276 -404.346674) (xy 291.248532 -404.395924) (xy 291.201937 -404.439679) (xy 291.150226 -404.47725)
			(xy 291.094213 -404.508043) (xy 291.034783 -404.531573) (xy 290.972872 -404.547468) (xy 290.909457 -404.555479)
			(xy 290.877498 -404.55596) (xy 290.877244 -404.55596) (xy 290.845498 -404.555442) (xy 290.782502 -404.547512)
			(xy 290.720982 -404.531809) (xy 290.661894 -404.508575) (xy 290.606154 -404.478171) (xy 290.554629 -404.44107)
			(xy 290.531042 -404.419816) (xy 290.523779 -404.413632) (xy 290.506029 -404.406681) (xy 290.486967 -404.406681)
			(xy 290.469217 -404.413632) (xy 290.461954 -404.419816) (xy 290.438367 -404.441074) (xy 290.386858 -404.478206)
			(xy 290.331123 -404.50863) (xy 290.272032 -404.531871) (xy 290.210504 -404.547567) (xy 290.147501 -404.555474)
			(xy 290.115752 -404.55596) (xy 290.115498 -404.55596) (xy 290.083534 -404.555554) (xy 290.02011 -404.547542)
			(xy 289.958191 -404.531643) (xy 289.898752 -404.50811) (xy 289.842731 -404.477312) (xy 289.791013 -404.439736)
			(xy 289.744411 -404.395974) (xy 289.703662 -404.346717) (xy 289.669408 -404.29274) (xy 289.642189 -404.234897)
			(xy 289.622434 -404.174098) (xy 289.610455 -404.111302) (xy 289.606441 -404.0475) (xy 288.846484 -404.0475)
			(xy 288.84247 -404.111293) (xy 288.830493 -404.174079) (xy 288.810741 -404.23487) (xy 288.783525 -404.292705)
			(xy 288.749276 -404.346674) (xy 288.708532 -404.395924) (xy 288.661937 -404.439679) (xy 288.610226 -404.47725)
			(xy 288.554213 -404.508043) (xy 288.494783 -404.531573) (xy 288.432872 -404.547468) (xy 288.369457 -404.555479)
			(xy 288.337498 -404.55596) (xy 288.337244 -404.55596) (xy 288.305498 -404.555442) (xy 288.242502 -404.547512)
			(xy 288.180982 -404.531809) (xy 288.121894 -404.508575) (xy 288.066154 -404.478171) (xy 288.014629 -404.44107)
			(xy 287.991042 -404.419816) (xy 287.983779 -404.413632) (xy 287.966029 -404.406681) (xy 287.946967 -404.406681)
			(xy 287.929217 -404.413632) (xy 287.921954 -404.419816) (xy 287.898367 -404.441074) (xy 287.846858 -404.478206)
			(xy 287.791123 -404.50863) (xy 287.732032 -404.531871) (xy 287.670504 -404.547567) (xy 287.607501 -404.555474)
			(xy 287.575752 -404.55596) (xy 287.575498 -404.55596) (xy 287.543534 -404.555554) (xy 287.48011 -404.547542)
			(xy 287.418191 -404.531643) (xy 287.358752 -404.50811) (xy 287.302731 -404.477312) (xy 287.251013 -404.439736)
			(xy 287.204411 -404.395974) (xy 287.163662 -404.346717) (xy 287.129408 -404.29274) (xy 287.102189 -404.234897)
			(xy 287.082434 -404.174098) (xy 287.070455 -404.111302) (xy 287.066441 -404.0475) (xy 281.686508 -404.0475)
			(xy 281.686508 -405.908764) (xy 281.686047 -405.933716) (xy 281.678246 -405.983008) (xy 281.662829 -406.030472)
			(xy 281.640178 -406.07494) (xy 281.610848 -406.115316) (xy 281.593544 -406.1333) (xy 281.262328 -406.464516)
			(xy 281.244328 -406.481797) (xy 281.203943 -406.511099) (xy 281.159477 -406.533733) (xy 281.11202 -406.549144)
			(xy 281.06274 -406.556952) (xy 281.037792 -406.55748) (xy 278.18334 -406.55748) (xy 278.17335 -406.558673)
			(xy 278.153269 -406.559941) (xy 278.143208 -406.56002) (xy 275.351748 -406.56002) (xy 275.326797 -406.559534)
			(xy 275.277509 -406.551736) (xy 275.230047 -406.536322) (xy 275.185581 -406.513674) (xy 275.145205 -406.484349)
			(xy 275.127212 -406.467056) (xy 275.088096 -406.42794) (xy 275.077426 -406.418067) (xy 275.05188 -406.404223)
			(xy 275.023469 -406.398135) (xy 274.994494 -406.400297) (xy 274.9673 -406.410533) (xy 274.944091 -406.428014)
			(xy 274.926746 -406.451325) (xy 274.921218 -406.46477) (xy 274.908109 -406.502967) (xy 274.874163 -406.576246)
			(xy 274.831847 -406.645033) (xy 274.781748 -406.708375) (xy 274.753578 -406.737312) (xy 274.459335 -407.031749)
			(xy 304.945298 -407.031749) (xy 304.945298 -406.977251) (xy 304.953054 -406.923307) (xy 304.968408 -406.871016)
			(xy 304.991047 -406.821442) (xy 305.02051 -406.775595) (xy 305.056199 -406.734407) (xy 305.097385 -406.698718)
			(xy 305.143232 -406.669252) (xy 305.192805 -406.646612) (xy 305.245095 -406.631257) (xy 305.299039 -406.623499)
			(xy 305.326288 -406.623012) (xy 306.189888 -406.623012) (xy 306.217143 -406.623434) (xy 306.271098 -406.63119)
			(xy 306.3234 -406.646546) (xy 306.372984 -406.669189) (xy 306.418841 -406.698658) (xy 306.460038 -406.734354)
			(xy 306.495735 -406.775549) (xy 306.525205 -406.821405) (xy 306.54785 -406.870989) (xy 306.563207 -406.92329)
			(xy 306.570965 -406.977245) (xy 306.570965 -407.031753) (xy 308.008475 -407.031753) (xy 308.008475 -406.977247)
			(xy 308.016233 -406.923297) (xy 308.031589 -406.870999) (xy 308.054233 -406.82142) (xy 308.083702 -406.775568)
			(xy 308.119397 -406.734377) (xy 308.16059 -406.698685) (xy 308.206445 -406.669219) (xy 308.256026 -406.64658)
			(xy 308.308324 -406.631227) (xy 308.362275 -406.623473) (xy 308.389528 -406.623012) (xy 309.253128 -406.623012)
			(xy 309.280379 -406.62346) (xy 309.334327 -406.63122) (xy 309.386621 -406.646578) (xy 309.436197 -406.669222)
			(xy 309.482047 -406.698691) (xy 309.523236 -406.734384) (xy 309.558926 -406.775576) (xy 309.588391 -406.821427)
			(xy 309.611032 -406.871005) (xy 309.626386 -406.923301) (xy 309.634142 -406.977249) (xy 309.634142 -407.031748)
			(xy 311.071798 -407.031748) (xy 311.071798 -406.977252) (xy 311.079553 -406.92331) (xy 311.094906 -406.87102)
			(xy 311.117544 -406.821448) (xy 311.147005 -406.775601) (xy 311.182692 -406.734414) (xy 311.223876 -406.698725)
			(xy 311.26972 -406.669259) (xy 311.31929 -406.646617) (xy 311.371578 -406.63126) (xy 311.42552 -406.6235)
			(xy 311.452768 -406.623012) (xy 312.316368 -406.623012) (xy 312.343624 -406.623433) (xy 312.397581 -406.631186)
			(xy 312.449886 -406.64654) (xy 312.499472 -406.669182) (xy 312.545332 -406.698651) (xy 312.586531 -406.734347)
			(xy 312.62223 -406.775542) (xy 312.651702 -406.821399) (xy 312.674348 -406.870984) (xy 312.689707 -406.923288)
			(xy 312.697465 -406.977244) (xy 312.697465 -407.031752) (xy 314.134975 -407.031752) (xy 314.134975 -406.977248)
			(xy 314.142732 -406.923299) (xy 314.158088 -406.871004) (xy 314.18073 -406.821426) (xy 314.210197 -406.775575)
			(xy 314.245889 -406.734384) (xy 314.287081 -406.698692) (xy 314.332933 -406.669226) (xy 314.382511 -406.646585)
			(xy 314.434807 -406.63123) (xy 314.488756 -406.623475) (xy 314.516008 -406.623012) (xy 315.379608 -406.623012)
			(xy 315.40686 -406.623458) (xy 315.46081 -406.631216) (xy 315.513107 -406.646573) (xy 315.562685 -406.669216)
			(xy 315.608537 -406.698684) (xy 315.649729 -406.734377) (xy 315.685421 -406.775569) (xy 315.714888 -406.821422)
			(xy 315.73753 -406.871001) (xy 315.752885 -406.923298) (xy 315.760642 -406.977248) (xy 315.760642 -407.031752)
			(xy 315.760642 -407.031754) (xy 317.198175 -407.031754) (xy 317.198175 -406.977246) (xy 317.205933 -406.923294)
			(xy 317.221291 -406.870995) (xy 317.243936 -406.821414) (xy 317.273407 -406.775561) (xy 317.309104 -406.73437)
			(xy 317.3503 -406.698678) (xy 317.396157 -406.669213) (xy 317.44574 -406.646574) (xy 317.498041 -406.631223)
			(xy 317.551994 -406.623472) (xy 317.579248 -406.623012) (xy 318.442848 -406.623012) (xy 318.470098 -406.623461)
			(xy 318.524044 -406.631224) (xy 318.576336 -406.646584) (xy 318.625909 -406.669229) (xy 318.671756 -406.698698)
			(xy 318.712943 -406.734391) (xy 318.748631 -406.775582) (xy 318.778094 -406.821433) (xy 318.800733 -406.87101)
			(xy 318.816087 -406.923303) (xy 318.823842 -406.97725) (xy 318.823842 -407.031749) (xy 320.261498 -407.031749)
			(xy 320.261498 -406.977251) (xy 320.269254 -406.923307) (xy 320.284608 -406.871016) (xy 320.307247 -406.821442)
			(xy 320.33671 -406.775595) (xy 320.372399 -406.734407) (xy 320.413585 -406.698718) (xy 320.459432 -406.669252)
			(xy 320.509005 -406.646612) (xy 320.561295 -406.631257) (xy 320.615239 -406.623499) (xy 320.642488 -406.623012)
			(xy 321.506088 -406.623012) (xy 321.533343 -406.623434) (xy 321.587298 -406.63119) (xy 321.6396 -406.646546)
			(xy 321.689184 -406.669189) (xy 321.735041 -406.698658) (xy 321.776238 -406.734354) (xy 321.811935 -406.775549)
			(xy 321.841405 -406.821405) (xy 321.86405 -406.870989) (xy 321.879407 -406.92329) (xy 321.887165 -406.977245)
			(xy 321.887165 -407.031753) (xy 323.324675 -407.031753) (xy 323.324675 -406.977247) (xy 323.332433 -406.923297)
			(xy 323.347789 -406.870999) (xy 323.370433 -406.82142) (xy 323.399902 -406.775568) (xy 323.435597 -406.734377)
			(xy 323.47679 -406.698685) (xy 323.522645 -406.669219) (xy 323.572226 -406.64658) (xy 323.624524 -406.631227)
			(xy 323.678475 -406.623473) (xy 323.705728 -406.623012) (xy 324.569328 -406.623012) (xy 324.596579 -406.62346)
			(xy 324.650527 -406.63122) (xy 324.702821 -406.646578) (xy 324.752397 -406.669222) (xy 324.798247 -406.698691)
			(xy 324.839436 -406.734384) (xy 324.875126 -406.775576) (xy 324.904591 -406.821427) (xy 324.927232 -406.871005)
			(xy 324.942586 -406.923301) (xy 324.950342 -406.977249) (xy 324.950342 -407.031748) (xy 326.387998 -407.031748)
			(xy 326.387998 -406.977252) (xy 326.395753 -406.92331) (xy 326.411106 -406.87102) (xy 326.433744 -406.821448)
			(xy 326.463205 -406.775601) (xy 326.498892 -406.734414) (xy 326.540076 -406.698725) (xy 326.58592 -406.669259)
			(xy 326.63549 -406.646617) (xy 326.687778 -406.63126) (xy 326.74172 -406.6235) (xy 326.768968 -406.623012)
			(xy 327.632568 -406.623012) (xy 327.659824 -406.623433) (xy 327.713781 -406.631186) (xy 327.766086 -406.64654)
			(xy 327.815672 -406.669182) (xy 327.861532 -406.698651) (xy 327.902731 -406.734347) (xy 327.93843 -406.775542)
			(xy 327.967902 -406.821399) (xy 327.990548 -406.870984) (xy 328.005907 -406.923288) (xy 328.013665 -406.977244)
			(xy 328.013665 -407.031752) (xy 329.451175 -407.031752) (xy 329.451175 -406.977248) (xy 329.458932 -406.923299)
			(xy 329.474288 -406.871004) (xy 329.49693 -406.821426) (xy 329.526397 -406.775575) (xy 329.562089 -406.734384)
			(xy 329.603281 -406.698692) (xy 329.649133 -406.669226) (xy 329.698711 -406.646585) (xy 329.751007 -406.63123)
			(xy 329.804956 -406.623475) (xy 329.832208 -406.623012) (xy 330.695808 -406.623012) (xy 330.72306 -406.623458)
			(xy 330.77701 -406.631216) (xy 330.829307 -406.646573) (xy 330.878885 -406.669216) (xy 330.924737 -406.698684)
			(xy 330.965929 -406.734377) (xy 331.001621 -406.775569) (xy 331.031088 -406.821422) (xy 331.05373 -406.871001)
			(xy 331.069085 -406.923298) (xy 331.076842 -406.977248) (xy 331.076842 -407.031752) (xy 331.076842 -407.031754)
			(xy 332.514375 -407.031754) (xy 332.514375 -406.977246) (xy 332.522133 -406.923294) (xy 332.537491 -406.870995)
			(xy 332.560136 -406.821414) (xy 332.589607 -406.775561) (xy 332.625304 -406.73437) (xy 332.6665 -406.698678)
			(xy 332.712357 -406.669213) (xy 332.76194 -406.646574) (xy 332.814241 -406.631223) (xy 332.868194 -406.623472)
			(xy 332.895448 -406.623012) (xy 333.759048 -406.623012) (xy 333.786298 -406.623461) (xy 333.840244 -406.631224)
			(xy 333.892536 -406.646584) (xy 333.942109 -406.669229) (xy 333.987956 -406.698698) (xy 334.029143 -406.734391)
			(xy 334.064831 -406.775582) (xy 334.094294 -406.821433) (xy 334.116933 -406.87101) (xy 334.132287 -406.923303)
			(xy 334.140042 -406.97725) (xy 334.140042 -407.031749) (xy 335.577698 -407.031749) (xy 335.577698 -406.977251)
			(xy 335.585454 -406.923307) (xy 335.600808 -406.871016) (xy 335.623447 -406.821442) (xy 335.65291 -406.775595)
			(xy 335.688599 -406.734407) (xy 335.729785 -406.698718) (xy 335.775632 -406.669252) (xy 335.825205 -406.646612)
			(xy 335.877495 -406.631257) (xy 335.931439 -406.623499) (xy 335.958688 -406.623012) (xy 336.822288 -406.623012)
			(xy 336.849543 -406.623434) (xy 336.903498 -406.63119) (xy 336.9558 -406.646546) (xy 337.005384 -406.669189)
			(xy 337.051241 -406.698658) (xy 337.092438 -406.734354) (xy 337.128135 -406.775549) (xy 337.157605 -406.821405)
			(xy 337.18025 -406.870989) (xy 337.195607 -406.92329) (xy 337.203365 -406.977245) (xy 337.203365 -407.031753)
			(xy 338.640875 -407.031753) (xy 338.640875 -406.977247) (xy 338.648633 -406.923297) (xy 338.663989 -406.870999)
			(xy 338.686633 -406.82142) (xy 338.716102 -406.775568) (xy 338.751797 -406.734377) (xy 338.79299 -406.698685)
			(xy 338.838845 -406.669219) (xy 338.888426 -406.64658) (xy 338.940724 -406.631227) (xy 338.994675 -406.623473)
			(xy 339.021928 -406.623012) (xy 339.885528 -406.623012) (xy 339.912779 -406.62346) (xy 339.966727 -406.63122)
			(xy 340.019021 -406.646578) (xy 340.068597 -406.669222) (xy 340.114447 -406.698691) (xy 340.155636 -406.734384)
			(xy 340.191326 -406.775576) (xy 340.220791 -406.821427) (xy 340.243432 -406.871005) (xy 340.258786 -406.923301)
			(xy 340.266542 -406.977249) (xy 340.266542 -407.031748) (xy 341.704198 -407.031748) (xy 341.704198 -406.977252)
			(xy 341.711953 -406.92331) (xy 341.727306 -406.87102) (xy 341.749944 -406.821448) (xy 341.779405 -406.775601)
			(xy 341.815092 -406.734414) (xy 341.856276 -406.698725) (xy 341.90212 -406.669259) (xy 341.95169 -406.646617)
			(xy 342.003978 -406.63126) (xy 342.05792 -406.6235) (xy 342.085168 -406.623012) (xy 342.948768 -406.623012)
			(xy 342.976024 -406.623433) (xy 343.029981 -406.631186) (xy 343.082286 -406.64654) (xy 343.131872 -406.669182)
			(xy 343.177732 -406.698651) (xy 343.218931 -406.734347) (xy 343.25463 -406.775542) (xy 343.284102 -406.821399)
			(xy 343.306748 -406.870984) (xy 343.322107 -406.923288) (xy 343.329865 -406.977244) (xy 343.329865 -407.031752)
			(xy 344.767375 -407.031752) (xy 344.767375 -406.977248) (xy 344.775132 -406.923299) (xy 344.790488 -406.871004)
			(xy 344.81313 -406.821426) (xy 344.842597 -406.775575) (xy 344.878289 -406.734384) (xy 344.919481 -406.698692)
			(xy 344.965333 -406.669226) (xy 345.014911 -406.646585) (xy 345.067207 -406.63123) (xy 345.121156 -406.623475)
			(xy 345.148408 -406.623012) (xy 346.012008 -406.623012) (xy 346.03926 -406.623458) (xy 346.09321 -406.631216)
			(xy 346.145507 -406.646573) (xy 346.195085 -406.669216) (xy 346.240937 -406.698684) (xy 346.282129 -406.734377)
			(xy 346.317821 -406.775569) (xy 346.347288 -406.821422) (xy 346.36993 -406.871001) (xy 346.385285 -406.923298)
			(xy 346.393042 -406.977248) (xy 346.393042 -407.031752) (xy 346.393042 -407.031754) (xy 347.830575 -407.031754)
			(xy 347.830575 -406.977246) (xy 347.838333 -406.923294) (xy 347.853691 -406.870995) (xy 347.876336 -406.821414)
			(xy 347.905807 -406.775561) (xy 347.941504 -406.73437) (xy 347.9827 -406.698678) (xy 348.028557 -406.669213)
			(xy 348.07814 -406.646574) (xy 348.130441 -406.631223) (xy 348.184394 -406.623472) (xy 348.211648 -406.623012)
			(xy 349.075248 -406.623012) (xy 349.102498 -406.623461) (xy 349.156444 -406.631224) (xy 349.208736 -406.646584)
			(xy 349.258309 -406.669229) (xy 349.304156 -406.698698) (xy 349.345343 -406.734391) (xy 349.381031 -406.775582)
			(xy 349.410494 -406.821433) (xy 349.433133 -406.87101) (xy 349.448487 -406.923303) (xy 349.456242 -406.97725)
			(xy 349.456242 -407.031749) (xy 350.893898 -407.031749) (xy 350.893898 -406.977251) (xy 350.901654 -406.923307)
			(xy 350.917008 -406.871016) (xy 350.939647 -406.821442) (xy 350.96911 -406.775595) (xy 351.004799 -406.734407)
			(xy 351.045985 -406.698718) (xy 351.091832 -406.669252) (xy 351.141405 -406.646612) (xy 351.193695 -406.631257)
			(xy 351.247639 -406.623499) (xy 351.274888 -406.623012) (xy 352.138488 -406.623012) (xy 352.165743 -406.623434)
			(xy 352.219698 -406.63119) (xy 352.272 -406.646546) (xy 352.321584 -406.669189) (xy 352.367441 -406.698658)
			(xy 352.408638 -406.734354) (xy 352.444335 -406.775549) (xy 352.473805 -406.821405) (xy 352.49645 -406.870989)
			(xy 352.511807 -406.92329) (xy 352.519565 -406.977245) (xy 352.519565 -407.031753) (xy 372.388075 -407.031753)
			(xy 372.388075 -406.977247) (xy 372.395833 -406.923296) (xy 372.411189 -406.870999) (xy 372.433833 -406.821419)
			(xy 372.463302 -406.775567) (xy 372.498997 -406.734376) (xy 372.540191 -406.698684) (xy 372.586046 -406.669219)
			(xy 372.635627 -406.646579) (xy 372.687926 -406.631226) (xy 372.741877 -406.623473) (xy 372.76913 -406.623012)
			(xy 373.63273 -406.623012) (xy 373.659981 -406.62346) (xy 373.713929 -406.63122) (xy 373.766222 -406.646579)
			(xy 373.815799 -406.669223) (xy 373.861648 -406.698691) (xy 373.902836 -406.734385) (xy 373.938527 -406.775576)
			(xy 373.967992 -406.821428) (xy 373.990632 -406.871006) (xy 374.005986 -406.923301) (xy 374.013742 -406.977249)
			(xy 374.013742 -407.031748) (xy 375.451398 -407.031748) (xy 375.451398 -406.977252) (xy 375.459153 -406.923309)
			(xy 375.474506 -406.87102) (xy 375.497144 -406.821447) (xy 375.526606 -406.775601) (xy 375.562292 -406.734414)
			(xy 375.603477 -406.698724) (xy 375.649321 -406.669258) (xy 375.698892 -406.646617) (xy 375.75118 -406.63126)
			(xy 375.805122 -406.6235) (xy 375.83237 -406.623012) (xy 376.69597 -406.623012) (xy 376.723226 -406.623433)
			(xy 376.777183 -406.631187) (xy 376.829487 -406.646541) (xy 376.879074 -406.669183) (xy 376.924933 -406.698652)
			(xy 376.966131 -406.734347) (xy 377.00183 -406.775543) (xy 377.031303 -406.8214) (xy 377.053948 -406.870985)
			(xy 377.069307 -406.923288) (xy 377.077065 -406.977244) (xy 377.077065 -407.031752) (xy 378.514575 -407.031752)
			(xy 378.514575 -406.977248) (xy 378.522332 -406.923299) (xy 378.537688 -406.871003) (xy 378.56033 -406.821425)
			(xy 378.589797 -406.775574) (xy 378.62549 -406.734383) (xy 378.666682 -406.698691) (xy 378.712534 -406.669225)
			(xy 378.762113 -406.646584) (xy 378.814409 -406.63123) (xy 378.868358 -406.623475) (xy 378.89561 -406.623012)
			(xy 379.75921 -406.623012) (xy 379.786462 -406.623459) (xy 379.840412 -406.631217) (xy 379.892708 -406.646573)
			(xy 379.942287 -406.669216) (xy 379.988138 -406.698684) (xy 380.029329 -406.734378) (xy 380.065022 -406.77557)
			(xy 380.094489 -406.821422) (xy 380.11713 -406.871001) (xy 380.132486 -406.923298) (xy 380.140242 -406.977248)
			(xy 380.140242 -407.031748) (xy 381.577898 -407.031748) (xy 381.577898 -406.977252) (xy 381.585653 -406.923312)
			(xy 381.601005 -406.871024) (xy 381.623641 -406.821453) (xy 381.653101 -406.775607) (xy 381.688785 -406.734421)
			(xy 381.729967 -406.698731) (xy 381.775809 -406.669265) (xy 381.825377 -406.646622) (xy 381.877663 -406.631264)
			(xy 381.931603 -406.623502) (xy 381.95885 -406.623012) (xy 382.82245 -406.623012) (xy 382.849707 -406.623431)
			(xy 382.903666 -406.631183) (xy 382.955973 -406.646536) (xy 383.005562 -406.669176) (xy 383.051423 -406.698645)
			(xy 383.092624 -406.73434) (xy 383.128325 -406.775536) (xy 383.1578 -406.821394) (xy 383.180447 -406.870981)
			(xy 383.195806 -406.923285) (xy 383.203565 -406.977243) (xy 383.203565 -407.031749) (xy 384.641098 -407.031749)
			(xy 384.641098 -406.977251) (xy 384.648854 -406.923307) (xy 384.664208 -406.871016) (xy 384.686847 -406.821442)
			(xy 384.716311 -406.775594) (xy 384.751999 -406.734406) (xy 384.793186 -406.698717) (xy 384.839033 -406.669252)
			(xy 384.888606 -406.646611) (xy 384.940897 -406.631256) (xy 384.994841 -406.623499) (xy 385.02209 -406.623012)
			(xy 385.88569 -406.623012) (xy 385.912945 -406.623434) (xy 385.9669 -406.63119) (xy 386.019202 -406.646546)
			(xy 386.068786 -406.66919) (xy 386.114642 -406.698659) (xy 386.155838 -406.734354) (xy 386.191535 -406.77555)
			(xy 386.221006 -406.821406) (xy 386.24365 -406.870989) (xy 386.259007 -406.923291) (xy 386.266765 -406.977245)
			(xy 386.266765 -407.031753) (xy 387.704275 -407.031753) (xy 387.704275 -406.977247) (xy 387.712033 -406.923296)
			(xy 387.727389 -406.870999) (xy 387.750033 -406.821419) (xy 387.779502 -406.775567) (xy 387.815197 -406.734376)
			(xy 387.856391 -406.698684) (xy 387.902246 -406.669219) (xy 387.951827 -406.646579) (xy 388.004126 -406.631226)
			(xy 388.058077 -406.623473) (xy 388.08533 -406.623012) (xy 388.94893 -406.623012) (xy 388.976181 -406.62346)
			(xy 389.030129 -406.63122) (xy 389.082422 -406.646579) (xy 389.131999 -406.669223) (xy 389.177848 -406.698691)
			(xy 389.219036 -406.734385) (xy 389.254727 -406.775576) (xy 389.284192 -406.821428) (xy 389.306832 -406.871006)
			(xy 389.322186 -406.923301) (xy 389.329942 -406.977249) (xy 389.329942 -407.031748) (xy 390.767598 -407.031748)
			(xy 390.767598 -406.977252) (xy 390.775353 -406.923309) (xy 390.790706 -406.87102) (xy 390.813344 -406.821447)
			(xy 390.842806 -406.775601) (xy 390.878492 -406.734414) (xy 390.919677 -406.698724) (xy 390.965521 -406.669258)
			(xy 391.015092 -406.646617) (xy 391.06738 -406.63126) (xy 391.121322 -406.6235) (xy 391.14857 -406.623012)
			(xy 392.01217 -406.623012) (xy 392.039426 -406.623433) (xy 392.093383 -406.631187) (xy 392.145687 -406.646541)
			(xy 392.195274 -406.669183) (xy 392.241133 -406.698652) (xy 392.282331 -406.734347) (xy 392.31803 -406.775543)
			(xy 392.347503 -406.8214) (xy 392.370148 -406.870985) (xy 392.385507 -406.923288) (xy 392.393265 -406.977244)
			(xy 392.393265 -407.031752) (xy 393.830775 -407.031752) (xy 393.830775 -406.977248) (xy 393.838532 -406.923299)
			(xy 393.853888 -406.871003) (xy 393.87653 -406.821425) (xy 393.905997 -406.775574) (xy 393.94169 -406.734383)
			(xy 393.982882 -406.698691) (xy 394.028734 -406.669225) (xy 394.078313 -406.646584) (xy 394.130609 -406.63123)
			(xy 394.184558 -406.623475) (xy 394.21181 -406.623012) (xy 395.07541 -406.623012) (xy 395.102662 -406.623459)
			(xy 395.156612 -406.631217) (xy 395.208908 -406.646573) (xy 395.258487 -406.669216) (xy 395.304338 -406.698684)
			(xy 395.345529 -406.734378) (xy 395.381222 -406.77557) (xy 395.410689 -406.821422) (xy 395.43333 -406.871001)
			(xy 395.448686 -406.923298) (xy 395.456442 -406.977248) (xy 395.456442 -407.031748) (xy 396.894098 -407.031748)
			(xy 396.894098 -406.977252) (xy 396.901853 -406.923312) (xy 396.917205 -406.871024) (xy 396.939841 -406.821453)
			(xy 396.969301 -406.775607) (xy 397.004985 -406.734421) (xy 397.046167 -406.698731) (xy 397.092009 -406.669265)
			(xy 397.141577 -406.646622) (xy 397.193863 -406.631264) (xy 397.247803 -406.623502) (xy 397.27505 -406.623012)
			(xy 398.13865 -406.623012) (xy 398.165907 -406.623431) (xy 398.219866 -406.631183) (xy 398.272173 -406.646536)
			(xy 398.321762 -406.669176) (xy 398.367623 -406.698645) (xy 398.408824 -406.73434) (xy 398.444525 -406.775536)
			(xy 398.474 -406.821394) (xy 398.496647 -406.870981) (xy 398.512006 -406.923285) (xy 398.519765 -406.977243)
			(xy 398.519765 -407.031749) (xy 399.957298 -407.031749) (xy 399.957298 -406.977251) (xy 399.965054 -406.923307)
			(xy 399.980408 -406.871016) (xy 400.003047 -406.821442) (xy 400.032511 -406.775594) (xy 400.068199 -406.734406)
			(xy 400.109386 -406.698717) (xy 400.155233 -406.669252) (xy 400.204806 -406.646611) (xy 400.257097 -406.631256)
			(xy 400.311041 -406.623499) (xy 400.33829 -406.623012) (xy 401.20189 -406.623012) (xy 401.229145 -406.623434)
			(xy 401.2831 -406.63119) (xy 401.335402 -406.646546) (xy 401.384986 -406.66919) (xy 401.430842 -406.698659)
			(xy 401.472038 -406.734354) (xy 401.507735 -406.77555) (xy 401.537206 -406.821406) (xy 401.55985 -406.870989)
			(xy 401.575207 -406.923291) (xy 401.582965 -406.977245) (xy 401.582965 -407.031753) (xy 403.020475 -407.031753)
			(xy 403.020475 -406.977247) (xy 403.028233 -406.923296) (xy 403.043589 -406.870999) (xy 403.066233 -406.821419)
			(xy 403.095702 -406.775567) (xy 403.131397 -406.734376) (xy 403.172591 -406.698684) (xy 403.218446 -406.669219)
			(xy 403.268027 -406.646579) (xy 403.320326 -406.631226) (xy 403.374277 -406.623473) (xy 403.40153 -406.623012)
			(xy 404.26513 -406.623012) (xy 404.292381 -406.62346) (xy 404.346329 -406.63122) (xy 404.398622 -406.646579)
			(xy 404.448199 -406.669223) (xy 404.494048 -406.698691) (xy 404.535236 -406.734385) (xy 404.570927 -406.775576)
			(xy 404.600392 -406.821428) (xy 404.623032 -406.871006) (xy 404.638386 -406.923301) (xy 404.646142 -406.977249)
			(xy 404.646142 -407.031748) (xy 406.083798 -407.031748) (xy 406.083798 -406.977252) (xy 406.091553 -406.923309)
			(xy 406.106906 -406.87102) (xy 406.129544 -406.821447) (xy 406.159006 -406.775601) (xy 406.194692 -406.734414)
			(xy 406.235877 -406.698724) (xy 406.281721 -406.669258) (xy 406.331292 -406.646617) (xy 406.38358 -406.63126)
			(xy 406.437522 -406.6235) (xy 406.46477 -406.623012) (xy 407.32837 -406.623012) (xy 407.355626 -406.623433)
			(xy 407.409583 -406.631187) (xy 407.461887 -406.646541) (xy 407.511474 -406.669183) (xy 407.557333 -406.698652)
			(xy 407.598531 -406.734347) (xy 407.63423 -406.775543) (xy 407.663703 -406.8214) (xy 407.686348 -406.870985)
			(xy 407.701707 -406.923288) (xy 407.709465 -406.977244) (xy 407.709465 -407.031752) (xy 409.146975 -407.031752)
			(xy 409.146975 -406.977248) (xy 409.154732 -406.923299) (xy 409.170088 -406.871003) (xy 409.19273 -406.821425)
			(xy 409.222197 -406.775574) (xy 409.25789 -406.734383) (xy 409.299082 -406.698691) (xy 409.344934 -406.669225)
			(xy 409.394513 -406.646584) (xy 409.446809 -406.63123) (xy 409.500758 -406.623475) (xy 409.52801 -406.623012)
			(xy 410.39161 -406.623012) (xy 410.418862 -406.623459) (xy 410.472812 -406.631217) (xy 410.525108 -406.646573)
			(xy 410.574687 -406.669216) (xy 410.620538 -406.698684) (xy 410.661729 -406.734378) (xy 410.697422 -406.77557)
			(xy 410.726889 -406.821422) (xy 410.74953 -406.871001) (xy 410.764886 -406.923298) (xy 410.772642 -406.977248)
			(xy 410.772642 -407.031748) (xy 412.210298 -407.031748) (xy 412.210298 -406.977252) (xy 412.218053 -406.923312)
			(xy 412.233405 -406.871024) (xy 412.256041 -406.821453) (xy 412.285501 -406.775607) (xy 412.321185 -406.734421)
			(xy 412.362367 -406.698731) (xy 412.408209 -406.669265) (xy 412.457777 -406.646622) (xy 412.510063 -406.631264)
			(xy 412.564003 -406.623502) (xy 412.59125 -406.623012) (xy 413.45485 -406.623012) (xy 413.482107 -406.623431)
			(xy 413.536066 -406.631183) (xy 413.588373 -406.646536) (xy 413.637962 -406.669176) (xy 413.683823 -406.698645)
			(xy 413.725024 -406.73434) (xy 413.760725 -406.775536) (xy 413.7902 -406.821394) (xy 413.812847 -406.870981)
			(xy 413.828206 -406.923285) (xy 413.835965 -406.977243) (xy 413.835965 -407.031749) (xy 415.273498 -407.031749)
			(xy 415.273498 -406.977251) (xy 415.281254 -406.923307) (xy 415.296608 -406.871016) (xy 415.319247 -406.821442)
			(xy 415.348711 -406.775594) (xy 415.384399 -406.734406) (xy 415.425586 -406.698717) (xy 415.471433 -406.669252)
			(xy 415.521006 -406.646611) (xy 415.573297 -406.631256) (xy 415.627241 -406.623499) (xy 415.65449 -406.623012)
			(xy 416.51809 -406.623012) (xy 416.545345 -406.623434) (xy 416.5993 -406.63119) (xy 416.651602 -406.646546)
			(xy 416.701186 -406.66919) (xy 416.747042 -406.698659) (xy 416.788238 -406.734354) (xy 416.823935 -406.77555)
			(xy 416.853406 -406.821406) (xy 416.87605 -406.870989) (xy 416.891407 -406.923291) (xy 416.899165 -406.977245)
			(xy 416.899165 -407.031753) (xy 418.336675 -407.031753) (xy 418.336675 -406.977247) (xy 418.344433 -406.923296)
			(xy 418.359789 -406.870999) (xy 418.382433 -406.821419) (xy 418.411902 -406.775567) (xy 418.447597 -406.734376)
			(xy 418.488791 -406.698684) (xy 418.534646 -406.669219) (xy 418.584227 -406.646579) (xy 418.636526 -406.631226)
			(xy 418.690477 -406.623473) (xy 418.71773 -406.623012) (xy 419.58133 -406.623012) (xy 419.608581 -406.62346)
			(xy 419.662529 -406.63122) (xy 419.714822 -406.646579) (xy 419.764399 -406.669223) (xy 419.810248 -406.698691)
			(xy 419.851436 -406.734385) (xy 419.887127 -406.775576) (xy 419.916592 -406.821428) (xy 419.939232 -406.871006)
			(xy 419.954586 -406.923301) (xy 419.962342 -406.977249) (xy 419.962342 -407.031751) (xy 419.954586 -407.085699)
			(xy 419.939232 -407.137994) (xy 419.916592 -407.187572) (xy 419.887127 -407.233424) (xy 419.851436 -407.274615)
			(xy 419.810248 -407.310309) (xy 419.764399 -407.339777) (xy 419.714822 -407.362421) (xy 419.662529 -407.37778)
			(xy 419.608581 -407.38554) (xy 419.58133 -407.386028) (xy 418.71773 -407.386028) (xy 418.690477 -407.385527)
			(xy 418.636526 -407.377774) (xy 418.584227 -407.362421) (xy 418.534646 -407.339781) (xy 418.488791 -407.310316)
			(xy 418.447597 -407.274624) (xy 418.411902 -407.233433) (xy 418.382433 -407.187581) (xy 418.359789 -407.138001)
			(xy 418.344433 -407.085704) (xy 418.336675 -407.031753) (xy 416.899165 -407.031753) (xy 416.899165 -407.031755)
			(xy 416.891407 -407.085709) (xy 416.87605 -407.138011) (xy 416.853406 -407.187594) (xy 416.823935 -407.23345)
			(xy 416.788238 -407.274646) (xy 416.747042 -407.310341) (xy 416.701186 -407.33981) (xy 416.651602 -407.362454)
			(xy 416.5993 -407.37781) (xy 416.545345 -407.385566) (xy 416.51809 -407.386028) (xy 415.65449 -407.386028)
			(xy 415.627241 -407.385501) (xy 415.573297 -407.377744) (xy 415.521006 -407.362389) (xy 415.471433 -407.339748)
			(xy 415.425586 -407.310283) (xy 415.384399 -407.274594) (xy 415.348711 -407.233406) (xy 415.319247 -407.187558)
			(xy 415.296608 -407.137984) (xy 415.281254 -407.085693) (xy 415.273498 -407.031749) (xy 413.835965 -407.031749)
			(xy 413.835965 -407.031757) (xy 413.828206 -407.085715) (xy 413.812847 -407.138019) (xy 413.7902 -407.187606)
			(xy 413.760725 -407.233464) (xy 413.725024 -407.27466) (xy 413.683823 -407.310355) (xy 413.637962 -407.339824)
			(xy 413.588373 -407.362464) (xy 413.536066 -407.377817) (xy 413.482107 -407.385569) (xy 413.45485 -407.386028)
			(xy 412.59125 -407.386028) (xy 412.564003 -407.385498) (xy 412.510063 -407.377736) (xy 412.457777 -407.362378)
			(xy 412.408209 -407.339735) (xy 412.362367 -407.310269) (xy 412.321185 -407.274579) (xy 412.285501 -407.233393)
			(xy 412.256041 -407.187547) (xy 412.233405 -407.137976) (xy 412.218053 -407.085688) (xy 412.210298 -407.031748)
			(xy 410.772642 -407.031748) (xy 410.772642 -407.031752) (xy 410.764886 -407.085702) (xy 410.74953 -407.137999)
			(xy 410.726889 -407.187578) (xy 410.697422 -407.23343) (xy 410.661729 -407.274622) (xy 410.620538 -407.310316)
			(xy 410.574687 -407.339784) (xy 410.525108 -407.362427) (xy 410.472812 -407.377783) (xy 410.418862 -407.385541)
			(xy 410.39161 -407.386028) (xy 409.52801 -407.386028) (xy 409.500758 -407.385525) (xy 409.446809 -407.37777)
			(xy 409.394513 -407.362416) (xy 409.344934 -407.339775) (xy 409.299082 -407.310309) (xy 409.25789 -407.274617)
			(xy 409.222197 -407.233426) (xy 409.19273 -407.187575) (xy 409.170088 -407.137997) (xy 409.154732 -407.085701)
			(xy 409.146975 -407.031752) (xy 407.709465 -407.031752) (xy 407.709465 -407.031756) (xy 407.701707 -407.085712)
			(xy 407.686348 -407.138015) (xy 407.663703 -407.1876) (xy 407.63423 -407.233457) (xy 407.598531 -407.274653)
			(xy 407.557333 -407.310348) (xy 407.511474 -407.339817) (xy 407.461887 -407.362459) (xy 407.409583 -407.377813)
			(xy 407.355626 -407.385567) (xy 407.32837 -407.386028) (xy 406.46477 -407.386028) (xy 406.437522 -407.3855)
			(xy 406.38358 -407.37774) (xy 406.331292 -407.362383) (xy 406.281721 -407.339742) (xy 406.235877 -407.310276)
			(xy 406.194692 -407.274586) (xy 406.159006 -407.233399) (xy 406.129544 -407.187553) (xy 406.106906 -407.13798)
			(xy 406.091553 -407.085691) (xy 406.083798 -407.031748) (xy 404.646142 -407.031748) (xy 404.646142 -407.031751)
			(xy 404.638386 -407.085699) (xy 404.623032 -407.137994) (xy 404.600392 -407.187572) (xy 404.570927 -407.233424)
			(xy 404.535236 -407.274615) (xy 404.494048 -407.310309) (xy 404.448199 -407.339777) (xy 404.398622 -407.362421)
			(xy 404.346329 -407.37778) (xy 404.292381 -407.38554) (xy 404.26513 -407.386028) (xy 403.40153 -407.386028)
			(xy 403.374277 -407.385527) (xy 403.320326 -407.377774) (xy 403.268027 -407.362421) (xy 403.218446 -407.339781)
			(xy 403.172591 -407.310316) (xy 403.131397 -407.274624) (xy 403.095702 -407.233433) (xy 403.066233 -407.187581)
			(xy 403.043589 -407.138001) (xy 403.028233 -407.085704) (xy 403.020475 -407.031753) (xy 401.582965 -407.031753)
			(xy 401.582965 -407.031755) (xy 401.575207 -407.085709) (xy 401.55985 -407.138011) (xy 401.537206 -407.187594)
			(xy 401.507735 -407.23345) (xy 401.472038 -407.274646) (xy 401.430842 -407.310341) (xy 401.384986 -407.33981)
			(xy 401.335402 -407.362454) (xy 401.2831 -407.37781) (xy 401.229145 -407.385566) (xy 401.20189 -407.386028)
			(xy 400.33829 -407.386028) (xy 400.311041 -407.385501) (xy 400.257097 -407.377744) (xy 400.204806 -407.362389)
			(xy 400.155233 -407.339748) (xy 400.109386 -407.310283) (xy 400.068199 -407.274594) (xy 400.032511 -407.233406)
			(xy 400.003047 -407.187558) (xy 399.980408 -407.137984) (xy 399.965054 -407.085693) (xy 399.957298 -407.031749)
			(xy 398.519765 -407.031749) (xy 398.519765 -407.031757) (xy 398.512006 -407.085715) (xy 398.496647 -407.138019)
			(xy 398.474 -407.187606) (xy 398.444525 -407.233464) (xy 398.408824 -407.27466) (xy 398.367623 -407.310355)
			(xy 398.321762 -407.339824) (xy 398.272173 -407.362464) (xy 398.219866 -407.377817) (xy 398.165907 -407.385569)
			(xy 398.13865 -407.386028) (xy 397.27505 -407.386028) (xy 397.247803 -407.385498) (xy 397.193863 -407.377736)
			(xy 397.141577 -407.362378) (xy 397.092009 -407.339735) (xy 397.046167 -407.310269) (xy 397.004985 -407.274579)
			(xy 396.969301 -407.233393) (xy 396.939841 -407.187547) (xy 396.917205 -407.137976) (xy 396.901853 -407.085688)
			(xy 396.894098 -407.031748) (xy 395.456442 -407.031748) (xy 395.456442 -407.031752) (xy 395.448686 -407.085702)
			(xy 395.43333 -407.137999) (xy 395.410689 -407.187578) (xy 395.381222 -407.23343) (xy 395.345529 -407.274622)
			(xy 395.304338 -407.310316) (xy 395.258487 -407.339784) (xy 395.208908 -407.362427) (xy 395.156612 -407.377783)
			(xy 395.102662 -407.385541) (xy 395.07541 -407.386028) (xy 394.21181 -407.386028) (xy 394.184558 -407.385525)
			(xy 394.130609 -407.37777) (xy 394.078313 -407.362416) (xy 394.028734 -407.339775) (xy 393.982882 -407.310309)
			(xy 393.94169 -407.274617) (xy 393.905997 -407.233426) (xy 393.87653 -407.187575) (xy 393.853888 -407.137997)
			(xy 393.838532 -407.085701) (xy 393.830775 -407.031752) (xy 392.393265 -407.031752) (xy 392.393265 -407.031756)
			(xy 392.385507 -407.085712) (xy 392.370148 -407.138015) (xy 392.347503 -407.1876) (xy 392.31803 -407.233457)
			(xy 392.282331 -407.274653) (xy 392.241133 -407.310348) (xy 392.195274 -407.339817) (xy 392.145687 -407.362459)
			(xy 392.093383 -407.377813) (xy 392.039426 -407.385567) (xy 392.01217 -407.386028) (xy 391.14857 -407.386028)
			(xy 391.121322 -407.3855) (xy 391.06738 -407.37774) (xy 391.015092 -407.362383) (xy 390.965521 -407.339742)
			(xy 390.919677 -407.310276) (xy 390.878492 -407.274586) (xy 390.842806 -407.233399) (xy 390.813344 -407.187553)
			(xy 390.790706 -407.13798) (xy 390.775353 -407.085691) (xy 390.767598 -407.031748) (xy 389.329942 -407.031748)
			(xy 389.329942 -407.031751) (xy 389.322186 -407.085699) (xy 389.306832 -407.137994) (xy 389.284192 -407.187572)
			(xy 389.254727 -407.233424) (xy 389.219036 -407.274615) (xy 389.177848 -407.310309) (xy 389.131999 -407.339777)
			(xy 389.082422 -407.362421) (xy 389.030129 -407.37778) (xy 388.976181 -407.38554) (xy 388.94893 -407.386028)
			(xy 388.08533 -407.386028) (xy 388.058077 -407.385527) (xy 388.004126 -407.377774) (xy 387.951827 -407.362421)
			(xy 387.902246 -407.339781) (xy 387.856391 -407.310316) (xy 387.815197 -407.274624) (xy 387.779502 -407.233433)
			(xy 387.750033 -407.187581) (xy 387.727389 -407.138001) (xy 387.712033 -407.085704) (xy 387.704275 -407.031753)
			(xy 386.266765 -407.031753) (xy 386.266765 -407.031755) (xy 386.259007 -407.085709) (xy 386.24365 -407.138011)
			(xy 386.221006 -407.187594) (xy 386.191535 -407.23345) (xy 386.155838 -407.274646) (xy 386.114642 -407.310341)
			(xy 386.068786 -407.33981) (xy 386.019202 -407.362454) (xy 385.9669 -407.37781) (xy 385.912945 -407.385566)
			(xy 385.88569 -407.386028) (xy 385.02209 -407.386028) (xy 384.994841 -407.385501) (xy 384.940897 -407.377744)
			(xy 384.888606 -407.362389) (xy 384.839033 -407.339748) (xy 384.793186 -407.310283) (xy 384.751999 -407.274594)
			(xy 384.716311 -407.233406) (xy 384.686847 -407.187558) (xy 384.664208 -407.137984) (xy 384.648854 -407.085693)
			(xy 384.641098 -407.031749) (xy 383.203565 -407.031749) (xy 383.203565 -407.031757) (xy 383.195806 -407.085715)
			(xy 383.180447 -407.138019) (xy 383.1578 -407.187606) (xy 383.128325 -407.233464) (xy 383.092624 -407.27466)
			(xy 383.051423 -407.310355) (xy 383.005562 -407.339824) (xy 382.955973 -407.362464) (xy 382.903666 -407.377817)
			(xy 382.849707 -407.385569) (xy 382.82245 -407.386028) (xy 381.95885 -407.386028) (xy 381.931603 -407.385498)
			(xy 381.877663 -407.377736) (xy 381.825377 -407.362378) (xy 381.775809 -407.339735) (xy 381.729967 -407.310269)
			(xy 381.688785 -407.274579) (xy 381.653101 -407.233393) (xy 381.623641 -407.187547) (xy 381.601005 -407.137976)
			(xy 381.585653 -407.085688) (xy 381.577898 -407.031748) (xy 380.140242 -407.031748) (xy 380.140242 -407.031752)
			(xy 380.132486 -407.085702) (xy 380.11713 -407.137999) (xy 380.094489 -407.187578) (xy 380.065022 -407.23343)
			(xy 380.029329 -407.274622) (xy 379.988138 -407.310316) (xy 379.942287 -407.339784) (xy 379.892708 -407.362427)
			(xy 379.840412 -407.377783) (xy 379.786462 -407.385541) (xy 379.75921 -407.386028) (xy 378.89561 -407.386028)
			(xy 378.868358 -407.385525) (xy 378.814409 -407.37777) (xy 378.762113 -407.362416) (xy 378.712534 -407.339775)
			(xy 378.666682 -407.310309) (xy 378.62549 -407.274617) (xy 378.589797 -407.233426) (xy 378.56033 -407.187575)
			(xy 378.537688 -407.137997) (xy 378.522332 -407.085701) (xy 378.514575 -407.031752) (xy 377.077065 -407.031752)
			(xy 377.077065 -407.031756) (xy 377.069307 -407.085712) (xy 377.053948 -407.138015) (xy 377.031303 -407.1876)
			(xy 377.00183 -407.233457) (xy 376.966131 -407.274653) (xy 376.924933 -407.310348) (xy 376.879074 -407.339817)
			(xy 376.829487 -407.362459) (xy 376.777183 -407.377813) (xy 376.723226 -407.385567) (xy 376.69597 -407.386028)
			(xy 375.83237 -407.386028) (xy 375.805122 -407.3855) (xy 375.75118 -407.37774) (xy 375.698892 -407.362383)
			(xy 375.649321 -407.339742) (xy 375.603477 -407.310276) (xy 375.562292 -407.274586) (xy 375.526606 -407.233399)
			(xy 375.497144 -407.187553) (xy 375.474506 -407.13798) (xy 375.459153 -407.085691) (xy 375.451398 -407.031748)
			(xy 374.013742 -407.031748) (xy 374.013742 -407.031751) (xy 374.005986 -407.085699) (xy 373.990632 -407.137994)
			(xy 373.967992 -407.187572) (xy 373.938527 -407.233424) (xy 373.902836 -407.274615) (xy 373.861648 -407.310309)
			(xy 373.815799 -407.339777) (xy 373.766222 -407.362421) (xy 373.713929 -407.37778) (xy 373.659981 -407.38554)
			(xy 373.63273 -407.386028) (xy 372.76913 -407.386028) (xy 372.741877 -407.385527) (xy 372.687926 -407.377774)
			(xy 372.635627 -407.362421) (xy 372.586046 -407.339781) (xy 372.540191 -407.310316) (xy 372.498997 -407.274624)
			(xy 372.463302 -407.233433) (xy 372.433833 -407.187581) (xy 372.411189 -407.138001) (xy 372.395833 -407.085704)
			(xy 372.388075 -407.031753) (xy 352.519565 -407.031753) (xy 352.519565 -407.031755) (xy 352.511807 -407.08571)
			(xy 352.49645 -407.138011) (xy 352.473805 -407.187595) (xy 352.444335 -407.233451) (xy 352.408638 -407.274646)
			(xy 352.367441 -407.310342) (xy 352.321584 -407.339811) (xy 352.272 -407.362454) (xy 352.219698 -407.37781)
			(xy 352.165743 -407.385566) (xy 352.138488 -407.386028) (xy 351.274888 -407.386028) (xy 351.247639 -407.385501)
			(xy 351.193695 -407.377743) (xy 351.141405 -407.362388) (xy 351.091832 -407.339748) (xy 351.045985 -407.310282)
			(xy 351.004799 -407.274593) (xy 350.96911 -407.233405) (xy 350.939647 -407.187558) (xy 350.917008 -407.137984)
			(xy 350.901654 -407.085693) (xy 350.893898 -407.031749) (xy 349.456242 -407.031749) (xy 349.456242 -407.03175)
			(xy 349.448487 -407.085697) (xy 349.433133 -407.137991) (xy 349.410494 -407.187567) (xy 349.381031 -407.233418)
			(xy 349.345343 -407.274609) (xy 349.304156 -407.310302) (xy 349.258309 -407.339771) (xy 349.208736 -407.362416)
			(xy 349.156444 -407.377776) (xy 349.102498 -407.385539) (xy 349.075248 -407.386028) (xy 348.211648 -407.386028)
			(xy 348.184394 -407.385528) (xy 348.130441 -407.377777) (xy 348.07814 -407.362426) (xy 348.028557 -407.339787)
			(xy 347.9827 -407.310322) (xy 347.941504 -407.27463) (xy 347.905807 -407.233439) (xy 347.876336 -407.187586)
			(xy 347.853691 -407.138005) (xy 347.838333 -407.085706) (xy 347.830575 -407.031754) (xy 346.393042 -407.031754)
			(xy 346.385285 -407.085702) (xy 346.36993 -407.137999) (xy 346.347288 -407.187578) (xy 346.317821 -407.233431)
			(xy 346.282129 -407.274623) (xy 346.240937 -407.310316) (xy 346.195085 -407.339784) (xy 346.145507 -407.362427)
			(xy 346.09321 -407.377784) (xy 346.03926 -407.385542) (xy 346.012008 -407.386028) (xy 345.148408 -407.386028)
			(xy 345.121156 -407.385525) (xy 345.067207 -407.37777) (xy 345.014911 -407.362415) (xy 344.965333 -407.339774)
			(xy 344.919481 -407.310308) (xy 344.878289 -407.274616) (xy 344.842597 -407.233425) (xy 344.81313 -407.187574)
			(xy 344.790488 -407.137996) (xy 344.775132 -407.085701) (xy 344.767375 -407.031752) (xy 343.329865 -407.031752)
			(xy 343.329865 -407.031756) (xy 343.322107 -407.085712) (xy 343.306748 -407.138016) (xy 343.284102 -407.187601)
			(xy 343.25463 -407.233458) (xy 343.218931 -407.274653) (xy 343.177732 -407.310349) (xy 343.131872 -407.339818)
			(xy 343.082286 -407.36246) (xy 343.029981 -407.377814) (xy 342.976024 -407.385567) (xy 342.948768 -407.386028)
			(xy 342.085168 -407.386028) (xy 342.05792 -407.3855) (xy 342.003978 -407.37774) (xy 341.95169 -407.362383)
			(xy 341.90212 -407.339741) (xy 341.856276 -407.310275) (xy 341.815092 -407.274586) (xy 341.779405 -407.233399)
			(xy 341.749944 -407.187552) (xy 341.727306 -407.13798) (xy 341.711953 -407.08569) (xy 341.704198 -407.031748)
			(xy 340.266542 -407.031748) (xy 340.266542 -407.031751) (xy 340.258786 -407.0857) (xy 340.243432 -407.137995)
			(xy 340.220791 -407.187573) (xy 340.191326 -407.233424) (xy 340.155636 -407.274616) (xy 340.114447 -407.310309)
			(xy 340.068597 -407.339778) (xy 340.019021 -407.362422) (xy 339.966727 -407.37778) (xy 339.912779 -407.38554)
			(xy 339.885528 -407.386028) (xy 339.021928 -407.386028) (xy 338.994675 -407.385527) (xy 338.940724 -407.377773)
			(xy 338.888426 -407.36242) (xy 338.838845 -407.339781) (xy 338.79299 -407.310315) (xy 338.751797 -407.274623)
			(xy 338.716102 -407.233432) (xy 338.686633 -407.18758) (xy 338.663989 -407.138001) (xy 338.648633 -407.085703)
			(xy 338.640875 -407.031753) (xy 337.203365 -407.031753) (xy 337.203365 -407.031755) (xy 337.195607 -407.08571)
			(xy 337.18025 -407.138011) (xy 337.157605 -407.187595) (xy 337.128135 -407.233451) (xy 337.092438 -407.274646)
			(xy 337.051241 -407.310342) (xy 337.005384 -407.339811) (xy 336.9558 -407.362454) (xy 336.903498 -407.37781)
			(xy 336.849543 -407.385566) (xy 336.822288 -407.386028) (xy 335.958688 -407.386028) (xy 335.931439 -407.385501)
			(xy 335.877495 -407.377743) (xy 335.825205 -407.362388) (xy 335.775632 -407.339748) (xy 335.729785 -407.310282)
			(xy 335.688599 -407.274593) (xy 335.65291 -407.233405) (xy 335.623447 -407.187558) (xy 335.600808 -407.137984)
			(xy 335.585454 -407.085693) (xy 335.577698 -407.031749) (xy 334.140042 -407.031749) (xy 334.140042 -407.03175)
			(xy 334.132287 -407.085697) (xy 334.116933 -407.137991) (xy 334.094294 -407.187567) (xy 334.064831 -407.233418)
			(xy 334.029143 -407.274609) (xy 333.987956 -407.310302) (xy 333.942109 -407.339771) (xy 333.892536 -407.362416)
			(xy 333.840244 -407.377776) (xy 333.786298 -407.385539) (xy 333.759048 -407.386028) (xy 332.895448 -407.386028)
			(xy 332.868194 -407.385528) (xy 332.814241 -407.377777) (xy 332.76194 -407.362426) (xy 332.712357 -407.339787)
			(xy 332.6665 -407.310322) (xy 332.625304 -407.27463) (xy 332.589607 -407.233439) (xy 332.560136 -407.187586)
			(xy 332.537491 -407.138005) (xy 332.522133 -407.085706) (xy 332.514375 -407.031754) (xy 331.076842 -407.031754)
			(xy 331.069085 -407.085702) (xy 331.05373 -407.137999) (xy 331.031088 -407.187578) (xy 331.001621 -407.233431)
			(xy 330.965929 -407.274623) (xy 330.924737 -407.310316) (xy 330.878885 -407.339784) (xy 330.829307 -407.362427)
			(xy 330.77701 -407.377784) (xy 330.72306 -407.385542) (xy 330.695808 -407.386028) (xy 329.832208 -407.386028)
			(xy 329.804956 -407.385525) (xy 329.751007 -407.37777) (xy 329.698711 -407.362415) (xy 329.649133 -407.339774)
			(xy 329.603281 -407.310308) (xy 329.562089 -407.274616) (xy 329.526397 -407.233425) (xy 329.49693 -407.187574)
			(xy 329.474288 -407.137996) (xy 329.458932 -407.085701) (xy 329.451175 -407.031752) (xy 328.013665 -407.031752)
			(xy 328.013665 -407.031756) (xy 328.005907 -407.085712) (xy 327.990548 -407.138016) (xy 327.967902 -407.187601)
			(xy 327.93843 -407.233458) (xy 327.902731 -407.274653) (xy 327.861532 -407.310349) (xy 327.815672 -407.339818)
			(xy 327.766086 -407.36246) (xy 327.713781 -407.377814) (xy 327.659824 -407.385567) (xy 327.632568 -407.386028)
			(xy 326.768968 -407.386028) (xy 326.74172 -407.3855) (xy 326.687778 -407.37774) (xy 326.63549 -407.362383)
			(xy 326.58592 -407.339741) (xy 326.540076 -407.310275) (xy 326.498892 -407.274586) (xy 326.463205 -407.233399)
			(xy 326.433744 -407.187552) (xy 326.411106 -407.13798) (xy 326.395753 -407.08569) (xy 326.387998 -407.031748)
			(xy 324.950342 -407.031748) (xy 324.950342 -407.031751) (xy 324.942586 -407.0857) (xy 324.927232 -407.137995)
			(xy 324.904591 -407.187573) (xy 324.875126 -407.233424) (xy 324.839436 -407.274616) (xy 324.798247 -407.310309)
			(xy 324.752397 -407.339778) (xy 324.702821 -407.362422) (xy 324.650527 -407.37778) (xy 324.596579 -407.38554)
			(xy 324.569328 -407.386028) (xy 323.705728 -407.386028) (xy 323.678475 -407.385527) (xy 323.624524 -407.377773)
			(xy 323.572226 -407.36242) (xy 323.522645 -407.339781) (xy 323.47679 -407.310315) (xy 323.435597 -407.274623)
			(xy 323.399902 -407.233432) (xy 323.370433 -407.18758) (xy 323.347789 -407.138001) (xy 323.332433 -407.085703)
			(xy 323.324675 -407.031753) (xy 321.887165 -407.031753) (xy 321.887165 -407.031755) (xy 321.879407 -407.08571)
			(xy 321.86405 -407.138011) (xy 321.841405 -407.187595) (xy 321.811935 -407.233451) (xy 321.776238 -407.274646)
			(xy 321.735041 -407.310342) (xy 321.689184 -407.339811) (xy 321.6396 -407.362454) (xy 321.587298 -407.37781)
			(xy 321.533343 -407.385566) (xy 321.506088 -407.386028) (xy 320.642488 -407.386028) (xy 320.615239 -407.385501)
			(xy 320.561295 -407.377743) (xy 320.509005 -407.362388) (xy 320.459432 -407.339748) (xy 320.413585 -407.310282)
			(xy 320.372399 -407.274593) (xy 320.33671 -407.233405) (xy 320.307247 -407.187558) (xy 320.284608 -407.137984)
			(xy 320.269254 -407.085693) (xy 320.261498 -407.031749) (xy 318.823842 -407.031749) (xy 318.823842 -407.03175)
			(xy 318.816087 -407.085697) (xy 318.800733 -407.137991) (xy 318.778094 -407.187567) (xy 318.748631 -407.233418)
			(xy 318.712943 -407.274609) (xy 318.671756 -407.310302) (xy 318.625909 -407.339771) (xy 318.576336 -407.362416)
			(xy 318.524044 -407.377776) (xy 318.470098 -407.385539) (xy 318.442848 -407.386028) (xy 317.579248 -407.386028)
			(xy 317.551994 -407.385528) (xy 317.498041 -407.377777) (xy 317.44574 -407.362426) (xy 317.396157 -407.339787)
			(xy 317.3503 -407.310322) (xy 317.309104 -407.27463) (xy 317.273407 -407.233439) (xy 317.243936 -407.187586)
			(xy 317.221291 -407.138005) (xy 317.205933 -407.085706) (xy 317.198175 -407.031754) (xy 315.760642 -407.031754)
			(xy 315.752885 -407.085702) (xy 315.73753 -407.137999) (xy 315.714888 -407.187578) (xy 315.685421 -407.233431)
			(xy 315.649729 -407.274623) (xy 315.608537 -407.310316) (xy 315.562685 -407.339784) (xy 315.513107 -407.362427)
			(xy 315.46081 -407.377784) (xy 315.40686 -407.385542) (xy 315.379608 -407.386028) (xy 314.516008 -407.386028)
			(xy 314.488756 -407.385525) (xy 314.434807 -407.37777) (xy 314.382511 -407.362415) (xy 314.332933 -407.339774)
			(xy 314.287081 -407.310308) (xy 314.245889 -407.274616) (xy 314.210197 -407.233425) (xy 314.18073 -407.187574)
			(xy 314.158088 -407.137996) (xy 314.142732 -407.085701) (xy 314.134975 -407.031752) (xy 312.697465 -407.031752)
			(xy 312.697465 -407.031756) (xy 312.689707 -407.085712) (xy 312.674348 -407.138016) (xy 312.651702 -407.187601)
			(xy 312.62223 -407.233458) (xy 312.586531 -407.274653) (xy 312.545332 -407.310349) (xy 312.499472 -407.339818)
			(xy 312.449886 -407.36246) (xy 312.397581 -407.377814) (xy 312.343624 -407.385567) (xy 312.316368 -407.386028)
			(xy 311.452768 -407.386028) (xy 311.42552 -407.3855) (xy 311.371578 -407.37774) (xy 311.31929 -407.362383)
			(xy 311.26972 -407.339741) (xy 311.223876 -407.310275) (xy 311.182692 -407.274586) (xy 311.147005 -407.233399)
			(xy 311.117544 -407.187552) (xy 311.094906 -407.13798) (xy 311.079553 -407.08569) (xy 311.071798 -407.031748)
			(xy 309.634142 -407.031748) (xy 309.634142 -407.031751) (xy 309.626386 -407.0857) (xy 309.611032 -407.137995)
			(xy 309.588391 -407.187573) (xy 309.558926 -407.233424) (xy 309.523236 -407.274616) (xy 309.482047 -407.310309)
			(xy 309.436197 -407.339778) (xy 309.386621 -407.362422) (xy 309.334327 -407.37778) (xy 309.280379 -407.38554)
			(xy 309.253128 -407.386028) (xy 308.389528 -407.386028) (xy 308.362275 -407.385527) (xy 308.308324 -407.377773)
			(xy 308.256026 -407.36242) (xy 308.206445 -407.339781) (xy 308.16059 -407.310315) (xy 308.119397 -407.274623)
			(xy 308.083702 -407.233432) (xy 308.054233 -407.18758) (xy 308.031589 -407.138001) (xy 308.016233 -407.085703)
			(xy 308.008475 -407.031753) (xy 306.570965 -407.031753) (xy 306.570965 -407.031755) (xy 306.563207 -407.08571)
			(xy 306.54785 -407.138011) (xy 306.525205 -407.187595) (xy 306.495735 -407.233451) (xy 306.460038 -407.274646)
			(xy 306.418841 -407.310342) (xy 306.372984 -407.339811) (xy 306.3234 -407.362454) (xy 306.271098 -407.37781)
			(xy 306.217143 -407.385566) (xy 306.189888 -407.386028) (xy 305.326288 -407.386028) (xy 305.299039 -407.385501)
			(xy 305.245095 -407.377743) (xy 305.192805 -407.362388) (xy 305.143232 -407.339748) (xy 305.097385 -407.310282)
			(xy 305.056199 -407.274593) (xy 305.02051 -407.233405) (xy 304.991047 -407.187558) (xy 304.968408 -407.137984)
			(xy 304.953054 -407.085693) (xy 304.945298 -407.031749) (xy 274.459335 -407.031749) (xy 274.369276 -407.121868)
			(xy 274.369276 -407.203148) (xy 274.602448 -407.43632) (xy 280.100532 -407.43632) (xy 280.125484 -407.436804)
			(xy 280.174775 -407.444599) (xy 280.222241 -407.460008) (xy 280.266712 -407.482651) (xy 280.307094 -407.511971)
			(xy 280.325068 -407.529284) (xy 280.739596 -407.943812) (xy 280.756881 -407.96181) (xy 280.786193 -408.002193)
			(xy 280.808837 -408.046659) (xy 280.824257 -408.094116) (xy 280.832075 -408.143399) (xy 280.83256 -408.168348)
			(xy 280.83256 -410.057453) (xy 304.945246 -410.057453) (xy 304.945246 -410.002947) (xy 304.953003 -409.948996)
			(xy 304.968358 -409.896698) (xy 304.991001 -409.847117) (xy 305.020468 -409.801263) (xy 305.056162 -409.76007)
			(xy 305.097354 -409.724375) (xy 305.143207 -409.694906) (xy 305.192786 -409.672263) (xy 305.245084 -409.656905)
			(xy 305.299035 -409.649147) (xy 305.326288 -409.64866) (xy 306.189888 -409.64866) (xy 306.217139 -409.649186)
			(xy 306.271087 -409.656941) (xy 306.323382 -409.672295) (xy 306.372959 -409.694935) (xy 306.41881 -409.7244)
			(xy 306.460001 -409.760091) (xy 306.495693 -409.80128) (xy 306.525159 -409.84713) (xy 306.547801 -409.896707)
			(xy 306.563156 -409.949001) (xy 306.570913 -410.002949) (xy 306.570913 -410.057451) (xy 306.570912 -410.057456)
			(xy 308.008423 -410.057456) (xy 308.008423 -410.002944) (xy 308.016181 -409.948986) (xy 308.03154 -409.896681)
			(xy 308.054187 -409.847095) (xy 308.08366 -409.801236) (xy 308.119359 -409.76004) (xy 308.160559 -409.724343)
			(xy 308.206419 -409.694873) (xy 308.256007 -409.67223) (xy 308.308313 -409.656875) (xy 308.362272 -409.649121)
			(xy 308.389528 -409.64866) (xy 309.253128 -409.64866) (xy 309.280376 -409.649212) (xy 309.334316 -409.656971)
			(xy 309.386603 -409.672327) (xy 309.436172 -409.694968) (xy 309.482015 -409.724433) (xy 309.523199 -409.760121)
			(xy 309.558884 -409.801307) (xy 309.588345 -409.847152) (xy 309.610982 -409.896724) (xy 309.626335 -409.949012)
			(xy 309.63409 -410.002952) (xy 309.63409 -410.057448) (xy 309.634089 -410.057452) (xy 311.071746 -410.057452)
			(xy 311.071746 -410.002948) (xy 311.079502 -409.948998) (xy 311.094857 -409.896702) (xy 311.117498 -409.847123)
			(xy 311.146963 -409.80127) (xy 311.182654 -409.760077) (xy 311.223844 -409.724383) (xy 311.269695 -409.694913)
			(xy 311.319272 -409.672268) (xy 311.371567 -409.656909) (xy 311.425516 -409.649148) (xy 311.452768 -409.64866)
			(xy 312.316368 -409.64866) (xy 312.34362 -409.649185) (xy 312.39757 -409.656938) (xy 312.449867 -409.67229)
			(xy 312.499447 -409.694928) (xy 312.545301 -409.724393) (xy 312.586494 -409.760084) (xy 312.622188 -409.801274)
			(xy 312.651656 -409.847125) (xy 312.674299 -409.896703) (xy 312.689655 -409.948999) (xy 312.697413 -410.002948)
			(xy 312.697413 -410.057452) (xy 312.697412 -410.057456) (xy 314.134923 -410.057456) (xy 314.134923 -410.002944)
			(xy 314.142681 -409.948988) (xy 314.158039 -409.896685) (xy 314.180684 -409.8471) (xy 314.210155 -409.801243)
			(xy 314.245852 -409.760047) (xy 314.287049 -409.72435) (xy 314.332907 -409.69488) (xy 314.382493 -409.672236)
			(xy 314.434796 -409.656879) (xy 314.488752 -409.649122) (xy 314.516008 -409.64866) (xy 315.379608 -409.64866)
			(xy 315.406857 -409.649211) (xy 315.460799 -409.656968) (xy 315.513088 -409.672322) (xy 315.56266 -409.694962)
			(xy 315.608506 -409.724426) (xy 315.649691 -409.760114) (xy 315.685379 -409.801301) (xy 315.714842 -409.847147)
			(xy 315.737481 -409.896719) (xy 315.752834 -409.949009) (xy 315.76059 -410.002951) (xy 315.76059 -410.057449)
			(xy 315.760589 -410.057457) (xy 317.198123 -410.057457) (xy 317.198123 -410.002943) (xy 317.205882 -409.948983)
			(xy 317.221242 -409.896677) (xy 317.24389 -409.847089) (xy 317.273365 -409.80123) (xy 317.309066 -409.760033)
			(xy 317.350268 -409.724336) (xy 317.396131 -409.694867) (xy 317.445722 -409.672225) (xy 317.49803 -409.656872)
			(xy 317.551991 -409.64912) (xy 317.579248 -409.64866) (xy 318.442848 -409.64866) (xy 318.470095 -409.649213)
			(xy 318.524033 -409.656975) (xy 318.576317 -409.672333) (xy 318.625884 -409.694975) (xy 318.671725 -409.72444)
			(xy 318.712906 -409.760128) (xy 318.748589 -409.801314) (xy 318.778048 -409.847158) (xy 318.800684 -409.896728)
			(xy 318.816035 -409.949014) (xy 318.82379 -410.002953) (xy 318.82379 -410.057447) (xy 318.823789 -410.057453)
			(xy 320.261446 -410.057453) (xy 320.261446 -410.002947) (xy 320.269203 -409.948996) (xy 320.284558 -409.896698)
			(xy 320.307201 -409.847117) (xy 320.336668 -409.801263) (xy 320.372362 -409.76007) (xy 320.413554 -409.724375)
			(xy 320.459407 -409.694906) (xy 320.508986 -409.672263) (xy 320.561284 -409.656905) (xy 320.615235 -409.649147)
			(xy 320.642488 -409.64866) (xy 321.506088 -409.64866) (xy 321.533339 -409.649186) (xy 321.587287 -409.656941)
			(xy 321.639582 -409.672295) (xy 321.689159 -409.694935) (xy 321.73501 -409.7244) (xy 321.776201 -409.760091)
			(xy 321.811893 -409.80128) (xy 321.841359 -409.84713) (xy 321.864001 -409.896707) (xy 321.879356 -409.949001)
			(xy 321.887113 -410.002949) (xy 321.887113 -410.057451) (xy 321.887112 -410.057456) (xy 323.324623 -410.057456)
			(xy 323.324623 -410.002944) (xy 323.332381 -409.948986) (xy 323.34774 -409.896681) (xy 323.370387 -409.847095)
			(xy 323.39986 -409.801236) (xy 323.435559 -409.76004) (xy 323.476759 -409.724343) (xy 323.522619 -409.694873)
			(xy 323.572207 -409.67223) (xy 323.624513 -409.656875) (xy 323.678472 -409.649121) (xy 323.705728 -409.64866)
			(xy 324.569328 -409.64866) (xy 324.596576 -409.649212) (xy 324.650516 -409.656971) (xy 324.702803 -409.672327)
			(xy 324.752372 -409.694968) (xy 324.798215 -409.724433) (xy 324.839399 -409.760121) (xy 324.875084 -409.801307)
			(xy 324.904545 -409.847152) (xy 324.927182 -409.896724) (xy 324.942535 -409.949012) (xy 324.95029 -410.002952)
			(xy 324.95029 -410.057448) (xy 324.950289 -410.057452) (xy 326.387946 -410.057452) (xy 326.387946 -410.002948)
			(xy 326.395702 -409.948998) (xy 326.411057 -409.896702) (xy 326.433698 -409.847123) (xy 326.463163 -409.80127)
			(xy 326.498854 -409.760077) (xy 326.540044 -409.724383) (xy 326.585895 -409.694913) (xy 326.635472 -409.672268)
			(xy 326.687767 -409.656909) (xy 326.741716 -409.649148) (xy 326.768968 -409.64866) (xy 327.632568 -409.64866)
			(xy 327.65982 -409.649185) (xy 327.71377 -409.656938) (xy 327.766067 -409.67229) (xy 327.815647 -409.694928)
			(xy 327.861501 -409.724393) (xy 327.902694 -409.760084) (xy 327.938388 -409.801274) (xy 327.967856 -409.847125)
			(xy 327.990499 -409.896703) (xy 328.005855 -409.948999) (xy 328.013613 -410.002948) (xy 328.013613 -410.057452)
			(xy 328.013612 -410.057456) (xy 329.451123 -410.057456) (xy 329.451123 -410.002944) (xy 329.458881 -409.948988)
			(xy 329.474239 -409.896685) (xy 329.496884 -409.8471) (xy 329.526355 -409.801243) (xy 329.562052 -409.760047)
			(xy 329.603249 -409.72435) (xy 329.649107 -409.69488) (xy 329.698693 -409.672236) (xy 329.750996 -409.656879)
			(xy 329.804952 -409.649122) (xy 329.832208 -409.64866) (xy 330.695808 -409.64866) (xy 330.723057 -409.649211)
			(xy 330.776999 -409.656968) (xy 330.829288 -409.672322) (xy 330.87886 -409.694962) (xy 330.924706 -409.724426)
			(xy 330.965891 -409.760114) (xy 331.001579 -409.801301) (xy 331.031042 -409.847147) (xy 331.053681 -409.896719)
			(xy 331.069034 -409.949009) (xy 331.07679 -410.002951) (xy 331.07679 -410.057449) (xy 331.076789 -410.057457)
			(xy 332.514323 -410.057457) (xy 332.514323 -410.002943) (xy 332.522082 -409.948983) (xy 332.537442 -409.896677)
			(xy 332.56009 -409.847089) (xy 332.589565 -409.80123) (xy 332.625266 -409.760033) (xy 332.666468 -409.724336)
			(xy 332.712331 -409.694867) (xy 332.761922 -409.672225) (xy 332.81423 -409.656872) (xy 332.868191 -409.64912)
			(xy 332.895448 -409.64866) (xy 333.759048 -409.64866) (xy 333.786295 -409.649213) (xy 333.840233 -409.656975)
			(xy 333.892517 -409.672333) (xy 333.942084 -409.694975) (xy 333.987925 -409.72444) (xy 334.029106 -409.760128)
			(xy 334.064789 -409.801314) (xy 334.094248 -409.847158) (xy 334.116884 -409.896728) (xy 334.132235 -409.949014)
			(xy 334.13999 -410.002953) (xy 334.13999 -410.057447) (xy 334.139989 -410.057453) (xy 335.577646 -410.057453)
			(xy 335.577646 -410.002947) (xy 335.585403 -409.948996) (xy 335.600758 -409.896698) (xy 335.623401 -409.847117)
			(xy 335.652868 -409.801263) (xy 335.688562 -409.76007) (xy 335.729754 -409.724375) (xy 335.775607 -409.694906)
			(xy 335.825186 -409.672263) (xy 335.877484 -409.656905) (xy 335.931435 -409.649147) (xy 335.958688 -409.64866)
			(xy 336.822288 -409.64866) (xy 336.849539 -409.649186) (xy 336.903487 -409.656941) (xy 336.955782 -409.672295)
			(xy 337.005359 -409.694935) (xy 337.05121 -409.7244) (xy 337.092401 -409.760091) (xy 337.128093 -409.80128)
			(xy 337.157559 -409.84713) (xy 337.180201 -409.896707) (xy 337.195556 -409.949001) (xy 337.203313 -410.002949)
			(xy 337.203313 -410.057451) (xy 337.203312 -410.057456) (xy 338.640823 -410.057456) (xy 338.640823 -410.002944)
			(xy 338.648581 -409.948986) (xy 338.66394 -409.896681) (xy 338.686587 -409.847095) (xy 338.71606 -409.801236)
			(xy 338.751759 -409.76004) (xy 338.792959 -409.724343) (xy 338.838819 -409.694873) (xy 338.888407 -409.67223)
			(xy 338.940713 -409.656875) (xy 338.994672 -409.649121) (xy 339.021928 -409.64866) (xy 339.885528 -409.64866)
			(xy 339.912776 -409.649212) (xy 339.966716 -409.656971) (xy 340.019003 -409.672327) (xy 340.068572 -409.694968)
			(xy 340.114415 -409.724433) (xy 340.155599 -409.760121) (xy 340.191284 -409.801307) (xy 340.220745 -409.847152)
			(xy 340.243382 -409.896724) (xy 340.258735 -409.949012) (xy 340.26649 -410.002952) (xy 340.26649 -410.057448)
			(xy 340.266489 -410.057452) (xy 341.704146 -410.057452) (xy 341.704146 -410.002948) (xy 341.711902 -409.948998)
			(xy 341.727257 -409.896702) (xy 341.749898 -409.847123) (xy 341.779363 -409.80127) (xy 341.815054 -409.760077)
			(xy 341.856244 -409.724383) (xy 341.902095 -409.694913) (xy 341.951672 -409.672268) (xy 342.003967 -409.656909)
			(xy 342.057916 -409.649148) (xy 342.085168 -409.64866) (xy 342.948768 -409.64866) (xy 342.97602 -409.649185)
			(xy 343.02997 -409.656938) (xy 343.082267 -409.67229) (xy 343.131847 -409.694928) (xy 343.177701 -409.724393)
			(xy 343.218894 -409.760084) (xy 343.254588 -409.801274) (xy 343.284056 -409.847125) (xy 343.306699 -409.896703)
			(xy 343.322055 -409.948999) (xy 343.329813 -410.002948) (xy 343.329813 -410.057452) (xy 343.329812 -410.057456)
			(xy 344.767323 -410.057456) (xy 344.767323 -410.002944) (xy 344.775081 -409.948988) (xy 344.790439 -409.896685)
			(xy 344.813084 -409.8471) (xy 344.842555 -409.801243) (xy 344.878252 -409.760047) (xy 344.919449 -409.72435)
			(xy 344.965307 -409.69488) (xy 345.014893 -409.672236) (xy 345.067196 -409.656879) (xy 345.121152 -409.649122)
			(xy 345.148408 -409.64866) (xy 346.012008 -409.64866) (xy 346.039257 -409.649211) (xy 346.093199 -409.656968)
			(xy 346.145488 -409.672322) (xy 346.19506 -409.694962) (xy 346.240906 -409.724426) (xy 346.282091 -409.760114)
			(xy 346.317779 -409.801301) (xy 346.347242 -409.847147) (xy 346.369881 -409.896719) (xy 346.385234 -409.949009)
			(xy 346.39299 -410.002951) (xy 346.39299 -410.057449) (xy 346.392989 -410.057457) (xy 347.830523 -410.057457)
			(xy 347.830523 -410.002943) (xy 347.838282 -409.948983) (xy 347.853642 -409.896677) (xy 347.87629 -409.847089)
			(xy 347.905765 -409.80123) (xy 347.941466 -409.760033) (xy 347.982668 -409.724336) (xy 348.028531 -409.694867)
			(xy 348.078122 -409.672225) (xy 348.13043 -409.656872) (xy 348.184391 -409.64912) (xy 348.211648 -409.64866)
			(xy 349.075248 -409.64866) (xy 349.102495 -409.649213) (xy 349.156433 -409.656975) (xy 349.208717 -409.672333)
			(xy 349.258284 -409.694975) (xy 349.304125 -409.72444) (xy 349.345306 -409.760128) (xy 349.380989 -409.801314)
			(xy 349.410448 -409.847158) (xy 349.433084 -409.896728) (xy 349.448435 -409.949014) (xy 349.45619 -410.002953)
			(xy 349.45619 -410.057447) (xy 349.456189 -410.057453) (xy 350.893846 -410.057453) (xy 350.893846 -410.002947)
			(xy 350.901603 -409.948996) (xy 350.916958 -409.896698) (xy 350.939601 -409.847117) (xy 350.969068 -409.801263)
			(xy 351.004762 -409.76007) (xy 351.045954 -409.724375) (xy 351.091807 -409.694906) (xy 351.141386 -409.672263)
			(xy 351.193684 -409.656905) (xy 351.247635 -409.649147) (xy 351.274888 -409.64866) (xy 352.138488 -409.64866)
			(xy 352.165739 -409.649186) (xy 352.219687 -409.656941) (xy 352.271982 -409.672295) (xy 352.321559 -409.694935)
			(xy 352.36741 -409.7244) (xy 352.408601 -409.760091) (xy 352.444293 -409.80128) (xy 352.473759 -409.84713)
			(xy 352.496401 -409.896707) (xy 352.511756 -409.949001) (xy 352.519513 -410.002949) (xy 352.519513 -410.057451)
			(xy 352.519512 -410.057457) (xy 372.388023 -410.057457) (xy 372.388023 -410.002943) (xy 372.395781 -409.948985)
			(xy 372.41114 -409.896681) (xy 372.433787 -409.847094) (xy 372.46326 -409.801236) (xy 372.49896 -409.760039)
			(xy 372.54016 -409.724342) (xy 372.586021 -409.694872) (xy 372.635609 -409.67223) (xy 372.687915 -409.656875)
			(xy 372.741873 -409.649121) (xy 372.76913 -409.64866) (xy 373.63273 -409.64866) (xy 373.659978 -409.649212)
			(xy 373.713917 -409.656972) (xy 373.766204 -409.672328) (xy 373.815773 -409.694969) (xy 373.861616 -409.724434)
			(xy 373.902799 -409.760122) (xy 373.938484 -409.801308) (xy 373.967945 -409.847153) (xy 373.990583 -409.896724)
			(xy 374.005935 -409.949012) (xy 374.01369 -410.002952) (xy 374.01369 -410.057448) (xy 374.013689 -410.057452)
			(xy 375.451346 -410.057452) (xy 375.451346 -410.002948) (xy 375.459102 -409.948998) (xy 375.474457 -409.896701)
			(xy 375.497098 -409.847122) (xy 375.526564 -409.801269) (xy 375.562255 -409.760076) (xy 375.603445 -409.724382)
			(xy 375.649296 -409.694912) (xy 375.698873 -409.672268) (xy 375.751169 -409.656909) (xy 375.805118 -409.649148)
			(xy 375.83237 -409.64866) (xy 376.69597 -409.64866) (xy 376.723222 -409.649185) (xy 376.777172 -409.656938)
			(xy 376.829469 -409.67229) (xy 376.879048 -409.694929) (xy 376.924901 -409.724394) (xy 376.966094 -409.760084)
			(xy 377.001788 -409.801274) (xy 377.031257 -409.847125) (xy 377.053899 -409.896703) (xy 377.069256 -409.948999)
			(xy 377.077013 -410.002948) (xy 377.077013 -410.057452) (xy 377.077012 -410.057456) (xy 378.514523 -410.057456)
			(xy 378.514523 -410.002944) (xy 378.522281 -409.948988) (xy 378.537639 -409.896685) (xy 378.560284 -409.8471)
			(xy 378.589755 -409.801242) (xy 378.625453 -409.760046) (xy 378.66665 -409.724349) (xy 378.712509 -409.694879)
			(xy 378.762094 -409.672235) (xy 378.814398 -409.656879) (xy 378.868354 -409.649122) (xy 378.89561 -409.64866)
			(xy 379.75921 -409.64866) (xy 379.786458 -409.649211) (xy 379.840401 -409.656968) (xy 379.89269 -409.672323)
			(xy 379.942261 -409.694962) (xy 379.988107 -409.724426) (xy 380.029292 -409.760115) (xy 380.06498 -409.801301)
			(xy 380.094442 -409.847147) (xy 380.117081 -409.89672) (xy 380.132434 -409.949009) (xy 380.14019 -410.002952)
			(xy 380.14019 -410.057448) (xy 380.14019 -410.057451) (xy 381.577846 -410.057451) (xy 381.577846 -410.002949)
			(xy 381.585602 -409.949001) (xy 381.600955 -409.896706) (xy 381.623595 -409.847128) (xy 381.653059 -409.801276)
			(xy 381.688748 -409.760083) (xy 381.729936 -409.724389) (xy 381.775784 -409.694919) (xy 381.825359 -409.672273)
			(xy 381.877652 -409.656912) (xy 381.931599 -409.649149) (xy 381.95885 -409.64866) (xy 382.82245 -409.64866)
			(xy 382.849703 -409.649184) (xy 382.903655 -409.656934) (xy 382.955954 -409.672285) (xy 383.005536 -409.694923)
			(xy 383.051392 -409.724387) (xy 383.092587 -409.760077) (xy 383.128283 -409.801268) (xy 383.157753 -409.84712)
			(xy 383.180398 -409.896699) (xy 383.195755 -409.948996) (xy 383.203513 -410.002947) (xy 383.203513 -410.057453)
			(xy 384.641046 -410.057453) (xy 384.641046 -410.002947) (xy 384.648803 -409.948996) (xy 384.664159 -409.896697)
			(xy 384.686801 -409.847117) (xy 384.716269 -409.801263) (xy 384.751962 -409.760069) (xy 384.793155 -409.724375)
			(xy 384.839008 -409.694906) (xy 384.888588 -409.672262) (xy 384.940886 -409.656905) (xy 384.994837 -409.649147)
			(xy 385.02209 -409.64866) (xy 385.88569 -409.64866) (xy 385.912941 -409.649187) (xy 385.966889 -409.656942)
			(xy 386.019183 -409.672296) (xy 386.06876 -409.694936) (xy 386.114611 -409.724401) (xy 386.155801 -409.760092)
			(xy 386.191493 -409.801281) (xy 386.22096 -409.847131) (xy 386.243601 -409.896707) (xy 386.258956 -409.949002)
			(xy 386.266713 -410.002949) (xy 386.266713 -410.057451) (xy 386.266712 -410.057457) (xy 387.704223 -410.057457)
			(xy 387.704223 -410.002943) (xy 387.711981 -409.948985) (xy 387.72734 -409.896681) (xy 387.749987 -409.847094)
			(xy 387.77946 -409.801236) (xy 387.81516 -409.760039) (xy 387.85636 -409.724342) (xy 387.902221 -409.694872)
			(xy 387.951809 -409.67223) (xy 388.004115 -409.656875) (xy 388.058073 -409.649121) (xy 388.08533 -409.64866)
			(xy 388.94893 -409.64866) (xy 388.976178 -409.649212) (xy 389.030117 -409.656972) (xy 389.082404 -409.672328)
			(xy 389.131973 -409.694969) (xy 389.177816 -409.724434) (xy 389.218999 -409.760122) (xy 389.254684 -409.801308)
			(xy 389.284145 -409.847153) (xy 389.306783 -409.896724) (xy 389.322135 -409.949012) (xy 389.32989 -410.002952)
			(xy 389.32989 -410.057448) (xy 389.329889 -410.057452) (xy 390.767546 -410.057452) (xy 390.767546 -410.002948)
			(xy 390.775302 -409.948998) (xy 390.790657 -409.896701) (xy 390.813298 -409.847122) (xy 390.842764 -409.801269)
			(xy 390.878455 -409.760076) (xy 390.919645 -409.724382) (xy 390.965496 -409.694912) (xy 391.015073 -409.672268)
			(xy 391.067369 -409.656909) (xy 391.121318 -409.649148) (xy 391.14857 -409.64866) (xy 392.01217 -409.64866)
			(xy 392.039422 -409.649185) (xy 392.093372 -409.656938) (xy 392.145669 -409.67229) (xy 392.195248 -409.694929)
			(xy 392.241101 -409.724394) (xy 392.282294 -409.760084) (xy 392.317988 -409.801274) (xy 392.347457 -409.847125)
			(xy 392.370099 -409.896703) (xy 392.385456 -409.948999) (xy 392.393213 -410.002948) (xy 392.393213 -410.057452)
			(xy 392.393212 -410.057456) (xy 393.830723 -410.057456) (xy 393.830723 -410.002944) (xy 393.838481 -409.948988)
			(xy 393.853839 -409.896685) (xy 393.876484 -409.8471) (xy 393.905955 -409.801242) (xy 393.941653 -409.760046)
			(xy 393.98285 -409.724349) (xy 394.028709 -409.694879) (xy 394.078294 -409.672235) (xy 394.130598 -409.656879)
			(xy 394.184554 -409.649122) (xy 394.21181 -409.64866) (xy 395.07541 -409.64866) (xy 395.102658 -409.649211)
			(xy 395.156601 -409.656968) (xy 395.20889 -409.672323) (xy 395.258461 -409.694962) (xy 395.304307 -409.724426)
			(xy 395.345492 -409.760115) (xy 395.38118 -409.801301) (xy 395.410642 -409.847147) (xy 395.433281 -409.89672)
			(xy 395.448634 -409.949009) (xy 395.45639 -410.002952) (xy 395.45639 -410.057448) (xy 395.45639 -410.057451)
			(xy 396.894046 -410.057451) (xy 396.894046 -410.002949) (xy 396.901802 -409.949001) (xy 396.917155 -409.896706)
			(xy 396.939795 -409.847128) (xy 396.969259 -409.801276) (xy 397.004948 -409.760083) (xy 397.046136 -409.724389)
			(xy 397.091984 -409.694919) (xy 397.141559 -409.672273) (xy 397.193852 -409.656912) (xy 397.247799 -409.649149)
			(xy 397.27505 -409.64866) (xy 398.13865 -409.64866) (xy 398.165903 -409.649184) (xy 398.219855 -409.656934)
			(xy 398.272154 -409.672285) (xy 398.321736 -409.694923) (xy 398.367592 -409.724387) (xy 398.408787 -409.760077)
			(xy 398.444483 -409.801268) (xy 398.473953 -409.84712) (xy 398.496598 -409.896699) (xy 398.511955 -409.948996)
			(xy 398.519713 -410.002947) (xy 398.519713 -410.057453) (xy 399.957246 -410.057453) (xy 399.957246 -410.002947)
			(xy 399.965003 -409.948996) (xy 399.980359 -409.896697) (xy 400.003001 -409.847117) (xy 400.032469 -409.801263)
			(xy 400.068162 -409.760069) (xy 400.109355 -409.724375) (xy 400.155208 -409.694906) (xy 400.204788 -409.672262)
			(xy 400.257086 -409.656905) (xy 400.311037 -409.649147) (xy 400.33829 -409.64866) (xy 401.20189 -409.64866)
			(xy 401.229141 -409.649187) (xy 401.283089 -409.656942) (xy 401.335383 -409.672296) (xy 401.38496 -409.694936)
			(xy 401.430811 -409.724401) (xy 401.472001 -409.760092) (xy 401.507693 -409.801281) (xy 401.53716 -409.847131)
			(xy 401.559801 -409.896707) (xy 401.575156 -409.949002) (xy 401.582913 -410.002949) (xy 401.582913 -410.057451)
			(xy 401.582912 -410.057457) (xy 403.020423 -410.057457) (xy 403.020423 -410.002943) (xy 403.028181 -409.948985)
			(xy 403.04354 -409.896681) (xy 403.066187 -409.847094) (xy 403.09566 -409.801236) (xy 403.13136 -409.760039)
			(xy 403.17256 -409.724342) (xy 403.218421 -409.694872) (xy 403.268009 -409.67223) (xy 403.320315 -409.656875)
			(xy 403.374273 -409.649121) (xy 403.40153 -409.64866) (xy 404.26513 -409.64866) (xy 404.292378 -409.649212)
			(xy 404.346317 -409.656972) (xy 404.398604 -409.672328) (xy 404.448173 -409.694969) (xy 404.494016 -409.724434)
			(xy 404.535199 -409.760122) (xy 404.570884 -409.801308) (xy 404.600345 -409.847153) (xy 404.622983 -409.896724)
			(xy 404.638335 -409.949012) (xy 404.64609 -410.002952) (xy 404.64609 -410.057448) (xy 404.646089 -410.057452)
			(xy 406.083746 -410.057452) (xy 406.083746 -410.002948) (xy 406.091502 -409.948998) (xy 406.106857 -409.896701)
			(xy 406.129498 -409.847122) (xy 406.158964 -409.801269) (xy 406.194655 -409.760076) (xy 406.235845 -409.724382)
			(xy 406.281696 -409.694912) (xy 406.331273 -409.672268) (xy 406.383569 -409.656909) (xy 406.437518 -409.649148)
			(xy 406.46477 -409.64866) (xy 407.32837 -409.64866) (xy 407.355622 -409.649185) (xy 407.409572 -409.656938)
			(xy 407.461869 -409.67229) (xy 407.511448 -409.694929) (xy 407.557301 -409.724394) (xy 407.598494 -409.760084)
			(xy 407.634188 -409.801274) (xy 407.663657 -409.847125) (xy 407.686299 -409.896703) (xy 407.701656 -409.948999)
			(xy 407.709413 -410.002948) (xy 407.709413 -410.057452) (xy 407.709412 -410.057456) (xy 409.146923 -410.057456)
			(xy 409.146923 -410.002944) (xy 409.154681 -409.948988) (xy 409.170039 -409.896685) (xy 409.192684 -409.8471)
			(xy 409.222155 -409.801242) (xy 409.257853 -409.760046) (xy 409.29905 -409.724349) (xy 409.344909 -409.694879)
			(xy 409.394494 -409.672235) (xy 409.446798 -409.656879) (xy 409.500754 -409.649122) (xy 409.52801 -409.64866)
			(xy 410.39161 -409.64866) (xy 410.418858 -409.649211) (xy 410.472801 -409.656968) (xy 410.52509 -409.672323)
			(xy 410.574661 -409.694962) (xy 410.620507 -409.724426) (xy 410.661692 -409.760115) (xy 410.69738 -409.801301)
			(xy 410.726842 -409.847147) (xy 410.749481 -409.89672) (xy 410.764834 -409.949009) (xy 410.77259 -410.002952)
			(xy 410.77259 -410.057448) (xy 410.77259 -410.057451) (xy 412.210246 -410.057451) (xy 412.210246 -410.002949)
			(xy 412.218002 -409.949001) (xy 412.233355 -409.896706) (xy 412.255995 -409.847128) (xy 412.285459 -409.801276)
			(xy 412.321148 -409.760083) (xy 412.362336 -409.724389) (xy 412.408184 -409.694919) (xy 412.457759 -409.672273)
			(xy 412.510052 -409.656912) (xy 412.563999 -409.649149) (xy 412.59125 -409.64866) (xy 413.45485 -409.64866)
			(xy 413.482103 -409.649184) (xy 413.536055 -409.656934) (xy 413.588354 -409.672285) (xy 413.637936 -409.694923)
			(xy 413.683792 -409.724387) (xy 413.724987 -409.760077) (xy 413.760683 -409.801268) (xy 413.790153 -409.84712)
			(xy 413.812798 -409.896699) (xy 413.828155 -409.948996) (xy 413.835913 -410.002947) (xy 413.835913 -410.057453)
			(xy 415.273446 -410.057453) (xy 415.273446 -410.002947) (xy 415.281203 -409.948996) (xy 415.296559 -409.896697)
			(xy 415.319201 -409.847117) (xy 415.348669 -409.801263) (xy 415.384362 -409.760069) (xy 415.425555 -409.724375)
			(xy 415.471408 -409.694906) (xy 415.520988 -409.672262) (xy 415.573286 -409.656905) (xy 415.627237 -409.649147)
			(xy 415.65449 -409.64866) (xy 416.51809 -409.64866) (xy 416.545341 -409.649187) (xy 416.599289 -409.656942)
			(xy 416.651583 -409.672296) (xy 416.70116 -409.694936) (xy 416.747011 -409.724401) (xy 416.788201 -409.760092)
			(xy 416.823893 -409.801281) (xy 416.85336 -409.847131) (xy 416.876001 -409.896707) (xy 416.891356 -409.949002)
			(xy 416.899113 -410.002949) (xy 416.899113 -410.057451) (xy 416.899112 -410.057457) (xy 418.336623 -410.057457)
			(xy 418.336623 -410.002943) (xy 418.344381 -409.948985) (xy 418.35974 -409.896681) (xy 418.382387 -409.847094)
			(xy 418.41186 -409.801236) (xy 418.44756 -409.760039) (xy 418.48876 -409.724342) (xy 418.534621 -409.694872)
			(xy 418.584209 -409.67223) (xy 418.636515 -409.656875) (xy 418.690473 -409.649121) (xy 418.71773 -409.64866)
			(xy 419.58133 -409.64866) (xy 419.608578 -409.649212) (xy 419.662517 -409.656972) (xy 419.714804 -409.672328)
			(xy 419.764373 -409.694969) (xy 419.810216 -409.724434) (xy 419.851399 -409.760122) (xy 419.887084 -409.801308)
			(xy 419.916545 -409.847153) (xy 419.939183 -409.896724) (xy 419.954535 -409.949012) (xy 419.96229 -410.002952)
			(xy 419.96229 -410.057448) (xy 419.954535 -410.111388) (xy 419.939183 -410.163676) (xy 419.916545 -410.213247)
			(xy 419.887084 -410.259092) (xy 419.851399 -410.300278) (xy 419.810216 -410.335966) (xy 419.764373 -410.365431)
			(xy 419.714804 -410.388072) (xy 419.662517 -410.403428) (xy 419.608578 -410.411188) (xy 419.58133 -410.411676)
			(xy 418.71773 -410.411676) (xy 418.690473 -410.411279) (xy 418.636515 -410.403525) (xy 418.584209 -410.38817)
			(xy 418.534621 -410.365528) (xy 418.48876 -410.336058) (xy 418.44756 -410.300361) (xy 418.41186 -410.259164)
			(xy 418.382387 -410.213306) (xy 418.35974 -410.163719) (xy 418.344381 -410.111415) (xy 418.336623 -410.057457)
			(xy 416.899112 -410.057457) (xy 416.891356 -410.111398) (xy 416.876001 -410.163693) (xy 416.85336 -410.213269)
			(xy 416.823893 -410.259119) (xy 416.788201 -410.300308) (xy 416.747011 -410.335999) (xy 416.70116 -410.365464)
			(xy 416.651583 -410.388104) (xy 416.599289 -410.403458) (xy 416.545341 -410.411213) (xy 416.51809 -410.411676)
			(xy 415.65449 -410.411676) (xy 415.627237 -410.411253) (xy 415.573286 -410.403495) (xy 415.520988 -410.388138)
			(xy 415.471408 -410.365494) (xy 415.425555 -410.336025) (xy 415.384362 -410.300331) (xy 415.348669 -410.259137)
			(xy 415.319201 -410.213283) (xy 415.296559 -410.163703) (xy 415.281203 -410.111404) (xy 415.273446 -410.057453)
			(xy 413.835913 -410.057453) (xy 413.828155 -410.111404) (xy 413.812798 -410.163701) (xy 413.790153 -410.21328)
			(xy 413.760683 -410.259132) (xy 413.724987 -410.300323) (xy 413.683792 -410.336013) (xy 413.637936 -410.365477)
			(xy 413.588354 -410.388115) (xy 413.536055 -410.403466) (xy 413.482103 -410.411216) (xy 413.45485 -410.411676)
			(xy 412.59125 -410.411676) (xy 412.563999 -410.411251) (xy 412.510052 -410.403488) (xy 412.457759 -410.388127)
			(xy 412.408184 -410.365481) (xy 412.362336 -410.336011) (xy 412.321148 -410.300317) (xy 412.285459 -410.259124)
			(xy 412.255995 -410.213272) (xy 412.233355 -410.163694) (xy 412.218002 -410.111399) (xy 412.210246 -410.057451)
			(xy 410.77259 -410.057451) (xy 410.764834 -410.111391) (xy 410.749481 -410.16368) (xy 410.726842 -410.213253)
			(xy 410.69738 -410.259099) (xy 410.661692 -410.300285) (xy 410.620507 -410.335974) (xy 410.574661 -410.365438)
			(xy 410.52509 -410.388077) (xy 410.472801 -410.403432) (xy 410.418858 -410.411189) (xy 410.39161 -410.411676)
			(xy 409.52801 -410.411676) (xy 409.500754 -410.411278) (xy 409.446798 -410.403521) (xy 409.394494 -410.388165)
			(xy 409.344909 -410.365521) (xy 409.29905 -410.336051) (xy 409.257853 -410.300354) (xy 409.222155 -410.259158)
			(xy 409.192684 -410.2133) (xy 409.170039 -410.163715) (xy 409.154681 -410.111412) (xy 409.146923 -410.057456)
			(xy 407.709412 -410.057456) (xy 407.701656 -410.111401) (xy 407.686299 -410.163697) (xy 407.663657 -410.213275)
			(xy 407.634188 -410.259126) (xy 407.598494 -410.300316) (xy 407.557301 -410.336006) (xy 407.511448 -410.365471)
			(xy 407.461869 -410.38811) (xy 407.409572 -410.403462) (xy 407.355622 -410.411215) (xy 407.32837 -410.411676)
			(xy 406.46477 -410.411676) (xy 406.437518 -410.411252) (xy 406.383569 -410.403491) (xy 406.331273 -410.388132)
			(xy 406.281696 -410.365488) (xy 406.235845 -410.336018) (xy 406.194655 -410.300324) (xy 406.158964 -410.259131)
			(xy 406.129498 -410.213278) (xy 406.106857 -410.163699) (xy 406.091502 -410.111402) (xy 406.083746 -410.057452)
			(xy 404.646089 -410.057452) (xy 404.638335 -410.111388) (xy 404.622983 -410.163676) (xy 404.600345 -410.213247)
			(xy 404.570884 -410.259092) (xy 404.535199 -410.300278) (xy 404.494016 -410.335966) (xy 404.448173 -410.365431)
			(xy 404.398604 -410.388072) (xy 404.346317 -410.403428) (xy 404.292378 -410.411188) (xy 404.26513 -410.411676)
			(xy 403.40153 -410.411676) (xy 403.374273 -410.411279) (xy 403.320315 -410.403525) (xy 403.268009 -410.38817)
			(xy 403.218421 -410.365528) (xy 403.17256 -410.336058) (xy 403.13136 -410.300361) (xy 403.09566 -410.259164)
			(xy 403.066187 -410.213306) (xy 403.04354 -410.163719) (xy 403.028181 -410.111415) (xy 403.020423 -410.057457)
			(xy 401.582912 -410.057457) (xy 401.575156 -410.111398) (xy 401.559801 -410.163693) (xy 401.53716 -410.213269)
			(xy 401.507693 -410.259119) (xy 401.472001 -410.300308) (xy 401.430811 -410.335999) (xy 401.38496 -410.365464)
			(xy 401.335383 -410.388104) (xy 401.283089 -410.403458) (xy 401.229141 -410.411213) (xy 401.20189 -410.411676)
			(xy 400.33829 -410.411676) (xy 400.311037 -410.411253) (xy 400.257086 -410.403495) (xy 400.204788 -410.388138)
			(xy 400.155208 -410.365494) (xy 400.109355 -410.336025) (xy 400.068162 -410.300331) (xy 400.032469 -410.259137)
			(xy 400.003001 -410.213283) (xy 399.980359 -410.163703) (xy 399.965003 -410.111404) (xy 399.957246 -410.057453)
			(xy 398.519713 -410.057453) (xy 398.511955 -410.111404) (xy 398.496598 -410.163701) (xy 398.473953 -410.21328)
			(xy 398.444483 -410.259132) (xy 398.408787 -410.300323) (xy 398.367592 -410.336013) (xy 398.321736 -410.365477)
			(xy 398.272154 -410.388115) (xy 398.219855 -410.403466) (xy 398.165903 -410.411216) (xy 398.13865 -410.411676)
			(xy 397.27505 -410.411676) (xy 397.247799 -410.411251) (xy 397.193852 -410.403488) (xy 397.141559 -410.388127)
			(xy 397.091984 -410.365481) (xy 397.046136 -410.336011) (xy 397.004948 -410.300317) (xy 396.969259 -410.259124)
			(xy 396.939795 -410.213272) (xy 396.917155 -410.163694) (xy 396.901802 -410.111399) (xy 396.894046 -410.057451)
			(xy 395.45639 -410.057451) (xy 395.448634 -410.111391) (xy 395.433281 -410.16368) (xy 395.410642 -410.213253)
			(xy 395.38118 -410.259099) (xy 395.345492 -410.300285) (xy 395.304307 -410.335974) (xy 395.258461 -410.365438)
			(xy 395.20889 -410.388077) (xy 395.156601 -410.403432) (xy 395.102658 -410.411189) (xy 395.07541 -410.411676)
			(xy 394.21181 -410.411676) (xy 394.184554 -410.411278) (xy 394.130598 -410.403521) (xy 394.078294 -410.388165)
			(xy 394.028709 -410.365521) (xy 393.98285 -410.336051) (xy 393.941653 -410.300354) (xy 393.905955 -410.259158)
			(xy 393.876484 -410.2133) (xy 393.853839 -410.163715) (xy 393.838481 -410.111412) (xy 393.830723 -410.057456)
			(xy 392.393212 -410.057456) (xy 392.385456 -410.111401) (xy 392.370099 -410.163697) (xy 392.347457 -410.213275)
			(xy 392.317988 -410.259126) (xy 392.282294 -410.300316) (xy 392.241101 -410.336006) (xy 392.195248 -410.365471)
			(xy 392.145669 -410.38811) (xy 392.093372 -410.403462) (xy 392.039422 -410.411215) (xy 392.01217 -410.411676)
			(xy 391.14857 -410.411676) (xy 391.121318 -410.411252) (xy 391.067369 -410.403491) (xy 391.015073 -410.388132)
			(xy 390.965496 -410.365488) (xy 390.919645 -410.336018) (xy 390.878455 -410.300324) (xy 390.842764 -410.259131)
			(xy 390.813298 -410.213278) (xy 390.790657 -410.163699) (xy 390.775302 -410.111402) (xy 390.767546 -410.057452)
			(xy 389.329889 -410.057452) (xy 389.322135 -410.111388) (xy 389.306783 -410.163676) (xy 389.284145 -410.213247)
			(xy 389.254684 -410.259092) (xy 389.218999 -410.300278) (xy 389.177816 -410.335966) (xy 389.131973 -410.365431)
			(xy 389.082404 -410.388072) (xy 389.030117 -410.403428) (xy 388.976178 -410.411188) (xy 388.94893 -410.411676)
			(xy 388.08533 -410.411676) (xy 388.058073 -410.411279) (xy 388.004115 -410.403525) (xy 387.951809 -410.38817)
			(xy 387.902221 -410.365528) (xy 387.85636 -410.336058) (xy 387.81516 -410.300361) (xy 387.77946 -410.259164)
			(xy 387.749987 -410.213306) (xy 387.72734 -410.163719) (xy 387.711981 -410.111415) (xy 387.704223 -410.057457)
			(xy 386.266712 -410.057457) (xy 386.258956 -410.111398) (xy 386.243601 -410.163693) (xy 386.22096 -410.213269)
			(xy 386.191493 -410.259119) (xy 386.155801 -410.300308) (xy 386.114611 -410.335999) (xy 386.06876 -410.365464)
			(xy 386.019183 -410.388104) (xy 385.966889 -410.403458) (xy 385.912941 -410.411213) (xy 385.88569 -410.411676)
			(xy 385.02209 -410.411676) (xy 384.994837 -410.411253) (xy 384.940886 -410.403495) (xy 384.888588 -410.388138)
			(xy 384.839008 -410.365494) (xy 384.793155 -410.336025) (xy 384.751962 -410.300331) (xy 384.716269 -410.259137)
			(xy 384.686801 -410.213283) (xy 384.664159 -410.163703) (xy 384.648803 -410.111404) (xy 384.641046 -410.057453)
			(xy 383.203513 -410.057453) (xy 383.195755 -410.111404) (xy 383.180398 -410.163701) (xy 383.157753 -410.21328)
			(xy 383.128283 -410.259132) (xy 383.092587 -410.300323) (xy 383.051392 -410.336013) (xy 383.005536 -410.365477)
			(xy 382.955954 -410.388115) (xy 382.903655 -410.403466) (xy 382.849703 -410.411216) (xy 382.82245 -410.411676)
			(xy 381.95885 -410.411676) (xy 381.931599 -410.411251) (xy 381.877652 -410.403488) (xy 381.825359 -410.388127)
			(xy 381.775784 -410.365481) (xy 381.729936 -410.336011) (xy 381.688748 -410.300317) (xy 381.653059 -410.259124)
			(xy 381.623595 -410.213272) (xy 381.600955 -410.163694) (xy 381.585602 -410.111399) (xy 381.577846 -410.057451)
			(xy 380.14019 -410.057451) (xy 380.132434 -410.111391) (xy 380.117081 -410.16368) (xy 380.094442 -410.213253)
			(xy 380.06498 -410.259099) (xy 380.029292 -410.300285) (xy 379.988107 -410.335974) (xy 379.942261 -410.365438)
			(xy 379.89269 -410.388077) (xy 379.840401 -410.403432) (xy 379.786458 -410.411189) (xy 379.75921 -410.411676)
			(xy 378.89561 -410.411676) (xy 378.868354 -410.411278) (xy 378.814398 -410.403521) (xy 378.762094 -410.388165)
			(xy 378.712509 -410.365521) (xy 378.66665 -410.336051) (xy 378.625453 -410.300354) (xy 378.589755 -410.259158)
			(xy 378.560284 -410.2133) (xy 378.537639 -410.163715) (xy 378.522281 -410.111412) (xy 378.514523 -410.057456)
			(xy 377.077012 -410.057456) (xy 377.069256 -410.111401) (xy 377.053899 -410.163697) (xy 377.031257 -410.213275)
			(xy 377.001788 -410.259126) (xy 376.966094 -410.300316) (xy 376.924901 -410.336006) (xy 376.879048 -410.365471)
			(xy 376.829469 -410.38811) (xy 376.777172 -410.403462) (xy 376.723222 -410.411215) (xy 376.69597 -410.411676)
			(xy 375.83237 -410.411676) (xy 375.805118 -410.411252) (xy 375.751169 -410.403491) (xy 375.698873 -410.388132)
			(xy 375.649296 -410.365488) (xy 375.603445 -410.336018) (xy 375.562255 -410.300324) (xy 375.526564 -410.259131)
			(xy 375.497098 -410.213278) (xy 375.474457 -410.163699) (xy 375.459102 -410.111402) (xy 375.451346 -410.057452)
			(xy 374.013689 -410.057452) (xy 374.005935 -410.111388) (xy 373.990583 -410.163676) (xy 373.967945 -410.213247)
			(xy 373.938484 -410.259092) (xy 373.902799 -410.300278) (xy 373.861616 -410.335966) (xy 373.815773 -410.365431)
			(xy 373.766204 -410.388072) (xy 373.713917 -410.403428) (xy 373.659978 -410.411188) (xy 373.63273 -410.411676)
			(xy 372.76913 -410.411676) (xy 372.741873 -410.411279) (xy 372.687915 -410.403525) (xy 372.635609 -410.38817)
			(xy 372.586021 -410.365528) (xy 372.54016 -410.336058) (xy 372.49896 -410.300361) (xy 372.46326 -410.259164)
			(xy 372.433787 -410.213306) (xy 372.41114 -410.163719) (xy 372.395781 -410.111415) (xy 372.388023 -410.057457)
			(xy 352.519512 -410.057457) (xy 352.511756 -410.111399) (xy 352.496401 -410.163693) (xy 352.473759 -410.21327)
			(xy 352.444293 -410.25912) (xy 352.408601 -410.300309) (xy 352.36741 -410.336) (xy 352.321559 -410.365465)
			(xy 352.271982 -410.388105) (xy 352.219687 -410.403459) (xy 352.165739 -410.411214) (xy 352.138488 -410.411676)
			(xy 351.274888 -410.411676) (xy 351.247635 -410.411253) (xy 351.193684 -410.403495) (xy 351.141386 -410.388137)
			(xy 351.091807 -410.365494) (xy 351.045954 -410.336025) (xy 351.004762 -410.30033) (xy 350.969068 -410.259137)
			(xy 350.939601 -410.213283) (xy 350.916958 -410.163702) (xy 350.901603 -410.111404) (xy 350.893846 -410.057453)
			(xy 349.456189 -410.057453) (xy 349.448435 -410.111386) (xy 349.433084 -410.163672) (xy 349.410448 -410.213242)
			(xy 349.380989 -410.259086) (xy 349.345306 -410.300272) (xy 349.304125 -410.33596) (xy 349.258284 -410.365425)
			(xy 349.208717 -410.388067) (xy 349.156433 -410.403425) (xy 349.102495 -410.411187) (xy 349.075248 -410.411676)
			(xy 348.211648 -410.411676) (xy 348.184391 -410.41128) (xy 348.13043 -410.403528) (xy 348.078122 -410.388175)
			(xy 348.028531 -410.365533) (xy 347.982668 -410.336064) (xy 347.941466 -410.300367) (xy 347.905765 -410.25917)
			(xy 347.87629 -410.213311) (xy 347.853642 -410.163723) (xy 347.838282 -410.111417) (xy 347.830523 -410.057457)
			(xy 346.392989 -410.057457) (xy 346.385234 -410.111391) (xy 346.369881 -410.163681) (xy 346.347242 -410.213253)
			(xy 346.317779 -410.259099) (xy 346.282091 -410.300286) (xy 346.240906 -410.335974) (xy 346.19506 -410.365438)
			(xy 346.145488 -410.388078) (xy 346.093199 -410.403432) (xy 346.039257 -410.411189) (xy 346.012008 -410.411676)
			(xy 345.148408 -410.411676) (xy 345.121152 -410.411278) (xy 345.067196 -410.403521) (xy 345.014893 -410.388164)
			(xy 344.965307 -410.36552) (xy 344.919449 -410.33605) (xy 344.878252 -410.300353) (xy 344.842555 -410.259157)
			(xy 344.813084 -410.2133) (xy 344.790439 -410.163715) (xy 344.775081 -410.111412) (xy 344.767323 -410.057456)
			(xy 343.329812 -410.057456) (xy 343.322055 -410.111401) (xy 343.306699 -410.163697) (xy 343.284056 -410.213275)
			(xy 343.254588 -410.259126) (xy 343.218894 -410.300316) (xy 343.177701 -410.336007) (xy 343.131847 -410.365472)
			(xy 343.082267 -410.38811) (xy 343.02997 -410.403462) (xy 342.97602 -410.411215) (xy 342.948768 -410.411676)
			(xy 342.085168 -410.411676) (xy 342.057916 -410.411252) (xy 342.003967 -410.403491) (xy 341.951672 -410.388132)
			(xy 341.902095 -410.365487) (xy 341.856244 -410.336017) (xy 341.815054 -410.300323) (xy 341.779363 -410.25913)
			(xy 341.749898 -410.213277) (xy 341.727257 -410.163698) (xy 341.711902 -410.111402) (xy 341.704146 -410.057452)
			(xy 340.266489 -410.057452) (xy 340.258735 -410.111388) (xy 340.243382 -410.163676) (xy 340.220745 -410.213248)
			(xy 340.191284 -410.259093) (xy 340.155599 -410.300279) (xy 340.114415 -410.335967) (xy 340.068572 -410.365432)
			(xy 340.019003 -410.388073) (xy 339.966716 -410.403429) (xy 339.912776 -410.411188) (xy 339.885528 -410.411676)
			(xy 339.021928 -410.411676) (xy 338.994672 -410.411279) (xy 338.940713 -410.403525) (xy 338.888407 -410.38817)
			(xy 338.838819 -410.365527) (xy 338.792959 -410.336057) (xy 338.751759 -410.30036) (xy 338.71606 -410.259164)
			(xy 338.686587 -410.213305) (xy 338.66394 -410.163719) (xy 338.648581 -410.111414) (xy 338.640823 -410.057456)
			(xy 337.203312 -410.057456) (xy 337.195556 -410.111399) (xy 337.180201 -410.163693) (xy 337.157559 -410.21327)
			(xy 337.128093 -410.25912) (xy 337.092401 -410.300309) (xy 337.05121 -410.336) (xy 337.005359 -410.365465)
			(xy 336.955782 -410.388105) (xy 336.903487 -410.403459) (xy 336.849539 -410.411214) (xy 336.822288 -410.411676)
			(xy 335.958688 -410.411676) (xy 335.931435 -410.411253) (xy 335.877484 -410.403495) (xy 335.825186 -410.388137)
			(xy 335.775607 -410.365494) (xy 335.729754 -410.336025) (xy 335.688562 -410.30033) (xy 335.652868 -410.259137)
			(xy 335.623401 -410.213283) (xy 335.600758 -410.163702) (xy 335.585403 -410.111404) (xy 335.577646 -410.057453)
			(xy 334.139989 -410.057453) (xy 334.132235 -410.111386) (xy 334.116884 -410.163672) (xy 334.094248 -410.213242)
			(xy 334.064789 -410.259086) (xy 334.029106 -410.300272) (xy 333.987925 -410.33596) (xy 333.942084 -410.365425)
			(xy 333.892517 -410.388067) (xy 333.840233 -410.403425) (xy 333.786295 -410.411187) (xy 333.759048 -410.411676)
			(xy 332.895448 -410.411676) (xy 332.868191 -410.41128) (xy 332.81423 -410.403528) (xy 332.761922 -410.388175)
			(xy 332.712331 -410.365533) (xy 332.666468 -410.336064) (xy 332.625266 -410.300367) (xy 332.589565 -410.25917)
			(xy 332.56009 -410.213311) (xy 332.537442 -410.163723) (xy 332.522082 -410.111417) (xy 332.514323 -410.057457)
			(xy 331.076789 -410.057457) (xy 331.069034 -410.111391) (xy 331.053681 -410.163681) (xy 331.031042 -410.213253)
			(xy 331.001579 -410.259099) (xy 330.965891 -410.300286) (xy 330.924706 -410.335974) (xy 330.87886 -410.365438)
			(xy 330.829288 -410.388078) (xy 330.776999 -410.403432) (xy 330.723057 -410.411189) (xy 330.695808 -410.411676)
			(xy 329.832208 -410.411676) (xy 329.804952 -410.411278) (xy 329.750996 -410.403521) (xy 329.698693 -410.388164)
			(xy 329.649107 -410.36552) (xy 329.603249 -410.33605) (xy 329.562052 -410.300353) (xy 329.526355 -410.259157)
			(xy 329.496884 -410.2133) (xy 329.474239 -410.163715) (xy 329.458881 -410.111412) (xy 329.451123 -410.057456)
			(xy 328.013612 -410.057456) (xy 328.005855 -410.111401) (xy 327.990499 -410.163697) (xy 327.967856 -410.213275)
			(xy 327.938388 -410.259126) (xy 327.902694 -410.300316) (xy 327.861501 -410.336007) (xy 327.815647 -410.365472)
			(xy 327.766067 -410.38811) (xy 327.71377 -410.403462) (xy 327.65982 -410.411215) (xy 327.632568 -410.411676)
			(xy 326.768968 -410.411676) (xy 326.741716 -410.411252) (xy 326.687767 -410.403491) (xy 326.635472 -410.388132)
			(xy 326.585895 -410.365487) (xy 326.540044 -410.336017) (xy 326.498854 -410.300323) (xy 326.463163 -410.25913)
			(xy 326.433698 -410.213277) (xy 326.411057 -410.163698) (xy 326.395702 -410.111402) (xy 326.387946 -410.057452)
			(xy 324.950289 -410.057452) (xy 324.942535 -410.111388) (xy 324.927182 -410.163676) (xy 324.904545 -410.213248)
			(xy 324.875084 -410.259093) (xy 324.839399 -410.300279) (xy 324.798215 -410.335967) (xy 324.752372 -410.365432)
			(xy 324.702803 -410.388073) (xy 324.650516 -410.403429) (xy 324.596576 -410.411188) (xy 324.569328 -410.411676)
			(xy 323.705728 -410.411676) (xy 323.678472 -410.411279) (xy 323.624513 -410.403525) (xy 323.572207 -410.38817)
			(xy 323.522619 -410.365527) (xy 323.476759 -410.336057) (xy 323.435559 -410.30036) (xy 323.39986 -410.259164)
			(xy 323.370387 -410.213305) (xy 323.34774 -410.163719) (xy 323.332381 -410.111414) (xy 323.324623 -410.057456)
			(xy 321.887112 -410.057456) (xy 321.879356 -410.111399) (xy 321.864001 -410.163693) (xy 321.841359 -410.21327)
			(xy 321.811893 -410.25912) (xy 321.776201 -410.300309) (xy 321.73501 -410.336) (xy 321.689159 -410.365465)
			(xy 321.639582 -410.388105) (xy 321.587287 -410.403459) (xy 321.533339 -410.411214) (xy 321.506088 -410.411676)
			(xy 320.642488 -410.411676) (xy 320.615235 -410.411253) (xy 320.561284 -410.403495) (xy 320.508986 -410.388137)
			(xy 320.459407 -410.365494) (xy 320.413554 -410.336025) (xy 320.372362 -410.30033) (xy 320.336668 -410.259137)
			(xy 320.307201 -410.213283) (xy 320.284558 -410.163702) (xy 320.269203 -410.111404) (xy 320.261446 -410.057453)
			(xy 318.823789 -410.057453) (xy 318.816035 -410.111386) (xy 318.800684 -410.163672) (xy 318.778048 -410.213242)
			(xy 318.748589 -410.259086) (xy 318.712906 -410.300272) (xy 318.671725 -410.33596) (xy 318.625884 -410.365425)
			(xy 318.576317 -410.388067) (xy 318.524033 -410.403425) (xy 318.470095 -410.411187) (xy 318.442848 -410.411676)
			(xy 317.579248 -410.411676) (xy 317.551991 -410.41128) (xy 317.49803 -410.403528) (xy 317.445722 -410.388175)
			(xy 317.396131 -410.365533) (xy 317.350268 -410.336064) (xy 317.309066 -410.300367) (xy 317.273365 -410.25917)
			(xy 317.24389 -410.213311) (xy 317.221242 -410.163723) (xy 317.205882 -410.111417) (xy 317.198123 -410.057457)
			(xy 315.760589 -410.057457) (xy 315.752834 -410.111391) (xy 315.737481 -410.163681) (xy 315.714842 -410.213253)
			(xy 315.685379 -410.259099) (xy 315.649691 -410.300286) (xy 315.608506 -410.335974) (xy 315.56266 -410.365438)
			(xy 315.513088 -410.388078) (xy 315.460799 -410.403432) (xy 315.406857 -410.411189) (xy 315.379608 -410.411676)
			(xy 314.516008 -410.411676) (xy 314.488752 -410.411278) (xy 314.434796 -410.403521) (xy 314.382493 -410.388164)
			(xy 314.332907 -410.36552) (xy 314.287049 -410.33605) (xy 314.245852 -410.300353) (xy 314.210155 -410.259157)
			(xy 314.180684 -410.2133) (xy 314.158039 -410.163715) (xy 314.142681 -410.111412) (xy 314.134923 -410.057456)
			(xy 312.697412 -410.057456) (xy 312.689655 -410.111401) (xy 312.674299 -410.163697) (xy 312.651656 -410.213275)
			(xy 312.622188 -410.259126) (xy 312.586494 -410.300316) (xy 312.545301 -410.336007) (xy 312.499447 -410.365472)
			(xy 312.449867 -410.38811) (xy 312.39757 -410.403462) (xy 312.34362 -410.411215) (xy 312.316368 -410.411676)
			(xy 311.452768 -410.411676) (xy 311.425516 -410.411252) (xy 311.371567 -410.403491) (xy 311.319272 -410.388132)
			(xy 311.269695 -410.365487) (xy 311.223844 -410.336017) (xy 311.182654 -410.300323) (xy 311.146963 -410.25913)
			(xy 311.117498 -410.213277) (xy 311.094857 -410.163698) (xy 311.079502 -410.111402) (xy 311.071746 -410.057452)
			(xy 309.634089 -410.057452) (xy 309.626335 -410.111388) (xy 309.610982 -410.163676) (xy 309.588345 -410.213248)
			(xy 309.558884 -410.259093) (xy 309.523199 -410.300279) (xy 309.482015 -410.335967) (xy 309.436172 -410.365432)
			(xy 309.386603 -410.388073) (xy 309.334316 -410.403429) (xy 309.280376 -410.411188) (xy 309.253128 -410.411676)
			(xy 308.389528 -410.411676) (xy 308.362272 -410.411279) (xy 308.308313 -410.403525) (xy 308.256007 -410.38817)
			(xy 308.206419 -410.365527) (xy 308.160559 -410.336057) (xy 308.119359 -410.30036) (xy 308.08366 -410.259164)
			(xy 308.054187 -410.213305) (xy 308.03154 -410.163719) (xy 308.016181 -410.111414) (xy 308.008423 -410.057456)
			(xy 306.570912 -410.057456) (xy 306.563156 -410.111399) (xy 306.547801 -410.163693) (xy 306.525159 -410.21327)
			(xy 306.495693 -410.25912) (xy 306.460001 -410.300309) (xy 306.41881 -410.336) (xy 306.372959 -410.365465)
			(xy 306.323382 -410.388105) (xy 306.271087 -410.403459) (xy 306.217139 -410.411214) (xy 306.189888 -410.411676)
			(xy 305.326288 -410.411676) (xy 305.299035 -410.411253) (xy 305.245084 -410.403495) (xy 305.192786 -410.388137)
			(xy 305.143207 -410.365494) (xy 305.097354 -410.336025) (xy 305.056162 -410.30033) (xy 305.020468 -410.259137)
			(xy 304.991001 -410.213283) (xy 304.968358 -410.163702) (xy 304.953003 -410.111404) (xy 304.945246 -410.057453)
			(xy 280.83256 -410.057453) (xy 280.83256 -414.855152) (xy 292.492176 -414.855152) (xy 292.506654 -414.827974)
			(xy 292.519946 -414.803725) (xy 292.55246 -414.758997) (xy 292.591093 -414.719435) (xy 292.635037 -414.685868)
			(xy 292.683368 -414.659001) (xy 292.735073 -414.639397) (xy 292.789068 -414.627468) (xy 292.84422 -414.623464)
			(xy 292.899372 -414.627468) (xy 292.953367 -414.639397) (xy 293.005072 -414.659001) (xy 293.053403 -414.685868)
			(xy 293.097347 -414.719435) (xy 293.13598 -414.758997) (xy 293.168494 -414.803725) (xy 293.181786 -414.827974)
			(xy 293.196264 -414.855152) (xy 304.845466 -414.855152) (xy 304.858928 -414.82518) (xy 304.870632 -414.800489)
			(xy 304.900057 -414.754449) (xy 304.93575 -414.713077) (xy 304.97698 -414.677221) (xy 305.022904 -414.647615)
			(xy 305.072582 -414.624863) (xy 305.124998 -414.609431) (xy 305.17908 -414.601635) (xy 305.23372 -414.601635)
			(xy 305.287802 -414.609431) (xy 305.340218 -414.624863) (xy 305.389896 -414.647615) (xy 305.43582 -414.677221)
			(xy 305.47705 -414.713077) (xy 305.512743 -414.754449) (xy 305.542168 -414.800489) (xy 305.553872 -414.82518)
			(xy 305.567334 -414.855152) (xy 309.099712 -414.855152) (xy 309.124664 -414.855634) (xy 309.173957 -414.863427)
			(xy 309.221423 -414.878835) (xy 309.265895 -414.901478) (xy 309.306277 -414.930799) (xy 309.324248 -414.948116)
			(xy 310.508396 -416.132264) (xy 310.525678 -416.150264) (xy 310.554983 -416.190648) (xy 310.57762 -416.235114)
			(xy 310.593033 -416.28257) (xy 310.600843 -416.331852) (xy 310.60136 -416.3568) (xy 310.60136 -427.289976)
			(xy 314.138056 -427.289976) (xy 314.13817 -427.274891) (xy 314.139948 -427.244772) (xy 314.141612 -427.229778)
			(xy 314.141612 -426.150024) (xy 314.139943 -426.135031) (xy 314.138165 -426.104912) (xy 314.138056 -426.089826)
			(xy 314.138166 -426.07474) (xy 314.139947 -426.044622) (xy 314.141612 -426.029628) (xy 314.141612 -425.419012)
			(xy 314.142023 -425.406928) (xy 314.14949 -425.383942) (xy 314.163696 -425.36439) (xy 314.183249 -425.350186)
			(xy 314.206236 -425.342722) (xy 314.21832 -425.342304) (xy 315.15812 -425.342304) (xy 315.170197 -425.342748)
			(xy 315.193167 -425.350217) (xy 315.212704 -425.364419) (xy 315.226898 -425.383962) (xy 315.234357 -425.406935)
			(xy 315.234828 -425.419012) (xy 315.234828 -427.960536) (xy 315.234367 -427.97261) (xy 315.226897 -427.995576)
			(xy 315.212699 -428.01511) (xy 315.193161 -428.029304) (xy 315.170195 -428.036769) (xy 315.15812 -428.037244)
			(xy 314.21832 -428.037244) (xy 314.20625 -428.036719) (xy 314.18329 -428.029267) (xy 314.163755 -428.015085)
			(xy 314.149559 -427.995561) (xy 314.142089 -427.972606) (xy 314.141612 -427.960536) (xy 314.141612 -427.350174)
			(xy 314.139948 -427.33518) (xy 314.138166 -427.305062) (xy 314.138056 -427.289976) (xy 310.60136 -427.289976)
			(xy 310.60136 -428.28972) (xy 316.138052 -428.28972) (xy 316.138162 -428.274634) (xy 316.139943 -428.244516)
			(xy 316.141608 -428.229522) (xy 316.141608 -427.150022) (xy 316.139939 -427.135029) (xy 316.138161 -427.10491)
			(xy 316.138052 -427.089824) (xy 316.138162 -427.074738) (xy 316.139943 -427.04462) (xy 316.141608 -427.029626)
			(xy 316.141608 -426.41901) (xy 316.142115 -426.406924) (xy 316.149565 -426.383929) (xy 316.163743 -426.364352)
			(xy 316.183266 -426.3501) (xy 316.206232 -426.342562) (xy 316.218316 -426.342048) (xy 317.158116 -426.342048)
			(xy 317.170221 -426.342502) (xy 317.193239 -426.349999) (xy 317.212808 -426.364253) (xy 317.227004 -426.383863)
			(xy 317.234433 -426.406904) (xy 317.234824 -426.41901) (xy 317.234824 -427.289976) (xy 318.138048 -427.289976)
			(xy 318.138162 -427.274891) (xy 318.13994 -427.244772) (xy 318.141604 -427.229778) (xy 318.141604 -426.150024)
			(xy 318.139935 -426.135031) (xy 318.138157 -426.104912) (xy 318.138048 -426.089826) (xy 318.138158 -426.07474)
			(xy 318.139939 -426.044622) (xy 318.141604 -426.029628) (xy 318.141604 -425.419012) (xy 318.142023 -425.406929)
			(xy 318.149489 -425.383944) (xy 318.163693 -425.364393) (xy 318.183244 -425.350189) (xy 318.206229 -425.342723)
			(xy 318.218312 -425.342304) (xy 319.158112 -425.342304) (xy 319.170188 -425.342754) (xy 319.193158 -425.350222)
			(xy 319.212696 -425.364421) (xy 319.226889 -425.383964) (xy 319.234349 -425.406935) (xy 319.23482 -425.419012)
			(xy 319.23482 -427.960536) (xy 319.234367 -427.972611) (xy 319.226896 -427.995578) (xy 319.212696 -428.015113)
			(xy 319.193156 -428.029307) (xy 319.170187 -428.036771) (xy 319.158112 -428.037244) (xy 318.218312 -428.037244)
			(xy 318.206242 -428.036726) (xy 318.183281 -428.029271) (xy 318.163747 -428.015087) (xy 318.149551 -427.995562)
			(xy 318.142081 -427.972606) (xy 318.141604 -427.960536) (xy 318.141604 -427.350174) (xy 318.13994 -427.33518)
			(xy 318.138158 -427.305062) (xy 318.138048 -427.289976) (xy 317.234824 -427.289976) (xy 317.234824 -428.28972)
			(xy 320.138044 -428.28972) (xy 320.138154 -428.274634) (xy 320.139935 -428.244516) (xy 320.1416 -428.229522)
			(xy 320.1416 -427.150022) (xy 320.139931 -427.135029) (xy 320.138153 -427.10491) (xy 320.138044 -427.089824)
			(xy 320.138154 -427.074738) (xy 320.139935 -427.04462) (xy 320.1416 -427.029626) (xy 320.1416 -426.41901)
			(xy 320.142115 -426.406925) (xy 320.149564 -426.383931) (xy 320.16374 -426.364355) (xy 320.183261 -426.350103)
			(xy 320.206225 -426.342563) (xy 320.218308 -426.342048) (xy 321.158108 -426.342048) (xy 321.170212 -426.342509)
			(xy 321.193231 -426.350004) (xy 321.212799 -426.364256) (xy 321.226996 -426.383865) (xy 321.234425 -426.406905)
			(xy 321.234816 -426.41901) (xy 321.234816 -427.289976) (xy 322.13804 -427.289976) (xy 322.138155 -427.274891)
			(xy 322.139932 -427.244772) (xy 322.141596 -427.229778) (xy 322.141596 -426.150024) (xy 322.139927 -426.135031)
			(xy 322.138149 -426.104912) (xy 322.13804 -426.089826) (xy 322.13815 -426.07474) (xy 322.139931 -426.044622)
			(xy 322.141596 -426.029628) (xy 322.141596 -425.419012) (xy 322.142023 -425.40693) (xy 322.149488 -425.383947)
			(xy 322.16369 -425.364396) (xy 322.183239 -425.350191) (xy 322.206222 -425.342724) (xy 322.218304 -425.342304)
			(xy 323.158104 -425.342304) (xy 323.170188 -425.342709) (xy 323.193173 -425.350179) (xy 323.212724 -425.364387)
			(xy 323.226928 -425.383941) (xy 323.234393 -425.406928) (xy 323.234812 -425.419012) (xy 323.234812 -427.960536)
			(xy 323.234367 -427.972612) (xy 323.226895 -427.99558) (xy 323.212693 -428.015116) (xy 323.193151 -428.029309)
			(xy 323.17018 -428.036772) (xy 323.158104 -428.037244) (xy 322.218304 -428.037244) (xy 322.206233 -428.036733)
			(xy 322.183272 -428.029276) (xy 322.163738 -428.01509) (xy 322.149542 -427.995564) (xy 322.142073 -427.972607)
			(xy 322.141596 -427.960536) (xy 322.141596 -427.350174) (xy 322.139932 -427.33518) (xy 322.13815 -427.305062)
			(xy 322.13804 -427.289976) (xy 321.234816 -427.289976) (xy 321.234816 -428.28972) (xy 324.138036 -428.28972)
			(xy 324.138148 -428.274634) (xy 324.139929 -428.244516) (xy 324.141592 -428.229522) (xy 324.141592 -427.150022)
			(xy 324.139923 -427.135029) (xy 324.138145 -427.10491) (xy 324.138036 -427.089824) (xy 324.138148 -427.074738)
			(xy 324.139929 -427.04462) (xy 324.141592 -427.029626) (xy 324.141592 -426.41901) (xy 324.142115 -426.406926)
			(xy 324.149563 -426.383934) (xy 324.163737 -426.364358) (xy 324.183256 -426.350105) (xy 324.206218 -426.342564)
			(xy 324.2183 -426.342048) (xy 325.1581 -426.342048) (xy 325.170204 -426.342515) (xy 325.193222 -426.350009)
			(xy 325.212791 -426.364259) (xy 325.226987 -426.383866) (xy 325.234417 -426.406905) (xy 325.234808 -426.41901)
			(xy 325.234808 -427.289976) (xy 326.138032 -427.289976) (xy 326.138149 -427.274891) (xy 326.139927 -427.244772)
			(xy 326.141588 -427.229778) (xy 326.141588 -426.150024) (xy 326.139919 -426.135031) (xy 326.138141 -426.104912)
			(xy 326.138032 -426.089826) (xy 326.138144 -426.07474) (xy 326.139925 -426.044622) (xy 326.141588 -426.029628)
			(xy 326.141588 -425.419012) (xy 326.142023 -425.40693) (xy 326.149487 -425.383949) (xy 326.163687 -425.364399)
			(xy 326.183234 -425.350194) (xy 326.206214 -425.342726) (xy 326.218296 -425.342304) (xy 327.158096 -425.342304)
			(xy 327.17018 -425.342716) (xy 327.193164 -425.350184) (xy 327.212716 -425.36439) (xy 327.22692 -425.383943)
			(xy 327.234385 -425.406928) (xy 327.234804 -425.419012) (xy 327.234804 -427.960536) (xy 327.234367 -427.972613)
			(xy 327.226894 -427.995582) (xy 327.21269 -428.015119) (xy 327.193146 -428.029312) (xy 327.170173 -428.036773)
			(xy 327.158096 -428.037244) (xy 326.218296 -428.037244) (xy 326.206225 -428.03674) (xy 326.183264 -428.02928)
			(xy 326.16373 -428.015093) (xy 326.149534 -427.995565) (xy 326.142065 -427.972607) (xy 326.141588 -427.960536)
			(xy 326.141588 -427.350174) (xy 326.139924 -427.33518) (xy 326.138142 -427.305062) (xy 326.138032 -427.289976)
			(xy 325.234808 -427.289976) (xy 325.234808 -428.28972) (xy 328.138028 -428.28972) (xy 328.13814 -428.274634)
			(xy 328.139921 -428.244516) (xy 328.141584 -428.229522) (xy 328.141584 -427.150022) (xy 328.139915 -427.135029)
			(xy 328.138137 -427.10491) (xy 328.138028 -427.089824) (xy 328.13814 -427.074738) (xy 328.139921 -427.04462)
			(xy 328.141584 -427.029626) (xy 328.141584 -426.41901) (xy 328.142017 -426.406917) (xy 328.149476 -426.383909)
			(xy 328.16367 -426.364325) (xy 328.183214 -426.350076) (xy 328.2062 -426.342551) (xy 328.218292 -426.342048)
			(xy 329.158092 -426.342048) (xy 329.170195 -426.342522) (xy 329.193214 -426.350013) (xy 329.212782 -426.364262)
			(xy 329.226979 -426.383868) (xy 329.234409 -426.406906) (xy 329.2348 -426.41901) (xy 329.2348 -427.289976)
			(xy 331.138022 -427.289976) (xy 331.138113 -427.275402) (xy 331.139767 -427.246301) (xy 331.141324 -427.23181)
			(xy 331.141324 -426.147992) (xy 331.139781 -426.1335) (xy 331.138128 -426.1044) (xy 331.138022 -426.089826)
			(xy 331.138117 -426.075252) (xy 331.139769 -426.046151) (xy 331.141324 -426.03166) (xy 331.141324 -425.419012)
			(xy 331.141727 -425.406901) (xy 331.149226 -425.38387) (xy 331.16349 -425.364295) (xy 331.183116 -425.350101)
			(xy 331.206174 -425.342684) (xy 331.218286 -425.342304) (xy 332.158086 -425.342304) (xy 332.170171 -425.342819)
			(xy 332.193165 -425.350267) (xy 332.212742 -425.364443) (xy 332.226995 -425.383964) (xy 332.234533 -425.406929)
			(xy 332.235048 -425.419012) (xy 332.235048 -427.960536) (xy 332.234615 -427.972642) (xy 332.227111 -427.995662)
			(xy 332.212852 -428.01523) (xy 332.193238 -428.029426) (xy 332.170193 -428.036854) (xy 332.158086 -428.037244)
			(xy 331.218286 -428.037244) (xy 331.206194 -428.036804) (xy 331.18319 -428.029342) (xy 331.163609 -428.015149)
			(xy 331.14936 -427.995609) (xy 331.141831 -427.972627) (xy 331.141324 -427.960536) (xy 331.141324 -427.348142)
			(xy 331.139777 -427.33365) (xy 331.138127 -427.30455) (xy 331.138022 -427.289976) (xy 329.2348 -427.289976)
			(xy 329.2348 -428.28972) (xy 333.138018 -428.28972) (xy 333.138113 -428.275146) (xy 333.139764 -428.246045)
			(xy 333.14132 -428.231554) (xy 333.14132 -427.14799) (xy 333.139777 -427.133498) (xy 333.138124 -427.104398)
			(xy 333.138018 -427.089824) (xy 333.138113 -427.07525) (xy 333.139765 -427.046149) (xy 333.14132 -427.031658)
			(xy 333.14132 -426.41901) (xy 333.14182 -426.406898) (xy 333.149302 -426.383858) (xy 333.163538 -426.364258)
			(xy 333.183133 -426.350015) (xy 333.20617 -426.342525) (xy 333.218282 -426.342048) (xy 334.158082 -426.342048)
			(xy 334.170205 -426.342475) (xy 334.193265 -426.349964) (xy 334.212881 -426.364213) (xy 334.227132 -426.383828)
			(xy 334.234623 -426.406887) (xy 334.235044 -426.41901) (xy 334.235044 -427.289976) (xy 335.138014 -427.289976)
			(xy 335.138104 -427.275402) (xy 335.139759 -427.246301) (xy 335.141316 -427.23181) (xy 335.141316 -426.147992)
			(xy 335.139773 -426.1335) (xy 335.13812 -426.1044) (xy 335.138014 -426.089826) (xy 335.138109 -426.075252)
			(xy 335.13976 -426.046151) (xy 335.141316 -426.03166) (xy 335.141316 -425.419012) (xy 335.141727 -425.406902)
			(xy 335.149225 -425.383873) (xy 335.163487 -425.364298) (xy 335.183111 -425.350104) (xy 335.206167 -425.342685)
			(xy 335.218278 -425.342304) (xy 336.158078 -425.342304) (xy 336.170163 -425.342825) (xy 336.193157 -425.350272)
			(xy 336.212734 -425.364446) (xy 336.226986 -425.383966) (xy 336.234525 -425.406929) (xy 336.23504 -425.419012)
			(xy 336.23504 -427.960536) (xy 336.234615 -427.972643) (xy 336.22711 -427.995664) (xy 336.21285 -428.015233)
			(xy 336.193233 -428.029428) (xy 336.170186 -428.036855) (xy 336.158078 -428.037244) (xy 335.218278 -428.037244)
			(xy 335.206186 -428.036811) (xy 335.183182 -428.029347) (xy 335.163601 -428.015152) (xy 335.149351 -427.99561)
			(xy 335.141823 -427.972627) (xy 335.141316 -427.960536) (xy 335.141316 -427.348142) (xy 335.139769 -427.33365)
			(xy 335.138119 -427.30455) (xy 335.138014 -427.289976) (xy 334.235044 -427.289976) (xy 334.235044 -428.28972)
			(xy 337.13801 -428.28972) (xy 337.138104 -428.275146) (xy 337.139756 -428.246045) (xy 337.141312 -428.231554)
			(xy 337.141312 -427.14799) (xy 337.139769 -427.133498) (xy 337.138116 -427.104398) (xy 337.13801 -427.089824)
			(xy 337.138104 -427.07525) (xy 337.139756 -427.046149) (xy 337.141312 -427.031658) (xy 337.141312 -426.41901)
			(xy 337.14182 -426.406899) (xy 337.149301 -426.38386) (xy 337.163535 -426.36426) (xy 337.183128 -426.350018)
			(xy 337.206163 -426.342526) (xy 337.218274 -426.342048) (xy 338.158074 -426.342048) (xy 338.170196 -426.342482)
			(xy 338.193256 -426.349969) (xy 338.212872 -426.364216) (xy 338.227124 -426.38383) (xy 338.234615 -426.406888)
			(xy 338.235036 -426.41901) (xy 338.235036 -427.289976) (xy 339.138006 -427.289976) (xy 339.138096 -427.275402)
			(xy 339.139751 -427.246301) (xy 339.141308 -427.23181) (xy 339.141308 -426.147992) (xy 339.139765 -426.1335)
			(xy 339.138112 -426.1044) (xy 339.138006 -426.089826) (xy 339.138101 -426.075252) (xy 339.139752 -426.046151)
			(xy 339.141308 -426.03166) (xy 339.141308 -425.419012) (xy 339.141727 -425.406903) (xy 339.149224 -425.383875)
			(xy 339.163485 -425.364301) (xy 339.183106 -425.350106) (xy 339.20616 -425.342687) (xy 339.21827 -425.342304)
			(xy 340.15807 -425.342304) (xy 340.170154 -425.342832) (xy 340.193148 -425.350276) (xy 340.212725 -425.364448)
			(xy 340.226978 -425.383967) (xy 340.234517 -425.40693) (xy 340.235032 -425.419012) (xy 340.235032 -427.960536)
			(xy 340.234615 -427.972644) (xy 340.227109 -427.995667) (xy 340.212847 -428.015236) (xy 340.193228 -428.029431)
			(xy 340.170179 -428.036856) (xy 340.15807 -428.037244) (xy 339.21827 -428.037244) (xy 339.206177 -428.036818)
			(xy 339.183173 -428.029351) (xy 339.163592 -428.015154) (xy 339.149343 -427.995612) (xy 339.141815 -427.972627)
			(xy 339.141308 -427.960536) (xy 339.141308 -427.348142) (xy 339.139761 -427.33365) (xy 339.138111 -427.30455)
			(xy 339.138006 -427.289976) (xy 338.235036 -427.289976) (xy 338.235036 -428.28972) (xy 341.138002 -428.28972)
			(xy 341.138096 -428.275146) (xy 341.139748 -428.246045) (xy 341.141304 -428.231554) (xy 341.141304 -427.14799)
			(xy 341.139761 -427.133498) (xy 341.138108 -427.104398) (xy 341.138002 -427.089824) (xy 341.138096 -427.07525)
			(xy 341.139748 -427.046149) (xy 341.141304 -427.031658) (xy 341.141304 -426.41901) (xy 341.14182 -426.406899)
			(xy 341.1493 -426.383862) (xy 341.163532 -426.364263) (xy 341.183123 -426.35002) (xy 341.206156 -426.342527)
			(xy 341.218266 -426.342048) (xy 342.158066 -426.342048) (xy 342.170188 -426.342489) (xy 342.193247 -426.349973)
			(xy 342.212864 -426.364219) (xy 342.227116 -426.383831) (xy 342.234607 -426.406888) (xy 342.235028 -426.41901)
			(xy 342.235028 -427.289976) (xy 343.137998 -427.289976) (xy 343.138088 -427.275402) (xy 343.139743 -427.246301)
			(xy 343.1413 -427.23181) (xy 343.1413 -426.147992) (xy 343.139757 -426.1335) (xy 343.138104 -426.1044)
			(xy 343.137998 -426.089826) (xy 343.138093 -426.075252) (xy 343.139744 -426.046151) (xy 343.1413 -426.03166)
			(xy 343.1413 -425.419012) (xy 343.141727 -425.406904) (xy 343.149223 -425.383877) (xy 343.163482 -425.364304)
			(xy 343.183101 -425.350109) (xy 343.206152 -425.342688) (xy 343.218262 -425.342304) (xy 344.158062 -425.342304)
			(xy 344.170146 -425.342839) (xy 344.193139 -425.350281) (xy 344.212717 -425.364451) (xy 344.22697 -425.383968)
			(xy 344.234509 -425.40693) (xy 344.235024 -425.419012) (xy 344.235024 -427.960536) (xy 344.234615 -427.972644)
			(xy 344.227108 -427.995669) (xy 344.212844 -428.015239) (xy 344.193223 -428.029433) (xy 344.170172 -428.036857)
			(xy 344.158062 -428.037244) (xy 343.218262 -428.037244) (xy 343.206169 -428.036825) (xy 343.183164 -428.029356)
			(xy 343.163584 -428.015157) (xy 343.149335 -427.995613) (xy 343.141807 -427.972628) (xy 343.1413 -427.960536)
			(xy 343.1413 -427.348142) (xy 343.139753 -427.33365) (xy 343.138103 -427.30455) (xy 343.137998 -427.289976)
			(xy 342.235028 -427.289976) (xy 342.235028 -428.28972) (xy 345.137994 -428.28972) (xy 345.138088 -428.275146)
			(xy 345.13974 -428.246045) (xy 345.141296 -428.231554) (xy 345.141296 -427.14799) (xy 345.139753 -427.133498)
			(xy 345.1381 -427.104398) (xy 345.137994 -427.089824) (xy 345.138088 -427.07525) (xy 345.13974 -427.046149)
			(xy 345.141296 -427.031658) (xy 345.141296 -426.41901) (xy 345.14182 -426.4069) (xy 345.149299 -426.383864)
			(xy 345.163529 -426.364266) (xy 345.183118 -426.350023) (xy 345.206148 -426.342528) (xy 345.218258 -426.342048)
			(xy 346.158058 -426.342048) (xy 346.17018 -426.342496) (xy 346.193239 -426.349978) (xy 346.212855 -426.364222)
			(xy 346.227108 -426.383833) (xy 346.234599 -426.406889) (xy 346.23502 -426.41901) (xy 346.23502 -428.960534)
			(xy 346.234669 -428.972663) (xy 346.227162 -428.99573) (xy 346.212894 -429.015348) (xy 346.193262 -429.029597)
			(xy 346.170187 -429.03708) (xy 346.158058 -429.037496) (xy 345.218258 -429.037496) (xy 345.206145 -429.037025)
			(xy 345.183106 -429.02953) (xy 345.163508 -429.015287) (xy 345.149266 -428.995687) (xy 345.141774 -428.972647)
			(xy 345.141296 -428.960534) (xy 345.141296 -428.347886) (xy 345.139753 -428.333394) (xy 345.1381 -428.304294)
			(xy 345.137994 -428.28972) (xy 342.235028 -428.28972) (xy 342.235028 -428.960534) (xy 342.234617 -428.972654)
			(xy 342.227116 -428.995704) (xy 342.21286 -429.015308) (xy 342.193243 -429.029547) (xy 342.170186 -429.037027)
			(xy 342.158066 -429.037496) (xy 341.218266 -429.037496) (xy 341.206153 -429.037018) (xy 341.183114 -429.029525)
			(xy 341.163516 -429.015284) (xy 341.149275 -428.995686) (xy 341.141782 -428.972647) (xy 341.141304 -428.960534)
			(xy 341.141304 -428.347886) (xy 341.139761 -428.333394) (xy 341.138108 -428.304294) (xy 341.138002 -428.28972)
			(xy 338.235036 -428.28972) (xy 338.235036 -428.960534) (xy 338.234617 -428.972653) (xy 338.227117 -428.995702)
			(xy 338.212862 -429.015305) (xy 338.193248 -429.029545) (xy 338.170193 -429.037026) (xy 338.158074 -429.037496)
			(xy 337.218274 -429.037496) (xy 337.206161 -429.037011) (xy 337.183123 -429.029521) (xy 337.163525 -429.015281)
			(xy 337.149283 -428.995684) (xy 337.14179 -428.972646) (xy 337.141312 -428.960534) (xy 337.141312 -428.347886)
			(xy 337.139769 -428.333394) (xy 337.138116 -428.304294) (xy 337.13801 -428.28972) (xy 334.235044 -428.28972)
			(xy 334.235044 -428.960534) (xy 334.234617 -428.972652) (xy 334.227118 -428.9957) (xy 334.212865 -429.015302)
			(xy 334.193253 -429.029542) (xy 334.1702 -429.037025) (xy 334.158082 -429.037496) (xy 333.218282 -429.037496)
			(xy 333.20617 -429.037004) (xy 333.183132 -429.029516) (xy 333.163533 -429.015278) (xy 333.149291 -428.995683)
			(xy 333.141798 -428.972646) (xy 333.14132 -428.960534) (xy 333.14132 -428.347886) (xy 333.139777 -428.333394)
			(xy 333.138124 -428.304294) (xy 333.138018 -428.28972) (xy 329.2348 -428.28972) (xy 329.2348 -428.960534)
			(xy 329.234322 -428.972621) (xy 329.226861 -428.995616) (xy 329.212676 -429.015192) (xy 329.193148 -429.029443)
			(xy 329.170178 -429.036981) (xy 329.158092 -429.037496) (xy 328.218292 -429.037496) (xy 328.206182 -429.037091)
			(xy 328.183154 -429.029588) (xy 328.163581 -429.015324) (xy 328.149386 -428.9957) (xy 328.141967 -428.972645)
			(xy 328.141584 -428.960534) (xy 328.141584 -428.349918) (xy 328.139915 -428.334925) (xy 328.138137 -428.304806)
			(xy 328.138028 -428.28972) (xy 325.234808 -428.28972) (xy 325.234808 -428.960534) (xy 325.234323 -428.972621)
			(xy 325.226862 -428.995614) (xy 325.212679 -429.01519) (xy 325.193153 -429.029441) (xy 325.170185 -429.03698)
			(xy 325.1581 -429.037496) (xy 324.2183 -429.037496) (xy 324.206191 -429.037084) (xy 324.183163 -429.029584)
			(xy 324.163589 -429.015321) (xy 324.149395 -428.995699) (xy 324.141975 -428.972645) (xy 324.141592 -428.960534)
			(xy 324.141592 -428.349918) (xy 324.139923 -428.334925) (xy 324.138145 -428.304806) (xy 324.138036 -428.28972)
			(xy 321.234816 -428.28972) (xy 321.234816 -428.960534) (xy 321.234421 -428.97263) (xy 321.226949 -428.995639)
			(xy 321.212746 -429.015222) (xy 321.193195 -429.02947) (xy 321.170203 -429.036993) (xy 321.158108 -429.037496)
			(xy 320.218308 -429.037496) (xy 320.206199 -429.037077) (xy 320.183171 -429.029579) (xy 320.163598 -429.015319)
			(xy 320.149403 -428.995697) (xy 320.141983 -428.972644) (xy 320.1416 -428.960534) (xy 320.1416 -428.349918)
			(xy 320.139931 -428.334925) (xy 320.138153 -428.304806) (xy 320.138044 -428.28972) (xy 317.234824 -428.28972)
			(xy 317.234824 -428.960534) (xy 317.234421 -428.972629) (xy 317.226951 -428.995637) (xy 317.212749 -429.015219)
			(xy 317.1932 -429.029467) (xy 317.17021 -429.036992) (xy 317.158116 -429.037496) (xy 316.218316 -429.037496)
			(xy 316.206208 -429.03707) (xy 316.18318 -429.029574) (xy 316.163607 -429.015315) (xy 316.149412 -428.995695)
			(xy 316.141991 -428.972644) (xy 316.141608 -428.960534) (xy 316.141608 -428.349918) (xy 316.139939 -428.334925)
			(xy 316.138161 -428.304806) (xy 316.138052 -428.28972) (xy 310.60136 -428.28972) (xy 310.60136 -430.889918)
			(xy 314.138056 -430.889918) (xy 314.138165 -430.874832) (xy 314.139947 -430.844714) (xy 314.141612 -430.82972)
			(xy 314.141612 -429.749966) (xy 314.139947 -429.734972) (xy 314.138166 -429.704854) (xy 314.138056 -429.689768)
			(xy 314.13817 -429.674682) (xy 314.139948 -429.644564) (xy 314.141612 -429.62957) (xy 314.141612 -429.018954)
			(xy 314.142068 -429.006865) (xy 314.149534 -428.983867) (xy 314.163724 -428.964291) (xy 314.183258 -428.950041)
			(xy 314.206232 -428.942505) (xy 314.21832 -428.941992) (xy 315.15812 -428.941992) (xy 315.170229 -428.942399)
			(xy 315.193256 -428.949903) (xy 315.212828 -428.964167) (xy 315.227022 -428.98379) (xy 315.234444 -429.006843)
			(xy 315.234828 -429.018954) (xy 315.234828 -431.560478) (xy 315.234373 -431.57257) (xy 315.226919 -431.595575)
			(xy 315.21273 -431.615158) (xy 315.193192 -431.629408) (xy 315.17021 -431.636935) (xy 315.15812 -431.63744)
			(xy 314.21832 -431.63744) (xy 314.206216 -431.636967) (xy 314.183196 -431.629478) (xy 314.163627 -431.61523)
			(xy 314.14943 -431.595622) (xy 314.142001 -431.572583) (xy 314.141612 -431.560478) (xy 314.141612 -430.950116)
			(xy 314.139943 -430.935123) (xy 314.138165 -430.905004) (xy 314.138056 -430.889918) (xy 310.60136 -430.889918)
			(xy 310.60136 -431.889916) (xy 316.138052 -431.889916) (xy 316.138161 -431.87483) (xy 316.139943 -431.844712)
			(xy 316.141608 -431.829718) (xy 316.141608 -430.749964) (xy 316.139943 -430.73497) (xy 316.138162 -430.704852)
			(xy 316.138052 -430.689766) (xy 316.138166 -430.67468) (xy 316.139944 -430.644562) (xy 316.141608 -430.629568)
			(xy 316.141608 -430.018952) (xy 316.142023 -430.006873) (xy 316.149501 -429.983902) (xy 316.16371 -429.964364)
			(xy 316.183259 -429.950172) (xy 316.206237 -429.942713) (xy 316.218316 -429.942244) (xy 317.158116 -429.942244)
			(xy 317.170187 -429.94275) (xy 317.193146 -429.950211) (xy 317.212679 -429.964399) (xy 317.226874 -429.983925)
			(xy 317.234345 -430.006882) (xy 317.234824 -430.018952) (xy 317.234824 -430.889918) (xy 318.138048 -430.889918)
			(xy 318.138157 -430.874832) (xy 318.139939 -430.844714) (xy 318.141604 -430.82972) (xy 318.141604 -429.749966)
			(xy 318.139939 -429.734972) (xy 318.138158 -429.704854) (xy 318.138048 -429.689768) (xy 318.138162 -429.674682)
			(xy 318.13994 -429.644564) (xy 318.141604 -429.62957) (xy 318.141604 -429.018954) (xy 318.142067 -429.006866)
			(xy 318.149532 -428.98387) (xy 318.163721 -428.964293) (xy 318.183253 -428.950043) (xy 318.206225 -428.942506)
			(xy 318.218312 -428.941992) (xy 319.158112 -428.941992) (xy 319.170221 -428.942406) (xy 319.193247 -428.949908)
			(xy 319.212819 -428.96417) (xy 319.227014 -428.983792) (xy 319.234436 -429.006844) (xy 319.23482 -429.018954)
			(xy 319.23482 -431.560478) (xy 319.234373 -431.57257) (xy 319.226918 -431.595577) (xy 319.212727 -431.615161)
			(xy 319.193187 -431.629411) (xy 319.170203 -431.636936) (xy 319.158112 -431.63744) (xy 318.218312 -431.63744)
			(xy 318.206208 -431.636974) (xy 318.183188 -431.629483) (xy 318.163618 -431.615232) (xy 318.149422 -431.595624)
			(xy 318.141993 -431.572583) (xy 318.141604 -431.560478) (xy 318.141604 -430.950116) (xy 318.139935 -430.935123)
			(xy 318.138157 -430.905004) (xy 318.138048 -430.889918) (xy 317.234824 -430.889918) (xy 317.234824 -431.889916)
			(xy 320.138044 -431.889916) (xy 320.138153 -431.87483) (xy 320.139935 -431.844712) (xy 320.1416 -431.829718)
			(xy 320.1416 -430.749964) (xy 320.139935 -430.73497) (xy 320.138154 -430.704852) (xy 320.138044 -430.689766)
			(xy 320.138158 -430.67468) (xy 320.139936 -430.644562) (xy 320.1416 -430.629568) (xy 320.1416 -430.018952)
			(xy 320.142023 -430.006874) (xy 320.1495 -429.983904) (xy 320.163707 -429.964367) (xy 320.183254 -429.950174)
			(xy 320.20623 -429.942714) (xy 320.218308 -429.942244) (xy 321.158108 -429.942244) (xy 321.170178 -429.942757)
			(xy 321.193137 -429.950216) (xy 321.21267 -429.964401) (xy 321.226866 -429.983927) (xy 321.234337 -430.006882)
			(xy 321.234816 -430.018952) (xy 321.234816 -430.889918) (xy 322.13804 -430.889918) (xy 322.138151 -430.874832)
			(xy 322.139933 -430.844714) (xy 322.141596 -430.82972) (xy 322.141596 -429.749966) (xy 322.139931 -429.734972)
			(xy 322.13815 -429.704854) (xy 322.13804 -429.689768) (xy 322.138154 -429.674682) (xy 322.139932 -429.644564)
			(xy 322.141596 -429.62957) (xy 322.141596 -429.018954) (xy 322.142067 -429.006866) (xy 322.149531 -428.983872)
			(xy 322.163718 -428.964296) (xy 322.183248 -428.950046) (xy 322.206218 -428.942507) (xy 322.218304 -428.941992)
			(xy 323.158104 -428.941992) (xy 323.170212 -428.942413) (xy 323.193238 -428.949912) (xy 323.212811 -428.964173)
			(xy 323.227006 -428.983793) (xy 323.234428 -429.006844) (xy 323.234812 -429.018954) (xy 323.234812 -431.560478)
			(xy 323.234373 -431.572571) (xy 323.226916 -431.595579) (xy 323.212724 -431.615164) (xy 323.193182 -431.629413)
			(xy 323.170196 -431.636937) (xy 323.158104 -431.63744) (xy 322.218304 -431.63744) (xy 322.206199 -431.636981)
			(xy 322.183179 -431.629488) (xy 322.163609 -431.615236) (xy 322.149413 -431.595625) (xy 322.141985 -431.572584)
			(xy 322.141596 -431.560478) (xy 322.141596 -430.950116) (xy 322.139927 -430.935123) (xy 322.138149 -430.905004)
			(xy 322.13804 -430.889918) (xy 321.234816 -430.889918) (xy 321.234816 -431.889916) (xy 324.138036 -431.889916)
			(xy 324.138147 -431.87483) (xy 324.139929 -431.844712) (xy 324.141592 -431.829718) (xy 324.141592 -430.749964)
			(xy 324.139927 -430.73497) (xy 324.138146 -430.704852) (xy 324.138036 -430.689766) (xy 324.138152 -430.674681)
			(xy 324.13993 -430.644562) (xy 324.141592 -430.629568) (xy 324.141592 -430.018952) (xy 324.142023 -430.006875)
			(xy 324.149499 -429.983906) (xy 324.163704 -429.96437) (xy 324.183249 -429.950177) (xy 324.206223 -429.942716)
			(xy 324.2183 -429.942244) (xy 325.1581 -429.942244) (xy 325.17017 -429.942764) (xy 325.193129 -429.95022)
			(xy 325.212662 -429.964404) (xy 325.226858 -429.983928) (xy 325.234329 -430.006883) (xy 325.234808 -430.018952)
			(xy 325.234808 -430.889918) (xy 326.138032 -430.889918) (xy 326.138143 -430.874832) (xy 326.139925 -430.844714)
			(xy 326.141588 -430.82972) (xy 326.141588 -429.749966) (xy 326.139923 -429.734972) (xy 326.138142 -429.704854)
			(xy 326.138032 -429.689768) (xy 326.138148 -429.674683) (xy 326.139926 -429.644564) (xy 326.141588 -429.62957)
			(xy 326.141588 -429.018954) (xy 326.141969 -429.006857) (xy 326.149444 -428.983847) (xy 326.163651 -428.964264)
			(xy 326.183205 -428.950016) (xy 326.2062 -428.942494) (xy 326.218296 -428.941992) (xy 327.158096 -428.941992)
			(xy 327.170204 -428.942419) (xy 327.19323 -428.949917) (xy 327.212802 -428.964176) (xy 327.226997 -428.983795)
			(xy 327.23442 -429.006845) (xy 327.234804 -429.018954) (xy 327.234804 -431.560478) (xy 327.234275 -431.572562)
			(xy 327.226829 -431.595555) (xy 327.212657 -431.615131) (xy 327.19314 -431.629384) (xy 327.170178 -431.636924)
			(xy 327.158096 -431.63744) (xy 326.218296 -431.63744) (xy 326.206191 -431.636988) (xy 326.18317 -431.629492)
			(xy 326.163601 -431.615238) (xy 326.149405 -431.595627) (xy 326.141977 -431.572584) (xy 326.141588 -431.560478)
			(xy 326.141588 -430.950116) (xy 326.139919 -430.935123) (xy 326.138141 -430.905004) (xy 326.138032 -430.889918)
			(xy 325.234808 -430.889918) (xy 325.234808 -431.889916) (xy 328.138028 -431.889916) (xy 328.138139 -431.87483)
			(xy 328.139921 -431.844712) (xy 328.141584 -431.829718) (xy 328.141584 -430.749964) (xy 328.139919 -430.73497)
			(xy 328.138138 -430.704852) (xy 328.138028 -430.689766) (xy 328.138144 -430.674681) (xy 328.139922 -430.644562)
			(xy 328.141584 -430.629568) (xy 328.141584 -430.018952) (xy 328.142023 -430.006876) (xy 328.149498 -429.983908)
			(xy 328.163701 -429.964373) (xy 328.183244 -429.95018) (xy 328.206215 -429.942717) (xy 328.218292 -429.942244)
			(xy 329.158092 -429.942244) (xy 329.170161 -429.94277) (xy 329.19312 -429.950225) (xy 329.212653 -429.964407)
			(xy 329.22685 -429.98393) (xy 329.234321 -430.006883) (xy 329.2348 -430.018952) (xy 329.2348 -430.889918)
			(xy 331.138022 -430.889918) (xy 331.138116 -430.875344) (xy 331.139768 -430.846243) (xy 331.141324 -430.831752)
			(xy 331.141324 -429.747934) (xy 331.139776 -429.733442) (xy 331.138126 -429.704342) (xy 331.138022 -429.689768)
			(xy 331.138121 -429.675194) (xy 331.13977 -429.646093) (xy 331.141324 -429.631602) (xy 331.141324 -429.018954)
			(xy 331.141772 -429.006838) (xy 331.14927 -428.983796) (xy 331.163519 -428.964196) (xy 331.183125 -428.949956)
			(xy 331.20617 -428.942467) (xy 331.218286 -428.941992) (xy 332.158086 -428.941992) (xy 332.170195 -428.942523)
			(xy 332.19323 -428.950001) (xy 332.212828 -428.964229) (xy 332.227072 -428.983816) (xy 332.234568 -429.006845)
			(xy 332.235048 -429.018954) (xy 332.235048 -431.560478) (xy 332.234621 -431.572601) (xy 332.227133 -431.595662)
			(xy 332.212884 -431.615278) (xy 332.193269 -431.62953) (xy 332.170209 -431.63702) (xy 332.158086 -431.63744)
			(xy 331.218286 -431.63744) (xy 331.20616 -431.637051) (xy 331.183097 -431.629553) (xy 331.163481 -431.615294)
			(xy 331.149231 -431.59567) (xy 331.141743 -431.572604) (xy 331.141324 -431.560478) (xy 331.141324 -430.948084)
			(xy 331.139781 -430.933592) (xy 331.138128 -430.904492) (xy 331.138022 -430.889918) (xy 329.2348 -430.889918)
			(xy 329.2348 -431.889916) (xy 333.138018 -431.889916) (xy 333.138112 -431.875342) (xy 333.139764 -431.846241)
			(xy 333.14132 -431.83175) (xy 333.14132 -430.747932) (xy 333.139772 -430.73344) (xy 333.138122 -430.70434)
			(xy 333.138018 -430.689766) (xy 333.138117 -430.675192) (xy 333.139766 -430.646091) (xy 333.14132 -430.6316)
			(xy 333.14132 -430.018952) (xy 333.141676 -430.006839) (xy 333.149191 -429.983806) (xy 333.163467 -429.964232)
			(xy 333.183103 -429.95004) (xy 333.206167 -429.942624) (xy 333.218282 -429.942244) (xy 334.158082 -429.942244)
			(xy 334.170171 -429.942723) (xy 334.193172 -429.950175) (xy 334.212752 -429.964358) (xy 334.227003 -429.98389)
			(xy 334.234535 -430.006865) (xy 334.235044 -430.018952) (xy 334.235044 -430.889918) (xy 335.138014 -430.889918)
			(xy 335.138108 -430.875344) (xy 335.13976 -430.846243) (xy 335.141316 -430.831752) (xy 335.141316 -429.747934)
			(xy 335.139768 -429.733442) (xy 335.138118 -429.704342) (xy 335.138014 -429.689768) (xy 335.138112 -429.675194)
			(xy 335.139762 -429.646093) (xy 335.141316 -429.631602) (xy 335.141316 -429.018954) (xy 335.141772 -429.006839)
			(xy 335.149269 -428.983798) (xy 335.163516 -428.964199) (xy 335.18312 -428.949958) (xy 335.206163 -428.942468)
			(xy 335.218278 -428.941992) (xy 336.158078 -428.941992) (xy 336.170187 -428.94253) (xy 336.193222 -428.950005)
			(xy 336.21282 -428.964232) (xy 336.227064 -428.983817) (xy 336.234559 -429.006846) (xy 336.23504 -429.018954)
			(xy 336.23504 -431.560478) (xy 336.234621 -431.572602) (xy 336.227132 -431.595664) (xy 336.212881 -431.615281)
			(xy 336.193264 -431.629532) (xy 336.170202 -431.637021) (xy 336.158078 -431.63744) (xy 335.218278 -431.63744)
			(xy 335.20616 -431.637007) (xy 335.183112 -431.629511) (xy 335.163509 -431.61526) (xy 335.149269 -431.595648)
			(xy 335.141786 -431.572596) (xy 335.141316 -431.560478) (xy 335.141316 -430.948084) (xy 335.139773 -430.933592)
			(xy 335.13812 -430.904492) (xy 335.138014 -430.889918) (xy 334.235044 -430.889918) (xy 334.235044 -431.889916)
			(xy 337.13801 -431.889916) (xy 337.138104 -431.875342) (xy 337.139756 -431.846241) (xy 337.141312 -431.83175)
			(xy 337.141312 -430.747932) (xy 337.139764 -430.73344) (xy 337.138114 -430.70434) (xy 337.13801 -430.689766)
			(xy 337.138108 -430.675192) (xy 337.139757 -430.646091) (xy 337.141312 -430.6316) (xy 337.141312 -430.018952)
			(xy 337.141676 -430.006839) (xy 337.14919 -429.983809) (xy 337.163465 -429.964235) (xy 337.183098 -429.950043)
			(xy 337.20616 -429.942625) (xy 337.218274 -429.942244) (xy 338.158074 -429.942244) (xy 338.170163 -429.94273)
			(xy 338.193163 -429.95018) (xy 338.212744 -429.964361) (xy 338.226995 -429.983891) (xy 338.234527 -430.006865)
			(xy 338.235036 -430.018952) (xy 338.235036 -430.889918) (xy 339.138006 -430.889918) (xy 339.1381 -430.875344)
			(xy 339.139752 -430.846243) (xy 339.141308 -430.831752) (xy 339.141308 -429.747934) (xy 339.13976 -429.733442)
			(xy 339.13811 -429.704342) (xy 339.138006 -429.689768) (xy 339.138104 -429.675194) (xy 339.139754 -429.646093)
			(xy 339.141308 -429.631602) (xy 339.141308 -429.018954) (xy 339.141772 -429.00684) (xy 339.149268 -428.9838)
			(xy 339.163513 -428.964202) (xy 339.183115 -428.949961) (xy 339.206156 -428.94247) (xy 339.21827 -428.941992)
			(xy 340.15807 -428.941992) (xy 340.170178 -428.942537) (xy 340.193213 -428.95001) (xy 340.212811 -428.964235)
			(xy 340.227055 -428.983819) (xy 340.234551 -429.006846) (xy 340.235032 -429.018954) (xy 340.235032 -431.560478)
			(xy 340.234621 -431.572603) (xy 340.227131 -431.595666) (xy 340.212878 -431.615284) (xy 340.193259 -431.629535)
			(xy 340.170195 -431.637022) (xy 340.15807 -431.63744) (xy 339.21827 -431.63744) (xy 339.206152 -431.637014)
			(xy 339.183104 -431.629515) (xy 339.163501 -431.615262) (xy 339.149261 -431.59565) (xy 339.141778 -431.572597)
			(xy 339.141308 -431.560478) (xy 339.141308 -430.948084) (xy 339.139764 -430.933592) (xy 339.138112 -430.904492)
			(xy 339.138006 -430.889918) (xy 338.235036 -430.889918) (xy 338.235036 -431.889916) (xy 341.138002 -431.889916)
			(xy 341.138096 -431.875342) (xy 341.139748 -431.846241) (xy 341.141304 -431.83175) (xy 341.141304 -430.747932)
			(xy 341.139756 -430.73344) (xy 341.138106 -430.70434) (xy 341.138002 -430.689766) (xy 341.1381 -430.675192)
			(xy 341.13975 -430.646091) (xy 341.141304 -430.6316) (xy 341.141304 -430.018952) (xy 341.141676 -430.00684)
			(xy 341.149189 -429.983811) (xy 341.163462 -429.964238) (xy 341.183093 -429.950045) (xy 341.206153 -429.942626)
			(xy 341.218266 -429.942244) (xy 342.158066 -429.942244) (xy 342.170154 -429.942736) (xy 342.193154 -429.950184)
			(xy 342.212735 -429.964364) (xy 342.226987 -429.983893) (xy 342.234519 -430.006866) (xy 342.235028 -430.018952)
			(xy 342.235028 -430.889918) (xy 343.137998 -430.889918) (xy 343.138092 -430.875344) (xy 343.139744 -430.846243)
			(xy 343.1413 -430.831752) (xy 343.1413 -429.747934) (xy 343.139752 -429.733442) (xy 343.138102 -429.704342)
			(xy 343.137998 -429.689768) (xy 343.138096 -429.675194) (xy 343.139746 -429.646093) (xy 343.1413 -429.631602)
			(xy 343.1413 -429.018954) (xy 343.141772 -429.006841) (xy 343.149267 -428.983803) (xy 343.163511 -428.964205)
			(xy 343.18311 -428.949964) (xy 343.206149 -428.942471) (xy 343.218262 -428.941992) (xy 344.158062 -428.941992)
			(xy 344.17017 -428.942543) (xy 344.193204 -428.950015) (xy 344.212803 -428.964238) (xy 344.227047 -428.98382)
			(xy 344.234543 -429.006847) (xy 344.235024 -429.018954) (xy 344.235024 -431.560478) (xy 344.234621 -431.572603)
			(xy 344.22713 -431.595668) (xy 344.212875 -431.615287) (xy 344.193254 -431.629537) (xy 344.170187 -431.637023)
			(xy 344.158062 -431.63744) (xy 343.218262 -431.63744) (xy 343.206143 -431.63702) (xy 343.183095 -431.62952)
			(xy 343.163492 -431.615265) (xy 343.149253 -431.595651) (xy 343.14177 -431.572597) (xy 343.1413 -431.560478)
			(xy 343.1413 -430.948084) (xy 343.139756 -430.933592) (xy 343.138104 -430.904492) (xy 343.137998 -430.889918)
			(xy 342.235028 -430.889918) (xy 342.235028 -431.889916) (xy 345.137994 -431.889916) (xy 345.138088 -431.875342)
			(xy 345.13974 -431.846241) (xy 345.141296 -431.83175) (xy 345.141296 -430.747932) (xy 345.139748 -430.73344)
			(xy 345.138098 -430.70434) (xy 345.137994 -430.689766) (xy 345.138092 -430.675192) (xy 345.139742 -430.646091)
			(xy 345.141296 -430.6316) (xy 345.141296 -430.018952) (xy 345.141676 -430.006841) (xy 345.149188 -429.983813)
			(xy 345.163459 -429.964241) (xy 345.183088 -429.950048) (xy 345.206145 -429.942628) (xy 345.218258 -429.942244)
			(xy 346.158058 -429.942244) (xy 346.170146 -429.942743) (xy 346.193146 -429.950189) (xy 346.212727 -429.964367)
			(xy 346.226979 -429.983894) (xy 346.234511 -430.006866) (xy 346.23502 -430.018952) (xy 346.23502 -432.560476)
			(xy 346.234563 -432.572582) (xy 346.227073 -432.595605) (xy 346.212821 -432.615176) (xy 346.193209 -432.629373)
			(xy 346.170165 -432.636797) (xy 346.158058 -432.637184) (xy 345.218258 -432.637184) (xy 345.206169 -432.636729)
			(xy 345.183171 -432.629264) (xy 345.163593 -432.615073) (xy 345.149343 -432.595539) (xy 345.141808 -432.572564)
			(xy 345.141296 -432.560476) (xy 345.141296 -431.948082) (xy 345.139753 -431.93359) (xy 345.1381 -431.90449)
			(xy 345.137994 -431.889916) (xy 342.235028 -431.889916) (xy 342.235028 -432.560476) (xy 342.234563 -432.572581)
			(xy 342.227074 -432.595602) (xy 342.212824 -432.615174) (xy 342.193214 -432.62937) (xy 342.170172 -432.636796)
			(xy 342.158066 -432.637184) (xy 341.218266 -432.637184) (xy 341.206177 -432.636722) (xy 341.183179 -432.629259)
			(xy 341.163602 -432.61507) (xy 341.149352 -432.595538) (xy 341.141816 -432.572563) (xy 341.141304 -432.560476)
			(xy 341.141304 -431.948082) (xy 341.13976 -431.93359) (xy 341.138108 -431.90449) (xy 341.138002 -431.889916)
			(xy 338.235036 -431.889916) (xy 338.235036 -432.560476) (xy 338.234564 -432.57258) (xy 338.227075 -432.5956)
			(xy 338.212827 -432.615171) (xy 338.193219 -432.629367) (xy 338.170179 -432.636795) (xy 338.158074 -432.637184)
			(xy 337.218274 -432.637184) (xy 337.206185 -432.636715) (xy 337.183188 -432.629254) (xy 337.163611 -432.615067)
			(xy 337.14936 -432.595536) (xy 337.141824 -432.572563) (xy 337.141312 -432.560476) (xy 337.141312 -431.948082)
			(xy 337.139768 -431.93359) (xy 337.138116 -431.90449) (xy 337.13801 -431.889916) (xy 334.235044 -431.889916)
			(xy 334.235044 -432.560476) (xy 334.234564 -432.572579) (xy 334.227076 -432.595598) (xy 334.21283 -432.615168)
			(xy 334.193224 -432.629365) (xy 334.170186 -432.636794) (xy 334.158082 -432.637184) (xy 333.218282 -432.637184)
			(xy 333.206194 -432.636709) (xy 333.183197 -432.62925) (xy 333.163619 -432.615065) (xy 333.149368 -432.595535)
			(xy 333.141832 -432.572563) (xy 333.14132 -432.560476) (xy 333.14132 -431.948082) (xy 333.139776 -431.93359)
			(xy 333.138124 -431.90449) (xy 333.138018 -431.889916) (xy 329.2348 -431.889916) (xy 329.2348 -432.560476)
			(xy 329.234367 -432.572558) (xy 329.226905 -432.595542) (xy 329.212704 -432.615093) (xy 329.193156 -432.629297)
			(xy 329.170174 -432.636764) (xy 329.158092 -432.637184) (xy 328.218292 -432.637184) (xy 328.206206 -432.636794)
			(xy 328.183219 -432.629321) (xy 328.163667 -432.61511) (xy 328.149464 -432.595552) (xy 328.142001 -432.572562)
			(xy 328.141584 -432.560476) (xy 328.141584 -431.950114) (xy 328.139914 -431.935121) (xy 328.138137 -431.905002)
			(xy 328.138028 -431.889916) (xy 325.234808 -431.889916) (xy 325.234808 -432.560476) (xy 325.234367 -432.572557)
			(xy 325.226906 -432.595539) (xy 325.212707 -432.61509) (xy 325.193161 -432.629295) (xy 325.170181 -432.636763)
			(xy 325.1581 -432.637184) (xy 324.2183 -432.637184) (xy 324.206215 -432.636787) (xy 324.183228 -432.629317)
			(xy 324.163676 -432.615107) (xy 324.149472 -432.59555) (xy 324.142009 -432.572561) (xy 324.141592 -432.560476)
			(xy 324.141592 -431.950114) (xy 324.139922 -431.935121) (xy 324.138145 -431.905002) (xy 324.138036 -431.889916)
			(xy 321.234816 -431.889916) (xy 321.234816 -432.560476) (xy 321.234367 -432.572557) (xy 321.226907 -432.595537)
			(xy 321.21271 -432.615087) (xy 321.193166 -432.629292) (xy 321.170188 -432.636762) (xy 321.158108 -432.637184)
			(xy 320.218308 -432.637184) (xy 320.206223 -432.63678) (xy 320.183237 -432.629312) (xy 320.163684 -432.615105)
			(xy 320.149481 -432.595549) (xy 320.142017 -432.572561) (xy 320.1416 -432.560476) (xy 320.1416 -431.950114)
			(xy 320.13993 -431.935121) (xy 320.138153 -431.905002) (xy 320.138044 -431.889916) (xy 317.234824 -431.889916)
			(xy 317.234824 -432.560476) (xy 317.234367 -432.572556) (xy 317.226908 -432.595535) (xy 317.212713 -432.615084)
			(xy 317.193171 -432.62929) (xy 317.170196 -432.636761) (xy 317.158116 -432.637184) (xy 316.218316 -432.637184)
			(xy 316.206232 -432.636773) (xy 316.183246 -432.629307) (xy 316.163693 -432.615101) (xy 316.149489 -432.595547)
			(xy 316.142026 -432.57256) (xy 316.141608 -432.560476) (xy 316.141608 -431.950114) (xy 316.139938 -431.935121)
			(xy 316.138161 -431.905002) (xy 316.138052 -431.889916) (xy 310.60136 -431.889916) (xy 310.60136 -434.48986)
			(xy 314.138056 -434.48986) (xy 314.138169 -434.474774) (xy 314.139948 -434.444656) (xy 314.141612 -434.429662)
			(xy 314.141612 -433.350162) (xy 314.139947 -433.335168) (xy 314.138166 -433.30505) (xy 314.138056 -433.289964)
			(xy 314.138169 -433.274878) (xy 314.139948 -433.24476) (xy 314.141612 -433.229766) (xy 314.141612 -432.618896)
			(xy 314.142009 -432.606811) (xy 314.14948 -432.583825) (xy 314.16369 -432.564273) (xy 314.183246 -432.550069)
			(xy 314.206235 -432.542606) (xy 314.21832 -432.542188) (xy 315.15812 -432.542188) (xy 315.170195 -432.542647)
			(xy 315.193162 -432.550115) (xy 315.212699 -432.564313) (xy 315.226893 -432.583852) (xy 315.234355 -432.606821)
			(xy 315.234828 -432.618896) (xy 315.234828 -435.16042) (xy 315.234353 -435.172494) (xy 315.226887 -435.195458)
			(xy 315.212693 -435.214993) (xy 315.193158 -435.229187) (xy 315.170194 -435.236653) (xy 315.15812 -435.237128)
			(xy 314.21832 -435.237128) (xy 314.206248 -435.236619) (xy 314.183285 -435.229165) (xy 314.16375 -435.214979)
			(xy 314.149554 -435.195451) (xy 314.142087 -435.172491) (xy 314.141612 -435.16042) (xy 314.141612 -434.550058)
			(xy 314.139946 -434.535064) (xy 314.138166 -434.504946) (xy 314.138056 -434.48986) (xy 310.60136 -434.48986)
			(xy 310.60136 -435.489858) (xy 316.138052 -435.489858) (xy 316.138165 -435.474772) (xy 316.139944 -435.444654)
			(xy 316.141608 -435.42966) (xy 316.141608 -434.35016) (xy 316.139943 -434.335166) (xy 316.138162 -434.305048)
			(xy 316.138052 -434.289962) (xy 316.138165 -434.274876) (xy 316.139944 -434.244758) (xy 316.141608 -434.229764)
			(xy 316.141608 -433.618894) (xy 316.142102 -433.606807) (xy 316.149556 -433.583812) (xy 316.163737 -433.564235)
			(xy 316.183263 -433.549984) (xy 316.206231 -433.542446) (xy 316.218316 -433.541932) (xy 317.158116 -433.541932)
			(xy 317.170229 -433.542303) (xy 317.193262 -433.549811) (xy 317.212838 -433.564083) (xy 317.227031 -433.583716)
			(xy 317.234445 -433.606779) (xy 317.234824 -433.618894) (xy 317.234824 -434.48986) (xy 318.138048 -434.48986)
			(xy 318.138161 -434.474774) (xy 318.13994 -434.444656) (xy 318.141604 -434.429662) (xy 318.141604 -433.350162)
			(xy 318.139939 -433.335168) (xy 318.138158 -433.30505) (xy 318.138048 -433.289964) (xy 318.138161 -433.274878)
			(xy 318.13994 -433.24476) (xy 318.141604 -433.229766) (xy 318.141604 -432.618896) (xy 318.142009 -432.606812)
			(xy 318.149479 -432.583827) (xy 318.163687 -432.564276) (xy 318.183241 -432.550072) (xy 318.206228 -432.542607)
			(xy 318.218312 -432.542188) (xy 319.158112 -432.542188) (xy 319.170187 -432.542654) (xy 319.193154 -432.550119)
			(xy 319.21269 -432.564316) (xy 319.226884 -432.583854) (xy 319.234347 -432.606821) (xy 319.23482 -432.618896)
			(xy 319.23482 -435.16042) (xy 319.234353 -435.172494) (xy 319.226886 -435.19546) (xy 319.21269 -435.214996)
			(xy 319.193153 -435.22919) (xy 319.170186 -435.236654) (xy 319.158112 -435.237128) (xy 318.218312 -435.237128)
			(xy 318.20624 -435.236626) (xy 318.183277 -435.229169) (xy 318.163741 -435.214982) (xy 318.149546 -435.195452)
			(xy 318.142079 -435.172492) (xy 318.141604 -435.16042) (xy 318.141604 -434.550058) (xy 318.139938 -434.535064)
			(xy 318.138158 -434.504946) (xy 318.138048 -434.48986) (xy 317.234824 -434.48986) (xy 317.234824 -435.489858)
			(xy 320.138044 -435.489858) (xy 320.138157 -435.474772) (xy 320.139936 -435.444654) (xy 320.1416 -435.42966)
			(xy 320.1416 -434.35016) (xy 320.139934 -434.335166) (xy 320.138154 -434.305048) (xy 320.138044 -434.289962)
			(xy 320.138157 -434.274876) (xy 320.139936 -434.244758) (xy 320.1416 -434.229764) (xy 320.1416 -433.618894)
			(xy 320.142102 -433.606808) (xy 320.149555 -433.583814) (xy 320.163734 -433.564238) (xy 320.183258 -433.549986)
			(xy 320.206224 -433.542447) (xy 320.218308 -433.541932) (xy 321.158108 -433.541932) (xy 321.170221 -433.54231)
			(xy 321.193254 -433.549815) (xy 321.212829 -433.564086) (xy 321.227023 -433.583717) (xy 321.234437 -433.60678)
			(xy 321.234816 -433.618894) (xy 321.234816 -434.48986) (xy 322.13804 -434.48986) (xy 322.138153 -434.474774)
			(xy 322.139932 -434.444656) (xy 322.141596 -434.429662) (xy 322.141596 -433.350162) (xy 322.139931 -433.335168)
			(xy 322.13815 -433.30505) (xy 322.13804 -433.289964) (xy 322.138153 -433.274878) (xy 322.139932 -433.24476)
			(xy 322.141596 -433.229766) (xy 322.141596 -432.618896) (xy 322.142061 -432.606821) (xy 322.149525 -432.583853)
			(xy 322.163721 -432.564316) (xy 322.18326 -432.550121) (xy 322.206229 -432.54266) (xy 322.218304 -432.542188)
			(xy 323.158104 -432.542188) (xy 323.170178 -432.542661) (xy 323.193145 -432.550124) (xy 323.212682 -432.564318)
			(xy 323.226876 -432.583855) (xy 323.234339 -432.606822) (xy 323.234812 -432.618896) (xy 323.234812 -435.16042)
			(xy 323.234353 -435.172495) (xy 323.226885 -435.195462) (xy 323.212687 -435.214999) (xy 323.193148 -435.229193)
			(xy 323.170179 -435.236655) (xy 323.158104 -435.237128) (xy 322.218304 -435.237128) (xy 322.206232 -435.236633)
			(xy 322.183268 -435.229174) (xy 322.163733 -435.214984) (xy 322.149537 -435.195454) (xy 322.142071 -435.172492)
			(xy 322.141596 -435.16042) (xy 322.141596 -434.550058) (xy 322.13993 -434.535064) (xy 322.13815 -434.504946)
			(xy 322.13804 -434.48986) (xy 321.234816 -434.48986) (xy 321.234816 -435.489858) (xy 324.138036 -435.489858)
			(xy 324.138151 -435.474773) (xy 324.13993 -435.444654) (xy 324.141592 -435.42966) (xy 324.141592 -434.35016)
			(xy 324.139926 -434.335166) (xy 324.138146 -434.305048) (xy 324.138036 -434.289962) (xy 324.138151 -434.274877)
			(xy 324.13993 -434.244758) (xy 324.141592 -434.229764) (xy 324.141592 -433.618894) (xy 324.142102 -433.606809)
			(xy 324.149554 -433.583816) (xy 324.163731 -433.564241) (xy 324.183253 -433.549989) (xy 324.206217 -433.542448)
			(xy 324.2183 -433.541932) (xy 325.1581 -433.541932) (xy 325.170212 -433.542317) (xy 325.193245 -433.54982)
			(xy 325.212821 -433.564088) (xy 325.227014 -433.583719) (xy 325.234429 -433.60678) (xy 325.234808 -433.618894)
			(xy 325.234808 -434.48986) (xy 326.138032 -434.48986) (xy 326.138147 -434.474775) (xy 326.139926 -434.444656)
			(xy 326.141588 -434.429662) (xy 326.141588 -433.350162) (xy 326.139923 -433.335168) (xy 326.138142 -433.30505)
			(xy 326.138032 -433.289964) (xy 326.138148 -433.274879) (xy 326.139926 -433.24476) (xy 326.141588 -433.229766)
			(xy 326.141588 -432.618896) (xy 326.142061 -432.606822) (xy 326.149524 -432.583855) (xy 326.163718 -432.564318)
			(xy 326.183255 -432.550124) (xy 326.206222 -432.542661) (xy 326.218296 -432.542188) (xy 327.158096 -432.542188)
			(xy 327.17017 -432.542668) (xy 327.193136 -432.550129) (xy 327.212673 -432.564321) (xy 327.226868 -432.583857)
			(xy 327.234331 -432.606822) (xy 327.234804 -432.618896) (xy 327.234804 -435.16042) (xy 327.234353 -435.172496)
			(xy 327.226884 -435.195464) (xy 327.212684 -435.215001) (xy 327.193143 -435.229195) (xy 327.170172 -435.236656)
			(xy 327.158096 -435.237128) (xy 326.218296 -435.237128) (xy 326.206223 -435.236639) (xy 326.183259 -435.229178)
			(xy 326.163724 -435.214987) (xy 326.149529 -435.195455) (xy 326.142063 -435.172493) (xy 326.141588 -435.16042)
			(xy 326.141588 -434.550058) (xy 326.139922 -434.535064) (xy 326.138142 -434.504946) (xy 326.138032 -434.48986)
			(xy 325.234808 -434.48986) (xy 325.234808 -435.489858) (xy 328.138028 -435.489858) (xy 328.138143 -435.474773)
			(xy 328.139922 -435.444654) (xy 328.141584 -435.42966) (xy 328.141584 -434.35016) (xy 328.139918 -434.335166)
			(xy 328.138138 -434.305048) (xy 328.138028 -434.289962) (xy 328.138143 -434.274877) (xy 328.139922 -434.244758)
			(xy 328.141584 -434.229764) (xy 328.141584 -433.618894) (xy 328.142003 -433.6068) (xy 328.149467 -433.583792)
			(xy 328.163664 -433.564208) (xy 328.183211 -433.549959) (xy 328.206199 -433.542435) (xy 328.218292 -433.541932)
			(xy 329.158092 -433.541932) (xy 329.170204 -433.542323) (xy 329.193236 -433.549824) (xy 329.212812 -433.564091)
			(xy 329.227006 -433.58372) (xy 329.234421 -433.606781) (xy 329.2348 -433.618894) (xy 329.2348 -434.48986)
			(xy 331.138022 -434.48986) (xy 331.13812 -434.475286) (xy 331.13977 -434.446185) (xy 331.141324 -434.431694)
			(xy 331.141324 -433.34813) (xy 331.139776 -433.333638) (xy 331.138126 -433.304538) (xy 331.138022 -433.289964)
			(xy 331.13812 -433.27539) (xy 331.13977 -433.246289) (xy 331.141324 -433.231798) (xy 331.141324 -432.618896)
			(xy 331.141713 -432.606785) (xy 331.149217 -432.583753) (xy 331.163484 -432.564178) (xy 331.183113 -432.549984)
			(xy 331.206173 -432.542568) (xy 331.218286 -432.542188) (xy 332.158086 -432.542188) (xy 332.17018 -432.54262)
			(xy 332.193188 -432.550079) (xy 332.212772 -432.564273) (xy 332.227021 -432.583817) (xy 332.234545 -432.606804)
			(xy 332.235048 -432.618896) (xy 332.235048 -435.16042) (xy 332.234601 -435.172525) (xy 332.227102 -435.195545)
			(xy 332.212847 -435.215113) (xy 332.193235 -435.229309) (xy 332.170192 -435.236738) (xy 332.158086 -435.237128)
			(xy 331.218286 -435.237128) (xy 331.206192 -435.236704) (xy 331.183186 -435.22924) (xy 331.163603 -435.215043)
			(xy 331.149354 -435.195499) (xy 331.141828 -435.172512) (xy 331.141324 -435.16042) (xy 331.141324 -434.548026)
			(xy 331.139776 -434.533534) (xy 331.138126 -434.504434) (xy 331.138022 -434.48986) (xy 329.2348 -434.48986)
			(xy 329.2348 -435.489858) (xy 333.138018 -435.489858) (xy 333.138116 -435.475284) (xy 333.139766 -435.446183)
			(xy 333.14132 -435.431692) (xy 333.14132 -434.348128) (xy 333.139772 -434.333636) (xy 333.138122 -434.304536)
			(xy 333.138018 -434.289962) (xy 333.138116 -434.275388) (xy 333.139766 -434.246287) (xy 333.14132 -434.231796)
			(xy 333.14132 -433.618894) (xy 333.141807 -433.606781) (xy 333.149293 -433.583741) (xy 333.163532 -433.564141)
			(xy 333.18313 -433.549899) (xy 333.206169 -433.542408) (xy 333.218282 -433.541932) (xy 334.158082 -433.541932)
			(xy 334.170203 -433.542375) (xy 334.19326 -433.549862) (xy 334.212875 -433.564108) (xy 334.227127 -433.583718)
			(xy 334.234621 -433.606773) (xy 334.235044 -433.618894) (xy 334.235044 -434.48986) (xy 335.138014 -434.48986)
			(xy 335.138111 -434.475286) (xy 335.139761 -434.446185) (xy 335.141316 -434.431694) (xy 335.141316 -433.34813)
			(xy 335.139768 -433.333638) (xy 335.138118 -433.304538) (xy 335.138014 -433.289964) (xy 335.138112 -433.27539)
			(xy 335.139761 -433.246289) (xy 335.141316 -433.231798) (xy 335.141316 -432.618896) (xy 335.141713 -432.606785)
			(xy 335.149215 -432.583755) (xy 335.163481 -432.564181) (xy 335.183108 -432.549987) (xy 335.206166 -432.542569)
			(xy 335.218278 -432.542188) (xy 336.158078 -432.542188) (xy 336.170171 -432.542627) (xy 336.193179 -432.550084)
			(xy 336.212764 -432.564276) (xy 336.227013 -432.583818) (xy 336.234537 -432.606804) (xy 336.23504 -432.618896)
			(xy 336.23504 -435.16042) (xy 336.234601 -435.172526) (xy 336.227101 -435.195547) (xy 336.212844 -435.215116)
			(xy 336.19323 -435.229312) (xy 336.170185 -435.236739) (xy 336.158078 -435.237128) (xy 335.218278 -435.237128)
			(xy 335.206184 -435.236711) (xy 335.183177 -435.229244) (xy 335.163595 -435.215046) (xy 335.149346 -435.1955)
			(xy 335.14182 -435.172513) (xy 335.141316 -435.16042) (xy 335.141316 -434.548026) (xy 335.139768 -434.533534)
			(xy 335.138118 -434.504434) (xy 335.138014 -434.48986) (xy 334.235044 -434.48986) (xy 334.235044 -435.489858)
			(xy 337.13801 -435.489858) (xy 337.138107 -435.475284) (xy 337.139757 -435.446183) (xy 337.141312 -435.431692)
			(xy 337.141312 -434.348128) (xy 337.139764 -434.333636) (xy 337.138114 -434.304536) (xy 337.13801 -434.289962)
			(xy 337.138108 -434.275388) (xy 337.139757 -434.246287) (xy 337.141312 -434.231796) (xy 337.141312 -433.618894)
			(xy 337.141806 -433.606782) (xy 337.149292 -433.583743) (xy 337.163529 -433.564143) (xy 337.183125 -433.549901)
			(xy 337.206162 -433.54241) (xy 337.218274 -433.541932) (xy 338.158074 -433.541932) (xy 338.170195 -433.542382)
			(xy 338.193252 -433.549866) (xy 338.212867 -433.56411) (xy 338.227119 -433.58372) (xy 338.234613 -433.606773)
			(xy 338.235036 -433.618894) (xy 338.235036 -434.48986) (xy 339.138006 -434.48986) (xy 339.138104 -434.475286)
			(xy 339.139753 -434.446185) (xy 339.141308 -434.431694) (xy 339.141308 -433.34813) (xy 339.13976 -433.333638)
			(xy 339.13811 -433.304538) (xy 339.138006 -433.289964) (xy 339.138104 -433.27539) (xy 339.139753 -433.246289)
			(xy 339.141308 -433.231798) (xy 339.141308 -432.618896) (xy 339.141713 -432.606786) (xy 339.149214 -432.583757)
			(xy 339.163479 -432.564184) (xy 339.183103 -432.549989) (xy 339.206159 -432.54257) (xy 339.21827 -432.542188)
			(xy 340.15807 -432.542188) (xy 340.170163 -432.542634) (xy 340.19317 -432.550088) (xy 340.212755 -432.564278)
			(xy 340.227005 -432.58382) (xy 340.234529 -432.606805) (xy 340.235032 -432.618896) (xy 340.235032 -435.16042)
			(xy 340.234601 -435.172527) (xy 340.2271 -435.195549) (xy 340.212841 -435.215119) (xy 340.193225 -435.229314)
			(xy 340.170178 -435.23674) (xy 340.15807 -435.237128) (xy 339.21827 -435.237128) (xy 339.206176 -435.236718)
			(xy 339.183169 -435.229249) (xy 339.163586 -435.215049) (xy 339.149338 -435.195502) (xy 339.141812 -435.172513)
			(xy 339.141308 -435.16042) (xy 339.141308 -434.548026) (xy 339.13976 -434.533534) (xy 339.13811 -434.504434)
			(xy 339.138006 -434.48986) (xy 338.235036 -434.48986) (xy 338.235036 -435.489858) (xy 341.138002 -435.489858)
			(xy 341.138099 -435.475284) (xy 341.139749 -435.446183) (xy 341.141304 -435.431692) (xy 341.141304 -434.348128)
			(xy 341.139756 -434.333636) (xy 341.138106 -434.304536) (xy 341.138002 -434.289962) (xy 341.1381 -434.275388)
			(xy 341.139749 -434.246287) (xy 341.141304 -434.231796) (xy 341.141304 -433.618894) (xy 341.141806 -433.606783)
			(xy 341.149291 -433.583745) (xy 341.163526 -433.564146) (xy 341.18312 -433.549904) (xy 341.206155 -433.542411)
			(xy 341.218266 -433.541932) (xy 342.158066 -433.541932) (xy 342.170186 -433.542389) (xy 342.193243 -433.549871)
			(xy 342.212858 -433.564113) (xy 342.227111 -433.583721) (xy 342.234605 -433.606774) (xy 342.235028 -433.618894)
			(xy 342.235028 -434.48986) (xy 343.137998 -434.48986) (xy 343.138096 -434.475286) (xy 343.139745 -434.446185)
			(xy 343.1413 -434.431694) (xy 343.1413 -433.34813) (xy 343.139752 -433.333638) (xy 343.138102 -433.304538)
			(xy 343.137998 -433.289964) (xy 343.138096 -433.27539) (xy 343.139745 -433.246289) (xy 343.1413 -433.231798)
			(xy 343.1413 -432.618896) (xy 343.141713 -432.606787) (xy 343.149213 -432.583759) (xy 343.163476 -432.564186)
			(xy 343.183098 -432.549992) (xy 343.206152 -432.542571) (xy 343.218262 -432.542188) (xy 344.158062 -432.542188)
			(xy 344.170154 -432.542641) (xy 344.193162 -432.550093) (xy 344.212747 -432.564281) (xy 344.226997 -432.583821)
			(xy 344.234521 -432.606805) (xy 344.235024 -432.618896) (xy 344.235024 -435.16042) (xy 344.234601 -435.172528)
			(xy 344.227099 -435.195551) (xy 344.212838 -435.215122) (xy 344.19322 -435.229317) (xy 344.170171 -435.236741)
			(xy 344.158062 -435.237128) (xy 343.218262 -435.237128) (xy 343.206167 -435.236724) (xy 343.18316 -435.229253)
			(xy 343.163578 -435.215052) (xy 343.14933 -435.195503) (xy 343.141804 -435.172514) (xy 343.1413 -435.16042)
			(xy 343.1413 -434.548026) (xy 343.139752 -434.533534) (xy 343.138102 -434.504434) (xy 343.137998 -434.48986)
			(xy 342.235028 -434.48986) (xy 342.235028 -435.489858) (xy 345.137994 -435.489858) (xy 345.138091 -435.475284)
			(xy 345.139741 -435.446183) (xy 345.141296 -435.431692) (xy 345.141296 -434.348128) (xy 345.139748 -434.333636)
			(xy 345.138098 -434.304536) (xy 345.137994 -434.289962) (xy 345.138092 -434.275388) (xy 345.139741 -434.246287)
			(xy 345.141296 -434.231796) (xy 345.141296 -433.618894) (xy 345.141806 -433.606783) (xy 345.14929 -433.583747)
			(xy 345.163524 -433.564149) (xy 345.183115 -433.549906) (xy 345.206148 -433.542412) (xy 345.218258 -433.541932)
			(xy 346.158058 -433.541932) (xy 346.170178 -433.542396) (xy 346.193234 -433.549876) (xy 346.21285 -433.564116)
			(xy 346.227103 -433.583722) (xy 346.234597 -433.606774) (xy 346.23502 -433.618894) (xy 346.23502 -436.160418)
			(xy 346.234654 -436.172546) (xy 346.227152 -436.195612) (xy 346.212888 -436.215231) (xy 346.193258 -436.22948)
			(xy 346.170186 -436.236964) (xy 346.158058 -436.23738) (xy 345.218258 -436.23738) (xy 345.206143 -436.236924)
			(xy 345.183101 -436.229428) (xy 345.163502 -436.215181) (xy 345.149261 -436.195577) (xy 345.141772 -436.172533)
			(xy 345.141296 -436.160418) (xy 345.141296 -435.548024) (xy 345.139748 -435.533532) (xy 345.138098 -435.504432)
			(xy 345.137994 -435.489858) (xy 342.235028 -435.489858) (xy 342.235028 -436.160418) (xy 342.234655 -436.172545)
			(xy 342.227153 -436.19561) (xy 342.212891 -436.215228) (xy 342.193264 -436.229477) (xy 342.170193 -436.236963)
			(xy 342.158066 -436.23738) (xy 341.218266 -436.23738) (xy 341.206151 -436.236918) (xy 341.18311 -436.229423)
			(xy 341.16351 -436.215178) (xy 341.149269 -436.195576) (xy 341.14178 -436.172533) (xy 341.141304 -436.160418)
			(xy 341.141304 -435.548024) (xy 341.139755 -435.533532) (xy 341.138106 -435.504432) (xy 341.138002 -435.489858)
			(xy 338.235036 -435.489858) (xy 338.235036 -436.160418) (xy 338.234655 -436.172544) (xy 338.227154 -436.195608)
			(xy 338.212894 -436.215225) (xy 338.193269 -436.229474) (xy 338.1702 -436.236962) (xy 338.158074 -436.23738)
			(xy 337.218274 -436.23738) (xy 337.20616 -436.236911) (xy 337.183119 -436.229419) (xy 337.163519 -436.215175)
			(xy 337.149278 -436.195574) (xy 337.141788 -436.172532) (xy 337.141312 -436.160418) (xy 337.141312 -435.548024)
			(xy 337.139763 -435.533532) (xy 337.138114 -435.504432) (xy 337.13801 -435.489858) (xy 334.235044 -435.489858)
			(xy 334.235044 -436.160418) (xy 334.234604 -436.172535) (xy 334.227109 -436.195582) (xy 334.21286 -436.215185)
			(xy 334.19325 -436.229426) (xy 334.1702 -436.236909) (xy 334.158082 -436.23738) (xy 333.218282 -436.23738)
			(xy 333.206168 -436.236904) (xy 333.183127 -436.229414) (xy 333.163528 -436.215172) (xy 333.149286 -436.195573)
			(xy 333.141796 -436.172532) (xy 333.14132 -436.160418) (xy 333.14132 -435.548024) (xy 333.139771 -435.533532)
			(xy 333.138122 -435.504432) (xy 333.138018 -435.489858) (xy 329.2348 -435.489858) (xy 329.2348 -436.160418)
			(xy 329.234309 -436.172505) (xy 329.226852 -436.195499) (xy 329.21267 -436.215075) (xy 329.193145 -436.229327)
			(xy 329.170177 -436.236865) (xy 329.158092 -436.23738) (xy 328.218292 -436.23738) (xy 328.206181 -436.23699)
			(xy 328.18315 -436.229486) (xy 328.163575 -436.215219) (xy 328.149381 -436.19559) (xy 328.141964 -436.172531)
			(xy 328.141584 -436.160418) (xy 328.141584 -435.550056) (xy 328.139918 -435.535062) (xy 328.138138 -435.504944)
			(xy 328.138028 -435.489858) (xy 325.234808 -435.489858) (xy 325.234808 -436.160418) (xy 325.234309 -436.172504)
			(xy 325.226853 -436.195497) (xy 325.212673 -436.215072) (xy 325.19315 -436.229324) (xy 325.170184 -436.236864)
			(xy 325.1581 -436.23738) (xy 324.2183 -436.23738) (xy 324.206189 -436.236984) (xy 324.183158 -436.229482)
			(xy 324.163583 -436.215216) (xy 324.14939 -436.195589) (xy 324.141972 -436.17253) (xy 324.141592 -436.160418)
			(xy 324.141592 -435.550056) (xy 324.139926 -435.535062) (xy 324.138146 -435.504944) (xy 324.138036 -435.489858)
			(xy 321.234816 -435.489858) (xy 321.234816 -436.160418) (xy 321.234407 -436.172513) (xy 321.22694 -436.195522)
			(xy 321.21274 -436.215105) (xy 321.193192 -436.229353) (xy 321.170202 -436.236877) (xy 321.158108 -436.23738)
			(xy 320.218308 -436.23738) (xy 320.206198 -436.236977) (xy 320.183167 -436.229477) (xy 320.163592 -436.215213)
			(xy 320.149398 -436.195587) (xy 320.14198 -436.17253) (xy 320.1416 -436.160418) (xy 320.1416 -435.550056)
			(xy 320.139934 -435.535062) (xy 320.138154 -435.504944) (xy 320.138044 -435.489858) (xy 317.234824 -435.489858)
			(xy 317.234824 -436.160418) (xy 317.234407 -436.172512) (xy 317.226941 -436.195519) (xy 317.212743 -436.215102)
			(xy 317.193197 -436.229351) (xy 317.170209 -436.236876) (xy 317.158116 -436.23738) (xy 316.218316 -436.23738)
			(xy 316.206206 -436.23697) (xy 316.183176 -436.229472) (xy 316.163601 -436.21521) (xy 316.149406 -436.195585)
			(xy 316.141989 -436.172529) (xy 316.141608 -436.160418) (xy 316.141608 -435.550056) (xy 316.139942 -435.535062)
			(xy 316.138162 -435.504944) (xy 316.138052 -435.489858) (xy 310.60136 -435.489858) (xy 310.60136 -438.089802)
			(xy 314.138056 -438.089802) (xy 314.138173 -438.074717) (xy 314.139949 -438.044598) (xy 314.141612 -438.029604)
			(xy 314.141612 -436.950104) (xy 314.139942 -436.935111) (xy 314.138164 -436.904992) (xy 314.138056 -436.889906)
			(xy 314.138164 -436.87482) (xy 314.139946 -436.844702) (xy 314.141612 -436.829708) (xy 314.141612 -436.219092)
			(xy 314.142006 -436.207007) (xy 314.149478 -436.18402) (xy 314.163688 -436.164469) (xy 314.183246 -436.150265)
			(xy 314.206235 -436.142802) (xy 314.21832 -436.142384) (xy 315.15812 -436.142384) (xy 315.170195 -436.142847)
			(xy 315.193161 -436.150314) (xy 315.212697 -436.164511) (xy 315.226891 -436.18405) (xy 315.234355 -436.207017)
			(xy 315.234828 -436.219092) (xy 315.234828 -438.760616) (xy 315.23435 -438.772689) (xy 315.226885 -438.795654)
			(xy 315.212691 -438.815189) (xy 315.193157 -438.829383) (xy 315.170193 -438.836849) (xy 315.15812 -438.837324)
			(xy 314.21832 -438.837324) (xy 314.20624 -438.83687) (xy 314.183261 -438.82941) (xy 314.163711 -438.815214)
			(xy 314.149506 -438.795672) (xy 314.142035 -438.772696) (xy 314.141612 -438.760616) (xy 314.141612 -438.15)
			(xy 314.139941 -438.135007) (xy 314.138164 -438.104888) (xy 314.138056 -438.089802) (xy 310.60136 -438.089802)
			(xy 310.60136 -439.0898) (xy 316.138052 -439.0898) (xy 316.138169 -439.074715) (xy 316.139945 -439.044596)
			(xy 316.141608 -439.029602) (xy 316.141608 -437.950102) (xy 316.139937 -437.935109) (xy 316.13816 -437.90499)
			(xy 316.138052 -437.889904) (xy 316.138169 -437.874819) (xy 316.139945 -437.8447) (xy 316.141608 -437.829706)
			(xy 316.141608 -437.21909) (xy 316.142098 -437.207003) (xy 316.149554 -437.184008) (xy 316.163736 -437.164431)
			(xy 316.183262 -437.150179) (xy 316.206231 -437.142642) (xy 316.218316 -437.142128) (xy 317.158116 -437.142128)
			(xy 317.170229 -437.142503) (xy 317.193261 -437.15001) (xy 317.212836 -437.164281) (xy 317.227029 -437.183914)
			(xy 317.234445 -437.206976) (xy 317.234824 -437.21909) (xy 317.234824 -438.089802) (xy 318.138048 -438.089802)
			(xy 318.138165 -438.074717) (xy 318.139941 -438.044598) (xy 318.141604 -438.029604) (xy 318.141604 -436.950104)
			(xy 318.139934 -436.935111) (xy 318.138156 -436.904992) (xy 318.138048 -436.889906) (xy 318.138156 -436.87482)
			(xy 318.139938 -436.844702) (xy 318.141604 -436.829708) (xy 318.141604 -436.219092) (xy 318.142006 -436.207008)
			(xy 318.149477 -436.184023) (xy 318.163686 -436.164471) (xy 318.183241 -436.150268) (xy 318.206228 -436.142803)
			(xy 318.218312 -436.142384) (xy 319.158112 -436.142384) (xy 319.170186 -436.142854) (xy 319.193153 -436.150319)
			(xy 319.212689 -436.164514) (xy 319.226883 -436.184051) (xy 319.234347 -436.207018) (xy 319.23482 -436.219092)
			(xy 319.23482 -438.760616) (xy 319.234349 -438.77269) (xy 319.226884 -438.795656) (xy 319.212689 -438.815191)
			(xy 319.193152 -438.829386) (xy 319.170186 -438.83685) (xy 319.158112 -438.837324) (xy 318.218312 -438.837324)
			(xy 318.20624 -438.836826) (xy 318.183276 -438.829369) (xy 318.16374 -438.81518) (xy 318.149544 -438.79565)
			(xy 318.142079 -438.772688) (xy 318.141604 -438.760616) (xy 318.141604 -438.15) (xy 318.139933 -438.135007)
			(xy 318.138156 -438.104888) (xy 318.138048 -438.089802) (xy 317.234824 -438.089802) (xy 317.234824 -439.0898)
			(xy 320.138044 -439.0898) (xy 320.138161 -439.074715) (xy 320.139937 -439.044596) (xy 320.1416 -439.029602)
			(xy 320.1416 -437.950102) (xy 320.139929 -437.935109) (xy 320.138152 -437.90499) (xy 320.138044 -437.889904)
			(xy 320.138161 -437.874819) (xy 320.139937 -437.8447) (xy 320.1416 -437.829706) (xy 320.1416 -437.21909)
			(xy 320.142098 -437.207004) (xy 320.149553 -437.18401) (xy 320.163733 -437.164434) (xy 320.183257 -437.150182)
			(xy 320.206224 -437.142643) (xy 320.218308 -437.142128) (xy 321.158108 -437.142128) (xy 321.17022 -437.14251)
			(xy 321.193252 -437.150015) (xy 321.212828 -437.164284) (xy 321.227021 -437.183915) (xy 321.234437 -437.206976)
			(xy 321.234816 -437.21909) (xy 321.234816 -438.089802) (xy 322.13804 -438.089802) (xy 322.138157 -438.074717)
			(xy 322.139933 -438.044598) (xy 322.141596 -438.029604) (xy 322.141596 -436.950104) (xy 322.139926 -436.935111)
			(xy 322.138148 -436.904992) (xy 322.13804 -436.889906) (xy 322.13815 -436.87482) (xy 322.139932 -436.844702)
			(xy 322.141596 -436.829708) (xy 322.141596 -436.219092) (xy 322.142058 -436.207017) (xy 322.149523 -436.184049)
			(xy 322.16372 -436.164511) (xy 322.183259 -436.150317) (xy 322.206229 -436.142856) (xy 322.218304 -436.142384)
			(xy 323.158104 -436.142384) (xy 323.170178 -436.142861) (xy 323.193144 -436.150323) (xy 323.21268 -436.164517)
			(xy 323.226875 -436.184053) (xy 323.234339 -436.207018) (xy 323.234812 -436.219092) (xy 323.234812 -438.760616)
			(xy 323.234349 -438.772691) (xy 323.226883 -438.795658) (xy 323.212686 -438.815194) (xy 323.193147 -438.829388)
			(xy 323.170179 -438.836851) (xy 323.158104 -438.837324) (xy 322.218304 -438.837324) (xy 322.206231 -438.836833)
			(xy 322.183267 -438.829373) (xy 322.163731 -438.815183) (xy 322.149536 -438.795651) (xy 322.142071 -438.772689)
			(xy 322.141596 -438.760616) (xy 322.141596 -438.15) (xy 322.139925 -438.135007) (xy 322.138148 -438.104888)
			(xy 322.13804 -438.089802) (xy 321.234816 -438.089802) (xy 321.234816 -439.0898) (xy 324.138036 -439.0898)
			(xy 324.138153 -439.074715) (xy 324.139929 -439.044596) (xy 324.141592 -439.029602) (xy 324.141592 -437.950102)
			(xy 324.139921 -437.935109) (xy 324.138144 -437.90499) (xy 324.138036 -437.889904) (xy 324.138153 -437.874819)
			(xy 324.139929 -437.8447) (xy 324.141592 -437.829706) (xy 324.141592 -437.21909) (xy 324.142098 -437.207005)
			(xy 324.149552 -437.184012) (xy 324.16373 -437.164436) (xy 324.183252 -437.150184) (xy 324.206217 -437.142644)
			(xy 324.2183 -437.142128) (xy 325.1581 -437.142128) (xy 325.170212 -437.142516) (xy 325.193244 -437.150019)
			(xy 325.212819 -437.164287) (xy 325.227013 -437.183916) (xy 325.234429 -437.206977) (xy 325.234808 -437.21909)
			(xy 325.234808 -438.089802) (xy 326.138032 -438.089802) (xy 326.138151 -438.074717) (xy 326.139927 -438.044598)
			(xy 326.141588 -438.029604) (xy 326.141588 -436.950104) (xy 326.139917 -436.935111) (xy 326.13814 -436.904992)
			(xy 326.138032 -436.889906) (xy 326.138142 -436.87482) (xy 326.139924 -436.844702) (xy 326.141588 -436.829708)
			(xy 326.141588 -436.219092) (xy 326.142057 -436.207017) (xy 326.149522 -436.184051) (xy 326.163717 -436.164514)
			(xy 326.183254 -436.15032) (xy 326.206221 -436.142857) (xy 326.218296 -436.142384) (xy 327.158096 -436.142384)
			(xy 327.17017 -436.142868) (xy 327.193135 -436.150328) (xy 327.212672 -436.16452) (xy 327.226867 -436.184054)
			(xy 327.234331 -436.207019) (xy 327.234804 -436.219092) (xy 327.234804 -438.760616) (xy 327.234349 -438.772692)
			(xy 327.226882 -438.79566) (xy 327.212683 -438.815197) (xy 327.193142 -438.829391) (xy 327.170172 -438.836852)
			(xy 327.158096 -438.837324) (xy 326.218296 -438.837324) (xy 326.206223 -438.836839) (xy 326.183258 -438.829378)
			(xy 326.163723 -438.815186) (xy 326.149528 -438.795652) (xy 326.142063 -438.772689) (xy 326.141588 -438.760616)
			(xy 326.141588 -438.15) (xy 326.139917 -438.135007) (xy 326.13814 -438.104888) (xy 326.138032 -438.089802)
			(xy 325.234808 -438.089802) (xy 325.234808 -439.0898) (xy 328.138028 -439.0898) (xy 328.138147 -439.074715)
			(xy 328.139923 -439.044596) (xy 328.141584 -439.029602) (xy 328.141584 -437.950102) (xy 328.139913 -437.935109)
			(xy 328.138136 -437.90499) (xy 328.138028 -437.889904) (xy 328.138147 -437.874819) (xy 328.139923 -437.8447)
			(xy 328.141584 -437.829706) (xy 328.141584 -437.21909) (xy 328.142 -437.206996) (xy 328.149465 -437.183987)
			(xy 328.163663 -437.164404) (xy 328.18321 -437.150155) (xy 328.206199 -437.142631) (xy 328.218292 -437.142128)
			(xy 329.158092 -437.142128) (xy 329.170203 -437.142523) (xy 329.193235 -437.150024) (xy 329.212811 -437.16429)
			(xy 329.227005 -437.183918) (xy 329.234421 -437.206977) (xy 329.2348 -437.21909) (xy 329.2348 -438.089802)
			(xy 331.138022 -438.089802) (xy 331.138115 -438.075228) (xy 331.139768 -438.046127) (xy 331.141324 -438.031636)
			(xy 331.141324 -436.948072) (xy 331.13978 -436.93358) (xy 331.138127 -436.90448) (xy 331.138022 -436.889906)
			(xy 331.138115 -436.875332) (xy 331.139768 -436.846231) (xy 331.141324 -436.83174) (xy 331.141324 -436.219092)
			(xy 331.14171 -436.20698) (xy 331.149214 -436.183949) (xy 331.163483 -436.164374) (xy 331.183112 -436.15018)
			(xy 331.206173 -436.142764) (xy 331.218286 -436.142384) (xy 332.158086 -436.142384) (xy 332.170179 -436.14282)
			(xy 332.193187 -436.150278) (xy 332.212771 -436.164471) (xy 332.22702 -436.184014) (xy 332.234545 -436.207)
			(xy 332.235048 -436.219092) (xy 332.235048 -438.760616) (xy 332.234598 -438.772721) (xy 332.2271 -438.795741)
			(xy 332.212845 -438.815309) (xy 332.193234 -438.829505) (xy 332.170192 -438.836934) (xy 332.158086 -438.837324)
			(xy 331.218286 -438.837324) (xy 331.206192 -438.836904) (xy 331.183185 -438.829439) (xy 331.163602 -438.815242)
			(xy 331.149353 -438.795696) (xy 331.141828 -438.772709) (xy 331.141324 -438.760616) (xy 331.141324 -438.147968)
			(xy 331.139779 -438.133476) (xy 331.138127 -438.104376) (xy 331.138022 -438.089802) (xy 329.2348 -438.089802)
			(xy 329.2348 -439.0898) (xy 333.138018 -439.0898) (xy 333.138111 -439.075226) (xy 333.139764 -439.046125)
			(xy 333.14132 -439.031634) (xy 333.14132 -437.94807) (xy 333.139775 -437.933578) (xy 333.138123 -437.904478)
			(xy 333.138018 -437.889904) (xy 333.138111 -437.87533) (xy 333.139764 -437.846229) (xy 333.14132 -437.831738)
			(xy 333.14132 -437.21909) (xy 333.141803 -437.206977) (xy 333.149291 -437.183936) (xy 333.163531 -437.164336)
			(xy 333.183129 -437.150095) (xy 333.206169 -437.142604) (xy 333.218282 -437.142128) (xy 334.158082 -437.142128)
			(xy 334.170203 -437.142575) (xy 334.193259 -437.150061) (xy 334.212874 -437.164306) (xy 334.227126 -437.183916)
			(xy 334.23462 -437.206969) (xy 334.235044 -437.21909) (xy 334.235044 -438.089802) (xy 335.138014 -438.089802)
			(xy 335.138106 -438.075228) (xy 335.13976 -438.046127) (xy 335.141316 -438.031636) (xy 335.141316 -436.948072)
			(xy 335.139772 -436.93358) (xy 335.138119 -436.90448) (xy 335.138014 -436.889906) (xy 335.138107 -436.875332)
			(xy 335.13976 -436.846231) (xy 335.141316 -436.83174) (xy 335.141316 -436.219092) (xy 335.14171 -436.206981)
			(xy 335.149213 -436.183951) (xy 335.16348 -436.164376) (xy 335.183107 -436.150183) (xy 335.206166 -436.142765)
			(xy 335.218278 -436.142384) (xy 336.158078 -436.142384) (xy 336.170171 -436.142827) (xy 336.193178 -436.150283)
			(xy 336.212762 -436.164474) (xy 336.227012 -436.184016) (xy 336.234537 -436.207001) (xy 336.23504 -436.219092)
			(xy 336.23504 -438.760616) (xy 336.234598 -438.772722) (xy 336.227099 -438.795743) (xy 336.212843 -438.815312)
			(xy 336.193229 -438.829508) (xy 336.170185 -438.836935) (xy 336.158078 -438.837324) (xy 335.218278 -438.837324)
			(xy 335.206184 -438.836911) (xy 335.183176 -438.829444) (xy 335.163594 -438.815245) (xy 335.149345 -438.795698)
			(xy 335.14182 -438.772709) (xy 335.141316 -438.760616) (xy 335.141316 -438.147968) (xy 335.139771 -438.133476)
			(xy 335.138119 -438.104376) (xy 335.138014 -438.089802) (xy 334.235044 -438.089802) (xy 334.235044 -439.0898)
			(xy 337.13801 -439.0898) (xy 337.138102 -439.075226) (xy 337.139756 -439.046125) (xy 337.141312 -439.031634)
			(xy 337.141312 -437.94807) (xy 337.139767 -437.933578) (xy 337.138115 -437.904478) (xy 337.13801 -437.889904)
			(xy 337.138103 -437.87533) (xy 337.139756 -437.846229) (xy 337.141312 -437.831738) (xy 337.141312 -437.21909)
			(xy 337.141803 -437.206978) (xy 337.14929 -437.183938) (xy 337.163528 -437.164339) (xy 337.183124 -437.150097)
			(xy 337.206162 -437.142606) (xy 337.218274 -437.142128) (xy 338.158074 -437.142128) (xy 338.170194 -437.142582)
			(xy 338.193251 -437.150066) (xy 338.212865 -437.164309) (xy 338.227118 -437.183917) (xy 338.234612 -437.20697)
			(xy 338.235036 -437.21909) (xy 338.235036 -438.089802) (xy 339.138006 -438.089802) (xy 339.138099 -438.075228)
			(xy 339.139752 -438.046127) (xy 339.141308 -438.031636) (xy 339.141308 -436.948072) (xy 339.139763 -436.93358)
			(xy 339.138111 -436.90448) (xy 339.138006 -436.889906) (xy 339.138099 -436.875332) (xy 339.139752 -436.846231)
			(xy 339.141308 -436.83174) (xy 339.141308 -436.219092) (xy 339.141709 -436.206982) (xy 339.149212 -436.183953)
			(xy 339.163477 -436.164379) (xy 339.183102 -436.150185) (xy 339.206158 -436.142766) (xy 339.21827 -436.142384)
			(xy 340.15807 -436.142384) (xy 340.170162 -436.142834) (xy 340.193169 -436.150288) (xy 340.212754 -436.164477)
			(xy 340.227004 -436.184017) (xy 340.234529 -436.207001) (xy 340.235032 -436.219092) (xy 340.235032 -438.760616)
			(xy 340.234598 -438.772723) (xy 340.227098 -438.795745) (xy 340.21284 -438.815315) (xy 340.193224 -438.82951)
			(xy 340.170178 -438.836936) (xy 340.15807 -438.837324) (xy 339.21827 -438.837324) (xy 339.206175 -438.836918)
			(xy 339.183168 -438.829448) (xy 339.163585 -438.815247) (xy 339.149337 -438.795699) (xy 339.141812 -438.77271)
			(xy 339.141308 -438.760616) (xy 339.141308 -438.147968) (xy 339.139763 -438.133476) (xy 339.138111 -438.104376)
			(xy 339.138006 -438.089802) (xy 338.235036 -438.089802) (xy 338.235036 -439.0898) (xy 341.138002 -439.0898)
			(xy 341.138094 -439.075226) (xy 341.139748 -439.046125) (xy 341.141304 -439.031634) (xy 341.141304 -437.94807)
			(xy 341.139759 -437.933578) (xy 341.138107 -437.904478) (xy 341.138002 -437.889904) (xy 341.138095 -437.87533)
			(xy 341.139748 -437.846229) (xy 341.141304 -437.831738) (xy 341.141304 -437.21909) (xy 341.141803 -437.206978)
			(xy 341.149289 -437.183941) (xy 341.163525 -437.164342) (xy 341.183119 -437.1501) (xy 341.206154 -437.142607)
			(xy 341.218266 -437.142128) (xy 342.158066 -437.142128) (xy 342.170186 -437.142589) (xy 342.193242 -437.15007)
			(xy 342.212857 -437.164312) (xy 342.22711 -437.183918) (xy 342.234604 -437.20697) (xy 342.235028 -437.21909)
			(xy 342.235028 -438.089802) (xy 343.137998 -438.089802) (xy 343.138091 -438.075228) (xy 343.139744 -438.046127)
			(xy 343.1413 -438.031636) (xy 343.1413 -436.948072) (xy 343.139755 -436.93358) (xy 343.138103 -436.90448)
			(xy 343.137998 -436.889906) (xy 343.138091 -436.875332) (xy 343.139744 -436.846231) (xy 343.1413 -436.83174)
			(xy 343.1413 -436.219092) (xy 343.141709 -436.206983) (xy 343.149211 -436.183955) (xy 343.163474 -436.164382)
			(xy 343.183097 -436.150188) (xy 343.206151 -436.142767) (xy 343.218262 -436.142384) (xy 344.158062 -436.142384)
			(xy 344.170154 -436.142841) (xy 344.193161 -436.150292) (xy 344.212745 -436.16448) (xy 344.226995 -436.184019)
			(xy 344.234521 -436.207002) (xy 344.235024 -436.219092) (xy 344.235024 -438.760616) (xy 344.234598 -438.772723)
			(xy 344.227097 -438.795747) (xy 344.212837 -438.815318) (xy 344.193219 -438.829513) (xy 344.170171 -438.836937)
			(xy 344.158062 -438.837324) (xy 343.218262 -438.837324) (xy 343.206167 -438.836924) (xy 343.183159 -438.829453)
			(xy 343.163577 -438.81525) (xy 343.149329 -438.795701) (xy 343.141804 -438.77271) (xy 343.1413 -438.760616)
			(xy 343.1413 -438.147968) (xy 343.139755 -438.133476) (xy 343.138103 -438.104376) (xy 343.137998 -438.089802)
			(xy 342.235028 -438.089802) (xy 342.235028 -439.0898) (xy 345.137994 -439.0898) (xy 345.138086 -439.075226)
			(xy 345.13974 -439.046125) (xy 345.141296 -439.031634) (xy 345.141296 -437.94807) (xy 345.139752 -437.933578)
			(xy 345.138099 -437.904478) (xy 345.137994 -437.889904) (xy 345.138087 -437.87533) (xy 345.13974 -437.846229)
			(xy 345.141296 -437.831738) (xy 345.141296 -437.21909) (xy 345.141803 -437.206979) (xy 345.149288 -437.183943)
			(xy 345.163522 -437.164345) (xy 345.183114 -437.150102) (xy 345.206147 -437.142608) (xy 345.218258 -437.142128)
			(xy 346.158058 -437.142128) (xy 346.170178 -437.142595) (xy 346.193233 -437.150075) (xy 346.212848 -437.164315)
			(xy 346.227101 -437.18392) (xy 346.234596 -437.206971) (xy 346.23502 -437.21909) (xy 346.23502 -439.760614)
			(xy 346.234651 -439.772742) (xy 346.22715 -439.795808) (xy 346.212886 -439.815426) (xy 346.193258 -439.829675)
			(xy 346.170186 -439.83716) (xy 346.158058 -439.837576) (xy 345.218258 -439.837576) (xy 345.206143 -439.837124)
			(xy 345.1831 -439.829627) (xy 345.163501 -439.815379) (xy 345.14926 -439.795774) (xy 345.141771 -439.77273)
			(xy 345.141296 -439.760614) (xy 345.141296 -439.147966) (xy 345.139751 -439.133474) (xy 345.138099 -439.104374)
			(xy 345.137994 -439.0898) (xy 342.235028 -439.0898) (xy 342.235028 -439.760614) (xy 342.234651 -439.772741)
			(xy 342.227151 -439.795806) (xy 342.212889 -439.815424) (xy 342.193263 -439.829673) (xy 342.170193 -439.837159)
			(xy 342.158066 -439.837576) (xy 341.218266 -439.837576) (xy 341.206151 -439.837118) (xy 341.183109 -439.829623)
			(xy 341.163509 -439.815377) (xy 341.149268 -439.795773) (xy 341.141779 -439.772729) (xy 341.141304 -439.760614)
			(xy 341.141304 -439.147966) (xy 341.139759 -439.133474) (xy 341.138107 -439.104374) (xy 341.138002 -439.0898)
			(xy 338.235036 -439.0898) (xy 338.235036 -439.760614) (xy 338.234651 -439.77274) (xy 338.227152 -439.795804)
			(xy 338.212892 -439.815421) (xy 338.193268 -439.82967) (xy 338.1702 -439.837158) (xy 338.158074 -439.837576)
			(xy 337.218274 -439.837576) (xy 337.206159 -439.837111) (xy 337.183118 -439.829618) (xy 337.163518 -439.815374)
			(xy 337.149276 -439.795772) (xy 337.141787 -439.772729) (xy 337.141312 -439.760614) (xy 337.141312 -439.147966)
			(xy 337.139767 -439.133474) (xy 337.138115 -439.104374) (xy 337.13801 -439.0898) (xy 334.235044 -439.0898)
			(xy 334.235044 -439.760614) (xy 334.234651 -439.772739) (xy 334.227153 -439.795802) (xy 334.212895 -439.815418)
			(xy 334.193273 -439.829668) (xy 334.170207 -439.837157) (xy 334.158082 -439.837576) (xy 333.218282 -439.837576)
			(xy 333.206168 -439.837104) (xy 333.183126 -439.829614) (xy 333.163526 -439.815371) (xy 333.149285 -439.79577)
			(xy 333.141795 -439.772728) (xy 333.14132 -439.760614) (xy 333.14132 -439.147966) (xy 333.139775 -439.133474)
			(xy 333.138123 -439.104374) (xy 333.138018 -439.0898) (xy 329.2348 -439.0898) (xy 329.2348 -439.760614)
			(xy 329.234306 -439.7727) (xy 329.22685 -439.795695) (xy 329.212669 -439.815271) (xy 329.193144 -439.829523)
			(xy 329.170177 -439.837061) (xy 329.158092 -439.837576) (xy 328.218292 -439.837576) (xy 328.20618 -439.83719)
			(xy 328.183149 -439.829686) (xy 328.163574 -439.815417) (xy 328.14938 -439.795788) (xy 328.141964 -439.772727)
			(xy 328.141584 -439.760614) (xy 328.141584 -439.149998) (xy 328.139913 -439.135005) (xy 328.138136 -439.104886)
			(xy 328.138028 -439.0898) (xy 325.234808 -439.0898) (xy 325.234808 -439.760614) (xy 325.234306 -439.7727)
			(xy 325.226851 -439.795693) (xy 325.212672 -439.815268) (xy 325.193149 -439.82952) (xy 325.170184 -439.83706)
			(xy 325.1581 -439.837576) (xy 324.2183 -439.837576) (xy 324.206189 -439.837184) (xy 324.183157 -439.829681)
			(xy 324.163582 -439.815414) (xy 324.149388 -439.795786) (xy 324.141972 -439.772727) (xy 324.141592 -439.760614)
			(xy 324.141592 -439.149998) (xy 324.139921 -439.135005) (xy 324.138144 -439.104886) (xy 324.138036 -439.0898)
			(xy 321.234816 -439.0898) (xy 321.234816 -439.760614) (xy 321.234404 -439.772709) (xy 321.226938 -439.795717)
			(xy 321.212739 -439.815301) (xy 321.193191 -439.829549) (xy 321.170201 -439.837073) (xy 321.158108 -439.837576)
			(xy 320.218308 -439.837576) (xy 320.206197 -439.837177) (xy 320.183166 -439.829677) (xy 320.163591 -439.815412)
			(xy 320.149396 -439.795785) (xy 320.14198 -439.772726) (xy 320.1416 -439.760614) (xy 320.1416 -439.149998)
			(xy 320.139929 -439.135005) (xy 320.138152 -439.104886) (xy 320.138044 -439.0898) (xy 317.234824 -439.0898)
			(xy 317.234824 -439.760614) (xy 317.234404 -439.772708) (xy 317.226939 -439.795715) (xy 317.212742 -439.815298)
			(xy 317.193196 -439.829547) (xy 317.170209 -439.837072) (xy 317.158116 -439.837576) (xy 316.218316 -439.837576)
			(xy 316.206206 -439.83717) (xy 316.183175 -439.829672) (xy 316.163599 -439.815408) (xy 316.149405 -439.795783)
			(xy 316.141988 -439.772726) (xy 316.141608 -439.760614) (xy 316.141608 -439.149998) (xy 316.139937 -439.135005)
			(xy 316.13816 -439.104886) (xy 316.138052 -439.0898) (xy 310.60136 -439.0898) (xy 310.60136 -440.045348)
			(xy 311.021984 -440.465972) (xy 314.13831 -440.465972) (xy 314.144152 -440.42203) (xy 314.148881 -440.390461)
			(xy 314.165184 -440.328742) (xy 314.189054 -440.269538) (xy 314.22012 -440.213771) (xy 314.257897 -440.162313)
			(xy 314.301794 -440.115967) (xy 314.351127 -440.075455) (xy 314.405126 -440.04141) (xy 314.462949 -440.014364)
			(xy 314.523693 -439.994738) (xy 314.586409 -439.982838) (xy 314.65012 -439.978851) (xy 314.713831 -439.982838)
			(xy 314.776547 -439.994738) (xy 314.837291 -440.014364) (xy 314.895114 -440.04141) (xy 314.949113 -440.075455)
			(xy 314.998446 -440.115967) (xy 315.042343 -440.162313) (xy 315.08012 -440.213771) (xy 315.111186 -440.269538)
			(xy 315.135056 -440.328742) (xy 315.151359 -440.390461) (xy 315.156088 -440.42203) (xy 315.16193 -440.465972)
			(xy 318.138302 -440.465972) (xy 318.144144 -440.42203) (xy 318.148873 -440.390461) (xy 318.165176 -440.328742)
			(xy 318.189046 -440.269538) (xy 318.220112 -440.213771) (xy 318.257889 -440.162313) (xy 318.301786 -440.115967)
			(xy 318.351119 -440.075455) (xy 318.405118 -440.04141) (xy 318.462941 -440.014364) (xy 318.523685 -439.994738)
			(xy 318.586401 -439.982838) (xy 318.650112 -439.978851) (xy 318.713823 -439.982838) (xy 318.776539 -439.994738)
			(xy 318.837283 -440.014364) (xy 318.895106 -440.04141) (xy 318.949105 -440.075455) (xy 318.998438 -440.115967)
			(xy 319.042335 -440.162313) (xy 319.080112 -440.213771) (xy 319.111178 -440.269538) (xy 319.135048 -440.328742)
			(xy 319.151351 -440.390461) (xy 319.15608 -440.42203) (xy 319.161922 -440.465972) (xy 322.138294 -440.465972)
			(xy 322.144136 -440.42203) (xy 322.148865 -440.390461) (xy 322.165168 -440.328742) (xy 322.189038 -440.269538)
			(xy 322.220104 -440.213771) (xy 322.257881 -440.162313) (xy 322.301778 -440.115967) (xy 322.351111 -440.075455)
			(xy 322.40511 -440.04141) (xy 322.462933 -440.014364) (xy 322.523677 -439.994738) (xy 322.586393 -439.982838)
			(xy 322.650104 -439.978851) (xy 322.713815 -439.982838) (xy 322.776531 -439.994738) (xy 322.837275 -440.014364)
			(xy 322.895098 -440.04141) (xy 322.949097 -440.075455) (xy 322.99843 -440.115967) (xy 323.042327 -440.162313)
			(xy 323.080104 -440.213771) (xy 323.11117 -440.269538) (xy 323.13504 -440.328742) (xy 323.151343 -440.390461)
			(xy 323.156072 -440.42203) (xy 323.161914 -440.465972) (xy 326.138286 -440.465972) (xy 326.144128 -440.42203)
			(xy 326.148857 -440.390461) (xy 326.16516 -440.328742) (xy 326.18903 -440.269538) (xy 326.220096 -440.213771)
			(xy 326.257873 -440.162313) (xy 326.30177 -440.115967) (xy 326.351103 -440.075455) (xy 326.405102 -440.04141)
			(xy 326.462925 -440.014364) (xy 326.523669 -439.994738) (xy 326.586385 -439.982838) (xy 326.650096 -439.978851)
			(xy 326.713807 -439.982838) (xy 326.776523 -439.994738) (xy 326.837267 -440.014364) (xy 326.89509 -440.04141)
			(xy 326.949089 -440.075455) (xy 326.998422 -440.115967) (xy 327.042319 -440.162313) (xy 327.080096 -440.213771)
			(xy 327.111162 -440.269538) (xy 327.135032 -440.328742) (xy 327.151335 -440.390461) (xy 327.156064 -440.42203)
			(xy 327.161906 -440.465972) (xy 331.138276 -440.465972) (xy 331.144118 -440.42203) (xy 331.148847 -440.390461)
			(xy 331.16515 -440.328742) (xy 331.18902 -440.269538) (xy 331.220086 -440.213771) (xy 331.257863 -440.162313)
			(xy 331.30176 -440.115967) (xy 331.351093 -440.075455) (xy 331.405092 -440.04141) (xy 331.462915 -440.014364)
			(xy 331.523659 -439.994738) (xy 331.586375 -439.982838) (xy 331.650086 -439.978851) (xy 331.713797 -439.982838)
			(xy 331.776513 -439.994738) (xy 331.837257 -440.014364) (xy 331.89508 -440.04141) (xy 331.949079 -440.075455)
			(xy 331.998412 -440.115967) (xy 332.042309 -440.162313) (xy 332.080086 -440.213771) (xy 332.111152 -440.269538)
			(xy 332.135022 -440.328742) (xy 332.151325 -440.390461) (xy 332.156054 -440.42203) (xy 332.161896 -440.465972)
			(xy 335.138268 -440.465972) (xy 335.14411 -440.42203) (xy 335.148839 -440.390461) (xy 335.165142 -440.328742)
			(xy 335.189012 -440.269538) (xy 335.220078 -440.213771) (xy 335.257855 -440.162313) (xy 335.301752 -440.115967)
			(xy 335.351085 -440.075455) (xy 335.405084 -440.04141) (xy 335.462907 -440.014364) (xy 335.523651 -439.994738)
			(xy 335.586367 -439.982838) (xy 335.650078 -439.978851) (xy 335.713789 -439.982838) (xy 335.776505 -439.994738)
			(xy 335.837249 -440.014364) (xy 335.895072 -440.04141) (xy 335.949071 -440.075455) (xy 335.998404 -440.115967)
			(xy 336.042301 -440.162313) (xy 336.080078 -440.213771) (xy 336.111144 -440.269538) (xy 336.135014 -440.328742)
			(xy 336.151317 -440.390461) (xy 336.156046 -440.42203) (xy 336.161888 -440.465972) (xy 339.13826 -440.465972)
			(xy 339.144102 -440.42203) (xy 339.148831 -440.390461) (xy 339.165134 -440.328742) (xy 339.189004 -440.269538)
			(xy 339.22007 -440.213771) (xy 339.257847 -440.162313) (xy 339.301744 -440.115967) (xy 339.351077 -440.075455)
			(xy 339.405076 -440.04141) (xy 339.462899 -440.014364) (xy 339.523643 -439.994738) (xy 339.586359 -439.982838)
			(xy 339.65007 -439.978851) (xy 339.713781 -439.982838) (xy 339.776497 -439.994738) (xy 339.837241 -440.014364)
			(xy 339.895064 -440.04141) (xy 339.949063 -440.075455) (xy 339.998396 -440.115967) (xy 340.042293 -440.162313)
			(xy 340.08007 -440.213771) (xy 340.111136 -440.269538) (xy 340.135006 -440.328742) (xy 340.151309 -440.390461)
			(xy 340.156038 -440.42203) (xy 340.16188 -440.465972) (xy 343.138252 -440.465972) (xy 343.144094 -440.42203)
			(xy 343.148823 -440.390461) (xy 343.165126 -440.328742) (xy 343.188996 -440.269538) (xy 343.220062 -440.213771)
			(xy 343.257839 -440.162313) (xy 343.301736 -440.115967) (xy 343.351069 -440.075455) (xy 343.405068 -440.04141)
			(xy 343.462891 -440.014364) (xy 343.523635 -439.994738) (xy 343.586351 -439.982838) (xy 343.650062 -439.978851)
			(xy 343.713773 -439.982838) (xy 343.776489 -439.994738) (xy 343.837233 -440.014364) (xy 343.895056 -440.04141)
			(xy 343.949055 -440.075455) (xy 343.998388 -440.115967) (xy 344.042285 -440.162313) (xy 344.080062 -440.213771)
			(xy 344.111128 -440.269538) (xy 344.134998 -440.328742) (xy 344.151301 -440.390461) (xy 344.15603 -440.42203)
			(xy 344.161872 -440.465972) (xy 356.237032 -440.465972) (xy 356.237032 -433.027582) (xy 356.198836 -432.945331)
			(xy 356.129188 -432.777865) (xy 356.067377 -432.607352) (xy 356.013535 -432.434156) (xy 355.96778 -432.258651)
			(xy 355.930209 -432.081214) (xy 355.900903 -431.902226) (xy 355.879924 -431.722072) (xy 355.867319 -431.541139)
			(xy 355.863113 -431.359816) (xy 355.867317 -431.178494) (xy 355.879921 -430.997561) (xy 355.900898 -430.817407)
			(xy 355.930203 -430.638418) (xy 355.967773 -430.460981) (xy 356.013526 -430.285475) (xy 356.067366 -430.112279)
			(xy 356.129176 -429.941765) (xy 356.198823 -429.774299) (xy 356.237032 -429.692054) (xy 356.237032 -420.841932)
			(xy 363.296708 -420.841932) (xy 363.296708 -424.470068) (xy 421.270176 -424.470068) (xy 421.270176 -417.770056)
			(xy 421.270681 -417.664527) (xy 421.278765 -417.453623) (xy 421.294922 -417.243184) (xy 421.319127 -417.033518)
			(xy 421.351345 -416.824934) (xy 421.391528 -416.617736) (xy 421.439619 -416.412229) (xy 421.495545 -416.208716)
			(xy 421.559226 -416.007493) (xy 421.630567 -415.808858) (xy 421.709464 -415.613101) (xy 421.795802 -415.420509)
			(xy 421.889452 -415.231366) (xy 421.990279 -415.045949) (xy 422.098134 -414.864529) (xy 422.212858 -414.687374)
			(xy 422.334284 -414.514743) (xy 422.462233 -414.34689) (xy 422.596517 -414.184061) (xy 422.73694 -414.026495)
			(xy 422.883295 -413.874423) (xy 423.035367 -413.728068) (xy 423.192933 -413.587645) (xy 423.355762 -413.453361)
			(xy 423.523615 -413.325412) (xy 423.696246 -413.203986) (xy 423.873401 -413.089262) (xy 424.054821 -412.981407)
			(xy 424.240238 -412.88058) (xy 424.429381 -412.78693) (xy 424.621973 -412.700592) (xy 424.81773 -412.621695)
			(xy 425.016365 -412.550354) (xy 425.217588 -412.486673) (xy 425.421101 -412.430747) (xy 425.626608 -412.382656)
			(xy 425.833806 -412.342473) (xy 426.04239 -412.310255) (xy 426.252056 -412.28605) (xy 426.462495 -412.269893)
			(xy 426.673399 -412.261809) (xy 426.884457 -412.261809) (xy 427.095361 -412.269893) (xy 427.3058 -412.28605)
			(xy 427.515466 -412.310255) (xy 427.72405 -412.342473) (xy 427.931248 -412.382656) (xy 428.136755 -412.430747)
			(xy 428.340268 -412.486673) (xy 428.541491 -412.550354) (xy 428.740126 -412.621695) (xy 428.935883 -412.700592)
			(xy 429.128475 -412.78693) (xy 429.317618 -412.88058) (xy 429.503035 -412.981407) (xy 429.684455 -413.089262)
			(xy 429.86161 -413.203986) (xy 430.034241 -413.325412) (xy 430.202094 -413.453361) (xy 430.364923 -413.587645)
			(xy 430.522489 -413.728068) (xy 430.674561 -413.874423) (xy 430.820916 -414.026495) (xy 430.961339 -414.184061)
			(xy 431.095623 -414.34689) (xy 431.223572 -414.514743) (xy 431.344998 -414.687374) (xy 431.459722 -414.864529)
			(xy 431.567577 -415.045949) (xy 431.668404 -415.231366) (xy 431.762054 -415.420509) (xy 431.848392 -415.613101)
			(xy 431.927289 -415.808858) (xy 431.99863 -416.007493) (xy 432.062311 -416.208716) (xy 432.118237 -416.412229)
			(xy 432.166328 -416.617736) (xy 432.206511 -416.824934) (xy 432.238729 -417.033518) (xy 432.262934 -417.243184)
			(xy 432.279091 -417.453623) (xy 432.287175 -417.664527) (xy 432.28768 -417.770056) (xy 432.28768 -424.470068)
			(xy 432.287175 -424.575597) (xy 432.279091 -424.786501) (xy 432.262934 -424.99694) (xy 432.238729 -425.206606)
			(xy 432.206511 -425.41519) (xy 432.166328 -425.622388) (xy 432.118237 -425.827895) (xy 432.062311 -426.031408)
			(xy 431.99863 -426.232631) (xy 431.927289 -426.431266) (xy 431.848392 -426.627023) (xy 431.762054 -426.819615)
			(xy 431.668404 -427.008758) (xy 431.567577 -427.194175) (xy 431.459722 -427.375595) (xy 431.344998 -427.55275)
			(xy 431.223572 -427.725381) (xy 431.095623 -427.893234) (xy 430.961339 -428.056063) (xy 430.820916 -428.213629)
			(xy 430.674561 -428.365701) (xy 430.522489 -428.512056) (xy 430.364923 -428.652479) (xy 430.202094 -428.786763)
			(xy 430.034241 -428.914712) (xy 429.86161 -429.036138) (xy 429.684455 -429.150862) (xy 429.503035 -429.258717)
			(xy 429.317618 -429.359544) (xy 429.128475 -429.453194) (xy 428.935883 -429.539532) (xy 428.740126 -429.618429)
			(xy 428.541491 -429.68977) (xy 428.340268 -429.753451) (xy 428.136755 -429.809377) (xy 427.931248 -429.857468)
			(xy 427.72405 -429.897651) (xy 427.515466 -429.929869) (xy 427.3058 -429.954074) (xy 427.095361 -429.970231)
			(xy 426.884457 -429.978315) (xy 426.673399 -429.978315) (xy 426.462495 -429.970231) (xy 426.252056 -429.954074)
			(xy 426.04239 -429.929869) (xy 425.833806 -429.897651) (xy 425.626608 -429.857468) (xy 425.421101 -429.809377)
			(xy 425.217588 -429.753451) (xy 425.016365 -429.68977) (xy 424.81773 -429.618429) (xy 424.621973 -429.539532)
			(xy 424.429381 -429.453194) (xy 424.240238 -429.359544) (xy 424.054821 -429.258717) (xy 423.873401 -429.150862)
			(xy 423.696246 -429.036138) (xy 423.523615 -428.914712) (xy 423.355762 -428.786763) (xy 423.192933 -428.652479)
			(xy 423.035367 -428.512056) (xy 422.883295 -428.365701) (xy 422.73694 -428.213629) (xy 422.596517 -428.056063)
			(xy 422.462233 -427.893234) (xy 422.334284 -427.725381) (xy 422.212858 -427.55275) (xy 422.098134 -427.375595)
			(xy 421.990279 -427.194175) (xy 421.889452 -427.008758) (xy 421.795802 -426.819615) (xy 421.709464 -426.627023)
			(xy 421.630567 -426.431266) (xy 421.559226 -426.232631) (xy 421.495545 -426.031408) (xy 421.439619 -425.827895)
			(xy 421.391528 -425.622388) (xy 421.351345 -425.41519) (xy 421.319127 -425.206606) (xy 421.294922 -424.99694)
			(xy 421.278765 -424.786501) (xy 421.270681 -424.575597) (xy 421.270176 -424.470068) (xy 363.296708 -424.470068)
			(xy 363.296708 -427.289976) (xy 381.237998 -427.289976) (xy 381.238088 -427.275402) (xy 381.239743 -427.246301)
			(xy 381.2413 -427.23181) (xy 381.2413 -426.147992) (xy 381.239757 -426.1335) (xy 381.238104 -426.1044)
			(xy 381.237998 -426.089826) (xy 381.238093 -426.075252) (xy 381.239744 -426.046151) (xy 381.2413 -426.03166)
			(xy 381.2413 -425.419012) (xy 381.241727 -425.406904) (xy 381.249223 -425.383877) (xy 381.263482 -425.364304)
			(xy 381.283101 -425.350109) (xy 381.306152 -425.342688) (xy 381.318262 -425.342304) (xy 382.258062 -425.342304)
			(xy 382.270146 -425.342839) (xy 382.293139 -425.350281) (xy 382.312717 -425.364451) (xy 382.32697 -425.383968)
			(xy 382.334509 -425.40693) (xy 382.335024 -425.419012) (xy 382.335024 -427.960536) (xy 382.334615 -427.972644)
			(xy 382.327108 -427.995669) (xy 382.312844 -428.015239) (xy 382.293223 -428.029433) (xy 382.270172 -428.036857)
			(xy 382.258062 -428.037244) (xy 381.318262 -428.037244) (xy 381.306169 -428.036825) (xy 381.283164 -428.029356)
			(xy 381.263584 -428.015157) (xy 381.249335 -427.995613) (xy 381.241807 -427.972628) (xy 381.2413 -427.960536)
			(xy 381.2413 -427.348142) (xy 381.239753 -427.33365) (xy 381.238103 -427.30455) (xy 381.237998 -427.289976)
			(xy 363.296708 -427.289976) (xy 363.296708 -428.28972) (xy 383.237994 -428.28972) (xy 383.238088 -428.275146)
			(xy 383.23974 -428.246045) (xy 383.241296 -428.231554) (xy 383.241296 -427.14799) (xy 383.239753 -427.133498)
			(xy 383.2381 -427.104398) (xy 383.237994 -427.089824) (xy 383.238088 -427.07525) (xy 383.23974 -427.046149)
			(xy 383.241296 -427.031658) (xy 383.241296 -426.41901) (xy 383.24182 -426.4069) (xy 383.249299 -426.383864)
			(xy 383.263529 -426.364266) (xy 383.283118 -426.350023) (xy 383.306148 -426.342528) (xy 383.318258 -426.342048)
			(xy 384.258058 -426.342048) (xy 384.27018 -426.342496) (xy 384.293239 -426.349978) (xy 384.312855 -426.364222)
			(xy 384.327108 -426.383833) (xy 384.334599 -426.406889) (xy 384.33502 -426.41901) (xy 384.33502 -427.289976)
			(xy 385.23799 -427.289976) (xy 385.23808 -427.275402) (xy 385.239735 -427.246301) (xy 385.241292 -427.23181)
			(xy 385.241292 -426.147992) (xy 385.239749 -426.1335) (xy 385.238096 -426.1044) (xy 385.23799 -426.089826)
			(xy 385.238085 -426.075252) (xy 385.239736 -426.046151) (xy 385.241292 -426.03166) (xy 385.241292 -425.419012)
			(xy 385.241727 -425.406905) (xy 385.249222 -425.383879) (xy 385.263479 -425.364307) (xy 385.283096 -425.350111)
			(xy 385.306145 -425.342689) (xy 385.318254 -425.342304) (xy 386.258054 -425.342304) (xy 386.270138 -425.342846)
			(xy 386.293131 -425.350286) (xy 386.312708 -425.364454) (xy 386.326962 -425.38397) (xy 386.334501 -425.40693)
			(xy 386.335016 -425.419012) (xy 386.335016 -427.960536) (xy 386.334615 -427.972645) (xy 386.327107 -427.995671)
			(xy 386.312841 -428.015242) (xy 386.293218 -428.029436) (xy 386.270165 -428.036859) (xy 386.258054 -428.037244)
			(xy 385.318254 -428.037244) (xy 385.30616 -428.036832) (xy 385.283156 -428.02936) (xy 385.263575 -428.01516)
			(xy 385.249327 -427.995615) (xy 385.241799 -427.972628) (xy 385.241292 -427.960536) (xy 385.241292 -427.348142)
			(xy 385.239745 -427.33365) (xy 385.238095 -427.30455) (xy 385.23799 -427.289976) (xy 384.33502 -427.289976)
			(xy 384.33502 -428.28972) (xy 387.237986 -428.28972) (xy 387.23808 -428.275146) (xy 387.239732 -428.246045)
			(xy 387.241288 -428.231554) (xy 387.241288 -427.14799) (xy 387.239745 -427.133498) (xy 387.238092 -427.104398)
			(xy 387.237986 -427.089824) (xy 387.238081 -427.07525) (xy 387.239732 -427.046149) (xy 387.241288 -427.031658)
			(xy 387.241288 -426.41901) (xy 387.24182 -426.406901) (xy 387.249298 -426.383867) (xy 387.263526 -426.364269)
			(xy 387.283113 -426.350025) (xy 387.306141 -426.342529) (xy 387.31825 -426.342048) (xy 388.25805 -426.342048)
			(xy 388.270168 -426.342469) (xy 388.293215 -426.349972) (xy 388.312816 -426.364226) (xy 388.327056 -426.383839)
			(xy 388.33454 -426.406891) (xy 388.335012 -426.41901) (xy 388.335012 -427.289976) (xy 389.237982 -427.289976)
			(xy 389.238072 -427.275402) (xy 389.239727 -427.246301) (xy 389.241284 -427.23181) (xy 389.241284 -426.147992)
			(xy 389.239741 -426.1335) (xy 389.238088 -426.1044) (xy 389.237982 -426.089826) (xy 389.238077 -426.075252)
			(xy 389.239728 -426.046151) (xy 389.241284 -426.03166) (xy 389.241284 -425.419012) (xy 389.241727 -425.406905)
			(xy 389.249221 -425.383881) (xy 389.263476 -425.364309) (xy 389.283091 -425.350114) (xy 389.306138 -425.34269)
			(xy 389.318246 -425.342304) (xy 390.258046 -425.342304) (xy 390.270134 -425.342767) (xy 390.29313 -425.350232)
			(xy 390.312707 -425.364421) (xy 390.326957 -425.383953) (xy 390.334494 -425.406925) (xy 390.335008 -425.419012)
			(xy 390.335008 -427.960536) (xy 390.334614 -427.972646) (xy 390.327106 -427.995673) (xy 390.312838 -428.015245)
			(xy 390.293213 -428.029438) (xy 390.270157 -428.03686) (xy 390.258046 -428.037244) (xy 389.318246 -428.037244)
			(xy 389.306157 -428.036753) (xy 389.283155 -428.029307) (xy 389.263573 -428.015127) (xy 389.249322 -427.995597)
			(xy 389.241791 -427.972623) (xy 389.241284 -427.960536) (xy 389.241284 -427.348142) (xy 389.239737 -427.33365)
			(xy 389.238087 -427.30455) (xy 389.237982 -427.289976) (xy 388.335012 -427.289976) (xy 388.335012 -428.28972)
			(xy 391.237978 -428.28972) (xy 391.238072 -428.275146) (xy 391.239724 -428.246045) (xy 391.24128 -428.231554)
			(xy 391.24128 -427.14799) (xy 391.239737 -427.133498) (xy 391.238084 -427.104398) (xy 391.237978 -427.089824)
			(xy 391.238073 -427.07525) (xy 391.239724 -427.046149) (xy 391.24128 -427.031658) (xy 391.24128 -426.41901)
			(xy 391.241669 -426.406884) (xy 391.249164 -426.383818) (xy 391.263422 -426.364199) (xy 391.283047 -426.349949)
			(xy 391.306115 -426.342464) (xy 391.318242 -426.342048) (xy 392.258042 -426.342048) (xy 392.27016 -426.342476)
			(xy 392.293206 -426.349976) (xy 392.312808 -426.364229) (xy 392.327048 -426.383841) (xy 392.334532 -426.406892)
			(xy 392.335004 -426.41901) (xy 392.335004 -427.289976) (xy 393.237974 -427.289976) (xy 393.238064 -427.275402)
			(xy 393.239719 -427.246301) (xy 393.241276 -427.23181) (xy 393.241276 -426.147992) (xy 393.239733 -426.1335)
			(xy 393.23808 -426.1044) (xy 393.237974 -426.089826) (xy 393.238069 -426.075252) (xy 393.23972 -426.046151)
			(xy 393.241276 -426.03166) (xy 393.241276 -425.419012) (xy 393.241726 -425.406906) (xy 393.24922 -425.383883)
			(xy 393.263473 -425.364312) (xy 393.283086 -425.350116) (xy 393.306131 -425.342691) (xy 393.318238 -425.342304)
			(xy 394.258038 -425.342304) (xy 394.270126 -425.342774) (xy 394.293122 -425.350237) (xy 394.312698 -425.364424)
			(xy 394.326949 -425.383954) (xy 394.334486 -425.406926) (xy 394.335 -425.419012) (xy 394.335 -427.960536)
			(xy 394.334614 -427.972647) (xy 394.327105 -427.995675) (xy 394.312835 -428.015248) (xy 394.293208 -428.029441)
			(xy 394.27015 -428.036861) (xy 394.258038 -428.037244) (xy 393.318238 -428.037244) (xy 393.306149 -428.03676)
			(xy 393.283147 -428.029312) (xy 393.263565 -428.01513) (xy 393.249314 -427.995599) (xy 393.241783 -427.972623)
			(xy 393.241276 -427.960536) (xy 393.241276 -427.348142) (xy 393.239729 -427.33365) (xy 393.238079 -427.30455)
			(xy 393.237974 -427.289976) (xy 392.335004 -427.289976) (xy 392.335004 -428.28972) (xy 395.23797 -428.28972)
			(xy 395.238064 -428.275146) (xy 395.239716 -428.246045) (xy 395.241272 -428.231554) (xy 395.241272 -427.14799)
			(xy 395.239729 -427.133498) (xy 395.238076 -427.104398) (xy 395.23797 -427.089824) (xy 395.238065 -427.07525)
			(xy 395.239716 -427.046149) (xy 395.241272 -427.031658) (xy 395.241272 -426.41901) (xy 395.241669 -426.406884)
			(xy 395.249163 -426.38382) (xy 395.263419 -426.364202) (xy 395.283042 -426.349952) (xy 395.306108 -426.342465)
			(xy 395.318234 -426.342048) (xy 396.258034 -426.342048) (xy 396.270151 -426.342483) (xy 396.293197 -426.349981)
			(xy 396.312799 -426.364232) (xy 396.327039 -426.383842) (xy 396.334524 -426.406892) (xy 396.334996 -426.41901)
			(xy 396.334996 -427.289976) (xy 398.237964 -427.289976) (xy 398.238078 -427.274891) (xy 398.239856 -427.244772)
			(xy 398.24152 -427.229778) (xy 398.24152 -426.150024) (xy 398.239851 -426.135031) (xy 398.238073 -426.104912)
			(xy 398.237964 -426.089826) (xy 398.238074 -426.07474) (xy 398.239855 -426.044622) (xy 398.24152 -426.029628)
			(xy 398.24152 -425.419012) (xy 398.241924 -425.406927) (xy 398.249391 -425.38394) (xy 398.263599 -425.364387)
			(xy 398.283154 -425.350184) (xy 398.306143 -425.342721) (xy 398.318228 -425.342304) (xy 399.258028 -425.342304)
			(xy 399.270105 -425.34274) (xy 399.293075 -425.350212) (xy 399.312613 -425.364415) (xy 399.326806 -425.38396)
			(xy 399.334266 -425.406935) (xy 399.334736 -425.419012) (xy 399.334736 -427.960536) (xy 399.334267 -427.97261)
			(xy 399.326798 -427.995573) (xy 399.312602 -428.015107) (xy 399.293066 -428.029302) (xy 399.270102 -428.036768)
			(xy 399.258028 -428.037244) (xy 398.318228 -428.037244) (xy 398.306158 -428.036713) (xy 398.283198 -428.029262)
			(xy 398.263664 -428.015082) (xy 398.249467 -427.995559) (xy 398.241997 -427.972605) (xy 398.24152 -427.960536)
			(xy 398.24152 -427.350174) (xy 398.239856 -427.33518) (xy 398.238074 -427.305062) (xy 398.237964 -427.289976)
			(xy 396.334996 -427.289976) (xy 396.334996 -428.28972) (xy 400.23796 -428.28972) (xy 400.238069 -428.274634)
			(xy 400.239851 -428.244516) (xy 400.241516 -428.229522) (xy 400.241516 -427.150022) (xy 400.239847 -427.135029)
			(xy 400.238069 -427.10491) (xy 400.23796 -427.089824) (xy 400.23807 -427.074738) (xy 400.239851 -427.04462)
			(xy 400.241516 -427.029626) (xy 400.241516 -426.41901) (xy 400.242016 -426.406923) (xy 400.249467 -426.383927)
			(xy 400.263646 -426.364349) (xy 400.283171 -426.350097) (xy 400.306139 -426.342561) (xy 400.318224 -426.342048)
			(xy 401.258024 -426.342048) (xy 401.270129 -426.342495) (xy 401.293148 -426.349995) (xy 401.312716 -426.36425)
			(xy 401.326912 -426.383862) (xy 401.334341 -426.406904) (xy 401.334732 -426.41901) (xy 401.334732 -427.289976)
			(xy 402.237956 -427.289976) (xy 402.23807 -427.274891) (xy 402.239848 -427.244772) (xy 402.241512 -427.229778)
			(xy 402.241512 -426.150024) (xy 402.239843 -426.135031) (xy 402.238065 -426.104912) (xy 402.237956 -426.089826)
			(xy 402.238066 -426.07474) (xy 402.239847 -426.044622) (xy 402.241512 -426.029628) (xy 402.241512 -425.419012)
			(xy 402.241923 -425.406928) (xy 402.24939 -425.383942) (xy 402.263596 -425.36439) (xy 402.283149 -425.350186)
			(xy 402.306136 -425.342722) (xy 402.31822 -425.342304) (xy 403.25802 -425.342304) (xy 403.270097 -425.342748)
			(xy 403.293067 -425.350217) (xy 403.312604 -425.364419) (xy 403.326798 -425.383962) (xy 403.334257 -425.406935)
			(xy 403.334728 -425.419012) (xy 403.334728 -427.960536) (xy 403.334267 -427.97261) (xy 403.326797 -427.995576)
			(xy 403.312599 -428.01511) (xy 403.293061 -428.029304) (xy 403.270095 -428.036769) (xy 403.25802 -428.037244)
			(xy 402.31822 -428.037244) (xy 402.30615 -428.036719) (xy 402.28319 -428.029267) (xy 402.263655 -428.015085)
			(xy 402.249459 -427.995561) (xy 402.241989 -427.972606) (xy 402.241512 -427.960536) (xy 402.241512 -427.350174)
			(xy 402.239848 -427.33518) (xy 402.238066 -427.305062) (xy 402.237956 -427.289976) (xy 401.334732 -427.289976)
			(xy 401.334732 -428.28972) (xy 404.237952 -428.28972) (xy 404.238062 -428.274634) (xy 404.239843 -428.244516)
			(xy 404.241508 -428.229522) (xy 404.241508 -427.150022) (xy 404.239839 -427.135029) (xy 404.238061 -427.10491)
			(xy 404.237952 -427.089824) (xy 404.238062 -427.074738) (xy 404.239843 -427.04462) (xy 404.241508 -427.029626)
			(xy 404.241508 -426.41901) (xy 404.242015 -426.406924) (xy 404.249465 -426.383929) (xy 404.263643 -426.364352)
			(xy 404.283166 -426.3501) (xy 404.306132 -426.342562) (xy 404.318216 -426.342048) (xy 405.258016 -426.342048)
			(xy 405.270121 -426.342502) (xy 405.293139 -426.349999) (xy 405.312708 -426.364253) (xy 405.326904 -426.383863)
			(xy 405.334333 -426.406904) (xy 405.334724 -426.41901) (xy 405.334724 -427.289976) (xy 406.237948 -427.289976)
			(xy 406.238062 -427.274891) (xy 406.23984 -427.244772) (xy 406.241504 -427.229778) (xy 406.241504 -426.150024)
			(xy 406.239835 -426.135031) (xy 406.238057 -426.104912) (xy 406.237948 -426.089826) (xy 406.238058 -426.07474)
			(xy 406.239839 -426.044622) (xy 406.241504 -426.029628) (xy 406.241504 -425.419012) (xy 406.241923 -425.406929)
			(xy 406.249389 -425.383944) (xy 406.263593 -425.364393) (xy 406.283144 -425.350189) (xy 406.306129 -425.342723)
			(xy 406.318212 -425.342304) (xy 407.258012 -425.342304) (xy 407.270088 -425.342754) (xy 407.293058 -425.350222)
			(xy 407.312596 -425.364421) (xy 407.326789 -425.383964) (xy 407.334249 -425.406935) (xy 407.33472 -425.419012)
			(xy 407.33472 -427.960536) (xy 407.334267 -427.972611) (xy 407.326796 -427.995578) (xy 407.312596 -428.015113)
			(xy 407.293056 -428.029307) (xy 407.270087 -428.036771) (xy 407.258012 -428.037244) (xy 406.318212 -428.037244)
			(xy 406.306142 -428.036726) (xy 406.283181 -428.029271) (xy 406.263647 -428.015087) (xy 406.249451 -427.995562)
			(xy 406.241981 -427.972606) (xy 406.241504 -427.960536) (xy 406.241504 -427.350174) (xy 406.23984 -427.33518)
			(xy 406.238058 -427.305062) (xy 406.237948 -427.289976) (xy 405.334724 -427.289976) (xy 405.334724 -428.28972)
			(xy 408.237944 -428.28972) (xy 408.238054 -428.274634) (xy 408.239835 -428.244516) (xy 408.2415 -428.229522)
			(xy 408.2415 -427.150022) (xy 408.239831 -427.135029) (xy 408.238053 -427.10491) (xy 408.237944 -427.089824)
			(xy 408.238054 -427.074738) (xy 408.239835 -427.04462) (xy 408.2415 -427.029626) (xy 408.2415 -426.41901)
			(xy 408.242015 -426.406925) (xy 408.249464 -426.383931) (xy 408.26364 -426.364355) (xy 408.283161 -426.350103)
			(xy 408.306125 -426.342563) (xy 408.318208 -426.342048) (xy 409.258008 -426.342048) (xy 409.270112 -426.342509)
			(xy 409.293131 -426.350004) (xy 409.312699 -426.364256) (xy 409.326896 -426.383865) (xy 409.334325 -426.406905)
			(xy 409.334716 -426.41901) (xy 409.334716 -427.289976) (xy 410.23794 -427.289976) (xy 410.238055 -427.274891)
			(xy 410.239832 -427.244772) (xy 410.241496 -427.229778) (xy 410.241496 -426.150024) (xy 410.239827 -426.135031)
			(xy 410.238049 -426.104912) (xy 410.23794 -426.089826) (xy 410.23805 -426.07474) (xy 410.239831 -426.044622)
			(xy 410.241496 -426.029628) (xy 410.241496 -425.419012) (xy 410.241923 -425.40693) (xy 410.249388 -425.383947)
			(xy 410.26359 -425.364396) (xy 410.283139 -425.350191) (xy 410.306122 -425.342724) (xy 410.318204 -425.342304)
			(xy 411.258004 -425.342304) (xy 411.270088 -425.342709) (xy 411.293073 -425.350179) (xy 411.312624 -425.364387)
			(xy 411.326828 -425.383941) (xy 411.334293 -425.406928) (xy 411.334712 -425.419012) (xy 411.334712 -427.960536)
			(xy 411.334267 -427.972612) (xy 411.326795 -427.99558) (xy 411.312593 -428.015116) (xy 411.293051 -428.029309)
			(xy 411.27008 -428.036772) (xy 411.258004 -428.037244) (xy 410.318204 -428.037244) (xy 410.306133 -428.036733)
			(xy 410.283172 -428.029276) (xy 410.263638 -428.01509) (xy 410.249442 -427.995564) (xy 410.241973 -427.972607)
			(xy 410.241496 -427.960536) (xy 410.241496 -427.350174) (xy 410.239832 -427.33518) (xy 410.23805 -427.305062)
			(xy 410.23794 -427.289976) (xy 409.334716 -427.289976) (xy 409.334716 -428.28972) (xy 412.237936 -428.28972)
			(xy 412.238048 -428.274634) (xy 412.239829 -428.244516) (xy 412.241492 -428.229522) (xy 412.241492 -427.150022)
			(xy 412.239823 -427.135029) (xy 412.238045 -427.10491) (xy 412.237936 -427.089824) (xy 412.238048 -427.074738)
			(xy 412.239829 -427.04462) (xy 412.241492 -427.029626) (xy 412.241492 -426.41901) (xy 412.242015 -426.406926)
			(xy 412.249463 -426.383934) (xy 412.263637 -426.364358) (xy 412.283156 -426.350105) (xy 412.306118 -426.342564)
			(xy 412.3182 -426.342048) (xy 413.258 -426.342048) (xy 413.270104 -426.342515) (xy 413.293122 -426.350009)
			(xy 413.312691 -426.364259) (xy 413.326887 -426.383866) (xy 413.334317 -426.406905) (xy 413.334708 -426.41901)
			(xy 413.334708 -428.960534) (xy 413.334223 -428.972621) (xy 413.326762 -428.995614) (xy 413.312579 -429.01519)
			(xy 413.293053 -429.029441) (xy 413.270085 -429.03698) (xy 413.258 -429.037496) (xy 412.3182 -429.037496)
			(xy 412.306091 -429.037084) (xy 412.283063 -429.029584) (xy 412.263489 -429.015321) (xy 412.249295 -428.995699)
			(xy 412.241875 -428.972645) (xy 412.241492 -428.960534) (xy 412.241492 -428.349918) (xy 412.239823 -428.334925)
			(xy 412.238045 -428.304806) (xy 412.237936 -428.28972) (xy 409.334716 -428.28972) (xy 409.334716 -428.960534)
			(xy 409.334321 -428.97263) (xy 409.326849 -428.995639) (xy 409.312646 -429.015222) (xy 409.293095 -429.02947)
			(xy 409.270103 -429.036993) (xy 409.258008 -429.037496) (xy 408.318208 -429.037496) (xy 408.306099 -429.037077)
			(xy 408.283071 -429.029579) (xy 408.263498 -429.015319) (xy 408.249303 -428.995697) (xy 408.241883 -428.972644)
			(xy 408.2415 -428.960534) (xy 408.2415 -428.349918) (xy 408.239831 -428.334925) (xy 408.238053 -428.304806)
			(xy 408.237944 -428.28972) (xy 405.334724 -428.28972) (xy 405.334724 -428.960534) (xy 405.334321 -428.972629)
			(xy 405.326851 -428.995637) (xy 405.312649 -429.015219) (xy 405.2931 -429.029467) (xy 405.27011 -429.036992)
			(xy 405.258016 -429.037496) (xy 404.318216 -429.037496) (xy 404.306108 -429.03707) (xy 404.28308 -429.029574)
			(xy 404.263507 -429.015315) (xy 404.249312 -428.995695) (xy 404.241891 -428.972644) (xy 404.241508 -428.960534)
			(xy 404.241508 -428.349918) (xy 404.239839 -428.334925) (xy 404.238061 -428.304806) (xy 404.237952 -428.28972)
			(xy 401.334732 -428.28972) (xy 401.334732 -428.960534) (xy 401.334321 -428.972628) (xy 401.326852 -428.995635)
			(xy 401.312652 -429.015216) (xy 401.293105 -429.029465) (xy 401.270117 -429.036991) (xy 401.258024 -429.037496)
			(xy 400.318224 -429.037496) (xy 400.306116 -429.037063) (xy 400.283089 -429.02957) (xy 400.263515 -429.015313)
			(xy 400.24932 -428.995694) (xy 400.241899 -428.972643) (xy 400.241516 -428.960534) (xy 400.241516 -428.349918)
			(xy 400.239847 -428.334925) (xy 400.238069 -428.304806) (xy 400.23796 -428.28972) (xy 396.334996 -428.28972)
			(xy 396.334996 -428.960534) (xy 396.334518 -428.972647) (xy 396.327025 -428.995686) (xy 396.312784 -429.015284)
			(xy 396.293186 -429.029525) (xy 396.270147 -429.037018) (xy 396.258034 -429.037496) (xy 395.318234 -429.037496)
			(xy 395.306125 -429.03696) (xy 395.283088 -429.029486) (xy 395.263489 -429.01526) (xy 395.249245 -428.995673)
			(xy 395.241751 -428.972643) (xy 395.241272 -428.960534) (xy 395.241272 -428.347886) (xy 395.239729 -428.333394)
			(xy 395.238076 -428.304294) (xy 395.23797 -428.28972) (xy 392.335004 -428.28972) (xy 392.335004 -428.960534)
			(xy 392.334518 -428.972646) (xy 392.327027 -428.995683) (xy 392.312787 -429.015281) (xy 392.293191 -429.029523)
			(xy 392.270154 -429.037017) (xy 392.258042 -429.037496) (xy 391.318242 -429.037496) (xy 391.306125 -429.037005)
			(xy 391.283073 -429.029528) (xy 391.26346 -429.015294) (xy 391.249206 -428.995695) (xy 391.241707 -428.972651)
			(xy 391.24128 -428.960534) (xy 391.24128 -428.347886) (xy 391.239737 -428.333394) (xy 391.238084 -428.304294)
			(xy 391.237978 -428.28972) (xy 388.335012 -428.28972) (xy 388.335012 -428.960534) (xy 388.334518 -428.972645)
			(xy 388.327028 -428.995681) (xy 388.31279 -429.015278) (xy 388.293196 -429.02952) (xy 388.270161 -429.037016)
			(xy 388.25805 -429.037496) (xy 387.31825 -429.037496) (xy 387.306136 -429.037031) (xy 387.283097 -429.029535)
			(xy 387.263499 -429.015289) (xy 387.249258 -428.995689) (xy 387.241766 -428.972648) (xy 387.241288 -428.960534)
			(xy 387.241288 -428.347886) (xy 387.239745 -428.333394) (xy 387.238092 -428.304294) (xy 387.237986 -428.28972)
			(xy 384.33502 -428.28972) (xy 384.33502 -428.960534) (xy 384.334669 -428.972663) (xy 384.327162 -428.99573)
			(xy 384.312894 -429.015348) (xy 384.293262 -429.029597) (xy 384.270187 -429.03708) (xy 384.258058 -429.037496)
			(xy 383.318258 -429.037496) (xy 383.306145 -429.037025) (xy 383.283106 -429.02953) (xy 383.263508 -429.015287)
			(xy 383.249266 -428.995687) (xy 383.241774 -428.972647) (xy 383.241296 -428.960534) (xy 383.241296 -428.347886)
			(xy 383.239753 -428.333394) (xy 383.2381 -428.304294) (xy 383.237994 -428.28972) (xy 363.296708 -428.28972)
			(xy 363.296708 -429.659034) (xy 363.334523 -429.738474) (xy 363.403833 -429.90021) (xy 363.465799 -430.064898)
			(xy 363.520297 -430.232206) (xy 363.567215 -430.401796) (xy 363.60646 -430.573324) (xy 363.637951 -430.746444)
			(xy 363.661626 -430.920805) (xy 363.677435 -431.096053) (xy 363.685347 -431.271836) (xy 363.685346 -431.447796)
			(xy 363.677433 -431.623579) (xy 363.661622 -431.798828) (xy 363.637946 -431.973188) (xy 363.606454 -432.146307)
			(xy 363.567208 -432.317835) (xy 363.520288 -432.487425) (xy 363.465789 -432.654733) (xy 363.403821 -432.819421)
			(xy 363.33451 -432.981155) (xy 363.296708 -433.060602) (xy 363.296708 -440.465972) (xy 368.815112 -440.465972)
			(xy 368.83017 -440.465428) (xy 368.858977 -440.456641) (xy 368.88397 -440.439836) (xy 368.902975 -440.416473)
			(xy 368.914341 -440.388583) (xy 368.91708 -440.358591) (xy 368.910953 -440.329104) (xy 368.896494 -440.302685)
			(xy 368.874958 -440.281631) (xy 368.861848 -440.274202) (xy 368.771072 -440.226324) (xy 368.592892 -440.124436)
			(xy 368.418814 -440.01569) (xy 368.2491 -439.900249) (xy 368.08401 -439.778288) (xy 367.923792 -439.649994)
			(xy 367.76869 -439.51556) (xy 367.618939 -439.37519) (xy 367.474765 -439.229096) (xy 367.336389 -439.077501)
			(xy 367.204018 -438.920634) (xy 367.077855 -438.758733) (xy 366.958089 -438.592043) (xy 366.844903 -438.420818)
			(xy 366.738469 -438.245316) (xy 366.638947 -438.065804) (xy 366.546489 -437.882553) (xy 366.461235 -437.695843)
			(xy 366.383313 -437.505955) (xy 366.312843 -437.313177) (xy 366.249931 -437.117802) (xy 366.194672 -436.920127)
			(xy 366.14715 -436.72045) (xy 366.107437 -436.519074) (xy 366.075594 -436.316306) (xy 366.051668 -436.112451)
			(xy 366.035696 -435.907819) (xy 366.027702 -435.702721) (xy 366.027208 -435.600094) (xy 366.027704 -435.497868)
			(xy 366.035631 -435.293569) (xy 366.051475 -435.089731) (xy 366.075211 -434.88666) (xy 366.106802 -434.684663)
			(xy 366.146203 -434.484043) (xy 366.193353 -434.285101) (xy 366.248182 -434.088137) (xy 366.310606 -433.893447)
			(xy 366.380533 -433.701324) (xy 366.457857 -433.512058) (xy 366.542462 -433.325931) (xy 366.63422 -433.143226)
			(xy 366.732994 -432.964215) (xy 366.838635 -432.78917) (xy 366.950983 -432.618352) (xy 367.069871 -432.452019)
			(xy 367.195119 -432.290421) (xy 367.326539 -432.133801) (xy 367.463933 -431.982394) (xy 367.607094 -431.83643)
			(xy 367.755808 -431.696126) (xy 367.90985 -431.561693) (xy 368.068988 -431.433336) (xy 368.232985 -431.311245)
			(xy 368.401592 -431.195605) (xy 368.574556 -431.08659) (xy 368.751618 -430.984363) (xy 368.93251 -430.889079)
			(xy 369.11696 -430.800881) (xy 369.304692 -430.719902) (xy 369.495423 -430.646262) (xy 369.688865 -430.580074)
			(xy 369.884729 -430.521436) (xy 370.082719 -430.470437) (xy 370.282538 -430.427154) (xy 370.483884 -430.391651)
			(xy 370.686456 -430.363982) (xy 370.889949 -430.344189) (xy 371.094056 -430.332301) (xy 371.29847 -430.328337)
			(xy 371.502884 -430.332301) (xy 371.706991 -430.344189) (xy 371.910484 -430.363982) (xy 372.113056 -430.391651)
			(xy 372.314402 -430.427154) (xy 372.514221 -430.470437) (xy 372.712211 -430.521436) (xy 372.908075 -430.580074)
			(xy 373.101517 -430.646262) (xy 373.292248 -430.719902) (xy 373.47998 -430.800881) (xy 373.66443 -430.889079)
			(xy 373.666023 -430.889918) (xy 381.237998 -430.889918) (xy 381.238092 -430.875344) (xy 381.239744 -430.846243)
			(xy 381.2413 -430.831752) (xy 381.2413 -429.747934) (xy 381.239752 -429.733442) (xy 381.238102 -429.704342)
			(xy 381.237998 -429.689768) (xy 381.238096 -429.675194) (xy 381.239746 -429.646093) (xy 381.2413 -429.631602)
			(xy 381.2413 -429.018954) (xy 381.241772 -429.006841) (xy 381.249267 -428.983803) (xy 381.263511 -428.964205)
			(xy 381.28311 -428.949964) (xy 381.306149 -428.942471) (xy 381.318262 -428.941992) (xy 382.258062 -428.941992)
			(xy 382.27017 -428.942543) (xy 382.293204 -428.950015) (xy 382.312803 -428.964238) (xy 382.327047 -428.98382)
			(xy 382.334543 -429.006847) (xy 382.335024 -429.018954) (xy 382.335024 -431.560478) (xy 382.334621 -431.572603)
			(xy 382.32713 -431.595668) (xy 382.312875 -431.615287) (xy 382.293254 -431.629537) (xy 382.270187 -431.637023)
			(xy 382.258062 -431.63744) (xy 381.318262 -431.63744) (xy 381.306143 -431.63702) (xy 381.283095 -431.62952)
			(xy 381.263492 -431.615265) (xy 381.249253 -431.595651) (xy 381.24177 -431.572597) (xy 381.2413 -431.560478)
			(xy 381.2413 -430.948084) (xy 381.239756 -430.933592) (xy 381.238104 -430.904492) (xy 381.237998 -430.889918)
			(xy 373.666023 -430.889918) (xy 373.845322 -430.984363) (xy 374.022384 -431.08659) (xy 374.195348 -431.195605)
			(xy 374.363955 -431.311245) (xy 374.527952 -431.433336) (xy 374.68709 -431.561693) (xy 374.841132 -431.696126)
			(xy 374.989846 -431.83643) (xy 375.042305 -431.889916) (xy 383.237994 -431.889916) (xy 383.238088 -431.875342)
			(xy 383.23974 -431.846241) (xy 383.241296 -431.83175) (xy 383.241296 -430.747932) (xy 383.239748 -430.73344)
			(xy 383.238098 -430.70434) (xy 383.237994 -430.689766) (xy 383.238092 -430.675192) (xy 383.239742 -430.646091)
			(xy 383.241296 -430.6316) (xy 383.241296 -430.018952) (xy 383.241676 -430.006841) (xy 383.249188 -429.983813)
			(xy 383.263459 -429.964241) (xy 383.283088 -429.950048) (xy 383.306145 -429.942628) (xy 383.318258 -429.942244)
			(xy 384.258058 -429.942244) (xy 384.270146 -429.942743) (xy 384.293146 -429.950189) (xy 384.312727 -429.964367)
			(xy 384.326979 -429.983894) (xy 384.334511 -430.006866) (xy 384.33502 -430.018952) (xy 384.33502 -430.889918)
			(xy 385.23799 -430.889918) (xy 385.238084 -430.875344) (xy 385.239736 -430.846243) (xy 385.241292 -430.831752)
			(xy 385.241292 -429.747934) (xy 385.239745 -429.733442) (xy 385.238094 -429.704342) (xy 385.23799 -429.689768)
			(xy 385.238088 -429.675194) (xy 385.239738 -429.646093) (xy 385.241292 -429.631602) (xy 385.241292 -429.018954)
			(xy 385.241772 -429.006842) (xy 385.249266 -428.983805) (xy 385.263508 -428.964208) (xy 385.283105 -428.949966)
			(xy 385.306142 -428.942472) (xy 385.318254 -428.941992) (xy 386.258054 -428.941992) (xy 386.270162 -428.94255)
			(xy 386.293196 -428.950019) (xy 386.312794 -428.96424) (xy 386.327039 -428.983822) (xy 386.334535 -429.006847)
			(xy 386.335016 -429.018954) (xy 386.335016 -431.560478) (xy 386.334621 -431.572604) (xy 386.327129 -431.59567)
			(xy 386.312872 -431.61529) (xy 386.293249 -431.62954) (xy 386.27018 -431.637024) (xy 386.258054 -431.63744)
			(xy 385.318254 -431.63744) (xy 385.306135 -431.637027) (xy 385.283086 -431.629525) (xy 385.263484 -431.615268)
			(xy 385.249244 -431.595653) (xy 385.241762 -431.572598) (xy 385.241292 -431.560478) (xy 385.241292 -430.948084)
			(xy 385.239749 -430.933592) (xy 385.238096 -430.904492) (xy 385.23799 -430.889918) (xy 384.33502 -430.889918)
			(xy 384.33502 -431.889916) (xy 387.237986 -431.889916) (xy 387.23808 -431.875342) (xy 387.239732 -431.846241)
			(xy 387.241288 -431.83175) (xy 387.241288 -430.747932) (xy 387.23974 -430.73344) (xy 387.23809 -430.70434)
			(xy 387.237986 -430.689766) (xy 387.238084 -430.675192) (xy 387.239734 -430.646091) (xy 387.241288 -430.6316)
			(xy 387.241288 -430.018952) (xy 387.241675 -430.006842) (xy 387.249187 -429.983815) (xy 387.263456 -429.964244)
			(xy 387.283083 -429.95005) (xy 387.306138 -429.942629) (xy 387.31825 -429.942244) (xy 388.25805 -429.942244)
			(xy 388.270137 -429.94275) (xy 388.293137 -429.950193) (xy 388.312718 -429.96437) (xy 388.32697 -429.983896)
			(xy 388.334503 -430.006866) (xy 388.335012 -430.018952) (xy 388.335012 -430.889918) (xy 389.237982 -430.889918)
			(xy 389.238076 -430.875344) (xy 389.239728 -430.846243) (xy 389.241284 -430.831752) (xy 389.241284 -429.747934)
			(xy 389.239737 -429.733442) (xy 389.238086 -429.704342) (xy 389.237982 -429.689768) (xy 389.23808 -429.675194)
			(xy 389.23973 -429.646093) (xy 389.241284 -429.631602) (xy 389.241284 -429.018954) (xy 389.241673 -429.006832)
			(xy 389.249179 -428.98378) (xy 389.26344 -428.964175) (xy 389.283062 -428.949937) (xy 389.306124 -428.942459)
			(xy 389.318246 -428.941992) (xy 390.258046 -428.941992) (xy 390.270158 -428.942472) (xy 390.293195 -428.949966)
			(xy 390.312792 -428.964208) (xy 390.327034 -428.983805) (xy 390.334528 -429.006842) (xy 390.335008 -429.018954)
			(xy 390.335008 -431.560478) (xy 390.33447 -431.572587) (xy 390.326995 -431.595622) (xy 390.312768 -431.61522)
			(xy 390.293183 -431.629464) (xy 390.270154 -431.636959) (xy 390.258046 -431.63744) (xy 389.318246 -431.63744)
			(xy 389.306123 -431.637001) (xy 389.283062 -431.629518) (xy 389.263445 -431.615273) (xy 389.249193 -431.595659)
			(xy 389.241703 -431.5726) (xy 389.241284 -431.560478) (xy 389.241284 -430.948084) (xy 389.239741 -430.933592)
			(xy 389.238088 -430.904492) (xy 389.237982 -430.889918) (xy 388.335012 -430.889918) (xy 388.335012 -431.889916)
			(xy 391.237978 -431.889916) (xy 391.238072 -431.875342) (xy 391.239724 -431.846241) (xy 391.24128 -431.83175)
			(xy 391.24128 -430.747932) (xy 391.239732 -430.73344) (xy 391.238082 -430.70434) (xy 391.237978 -430.689766)
			(xy 391.238076 -430.675192) (xy 391.239726 -430.646091) (xy 391.24128 -430.6316) (xy 391.24128 -430.018952)
			(xy 391.241675 -430.006843) (xy 391.249186 -429.983817) (xy 391.263453 -429.964247) (xy 391.283077 -429.950053)
			(xy 391.306131 -429.94263) (xy 391.318242 -429.942244) (xy 392.258042 -429.942244) (xy 392.270134 -429.942672)
			(xy 392.293137 -429.95014) (xy 392.312716 -429.964337) (xy 392.326965 -429.983879) (xy 392.334496 -430.006861)
			(xy 392.335004 -430.018952) (xy 392.335004 -430.889918) (xy 393.237974 -430.889918) (xy 393.238068 -430.875344)
			(xy 393.23972 -430.846243) (xy 393.241276 -430.831752) (xy 393.241276 -429.747934) (xy 393.239729 -429.733442)
			(xy 393.238078 -429.704342) (xy 393.237974 -429.689768) (xy 393.238072 -429.675194) (xy 393.239722 -429.646093)
			(xy 393.241276 -429.631602) (xy 393.241276 -429.018954) (xy 393.241673 -429.006833) (xy 393.249178 -428.983782)
			(xy 393.263438 -428.964178) (xy 393.283057 -428.949939) (xy 393.306117 -428.94246) (xy 393.318238 -428.941992)
			(xy 394.258038 -428.941992) (xy 394.27015 -428.942479) (xy 394.293187 -428.949971) (xy 394.312784 -428.964211)
			(xy 394.327026 -428.983806) (xy 394.33452 -429.006842) (xy 394.335 -429.018954) (xy 394.335 -431.560478)
			(xy 394.33447 -431.572588) (xy 394.326994 -431.595624) (xy 394.312765 -431.615223) (xy 394.293177 -431.629466)
			(xy 394.270147 -431.636961) (xy 394.258038 -431.63744) (xy 393.318238 -431.63744) (xy 393.306115 -431.637007)
			(xy 393.283054 -431.629523) (xy 393.263436 -431.615275) (xy 393.249184 -431.595661) (xy 393.241695 -431.572601)
			(xy 393.241276 -431.560478) (xy 393.241276 -430.948084) (xy 393.239733 -430.933592) (xy 393.23808 -430.904492)
			(xy 393.237974 -430.889918) (xy 392.335004 -430.889918) (xy 392.335004 -431.889916) (xy 395.23797 -431.889916)
			(xy 395.238064 -431.875342) (xy 395.239716 -431.846241) (xy 395.241272 -431.83175) (xy 395.241272 -430.747932)
			(xy 395.239724 -430.73344) (xy 395.238074 -430.70434) (xy 395.23797 -430.689766) (xy 395.238068 -430.675192)
			(xy 395.239718 -430.646091) (xy 395.241272 -430.6316) (xy 395.241272 -430.018952) (xy 395.241675 -430.006843)
			(xy 395.249184 -429.983819) (xy 395.26345 -429.96425) (xy 395.283072 -429.950056) (xy 395.306124 -429.942631)
			(xy 395.318234 -429.942244) (xy 396.258034 -429.942244) (xy 396.270126 -429.942678) (xy 396.293128 -429.950145)
			(xy 396.312708 -429.96434) (xy 396.326957 -429.98388) (xy 396.334488 -430.006862) (xy 396.334996 -430.018952)
			(xy 396.334996 -430.889918) (xy 398.237964 -430.889918) (xy 398.238073 -430.874832) (xy 398.239855 -430.844714)
			(xy 398.24152 -430.82972) (xy 398.24152 -429.749966) (xy 398.239855 -429.734972) (xy 398.238074 -429.704854)
			(xy 398.237964 -429.689768) (xy 398.238078 -429.674682) (xy 398.239856 -429.644564) (xy 398.24152 -429.62957)
			(xy 398.24152 -429.018954) (xy 398.241968 -429.006864) (xy 398.249435 -428.983865) (xy 398.263627 -428.964288)
			(xy 398.283163 -428.950038) (xy 398.306139 -428.942504) (xy 398.318228 -428.941992) (xy 399.258028 -428.941992)
			(xy 399.270138 -428.942392) (xy 399.293164 -428.949899) (xy 399.312736 -428.964165) (xy 399.32693 -428.983789)
			(xy 399.334352 -429.006843) (xy 399.334736 -429.018954) (xy 399.334736 -431.560478) (xy 399.334273 -431.572569)
			(xy 399.32682 -431.595573) (xy 399.312633 -431.615155) (xy 399.293097 -431.629405) (xy 399.270117 -431.636934)
			(xy 399.258028 -431.63744) (xy 398.318228 -431.63744) (xy 398.306125 -431.63696) (xy 398.283105 -431.629473)
			(xy 398.263535 -431.615227) (xy 398.249338 -431.595621) (xy 398.241909 -431.572582) (xy 398.24152 -431.560478)
			(xy 398.24152 -430.950116) (xy 398.239851 -430.935123) (xy 398.238073 -430.905004) (xy 398.237964 -430.889918)
			(xy 396.334996 -430.889918) (xy 396.334996 -431.889916) (xy 400.23796 -431.889916) (xy 400.238069 -431.87483)
			(xy 400.239851 -431.844712) (xy 400.241516 -431.829718) (xy 400.241516 -430.749964) (xy 400.239851 -430.73497)
			(xy 400.23807 -430.704852) (xy 400.23796 -430.689766) (xy 400.238074 -430.67468) (xy 400.239852 -430.644562)
			(xy 400.241516 -430.629568) (xy 400.241516 -430.018952) (xy 400.241924 -430.006873) (xy 400.249402 -429.9839)
			(xy 400.263613 -429.964361) (xy 400.283164 -429.950169) (xy 400.306144 -429.942712) (xy 400.318224 -429.942244)
			(xy 401.258024 -429.942244) (xy 401.270095 -429.942743) (xy 401.293055 -429.950206) (xy 401.312587 -429.964396)
			(xy 401.326783 -429.983924) (xy 401.334253 -430.006881) (xy 401.334732 -430.018952) (xy 401.334732 -430.889918)
			(xy 402.237956 -430.889918) (xy 402.238065 -430.874832) (xy 402.239847 -430.844714) (xy 402.241512 -430.82972)
			(xy 402.241512 -429.749966) (xy 402.239847 -429.734972) (xy 402.238066 -429.704854) (xy 402.237956 -429.689768)
			(xy 402.23807 -429.674682) (xy 402.239848 -429.644564) (xy 402.241512 -429.62957) (xy 402.241512 -429.018954)
			(xy 402.241968 -429.006865) (xy 402.249434 -428.983867) (xy 402.263624 -428.964291) (xy 402.283158 -428.950041)
			(xy 402.306132 -428.942505) (xy 402.31822 -428.941992) (xy 403.25802 -428.941992) (xy 403.270129 -428.942399)
			(xy 403.293156 -428.949903) (xy 403.312728 -428.964167) (xy 403.326922 -428.98379) (xy 403.334344 -429.006843)
			(xy 403.334728 -429.018954) (xy 403.334728 -431.560478) (xy 403.334273 -431.57257) (xy 403.326819 -431.595575)
			(xy 403.31263 -431.615158) (xy 403.293092 -431.629408) (xy 403.27011 -431.636935) (xy 403.25802 -431.63744)
			(xy 402.31822 -431.63744) (xy 402.306116 -431.636967) (xy 402.283096 -431.629478) (xy 402.263527 -431.61523)
			(xy 402.24933 -431.595622) (xy 402.241901 -431.572583) (xy 402.241512 -431.560478) (xy 402.241512 -430.950116)
			(xy 402.239843 -430.935123) (xy 402.238065 -430.905004) (xy 402.237956 -430.889918) (xy 401.334732 -430.889918)
			(xy 401.334732 -431.889916) (xy 404.237952 -431.889916) (xy 404.238061 -431.87483) (xy 404.239843 -431.844712)
			(xy 404.241508 -431.829718) (xy 404.241508 -430.749964) (xy 404.239843 -430.73497) (xy 404.238062 -430.704852)
			(xy 404.237952 -430.689766) (xy 404.238066 -430.67468) (xy 404.239844 -430.644562) (xy 404.241508 -430.629568)
			(xy 404.241508 -430.018952) (xy 404.241923 -430.006873) (xy 404.249401 -429.983902) (xy 404.26361 -429.964364)
			(xy 404.283159 -429.950172) (xy 404.306137 -429.942713) (xy 404.318216 -429.942244) (xy 405.258016 -429.942244)
			(xy 405.270087 -429.94275) (xy 405.293046 -429.950211) (xy 405.312579 -429.964399) (xy 405.326774 -429.983925)
			(xy 405.334245 -430.006882) (xy 405.334724 -430.018952) (xy 405.334724 -430.889918) (xy 406.237948 -430.889918)
			(xy 406.238057 -430.874832) (xy 406.239839 -430.844714) (xy 406.241504 -430.82972) (xy 406.241504 -429.749966)
			(xy 406.239839 -429.734972) (xy 406.238058 -429.704854) (xy 406.237948 -429.689768) (xy 406.238062 -429.674682)
			(xy 406.23984 -429.644564) (xy 406.241504 -429.62957) (xy 406.241504 -429.018954) (xy 406.241967 -429.006866)
			(xy 406.249432 -428.98387) (xy 406.263621 -428.964293) (xy 406.283153 -428.950043) (xy 406.306125 -428.942506)
			(xy 406.318212 -428.941992) (xy 407.258012 -428.941992) (xy 407.270121 -428.942406) (xy 407.293147 -428.949908)
			(xy 407.312719 -428.96417) (xy 407.326914 -428.983792) (xy 407.334336 -429.006844) (xy 407.33472 -429.018954)
			(xy 407.33472 -431.560478) (xy 407.334273 -431.57257) (xy 407.326818 -431.595577) (xy 407.312627 -431.615161)
			(xy 407.293087 -431.629411) (xy 407.270103 -431.636936) (xy 407.258012 -431.63744) (xy 406.318212 -431.63744)
			(xy 406.306108 -431.636974) (xy 406.283088 -431.629483) (xy 406.263518 -431.615232) (xy 406.249322 -431.595624)
			(xy 406.241893 -431.572583) (xy 406.241504 -431.560478) (xy 406.241504 -430.950116) (xy 406.239835 -430.935123)
			(xy 406.238057 -430.905004) (xy 406.237948 -430.889918) (xy 405.334724 -430.889918) (xy 405.334724 -431.889916)
			(xy 408.237944 -431.889916) (xy 408.238053 -431.87483) (xy 408.239835 -431.844712) (xy 408.2415 -431.829718)
			(xy 408.2415 -430.749964) (xy 408.239835 -430.73497) (xy 408.238054 -430.704852) (xy 408.237944 -430.689766)
			(xy 408.238058 -430.67468) (xy 408.239836 -430.644562) (xy 408.2415 -430.629568) (xy 408.2415 -430.018952)
			(xy 408.241923 -430.006874) (xy 408.2494 -429.983904) (xy 408.263607 -429.964367) (xy 408.283154 -429.950174)
			(xy 408.30613 -429.942714) (xy 408.318208 -429.942244) (xy 409.258008 -429.942244) (xy 409.270078 -429.942757)
			(xy 409.293037 -429.950216) (xy 409.31257 -429.964401) (xy 409.326766 -429.983927) (xy 409.334237 -430.006882)
			(xy 409.334716 -430.018952) (xy 409.334716 -430.889918) (xy 410.23794 -430.889918) (xy 410.238051 -430.874832)
			(xy 410.239833 -430.844714) (xy 410.241496 -430.82972) (xy 410.241496 -429.749966) (xy 410.239831 -429.734972)
			(xy 410.23805 -429.704854) (xy 410.23794 -429.689768) (xy 410.238054 -429.674682) (xy 410.239832 -429.644564)
			(xy 410.241496 -429.62957) (xy 410.241496 -429.018954) (xy 410.241967 -429.006866) (xy 410.249431 -428.983872)
			(xy 410.263618 -428.964296) (xy 410.283148 -428.950046) (xy 410.306118 -428.942507) (xy 410.318204 -428.941992)
			(xy 411.258004 -428.941992) (xy 411.270112 -428.942413) (xy 411.293138 -428.949912) (xy 411.312711 -428.964173)
			(xy 411.326906 -428.983793) (xy 411.334328 -429.006844) (xy 411.334712 -429.018954) (xy 411.334712 -431.560478)
			(xy 411.334273 -431.572571) (xy 411.326816 -431.595579) (xy 411.312624 -431.615164) (xy 411.293082 -431.629413)
			(xy 411.270096 -431.636937) (xy 411.258004 -431.63744) (xy 410.318204 -431.63744) (xy 410.306099 -431.636981)
			(xy 410.283079 -431.629488) (xy 410.263509 -431.615236) (xy 410.249313 -431.595625) (xy 410.241885 -431.572584)
			(xy 410.241496 -431.560478) (xy 410.241496 -430.950116) (xy 410.239827 -430.935123) (xy 410.238049 -430.905004)
			(xy 410.23794 -430.889918) (xy 409.334716 -430.889918) (xy 409.334716 -431.889916) (xy 412.237936 -431.889916)
			(xy 412.238047 -431.87483) (xy 412.239829 -431.844712) (xy 412.241492 -431.829718) (xy 412.241492 -430.749964)
			(xy 412.239827 -430.73497) (xy 412.238046 -430.704852) (xy 412.237936 -430.689766) (xy 412.238052 -430.674681)
			(xy 412.23983 -430.644562) (xy 412.241492 -430.629568) (xy 412.241492 -430.018952) (xy 412.241923 -430.006875)
			(xy 412.249399 -429.983906) (xy 412.263604 -429.96437) (xy 412.283149 -429.950177) (xy 412.306123 -429.942716)
			(xy 412.3182 -429.942244) (xy 413.258 -429.942244) (xy 413.27007 -429.942764) (xy 413.293029 -429.95022)
			(xy 413.312562 -429.964404) (xy 413.326758 -429.983928) (xy 413.334229 -430.006883) (xy 413.334708 -430.018952)
			(xy 413.334708 -432.560476) (xy 413.334267 -432.572557) (xy 413.326806 -432.595539) (xy 413.312607 -432.61509)
			(xy 413.293061 -432.629295) (xy 413.270081 -432.636763) (xy 413.258 -432.637184) (xy 412.3182 -432.637184)
			(xy 412.306115 -432.636787) (xy 412.283128 -432.629317) (xy 412.263576 -432.615107) (xy 412.249372 -432.59555)
			(xy 412.241909 -432.572561) (xy 412.241492 -432.560476) (xy 412.241492 -431.950114) (xy 412.239822 -431.935121)
			(xy 412.238045 -431.905002) (xy 412.237936 -431.889916) (xy 409.334716 -431.889916) (xy 409.334716 -432.560476)
			(xy 409.334267 -432.572557) (xy 409.326807 -432.595537) (xy 409.31261 -432.615087) (xy 409.293066 -432.629292)
			(xy 409.270088 -432.636762) (xy 409.258008 -432.637184) (xy 408.318208 -432.637184) (xy 408.306123 -432.63678)
			(xy 408.283137 -432.629312) (xy 408.263584 -432.615105) (xy 408.249381 -432.595549) (xy 408.241917 -432.572561)
			(xy 408.2415 -432.560476) (xy 408.2415 -431.950114) (xy 408.23983 -431.935121) (xy 408.238053 -431.905002)
			(xy 408.237944 -431.889916) (xy 405.334724 -431.889916) (xy 405.334724 -432.560476) (xy 405.334267 -432.572556)
			(xy 405.326808 -432.595535) (xy 405.312613 -432.615084) (xy 405.293071 -432.62929) (xy 405.270096 -432.636761)
			(xy 405.258016 -432.637184) (xy 404.318216 -432.637184) (xy 404.306132 -432.636773) (xy 404.283146 -432.629307)
			(xy 404.263593 -432.615101) (xy 404.249389 -432.595547) (xy 404.241926 -432.57256) (xy 404.241508 -432.560476)
			(xy 404.241508 -431.950114) (xy 404.239838 -431.935121) (xy 404.238061 -431.905002) (xy 404.237952 -431.889916)
			(xy 401.334732 -431.889916) (xy 401.334732 -432.560476) (xy 401.334216 -432.572547) (xy 401.326763 -432.595509)
			(xy 401.312579 -432.615045) (xy 401.293052 -432.629241) (xy 401.270095 -432.636708) (xy 401.258024 -432.637184)
			(xy 400.318224 -432.637184) (xy 400.30614 -432.636766) (xy 400.283154 -432.629303) (xy 400.263601 -432.615099)
			(xy 400.249397 -432.595546) (xy 400.241934 -432.57256) (xy 400.241516 -432.560476) (xy 400.241516 -431.950114)
			(xy 400.239846 -431.935121) (xy 400.238069 -431.905002) (xy 400.23796 -431.889916) (xy 396.334996 -431.889916)
			(xy 396.334996 -432.560476) (xy 396.334563 -432.572584) (xy 396.32707 -432.595611) (xy 396.312813 -432.615185)
			(xy 396.293194 -432.62938) (xy 396.270143 -432.636801) (xy 396.258034 -432.637184) (xy 395.318234 -432.637184)
			(xy 395.306149 -432.636664) (xy 395.283153 -432.62922) (xy 395.263575 -432.615046) (xy 395.249322 -432.595525)
			(xy 395.241785 -432.572559) (xy 395.241272 -432.560476) (xy 395.241272 -431.948082) (xy 395.239729 -431.93359)
			(xy 395.238076 -431.90449) (xy 395.23797 -431.889916) (xy 392.335004 -431.889916) (xy 392.335004 -432.560476)
			(xy 392.334563 -432.572583) (xy 392.327071 -432.595609) (xy 392.312815 -432.615182) (xy 392.293199 -432.629378)
			(xy 392.27015 -432.6368) (xy 392.258042 -432.637184) (xy 391.318242 -432.637184) (xy 391.306157 -432.636657)
			(xy 391.283162 -432.629215) (xy 391.263583 -432.615043) (xy 391.24933 -432.595523) (xy 391.241793 -432.572559)
			(xy 391.24128 -432.560476) (xy 391.24128 -431.948082) (xy 391.239737 -431.93359) (xy 391.238084 -431.90449)
			(xy 391.237978 -431.889916) (xy 388.335012 -431.889916) (xy 388.335012 -432.560476) (xy 388.334563 -432.572582)
			(xy 388.327072 -432.595607) (xy 388.312818 -432.615179) (xy 388.293204 -432.629375) (xy 388.270158 -432.636799)
			(xy 388.25805 -432.637184) (xy 387.31825 -432.637184) (xy 387.306165 -432.636651) (xy 387.28317 -432.62921)
			(xy 387.263592 -432.61504) (xy 387.249339 -432.595522) (xy 387.241801 -432.572559) (xy 387.241288 -432.560476)
			(xy 387.241288 -431.948082) (xy 387.239745 -431.93359) (xy 387.238092 -431.90449) (xy 387.237986 -431.889916)
			(xy 384.33502 -431.889916) (xy 384.33502 -432.560476) (xy 384.334563 -432.572582) (xy 384.327073 -432.595605)
			(xy 384.312821 -432.615176) (xy 384.293209 -432.629373) (xy 384.270165 -432.636797) (xy 384.258058 -432.637184)
			(xy 383.318258 -432.637184) (xy 383.306169 -432.636729) (xy 383.283171 -432.629264) (xy 383.263593 -432.615073)
			(xy 383.249343 -432.595539) (xy 383.241808 -432.572564) (xy 383.241296 -432.560476) (xy 383.241296 -431.948082)
			(xy 383.239753 -431.93359) (xy 383.2381 -431.90449) (xy 383.237994 -431.889916) (xy 375.042305 -431.889916)
			(xy 375.133007 -431.982394) (xy 375.270401 -432.133801) (xy 375.401821 -432.290421) (xy 375.527069 -432.452019)
			(xy 375.645957 -432.618352) (xy 375.758305 -432.78917) (xy 375.863946 -432.964215) (xy 375.96272 -433.143226)
			(xy 376.054478 -433.325931) (xy 376.139083 -433.512058) (xy 376.216407 -433.701324) (xy 376.286334 -433.893447)
			(xy 376.348758 -434.088137) (xy 376.403587 -434.285101) (xy 376.450737 -434.484043) (xy 376.451879 -434.48986)
			(xy 381.237998 -434.48986) (xy 381.238096 -434.475286) (xy 381.239745 -434.446185) (xy 381.2413 -434.431694)
			(xy 381.2413 -433.34813) (xy 381.239752 -433.333638) (xy 381.238102 -433.304538) (xy 381.237998 -433.289964)
			(xy 381.238096 -433.27539) (xy 381.239745 -433.246289) (xy 381.2413 -433.231798) (xy 381.2413 -432.618896)
			(xy 381.241713 -432.606787) (xy 381.249213 -432.583759) (xy 381.263476 -432.564186) (xy 381.283098 -432.549992)
			(xy 381.306152 -432.542571) (xy 381.318262 -432.542188) (xy 382.258062 -432.542188) (xy 382.270154 -432.542641)
			(xy 382.293162 -432.550093) (xy 382.312747 -432.564281) (xy 382.326997 -432.583821) (xy 382.334521 -432.606805)
			(xy 382.335024 -432.618896) (xy 382.335024 -435.16042) (xy 382.334601 -435.172528) (xy 382.327099 -435.195551)
			(xy 382.312838 -435.215122) (xy 382.29322 -435.229317) (xy 382.270171 -435.236741) (xy 382.258062 -435.237128)
			(xy 381.318262 -435.237128) (xy 381.306167 -435.236724) (xy 381.28316 -435.229253) (xy 381.263578 -435.215052)
			(xy 381.24933 -435.195503) (xy 381.241804 -435.172514) (xy 381.2413 -435.16042) (xy 381.2413 -434.548026)
			(xy 381.239752 -434.533534) (xy 381.238102 -434.504434) (xy 381.237998 -434.48986) (xy 376.451879 -434.48986)
			(xy 376.490138 -434.684663) (xy 376.521729 -434.88666) (xy 376.545465 -435.089731) (xy 376.561309 -435.293569)
			(xy 376.568925 -435.489858) (xy 383.237994 -435.489858) (xy 383.238091 -435.475284) (xy 383.239741 -435.446183)
			(xy 383.241296 -435.431692) (xy 383.241296 -434.348128) (xy 383.239748 -434.333636) (xy 383.238098 -434.304536)
			(xy 383.237994 -434.289962) (xy 383.238092 -434.275388) (xy 383.239741 -434.246287) (xy 383.241296 -434.231796)
			(xy 383.241296 -433.618894) (xy 383.241806 -433.606783) (xy 383.24929 -433.583747) (xy 383.263524 -433.564149)
			(xy 383.283115 -433.549906) (xy 383.306148 -433.542412) (xy 383.318258 -433.541932) (xy 384.258058 -433.541932)
			(xy 384.270178 -433.542396) (xy 384.293234 -433.549876) (xy 384.31285 -433.564116) (xy 384.327103 -433.583722)
			(xy 384.334597 -433.606774) (xy 384.33502 -433.618894) (xy 384.33502 -434.48986) (xy 385.23799 -434.48986)
			(xy 385.238088 -434.475286) (xy 385.239737 -434.446185) (xy 385.241292 -434.431694) (xy 385.241292 -433.34813)
			(xy 385.239744 -433.333638) (xy 385.238094 -433.304538) (xy 385.23799 -433.289964) (xy 385.238088 -433.27539)
			(xy 385.239737 -433.246289) (xy 385.241292 -433.231798) (xy 385.241292 -432.618896) (xy 385.241713 -432.606788)
			(xy 385.249212 -432.583762) (xy 385.263473 -432.564189) (xy 385.283093 -432.549994) (xy 385.306144 -432.542572)
			(xy 385.318254 -432.542188) (xy 386.258054 -432.542188) (xy 386.270146 -432.542647) (xy 386.293153 -432.550097)
			(xy 386.312738 -432.564284) (xy 386.326988 -432.583823) (xy 386.334513 -432.606806) (xy 386.335016 -432.618896)
			(xy 386.335016 -435.16042) (xy 386.334601 -435.172528) (xy 386.327098 -435.195554) (xy 386.312836 -435.215125)
			(xy 386.293215 -435.229319) (xy 386.270164 -435.236743) (xy 386.258054 -435.237128) (xy 385.318254 -435.237128)
			(xy 385.306159 -435.236731) (xy 385.283151 -435.229258) (xy 385.263569 -435.215054) (xy 385.249322 -435.195505)
			(xy 385.241796 -435.172514) (xy 385.241292 -435.16042) (xy 385.241292 -434.548026) (xy 385.239744 -434.533534)
			(xy 385.238094 -434.504434) (xy 385.23799 -434.48986) (xy 384.33502 -434.48986) (xy 384.33502 -435.489858)
			(xy 387.237986 -435.489858) (xy 387.238083 -435.475284) (xy 387.239733 -435.446183) (xy 387.241288 -435.431692)
			(xy 387.241288 -434.348128) (xy 387.23974 -434.333636) (xy 387.23809 -434.304536) (xy 387.237986 -434.289962)
			(xy 387.238084 -434.275388) (xy 387.239733 -434.246287) (xy 387.241288 -434.231796) (xy 387.241288 -433.618894)
			(xy 387.241806 -433.606784) (xy 387.249289 -433.583749) (xy 387.263521 -433.564152) (xy 387.28311 -433.549909)
			(xy 387.30614 -433.542413) (xy 387.31825 -433.541932) (xy 388.25805 -433.541932) (xy 388.270167 -433.542369)
			(xy 388.29321 -433.549869) (xy 388.312811 -433.564121) (xy 388.327051 -433.583729) (xy 388.334538 -433.606777)
			(xy 388.335012 -433.618894) (xy 388.335012 -434.48986) (xy 389.237982 -434.48986) (xy 389.23808 -434.475286)
			(xy 389.239729 -434.446185) (xy 389.241284 -434.431694) (xy 389.241284 -433.34813) (xy 389.239736 -433.333638)
			(xy 389.238086 -433.304538) (xy 389.237982 -433.289964) (xy 389.23808 -433.27539) (xy 389.23973 -433.246289)
			(xy 389.241284 -433.231798) (xy 389.241284 -432.618896) (xy 389.241713 -432.606789) (xy 389.249211 -432.583764)
			(xy 389.26347 -432.564192) (xy 389.283088 -432.549997) (xy 389.306137 -432.542573) (xy 389.318246 -432.542188)
			(xy 390.258046 -432.542188) (xy 390.270143 -432.542569) (xy 390.293153 -432.550044) (xy 390.312736 -432.564251)
			(xy 390.326984 -432.583805) (xy 390.334506 -432.6068) (xy 390.335008 -432.618896) (xy 390.335008 -435.16042)
			(xy 390.334601 -435.172529) (xy 390.327097 -435.195556) (xy 390.312833 -435.215128) (xy 390.29321 -435.229322)
			(xy 390.270157 -435.236744) (xy 390.258046 -435.237128) (xy 389.318246 -435.237128) (xy 389.306156 -435.236653)
			(xy 389.283151 -435.229205) (xy 389.263568 -435.215022) (xy 389.249317 -435.195487) (xy 389.241789 -435.172509)
			(xy 389.241284 -435.16042) (xy 389.241284 -434.548026) (xy 389.239736 -434.533534) (xy 389.238086 -434.504434)
			(xy 389.237982 -434.48986) (xy 388.335012 -434.48986) (xy 388.335012 -435.489858) (xy 391.237978 -435.489858)
			(xy 391.238076 -435.475284) (xy 391.239725 -435.446183) (xy 391.24128 -435.431692) (xy 391.24128 -434.348128)
			(xy 391.239732 -434.333636) (xy 391.238082 -434.304536) (xy 391.237978 -434.289962) (xy 391.238076 -434.275388)
			(xy 391.239725 -434.246287) (xy 391.24128 -434.231796) (xy 391.24128 -433.618894) (xy 391.241656 -433.606767)
			(xy 391.249155 -433.583701) (xy 391.263416 -433.564082) (xy 391.283044 -433.549833) (xy 391.306115 -433.542348)
			(xy 391.318242 -433.541932) (xy 392.258042 -433.541932) (xy 392.270158 -433.542376) (xy 392.293202 -433.549874)
			(xy 392.312802 -433.564123) (xy 392.327043 -433.583731) (xy 392.33453 -433.606778) (xy 392.335004 -433.618894)
			(xy 392.335004 -434.48986) (xy 393.237974 -434.48986) (xy 393.238072 -434.475286) (xy 393.239721 -434.446185)
			(xy 393.241276 -434.431694) (xy 393.241276 -433.34813) (xy 393.239728 -433.333638) (xy 393.238078 -433.304538)
			(xy 393.237974 -433.289964) (xy 393.238072 -433.27539) (xy 393.239722 -433.246289) (xy 393.241276 -433.231798)
			(xy 393.241276 -432.618896) (xy 393.241712 -432.606789) (xy 393.24921 -432.583766) (xy 393.263467 -432.564195)
			(xy 393.283083 -432.55) (xy 393.30613 -432.542575) (xy 393.318238 -432.542188) (xy 394.258038 -432.542188)
			(xy 394.270134 -432.542576) (xy 394.293144 -432.550049) (xy 394.312728 -432.564254) (xy 394.326975 -432.583807)
			(xy 394.334498 -432.606801) (xy 394.335 -432.618896) (xy 394.335 -435.16042) (xy 394.334601 -435.17253)
			(xy 394.327096 -435.195558) (xy 394.31283 -435.215131) (xy 394.293205 -435.229325) (xy 394.270149 -435.236745)
			(xy 394.258038 -435.237128) (xy 393.318238 -435.237128) (xy 393.306147 -435.23666) (xy 393.283142 -435.22921)
			(xy 393.263559 -435.215024) (xy 393.249308 -435.195489) (xy 393.241781 -435.172509) (xy 393.241276 -435.16042)
			(xy 393.241276 -434.548026) (xy 393.239728 -434.533534) (xy 393.238078 -434.504434) (xy 393.237974 -434.48986)
			(xy 392.335004 -434.48986) (xy 392.335004 -435.489858) (xy 395.23797 -435.489858) (xy 395.238068 -435.475284)
			(xy 395.239717 -435.446183) (xy 395.241272 -435.431692) (xy 395.241272 -434.348128) (xy 395.239724 -434.333636)
			(xy 395.238074 -434.304536) (xy 395.23797 -434.289962) (xy 395.238068 -434.275388) (xy 395.239717 -434.246287)
			(xy 395.241272 -434.231796) (xy 395.241272 -433.618894) (xy 395.241656 -433.606768) (xy 395.249154 -433.583703)
			(xy 395.263413 -433.564085) (xy 395.283039 -433.549835) (xy 395.306107 -433.542349) (xy 395.318234 -433.541932)
			(xy 396.258034 -433.541932) (xy 396.27015 -433.542383) (xy 396.293193 -433.549878) (xy 396.312794 -433.564126)
			(xy 396.327034 -433.583732) (xy 396.334522 -433.606778) (xy 396.334996 -433.618894) (xy 396.334996 -434.48986)
			(xy 398.237964 -434.48986) (xy 398.238077 -434.474774) (xy 398.239856 -434.444656) (xy 398.24152 -434.429662)
			(xy 398.24152 -433.350162) (xy 398.239855 -433.335168) (xy 398.238074 -433.30505) (xy 398.237964 -433.289964)
			(xy 398.238077 -433.274878) (xy 398.239856 -433.24476) (xy 398.24152 -433.229766) (xy 398.24152 -432.618896)
			(xy 398.241909 -432.60681) (xy 398.249382 -432.583823) (xy 398.263593 -432.56427) (xy 398.283151 -432.550067)
			(xy 398.306142 -432.542604) (xy 398.318228 -432.542188) (xy 399.258028 -432.542188) (xy 399.270104 -432.54264)
			(xy 399.293071 -432.55011) (xy 399.312607 -432.56431) (xy 399.326801 -432.58385) (xy 399.334264 -432.60682)
			(xy 399.334736 -432.618896) (xy 399.334736 -435.16042) (xy 399.334253 -435.172493) (xy 399.326788 -435.195456)
			(xy 399.312596 -435.21499) (xy 399.293063 -435.229185) (xy 399.270101 -435.236652) (xy 399.258028 -435.237128)
			(xy 398.318228 -435.237128) (xy 398.306149 -435.236664) (xy 398.28317 -435.229206) (xy 398.263621 -435.215013)
			(xy 398.249416 -435.195473) (xy 398.241944 -435.172499) (xy 398.24152 -435.16042) (xy 398.24152 -434.550058)
			(xy 398.239854 -434.535064) (xy 398.238074 -434.504946) (xy 398.237964 -434.48986) (xy 396.334996 -434.48986)
			(xy 396.334996 -435.489858) (xy 400.23796 -435.489858) (xy 400.238073 -435.474772) (xy 400.239852 -435.444654)
			(xy 400.241516 -435.42966) (xy 400.241516 -434.35016) (xy 400.239851 -434.335166) (xy 400.23807 -434.305048)
			(xy 400.23796 -434.289962) (xy 400.238073 -434.274876) (xy 400.239852 -434.244758) (xy 400.241516 -434.229764)
			(xy 400.241516 -433.618894) (xy 400.242002 -433.606807) (xy 400.249457 -433.58381) (xy 400.26364 -433.564232)
			(xy 400.283168 -433.549981) (xy 400.306138 -433.542445) (xy 400.318224 -433.541932) (xy 401.258024 -433.541932)
			(xy 401.270137 -433.542296) (xy 401.293171 -433.549806) (xy 401.312746 -433.56408) (xy 401.326939 -433.583715)
			(xy 401.334353 -433.606779) (xy 401.334732 -433.618894) (xy 401.334732 -434.48986) (xy 402.237956 -434.48986)
			(xy 402.238069 -434.474774) (xy 402.239848 -434.444656) (xy 402.241512 -434.429662) (xy 402.241512 -433.350162)
			(xy 402.239847 -433.335168) (xy 402.238066 -433.30505) (xy 402.237956 -433.289964) (xy 402.238069 -433.274878)
			(xy 402.239848 -433.24476) (xy 402.241512 -433.229766) (xy 402.241512 -432.618896) (xy 402.241909 -432.606811)
			(xy 402.24938 -432.583825) (xy 402.26359 -432.564273) (xy 402.283146 -432.550069) (xy 402.306135 -432.542606)
			(xy 402.31822 -432.542188) (xy 403.25802 -432.542188) (xy 403.270095 -432.542647) (xy 403.293062 -432.550115)
			(xy 403.312599 -432.564313) (xy 403.326793 -432.583852) (xy 403.334255 -432.606821) (xy 403.334728 -432.618896)
			(xy 403.334728 -435.16042) (xy 403.334253 -435.172494) (xy 403.326787 -435.195458) (xy 403.312593 -435.214993)
			(xy 403.293058 -435.229187) (xy 403.270094 -435.236653) (xy 403.25802 -435.237128) (xy 402.31822 -435.237128)
			(xy 402.306148 -435.236619) (xy 402.283185 -435.229165) (xy 402.26365 -435.214979) (xy 402.249454 -435.195451)
			(xy 402.241987 -435.172491) (xy 402.241512 -435.16042) (xy 402.241512 -434.550058) (xy 402.239846 -434.535064)
			(xy 402.238066 -434.504946) (xy 402.237956 -434.48986) (xy 401.334732 -434.48986) (xy 401.334732 -435.489858)
			(xy 404.237952 -435.489858) (xy 404.238065 -435.474772) (xy 404.239844 -435.444654) (xy 404.241508 -435.42966)
			(xy 404.241508 -434.35016) (xy 404.239843 -434.335166) (xy 404.238062 -434.305048) (xy 404.237952 -434.289962)
			(xy 404.238065 -434.274876) (xy 404.239844 -434.244758) (xy 404.241508 -434.229764) (xy 404.241508 -433.618894)
			(xy 404.242002 -433.606807) (xy 404.249456 -433.583812) (xy 404.263637 -433.564235) (xy 404.283163 -433.549984)
			(xy 404.306131 -433.542446) (xy 404.318216 -433.541932) (xy 405.258016 -433.541932) (xy 405.270129 -433.542303)
			(xy 405.293162 -433.549811) (xy 405.312738 -433.564083) (xy 405.326931 -433.583716) (xy 405.334345 -433.606779)
			(xy 405.334724 -433.618894) (xy 405.334724 -434.48986) (xy 406.237948 -434.48986) (xy 406.238061 -434.474774)
			(xy 406.23984 -434.444656) (xy 406.241504 -434.429662) (xy 406.241504 -433.350162) (xy 406.239839 -433.335168)
			(xy 406.238058 -433.30505) (xy 406.237948 -433.289964) (xy 406.238061 -433.274878) (xy 406.23984 -433.24476)
			(xy 406.241504 -433.229766) (xy 406.241504 -432.618896) (xy 406.241909 -432.606812) (xy 406.249379 -432.583827)
			(xy 406.263587 -432.564276) (xy 406.283141 -432.550072) (xy 406.306128 -432.542607) (xy 406.318212 -432.542188)
			(xy 407.258012 -432.542188) (xy 407.270087 -432.542654) (xy 407.293054 -432.550119) (xy 407.31259 -432.564316)
			(xy 407.326784 -432.583854) (xy 407.334247 -432.606821) (xy 407.33472 -432.618896) (xy 407.33472 -435.16042)
			(xy 407.334253 -435.172494) (xy 407.326786 -435.19546) (xy 407.31259 -435.214996) (xy 407.293053 -435.22919)
			(xy 407.270086 -435.236654) (xy 407.258012 -435.237128) (xy 406.318212 -435.237128) (xy 406.30614 -435.236626)
			(xy 406.283177 -435.229169) (xy 406.263641 -435.214982) (xy 406.249446 -435.195452) (xy 406.241979 -435.172492)
			(xy 406.241504 -435.16042) (xy 406.241504 -434.550058) (xy 406.239838 -434.535064) (xy 406.238058 -434.504946)
			(xy 406.237948 -434.48986) (xy 405.334724 -434.48986) (xy 405.334724 -435.489858) (xy 408.237944 -435.489858)
			(xy 408.238057 -435.474772) (xy 408.239836 -435.444654) (xy 408.2415 -435.42966) (xy 408.2415 -434.35016)
			(xy 408.239834 -434.335166) (xy 408.238054 -434.305048) (xy 408.237944 -434.289962) (xy 408.238057 -434.274876)
			(xy 408.239836 -434.244758) (xy 408.2415 -434.229764) (xy 408.2415 -433.618894) (xy 408.242002 -433.606808)
			(xy 408.249455 -433.583814) (xy 408.263634 -433.564238) (xy 408.283158 -433.549986) (xy 408.306124 -433.542447)
			(xy 408.318208 -433.541932) (xy 409.258008 -433.541932) (xy 409.270121 -433.54231) (xy 409.293154 -433.549815)
			(xy 409.312729 -433.564086) (xy 409.326923 -433.583717) (xy 409.334337 -433.60678) (xy 409.334716 -433.618894)
			(xy 409.334716 -434.48986) (xy 410.23794 -434.48986) (xy 410.238053 -434.474774) (xy 410.239832 -434.444656)
			(xy 410.241496 -434.429662) (xy 410.241496 -433.350162) (xy 410.239831 -433.335168) (xy 410.23805 -433.30505)
			(xy 410.23794 -433.289964) (xy 410.238053 -433.274878) (xy 410.239832 -433.24476) (xy 410.241496 -433.229766)
			(xy 410.241496 -432.618896) (xy 410.241961 -432.606821) (xy 410.249425 -432.583853) (xy 410.263621 -432.564316)
			(xy 410.28316 -432.550121) (xy 410.306129 -432.54266) (xy 410.318204 -432.542188) (xy 411.258004 -432.542188)
			(xy 411.270078 -432.542661) (xy 411.293045 -432.550124) (xy 411.312582 -432.564318) (xy 411.326776 -432.583855)
			(xy 411.334239 -432.606822) (xy 411.334712 -432.618896) (xy 411.334712 -435.16042) (xy 411.334253 -435.172495)
			(xy 411.326785 -435.195462) (xy 411.312587 -435.214999) (xy 411.293048 -435.229193) (xy 411.270079 -435.236655)
			(xy 411.258004 -435.237128) (xy 410.318204 -435.237128) (xy 410.306132 -435.236633) (xy 410.283168 -435.229174)
			(xy 410.263633 -435.214984) (xy 410.249437 -435.195454) (xy 410.241971 -435.172492) (xy 410.241496 -435.16042)
			(xy 410.241496 -434.550058) (xy 410.23983 -434.535064) (xy 410.23805 -434.504946) (xy 410.23794 -434.48986)
			(xy 409.334716 -434.48986) (xy 409.334716 -435.489858) (xy 412.237936 -435.489858) (xy 412.238051 -435.474773)
			(xy 412.23983 -435.444654) (xy 412.241492 -435.42966) (xy 412.241492 -434.35016) (xy 412.239826 -434.335166)
			(xy 412.238046 -434.305048) (xy 412.237936 -434.289962) (xy 412.238051 -434.274877) (xy 412.23983 -434.244758)
			(xy 412.241492 -434.229764) (xy 412.241492 -433.618894) (xy 412.242002 -433.606809) (xy 412.249454 -433.583816)
			(xy 412.263631 -433.564241) (xy 412.283153 -433.549989) (xy 412.306117 -433.542448) (xy 412.3182 -433.541932)
			(xy 413.258 -433.541932) (xy 413.270112 -433.542317) (xy 413.293145 -433.54982) (xy 413.312721 -433.564088)
			(xy 413.326914 -433.583719) (xy 413.334329 -433.60678) (xy 413.334708 -433.618894) (xy 413.334708 -436.160418)
			(xy 413.334209 -436.172504) (xy 413.326753 -436.195497) (xy 413.312573 -436.215072) (xy 413.29305 -436.229324)
			(xy 413.270084 -436.236864) (xy 413.258 -436.23738) (xy 412.3182 -436.23738) (xy 412.306089 -436.236984)
			(xy 412.283058 -436.229482) (xy 412.263483 -436.215216) (xy 412.24929 -436.195589) (xy 412.241872 -436.17253)
			(xy 412.241492 -436.160418) (xy 412.241492 -435.550056) (xy 412.239826 -435.535062) (xy 412.238046 -435.504944)
			(xy 412.237936 -435.489858) (xy 409.334716 -435.489858) (xy 409.334716 -436.160418) (xy 409.334307 -436.172513)
			(xy 409.32684 -436.195522) (xy 409.31264 -436.215105) (xy 409.293092 -436.229353) (xy 409.270102 -436.236877)
			(xy 409.258008 -436.23738) (xy 408.318208 -436.23738) (xy 408.306098 -436.236977) (xy 408.283067 -436.229477)
			(xy 408.263492 -436.215213) (xy 408.249298 -436.195587) (xy 408.24188 -436.17253) (xy 408.2415 -436.160418)
			(xy 408.2415 -435.550056) (xy 408.239834 -435.535062) (xy 408.238054 -435.504944) (xy 408.237944 -435.489858)
			(xy 405.334724 -435.489858) (xy 405.334724 -436.160418) (xy 405.334307 -436.172512) (xy 405.326841 -436.195519)
			(xy 405.312643 -436.215102) (xy 405.293097 -436.229351) (xy 405.270109 -436.236876) (xy 405.258016 -436.23738)
			(xy 404.318216 -436.23738) (xy 404.306106 -436.23697) (xy 404.283076 -436.229472) (xy 404.263501 -436.21521)
			(xy 404.249306 -436.195585) (xy 404.241889 -436.172529) (xy 404.241508 -436.160418) (xy 404.241508 -435.550056)
			(xy 404.239842 -435.535062) (xy 404.238062 -435.504944) (xy 404.237952 -435.489858) (xy 401.334732 -435.489858)
			(xy 401.334732 -436.160418) (xy 401.334308 -436.172511) (xy 401.326843 -436.195517) (xy 401.312646 -436.215099)
			(xy 401.293102 -436.229348) (xy 401.270116 -436.236875) (xy 401.258024 -436.23738) (xy 400.318224 -436.23738)
			(xy 400.306114 -436.236963) (xy 400.283085 -436.229468) (xy 400.263509 -436.215207) (xy 400.249315 -436.195584)
			(xy 400.241897 -436.172529) (xy 400.241516 -436.160418) (xy 400.241516 -435.550056) (xy 400.23985 -435.535062)
			(xy 400.23807 -435.504944) (xy 400.23796 -435.489858) (xy 396.334996 -435.489858) (xy 396.334996 -436.160418)
			(xy 396.334504 -436.17253) (xy 396.327016 -436.195568) (xy 396.312778 -436.215167) (xy 396.293183 -436.229409)
			(xy 396.270146 -436.236902) (xy 396.258034 -436.23738) (xy 395.318234 -436.23738) (xy 395.306115 -436.236911)
			(xy 395.28306 -436.229431) (xy 395.263446 -436.215191) (xy 395.249193 -436.195587) (xy 395.241697 -436.172537)
			(xy 395.241272 -436.160418) (xy 395.241272 -435.548024) (xy 395.239724 -435.533532) (xy 395.238074 -435.504432)
			(xy 395.23797 -435.489858) (xy 392.335004 -435.489858) (xy 392.335004 -436.160418) (xy 392.334504 -436.172529)
			(xy 392.327017 -436.195566) (xy 392.312781 -436.215164) (xy 392.293188 -436.229406) (xy 392.270153 -436.236901)
			(xy 392.258042 -436.23738) (xy 391.318242 -436.23738) (xy 391.306123 -436.236905) (xy 391.283069 -436.229426)
			(xy 391.263455 -436.215188) (xy 391.249201 -436.195585) (xy 391.241705 -436.172536) (xy 391.24128 -436.160418)
			(xy 391.24128 -435.548024) (xy 391.239732 -435.533532) (xy 391.238082 -435.504432) (xy 391.237978 -435.489858)
			(xy 388.335012 -435.489858) (xy 388.335012 -436.160418) (xy 388.334505 -436.172529) (xy 388.327018 -436.195564)
			(xy 388.312784 -436.215161) (xy 388.293193 -436.229404) (xy 388.27016 -436.2369) (xy 388.25805 -436.23738)
			(xy 387.31825 -436.23738) (xy 387.306135 -436.236931) (xy 387.283093 -436.229432) (xy 387.263493 -436.215184)
			(xy 387.249253 -436.195578) (xy 387.241764 -436.172534) (xy 387.241288 -436.160418) (xy 387.241288 -435.548024)
			(xy 387.23974 -435.533532) (xy 387.23809 -435.504432) (xy 387.237986 -435.489858) (xy 384.33502 -435.489858)
			(xy 384.33502 -436.160418) (xy 384.334654 -436.172546) (xy 384.327152 -436.195612) (xy 384.312888 -436.215231)
			(xy 384.293258 -436.22948) (xy 384.270186 -436.236964) (xy 384.258058 -436.23738) (xy 383.318258 -436.23738)
			(xy 383.306143 -436.236924) (xy 383.283101 -436.229428) (xy 383.263502 -436.215181) (xy 383.249261 -436.195577)
			(xy 383.241772 -436.172533) (xy 383.241296 -436.160418) (xy 383.241296 -435.548024) (xy 383.239748 -435.533532)
			(xy 383.238098 -435.504432) (xy 383.237994 -435.489858) (xy 376.568925 -435.489858) (xy 376.569236 -435.497868)
			(xy 376.569732 -435.600094) (xy 376.569235 -435.702721) (xy 376.561245 -435.90782) (xy 376.545276 -436.112453)
			(xy 376.521353 -436.316308) (xy 376.489512 -436.519078) (xy 376.449802 -436.720455) (xy 376.402282 -436.920133)
			(xy 376.347025 -437.117809) (xy 376.284114 -437.313185) (xy 376.213645 -437.505964) (xy 376.135724 -437.695853)
			(xy 376.050471 -437.882564) (xy 375.958013 -438.065815) (xy 375.944715 -438.089802) (xy 381.237998 -438.089802)
			(xy 381.238091 -438.075228) (xy 381.239744 -438.046127) (xy 381.2413 -438.031636) (xy 381.2413 -436.948072)
			(xy 381.239755 -436.93358) (xy 381.238103 -436.90448) (xy 381.237998 -436.889906) (xy 381.238091 -436.875332)
			(xy 381.239744 -436.846231) (xy 381.2413 -436.83174) (xy 381.2413 -436.219092) (xy 381.241709 -436.206983)
			(xy 381.249211 -436.183955) (xy 381.263474 -436.164382) (xy 381.283097 -436.150188) (xy 381.306151 -436.142767)
			(xy 381.318262 -436.142384) (xy 382.258062 -436.142384) (xy 382.270154 -436.142841) (xy 382.293161 -436.150292)
			(xy 382.312745 -436.16448) (xy 382.326995 -436.184019) (xy 382.334521 -436.207002) (xy 382.335024 -436.219092)
			(xy 382.335024 -438.760616) (xy 382.334598 -438.772723) (xy 382.327097 -438.795747) (xy 382.312837 -438.815318)
			(xy 382.293219 -438.829513) (xy 382.270171 -438.836937) (xy 382.258062 -438.837324) (xy 381.318262 -438.837324)
			(xy 381.306167 -438.836924) (xy 381.283159 -438.829453) (xy 381.263577 -438.81525) (xy 381.249329 -438.795701)
			(xy 381.241804 -438.77271) (xy 381.2413 -438.760616) (xy 381.2413 -438.147968) (xy 381.239755 -438.133476)
			(xy 381.238103 -438.104376) (xy 381.237998 -438.089802) (xy 375.944715 -438.089802) (xy 375.858491 -438.245328)
			(xy 375.752057 -438.420831) (xy 375.63887 -438.592057) (xy 375.519104 -438.758747) (xy 375.39294 -438.920648)
			(xy 375.260568 -439.077514) (xy 375.249353 -439.0898) (xy 383.237994 -439.0898) (xy 383.238086 -439.075226)
			(xy 383.23974 -439.046125) (xy 383.241296 -439.031634) (xy 383.241296 -437.94807) (xy 383.239752 -437.933578)
			(xy 383.238099 -437.904478) (xy 383.237994 -437.889904) (xy 383.238087 -437.87533) (xy 383.23974 -437.846229)
			(xy 383.241296 -437.831738) (xy 383.241296 -437.21909) (xy 383.241803 -437.206979) (xy 383.249288 -437.183943)
			(xy 383.263522 -437.164345) (xy 383.283114 -437.150102) (xy 383.306147 -437.142608) (xy 383.318258 -437.142128)
			(xy 384.258058 -437.142128) (xy 384.270178 -437.142595) (xy 384.293233 -437.150075) (xy 384.312848 -437.164315)
			(xy 384.327101 -437.18392) (xy 384.334596 -437.206971) (xy 384.33502 -437.21909) (xy 384.33502 -438.089802)
			(xy 385.23799 -438.089802) (xy 385.238083 -438.075228) (xy 385.239736 -438.046127) (xy 385.241292 -438.031636)
			(xy 385.241292 -436.948072) (xy 385.239748 -436.93358) (xy 385.238095 -436.90448) (xy 385.23799 -436.889906)
			(xy 385.238083 -436.875332) (xy 385.239736 -436.846231) (xy 385.241292 -436.83174) (xy 385.241292 -436.219092)
			(xy 385.241709 -436.206983) (xy 385.24921 -436.183957) (xy 385.263472 -436.164385) (xy 385.283092 -436.15019)
			(xy 385.306144 -436.142768) (xy 385.318254 -436.142384) (xy 386.258054 -436.142384) (xy 386.270146 -436.142847)
			(xy 386.293152 -436.150297) (xy 386.312737 -436.164483) (xy 386.326987 -436.18402) (xy 386.334512 -436.207002)
			(xy 386.335016 -436.219092) (xy 386.335016 -438.760616) (xy 386.334598 -438.772724) (xy 386.327096 -438.795749)
			(xy 386.312834 -438.815321) (xy 386.293214 -438.829515) (xy 386.270163 -438.836939) (xy 386.258054 -438.837324)
			(xy 385.318254 -438.837324) (xy 385.306158 -438.836931) (xy 385.28315 -438.829457) (xy 385.263568 -438.815253)
			(xy 385.24932 -438.795702) (xy 385.241796 -438.77271) (xy 385.241292 -438.760616) (xy 385.241292 -438.147968)
			(xy 385.239747 -438.133476) (xy 385.238095 -438.104376) (xy 385.23799 -438.089802) (xy 384.33502 -438.089802)
			(xy 384.33502 -439.0898) (xy 387.237986 -439.0898) (xy 387.238078 -439.075226) (xy 387.239732 -439.046125)
			(xy 387.241288 -439.031634) (xy 387.241288 -437.94807) (xy 387.239744 -437.933578) (xy 387.238091 -437.904478)
			(xy 387.237986 -437.889904) (xy 387.238079 -437.87533) (xy 387.239732 -437.846229) (xy 387.241288 -437.831738)
			(xy 387.241288 -437.21909) (xy 387.241803 -437.20698) (xy 387.249287 -437.183945) (xy 387.263519 -437.164348)
			(xy 387.283109 -437.150105) (xy 387.30614 -437.142609) (xy 387.31825 -437.142128) (xy 388.25805 -437.142128)
			(xy 388.270166 -437.142569) (xy 388.293209 -437.150069) (xy 388.312809 -437.164319) (xy 388.32705 -437.183927)
			(xy 388.334537 -437.206974) (xy 388.335012 -437.21909) (xy 388.335012 -438.089802) (xy 389.237982 -438.089802)
			(xy 389.238075 -438.075228) (xy 389.239728 -438.046127) (xy 389.241284 -438.031636) (xy 389.241284 -436.948072)
			(xy 389.23974 -436.93358) (xy 389.238087 -436.90448) (xy 389.237982 -436.889906) (xy 389.238075 -436.875332)
			(xy 389.239728 -436.846231) (xy 389.241284 -436.83174) (xy 389.241284 -436.219092) (xy 389.241709 -436.206984)
			(xy 389.249209 -436.183959) (xy 389.263469 -436.164388) (xy 389.283087 -436.150193) (xy 389.306137 -436.142769)
			(xy 389.318246 -436.142384) (xy 390.258046 -436.142384) (xy 390.270142 -436.142769) (xy 390.293152 -436.150244)
			(xy 390.312735 -436.16445) (xy 390.326982 -436.184003) (xy 390.334505 -436.206997) (xy 390.335008 -436.219092)
			(xy 390.335008 -438.760616) (xy 390.334598 -438.772725) (xy 390.327095 -438.795751) (xy 390.312831 -438.815324)
			(xy 390.293209 -438.829518) (xy 390.270156 -438.83694) (xy 390.258046 -438.837324) (xy 389.318246 -438.837324)
			(xy 389.306155 -438.836853) (xy 389.28315 -438.829404) (xy 389.263566 -438.81522) (xy 389.249315 -438.795685)
			(xy 389.241789 -438.772705) (xy 389.241284 -438.760616) (xy 389.241284 -438.147968) (xy 389.239739 -438.133476)
			(xy 389.238087 -438.104376) (xy 389.237982 -438.089802) (xy 388.335012 -438.089802) (xy 388.335012 -439.0898)
			(xy 391.237978 -439.0898) (xy 391.238071 -439.075226) (xy 391.239724 -439.046125) (xy 391.24128 -439.031634)
			(xy 391.24128 -437.94807) (xy 391.239736 -437.933578) (xy 391.238083 -437.904478) (xy 391.237978 -437.889904)
			(xy 391.238071 -437.87533) (xy 391.239724 -437.846229) (xy 391.24128 -437.831738) (xy 391.24128 -437.21909)
			(xy 391.241652 -437.206963) (xy 391.249152 -437.183896) (xy 391.263415 -437.164278) (xy 391.283043 -437.150029)
			(xy 391.306114 -437.142544) (xy 391.318242 -437.142128) (xy 392.258042 -437.142128) (xy 392.270158 -437.142576)
			(xy 392.293201 -437.150073) (xy 392.312801 -437.164322) (xy 392.327041 -437.183928) (xy 392.334529 -437.206974)
			(xy 392.335004 -437.21909) (xy 392.335004 -438.089802) (xy 393.237974 -438.089802) (xy 393.238067 -438.075228)
			(xy 393.23972 -438.046127) (xy 393.241276 -438.031636) (xy 393.241276 -436.948072) (xy 393.239732 -436.93358)
			(xy 393.238079 -436.90448) (xy 393.237974 -436.889906) (xy 393.238067 -436.875332) (xy 393.23972 -436.846231)
			(xy 393.241276 -436.83174) (xy 393.241276 -436.219092) (xy 393.241709 -436.206985) (xy 393.249208 -436.183962)
			(xy 393.263466 -436.164391) (xy 393.283082 -436.150195) (xy 393.30613 -436.142771) (xy 393.318238 -436.142384)
			(xy 394.258038 -436.142384) (xy 394.270134 -436.142776) (xy 394.293143 -436.150248) (xy 394.312726 -436.164453)
			(xy 394.326974 -436.184004) (xy 394.334497 -436.206997) (xy 394.335 -436.219092) (xy 394.335 -438.760616)
			(xy 394.334597 -438.772726) (xy 394.327094 -438.795754) (xy 394.312828 -438.815326) (xy 394.293204 -438.82952)
			(xy 394.270149 -438.836941) (xy 394.258038 -438.837324) (xy 393.318238 -438.837324) (xy 393.306147 -438.83686)
			(xy 393.283141 -438.829409) (xy 393.263558 -438.815223) (xy 393.249307 -438.795686) (xy 393.241781 -438.772706)
			(xy 393.241276 -438.760616) (xy 393.241276 -438.147968) (xy 393.239731 -438.133476) (xy 393.238079 -438.104376)
			(xy 393.237974 -438.089802) (xy 392.335004 -438.089802) (xy 392.335004 -439.0898) (xy 395.23797 -439.0898)
			(xy 395.238063 -439.075226) (xy 395.239716 -439.046125) (xy 395.241272 -439.031634) (xy 395.241272 -437.94807)
			(xy 395.239728 -437.933578) (xy 395.238075 -437.904478) (xy 395.23797 -437.889904) (xy 395.238063 -437.87533)
			(xy 395.239716 -437.846229) (xy 395.241272 -437.831738) (xy 395.241272 -437.21909) (xy 395.241652 -437.206963)
			(xy 395.249151 -437.183898) (xy 395.263412 -437.164281) (xy 395.283038 -437.150031) (xy 395.306107 -437.142545)
			(xy 395.318234 -437.142128) (xy 396.258034 -437.142128) (xy 396.270149 -437.142583) (xy 396.293192 -437.150078)
			(xy 396.312792 -437.164325) (xy 396.327033 -437.18393) (xy 396.334521 -437.206975) (xy 396.334996 -437.21909)
			(xy 396.334996 -438.089802) (xy 398.237964 -438.089802) (xy 398.238081 -438.074717) (xy 398.239857 -438.044598)
			(xy 398.24152 -438.029604) (xy 398.24152 -436.950104) (xy 398.23985 -436.935111) (xy 398.238072 -436.904992)
			(xy 398.237964 -436.889906) (xy 398.238072 -436.87482) (xy 398.239854 -436.844702) (xy 398.24152 -436.829708)
			(xy 398.24152 -436.219092) (xy 398.241906 -436.207006) (xy 398.249379 -436.184018) (xy 398.263591 -436.164466)
			(xy 398.283151 -436.150263) (xy 398.306142 -436.1428) (xy 398.318228 -436.142384) (xy 399.258028 -436.142384)
			(xy 399.270103 -436.14284) (xy 399.29307 -436.150309) (xy 399.312606 -436.164508) (xy 399.3268 -436.184048)
			(xy 399.334263 -436.207017) (xy 399.334736 -436.219092) (xy 399.334736 -438.760616) (xy 399.33425 -438.772689)
			(xy 399.326786 -438.795651) (xy 399.312594 -438.815186) (xy 399.293062 -438.829381) (xy 399.270101 -438.836848)
			(xy 399.258028 -438.837324) (xy 398.318228 -438.837324) (xy 398.306148 -438.836864) (xy 398.283169 -438.829406)
			(xy 398.26362 -438.815211) (xy 398.249414 -438.79567) (xy 398.241943 -438.772695) (xy 398.24152 -438.760616)
			(xy 398.24152 -438.15) (xy 398.239849 -438.135007) (xy 398.238072 -438.104888) (xy 398.237964 -438.089802)
			(xy 396.334996 -438.089802) (xy 396.334996 -439.0898) (xy 400.23796 -439.0898) (xy 400.238077 -439.074715)
			(xy 400.239853 -439.044596) (xy 400.241516 -439.029602) (xy 400.241516 -437.950102) (xy 400.239845 -437.935109)
			(xy 400.238068 -437.90499) (xy 400.23796 -437.889904) (xy 400.238077 -437.874819) (xy 400.239853 -437.8447)
			(xy 400.241516 -437.829706) (xy 400.241516 -437.21909) (xy 400.241999 -437.207002) (xy 400.249455 -437.184006)
			(xy 400.263639 -437.164428) (xy 400.283167 -437.150177) (xy 400.306138 -437.142641) (xy 400.318224 -437.142128)
			(xy 401.258024 -437.142128) (xy 401.270137 -437.142496) (xy 401.29317 -437.150006) (xy 401.312745 -437.164279)
			(xy 401.326938 -437.183912) (xy 401.334353 -437.206975) (xy 401.334732 -437.21909) (xy 401.334732 -438.089802)
			(xy 402.237956 -438.089802) (xy 402.238073 -438.074717) (xy 402.239849 -438.044598) (xy 402.241512 -438.029604)
			(xy 402.241512 -436.950104) (xy 402.239842 -436.935111) (xy 402.238064 -436.904992) (xy 402.237956 -436.889906)
			(xy 402.238064 -436.87482) (xy 402.239846 -436.844702) (xy 402.241512 -436.829708) (xy 402.241512 -436.219092)
			(xy 402.241906 -436.207007) (xy 402.249378 -436.18402) (xy 402.263588 -436.164469) (xy 402.283146 -436.150265)
			(xy 402.306135 -436.142802) (xy 402.31822 -436.142384) (xy 403.25802 -436.142384) (xy 403.270095 -436.142847)
			(xy 403.293061 -436.150314) (xy 403.312597 -436.164511) (xy 403.326791 -436.18405) (xy 403.334255 -436.207017)
			(xy 403.334728 -436.219092) (xy 403.334728 -438.760616) (xy 403.33425 -438.772689) (xy 403.326785 -438.795654)
			(xy 403.312591 -438.815189) (xy 403.293057 -438.829383) (xy 403.270093 -438.836849) (xy 403.25802 -438.837324)
			(xy 402.31822 -438.837324) (xy 402.30614 -438.83687) (xy 402.283161 -438.82941) (xy 402.263611 -438.815214)
			(xy 402.249406 -438.795672) (xy 402.241935 -438.772696) (xy 402.241512 -438.760616) (xy 402.241512 -438.15)
			(xy 402.239841 -438.135007) (xy 402.238064 -438.104888) (xy 402.237956 -438.089802) (xy 401.334732 -438.089802)
			(xy 401.334732 -439.0898) (xy 404.237952 -439.0898) (xy 404.238069 -439.074715) (xy 404.239845 -439.044596)
			(xy 404.241508 -439.029602) (xy 404.241508 -437.950102) (xy 404.239837 -437.935109) (xy 404.23806 -437.90499)
			(xy 404.237952 -437.889904) (xy 404.238069 -437.874819) (xy 404.239845 -437.8447) (xy 404.241508 -437.829706)
			(xy 404.241508 -437.21909) (xy 404.241998 -437.207003) (xy 404.249454 -437.184008) (xy 404.263636 -437.164431)
			(xy 404.283162 -437.150179) (xy 404.306131 -437.142642) (xy 404.318216 -437.142128) (xy 405.258016 -437.142128)
			(xy 405.270129 -437.142503) (xy 405.293161 -437.15001) (xy 405.312736 -437.164281) (xy 405.326929 -437.183914)
			(xy 405.334345 -437.206976) (xy 405.334724 -437.21909) (xy 405.334724 -438.089802) (xy 406.237948 -438.089802)
			(xy 406.238065 -438.074717) (xy 406.239841 -438.044598) (xy 406.241504 -438.029604) (xy 406.241504 -436.950104)
			(xy 406.239834 -436.935111) (xy 406.238056 -436.904992) (xy 406.237948 -436.889906) (xy 406.238056 -436.87482)
			(xy 406.239838 -436.844702) (xy 406.241504 -436.829708) (xy 406.241504 -436.219092) (xy 406.241906 -436.207008)
			(xy 406.249377 -436.184023) (xy 406.263586 -436.164471) (xy 406.283141 -436.150268) (xy 406.306128 -436.142803)
			(xy 406.318212 -436.142384) (xy 407.258012 -436.142384) (xy 407.270086 -436.142854) (xy 407.293053 -436.150319)
			(xy 407.312589 -436.164514) (xy 407.326783 -436.184051) (xy 407.334247 -436.207018) (xy 407.33472 -436.219092)
			(xy 407.33472 -438.760616) (xy 407.334249 -438.77269) (xy 407.326784 -438.795656) (xy 407.312589 -438.815191)
			(xy 407.293052 -438.829386) (xy 407.270086 -438.83685) (xy 407.258012 -438.837324) (xy 406.318212 -438.837324)
			(xy 406.30614 -438.836826) (xy 406.283176 -438.829369) (xy 406.26364 -438.81518) (xy 406.249444 -438.79565)
			(xy 406.241979 -438.772688) (xy 406.241504 -438.760616) (xy 406.241504 -438.15) (xy 406.239833 -438.135007)
			(xy 406.238056 -438.104888) (xy 406.237948 -438.089802) (xy 405.334724 -438.089802) (xy 405.334724 -439.0898)
			(xy 408.237944 -439.0898) (xy 408.238061 -439.074715) (xy 408.239837 -439.044596) (xy 408.2415 -439.029602)
			(xy 408.2415 -437.950102) (xy 408.239829 -437.935109) (xy 408.238052 -437.90499) (xy 408.237944 -437.889904)
			(xy 408.238061 -437.874819) (xy 408.239837 -437.8447) (xy 408.2415 -437.829706) (xy 408.2415 -437.21909)
			(xy 408.241998 -437.207004) (xy 408.249453 -437.18401) (xy 408.263633 -437.164434) (xy 408.283157 -437.150182)
			(xy 408.306124 -437.142643) (xy 408.318208 -437.142128) (xy 409.258008 -437.142128) (xy 409.27012 -437.14251)
			(xy 409.293152 -437.150015) (xy 409.312728 -437.164284) (xy 409.326921 -437.183915) (xy 409.334337 -437.206976)
			(xy 409.334716 -437.21909) (xy 409.334716 -438.089802) (xy 410.23794 -438.089802) (xy 410.238057 -438.074717)
			(xy 410.239833 -438.044598) (xy 410.241496 -438.029604) (xy 410.241496 -436.950104) (xy 410.239826 -436.935111)
			(xy 410.238048 -436.904992) (xy 410.23794 -436.889906) (xy 410.23805 -436.87482) (xy 410.239832 -436.844702)
			(xy 410.241496 -436.829708) (xy 410.241496 -436.219092) (xy 410.241958 -436.207017) (xy 410.249423 -436.184049)
			(xy 410.26362 -436.164511) (xy 410.283159 -436.150317) (xy 410.306129 -436.142856) (xy 410.318204 -436.142384)
			(xy 411.258004 -436.142384) (xy 411.270078 -436.142861) (xy 411.293044 -436.150323) (xy 411.31258 -436.164517)
			(xy 411.326775 -436.184053) (xy 411.334239 -436.207018) (xy 411.334712 -436.219092) (xy 411.334712 -438.760616)
			(xy 411.334249 -438.772691) (xy 411.326783 -438.795658) (xy 411.312586 -438.815194) (xy 411.293047 -438.829388)
			(xy 411.270079 -438.836851) (xy 411.258004 -438.837324) (xy 410.318204 -438.837324) (xy 410.306131 -438.836833)
			(xy 410.283167 -438.829373) (xy 410.263631 -438.815183) (xy 410.249436 -438.795651) (xy 410.241971 -438.772689)
			(xy 410.241496 -438.760616) (xy 410.241496 -438.15) (xy 410.239825 -438.135007) (xy 410.238048 -438.104888)
			(xy 410.23794 -438.089802) (xy 409.334716 -438.089802) (xy 409.334716 -439.0898) (xy 412.237936 -439.0898)
			(xy 412.238053 -439.074715) (xy 412.239829 -439.044596) (xy 412.241492 -439.029602) (xy 412.241492 -437.950102)
			(xy 412.239821 -437.935109) (xy 412.238044 -437.90499) (xy 412.237936 -437.889904) (xy 412.238053 -437.874819)
			(xy 412.239829 -437.8447) (xy 412.241492 -437.829706) (xy 412.241492 -437.21909) (xy 412.241998 -437.207005)
			(xy 412.249452 -437.184012) (xy 412.26363 -437.164436) (xy 412.283152 -437.150184) (xy 412.306117 -437.142644)
			(xy 412.3182 -437.142128) (xy 413.258 -437.142128) (xy 413.270112 -437.142516) (xy 413.293144 -437.150019)
			(xy 413.312719 -437.164287) (xy 413.326913 -437.183916) (xy 413.334329 -437.206977) (xy 413.334708 -437.21909)
			(xy 413.334708 -439.760614) (xy 413.334206 -439.7727) (xy 413.326751 -439.795693) (xy 413.312572 -439.815268)
			(xy 413.293049 -439.82952) (xy 413.270084 -439.83706) (xy 413.258 -439.837576) (xy 412.3182 -439.837576)
			(xy 412.306089 -439.837184) (xy 412.283057 -439.829681) (xy 412.263482 -439.815414) (xy 412.249288 -439.795786)
			(xy 412.241872 -439.772727) (xy 412.241492 -439.760614) (xy 412.241492 -439.149998) (xy 412.239821 -439.135005)
			(xy 412.238044 -439.104886) (xy 412.237936 -439.0898) (xy 409.334716 -439.0898) (xy 409.334716 -439.760614)
			(xy 409.334304 -439.772709) (xy 409.326838 -439.795717) (xy 409.312639 -439.815301) (xy 409.293091 -439.829549)
			(xy 409.270101 -439.837073) (xy 409.258008 -439.837576) (xy 408.318208 -439.837576) (xy 408.306097 -439.837177)
			(xy 408.283066 -439.829677) (xy 408.263491 -439.815412) (xy 408.249296 -439.795785) (xy 408.24188 -439.772726)
			(xy 408.2415 -439.760614) (xy 408.2415 -439.149998) (xy 408.239829 -439.135005) (xy 408.238052 -439.104886)
			(xy 408.237944 -439.0898) (xy 405.334724 -439.0898) (xy 405.334724 -439.760614) (xy 405.334304 -439.772708)
			(xy 405.326839 -439.795715) (xy 405.312642 -439.815298) (xy 405.293096 -439.829547) (xy 405.270109 -439.837072)
			(xy 405.258016 -439.837576) (xy 404.318216 -439.837576) (xy 404.306106 -439.83717) (xy 404.283075 -439.829672)
			(xy 404.263499 -439.815408) (xy 404.249305 -439.795783) (xy 404.241888 -439.772726) (xy 404.241508 -439.760614)
			(xy 404.241508 -439.149998) (xy 404.239837 -439.135005) (xy 404.23806 -439.104886) (xy 404.237952 -439.0898)
			(xy 401.334732 -439.0898) (xy 401.334732 -439.760614) (xy 401.334304 -439.772707) (xy 401.32684 -439.795713)
			(xy 401.312645 -439.815295) (xy 401.293101 -439.829544) (xy 401.270116 -439.837071) (xy 401.258024 -439.837576)
			(xy 400.318224 -439.837576) (xy 400.306114 -439.837163) (xy 400.283083 -439.829667) (xy 400.263508 -439.815406)
			(xy 400.249313 -439.795781) (xy 400.241896 -439.772725) (xy 400.241516 -439.760614) (xy 400.241516 -439.149998)
			(xy 400.239845 -439.135005) (xy 400.238068 -439.104886) (xy 400.23796 -439.0898) (xy 396.334996 -439.0898)
			(xy 396.334996 -439.760614) (xy 396.334501 -439.772726) (xy 396.327014 -439.795764) (xy 396.312777 -439.815363)
			(xy 396.293182 -439.829605) (xy 396.270146 -439.837098) (xy 396.258034 -439.837576) (xy 395.318234 -439.837576)
			(xy 395.306114 -439.837111) (xy 395.283059 -439.82963) (xy 395.263445 -439.81539) (xy 395.249192 -439.795784)
			(xy 395.241696 -439.772733) (xy 395.241272 -439.760614) (xy 395.241272 -439.147966) (xy 395.239727 -439.133474)
			(xy 395.238075 -439.104374) (xy 395.23797 -439.0898) (xy 392.335004 -439.0898) (xy 392.335004 -439.760614)
			(xy 392.334501 -439.772725) (xy 392.327015 -439.795762) (xy 392.31278 -439.81536) (xy 392.293187 -439.829602)
			(xy 392.270153 -439.837097) (xy 392.258042 -439.837576) (xy 391.318242 -439.837576) (xy 391.306123 -439.837105)
			(xy 391.283068 -439.829626) (xy 391.263453 -439.815387) (xy 391.2492 -439.795783) (xy 391.241704 -439.772733)
			(xy 391.24128 -439.760614) (xy 391.24128 -439.147966) (xy 391.239735 -439.133474) (xy 391.238083 -439.104374)
			(xy 391.237978 -439.0898) (xy 388.335012 -439.0898) (xy 388.335012 -439.760614) (xy 388.334501 -439.772724)
			(xy 388.327016 -439.79576) (xy 388.312782 -439.815357) (xy 388.293192 -439.8296) (xy 388.27016 -439.837096)
			(xy 388.25805 -439.837576) (xy 387.31825 -439.837576) (xy 387.306134 -439.837131) (xy 387.283092 -439.829632)
			(xy 387.263492 -439.815382) (xy 387.249252 -439.795776) (xy 387.241763 -439.77273) (xy 387.241288 -439.760614)
			(xy 387.241288 -439.147966) (xy 387.239743 -439.133474) (xy 387.238091 -439.104374) (xy 387.237986 -439.0898)
			(xy 384.33502 -439.0898) (xy 384.33502 -439.760614) (xy 384.334651 -439.772742) (xy 384.32715 -439.795808)
			(xy 384.312886 -439.815426) (xy 384.293258 -439.829675) (xy 384.270186 -439.83716) (xy 384.258058 -439.837576)
			(xy 383.318258 -439.837576) (xy 383.306143 -439.837124) (xy 383.2831 -439.829627) (xy 383.263501 -439.815379)
			(xy 383.24926 -439.795774) (xy 383.241771 -439.77273) (xy 383.241296 -439.760614) (xy 383.241296 -439.147966)
			(xy 383.239751 -439.133474) (xy 383.238099 -439.104374) (xy 383.237994 -439.0898) (xy 375.249353 -439.0898)
			(xy 375.12219 -439.229109) (xy 374.978015 -439.375202) (xy 374.828262 -439.515571) (xy 374.673158 -439.650004)
			(xy 374.512939 -439.778297) (xy 374.347846 -439.900255) (xy 374.178131 -440.015694) (xy 374.00405 -440.124438)
			(xy 373.825868 -440.226324) (xy 373.735092 -440.274202) (xy 373.721975 -440.281619) (xy 373.700446 -440.302683)
			(xy 373.685993 -440.329108) (xy 373.679871 -440.358598) (xy 373.68261 -440.388592) (xy 373.693975 -440.416484)
			(xy 373.712976 -440.439853) (xy 373.737964 -440.456668) (xy 373.766769 -440.465468) (xy 373.781828 -440.465972)
			(xy 381.238252 -440.465972) (xy 381.244094 -440.42203) (xy 381.248823 -440.390461) (xy 381.265126 -440.328742)
			(xy 381.288996 -440.269538) (xy 381.320062 -440.213771) (xy 381.357839 -440.162313) (xy 381.401736 -440.115967)
			(xy 381.451069 -440.075455) (xy 381.505068 -440.04141) (xy 381.562891 -440.014364) (xy 381.623635 -439.994738)
			(xy 381.686351 -439.982838) (xy 381.750062 -439.978851) (xy 381.813773 -439.982838) (xy 381.876489 -439.994738)
			(xy 381.937233 -440.014364) (xy 381.995056 -440.04141) (xy 382.049055 -440.075455) (xy 382.098388 -440.115967)
			(xy 382.142285 -440.162313) (xy 382.180062 -440.213771) (xy 382.211128 -440.269538) (xy 382.234998 -440.328742)
			(xy 382.251301 -440.390461) (xy 382.25603 -440.42203) (xy 382.261872 -440.465972) (xy 385.238244 -440.465972)
			(xy 385.244086 -440.42203) (xy 385.248815 -440.390461) (xy 385.265118 -440.328742) (xy 385.288988 -440.269538)
			(xy 385.320054 -440.213771) (xy 385.357831 -440.162313) (xy 385.401728 -440.115967) (xy 385.451061 -440.075455)
			(xy 385.50506 -440.04141) (xy 385.562883 -440.014364) (xy 385.623627 -439.994738) (xy 385.686343 -439.982838)
			(xy 385.750054 -439.978851) (xy 385.813765 -439.982838) (xy 385.876481 -439.994738) (xy 385.937225 -440.014364)
			(xy 385.995048 -440.04141) (xy 386.049047 -440.075455) (xy 386.09838 -440.115967) (xy 386.142277 -440.162313)
			(xy 386.180054 -440.213771) (xy 386.21112 -440.269538) (xy 386.23499 -440.328742) (xy 386.251293 -440.390461)
			(xy 386.256022 -440.42203) (xy 386.261864 -440.465972) (xy 389.238236 -440.465972) (xy 389.244078 -440.42203)
			(xy 389.248807 -440.390461) (xy 389.26511 -440.328742) (xy 389.28898 -440.269538) (xy 389.320046 -440.213771)
			(xy 389.357823 -440.162313) (xy 389.40172 -440.115967) (xy 389.451053 -440.075455) (xy 389.505052 -440.04141)
			(xy 389.562875 -440.014364) (xy 389.623619 -439.994738) (xy 389.686335 -439.982838) (xy 389.750046 -439.978851)
			(xy 389.813757 -439.982838) (xy 389.876473 -439.994738) (xy 389.937217 -440.014364) (xy 389.99504 -440.04141)
			(xy 390.049039 -440.075455) (xy 390.098372 -440.115967) (xy 390.142269 -440.162313) (xy 390.180046 -440.213771)
			(xy 390.211112 -440.269538) (xy 390.234982 -440.328742) (xy 390.251285 -440.390461) (xy 390.256014 -440.42203)
			(xy 390.261856 -440.465972) (xy 393.238228 -440.465972) (xy 393.24407 -440.42203) (xy 393.248799 -440.390461)
			(xy 393.265102 -440.328742) (xy 393.288972 -440.269538) (xy 393.320038 -440.213771) (xy 393.357815 -440.162313)
			(xy 393.401712 -440.115967) (xy 393.451045 -440.075455) (xy 393.505044 -440.04141) (xy 393.562867 -440.014364)
			(xy 393.623611 -439.994738) (xy 393.686327 -439.982838) (xy 393.750038 -439.978851) (xy 393.813749 -439.982838)
			(xy 393.876465 -439.994738) (xy 393.937209 -440.014364) (xy 393.995032 -440.04141) (xy 394.049031 -440.075455)
			(xy 394.098364 -440.115967) (xy 394.142261 -440.162313) (xy 394.180038 -440.213771) (xy 394.211104 -440.269538)
			(xy 394.234974 -440.328742) (xy 394.251277 -440.390461) (xy 394.256006 -440.42203) (xy 394.261848 -440.465972)
			(xy 398.238218 -440.465972) (xy 398.24406 -440.42203) (xy 398.248789 -440.390461) (xy 398.265092 -440.328742)
			(xy 398.288962 -440.269538) (xy 398.320028 -440.213771) (xy 398.357805 -440.162313) (xy 398.401702 -440.115967)
			(xy 398.451035 -440.075455) (xy 398.505034 -440.04141) (xy 398.562857 -440.014364) (xy 398.623601 -439.994738)
			(xy 398.686317 -439.982838) (xy 398.750028 -439.978851) (xy 398.813739 -439.982838) (xy 398.876455 -439.994738)
			(xy 398.937199 -440.014364) (xy 398.995022 -440.04141) (xy 399.049021 -440.075455) (xy 399.098354 -440.115967)
			(xy 399.142251 -440.162313) (xy 399.180028 -440.213771) (xy 399.211094 -440.269538) (xy 399.234964 -440.328742)
			(xy 399.251267 -440.390461) (xy 399.255996 -440.42203) (xy 399.261838 -440.465972) (xy 402.23821 -440.465972)
			(xy 402.244052 -440.42203) (xy 402.248781 -440.390461) (xy 402.265084 -440.328742) (xy 402.288954 -440.269538)
			(xy 402.32002 -440.213771) (xy 402.357797 -440.162313) (xy 402.401694 -440.115967) (xy 402.451027 -440.075455)
			(xy 402.505026 -440.04141) (xy 402.562849 -440.014364) (xy 402.623593 -439.994738) (xy 402.686309 -439.982838)
			(xy 402.75002 -439.978851) (xy 402.813731 -439.982838) (xy 402.876447 -439.994738) (xy 402.937191 -440.014364)
			(xy 402.995014 -440.04141) (xy 403.049013 -440.075455) (xy 403.098346 -440.115967) (xy 403.142243 -440.162313)
			(xy 403.18002 -440.213771) (xy 403.211086 -440.269538) (xy 403.234956 -440.328742) (xy 403.251259 -440.390461)
			(xy 403.255988 -440.42203) (xy 403.26183 -440.465972) (xy 406.238202 -440.465972) (xy 406.244044 -440.42203)
			(xy 406.248773 -440.390461) (xy 406.265076 -440.328742) (xy 406.288946 -440.269538) (xy 406.320012 -440.213771)
			(xy 406.357789 -440.162313) (xy 406.401686 -440.115967) (xy 406.451019 -440.075455) (xy 406.505018 -440.04141)
			(xy 406.562841 -440.014364) (xy 406.623585 -439.994738) (xy 406.686301 -439.982838) (xy 406.750012 -439.978851)
			(xy 406.813723 -439.982838) (xy 406.876439 -439.994738) (xy 406.937183 -440.014364) (xy 406.995006 -440.04141)
			(xy 407.049005 -440.075455) (xy 407.098338 -440.115967) (xy 407.142235 -440.162313) (xy 407.180012 -440.213771)
			(xy 407.211078 -440.269538) (xy 407.234948 -440.328742) (xy 407.251251 -440.390461) (xy 407.25598 -440.42203)
			(xy 407.261822 -440.465972) (xy 410.238194 -440.465972) (xy 410.244036 -440.42203) (xy 410.248765 -440.390461)
			(xy 410.265068 -440.328742) (xy 410.288938 -440.269538) (xy 410.320004 -440.213771) (xy 410.357781 -440.162313)
			(xy 410.401678 -440.115967) (xy 410.451011 -440.075455) (xy 410.50501 -440.04141) (xy 410.562833 -440.014364)
			(xy 410.623577 -439.994738) (xy 410.686293 -439.982838) (xy 410.750004 -439.978851) (xy 410.813715 -439.982838)
			(xy 410.876431 -439.994738) (xy 410.937175 -440.014364) (xy 410.994998 -440.04141) (xy 411.048997 -440.075455)
			(xy 411.09833 -440.115967) (xy 411.142227 -440.162313) (xy 411.180004 -440.213771) (xy 411.21107 -440.269538)
			(xy 411.23494 -440.328742) (xy 411.251243 -440.390461) (xy 411.255972 -440.42203) (xy 411.261814 -440.465972)
			(xy 456.316588 -440.465972) (xy 456.331649 -440.465431) (xy 456.360462 -440.456649) (xy 456.385461 -440.439844)
			(xy 456.404472 -440.416479) (xy 456.415841 -440.388585) (xy 456.41858 -440.358587) (xy 456.41245 -440.329096)
			(xy 456.397986 -440.302674) (xy 456.376443 -440.28162) (xy 456.363324 -440.274202) (xy 456.272548 -440.226324)
			(xy 456.094369 -440.124435) (xy 455.920291 -440.015688) (xy 455.750579 -439.900247) (xy 455.585489 -439.778286)
			(xy 455.425272 -439.649992) (xy 455.27017 -439.515557) (xy 455.12042 -439.375187) (xy 454.976247 -439.229093)
			(xy 454.837871 -439.077498) (xy 454.705501 -438.920631) (xy 454.579338 -438.75873) (xy 454.459573 -438.59204)
			(xy 454.346388 -438.420815) (xy 454.239954 -438.245313) (xy 454.140433 -438.0658) (xy 454.047975 -437.88255)
			(xy 453.962722 -437.69584) (xy 453.884801 -437.505952) (xy 453.814331 -437.313175) (xy 453.751419 -437.1178)
			(xy 453.69616 -436.920125) (xy 453.648638 -436.720448) (xy 453.608926 -436.519073) (xy 453.577082 -436.316305)
			(xy 453.553157 -436.11245) (xy 453.537185 -435.907819) (xy 453.529191 -435.702721) (xy 453.528684 -435.600094)
			(xy 453.529186 -435.49659) (xy 453.537313 -435.289742) (xy 453.553555 -435.083372) (xy 453.577887 -434.877798)
			(xy 453.61027 -434.673339) (xy 453.650656 -434.470309) (xy 453.698982 -434.26902) (xy 453.755172 -434.069784)
			(xy 453.819142 -433.872908) (xy 453.890791 -433.678695) (xy 453.970011 -433.487445) (xy 454.056677 -433.299452)
			(xy 454.150657 -433.115007) (xy 454.251807 -432.934394) (xy 454.359969 -432.757891) (xy 454.474977 -432.58577)
			(xy 454.596654 -432.418298) (xy 454.724812 -432.255731) (xy 454.859254 -432.098322) (xy 454.999772 -431.946312)
			(xy 455.146149 -431.799936) (xy 455.298161 -431.659419) (xy 455.455572 -431.524979) (xy 455.618139 -431.396823)
			(xy 455.785613 -431.275147) (xy 455.957735 -431.160141) (xy 456.134239 -431.05198) (xy 456.314853 -430.950833)
			(xy 456.499299 -430.856854) (xy 456.687293 -430.77019) (xy 456.878544 -430.690973) (xy 457.072757 -430.619325)
			(xy 457.269634 -430.555357) (xy 457.468871 -430.499168) (xy 457.670159 -430.450845) (xy 457.87319 -430.410461)
			(xy 458.07765 -430.37808) (xy 458.283223 -430.35375) (xy 458.489593 -430.33751) (xy 458.696442 -430.329385)
			(xy 458.799946 -430.328832) (xy 458.903262 -430.329336) (xy 459.109734 -430.337432) (xy 459.315731 -430.353613)
			(xy 459.520936 -430.377856) (xy 459.725032 -430.410122) (xy 459.927707 -430.450362) (xy 460.12865 -430.498514)
			(xy 460.327551 -430.554505) (xy 460.524105 -430.618248) (xy 460.718009 -430.689644) (xy 460.908967 -430.768586)
			(xy 461.096684 -430.85495) (xy 461.280872 -430.948606) (xy 461.461248 -431.049407) (xy 461.637535 -431.157201)
			(xy 461.809462 -431.27182) (xy 461.976765 -431.39309) (xy 462.139187 -431.520823) (xy 462.296477 -431.654823)
			(xy 462.448396 -431.794885) (xy 462.594708 -431.940794) (xy 462.73519 -432.092324) (xy 462.869625 -432.249243)
			(xy 462.997807 -432.411311) (xy 463.119539 -432.578278) (xy 463.234633 -432.749887) (xy 463.342914 -432.925875)
			(xy 463.444214 -433.105972) (xy 463.538378 -433.2899) (xy 463.582258 -433.383436) (xy 463.588458 -433.395758)
			(xy 463.606302 -433.416779) (xy 463.629121 -433.432257) (xy 463.65525 -433.441065) (xy 463.682782 -433.44256)
			(xy 463.709711 -433.436633) (xy 463.734071 -433.423715) (xy 463.754087 -433.40475) (xy 463.768297 -433.381121)
			(xy 463.775666 -433.354551) (xy 463.77606 -433.340764) (xy 463.77606 -409.52801) (xy 463.77658 -409.441525)
			(xy 463.785062 -409.268764) (xy 463.802011 -409.096628) (xy 463.827387 -408.92553) (xy 463.861128 -408.755884)
			(xy 463.903153 -408.588097) (xy 463.953361 -408.422575) (xy 464.01163 -408.259716) (xy 464.07782 -408.099913)
			(xy 464.151773 -407.94355) (xy 464.233309 -407.791004) (xy 464.322232 -407.642643) (xy 464.418328 -407.498824)
			(xy 464.521366 -407.359894) (xy 464.631097 -407.226187) (xy 464.747256 -407.098026) (xy 464.808062 -407.036524)
			(xy 466.636608 -405.207978) (xy 466.658299 -405.185621) (xy 466.696247 -405.13622) (xy 466.72742 -405.082289)
			(xy 466.751285 -405.024748) (xy 466.767434 -404.964585) (xy 466.77559 -404.902828) (xy 466.776054 -404.871682)
			(xy 466.776054 -363.98835) (xy 466.775577 -363.974051) (xy 466.767657 -363.946572) (xy 466.752426 -363.922368)
			(xy 466.731078 -363.903339) (xy 466.705289 -363.890978) (xy 466.677084 -363.886257) (xy 466.648676 -363.889545)
			(xy 466.622295 -363.900584) (xy 466.600011 -363.918508) (xy 466.591396 -363.92993) (xy 466.530259 -364.016186)
			(xy 466.402259 -364.18449) (xy 466.267899 -364.347762) (xy 466.127377 -364.505761) (xy 465.980899 -364.658255)
			(xy 465.828681 -364.80502) (xy 465.670947 -364.94584) (xy 465.507928 -365.080507) (xy 465.339866 -365.208824)
			(xy 465.167006 -365.330602) (xy 464.989604 -365.445661) (xy 464.80792 -365.553833) (xy 464.622221 -365.654958)
			(xy 464.432781 -365.748887) (xy 464.239878 -365.835483) (xy 464.043796 -365.914617) (xy 463.844824 -365.986174)
			(xy 463.643255 -366.050049) (xy 463.439384 -366.106146) (xy 463.233512 -366.154384) (xy 463.025941 -366.194692)
			(xy 462.816977 -366.227011) (xy 462.606928 -366.251292) (xy 462.396102 -366.267501) (xy 462.18481 -366.275612)
			(xy 462.079086 -366.276128) (xy 462.078832 -366.276128) (xy 461.973234 -366.275629) (xy 461.762192 -366.267541)
			(xy 461.551616 -366.251375) (xy 461.341813 -366.227156) (xy 461.133091 -366.194918) (xy 460.925758 -366.154709)
			(xy 460.720117 -366.106588) (xy 460.516469 -366.050626) (xy 460.315115 -365.986905) (xy 460.11635 -365.915518)
			(xy 459.920464 -365.83657) (xy 459.727746 -365.750177) (xy 459.538479 -365.656465) (xy 459.35294 -365.555573)
			(xy 459.171402 -365.447649) (xy 458.99413 -365.33285) (xy 458.821386 -365.211345) (xy 458.653423 -365.083313)
			(xy 458.490487 -364.948942) (xy 458.332817 -364.808428) (xy 458.180645 -364.661978) (xy 458.034194 -364.509807)
			(xy 457.893679 -364.352138) (xy 457.759307 -364.189202) (xy 457.631274 -364.02124) (xy 457.509768 -363.848496)
			(xy 457.394968 -363.671226) (xy 457.287042 -363.489688) (xy 457.186149 -363.304149) (xy 457.092437 -363.114883)
			(xy 457.006043 -362.922165) (xy 456.927094 -362.72628) (xy 456.855706 -362.527515) (xy 456.791983 -362.326161)
			(xy 456.73602 -362.122514) (xy 456.687898 -361.916874) (xy 456.647688 -361.70954) (xy 456.615449 -361.500819)
			(xy 456.591228 -361.291016) (xy 456.575061 -361.08044) (xy 456.566971 -360.869398) (xy 456.566971 -360.658202)
			(xy 456.575061 -360.44716) (xy 456.591228 -360.236584) (xy 456.615449 -360.026781) (xy 456.647688 -359.81806)
			(xy 456.687898 -359.610726) (xy 456.73602 -359.405086) (xy 456.791983 -359.201439) (xy 456.855706 -359.000085)
			(xy 456.927094 -358.80132) (xy 457.006043 -358.605435) (xy 457.092437 -358.412717) (xy 457.186149 -358.223451)
			(xy 457.287042 -358.037912) (xy 457.394968 -357.856374) (xy 457.509768 -357.679104) (xy 457.631274 -357.50636)
			(xy 457.759307 -357.338398) (xy 457.893679 -357.175462) (xy 458.034194 -357.017793) (xy 458.180645 -356.865622)
			(xy 458.332817 -356.719172) (xy 458.490487 -356.578658) (xy 458.653423 -356.444287) (xy 458.821386 -356.316255)
			(xy 458.99413 -356.19475) (xy 459.171402 -356.079951) (xy 459.35294 -355.972027) (xy 459.538479 -355.871135)
			(xy 459.727746 -355.777423) (xy 459.920464 -355.69103) (xy 460.11635 -355.612082) (xy 460.315115 -355.540695)
			(xy 460.516469 -355.476974) (xy 460.720117 -355.421012) (xy 460.925758 -355.372891) (xy 461.133091 -355.332682)
			(xy 461.341813 -355.300444) (xy 461.551616 -355.276225) (xy 461.762192 -355.260059) (xy 461.973234 -355.251971)
			(xy 462.078832 -355.251512) (xy 462.079086 -355.251512) (xy 462.18481 -355.252014) (xy 462.396104 -355.260122)
			(xy 462.606931 -355.276328) (xy 462.816981 -355.300606) (xy 463.025946 -355.332922) (xy 463.233518 -355.373229)
			(xy 463.439391 -355.421465) (xy 463.643263 -355.477562) (xy 463.844834 -355.541436) (xy 464.043807 -355.612992)
			(xy 464.239889 -355.692127) (xy 464.432792 -355.778723) (xy 464.622233 -355.872653) (xy 464.807932 -355.97378)
			(xy 464.989616 -356.081953) (xy 465.167018 -356.197014) (xy 465.339878 -356.318794) (xy 465.507939 -356.447113)
			(xy 465.670956 -356.581783) (xy 465.828689 -356.722606) (xy 465.980905 -356.869374) (xy 466.127381 -357.021871)
			(xy 466.267901 -357.179874) (xy 466.402258 -357.343149) (xy 466.530254 -357.511457) (xy 466.591396 -357.59771)
			(xy 466.600021 -357.609122) (xy 466.622316 -357.627023) (xy 466.648698 -357.638046) (xy 466.677102 -357.641324)
			(xy 466.705302 -357.636603) (xy 466.731089 -357.624252) (xy 466.752443 -357.605238) (xy 466.767691 -357.581051)
			(xy 466.77564 -357.553586) (xy 466.776054 -357.53929) (xy 466.776054 -348.99346) (xy 466.775525 -348.978732)
			(xy 466.76705 -348.95052) (xy 466.750876 -348.9259) (xy 466.728347 -348.906921) (xy 466.701338 -348.895162)
			(xy 466.672096 -348.891601) (xy 466.643055 -348.896534) (xy 466.616629 -348.909551) (xy 466.595018 -348.929569)
			(xy 466.58002 -348.954923) (xy 466.575902 -348.969076) (xy 466.550644 -349.068848) (xy 466.493331 -349.266545)
			(xy 466.428343 -349.461854) (xy 466.35578 -349.654477) (xy 466.275752 -349.844119) (xy 466.188381 -350.030493)
			(xy 466.093801 -350.213314) (xy 465.992156 -350.392303) (xy 465.8836 -350.567188) (xy 465.768299 -350.737701)
			(xy 465.64643 -350.903583) (xy 465.518177 -351.06458) (xy 465.383737 -351.220448) (xy 465.243314 -351.370948)
			(xy 465.097123 -351.515851) (xy 464.945386 -351.654937) (xy 464.788334 -351.787992) (xy 464.626208 -351.914815)
			(xy 464.459255 -352.035212) (xy 464.287728 -352.148999) (xy 464.11189 -352.256003) (xy 463.932008 -352.35606)
			(xy 463.748357 -352.449018) (xy 463.561217 -352.534736) (xy 463.370874 -352.613083) (xy 463.177616 -352.683938)
			(xy 462.98174 -352.747195) (xy 462.783544 -352.802757) (xy 462.583329 -352.850538) (xy 462.381402 -352.890467)
			(xy 462.17807 -352.922482) (xy 461.973643 -352.946535) (xy 461.768433 -352.962588) (xy 461.562753 -352.970617)
			(xy 461.459834 -352.9711) (xy 461.357606 -352.970611) (xy 461.153305 -352.962685) (xy 460.949464 -352.946842)
			(xy 460.746391 -352.923108) (xy 460.544391 -352.891517) (xy 460.343768 -352.852117) (xy 460.144823 -352.804967)
			(xy 459.947857 -352.750139) (xy 459.753164 -352.687714) (xy 459.561039 -352.617788) (xy 459.371769 -352.540463)
			(xy 459.18564 -352.455859) (xy 459.002932 -352.3641) (xy 458.823919 -352.265326) (xy 458.64887 -352.159685)
			(xy 458.47805 -352.047335) (xy 458.311714 -351.928447) (xy 458.150114 -351.803198) (xy 457.993491 -351.671777)
			(xy 457.842083 -351.534382) (xy 457.696116 -351.391219) (xy 457.555809 -351.242504) (xy 457.421375 -351.088461)
			(xy 457.293015 -350.92932) (xy 457.170922 -350.765322) (xy 457.055281 -350.596713) (xy 456.946264 -350.423747)
			(xy 456.844036 -350.246684) (xy 456.74875 -350.065789) (xy 456.660551 -349.881337) (xy 456.57957 -349.693603)
			(xy 456.505929 -349.50287) (xy 456.43974 -349.309425) (xy 456.381101 -349.113559) (xy 456.330101 -348.915566)
			(xy 456.286817 -348.715745) (xy 456.251314 -348.514396) (xy 456.223644 -348.311821) (xy 456.203851 -348.108326)
			(xy 456.191963 -347.904217) (xy 456.187998 -347.6998) (xy 456.191963 -347.495383) (xy 456.203851 -347.291274)
			(xy 456.223644 -347.087779) (xy 456.251314 -346.885204) (xy 456.286817 -346.683855) (xy 456.330101 -346.484034)
			(xy 456.381101 -346.286041) (xy 456.43974 -346.090175) (xy 456.505929 -345.89673) (xy 456.57957 -345.705997)
			(xy 456.660551 -345.518263) (xy 456.74875 -345.333811) (xy 456.844036 -345.152916) (xy 456.946264 -344.975853)
			(xy 457.055281 -344.802887) (xy 457.170922 -344.634278) (xy 457.293015 -344.47028) (xy 457.421375 -344.311139)
			(xy 457.555809 -344.157096) (xy 457.696116 -344.008381) (xy 457.842083 -343.865218) (xy 457.993491 -343.727823)
			(xy 458.150114 -343.596402) (xy 458.311714 -343.471153) (xy 458.47805 -343.352265) (xy 458.64887 -343.239915)
			(xy 458.823919 -343.134274) (xy 459.002932 -343.0355) (xy 459.18564 -342.943741) (xy 459.371769 -342.859137)
			(xy 459.561039 -342.781812) (xy 459.753164 -342.711886) (xy 459.947857 -342.649461) (xy 460.144823 -342.594633)
			(xy 460.343768 -342.547483) (xy 460.544391 -342.508083) (xy 460.746391 -342.476492) (xy 460.949464 -342.452758)
			(xy 461.153305 -342.436915) (xy 461.357606 -342.428989) (xy 461.459834 -342.428576) (xy 461.562752 -342.429073)
			(xy 461.76843 -342.43711) (xy 461.973639 -342.45317) (xy 462.178063 -342.477228) (xy 462.381393 -342.509249)
			(xy 462.583318 -342.549182) (xy 462.78353 -342.596968) (xy 462.981724 -342.652533) (xy 463.177597 -342.715792)
			(xy 463.370852 -342.78665) (xy 463.561194 -342.864999) (xy 463.748331 -342.950718) (xy 463.93198 -343.043677)
			(xy 464.11186 -343.143734) (xy 464.287697 -343.250737) (xy 464.459223 -343.364523) (xy 464.626175 -343.484919)
			(xy 464.788301 -343.61174) (xy 464.945353 -343.744793) (xy 465.09709 -343.883876) (xy 465.243282 -344.028776)
			(xy 465.383707 -344.179273) (xy 465.518149 -344.335136) (xy 465.646404 -344.49613) (xy 465.768277 -344.662007)
			(xy 465.883581 -344.832516) (xy 465.992141 -345.007396) (xy 466.093792 -345.186381) (xy 466.188378 -345.369197)
			(xy 466.275755 -345.555566) (xy 466.35579 -345.745205) (xy 466.428361 -345.937823) (xy 466.493357 -346.133127)
			(xy 466.550679 -346.33082) (xy 466.575902 -346.4306) (xy 466.57995 -346.444783) (xy 466.594956 -346.47016)
			(xy 466.616582 -346.490197) (xy 466.643028 -346.503228) (xy 466.672093 -346.508166) (xy 466.701358 -346.504602)
			(xy 466.728388 -346.492832) (xy 466.750934 -346.473835) (xy 466.767118 -346.449193) (xy 466.775594 -346.420956)
			(xy 466.776054 -346.406216) (xy 466.776054 -161.793682) (xy 466.775528 -161.778952) (xy 466.767057 -161.750734)
			(xy 466.750883 -161.726108) (xy 466.728353 -161.707125) (xy 466.70134 -161.695362) (xy 466.672094 -161.691801)
			(xy 466.643049 -161.696736) (xy 466.61662 -161.709757) (xy 466.595009 -161.729781) (xy 466.580013 -161.755141)
			(xy 466.575902 -161.769298) (xy 466.550633 -161.869063) (xy 466.4933 -162.066744) (xy 466.428294 -162.262037)
			(xy 466.355714 -162.454644) (xy 466.275671 -162.644271) (xy 466.188287 -162.830628) (xy 466.093695 -163.013433)
			(xy 465.992039 -163.192405) (xy 465.883474 -163.367273) (xy 465.768167 -163.537771) (xy 465.646291 -163.703637)
			(xy 465.518034 -163.864619) (xy 465.383591 -164.020472) (xy 465.243167 -164.170958) (xy 465.096975 -164.315848)
			(xy 464.945239 -164.454921) (xy 464.78819 -164.587965) (xy 464.626067 -164.714777) (xy 464.459118 -164.835164)
			(xy 464.287596 -164.948943) (xy 464.111764 -165.055939) (xy 463.931889 -165.15599) (xy 463.748246 -165.248943)
			(xy 463.561115 -165.334657) (xy 463.37078 -165.413001) (xy 463.177532 -165.483856) (xy 462.981666 -165.547113)
			(xy 462.783479 -165.602676) (xy 462.583275 -165.650461) (xy 462.381358 -165.690394) (xy 462.178036 -165.722415)
			(xy 461.973619 -165.746475) (xy 461.768419 -165.762537) (xy 461.562748 -165.770577) (xy 461.459834 -165.771068)
			(xy 461.357613 -165.770579) (xy 461.153324 -165.762653) (xy 460.949496 -165.746812) (xy 460.746436 -165.723079)
			(xy 460.544449 -165.69149) (xy 460.343838 -165.652092) (xy 460.144906 -165.604946) (xy 459.947952 -165.550121)
			(xy 459.753272 -165.4877) (xy 459.561158 -165.417778) (xy 459.371901 -165.340459) (xy 459.185783 -165.255859)
			(xy 459.003086 -165.164106) (xy 458.824085 -165.065338) (xy 458.649047 -164.959704) (xy 458.478238 -164.847361)
			(xy 458.311913 -164.72848) (xy 458.150322 -164.603239) (xy 457.99371 -164.471827) (xy 457.842311 -164.33444)
			(xy 457.696353 -164.191287) (xy 457.556055 -164.042581) (xy 457.421629 -163.888547) (xy 457.293277 -163.729417)
			(xy 457.171192 -163.565429) (xy 457.055558 -163.396831) (xy 456.946548 -163.223875) (xy 456.844326 -163.046823)
			(xy 456.749047 -162.86594) (xy 456.660853 -162.681499) (xy 456.579877 -162.493777) (xy 456.506241 -162.303056)
			(xy 456.440056 -162.109623) (xy 456.381421 -161.91377) (xy 456.330424 -161.71579) (xy 456.287143 -161.515981)
			(xy 456.251642 -161.314644) (xy 456.223974 -161.112083) (xy 456.204182 -160.908601) (xy 456.192294 -160.704504)
			(xy 456.18833 -160.5001) (xy 456.192294 -160.295696) (xy 456.204182 -160.091599) (xy 456.223974 -159.888117)
			(xy 456.251642 -159.685556) (xy 456.287143 -159.484219) (xy 456.330424 -159.28441) (xy 456.381421 -159.08643)
			(xy 456.440056 -158.890577) (xy 456.506241 -158.697144) (xy 456.579877 -158.506423) (xy 456.660853 -158.318701)
			(xy 456.749047 -158.13426) (xy 456.844326 -157.953377) (xy 456.946548 -157.776325) (xy 457.055558 -157.603369)
			(xy 457.171192 -157.434771) (xy 457.293277 -157.270783) (xy 457.421629 -157.111653) (xy 457.556055 -156.957619)
			(xy 457.696353 -156.808913) (xy 457.842311 -156.66576) (xy 457.99371 -156.528373) (xy 458.150322 -156.396961)
			(xy 458.311913 -156.27172) (xy 458.478238 -156.152839) (xy 458.649047 -156.040496) (xy 458.824085 -155.934862)
			(xy 459.003086 -155.836094) (xy 459.185783 -155.744341) (xy 459.371901 -155.659741) (xy 459.561158 -155.582422)
			(xy 459.753272 -155.5125) (xy 459.947952 -155.450079) (xy 460.144906 -155.395254) (xy 460.343838 -155.348108)
			(xy 460.544449 -155.30871) (xy 460.746436 -155.277121) (xy 460.949496 -155.253388) (xy 461.153324 -155.237547)
			(xy 461.357613 -155.229621) (xy 461.459834 -155.229052) (xy 461.562749 -155.229547) (xy 461.768422 -155.23758)
			(xy 461.973625 -155.253635) (xy 462.178044 -155.277689) (xy 462.381369 -155.309704) (xy 462.583289 -155.349632)
			(xy 462.783496 -155.397411) (xy 462.981685 -155.45297) (xy 463.177555 -155.516224) (xy 463.370806 -155.587075)
			(xy 463.561144 -155.665417) (xy 463.748279 -155.751129) (xy 463.931925 -155.84408) (xy 464.111802 -155.94413)
			(xy 464.287637 -156.051126) (xy 464.459161 -156.164904) (xy 464.626112 -156.285291) (xy 464.788237 -156.412104)
			(xy 464.945288 -156.545149) (xy 465.097025 -156.684223) (xy 465.243218 -156.829115) (xy 465.383643 -156.979603)
			(xy 465.518086 -157.135459) (xy 465.646343 -157.296443) (xy 465.768217 -157.462312) (xy 465.883524 -157.632812)
			(xy 465.992086 -157.807684) (xy 466.09374 -157.98666) (xy 466.188329 -158.169468) (xy 466.27571 -158.355829)
			(xy 466.35575 -158.545459) (xy 466.428326 -158.738069) (xy 466.493327 -158.933366) (xy 466.550655 -159.131051)
			(xy 466.575902 -159.230822) (xy 466.579953 -159.245003) (xy 466.594961 -159.270375) (xy 466.616587 -159.290408)
			(xy 466.643032 -159.303435) (xy 466.672094 -159.308372) (xy 466.701357 -159.304808) (xy 466.728385 -159.29304)
			(xy 466.75093 -159.274047) (xy 466.767116 -159.249409) (xy 466.775597 -159.221176) (xy 466.776054 -159.206438)
			(xy 466.776054 -116.991384) (xy 466.740748 -116.979954) (xy 466.713936 -116.970846) (xy 466.663138 -116.945827)
			(xy 466.616598 -116.913571) (xy 466.57534 -116.874789) (xy 466.54027 -116.830331) (xy 466.51216 -116.781177)
			(xy 466.491627 -116.728406) (xy 466.479123 -116.673179) (xy 466.474924 -116.61671) (xy 466.47912 -116.560241)
			(xy 466.491621 -116.505014) (xy 466.512151 -116.452242) (xy 466.540259 -116.403086) (xy 466.575326 -116.358627)
			(xy 466.616582 -116.319842) (xy 466.66312 -116.287584) (xy 466.713917 -116.262562) (xy 466.740748 -116.253514)
			(xy 466.776054 -116.242084) (xy 466.776054 -115.636294) (xy 466.751251 -115.623187) (xy 466.705446 -115.590802)
			(xy 466.664877 -115.552057) (xy 466.63042 -115.50779) (xy 466.602816 -115.458953) (xy 466.582663 -115.406601)
			(xy 466.570393 -115.351861) (xy 466.566272 -115.295915) (xy 466.570389 -115.239969) (xy 466.582654 -115.185229)
			(xy 466.602803 -115.132875) (xy 466.630402 -115.084036) (xy 466.664856 -115.039765) (xy 466.705422 -115.001018)
			(xy 466.751225 -114.968629) (xy 466.776054 -114.955574) (xy 466.776054 -82.827876) (xy 466.776575 -82.741392)
			(xy 466.785059 -82.568632) (xy 466.80201 -82.396497) (xy 466.827388 -82.2254) (xy 466.861131 -82.055755)
			(xy 466.903158 -81.887971) (xy 466.953368 -81.722451) (xy 467.011639 -81.559594) (xy 467.077832 -81.399792)
			(xy 467.151787 -81.243432) (xy 467.233326 -81.090888) (xy 467.322251 -80.94253) (xy 467.41835 -80.798714)
			(xy 467.52139 -80.659787) (xy 467.631124 -80.526084) (xy 467.747286 -80.397927) (xy 467.808056 -80.33639)
			(xy 470.136474 -78.007972) (xy 470.158166 -77.985616) (xy 470.196116 -77.936216) (xy 470.22729 -77.882284)
			(xy 470.251157 -77.824744) (xy 470.267306 -77.76458) (xy 470.275462 -77.702823) (xy 470.27592 -77.671676)
			(xy 470.27592 -13.780008) (xy 470.275411 -13.748842) (xy 470.267276 -13.687043) (xy 470.251145 -13.626835)
			(xy 470.227293 -13.569247) (xy 470.196128 -13.515265) (xy 470.158185 -13.465813) (xy 470.114111 -13.421736)
			(xy 470.064661 -13.383789) (xy 470.010681 -13.352621) (xy 469.953095 -13.328766) (xy 469.892888 -13.31263)
			(xy 469.83109 -13.304491) (xy 469.799924 -13.304012) (xy 458.20203 -13.304012) (xy 458.118154 -13.303522)
			(xy 457.950593 -13.295541) (xy 457.783601 -13.279597) (xy 457.617557 -13.255724) (xy 457.452837 -13.223979)
			(xy 457.289814 -13.184431) (xy 457.128858 -13.137171) (xy 456.970332 -13.082306) (xy 456.814597 -13.019961)
			(xy 456.662004 -12.950276) (xy 456.5129 -12.873409) (xy 456.367623 -12.789534) (xy 456.226501 -12.698842)
			(xy 456.089854 -12.601537) (xy 455.957992 -12.497841) (xy 455.831213 -12.387988) (xy 455.709805 -12.272228)
			(xy 455.594043 -12.150821) (xy 455.484188 -12.024044) (xy 455.38049 -11.892183) (xy 455.283184 -11.755537)
			(xy 455.19249 -11.614417) (xy 455.108614 -11.46914) (xy 455.031745 -11.320037) (xy 454.962057 -11.167446)
			(xy 454.89971 -11.011711) (xy 454.844843 -10.853186) (xy 454.797581 -10.69223) (xy 454.758031 -10.529208)
			(xy 454.726283 -10.364488) (xy 454.702409 -10.198445) (xy 454.686462 -10.031453) (xy 454.67848 -9.863892)
			(xy 454.678034 -9.780016) (xy 454.678034 -7.056374) (xy 454.677578 -7.042621) (xy 454.670229 -7.016114)
			(xy 454.656071 -6.99253) (xy 454.636133 -6.973582) (xy 454.611859 -6.960642) (xy 454.585013 -6.954652)
			(xy 454.557541 -6.956045) (xy 454.531438 -6.964719) (xy 454.519792 -6.972046) (xy 454.482612 -6.996373)
			(xy 454.404581 -7.03888) (xy 454.322975 -7.074041) (xy 454.238485 -7.101556) (xy 454.151825 -7.121195)
			(xy 454.063727 -7.132791) (xy 453.974936 -7.136245) (xy 453.886204 -7.13153) (xy 453.79828 -7.118684)
			(xy 453.711907 -7.097816) (xy 453.627816 -7.069103) (xy 453.546718 -7.032787) (xy 453.469299 -6.989176)
			(xy 453.396213 -6.938638) (xy 453.328077 -6.8816) (xy 453.265469 -6.818545) (xy 453.208918 -6.750006)
			(xy 453.1589 -6.676563) (xy 453.115841 -6.598835) (xy 453.080103 -6.517481) (xy 453.051988 -6.433188)
			(xy 453.031735 -6.346669) (xy 453.019515 -6.258656) (xy 453.01543 -6.169892) (xy 453.019516 -6.081128)
			(xy 453.031738 -5.993115) (xy 453.051992 -5.906597) (xy 453.080108 -5.822304) (xy 453.115848 -5.740951)
			(xy 453.158909 -5.663224) (xy 453.208927 -5.589781) (xy 453.26548 -5.521243) (xy 453.328089 -5.458189)
			(xy 453.396225 -5.401153) (xy 453.469312 -5.350616) (xy 453.546732 -5.307006) (xy 453.627831 -5.270691)
			(xy 453.711922 -5.24198) (xy 453.798295 -5.221113) (xy 453.886219 -5.208269) (xy 453.974952 -5.203554)
			(xy 454.063742 -5.207011) (xy 454.15184 -5.218608) (xy 454.2385 -5.238248) (xy 454.32299 -5.265765)
			(xy 454.404595 -5.300926) (xy 454.482625 -5.343435) (xy 454.519792 -5.367782) (xy 454.53146 -5.375065)
			(xy 454.557553 -5.383734) (xy 454.585013 -5.385124) (xy 454.611848 -5.379137) (xy 454.636112 -5.366204)
			(xy 454.656044 -5.347266) (xy 454.6702 -5.323695) (xy 454.677551 -5.297201) (xy 454.678034 -5.283454)
			(xy 454.678034 -1.524) (xy 389.125968 -1.524) (xy 389.125968 -4.280154) (xy 389.126411 -4.293871)
			(xy 389.133709 -4.320316) (xy 389.147791 -4.343859) (xy 389.167638 -4.362798) (xy 389.191814 -4.375764)
			(xy 389.218571 -4.381818) (xy 389.245974 -4.380523) (xy 389.272041 -4.371972) (xy 389.283702 -4.364736)
			(xy 389.320918 -4.340694) (xy 389.398968 -4.298748) (xy 389.480532 -4.264128) (xy 389.564925 -4.237125)
			(xy 389.651436 -4.217966) (xy 389.739338 -4.206812) (xy 389.827893 -4.203757) (xy 389.916355 -4.208826)
			(xy 390.003981 -4.221977) (xy 390.090034 -4.243099) (xy 390.17379 -4.272015) (xy 390.254546 -4.308482)
			(xy 390.331621 -4.352193) (xy 390.404369 -4.40278) (xy 390.472177 -4.459818) (xy 390.534475 -4.522827)
			(xy 390.59074 -4.591278) (xy 390.640498 -4.664595) (xy 390.683331 -4.742162) (xy 390.718878 -4.823326)
			(xy 390.746842 -4.907405) (xy 390.763549 -4.978969) (xy 394.947631 -4.978969) (xy 394.947631 -4.924431)
			(xy 394.955393 -4.870448) (xy 394.970758 -4.81812) (xy 394.993414 -4.76851) (xy 395.0229 -4.72263)
			(xy 395.058614 -4.681413) (xy 395.099832 -4.645698) (xy 395.145712 -4.616213) (xy 395.195321 -4.593557)
			(xy 395.24765 -4.578193) (xy 395.301633 -4.570431) (xy 395.328902 -4.569968) (xy 396.192502 -4.569968)
			(xy 396.219773 -4.570395) (xy 396.273761 -4.578157) (xy 396.326094 -4.593524) (xy 396.375708 -4.616182)
			(xy 396.421593 -4.64567) (xy 396.462813 -4.681388) (xy 396.498531 -4.722609) (xy 396.528019 -4.768493)
			(xy 396.550677 -4.818107) (xy 396.566043 -4.870441) (xy 396.573806 -4.924429) (xy 396.573806 -4.978971)
			(xy 398.547532 -4.978971) (xy 398.547532 -4.924429) (xy 398.555294 -4.870443) (xy 398.570661 -4.818111)
			(xy 398.593321 -4.768498) (xy 398.62281 -4.722616) (xy 398.658529 -4.681398) (xy 398.699751 -4.645684)
			(xy 398.745637 -4.616199) (xy 398.795252 -4.593546) (xy 398.847586 -4.578185) (xy 398.901573 -4.570428)
			(xy 398.928844 -4.569968) (xy 399.792444 -4.569968) (xy 399.819713 -4.570398) (xy 399.873697 -4.578165)
			(xy 399.926025 -4.593535) (xy 399.975633 -4.616196) (xy 400.021512 -4.645685) (xy 400.062728 -4.681403)
			(xy 400.098441 -4.722623) (xy 400.127925 -4.768505) (xy 400.15058 -4.818116) (xy 400.165944 -4.870447)
			(xy 400.173706 -4.92443) (xy 400.173706 -4.978967) (xy 402.147554 -4.978967) (xy 402.147554 -4.924433)
			(xy 402.155315 -4.870455) (xy 402.170678 -4.818131) (xy 402.193332 -4.768526) (xy 402.222814 -4.722649)
			(xy 402.258525 -4.681435) (xy 402.299738 -4.645722) (xy 402.345613 -4.616239) (xy 402.395218 -4.593583)
			(xy 402.447542 -4.578218) (xy 402.501519 -4.570455) (xy 402.528786 -4.569968) (xy 403.392386 -4.569968)
			(xy 403.41966 -4.570371) (xy 403.473652 -4.578132) (xy 403.525991 -4.593498) (xy 403.57561 -4.616157)
			(xy 403.621499 -4.645646) (xy 403.662724 -4.681366) (xy 403.698445 -4.72259) (xy 403.727937 -4.768478)
			(xy 403.750597 -4.818096) (xy 403.765965 -4.870434) (xy 403.773728 -4.924426) (xy 403.773728 -4.978966)
			(xy 405.747754 -4.978966) (xy 405.747754 -4.924434) (xy 405.755515 -4.870456) (xy 405.770878 -4.818132)
			(xy 405.793531 -4.768527) (xy 405.823013 -4.72265) (xy 405.858724 -4.681436) (xy 405.899936 -4.645724)
			(xy 405.945811 -4.61624) (xy 405.995415 -4.593584) (xy 406.047738 -4.578219) (xy 406.101716 -4.570456)
			(xy 406.128982 -4.569968) (xy 406.992582 -4.569968) (xy 407.019856 -4.57037) (xy 407.073849 -4.578131)
			(xy 407.126188 -4.593497) (xy 407.175807 -4.616155) (xy 407.221697 -4.645645) (xy 407.262922 -4.681365)
			(xy 407.298644 -4.722589) (xy 407.328136 -4.768477) (xy 407.350797 -4.818095) (xy 407.366165 -4.870433)
			(xy 407.373928 -4.924426) (xy 407.373928 -4.978971) (xy 414.857632 -4.978971) (xy 414.857632 -4.924429)
			(xy 414.865394 -4.870442) (xy 414.880762 -4.81811) (xy 414.903421 -4.768498) (xy 414.93291 -4.722616)
			(xy 414.96863 -4.681397) (xy 415.009852 -4.645683) (xy 415.055738 -4.616199) (xy 415.105353 -4.593546)
			(xy 415.157687 -4.578184) (xy 415.211675 -4.570428) (xy 415.238946 -4.569968) (xy 416.102546 -4.569968)
			(xy 416.129815 -4.570398) (xy 416.183798 -4.578165) (xy 416.236126 -4.593536) (xy 416.285735 -4.616196)
			(xy 416.331613 -4.645686) (xy 416.372829 -4.681404) (xy 416.408542 -4.722624) (xy 416.438026 -4.768506)
			(xy 416.46068 -4.818117) (xy 416.476045 -4.870447) (xy 416.483806 -4.924431) (xy 416.483806 -4.978967)
			(xy 418.457654 -4.978967) (xy 418.457654 -4.924433) (xy 418.465415 -4.870455) (xy 418.480779 -4.818131)
			(xy 418.503432 -4.768525) (xy 418.532915 -4.722648) (xy 418.568626 -4.681434) (xy 418.609839 -4.645722)
			(xy 418.655715 -4.616238) (xy 418.705319 -4.593583) (xy 418.757643 -4.578218) (xy 418.811621 -4.570455)
			(xy 418.838888 -4.569968) (xy 419.702488 -4.569968) (xy 419.729762 -4.570371) (xy 419.783754 -4.578132)
			(xy 419.836092 -4.593499) (xy 419.885711 -4.616157) (xy 419.9316 -4.645647) (xy 419.972824 -4.681367)
			(xy 420.008546 -4.722591) (xy 420.038037 -4.768479) (xy 420.060697 -4.818096) (xy 420.076065 -4.870434)
			(xy 420.083828 -4.924426) (xy 420.083828 -4.978966) (xy 426.067754 -4.978966) (xy 426.067754 -4.924434)
			(xy 426.075515 -4.870456) (xy 426.090878 -4.818132) (xy 426.113531 -4.768527) (xy 426.143013 -4.72265)
			(xy 426.178724 -4.681436) (xy 426.219936 -4.645724) (xy 426.265811 -4.61624) (xy 426.315415 -4.593584)
			(xy 426.367738 -4.578219) (xy 426.421716 -4.570456) (xy 426.448982 -4.569968) (xy 427.312582 -4.569968)
			(xy 427.339856 -4.57037) (xy 427.393849 -4.578131) (xy 427.446188 -4.593497) (xy 427.495807 -4.616155)
			(xy 427.541697 -4.645645) (xy 427.582922 -4.681365) (xy 427.618644 -4.722589) (xy 427.648136 -4.768477)
			(xy 427.670797 -4.818095) (xy 427.686165 -4.870433) (xy 427.693928 -4.924426) (xy 427.693928 -4.97897)
			(xy 429.667631 -4.97897) (xy 429.667631 -4.92443) (xy 429.675394 -4.870445) (xy 429.69076 -4.818115)
			(xy 429.713417 -4.768504) (xy 429.742905 -4.722623) (xy 429.778622 -4.681405) (xy 429.819842 -4.645691)
			(xy 429.865725 -4.616206) (xy 429.915337 -4.593552) (xy 429.967669 -4.578189) (xy 430.021654 -4.57043)
			(xy 430.048924 -4.569968) (xy 430.912524 -4.569968) (xy 430.939794 -4.570396) (xy 430.99378 -4.578161)
			(xy 431.04611 -4.59353) (xy 431.095721 -4.616189) (xy 431.141603 -4.645678) (xy 431.182821 -4.681396)
			(xy 431.218536 -4.722616) (xy 431.248022 -4.7685) (xy 431.270679 -4.818112) (xy 431.286044 -4.870444)
			(xy 431.293806 -4.92443) (xy 431.293806 -4.97897) (xy 431.286044 -5.032956) (xy 431.270679 -5.085288)
			(xy 431.248022 -5.1349) (xy 431.218536 -5.180784) (xy 431.182821 -5.222004) (xy 431.141603 -5.257722)
			(xy 431.095721 -5.287211) (xy 431.04611 -5.30987) (xy 430.99378 -5.325239) (xy 430.939794 -5.333004)
			(xy 430.912524 -5.333492) (xy 430.048924 -5.333492) (xy 430.021654 -5.33297) (xy 429.967669 -5.325211)
			(xy 429.915337 -5.309848) (xy 429.865725 -5.287194) (xy 429.819842 -5.257709) (xy 429.778622 -5.221995)
			(xy 429.742905 -5.180777) (xy 429.713417 -5.134896) (xy 429.69076 -5.085285) (xy 429.675394 -5.032955)
			(xy 429.667631 -4.97897) (xy 427.693928 -4.97897) (xy 427.693928 -4.978974) (xy 427.686165 -5.032967)
			(xy 427.670797 -5.085305) (xy 427.648136 -5.134923) (xy 427.618644 -5.180811) (xy 427.582922 -5.222035)
			(xy 427.541697 -5.257755) (xy 427.495807 -5.287245) (xy 427.446188 -5.309903) (xy 427.393849 -5.325269)
			(xy 427.339856 -5.33303) (xy 427.312582 -5.333492) (xy 426.448982 -5.333492) (xy 426.421716 -5.332944)
			(xy 426.367738 -5.325181) (xy 426.315415 -5.309816) (xy 426.265811 -5.28716) (xy 426.219936 -5.257676)
			(xy 426.178724 -5.221964) (xy 426.143013 -5.18075) (xy 426.113531 -5.134873) (xy 426.090878 -5.085268)
			(xy 426.075515 -5.032944) (xy 426.067754 -4.978966) (xy 420.083828 -4.978966) (xy 420.083828 -4.978974)
			(xy 420.076065 -5.032966) (xy 420.060697 -5.085304) (xy 420.038037 -5.134921) (xy 420.008546 -5.180809)
			(xy 419.972824 -5.222033) (xy 419.9316 -5.257753) (xy 419.885711 -5.287243) (xy 419.836092 -5.309901)
			(xy 419.783754 -5.325268) (xy 419.729762 -5.333029) (xy 419.702488 -5.333492) (xy 418.838888 -5.333492)
			(xy 418.811621 -5.332945) (xy 418.757643 -5.325182) (xy 418.705319 -5.309817) (xy 418.655715 -5.287162)
			(xy 418.609839 -5.257678) (xy 418.568626 -5.221966) (xy 418.532915 -5.180752) (xy 418.503432 -5.134875)
			(xy 418.480779 -5.085269) (xy 418.465415 -5.032945) (xy 418.457654 -4.978967) (xy 416.483806 -4.978967)
			(xy 416.483806 -4.978969) (xy 416.476045 -5.032953) (xy 416.46068 -5.085283) (xy 416.438026 -5.134894)
			(xy 416.408542 -5.180776) (xy 416.372829 -5.221996) (xy 416.331613 -5.257714) (xy 416.285735 -5.287204)
			(xy 416.236126 -5.309864) (xy 416.183798 -5.325235) (xy 416.129815 -5.333002) (xy 416.102546 -5.333492)
			(xy 415.238946 -5.333492) (xy 415.211675 -5.332972) (xy 415.157687 -5.325216) (xy 415.105353 -5.309854)
			(xy 415.055738 -5.287201) (xy 415.009852 -5.257717) (xy 414.96863 -5.222003) (xy 414.93291 -5.180784)
			(xy 414.903421 -5.134902) (xy 414.880762 -5.08529) (xy 414.865394 -5.032958) (xy 414.857632 -4.978971)
			(xy 407.373928 -4.978971) (xy 407.373928 -4.978974) (xy 407.366165 -5.032967) (xy 407.350797 -5.085305)
			(xy 407.328136 -5.134923) (xy 407.298644 -5.180811) (xy 407.262922 -5.222035) (xy 407.221697 -5.257755)
			(xy 407.175807 -5.287245) (xy 407.126188 -5.309903) (xy 407.073849 -5.325269) (xy 407.019856 -5.33303)
			(xy 406.992582 -5.333492) (xy 406.128982 -5.333492) (xy 406.101716 -5.332944) (xy 406.047738 -5.325181)
			(xy 405.995415 -5.309816) (xy 405.945811 -5.28716) (xy 405.899936 -5.257676) (xy 405.858724 -5.221964)
			(xy 405.823013 -5.18075) (xy 405.793531 -5.134873) (xy 405.770878 -5.085268) (xy 405.755515 -5.032944)
			(xy 405.747754 -4.978966) (xy 403.773728 -4.978966) (xy 403.773728 -4.978974) (xy 403.765965 -5.032966)
			(xy 403.750597 -5.085304) (xy 403.727937 -5.134922) (xy 403.698445 -5.18081) (xy 403.662724 -5.222034)
			(xy 403.621499 -5.257754) (xy 403.57561 -5.287243) (xy 403.525991 -5.309902) (xy 403.473652 -5.325268)
			(xy 403.41966 -5.333029) (xy 403.392386 -5.333492) (xy 402.528786 -5.333492) (xy 402.501519 -5.332945)
			(xy 402.447542 -5.325182) (xy 402.395218 -5.309817) (xy 402.345613 -5.287161) (xy 402.299738 -5.257678)
			(xy 402.258525 -5.221965) (xy 402.222814 -5.180751) (xy 402.193332 -5.134874) (xy 402.170678 -5.085269)
			(xy 402.155315 -5.032945) (xy 402.147554 -4.978967) (xy 400.173706 -4.978967) (xy 400.173706 -4.97897)
			(xy 400.165944 -5.032953) (xy 400.15058 -5.085284) (xy 400.127925 -5.134895) (xy 400.098441 -5.180777)
			(xy 400.062728 -5.221997) (xy 400.021512 -5.257715) (xy 399.975633 -5.287204) (xy 399.926025 -5.309865)
			(xy 399.873697 -5.325235) (xy 399.819713 -5.333002) (xy 399.792444 -5.333492) (xy 398.928844 -5.333492)
			(xy 398.901573 -5.332972) (xy 398.847586 -5.325215) (xy 398.795252 -5.309854) (xy 398.745637 -5.287201)
			(xy 398.699751 -5.257716) (xy 398.658529 -5.222002) (xy 398.62281 -5.180784) (xy 398.593321 -5.134902)
			(xy 398.570661 -5.085289) (xy 398.555294 -5.032957) (xy 398.547532 -4.978971) (xy 396.573806 -4.978971)
			(xy 396.566043 -5.032959) (xy 396.550677 -5.085293) (xy 396.528019 -5.134907) (xy 396.498531 -5.180791)
			(xy 396.462813 -5.222012) (xy 396.421593 -5.25773) (xy 396.375708 -5.287218) (xy 396.326094 -5.309876)
			(xy 396.273761 -5.325243) (xy 396.219773 -5.333005) (xy 396.192502 -5.333492) (xy 395.328902 -5.333492)
			(xy 395.301633 -5.332969) (xy 395.24765 -5.325207) (xy 395.195321 -5.309843) (xy 395.145712 -5.287187)
			(xy 395.099832 -5.257702) (xy 395.058614 -5.221987) (xy 395.0229 -5.18077) (xy 394.993414 -5.13489)
			(xy 394.970758 -5.08528) (xy 394.955393 -5.032952) (xy 394.947631 -4.978969) (xy 390.763549 -4.978969)
			(xy 390.766986 -4.993693) (xy 390.779141 -5.081462) (xy 390.783206 -5.169976) (xy 390.779146 -5.25849)
			(xy 390.766994 -5.346261) (xy 390.746854 -5.432549) (xy 390.718895 -5.516629) (xy 390.683352 -5.597795)
			(xy 390.640523 -5.675364) (xy 390.590768 -5.748684) (xy 390.534507 -5.817138) (xy 390.472212 -5.88015)
			(xy 390.404407 -5.937192) (xy 390.331662 -5.987782) (xy 390.254588 -6.031496) (xy 390.173835 -6.067967)
			(xy 390.09008 -6.096887) (xy 390.004028 -6.118014) (xy 389.916403 -6.131169) (xy 389.827941 -6.136243)
			(xy 389.739386 -6.133192) (xy 389.651483 -6.122042) (xy 389.564971 -6.102887) (xy 389.480577 -6.075888)
			(xy 389.399011 -6.041273) (xy 389.320959 -5.999331) (xy 389.283702 -5.97535) (xy 389.272033 -5.968152)
			(xy 389.245982 -5.959639) (xy 389.218604 -5.958367) (xy 389.191876 -5.964428) (xy 389.167726 -5.977384)
			(xy 389.147895 -5.996302) (xy 389.133816 -6.019816) (xy 389.126503 -6.046229) (xy 389.125968 -6.059932)
			(xy 389.125968 -6.740774) (xy 393.142876 -6.740774) (xy 393.142876 -6.686226) (xy 393.150639 -6.632232)
			(xy 393.166008 -6.579894) (xy 393.18867 -6.530275) (xy 393.218162 -6.484387) (xy 393.253885 -6.443163)
			(xy 393.295112 -6.407443) (xy 393.341003 -6.377954) (xy 393.390624 -6.355297) (xy 393.442964 -6.339932)
			(xy 393.496958 -6.332173) (xy 393.524232 -6.331712) (xy 394.387832 -6.331712) (xy 394.415098 -6.332253)
			(xy 394.469074 -6.340017) (xy 394.521397 -6.355384) (xy 394.570999 -6.378041) (xy 394.616873 -6.407526)
			(xy 394.658084 -6.443238) (xy 394.693794 -6.484452) (xy 394.723274 -6.530329) (xy 394.745927 -6.579933)
			(xy 394.761289 -6.632257) (xy 394.76905 -6.686234) (xy 394.76905 -6.740766) (xy 394.769049 -6.74077)
			(xy 396.742898 -6.74077) (xy 396.742898 -6.68623) (xy 396.75066 -6.632245) (xy 396.766025 -6.579914)
			(xy 396.788681 -6.530302) (xy 396.818166 -6.484419) (xy 396.853881 -6.4432) (xy 396.895099 -6.407482)
			(xy 396.940979 -6.377993) (xy 396.99059 -6.355334) (xy 397.04292 -6.339965) (xy 397.096904 -6.3322)
			(xy 397.124174 -6.331712) (xy 397.987774 -6.331712) (xy 398.015044 -6.332226) (xy 398.06903 -6.339984)
			(xy 398.121363 -6.355347) (xy 398.170976 -6.378002) (xy 398.216859 -6.407487) (xy 398.25808 -6.443202)
			(xy 398.293798 -6.48442) (xy 398.323286 -6.530301) (xy 398.345944 -6.579913) (xy 398.36131 -6.632244)
			(xy 398.369072 -6.68623) (xy 398.369072 -6.74077) (xy 398.369071 -6.740774) (xy 400.342776 -6.740774)
			(xy 400.342776 -6.686226) (xy 400.350539 -6.632234) (xy 400.365907 -6.579897) (xy 400.388567 -6.530279)
			(xy 400.418058 -6.484392) (xy 400.45378 -6.443168) (xy 400.495005 -6.407449) (xy 400.540893 -6.377959)
			(xy 400.590512 -6.355301) (xy 400.64285 -6.339935) (xy 400.696842 -6.332174) (xy 400.724116 -6.331712)
			(xy 401.587716 -6.331712) (xy 401.614983 -6.332251) (xy 401.668961 -6.340014) (xy 401.721285 -6.35538)
			(xy 401.77089 -6.378036) (xy 401.816766 -6.40752) (xy 401.857978 -6.443233) (xy 401.89369 -6.484447)
			(xy 401.923172 -6.530324) (xy 401.945825 -6.57993) (xy 401.961189 -6.632255) (xy 401.96895 -6.686233)
			(xy 401.96895 -6.740767) (xy 401.968949 -6.740773) (xy 403.942976 -6.740773) (xy 403.942976 -6.686227)
			(xy 403.950739 -6.632235) (xy 403.966106 -6.579898) (xy 403.988766 -6.53028) (xy 404.018257 -6.484393)
			(xy 404.053978 -6.44317) (xy 404.095203 -6.40745) (xy 404.141091 -6.377961) (xy 404.190709 -6.355302)
			(xy 404.243047 -6.339936) (xy 404.297039 -6.332175) (xy 404.324312 -6.331712) (xy 405.187912 -6.331712)
			(xy 405.215179 -6.332251) (xy 405.269158 -6.340014) (xy 405.321482 -6.355379) (xy 405.371087 -6.378034)
			(xy 405.416964 -6.407519) (xy 405.458177 -6.443231) (xy 405.493889 -6.484446) (xy 405.523371 -6.530323)
			(xy 405.546025 -6.579929) (xy 405.561389 -6.632254) (xy 405.56915 -6.686233) (xy 405.56915 -6.740767)
			(xy 405.56915 -6.74077) (xy 413.052998 -6.74077) (xy 413.052998 -6.68623) (xy 413.06076 -6.632245)
			(xy 413.076125 -6.579914) (xy 413.098781 -6.530302) (xy 413.128267 -6.484419) (xy 413.163982 -6.443199)
			(xy 413.205199 -6.407481) (xy 413.25108 -6.377993) (xy 413.300691 -6.355334) (xy 413.353021 -6.339965)
			(xy 413.407006 -6.3322) (xy 413.434276 -6.331712) (xy 414.297876 -6.331712) (xy 414.325146 -6.332226)
			(xy 414.379132 -6.339985) (xy 414.431464 -6.355348) (xy 414.481077 -6.378002) (xy 414.52696 -6.407487)
			(xy 414.568181 -6.443202) (xy 414.603898 -6.48442) (xy 414.633386 -6.530302) (xy 414.656044 -6.579913)
			(xy 414.67141 -6.632244) (xy 414.679173 -6.68623) (xy 414.679173 -6.74077) (xy 414.679172 -6.740774)
			(xy 416.652876 -6.740774) (xy 416.652876 -6.686226) (xy 416.660639 -6.632234) (xy 416.676007 -6.579897)
			(xy 416.698667 -6.530279) (xy 416.728159 -6.484391) (xy 416.763881 -6.443168) (xy 416.805106 -6.407448)
			(xy 416.850995 -6.377959) (xy 416.900613 -6.355301) (xy 416.952952 -6.339935) (xy 417.006944 -6.332174)
			(xy 417.034218 -6.331712) (xy 417.897818 -6.331712) (xy 417.925085 -6.332252) (xy 417.979063 -6.340015)
			(xy 418.031386 -6.355381) (xy 418.080991 -6.378036) (xy 418.126867 -6.407521) (xy 418.168079 -6.443234)
			(xy 418.20379 -6.484448) (xy 418.233272 -6.530325) (xy 418.255926 -6.57993) (xy 418.271289 -6.632255)
			(xy 418.27905 -6.686233) (xy 418.27905 -6.740767) (xy 418.279049 -6.740773) (xy 424.262976 -6.740773)
			(xy 424.262976 -6.686227) (xy 424.270739 -6.632235) (xy 424.286106 -6.579898) (xy 424.308766 -6.53028)
			(xy 424.338257 -6.484393) (xy 424.373978 -6.44317) (xy 424.415203 -6.40745) (xy 424.461091 -6.377961)
			(xy 424.510709 -6.355302) (xy 424.563047 -6.339936) (xy 424.617039 -6.332175) (xy 424.644312 -6.331712)
			(xy 425.507912 -6.331712) (xy 425.535179 -6.332251) (xy 425.589158 -6.340014) (xy 425.641482 -6.355379)
			(xy 425.691087 -6.378034) (xy 425.736964 -6.407519) (xy 425.778177 -6.443231) (xy 425.813889 -6.484446)
			(xy 425.843371 -6.530323) (xy 425.866025 -6.579929) (xy 425.881389 -6.632254) (xy 425.88915 -6.686233)
			(xy 425.88915 -6.740767) (xy 425.88915 -6.740769) (xy 427.862998 -6.740769) (xy 427.862998 -6.686231)
			(xy 427.870759 -6.632248) (xy 427.886123 -6.579918) (xy 427.908778 -6.530308) (xy 427.938261 -6.484426)
			(xy 427.973974 -6.443207) (xy 428.015189 -6.407489) (xy 428.061067 -6.378) (xy 428.110675 -6.35534)
			(xy 428.163003 -6.339969) (xy 428.216985 -6.332202) (xy 428.244254 -6.331712) (xy 429.107854 -6.331712)
			(xy 429.135125 -6.332224) (xy 429.189113 -6.339981) (xy 429.241448 -6.355342) (xy 429.291064 -6.377995)
			(xy 429.33695 -6.40748) (xy 429.378173 -6.443195) (xy 429.413893 -6.484413) (xy 429.443383 -6.530296)
			(xy 429.466042 -6.579909) (xy 429.48141 -6.632242) (xy 429.489172 -6.686229) (xy 429.489172 -6.740771)
			(xy 429.488151 -6.747873) (xy 431.473788 -6.747873) (xy 431.473788 -6.693327) (xy 431.48155 -6.639337)
			(xy 431.496918 -6.587001) (xy 431.519578 -6.537385) (xy 431.549068 -6.491498) (xy 431.584789 -6.450276)
			(xy 431.626013 -6.414558) (xy 431.6719 -6.385069) (xy 431.721518 -6.362412) (xy 431.773854 -6.347047)
			(xy 431.827845 -6.339286) (xy 431.855118 -6.338824) (xy 432.718718 -6.338824) (xy 432.745986 -6.33934)
			(xy 432.799965 -6.347103) (xy 432.852291 -6.362469) (xy 432.901897 -6.385126) (xy 432.947774 -6.414611)
			(xy 432.988988 -6.450325) (xy 433.0247 -6.491541) (xy 433.054183 -6.537419) (xy 433.076837 -6.587026)
			(xy 433.092201 -6.639352) (xy 433.099962 -6.693332) (xy 433.099962 -6.740771) (xy 445.457798 -6.740771)
			(xy 445.457798 -6.686229) (xy 445.46556 -6.632243) (xy 445.480926 -6.579911) (xy 445.503583 -6.530298)
			(xy 445.53307 -6.484415) (xy 445.568786 -6.443195) (xy 445.610005 -6.407477) (xy 445.655888 -6.377989)
			(xy 445.7055 -6.35533) (xy 445.757831 -6.339963) (xy 445.811817 -6.332199) (xy 445.839088 -6.331712)
			(xy 446.702688 -6.331712) (xy 446.729958 -6.332227) (xy 446.783942 -6.339987) (xy 446.836273 -6.355351)
			(xy 446.885884 -6.378006) (xy 446.931766 -6.407492) (xy 446.972985 -6.443207) (xy 447.008701 -6.484424)
			(xy 447.038188 -6.530305) (xy 447.060845 -6.579916) (xy 447.076211 -6.632246) (xy 447.083973 -6.68623)
			(xy 447.083973 -6.74077) (xy 447.076211 -6.794754) (xy 447.060845 -6.847084) (xy 447.038188 -6.896695)
			(xy 447.008701 -6.942576) (xy 446.972985 -6.983793) (xy 446.931766 -7.019508) (xy 446.885884 -7.048994)
			(xy 446.836273 -7.071649) (xy 446.783942 -7.087013) (xy 446.729958 -7.094773) (xy 446.702688 -7.095236)
			(xy 445.839088 -7.095236) (xy 445.811817 -7.094801) (xy 445.757831 -7.087037) (xy 445.7055 -7.07167)
			(xy 445.655888 -7.049011) (xy 445.610005 -7.019523) (xy 445.568786 -6.983805) (xy 445.53307 -6.942585)
			(xy 445.503583 -6.896702) (xy 445.480926 -6.847089) (xy 445.46556 -6.794757) (xy 445.457798 -6.740771)
			(xy 433.099962 -6.740771) (xy 433.099962 -6.747868) (xy 433.092201 -6.801848) (xy 433.076837 -6.854174)
			(xy 433.054183 -6.903781) (xy 433.0247 -6.949659) (xy 432.988988 -6.990875) (xy 432.947774 -7.026589)
			(xy 432.901897 -7.056074) (xy 432.852291 -7.078731) (xy 432.799965 -7.094097) (xy 432.745986 -7.10186)
			(xy 432.718718 -7.102348) (xy 431.855118 -7.102348) (xy 431.827845 -7.101914) (xy 431.773854 -7.094153)
			(xy 431.721518 -7.078788) (xy 431.6719 -7.056131) (xy 431.626013 -7.026642) (xy 431.584789 -6.990924)
			(xy 431.549068 -6.949702) (xy 431.519578 -6.903815) (xy 431.496918 -6.854199) (xy 431.48155 -6.801863)
			(xy 431.473788 -6.747873) (xy 429.488151 -6.747873) (xy 429.48141 -6.794758) (xy 429.466042 -6.847091)
			(xy 429.443383 -6.896704) (xy 429.413893 -6.942587) (xy 429.378173 -6.983805) (xy 429.33695 -7.01952)
			(xy 429.291064 -7.049005) (xy 429.241448 -7.071658) (xy 429.189113 -7.087019) (xy 429.135125 -7.094776)
			(xy 429.107854 -7.095236) (xy 428.244254 -7.095236) (xy 428.216985 -7.094798) (xy 428.163003 -7.087031)
			(xy 428.110675 -7.07166) (xy 428.061067 -7.049) (xy 428.015189 -7.019511) (xy 427.973974 -6.983793)
			(xy 427.938261 -6.942574) (xy 427.908778 -6.896692) (xy 427.886123 -6.847082) (xy 427.870759 -6.794752)
			(xy 427.862998 -6.740769) (xy 425.88915 -6.740769) (xy 425.881389 -6.794746) (xy 425.866025 -6.847071)
			(xy 425.843371 -6.896677) (xy 425.813889 -6.942554) (xy 425.778177 -6.983769) (xy 425.736964 -7.019481)
			(xy 425.691087 -7.048966) (xy 425.641482 -7.071621) (xy 425.589158 -7.086986) (xy 425.535179 -7.094749)
			(xy 425.507912 -7.095236) (xy 424.644312 -7.095236) (xy 424.617039 -7.094825) (xy 424.563047 -7.087064)
			(xy 424.510709 -7.071698) (xy 424.461091 -7.049039) (xy 424.415203 -7.01955) (xy 424.373978 -6.98383)
			(xy 424.338257 -6.942607) (xy 424.308766 -6.89672) (xy 424.286106 -6.847102) (xy 424.270739 -6.794765)
			(xy 424.262976 -6.740773) (xy 418.279049 -6.740773) (xy 418.271289 -6.794745) (xy 418.255926 -6.84707)
			(xy 418.233272 -6.896675) (xy 418.20379 -6.942552) (xy 418.168079 -6.983766) (xy 418.126867 -7.019479)
			(xy 418.080991 -7.048964) (xy 418.031386 -7.071619) (xy 417.979063 -7.086985) (xy 417.925085 -7.094748)
			(xy 417.897818 -7.095236) (xy 417.034218 -7.095236) (xy 417.006944 -7.094826) (xy 416.952952 -7.087065)
			(xy 416.900613 -7.071699) (xy 416.850995 -7.049041) (xy 416.805106 -7.019552) (xy 416.763881 -6.983832)
			(xy 416.728159 -6.942609) (xy 416.698667 -6.896721) (xy 416.676007 -6.847103) (xy 416.660639 -6.794766)
			(xy 416.652876 -6.740774) (xy 414.679172 -6.740774) (xy 414.67141 -6.794756) (xy 414.656044 -6.847087)
			(xy 414.633386 -6.896698) (xy 414.603898 -6.94258) (xy 414.568181 -6.983798) (xy 414.52696 -7.019513)
			(xy 414.481077 -7.048998) (xy 414.431464 -7.071652) (xy 414.379132 -7.087015) (xy 414.325146 -7.094774)
			(xy 414.297876 -7.095236) (xy 413.434276 -7.095236) (xy 413.407006 -7.0948) (xy 413.353021 -7.087035)
			(xy 413.300691 -7.071666) (xy 413.25108 -7.049007) (xy 413.205199 -7.019519) (xy 413.163982 -6.983801)
			(xy 413.128267 -6.942581) (xy 413.098781 -6.896698) (xy 413.076125 -6.847086) (xy 413.06076 -6.794755)
			(xy 413.052998 -6.74077) (xy 405.56915 -6.74077) (xy 405.561389 -6.794746) (xy 405.546025 -6.847071)
			(xy 405.523371 -6.896677) (xy 405.493889 -6.942554) (xy 405.458177 -6.983769) (xy 405.416964 -7.019481)
			(xy 405.371087 -7.048966) (xy 405.321482 -7.071621) (xy 405.269158 -7.086986) (xy 405.215179 -7.094749)
			(xy 405.187912 -7.095236) (xy 404.324312 -7.095236) (xy 404.297039 -7.094825) (xy 404.243047 -7.087064)
			(xy 404.190709 -7.071698) (xy 404.141091 -7.049039) (xy 404.095203 -7.01955) (xy 404.053978 -6.98383)
			(xy 404.018257 -6.942607) (xy 403.988766 -6.89672) (xy 403.966106 -6.847102) (xy 403.950739 -6.794765)
			(xy 403.942976 -6.740773) (xy 401.968949 -6.740773) (xy 401.961189 -6.794745) (xy 401.945825 -6.84707)
			(xy 401.923172 -6.896676) (xy 401.89369 -6.942553) (xy 401.857978 -6.983767) (xy 401.816766 -7.01948)
			(xy 401.77089 -7.048964) (xy 401.721285 -7.07162) (xy 401.668961 -7.086986) (xy 401.614983 -7.094749)
			(xy 401.587716 -7.095236) (xy 400.724116 -7.095236) (xy 400.696842 -7.094826) (xy 400.64285 -7.087065)
			(xy 400.590512 -7.071699) (xy 400.540893 -7.049041) (xy 400.495005 -7.019551) (xy 400.45378 -6.983832)
			(xy 400.418058 -6.942608) (xy 400.388567 -6.896721) (xy 400.365907 -6.847103) (xy 400.350539 -6.794766)
			(xy 400.342776 -6.740774) (xy 398.369071 -6.740774) (xy 398.36131 -6.794756) (xy 398.345944 -6.847087)
			(xy 398.323286 -6.896699) (xy 398.293798 -6.94258) (xy 398.25808 -6.983798) (xy 398.216859 -7.019513)
			(xy 398.170976 -7.048998) (xy 398.121363 -7.071653) (xy 398.06903 -7.087016) (xy 398.015044 -7.094774)
			(xy 397.987774 -7.095236) (xy 397.124174 -7.095236) (xy 397.096904 -7.0948) (xy 397.04292 -7.087035)
			(xy 396.99059 -7.071666) (xy 396.940979 -7.049007) (xy 396.895099 -7.019518) (xy 396.853881 -6.9838)
			(xy 396.818166 -6.942581) (xy 396.788681 -6.896698) (xy 396.766025 -6.847086) (xy 396.75066 -6.794755)
			(xy 396.742898 -6.74077) (xy 394.769049 -6.74077) (xy 394.761289 -6.794743) (xy 394.745927 -6.847067)
			(xy 394.723274 -6.896671) (xy 394.693794 -6.942548) (xy 394.658084 -6.983762) (xy 394.616873 -7.019474)
			(xy 394.570999 -7.048959) (xy 394.521397 -7.071616) (xy 394.469074 -7.086983) (xy 394.415098 -7.094747)
			(xy 394.387832 -7.095236) (xy 393.524232 -7.095236) (xy 393.496958 -7.094827) (xy 393.442964 -7.087068)
			(xy 393.390624 -7.071703) (xy 393.341003 -7.049046) (xy 393.295112 -7.019557) (xy 393.253885 -6.983837)
			(xy 393.218162 -6.942613) (xy 393.18867 -6.896725) (xy 393.166008 -6.847106) (xy 393.150639 -6.794768)
			(xy 393.142876 -6.740774) (xy 389.125968 -6.740774) (xy 389.125968 -9.780016) (xy 389.125476 -9.863891)
			(xy 389.117494 -10.03145) (xy 389.101547 -10.198439) (xy 389.077674 -10.364481) (xy 389.045926 -10.529198)
			(xy 389.006377 -10.692219) (xy 388.959116 -10.853173) (xy 388.904249 -11.011695) (xy 388.841902 -11.167428)
			(xy 388.772216 -11.320018) (xy 388.695348 -11.469118) (xy 388.611473 -11.614393) (xy 388.52078 -11.755512)
			(xy 388.423475 -11.892156) (xy 388.319779 -12.024015) (xy 388.209926 -12.150791) (xy 388.094165 -12.272196)
			(xy 387.972758 -12.387955) (xy 387.845981 -12.497807) (xy 387.714121 -12.601501) (xy 387.577476 -12.698805)
			(xy 387.436355 -12.789496) (xy 387.29108 -12.873369) (xy 387.254814 -12.892065) (xy 431.46197 -12.892065)
			(xy 431.46197 -12.837535) (xy 431.46973 -12.783559) (xy 431.485093 -12.731238) (xy 431.507745 -12.681635)
			(xy 431.537225 -12.635761) (xy 431.572934 -12.594548) (xy 431.614145 -12.558837) (xy 431.660017 -12.529355)
			(xy 431.709619 -12.5067) (xy 431.76194 -12.491335) (xy 431.815915 -12.483572) (xy 431.84318 -12.483084)
			(xy 432.70678 -12.483084) (xy 432.734055 -12.483454) (xy 432.788051 -12.491215) (xy 432.840392 -12.506581)
			(xy 432.890014 -12.529241) (xy 432.935905 -12.558731) (xy 432.977133 -12.594453) (xy 433.012857 -12.635678)
			(xy 433.04235 -12.681569) (xy 433.065012 -12.731189) (xy 433.080381 -12.78353) (xy 433.088144 -12.837525)
			(xy 433.088144 -12.864846) (xy 445.45631 -12.864846) (xy 445.45631 -12.864592) (xy 445.456564 -12.850622)
			(xy 445.45717 -12.823469) (xy 445.46523 -12.769758) (xy 445.48082 -12.717731) (xy 445.503625 -12.668439)
			(xy 445.533186 -12.622876) (xy 445.568905 -12.581962) (xy 445.610062 -12.546522) (xy 445.655826 -12.517273)
			(xy 445.705273 -12.494804) (xy 445.757405 -12.47957) (xy 445.81117 -12.471876) (xy 445.838326 -12.4714)
			(xy 446.701926 -12.4714) (xy 446.72908 -12.471883) (xy 446.782838 -12.479582) (xy 446.834964 -12.494821)
			(xy 446.884404 -12.517293) (xy 446.93016 -12.546543) (xy 446.971311 -12.581982) (xy 447.007024 -12.622895)
			(xy 447.03658 -12.668455) (xy 447.059381 -12.717744) (xy 447.074968 -12.769766) (xy 447.083027 -12.823472)
			(xy 447.083688 -12.850622) (xy 447.083942 -12.864592) (xy 447.083942 -12.864846) (xy 447.083472 -12.892133)
			(xy 447.0757 -12.946152) (xy 447.06032 -12.998515) (xy 447.037645 -13.048157) (xy 447.008137 -13.094067)
			(xy 446.972397 -13.135311) (xy 446.931151 -13.171049) (xy 446.885239 -13.200555) (xy 446.835597 -13.223227)
			(xy 446.783233 -13.238604) (xy 446.729214 -13.246374) (xy 446.701926 -13.246862) (xy 446.679426 -13.246581)
			(xy 446.634732 -13.241355) (xy 446.612772 -13.236448) (xy 446.60693 -13.234924) (xy 445.933322 -13.234924)
			(xy 445.92748 -13.236448) (xy 445.905519 -13.241348) (xy 445.860825 -13.246566) (xy 445.838326 -13.246862)
			(xy 445.811041 -13.246305) (xy 445.757027 -13.238543) (xy 445.704666 -13.223173) (xy 445.655026 -13.200508)
			(xy 445.609117 -13.17101) (xy 445.567873 -13.135278) (xy 445.532133 -13.094041) (xy 445.502626 -13.048137)
			(xy 445.479952 -12.998501) (xy 445.464572 -12.946144) (xy 445.4568 -12.892131) (xy 445.45631 -12.864846)
			(xy 433.088144 -12.864846) (xy 433.088144 -12.892075) (xy 433.080381 -12.94607) (xy 433.065012 -12.998411)
			(xy 433.04235 -13.048031) (xy 433.012857 -13.093921) (xy 432.977133 -13.135147) (xy 432.935905 -13.170869)
			(xy 432.890014 -13.200359) (xy 432.840392 -13.223019) (xy 432.788051 -13.238385) (xy 432.734055 -13.246146)
			(xy 432.70678 -13.246608) (xy 431.84318 -13.246608) (xy 431.815915 -13.246028) (xy 431.76194 -13.238265)
			(xy 431.709619 -13.2229) (xy 431.660017 -13.200245) (xy 431.614145 -13.170763) (xy 431.572934 -13.135052)
			(xy 431.537225 -13.093839) (xy 431.507745 -13.047965) (xy 431.485093 -12.998362) (xy 431.46973 -12.946041)
			(xy 431.46197 -12.892065) (xy 387.254814 -12.892065) (xy 387.141978 -12.950235) (xy 386.989387 -13.01992)
			(xy 386.833654 -13.082265) (xy 386.675131 -13.137129) (xy 386.514176 -13.184388) (xy 386.351155 -13.223935)
			(xy 386.186437 -13.255681) (xy 386.020395 -13.279553) (xy 385.853406 -13.295497) (xy 385.685847 -13.303478)
			(xy 385.601972 -13.304012) (xy 320.726308 -13.304012) (xy 320.715132 -13.339318) (xy 320.706577 -13.364685)
			(xy 320.683356 -13.41292) (xy 320.65362 -13.457435) (xy 320.617953 -13.497357) (xy 320.577056 -13.531901)
			(xy 320.531732 -13.560389) (xy 320.482871 -13.582261) (xy 320.431432 -13.597089) (xy 320.378425 -13.60458)
			(xy 320.351658 -13.605002) (xy 320.324289 -13.604527) (xy 320.270114 -13.596698) (xy 320.217613 -13.581207)
			(xy 320.167866 -13.558371) (xy 320.121894 -13.528659) (xy 320.10096 -13.511022) (xy 320.089632 -13.501786)
			(xy 320.063075 -13.48961) (xy 320.034158 -13.485437) (xy 320.005241 -13.48961) (xy 319.978684 -13.501786)
			(xy 319.967356 -13.511022) (xy 319.946423 -13.528661) (xy 319.900455 -13.55838) (xy 319.850708 -13.581216)
			(xy 319.798205 -13.596699) (xy 319.744027 -13.604511) (xy 319.716658 -13.605002) (xy 319.689891 -13.604554)
			(xy 319.636881 -13.597076) (xy 319.585438 -13.582258) (xy 319.536573 -13.560393) (xy 319.491245 -13.531909)
			(xy 319.450346 -13.497367) (xy 319.414679 -13.457444) (xy 319.384946 -13.412927) (xy 319.361729 -13.364688)
			(xy 319.353184 -13.339318) (xy 319.342008 -13.304012) (xy 260.800088 -13.304012) (xy 260.768924 -13.304522)
			(xy 260.707128 -13.31266) (xy 260.646924 -13.328793) (xy 260.58934 -13.352646) (xy 260.535363 -13.383812)
			(xy 260.485915 -13.421756) (xy 260.441843 -13.46583) (xy 260.403901 -13.51528) (xy 260.372737 -13.569258)
			(xy 260.348886 -13.626843) (xy 260.332756 -13.687048) (xy 260.324621 -13.748844) (xy 260.324092 -13.780008)
			(xy 260.324092 -21.044662) (xy 260.32459 -21.059465) (xy 260.333067 -21.087832) (xy 260.349321 -21.112578)
			(xy 260.371987 -21.131625) (xy 260.399161 -21.143376) (xy 260.428564 -21.146842) (xy 260.457726 -21.141733)
			(xy 260.4842 -21.128479) (xy 260.505763 -21.108191) (xy 260.520604 -21.082574) (xy 260.524498 -21.068284)
			(xy 260.549167 -20.967779) (xy 260.60538 -20.768585) (xy 260.669369 -20.571751) (xy 260.741035 -20.377581)
			(xy 260.820269 -20.186374) (xy 260.906947 -19.998424) (xy 261.000937 -19.814022) (xy 261.102093 -19.633452)
			(xy 261.21026 -19.456992) (xy 261.32527 -19.284914) (xy 261.446946 -19.117483) (xy 261.575102 -18.954958)
			(xy 261.709538 -18.797589) (xy 261.850049 -18.645619) (xy 261.996417 -18.499282) (xy 262.148416 -18.358803)
			(xy 262.305814 -18.2244) (xy 262.468365 -18.096278) (xy 262.635821 -17.974637) (xy 262.807924 -17.859663)
			(xy 262.984406 -17.751534) (xy 263.164998 -17.650415) (xy 263.34942 -17.556464) (xy 263.537387 -17.469825)
			(xy 263.728611 -17.390632) (xy 263.922796 -17.319006) (xy 264.119644 -17.255059) (xy 264.31885 -17.198887)
			(xy 264.520107 -17.15058) (xy 264.723105 -17.11021) (xy 264.927532 -17.077839) (xy 265.133072 -17.053519)
			(xy 265.339409 -17.037286) (xy 265.546223 -17.029166) (xy 265.64971 -17.028668) (xy 265.751936 -17.029164)
			(xy 265.956233 -17.037092) (xy 266.16007 -17.052936) (xy 266.363139 -17.076672) (xy 266.565135 -17.108263)
			(xy 266.765754 -17.147664) (xy 266.964694 -17.194814) (xy 267.161656 -17.249643) (xy 267.356345 -17.312067)
			(xy 267.548466 -17.381994) (xy 267.737731 -17.459318) (xy 267.923856 -17.543922) (xy 268.106561 -17.63568)
			(xy 268.28557 -17.734453) (xy 268.460614 -17.840094) (xy 268.63143 -17.952442) (xy 268.797762 -18.071329)
			(xy 268.959359 -18.196576) (xy 269.115978 -18.327995) (xy 269.267383 -18.465388) (xy 269.413346 -18.608548)
			(xy 269.553649 -18.757261) (xy 269.68808 -18.911302) (xy 269.816437 -19.07044) (xy 269.938527 -19.234435)
			(xy 270.054166 -19.403042) (xy 270.16318 -19.576005) (xy 270.265406 -19.753065) (xy 270.360689 -19.933956)
			(xy 270.448886 -20.118405) (xy 270.529865 -20.306136) (xy 270.603504 -20.496865) (xy 270.669692 -20.690306)
			(xy 270.728329 -20.886169) (xy 270.779328 -21.084157) (xy 270.822611 -21.283975) (xy 270.858113 -21.48532)
			(xy 270.885782 -21.687891) (xy 270.905575 -21.891382) (xy 270.917463 -22.095487) (xy 270.921428 -22.2999)
			(xy 270.921427 -22.29993) (xy 375.62816 -22.29993) (xy 375.632174 -22.094246) (xy 375.64421 -21.888876)
			(xy 375.664249 -21.684132) (xy 375.692262 -21.480325) (xy 375.728205 -21.277766) (xy 375.772024 -21.076764)
			(xy 375.823651 -20.877625) (xy 375.883009 -20.680652) (xy 375.950007 -20.486144) (xy 376.024543 -20.294399)
			(xy 376.106503 -20.105708) (xy 376.195763 -19.920358) (xy 376.292186 -19.738632) (xy 376.395627 -19.560806)
			(xy 376.505926 -19.387152) (xy 376.622917 -19.217933) (xy 376.746421 -19.053407) (xy 376.87625 -18.893826)
			(xy 377.012207 -18.739431) (xy 377.154084 -18.590459) (xy 377.301665 -18.447135) (xy 377.454726 -18.309679)
			(xy 377.613033 -18.178299) (xy 377.776346 -18.053196) (xy 377.944415 -17.934559) (xy 378.116985 -17.822571)
			(xy 378.293793 -17.7174) (xy 378.47457 -17.619209) (xy 378.65904 -17.528145) (xy 378.846922 -17.444348)
			(xy 379.037932 -17.367945) (xy 379.231776 -17.299052) (xy 379.428161 -17.237775) (xy 379.626787 -17.184207)
			(xy 379.827352 -17.13843) (xy 380.02955 -17.100512) (xy 380.233074 -17.070513) (xy 380.437613 -17.048476)
			(xy 380.642856 -17.034437) (xy 380.848491 -17.028417) (xy 381.054204 -17.030424) (xy 381.259682 -17.040456)
			(xy 381.464612 -17.058497) (xy 381.668682 -17.08452) (xy 381.871582 -17.118485) (xy 382.073002 -17.16034)
			(xy 382.272635 -17.210022) (xy 382.470178 -17.267456) (xy 382.66533 -17.332553) (xy 382.857794 -17.405214)
			(xy 383.047276 -17.48533) (xy 383.233487 -17.572777) (xy 383.341348 -17.628666) (xy 389.660162 -17.628666)
			(xy 389.660162 -17.574134) (xy 389.667923 -17.520157) (xy 389.683286 -17.467834) (xy 389.705939 -17.41823)
			(xy 389.73542 -17.372354) (xy 389.77113 -17.331141) (xy 389.812342 -17.29543) (xy 389.858216 -17.265946)
			(xy 389.907819 -17.243291) (xy 389.960142 -17.227926) (xy 390.014118 -17.220163) (xy 390.041384 -17.219676)
			(xy 390.904984 -17.219676) (xy 390.932258 -17.220062) (xy 390.986252 -17.227824) (xy 391.038592 -17.24319)
			(xy 391.088212 -17.265849) (xy 391.134103 -17.295339) (xy 391.175329 -17.33106) (xy 391.211051 -17.372285)
			(xy 391.240543 -17.418174) (xy 391.263204 -17.467793) (xy 391.278573 -17.520132) (xy 391.286336 -17.574126)
			(xy 391.286336 -17.628666) (xy 395.248162 -17.628666) (xy 395.248162 -17.574134) (xy 395.255923 -17.520157)
			(xy 395.271286 -17.467834) (xy 395.293939 -17.41823) (xy 395.32342 -17.372354) (xy 395.35913 -17.331141)
			(xy 395.400342 -17.29543) (xy 395.446216 -17.265946) (xy 395.495819 -17.243291) (xy 395.548142 -17.227926)
			(xy 395.602118 -17.220163) (xy 395.629384 -17.219676) (xy 396.492984 -17.219676) (xy 396.520258 -17.220062)
			(xy 396.574252 -17.227824) (xy 396.626592 -17.24319) (xy 396.676212 -17.265849) (xy 396.722103 -17.295339)
			(xy 396.763329 -17.33106) (xy 396.799051 -17.372285) (xy 396.828543 -17.418174) (xy 396.851204 -17.467793)
			(xy 396.866573 -17.520132) (xy 396.874336 -17.574126) (xy 396.874336 -17.628666) (xy 400.836162 -17.628666)
			(xy 400.836162 -17.574134) (xy 400.843923 -17.520157) (xy 400.859286 -17.467834) (xy 400.881939 -17.41823)
			(xy 400.91142 -17.372354) (xy 400.94713 -17.331141) (xy 400.988342 -17.29543) (xy 401.034216 -17.265946)
			(xy 401.083819 -17.243291) (xy 401.136142 -17.227926) (xy 401.190118 -17.220163) (xy 401.217384 -17.219676)
			(xy 402.080984 -17.219676) (xy 402.108258 -17.220062) (xy 402.162252 -17.227824) (xy 402.214592 -17.24319)
			(xy 402.264212 -17.265849) (xy 402.310103 -17.295339) (xy 402.351329 -17.33106) (xy 402.387051 -17.372285)
			(xy 402.416543 -17.418174) (xy 402.439204 -17.467793) (xy 402.454573 -17.520132) (xy 402.462336 -17.574126)
			(xy 402.462336 -17.628666) (xy 406.424162 -17.628666) (xy 406.424162 -17.574134) (xy 406.431923 -17.520157)
			(xy 406.447286 -17.467834) (xy 406.469939 -17.41823) (xy 406.49942 -17.372354) (xy 406.53513 -17.331141)
			(xy 406.576342 -17.29543) (xy 406.622216 -17.265946) (xy 406.671819 -17.243291) (xy 406.724142 -17.227926)
			(xy 406.778118 -17.220163) (xy 406.805384 -17.219676) (xy 407.668984 -17.219676) (xy 407.696258 -17.220062)
			(xy 407.750252 -17.227824) (xy 407.802592 -17.24319) (xy 407.852212 -17.265849) (xy 407.898103 -17.295339)
			(xy 407.939329 -17.33106) (xy 407.975051 -17.372285) (xy 408.004543 -17.418174) (xy 408.027204 -17.467793)
			(xy 408.042573 -17.520132) (xy 408.050336 -17.574126) (xy 408.050336 -17.628666) (xy 412.012162 -17.628666)
			(xy 412.012162 -17.574134) (xy 412.019923 -17.520157) (xy 412.035286 -17.467834) (xy 412.057939 -17.41823)
			(xy 412.08742 -17.372354) (xy 412.12313 -17.331141) (xy 412.164342 -17.29543) (xy 412.210216 -17.265946)
			(xy 412.259819 -17.243291) (xy 412.312142 -17.227926) (xy 412.366118 -17.220163) (xy 412.393384 -17.219676)
			(xy 413.256984 -17.219676) (xy 413.284258 -17.220062) (xy 413.338252 -17.227824) (xy 413.390592 -17.24319)
			(xy 413.440212 -17.265849) (xy 413.486103 -17.295339) (xy 413.527329 -17.33106) (xy 413.563051 -17.372285)
			(xy 413.592543 -17.418174) (xy 413.615204 -17.467793) (xy 413.630573 -17.520132) (xy 413.638336 -17.574126)
			(xy 413.638336 -17.628667) (xy 417.905962 -17.628667) (xy 417.905962 -17.574133) (xy 417.913723 -17.520155)
			(xy 417.929087 -17.467831) (xy 417.951741 -17.418226) (xy 417.981224 -17.372349) (xy 418.016936 -17.331136)
			(xy 418.058149 -17.295424) (xy 418.104026 -17.265941) (xy 418.153631 -17.243287) (xy 418.205955 -17.227923)
			(xy 418.259933 -17.220162) (xy 418.2872 -17.219676) (xy 419.1508 -17.219676) (xy 419.178072 -17.220087)
			(xy 419.232061 -17.227849) (xy 419.284396 -17.243216) (xy 419.334011 -17.265874) (xy 419.379896 -17.295363)
			(xy 419.421118 -17.331082) (xy 419.456837 -17.372304) (xy 419.486326 -17.418189) (xy 419.508984 -17.467804)
			(xy 419.524351 -17.520139) (xy 419.532113 -17.574128) (xy 419.532113 -17.628667) (xy 423.493962 -17.628667)
			(xy 423.493962 -17.574133) (xy 423.501723 -17.520155) (xy 423.517087 -17.467831) (xy 423.539741 -17.418226)
			(xy 423.569224 -17.372349) (xy 423.604936 -17.331136) (xy 423.646149 -17.295424) (xy 423.692026 -17.265941)
			(xy 423.741631 -17.243287) (xy 423.793955 -17.227923) (xy 423.847933 -17.220162) (xy 423.8752 -17.219676)
			(xy 424.7388 -17.219676) (xy 424.766072 -17.220087) (xy 424.820061 -17.227849) (xy 424.872396 -17.243216)
			(xy 424.922011 -17.265874) (xy 424.967896 -17.295363) (xy 425.009118 -17.331082) (xy 425.044837 -17.372304)
			(xy 425.074326 -17.418189) (xy 425.096984 -17.467804) (xy 425.112351 -17.520139) (xy 425.120113 -17.574128)
			(xy 425.120113 -17.62867) (xy 429.11594 -17.62867) (xy 429.11594 -17.57413) (xy 429.123702 -17.520145)
			(xy 429.139068 -17.467815) (xy 429.161726 -17.418204) (xy 429.191214 -17.372324) (xy 429.226932 -17.331107)
			(xy 429.268152 -17.295393) (xy 429.314036 -17.265909) (xy 429.363649 -17.243256) (xy 429.415981 -17.227894)
			(xy 429.469966 -17.220137) (xy 429.497236 -17.219676) (xy 430.360836 -17.219676) (xy 430.388106 -17.220089)
			(xy 430.442091 -17.227856) (xy 430.494422 -17.243226) (xy 430.544032 -17.265886) (xy 430.589913 -17.295376)
			(xy 430.631131 -17.331095) (xy 430.666846 -17.372315) (xy 430.696331 -17.418199) (xy 430.718987 -17.467812)
			(xy 430.734352 -17.520144) (xy 430.742114 -17.57413) (xy 430.742114 -17.62867) (xy 430.734352 -17.682656)
			(xy 430.718987 -17.734988) (xy 430.696331 -17.784601) (xy 430.666846 -17.830485) (xy 430.631131 -17.871705)
			(xy 430.589913 -17.907424) (xy 430.544032 -17.936914) (xy 430.494422 -17.959574) (xy 430.442091 -17.974944)
			(xy 430.388106 -17.982711) (xy 430.360836 -17.9832) (xy 429.497236 -17.9832) (xy 429.469966 -17.982663)
			(xy 429.415981 -17.974906) (xy 429.363649 -17.959544) (xy 429.314036 -17.936891) (xy 429.268152 -17.907407)
			(xy 429.226932 -17.871693) (xy 429.191214 -17.830476) (xy 429.161726 -17.784596) (xy 429.139068 -17.734985)
			(xy 429.123702 -17.682655) (xy 429.11594 -17.62867) (xy 425.120113 -17.62867) (xy 425.120113 -17.628672)
			(xy 425.112351 -17.682661) (xy 425.096984 -17.734996) (xy 425.074326 -17.784611) (xy 425.044837 -17.830496)
			(xy 425.009118 -17.871718) (xy 424.967896 -17.907437) (xy 424.922011 -17.936926) (xy 424.872396 -17.959584)
			(xy 424.820061 -17.974951) (xy 424.766072 -17.982713) (xy 424.7388 -17.9832) (xy 423.8752 -17.9832)
			(xy 423.847933 -17.982638) (xy 423.793955 -17.974877) (xy 423.741631 -17.959513) (xy 423.692026 -17.936859)
			(xy 423.646149 -17.907376) (xy 423.604936 -17.871664) (xy 423.569224 -17.830451) (xy 423.539741 -17.784574)
			(xy 423.517087 -17.734969) (xy 423.501723 -17.682645) (xy 423.493962 -17.628667) (xy 419.532113 -17.628667)
			(xy 419.532113 -17.628672) (xy 419.524351 -17.682661) (xy 419.508984 -17.734996) (xy 419.486326 -17.784611)
			(xy 419.456837 -17.830496) (xy 419.421118 -17.871718) (xy 419.379896 -17.907437) (xy 419.334011 -17.936926)
			(xy 419.284396 -17.959584) (xy 419.232061 -17.974951) (xy 419.178072 -17.982713) (xy 419.1508 -17.9832)
			(xy 418.2872 -17.9832) (xy 418.259933 -17.982638) (xy 418.205955 -17.974877) (xy 418.153631 -17.959513)
			(xy 418.104026 -17.936859) (xy 418.058149 -17.907376) (xy 418.016936 -17.871664) (xy 417.981224 -17.830451)
			(xy 417.951741 -17.784574) (xy 417.929087 -17.734969) (xy 417.913723 -17.682645) (xy 417.905962 -17.628667)
			(xy 413.638336 -17.628667) (xy 413.638336 -17.628674) (xy 413.630573 -17.682668) (xy 413.615204 -17.735007)
			(xy 413.592543 -17.784626) (xy 413.563051 -17.830515) (xy 413.527329 -17.87174) (xy 413.486103 -17.907461)
			(xy 413.440212 -17.936951) (xy 413.390592 -17.95961) (xy 413.338252 -17.974976) (xy 413.284258 -17.982738)
			(xy 413.256984 -17.9832) (xy 412.393384 -17.9832) (xy 412.366118 -17.982637) (xy 412.312142 -17.974874)
			(xy 412.259819 -17.959509) (xy 412.210216 -17.936854) (xy 412.164342 -17.90737) (xy 412.12313 -17.871659)
			(xy 412.08742 -17.830446) (xy 412.057939 -17.78457) (xy 412.035286 -17.734966) (xy 412.019923 -17.682643)
			(xy 412.012162 -17.628666) (xy 408.050336 -17.628666) (xy 408.050336 -17.628674) (xy 408.042573 -17.682668)
			(xy 408.027204 -17.735007) (xy 408.004543 -17.784626) (xy 407.975051 -17.830515) (xy 407.939329 -17.87174)
			(xy 407.898103 -17.907461) (xy 407.852212 -17.936951) (xy 407.802592 -17.95961) (xy 407.750252 -17.974976)
			(xy 407.696258 -17.982738) (xy 407.668984 -17.9832) (xy 406.805384 -17.9832) (xy 406.778118 -17.982637)
			(xy 406.724142 -17.974874) (xy 406.671819 -17.959509) (xy 406.622216 -17.936854) (xy 406.576342 -17.90737)
			(xy 406.53513 -17.871659) (xy 406.49942 -17.830446) (xy 406.469939 -17.78457) (xy 406.447286 -17.734966)
			(xy 406.431923 -17.682643) (xy 406.424162 -17.628666) (xy 402.462336 -17.628666) (xy 402.462336 -17.628674)
			(xy 402.454573 -17.682668) (xy 402.439204 -17.735007) (xy 402.416543 -17.784626) (xy 402.387051 -17.830515)
			(xy 402.351329 -17.87174) (xy 402.310103 -17.907461) (xy 402.264212 -17.936951) (xy 402.214592 -17.95961)
			(xy 402.162252 -17.974976) (xy 402.108258 -17.982738) (xy 402.080984 -17.9832) (xy 401.217384 -17.9832)
			(xy 401.190118 -17.982637) (xy 401.136142 -17.974874) (xy 401.083819 -17.959509) (xy 401.034216 -17.936854)
			(xy 400.988342 -17.90737) (xy 400.94713 -17.871659) (xy 400.91142 -17.830446) (xy 400.881939 -17.78457)
			(xy 400.859286 -17.734966) (xy 400.843923 -17.682643) (xy 400.836162 -17.628666) (xy 396.874336 -17.628666)
			(xy 396.874336 -17.628674) (xy 396.866573 -17.682668) (xy 396.851204 -17.735007) (xy 396.828543 -17.784626)
			(xy 396.799051 -17.830515) (xy 396.763329 -17.87174) (xy 396.722103 -17.907461) (xy 396.676212 -17.936951)
			(xy 396.626592 -17.95961) (xy 396.574252 -17.974976) (xy 396.520258 -17.982738) (xy 396.492984 -17.9832)
			(xy 395.629384 -17.9832) (xy 395.602118 -17.982637) (xy 395.548142 -17.974874) (xy 395.495819 -17.959509)
			(xy 395.446216 -17.936854) (xy 395.400342 -17.90737) (xy 395.35913 -17.871659) (xy 395.32342 -17.830446)
			(xy 395.293939 -17.78457) (xy 395.271286 -17.734966) (xy 395.255923 -17.682643) (xy 395.248162 -17.628666)
			(xy 391.286336 -17.628666) (xy 391.286336 -17.628674) (xy 391.278573 -17.682668) (xy 391.263204 -17.735007)
			(xy 391.240543 -17.784626) (xy 391.211051 -17.830515) (xy 391.175329 -17.87174) (xy 391.134103 -17.907461)
			(xy 391.088212 -17.936951) (xy 391.038592 -17.95961) (xy 390.986252 -17.974976) (xy 390.932258 -17.982738)
			(xy 390.904984 -17.9832) (xy 390.041384 -17.9832) (xy 390.014118 -17.982637) (xy 389.960142 -17.974874)
			(xy 389.907819 -17.959509) (xy 389.858216 -17.936854) (xy 389.812342 -17.90737) (xy 389.77113 -17.871659)
			(xy 389.73542 -17.830446) (xy 389.705939 -17.78457) (xy 389.683286 -17.734966) (xy 389.667923 -17.682643)
			(xy 389.660162 -17.628666) (xy 383.341348 -17.628666) (xy 383.416146 -17.667423) (xy 383.594972 -17.769123)
			(xy 383.769694 -17.877723) (xy 383.940047 -17.993058) (xy 384.105769 -18.114951) (xy 384.26661 -18.243217)
			(xy 384.422323 -18.37766) (xy 384.572673 -18.518077) (xy 384.71743 -18.664253) (xy 384.856373 -18.815965)
			(xy 384.989291 -18.972983) (xy 385.115982 -19.135068) (xy 385.128663 -19.152666) (xy 392.454162 -19.152666)
			(xy 392.454162 -19.098134) (xy 392.461923 -19.044157) (xy 392.477286 -18.991834) (xy 392.499939 -18.94223)
			(xy 392.52942 -18.896354) (xy 392.56513 -18.855141) (xy 392.606342 -18.81943) (xy 392.652216 -18.789946)
			(xy 392.701819 -18.767291) (xy 392.754142 -18.751926) (xy 392.808118 -18.744163) (xy 392.835384 -18.743676)
			(xy 393.698984 -18.743676) (xy 393.726258 -18.744062) (xy 393.780252 -18.751824) (xy 393.832592 -18.76719)
			(xy 393.882212 -18.789849) (xy 393.928103 -18.819339) (xy 393.969329 -18.85506) (xy 394.005051 -18.896285)
			(xy 394.034543 -18.942174) (xy 394.057204 -18.991793) (xy 394.072573 -19.044132) (xy 394.080336 -19.098126)
			(xy 394.080336 -19.152666) (xy 398.042162 -19.152666) (xy 398.042162 -19.098134) (xy 398.049923 -19.044157)
			(xy 398.065286 -18.991834) (xy 398.087939 -18.94223) (xy 398.11742 -18.896354) (xy 398.15313 -18.855141)
			(xy 398.194342 -18.81943) (xy 398.240216 -18.789946) (xy 398.289819 -18.767291) (xy 398.342142 -18.751926)
			(xy 398.396118 -18.744163) (xy 398.423384 -18.743676) (xy 399.286984 -18.743676) (xy 399.314258 -18.744062)
			(xy 399.368252 -18.751824) (xy 399.420592 -18.76719) (xy 399.470212 -18.789849) (xy 399.516103 -18.819339)
			(xy 399.557329 -18.85506) (xy 399.593051 -18.896285) (xy 399.622543 -18.942174) (xy 399.645204 -18.991793)
			(xy 399.660573 -19.044132) (xy 399.668336 -19.098126) (xy 399.668336 -19.152666) (xy 403.630162 -19.152666)
			(xy 403.630162 -19.098134) (xy 403.637923 -19.044157) (xy 403.653286 -18.991834) (xy 403.675939 -18.94223)
			(xy 403.70542 -18.896354) (xy 403.74113 -18.855141) (xy 403.782342 -18.81943) (xy 403.828216 -18.789946)
			(xy 403.877819 -18.767291) (xy 403.930142 -18.751926) (xy 403.984118 -18.744163) (xy 404.011384 -18.743676)
			(xy 404.874984 -18.743676) (xy 404.902258 -18.744062) (xy 404.956252 -18.751824) (xy 405.008592 -18.76719)
			(xy 405.058212 -18.789849) (xy 405.104103 -18.819339) (xy 405.145329 -18.85506) (xy 405.181051 -18.896285)
			(xy 405.210543 -18.942174) (xy 405.233204 -18.991793) (xy 405.248573 -19.044132) (xy 405.256336 -19.098126)
			(xy 405.256336 -19.152666) (xy 409.218162 -19.152666) (xy 409.218162 -19.098134) (xy 409.225923 -19.044157)
			(xy 409.241286 -18.991834) (xy 409.263939 -18.94223) (xy 409.29342 -18.896354) (xy 409.32913 -18.855141)
			(xy 409.370342 -18.81943) (xy 409.416216 -18.789946) (xy 409.465819 -18.767291) (xy 409.518142 -18.751926)
			(xy 409.572118 -18.744163) (xy 409.599384 -18.743676) (xy 410.462984 -18.743676) (xy 410.490258 -18.744062)
			(xy 410.544252 -18.751824) (xy 410.596592 -18.76719) (xy 410.646212 -18.789849) (xy 410.692103 -18.819339)
			(xy 410.733329 -18.85506) (xy 410.769051 -18.896285) (xy 410.798543 -18.942174) (xy 410.821204 -18.991793)
			(xy 410.836573 -19.044132) (xy 410.844336 -19.098126) (xy 410.844336 -19.152667) (xy 415.111962 -19.152667)
			(xy 415.111962 -19.098133) (xy 415.119723 -19.044155) (xy 415.135087 -18.991831) (xy 415.157741 -18.942226)
			(xy 415.187224 -18.896349) (xy 415.222936 -18.855136) (xy 415.264149 -18.819424) (xy 415.310026 -18.789941)
			(xy 415.359631 -18.767287) (xy 415.411955 -18.751923) (xy 415.465933 -18.744162) (xy 415.4932 -18.743676)
			(xy 416.3568 -18.743676) (xy 416.384072 -18.744087) (xy 416.438061 -18.751849) (xy 416.490396 -18.767216)
			(xy 416.540011 -18.789874) (xy 416.585896 -18.819363) (xy 416.627118 -18.855082) (xy 416.662837 -18.896304)
			(xy 416.692326 -18.942189) (xy 416.714984 -18.991804) (xy 416.730351 -19.044139) (xy 416.738113 -19.098128)
			(xy 416.738113 -19.152667) (xy 420.699962 -19.152667) (xy 420.699962 -19.098133) (xy 420.707723 -19.044155)
			(xy 420.723087 -18.991831) (xy 420.745741 -18.942226) (xy 420.775224 -18.896349) (xy 420.810936 -18.855136)
			(xy 420.852149 -18.819424) (xy 420.898026 -18.789941) (xy 420.947631 -18.767287) (xy 420.999955 -18.751923)
			(xy 421.053933 -18.744162) (xy 421.0812 -18.743676) (xy 421.9448 -18.743676) (xy 421.972072 -18.744087)
			(xy 422.026061 -18.751849) (xy 422.078396 -18.767216) (xy 422.128011 -18.789874) (xy 422.173896 -18.819363)
			(xy 422.215118 -18.855082) (xy 422.250837 -18.896304) (xy 422.280326 -18.942189) (xy 422.302984 -18.991804)
			(xy 422.318351 -19.044139) (xy 422.326113 -19.098128) (xy 422.326113 -19.15267) (xy 426.32194 -19.15267)
			(xy 426.32194 -19.09813) (xy 426.329702 -19.044145) (xy 426.345068 -18.991815) (xy 426.367726 -18.942204)
			(xy 426.397214 -18.896324) (xy 426.432932 -18.855107) (xy 426.474152 -18.819393) (xy 426.520036 -18.789909)
			(xy 426.569649 -18.767256) (xy 426.621981 -18.751894) (xy 426.675966 -18.744137) (xy 426.703236 -18.743676)
			(xy 427.566836 -18.743676) (xy 427.594106 -18.744089) (xy 427.648091 -18.751856) (xy 427.700422 -18.767226)
			(xy 427.750032 -18.789886) (xy 427.795913 -18.819376) (xy 427.837131 -18.855095) (xy 427.872846 -18.896315)
			(xy 427.902331 -18.942199) (xy 427.924987 -18.991812) (xy 427.940352 -19.044144) (xy 427.948114 -19.09813)
			(xy 427.948114 -19.15267) (xy 431.90994 -19.15267) (xy 431.90994 -19.09813) (xy 431.917702 -19.044145)
			(xy 431.933068 -18.991815) (xy 431.955726 -18.942204) (xy 431.985214 -18.896324) (xy 432.020932 -18.855107)
			(xy 432.062152 -18.819393) (xy 432.108036 -18.789909) (xy 432.157649 -18.767256) (xy 432.209981 -18.751894)
			(xy 432.263966 -18.744137) (xy 432.291236 -18.743676) (xy 433.154836 -18.743676) (xy 433.182106 -18.744089)
			(xy 433.236091 -18.751856) (xy 433.288422 -18.767226) (xy 433.338032 -18.789886) (xy 433.383913 -18.819376)
			(xy 433.425131 -18.855095) (xy 433.460846 -18.896315) (xy 433.490331 -18.942199) (xy 433.512987 -18.991812)
			(xy 433.528352 -19.044144) (xy 433.536114 -19.09813) (xy 433.536114 -19.15267) (xy 433.528352 -19.206656)
			(xy 433.512987 -19.258988) (xy 433.490331 -19.308601) (xy 433.460846 -19.354485) (xy 433.425131 -19.395705)
			(xy 433.383913 -19.431424) (xy 433.338032 -19.460914) (xy 433.288422 -19.483574) (xy 433.236091 -19.498944)
			(xy 433.182106 -19.506711) (xy 433.154836 -19.5072) (xy 432.291236 -19.5072) (xy 432.263966 -19.506663)
			(xy 432.209981 -19.498906) (xy 432.157649 -19.483544) (xy 432.108036 -19.460891) (xy 432.062152 -19.431407)
			(xy 432.020932 -19.395693) (xy 431.985214 -19.354476) (xy 431.955726 -19.308596) (xy 431.933068 -19.258985)
			(xy 431.917702 -19.206655) (xy 431.90994 -19.15267) (xy 427.948114 -19.15267) (xy 427.940352 -19.206656)
			(xy 427.924987 -19.258988) (xy 427.902331 -19.308601) (xy 427.872846 -19.354485) (xy 427.837131 -19.395705)
			(xy 427.795913 -19.431424) (xy 427.750032 -19.460914) (xy 427.700422 -19.483574) (xy 427.648091 -19.498944)
			(xy 427.594106 -19.506711) (xy 427.566836 -19.5072) (xy 426.703236 -19.5072) (xy 426.675966 -19.506663)
			(xy 426.621981 -19.498906) (xy 426.569649 -19.483544) (xy 426.520036 -19.460891) (xy 426.474152 -19.431407)
			(xy 426.432932 -19.395693) (xy 426.397214 -19.354476) (xy 426.367726 -19.308596) (xy 426.345068 -19.258985)
			(xy 426.329702 -19.206655) (xy 426.32194 -19.15267) (xy 422.326113 -19.15267) (xy 422.326113 -19.152672)
			(xy 422.318351 -19.206661) (xy 422.302984 -19.258996) (xy 422.280326 -19.308611) (xy 422.250837 -19.354496)
			(xy 422.215118 -19.395718) (xy 422.173896 -19.431437) (xy 422.128011 -19.460926) (xy 422.078396 -19.483584)
			(xy 422.026061 -19.498951) (xy 421.972072 -19.506713) (xy 421.9448 -19.5072) (xy 421.0812 -19.5072)
			(xy 421.053933 -19.506638) (xy 420.999955 -19.498877) (xy 420.947631 -19.483513) (xy 420.898026 -19.460859)
			(xy 420.852149 -19.431376) (xy 420.810936 -19.395664) (xy 420.775224 -19.354451) (xy 420.745741 -19.308574)
			(xy 420.723087 -19.258969) (xy 420.707723 -19.206645) (xy 420.699962 -19.152667) (xy 416.738113 -19.152667)
			(xy 416.738113 -19.152672) (xy 416.730351 -19.206661) (xy 416.714984 -19.258996) (xy 416.692326 -19.308611)
			(xy 416.662837 -19.354496) (xy 416.627118 -19.395718) (xy 416.585896 -19.431437) (xy 416.540011 -19.460926)
			(xy 416.490396 -19.483584) (xy 416.438061 -19.498951) (xy 416.384072 -19.506713) (xy 416.3568 -19.5072)
			(xy 415.4932 -19.5072) (xy 415.465933 -19.506638) (xy 415.411955 -19.498877) (xy 415.359631 -19.483513)
			(xy 415.310026 -19.460859) (xy 415.264149 -19.431376) (xy 415.222936 -19.395664) (xy 415.187224 -19.354451)
			(xy 415.157741 -19.308574) (xy 415.135087 -19.258969) (xy 415.119723 -19.206645) (xy 415.111962 -19.152667)
			(xy 410.844336 -19.152667) (xy 410.844336 -19.152674) (xy 410.836573 -19.206668) (xy 410.821204 -19.259007)
			(xy 410.798543 -19.308626) (xy 410.769051 -19.354515) (xy 410.733329 -19.39574) (xy 410.692103 -19.431461)
			(xy 410.646212 -19.460951) (xy 410.596592 -19.48361) (xy 410.544252 -19.498976) (xy 410.490258 -19.506738)
			(xy 410.462984 -19.5072) (xy 409.599384 -19.5072) (xy 409.572118 -19.506637) (xy 409.518142 -19.498874)
			(xy 409.465819 -19.483509) (xy 409.416216 -19.460854) (xy 409.370342 -19.43137) (xy 409.32913 -19.395659)
			(xy 409.29342 -19.354446) (xy 409.263939 -19.30857) (xy 409.241286 -19.258966) (xy 409.225923 -19.206643)
			(xy 409.218162 -19.152666) (xy 405.256336 -19.152666) (xy 405.256336 -19.152674) (xy 405.248573 -19.206668)
			(xy 405.233204 -19.259007) (xy 405.210543 -19.308626) (xy 405.181051 -19.354515) (xy 405.145329 -19.39574)
			(xy 405.104103 -19.431461) (xy 405.058212 -19.460951) (xy 405.008592 -19.48361) (xy 404.956252 -19.498976)
			(xy 404.902258 -19.506738) (xy 404.874984 -19.5072) (xy 404.011384 -19.5072) (xy 403.984118 -19.506637)
			(xy 403.930142 -19.498874) (xy 403.877819 -19.483509) (xy 403.828216 -19.460854) (xy 403.782342 -19.43137)
			(xy 403.74113 -19.395659) (xy 403.70542 -19.354446) (xy 403.675939 -19.30857) (xy 403.653286 -19.258966)
			(xy 403.637923 -19.206643) (xy 403.630162 -19.152666) (xy 399.668336 -19.152666) (xy 399.668336 -19.152674)
			(xy 399.660573 -19.206668) (xy 399.645204 -19.259007) (xy 399.622543 -19.308626) (xy 399.593051 -19.354515)
			(xy 399.557329 -19.39574) (xy 399.516103 -19.431461) (xy 399.470212 -19.460951) (xy 399.420592 -19.48361)
			(xy 399.368252 -19.498976) (xy 399.314258 -19.506738) (xy 399.286984 -19.5072) (xy 398.423384 -19.5072)
			(xy 398.396118 -19.506637) (xy 398.342142 -19.498874) (xy 398.289819 -19.483509) (xy 398.240216 -19.460854)
			(xy 398.194342 -19.43137) (xy 398.15313 -19.395659) (xy 398.11742 -19.354446) (xy 398.087939 -19.30857)
			(xy 398.065286 -19.258966) (xy 398.049923 -19.206643) (xy 398.042162 -19.152666) (xy 394.080336 -19.152666)
			(xy 394.080336 -19.152674) (xy 394.072573 -19.206668) (xy 394.057204 -19.259007) (xy 394.034543 -19.308626)
			(xy 394.005051 -19.354515) (xy 393.969329 -19.39574) (xy 393.928103 -19.431461) (xy 393.882212 -19.460951)
			(xy 393.832592 -19.48361) (xy 393.780252 -19.498976) (xy 393.726258 -19.506738) (xy 393.698984 -19.5072)
			(xy 392.835384 -19.5072) (xy 392.808118 -19.506637) (xy 392.754142 -19.498874) (xy 392.701819 -19.483509)
			(xy 392.652216 -19.460854) (xy 392.606342 -19.43137) (xy 392.56513 -19.395659) (xy 392.52942 -19.354446)
			(xy 392.499939 -19.30857) (xy 392.477286 -19.258966) (xy 392.461923 -19.206643) (xy 392.454162 -19.152666)
			(xy 385.128663 -19.152666) (xy 385.236252 -19.301971) (xy 385.349919 -19.473441) (xy 385.456809 -19.649214)
			(xy 385.55676 -19.829024) (xy 385.649619 -20.012597) (xy 385.735246 -20.199653) (xy 385.813508 -20.389908)
			(xy 385.884289 -20.583071) (xy 385.947479 -20.778849) (xy 386.002982 -20.976943) (xy 386.050714 -21.177052)
			(xy 386.090603 -21.37887) (xy 386.122587 -21.582092) (xy 386.146617 -21.786406) (xy 386.162658 -21.991502)
			(xy 386.170684 -22.197069) (xy 386.171186 -22.29993) (xy 459.52817 -22.29993) (xy 459.532184 -22.094246)
			(xy 459.54422 -21.888876) (xy 459.564259 -21.684132) (xy 459.592272 -21.480325) (xy 459.628215 -21.277766)
			(xy 459.672034 -21.076764) (xy 459.723661 -20.877625) (xy 459.783019 -20.680652) (xy 459.850017 -20.486144)
			(xy 459.924553 -20.294399) (xy 460.006513 -20.105708) (xy 460.095773 -19.920358) (xy 460.192196 -19.738632)
			(xy 460.295637 -19.560806) (xy 460.405936 -19.387152) (xy 460.522927 -19.217933) (xy 460.646431 -19.053407)
			(xy 460.77626 -18.893826) (xy 460.912217 -18.739431) (xy 461.054094 -18.590459) (xy 461.201675 -18.447135)
			(xy 461.354736 -18.309679) (xy 461.513043 -18.178299) (xy 461.676356 -18.053196) (xy 461.844425 -17.934559)
			(xy 462.016995 -17.822571) (xy 462.193803 -17.7174) (xy 462.37458 -17.619209) (xy 462.55905 -17.528145)
			(xy 462.746932 -17.444348) (xy 462.937942 -17.367945) (xy 463.131786 -17.299052) (xy 463.328171 -17.237775)
			(xy 463.526797 -17.184207) (xy 463.727362 -17.13843) (xy 463.92956 -17.100512) (xy 464.133084 -17.070513)
			(xy 464.337623 -17.048476) (xy 464.542866 -17.034437) (xy 464.748501 -17.028417) (xy 464.954214 -17.030424)
			(xy 465.159692 -17.040456) (xy 465.364622 -17.058497) (xy 465.568692 -17.08452) (xy 465.771592 -17.118485)
			(xy 465.973012 -17.16034) (xy 466.172645 -17.210022) (xy 466.370188 -17.267456) (xy 466.56534 -17.332553)
			(xy 466.757804 -17.405214) (xy 466.947286 -17.48533) (xy 467.133497 -17.572777) (xy 467.316156 -17.667423)
			(xy 467.494982 -17.769123) (xy 467.669704 -17.877723) (xy 467.840057 -17.993058) (xy 468.005779 -18.114951)
			(xy 468.16662 -18.243217) (xy 468.322333 -18.37766) (xy 468.472683 -18.518077) (xy 468.61744 -18.664253)
			(xy 468.756383 -18.815965) (xy 468.889301 -18.972983) (xy 469.015992 -19.135068) (xy 469.136262 -19.301971)
			(xy 469.249929 -19.473441) (xy 469.356819 -19.649214) (xy 469.45677 -19.829024) (xy 469.549629 -20.012597)
			(xy 469.635256 -20.199653) (xy 469.713518 -20.389908) (xy 469.784299 -20.583071) (xy 469.847489 -20.778849)
			(xy 469.902992 -20.976943) (xy 469.950724 -21.177052) (xy 469.990613 -21.37887) (xy 470.022597 -21.582092)
			(xy 470.046627 -21.786406) (xy 470.062668 -21.991502) (xy 470.070694 -22.197069) (xy 470.071196 -22.29993)
			(xy 470.070694 -22.402791) (xy 470.062668 -22.608358) (xy 470.046627 -22.813454) (xy 470.022597 -23.017768)
			(xy 469.990613 -23.22099) (xy 469.950724 -23.422808) (xy 469.902992 -23.622917) (xy 469.847489 -23.821011)
			(xy 469.784299 -24.016789) (xy 469.713518 -24.209952) (xy 469.635256 -24.400207) (xy 469.549629 -24.587263)
			(xy 469.45677 -24.770836) (xy 469.356819 -24.950646) (xy 469.249929 -25.126419) (xy 469.136262 -25.297889)
			(xy 469.015992 -25.464792) (xy 468.889301 -25.626877) (xy 468.756383 -25.783895) (xy 468.61744 -25.935607)
			(xy 468.472683 -26.081783) (xy 468.322333 -26.2222) (xy 468.16662 -26.356643) (xy 468.005779 -26.484909)
			(xy 467.840057 -26.606802) (xy 467.669704 -26.722137) (xy 467.494982 -26.830737) (xy 467.316156 -26.932437)
			(xy 467.133497 -27.027083) (xy 466.947286 -27.11453) (xy 466.757804 -27.194646) (xy 466.56534 -27.267307)
			(xy 466.370188 -27.332404) (xy 466.172645 -27.389838) (xy 465.973012 -27.43952) (xy 465.771592 -27.481375)
			(xy 465.568692 -27.51534) (xy 465.364622 -27.541363) (xy 465.159692 -27.559404) (xy 464.954214 -27.569436)
			(xy 464.748501 -27.571443) (xy 464.542866 -27.565423) (xy 464.337623 -27.551384) (xy 464.133084 -27.529347)
			(xy 463.92956 -27.499348) (xy 463.727362 -27.46143) (xy 463.526797 -27.415653) (xy 463.328171 -27.362085)
			(xy 463.131786 -27.300808) (xy 462.937942 -27.231915) (xy 462.746932 -27.155512) (xy 462.55905 -27.071715)
			(xy 462.37458 -26.980651) (xy 462.193803 -26.88246) (xy 462.016995 -26.777289) (xy 461.844425 -26.665301)
			(xy 461.676356 -26.546664) (xy 461.513043 -26.421561) (xy 461.354736 -26.290181) (xy 461.201675 -26.152725)
			(xy 461.054094 -26.009401) (xy 460.912217 -25.860429) (xy 460.77626 -25.706034) (xy 460.646431 -25.546453)
			(xy 460.522927 -25.381927) (xy 460.405936 -25.212708) (xy 460.295637 -25.039054) (xy 460.192196 -24.861228)
			(xy 460.095773 -24.679502) (xy 460.006513 -24.494152) (xy 459.924553 -24.305461) (xy 459.850017 -24.113716)
			(xy 459.783019 -23.919208) (xy 459.723661 -23.722235) (xy 459.672034 -23.523096) (xy 459.628215 -23.322094)
			(xy 459.592272 -23.119535) (xy 459.564259 -22.915728) (xy 459.54422 -22.710984) (xy 459.532184 -22.505614)
			(xy 459.52817 -22.29993) (xy 386.171186 -22.29993) (xy 386.170684 -22.402791) (xy 386.162658 -22.608358)
			(xy 386.146617 -22.813454) (xy 386.122587 -23.017768) (xy 386.090603 -23.22099) (xy 386.050714 -23.422808)
			(xy 386.002982 -23.622917) (xy 385.947479 -23.821011) (xy 385.884289 -24.016789) (xy 385.813508 -24.209952)
			(xy 385.735246 -24.400207) (xy 385.649619 -24.587263) (xy 385.55676 -24.770836) (xy 385.456809 -24.950646)
			(xy 385.349919 -25.126419) (xy 385.236252 -25.297889) (xy 385.115982 -25.464792) (xy 385.1132 -25.468351)
			(xy 388.406603 -25.468351) (xy 388.406603 -25.413849) (xy 388.41436 -25.359901) (xy 388.429716 -25.307607)
			(xy 388.452359 -25.25803) (xy 388.481827 -25.212181) (xy 388.517521 -25.170992) (xy 388.558713 -25.135303)
			(xy 388.604565 -25.10584) (xy 388.654144 -25.083202) (xy 388.70644 -25.067852) (xy 388.760389 -25.0601)
			(xy 388.78764 -25.05964) (xy 389.65124 -25.05964) (xy 389.678493 -25.060033) (xy 389.732443 -25.067795)
			(xy 389.78474 -25.083155) (xy 389.834318 -25.105802) (xy 389.880169 -25.135273) (xy 389.92136 -25.170969)
			(xy 389.957051 -25.212163) (xy 389.986518 -25.258017) (xy 390.009159 -25.307598) (xy 390.024514 -25.359896)
			(xy 390.03227 -25.413847) (xy 390.03227 -25.468353) (xy 390.024514 -25.522304) (xy 390.009159 -25.574602)
			(xy 389.986518 -25.624183) (xy 389.957051 -25.670037) (xy 389.92136 -25.711231) (xy 389.880169 -25.746927)
			(xy 389.834318 -25.776398) (xy 389.78474 -25.799045) (xy 389.732443 -25.814405) (xy 389.678493 -25.822167)
			(xy 389.65124 -25.822656) (xy 388.78764 -25.822656) (xy 388.760389 -25.8221) (xy 388.70644 -25.814348)
			(xy 388.654144 -25.798998) (xy 388.604565 -25.77636) (xy 388.558713 -25.746897) (xy 388.517521 -25.711208)
			(xy 388.481827 -25.670019) (xy 388.452359 -25.62417) (xy 388.429716 -25.574593) (xy 388.41436 -25.522299)
			(xy 388.406603 -25.468351) (xy 385.1132 -25.468351) (xy 384.989291 -25.626877) (xy 384.856373 -25.783895)
			(xy 384.71743 -25.935607) (xy 384.572673 -26.081783) (xy 384.422323 -26.2222) (xy 384.26661 -26.356643)
			(xy 384.105769 -26.484909) (xy 383.940047 -26.606802) (xy 383.769694 -26.722137) (xy 383.594972 -26.830737)
			(xy 383.416146 -26.932437) (xy 383.233487 -27.027083) (xy 383.047276 -27.11453) (xy 382.857794 -27.194646)
			(xy 382.66533 -27.267307) (xy 382.470178 -27.332404) (xy 382.272635 -27.389838) (xy 382.073002 -27.43952)
			(xy 381.871582 -27.481375) (xy 381.668682 -27.51534) (xy 381.464612 -27.541363) (xy 381.259682 -27.559404)
			(xy 381.054204 -27.569436) (xy 380.848491 -27.571443) (xy 380.642856 -27.565423) (xy 380.437613 -27.551384)
			(xy 380.233074 -27.529347) (xy 380.02955 -27.499348) (xy 379.827352 -27.46143) (xy 379.626787 -27.415653)
			(xy 379.428161 -27.362085) (xy 379.231776 -27.300808) (xy 379.037932 -27.231915) (xy 378.846922 -27.155512)
			(xy 378.65904 -27.071715) (xy 378.47457 -26.980651) (xy 378.293793 -26.88246) (xy 378.116985 -26.777289)
			(xy 377.944415 -26.665301) (xy 377.776346 -26.546664) (xy 377.613033 -26.421561) (xy 377.454726 -26.290181)
			(xy 377.301665 -26.152725) (xy 377.154084 -26.009401) (xy 377.012207 -25.860429) (xy 376.87625 -25.706034)
			(xy 376.746421 -25.546453) (xy 376.622917 -25.381927) (xy 376.505926 -25.212708) (xy 376.395627 -25.039054)
			(xy 376.292186 -24.861228) (xy 376.195763 -24.679502) (xy 376.106503 -24.494152) (xy 376.024543 -24.305461)
			(xy 375.950007 -24.113716) (xy 375.883009 -23.919208) (xy 375.823651 -23.722235) (xy 375.772024 -23.523096)
			(xy 375.728205 -23.322094) (xy 375.692262 -23.119535) (xy 375.664249 -22.915728) (xy 375.64421 -22.710984)
			(xy 375.632174 -22.505614) (xy 375.62816 -22.29993) (xy 270.921427 -22.29993) (xy 270.917463 -22.504313)
			(xy 270.905575 -22.708418) (xy 270.885782 -22.911909) (xy 270.858113 -23.11448) (xy 270.822611 -23.315825)
			(xy 270.779328 -23.515643) (xy 270.728329 -23.713631) (xy 270.669692 -23.909494) (xy 270.603504 -24.102935)
			(xy 270.529865 -24.293664) (xy 270.448886 -24.481395) (xy 270.360689 -24.665844) (xy 270.265406 -24.846735)
			(xy 270.16318 -25.023795) (xy 270.054166 -25.196758) (xy 269.938527 -25.365365) (xy 269.816437 -25.52936)
			(xy 269.68808 -25.688498) (xy 269.553649 -25.842539) (xy 269.413346 -25.991252) (xy 269.267383 -26.134412)
			(xy 269.115978 -26.271805) (xy 268.959359 -26.403224) (xy 268.797762 -26.528471) (xy 268.63143 -26.647358)
			(xy 268.460614 -26.759706) (xy 268.28557 -26.865347) (xy 268.106561 -26.96412) (xy 267.923856 -27.055878)
			(xy 267.737731 -27.140482) (xy 267.548466 -27.217806) (xy 267.356345 -27.287733) (xy 267.161656 -27.350157)
			(xy 266.964694 -27.404986) (xy 266.765754 -27.452136) (xy 266.565135 -27.491537) (xy 266.363139 -27.523128)
			(xy 266.16007 -27.546864) (xy 265.956233 -27.562708) (xy 265.751936 -27.570636) (xy 265.64971 -27.571192)
			(xy 265.546225 -27.570682) (xy 265.339414 -27.562554) (xy 265.133081 -27.546315) (xy 264.927545 -27.521988)
			(xy 264.723122 -27.489612) (xy 264.520128 -27.449237) (xy 264.318875 -27.400924) (xy 264.119673 -27.344749)
			(xy 263.922831 -27.280797) (xy 263.72865 -27.209168) (xy 263.537431 -27.129972) (xy 263.349467 -27.043331)
			(xy 263.16505 -26.949378) (xy 262.984463 -26.848258) (xy 262.807984 -26.740128) (xy 262.635886 -26.625154)
			(xy 262.468434 -26.503512) (xy 262.305885 -26.375392) (xy 262.148492 -26.240989) (xy 261.996495 -26.100512)
			(xy 261.85013 -25.954176) (xy 261.709622 -25.802208) (xy 261.575187 -25.644841) (xy 261.447033 -25.482319)
			(xy 261.325358 -25.314892) (xy 261.210349 -25.142817) (xy 261.102183 -24.96636) (xy 261.001027 -24.785793)
			(xy 260.907036 -24.601395) (xy 260.820357 -24.41345) (xy 260.741122 -24.222246) (xy 260.669453 -24.02808)
			(xy 260.605462 -23.83125) (xy 260.549246 -23.63206) (xy 260.524498 -23.531576) (xy 260.520567 -23.517303)
			(xy 260.505726 -23.491703) (xy 260.48417 -23.471431) (xy 260.457708 -23.458187) (xy 260.42856 -23.453083)
			(xy 260.399172 -23.456548) (xy 260.372011 -23.46829) (xy 260.349354 -23.487324) (xy 260.333102 -23.512053)
			(xy 260.324621 -23.540402) (xy 260.324092 -23.555198) (xy 260.324092 -33.275016) (xy 260.323592 -33.358891)
			(xy 260.31561 -33.52645) (xy 260.299664 -33.693439) (xy 260.27579 -33.859481) (xy 260.244042 -34.024198)
			(xy 260.204493 -34.187219) (xy 260.157232 -34.348173) (xy 260.102366 -34.506696) (xy 260.04002 -34.662429)
			(xy 259.970334 -34.815018) (xy 259.893466 -34.964119) (xy 259.809591 -35.109394) (xy 259.718898 -35.250513)
			(xy 259.621594 -35.387158) (xy 259.517898 -35.519017) (xy 259.408045 -35.645793) (xy 259.292284 -35.767199)
			(xy 259.170878 -35.882958) (xy 259.044102 -35.99281) (xy 258.912242 -36.096506) (xy 258.775597 -36.193809)
			(xy 258.634477 -36.284501) (xy 258.489202 -36.368375) (xy 258.3401 -36.445242) (xy 258.18751 -36.514927)
			(xy 258.031777 -36.577273) (xy 257.873254 -36.632138) (xy 257.7123 -36.679398) (xy 257.549279 -36.718947)
			(xy 257.384561 -36.750693) (xy 257.218519 -36.774566) (xy 257.05153 -36.790511) (xy 256.883971 -36.798493)
			(xy 256.800096 -36.799012) (xy 225.300032 -36.799012) (xy 225.216156 -36.798522) (xy 225.048595 -36.790541)
			(xy 224.881603 -36.774597) (xy 224.715559 -36.750725) (xy 224.550839 -36.718979) (xy 224.387816 -36.679432)
			(xy 224.226859 -36.632172) (xy 224.068333 -36.577307) (xy 223.912598 -36.514961) (xy 223.760005 -36.445276)
			(xy 223.610901 -36.368409) (xy 223.465624 -36.284535) (xy 223.324502 -36.193842) (xy 223.187855 -36.096538)
			(xy 223.055993 -35.992842) (xy 222.929214 -35.882989) (xy 222.807806 -35.767228) (xy 222.692043 -35.645822)
			(xy 222.582189 -35.519044) (xy 222.478491 -35.387184) (xy 222.381184 -35.250538) (xy 222.29049 -35.109417)
			(xy 222.206614 -34.964141) (xy 222.129745 -34.815038) (xy 222.060058 -34.662446) (xy 221.99771 -34.506712)
			(xy 221.942843 -34.348187) (xy 221.895581 -34.187231) (xy 221.856031 -34.024208) (xy 221.824283 -33.859488)
			(xy 221.800409 -33.693445) (xy 221.784462 -33.526453) (xy 221.77648 -33.358892) (xy 221.776036 -33.275016)
			(xy 221.776036 -13.780008) (xy 221.775527 -13.748842) (xy 221.767392 -13.687042) (xy 221.751261 -13.626833)
			(xy 221.727409 -13.569244) (xy 221.696245 -13.515262) (xy 221.658302 -13.465808) (xy 221.614228 -13.42173)
			(xy 221.564778 -13.383782) (xy 221.510799 -13.352612) (xy 221.453212 -13.328754) (xy 221.393005 -13.312617)
			(xy 221.331206 -13.304476) (xy 221.30004 -13.304012) (xy 196.701918 -13.304012) (xy 196.617223 -13.303509)
			(xy 196.448027 -13.295372) (xy 196.279418 -13.279115) (xy 196.111785 -13.254776) (xy 195.945515 -13.222412)
			(xy 195.780992 -13.182097) (xy 195.618595 -13.133924) (xy 195.458701 -13.078004) (xy 195.301678 -13.014468)
			(xy 195.147888 -12.94346) (xy 194.997688 -12.865146) (xy 194.851424 -12.779706) (xy 194.709433 -12.687337)
			(xy 194.572044 -12.588254) (xy 194.439575 -12.482684) (xy 194.31233 -12.370871) (xy 194.190604 -12.253075)
			(xy 194.074678 -12.129566) (xy 193.96482 -12.000631) (xy 193.861283 -11.866566) (xy 193.764307 -11.727681)
			(xy 193.674115 -11.584298) (xy 193.632074 -11.510772) (xy 193.624643 -11.49858) (xy 193.604286 -11.478578)
			(xy 193.579189 -11.464991) (xy 193.551312 -11.458879) (xy 193.522832 -11.460722) (xy 193.495974 -11.470375)
			(xy 193.472837 -11.487083) (xy 193.455228 -11.509541) (xy 193.444521 -11.535996) (xy 193.44259 -11.550142)
			(xy 193.437496 -11.59417) (xy 193.420266 -11.681117) (xy 193.395141 -11.766119) (xy 193.362333 -11.848462)
			(xy 193.322118 -11.927452) (xy 193.274834 -12.002424) (xy 193.220879 -12.072749) (xy 193.160707 -12.137834)
			(xy 193.094825 -12.197131) (xy 193.023786 -12.250142) (xy 192.948188 -12.29642) (xy 192.868668 -12.335577)
			(xy 192.785895 -12.367282) (xy 192.700565 -12.391269) (xy 192.613395 -12.407337) (xy 192.52512 -12.415349)
			(xy 192.436483 -12.415239) (xy 192.348228 -12.407008) (xy 192.261099 -12.390724) (xy 192.175828 -12.366525)
			(xy 192.093134 -12.334614) (xy 192.013711 -12.29526) (xy 191.938229 -12.248794) (xy 191.867322 -12.195607)
			(xy 191.801587 -12.136146) (xy 191.741577 -12.070912) (xy 191.687797 -12.000454) (xy 191.640699 -11.925364)
			(xy 191.60068 -11.846275) (xy 191.568077 -11.763851) (xy 191.543163 -11.678787) (xy 191.526148 -11.591797)
			(xy 191.517177 -11.503614) (xy 191.516323 -11.414981) (xy 191.523594 -11.326642) (xy 191.53893 -11.239341)
			(xy 191.5622 -11.153812) (xy 191.59321 -11.070775) (xy 191.631698 -10.99093) (xy 191.677341 -10.914947)
			(xy 191.729754 -10.843466) (xy 191.788496 -10.777088) (xy 191.853074 -10.716372) (xy 191.922943 -10.661829)
			(xy 191.997516 -10.613918) (xy 192.076166 -10.573041) (xy 192.15823 -10.539543) (xy 192.243019 -10.513706)
			(xy 192.329818 -10.495747) (xy 192.417898 -10.485817) (xy 192.506517 -10.483999) (xy 192.59493 -10.49031)
			(xy 192.682393 -10.504695) (xy 192.768169 -10.527034) (xy 192.851538 -10.557139) (xy 192.931798 -10.594757)
			(xy 193.008272 -10.639571) (xy 193.080319 -10.691203) (xy 193.114168 -10.719816) (xy 193.125179 -10.728748)
			(xy 193.15087 -10.740713) (xy 193.17886 -10.745153) (xy 193.206993 -10.741725) (xy 193.233098 -10.730693)
			(xy 193.255164 -10.712909) (xy 193.271489 -10.689743) (xy 193.280814 -10.66298) (xy 193.282422 -10.634685)
			(xy 193.279776 -10.620756) (xy 193.260011 -10.538189) (xy 193.227481 -10.371539) (xy 193.20301 -10.203517)
			(xy 193.186654 -10.034511) (xy 193.178452 -9.864914) (xy 193.177922 -9.780016) (xy 193.177922 -6.803898)
			(xy 127.62611 -6.803898) (xy 127.62611 -9.560306) (xy 127.626547 -9.574024) (xy 127.633838 -9.600474)
			(xy 127.647916 -9.624022) (xy 127.667763 -9.642964) (xy 127.691942 -9.655929) (xy 127.718702 -9.661978)
			(xy 127.746107 -9.660673) (xy 127.772172 -9.652109) (xy 127.783844 -9.644888) (xy 127.82071 -9.621071)
			(xy 127.897991 -9.57945) (xy 127.978729 -9.545014) (xy 128.062259 -9.518045) (xy 128.147891 -9.498766)
			(xy 128.234919 -9.487338) (xy 128.322626 -9.483853) (xy 128.410286 -9.48834) (xy 128.497178 -9.500764)
			(xy 128.582584 -9.52102) (xy 128.6658 -9.548942) (xy 128.746139 -9.5843) (xy 128.822939 -9.626802)
			(xy 128.895565 -9.676097) (xy 128.963419 -9.731778) (xy 129.02594 -9.793387) (xy 129.082613 -9.860414)
			(xy 129.132971 -9.932308) (xy 129.176597 -10.008474) (xy 129.213133 -10.088284) (xy 129.242276 -10.171081)
			(xy 129.263786 -10.25618) (xy 129.266056 -10.270548) (xy 131.63909 -10.270548) (xy 131.63909 -10.216052)
			(xy 131.646845 -10.16211) (xy 131.662198 -10.10982) (xy 131.684835 -10.060247) (xy 131.714296 -10.014401)
			(xy 131.749982 -9.973213) (xy 131.791165 -9.937522) (xy 131.837009 -9.908056) (xy 131.886579 -9.885413)
			(xy 131.938866 -9.870055) (xy 131.992808 -9.862293) (xy 132.020056 -9.861804) (xy 132.883656 -9.861804)
			(xy 132.910912 -9.86224) (xy 132.964869 -9.869992) (xy 133.017174 -9.885345) (xy 133.066761 -9.907985)
			(xy 133.112622 -9.937453) (xy 133.153821 -9.973148) (xy 133.18952 -10.014343) (xy 133.218993 -10.0602)
			(xy 133.24164 -10.109785) (xy 133.256999 -10.162088) (xy 133.264757 -10.216044) (xy 133.264757 -10.270556)
			(xy 133.256999 -10.324512) (xy 133.24164 -10.376815) (xy 133.218993 -10.4264) (xy 133.18952 -10.472257)
			(xy 133.153821 -10.513452) (xy 133.112622 -10.549147) (xy 133.066761 -10.578615) (xy 133.017174 -10.601255)
			(xy 132.964869 -10.616608) (xy 132.910912 -10.62436) (xy 132.883656 -10.62482) (xy 132.020056 -10.62482)
			(xy 131.992808 -10.624307) (xy 131.938866 -10.616545) (xy 131.886579 -10.601187) (xy 131.837009 -10.578544)
			(xy 131.791165 -10.549078) (xy 131.749982 -10.513387) (xy 131.714296 -10.472199) (xy 131.684835 -10.426353)
			(xy 131.662198 -10.37678) (xy 131.646845 -10.32449) (xy 131.63909 -10.270548) (xy 129.266056 -10.270548)
			(xy 129.277485 -10.342879) (xy 129.283261 -10.430465) (xy 129.281067 -10.518213) (xy 129.270919 -10.6054)
			(xy 129.252902 -10.691306) (xy 129.227164 -10.775224) (xy 129.193919 -10.856459) (xy 129.153439 -10.934343)
			(xy 129.106059 -11.008233) (xy 129.087143 -11.032553) (xy 168.158867 -11.032553) (xy 168.158867 -10.978047)
			(xy 168.166625 -10.924096) (xy 168.181981 -10.871798) (xy 168.204625 -10.822218) (xy 168.234094 -10.776365)
			(xy 168.269789 -10.735173) (xy 168.310983 -10.699481) (xy 168.356837 -10.670014) (xy 168.406419 -10.647374)
			(xy 168.458717 -10.63202) (xy 168.512669 -10.624266) (xy 168.539922 -10.623804) (xy 169.403522 -10.623804)
			(xy 169.430773 -10.624267) (xy 169.48472 -10.632027) (xy 169.537014 -10.647384) (xy 169.58659 -10.670027)
			(xy 169.632439 -10.699495) (xy 169.673628 -10.735188) (xy 169.709318 -10.776379) (xy 169.738783 -10.822229)
			(xy 169.761424 -10.871807) (xy 169.776778 -10.924101) (xy 169.784534 -10.978049) (xy 169.784534 -11.032551)
			(xy 169.776778 -11.086499) (xy 169.761424 -11.138793) (xy 169.738783 -11.188371) (xy 169.709318 -11.234221)
			(xy 169.673628 -11.275412) (xy 169.632439 -11.311105) (xy 169.58659 -11.340573) (xy 169.537014 -11.363216)
			(xy 169.48472 -11.378573) (xy 169.430773 -11.386333) (xy 169.403522 -11.38682) (xy 168.539922 -11.38682)
			(xy 168.512669 -11.386334) (xy 168.458717 -11.37858) (xy 168.406419 -11.363226) (xy 168.356837 -11.340586)
			(xy 168.310983 -11.311119) (xy 168.269789 -11.275427) (xy 168.234094 -11.234235) (xy 168.204625 -11.188382)
			(xy 168.181981 -11.138802) (xy 168.166625 -11.086504) (xy 168.158867 -11.032553) (xy 129.087143 -11.032553)
			(xy 129.05217 -11.077519) (xy 128.992217 -11.141629) (xy 128.926694 -11.200035) (xy 128.856141 -11.252255)
			(xy 128.781141 -11.297857) (xy 128.702313 -11.336466) (xy 128.620307 -11.367764) (xy 128.535799 -11.391491)
			(xy 128.449487 -11.407452) (xy 128.362083 -11.415515) (xy 128.274307 -11.415615) (xy 128.186885 -11.40775)
			(xy 128.100537 -11.391984) (xy 128.015975 -11.368449) (xy 127.933898 -11.337338) (xy 127.854983 -11.298908)
			(xy 127.77988 -11.253476) (xy 127.709209 -11.201416) (xy 127.643553 -11.143159) (xy 127.583455 -11.079185)
			(xy 127.556006 -11.044936) (xy 127.546188 -11.033218) (xy 127.52109 -11.015788) (xy 127.491961 -11.006557)
			(xy 127.461404 -11.006351) (xy 127.432153 -11.015187) (xy 127.406822 -11.032277) (xy 127.387675 -11.056091)
			(xy 127.381508 -11.070082) (xy 127.350183 -11.148346) (xy 127.281032 -11.30211) (xy 127.204607 -11.452392)
			(xy 127.121082 -11.598846) (xy 127.030649 -11.741138) (xy 126.933515 -11.878943) (xy 126.829902 -12.011945)
			(xy 126.81237 -12.032356) (xy 166.354411 -12.032356) (xy 166.354411 -11.977844) (xy 166.362169 -11.923886)
			(xy 166.377527 -11.871582) (xy 166.400173 -11.821995) (xy 166.429645 -11.776137) (xy 166.465343 -11.734939)
			(xy 166.506541 -11.699241) (xy 166.552401 -11.66977) (xy 166.601987 -11.647125) (xy 166.654292 -11.631768)
			(xy 166.70825 -11.624011) (xy 166.735506 -11.623548) (xy 167.599106 -11.623548) (xy 167.626354 -11.624123)
			(xy 167.680295 -11.631879) (xy 167.732583 -11.647233) (xy 167.782153 -11.669872) (xy 167.827998 -11.699335)
			(xy 167.869182 -11.735022) (xy 167.904869 -11.776207) (xy 167.934331 -11.822052) (xy 167.956969 -11.871623)
			(xy 167.972322 -11.923911) (xy 167.980078 -11.977852) (xy 167.980078 -12.032348) (xy 167.980077 -12.032358)
			(xy 169.954311 -12.032358) (xy 169.954311 -11.977842) (xy 169.96207 -11.92388) (xy 169.97743 -11.871573)
			(xy 170.000079 -11.821984) (xy 170.029555 -11.776123) (xy 170.065258 -11.734924) (xy 170.106461 -11.699226)
			(xy 170.152326 -11.669756) (xy 170.201918 -11.647114) (xy 170.254227 -11.63176) (xy 170.30819 -11.624008)
			(xy 170.335448 -11.623548) (xy 171.199048 -11.623548) (xy 171.226294 -11.624125) (xy 171.28023 -11.631887)
			(xy 171.332513 -11.647244) (xy 171.382078 -11.669885) (xy 171.427917 -11.699349) (xy 171.469097 -11.735037)
			(xy 171.504779 -11.776221) (xy 171.534238 -11.822064) (xy 171.556873 -11.871632) (xy 171.572224 -11.923917)
			(xy 171.579978 -11.977854) (xy 171.579978 -12.032346) (xy 171.572224 -12.086283) (xy 171.556873 -12.138568)
			(xy 171.534238 -12.188136) (xy 171.504779 -12.233979) (xy 171.469097 -12.275163) (xy 171.427917 -12.310851)
			(xy 171.382078 -12.340315) (xy 171.332513 -12.362956) (xy 171.28023 -12.378313) (xy 171.226294 -12.386075)
			(xy 171.199048 -12.386564) (xy 170.335448 -12.386564) (xy 170.30819 -12.386192) (xy 170.254227 -12.37844)
			(xy 170.201918 -12.363086) (xy 170.152326 -12.340444) (xy 170.106461 -12.310974) (xy 170.065258 -12.275276)
			(xy 170.029555 -12.234077) (xy 170.000079 -12.188216) (xy 169.97743 -12.138627) (xy 169.96207 -12.08632)
			(xy 169.954311 -12.032358) (xy 167.980077 -12.032358) (xy 167.972322 -12.086289) (xy 167.956969 -12.138577)
			(xy 167.934331 -12.188148) (xy 167.904869 -12.233993) (xy 167.869182 -12.275178) (xy 167.827998 -12.310865)
			(xy 167.782153 -12.340328) (xy 167.732583 -12.362967) (xy 167.680295 -12.378321) (xy 167.626354 -12.386077)
			(xy 167.599106 -12.386564) (xy 166.735506 -12.386564) (xy 166.70825 -12.386189) (xy 166.654292 -12.378432)
			(xy 166.601987 -12.363075) (xy 166.552401 -12.34043) (xy 166.506541 -12.310959) (xy 166.465343 -12.275261)
			(xy 166.429645 -12.234063) (xy 166.400173 -12.188205) (xy 166.377527 -12.138618) (xy 166.362169 -12.086314)
			(xy 166.354411 -12.032356) (xy 126.81237 -12.032356) (xy 126.720046 -12.139839) (xy 126.6042 -12.262334)
			(xy 126.482628 -12.379148) (xy 126.355609 -12.490015) (xy 126.223433 -12.59468) (xy 126.086403 -12.692904)
			(xy 125.944832 -12.784463) (xy 125.799045 -12.869146) (xy 125.649374 -12.946761) (xy 125.496164 -13.017129)
			(xy 125.339763 -13.080089) (xy 125.18053 -13.135498) (xy 125.018829 -13.183228) (xy 124.855031 -13.22317)
			(xy 124.68951 -13.255234) (xy 124.522645 -13.279345) (xy 124.354818 -13.295448) (xy 124.186413 -13.303507)
			(xy 124.102114 -13.304012) (xy 83.70189 -13.304012) (xy 83.618015 -13.303513) (xy 83.450455 -13.29553)
			(xy 83.283465 -13.279584) (xy 83.117423 -13.255711) (xy 82.952705 -13.223964) (xy 82.789684 -13.184415)
			(xy 82.628729 -13.137154) (xy 82.470206 -13.082288) (xy 82.314472 -13.019942) (xy 82.161882 -12.950256)
			(xy 82.01278 -12.873388) (xy 81.867505 -12.789514) (xy 81.726385 -12.698821) (xy 81.58974 -12.601517)
			(xy 81.45788 -12.497821) (xy 81.331103 -12.387968) (xy 81.209696 -12.272208) (xy 81.093936 -12.150802)
			(xy 80.984083 -12.024025) (xy 80.880387 -11.892165) (xy 80.783082 -11.75552) (xy 80.69239 -11.6144)
			(xy 80.608514 -11.469125) (xy 80.531647 -11.320023) (xy 80.461961 -11.167433) (xy 80.399614 -11.0117)
			(xy 80.344748 -10.853176) (xy 80.297487 -10.692222) (xy 80.257938 -10.529201) (xy 80.22619 -10.364483)
			(xy 80.202316 -10.198441) (xy 80.18637 -10.031451) (xy 80.178388 -9.863891) (xy 80.177894 -9.780016)
			(xy 80.177894 -7.056628) (xy 80.177444 -7.042873) (xy 80.170105 -7.016359) (xy 80.155951 -6.992769)
			(xy 80.136011 -6.973816) (xy 80.111734 -6.960876) (xy 80.084883 -6.95489) (xy 80.057408 -6.956292)
			(xy 80.031306 -6.964981) (xy 80.019652 -6.9723) (xy 79.982471 -6.996608) (xy 79.904443 -7.039076)
			(xy 79.822844 -7.0742) (xy 79.738364 -7.101681) (xy 79.651718 -7.121287) (xy 79.563637 -7.132854)
			(xy 79.474866 -7.136282) (xy 79.386156 -7.131543) (xy 79.298255 -7.118678) (xy 79.211908 -7.097794)
			(xy 79.127843 -7.069069) (xy 79.046771 -7.032744) (xy 78.969379 -6.989128) (xy 78.896318 -6.938589)
			(xy 78.828208 -6.881553) (xy 78.765624 -6.818504) (xy 78.709095 -6.749973) (xy 78.659098 -6.676541)
			(xy 78.616056 -6.598827) (xy 78.580333 -6.517489) (xy 78.552231 -6.433214) (xy 78.531987 -6.346714)
			(xy 78.519773 -6.25872) (xy 78.515692 -6.169977) (xy 78.519777 -6.081234) (xy 78.531996 -5.993241)
			(xy 78.552243 -5.906742) (xy 78.580349 -5.822469) (xy 78.616076 -5.741132) (xy 78.659122 -5.66342)
			(xy 78.709122 -5.58999) (xy 78.765655 -5.521462) (xy 78.828242 -5.458416) (xy 78.896355 -5.401383)
			(xy 78.969417 -5.350847) (xy 79.046812 -5.307235) (xy 79.127885 -5.270915) (xy 79.211951 -5.242193)
			(xy 79.2983 -5.221313) (xy 79.386201 -5.208452) (xy 79.474912 -5.203718) (xy 79.563683 -5.20715)
			(xy 79.651763 -5.218721) (xy 79.738408 -5.238331) (xy 79.822887 -5.265816) (xy 79.904484 -5.300944)
			(xy 79.98251 -5.343416) (xy 80.019652 -5.367782) (xy 80.031322 -5.375072) (xy 80.057422 -5.383751)
			(xy 80.084892 -5.385149) (xy 80.111738 -5.379165) (xy 80.136013 -5.366232) (xy 80.155955 -5.347288)
			(xy 80.170118 -5.32371) (xy 80.177474 -5.297206) (xy 80.177894 -5.283454) (xy 80.177894 -1.524) (xy 14.626082 -1.524)
			(xy 14.626082 -4.377182) (xy 14.626518 -4.386931) (xy 14.633798 -4.405018) (xy 14.647311 -4.419073)
			(xy 14.665097 -4.42706) (xy 14.684579 -4.427821) (xy 14.6939 -4.424934) (xy 14.708886 -4.4196) (xy 14.715236 -4.41452)
			(xy 14.738096 -4.396994) (xy 14.773063 -4.371333) (xy 14.846818 -4.325685) (xy 14.92437 -4.286834)
			(xy 15.005094 -4.255093) (xy 15.088338 -4.230718) (xy 15.173432 -4.213906) (xy 15.259691 -4.204792)
			(xy 15.34642 -4.20345) (xy 15.43292 -4.209889) (xy 15.518494 -4.224059) (xy 15.602453 -4.245845)
			(xy 15.68412 -4.275071) (xy 15.762838 -4.311503) (xy 15.837971 -4.354846) (xy 15.908916 -4.404752)
			(xy 15.975099 -4.460818) (xy 16.035989 -4.522593) (xy 16.091095 -4.589579) (xy 16.139972 -4.661236)
			(xy 16.182226 -4.736987) (xy 16.217518 -4.816222) (xy 16.245563 -4.898303) (xy 16.266136 -4.982567)
			(xy 16.267242 -4.989901) (xy 20.44038 -4.989901) (xy 20.44038 -4.935399) (xy 20.448136 -4.881452)
			(xy 20.463491 -4.829158) (xy 20.486132 -4.779581) (xy 20.515597 -4.733731) (xy 20.551288 -4.692541)
			(xy 20.592478 -4.65685) (xy 20.638328 -4.627384) (xy 20.687904 -4.604742) (xy 20.740198 -4.589387)
			(xy 20.794145 -4.58163) (xy 20.821396 -4.581144) (xy 21.684996 -4.581144) (xy 21.712249 -4.581603)
			(xy 21.766201 -4.58936) (xy 21.818499 -4.604715) (xy 21.86808 -4.627358) (xy 21.913934 -4.656826)
			(xy 21.955128 -4.69252) (xy 21.990822 -4.733713) (xy 22.02029 -4.779566) (xy 22.042933 -4.829147)
			(xy 22.05829 -4.881445) (xy 22.066047 -4.935397) (xy 22.066047 -4.989901) (xy 24.04032 -4.989901)
			(xy 24.04032 -4.935399) (xy 24.048076 -4.881452) (xy 24.063431 -4.829157) (xy 24.086072 -4.779581)
			(xy 24.115538 -4.73373) (xy 24.151229 -4.692541) (xy 24.192419 -4.656849) (xy 24.238269 -4.627383)
			(xy 24.287846 -4.604742) (xy 24.34014 -4.589387) (xy 24.394087 -4.58163) (xy 24.421338 -4.581144)
			(xy 25.284938 -4.581144) (xy 25.312191 -4.581603) (xy 25.366143 -4.58936) (xy 25.418441 -4.604716)
			(xy 25.468021 -4.627358) (xy 25.513875 -4.656827) (xy 25.555068 -4.69252) (xy 25.590762 -4.733713)
			(xy 25.620231 -4.779567) (xy 25.642873 -4.829147) (xy 25.65823 -4.881446) (xy 25.665987 -4.935397)
			(xy 25.665987 -4.989903) (xy 25.66598 -4.989954) (xy 27.64023 -4.989954) (xy 27.64023 -4.935446)
			(xy 27.647987 -4.881493) (xy 27.663343 -4.829194) (xy 27.685985 -4.779612) (xy 27.715454 -4.733756)
			(xy 27.751147 -4.692562) (xy 27.79234 -4.656866) (xy 27.838194 -4.627395) (xy 27.887775 -4.60475)
			(xy 27.940074 -4.589391) (xy 27.994026 -4.581631) (xy 28.02128 -4.581144) (xy 28.88488 -4.581144)
			(xy 28.91213 -4.581702) (xy 28.966077 -4.589456) (xy 29.01837 -4.604808) (xy 29.067947 -4.627446)
			(xy 29.113797 -4.65691) (xy 29.154986 -4.692599) (xy 29.190678 -4.733787) (xy 29.220144 -4.779636)
			(xy 29.242785 -4.829211) (xy 29.25814 -4.881504) (xy 29.265897 -4.93545) (xy 29.265897 -4.98995)
			(xy 29.265896 -4.989954) (xy 31.24043 -4.989954) (xy 31.24043 -4.935446) (xy 31.248187 -4.881494)
			(xy 31.263543 -4.829195) (xy 31.286185 -4.779613) (xy 31.315653 -4.733758) (xy 31.351346 -4.692563)
			(xy 31.392538 -4.656867) (xy 31.438392 -4.627396) (xy 31.487972 -4.604751) (xy 31.540271 -4.589392)
			(xy 31.594222 -4.581632) (xy 31.621476 -4.581144) (xy 32.485076 -4.581144) (xy 32.512327 -4.581702)
			(xy 32.566273 -4.589455) (xy 32.618567 -4.604807) (xy 32.668144 -4.627445) (xy 32.713995 -4.656909)
			(xy 32.755185 -4.692598) (xy 32.790877 -4.733786) (xy 32.820343 -4.779635) (xy 32.842985 -4.82921)
			(xy 32.85834 -4.881503) (xy 32.866097 -4.935449) (xy 32.866097 -4.989951) (xy 32.866096 -4.989958)
			(xy 40.350307 -4.989958) (xy 40.350307 -4.935442) (xy 40.358066 -4.881481) (xy 40.373426 -4.829173)
			(xy 40.396074 -4.779584) (xy 40.42555 -4.733723) (xy 40.461252 -4.692524) (xy 40.502455 -4.656826)
			(xy 40.548319 -4.627355) (xy 40.59791 -4.604712) (xy 40.65022 -4.589358) (xy 40.704182 -4.581604)
			(xy 40.73144 -4.581144) (xy 41.59504 -4.581144) (xy 41.622286 -4.581729) (xy 41.676222 -4.589489)
			(xy 41.728506 -4.604846) (xy 41.778072 -4.627486) (xy 41.823911 -4.65695) (xy 41.865091 -4.692637)
			(xy 41.900774 -4.733821) (xy 41.930233 -4.779663) (xy 41.952868 -4.829232) (xy 41.968219 -4.881517)
			(xy 41.975974 -4.935454) (xy 41.975974 -4.989946) (xy 41.975973 -4.989954) (xy 43.95033 -4.989954)
			(xy 43.95033 -4.935446) (xy 43.958087 -4.881493) (xy 43.973443 -4.829193) (xy 43.996086 -4.779611)
			(xy 44.025554 -4.733756) (xy 44.061248 -4.692561) (xy 44.102441 -4.656865) (xy 44.148295 -4.627394)
			(xy 44.197876 -4.604749) (xy 44.250176 -4.589391) (xy 44.304128 -4.581631) (xy 44.331382 -4.581144)
			(xy 45.194982 -4.581144) (xy 45.222232 -4.581702) (xy 45.276178 -4.589456) (xy 45.328472 -4.604808)
			(xy 45.378048 -4.627447) (xy 45.423898 -4.656911) (xy 45.465087 -4.6926) (xy 45.500778 -4.733788)
			(xy 45.530244 -4.779636) (xy 45.552885 -4.829211) (xy 45.56824 -4.881504) (xy 45.575997 -4.93545)
			(xy 45.575997 -4.98995) (xy 45.575996 -4.989954) (xy 51.56043 -4.989954) (xy 51.56043 -4.935446)
			(xy 51.568187 -4.881494) (xy 51.583543 -4.829195) (xy 51.606185 -4.779613) (xy 51.635653 -4.733758)
			(xy 51.671346 -4.692563) (xy 51.712538 -4.656867) (xy 51.758392 -4.627396) (xy 51.807972 -4.604751)
			(xy 51.860271 -4.589392) (xy 51.914222 -4.581632) (xy 51.941476 -4.581144) (xy 52.805076 -4.581144)
			(xy 52.832327 -4.581702) (xy 52.886273 -4.589455) (xy 52.938567 -4.604807) (xy 52.988144 -4.627445)
			(xy 53.033995 -4.656909) (xy 53.075185 -4.692598) (xy 53.110877 -4.733786) (xy 53.140343 -4.779635)
			(xy 53.162985 -4.82921) (xy 53.17834 -4.881503) (xy 53.186097 -4.935449) (xy 53.186097 -4.989951)
			(xy 53.186096 -4.989957) (xy 55.160307 -4.989957) (xy 55.160307 -4.935443) (xy 55.168065 -4.881484)
			(xy 55.183424 -4.829178) (xy 55.206071 -4.77959) (xy 55.235544 -4.73373) (xy 55.271245 -4.692532)
			(xy 55.312445 -4.656834) (xy 55.358306 -4.627362) (xy 55.407894 -4.604718) (xy 55.460201 -4.589362)
			(xy 55.514161 -4.581606) (xy 55.541418 -4.581144) (xy 56.405018 -4.581144) (xy 56.432265 -4.581727)
			(xy 56.486204 -4.589485) (xy 56.53849 -4.60484) (xy 56.588058 -4.627479) (xy 56.633901 -4.656942)
			(xy 56.675084 -4.692629) (xy 56.710769 -4.733814) (xy 56.74023 -4.779657) (xy 56.762867 -4.829227)
			(xy 56.778219 -4.881514) (xy 56.785974 -4.935453) (xy 56.785974 -4.989947) (xy 56.778219 -5.043886)
			(xy 56.762867 -5.096173) (xy 56.74023 -5.145743) (xy 56.710769 -5.191586) (xy 56.675084 -5.232771)
			(xy 56.633901 -5.268458) (xy 56.588058 -5.297921) (xy 56.53849 -5.32056) (xy 56.486204 -5.335915)
			(xy 56.432265 -5.343673) (xy 56.405018 -5.34416) (xy 55.541418 -5.34416) (xy 55.514161 -5.343794)
			(xy 55.460201 -5.336038) (xy 55.407894 -5.320682) (xy 55.358306 -5.298038) (xy 55.312445 -5.268566)
			(xy 55.271245 -5.232868) (xy 55.235544 -5.19167) (xy 55.206071 -5.14581) (xy 55.183424 -5.096222)
			(xy 55.168065 -5.043916) (xy 55.160307 -4.989957) (xy 53.186096 -4.989957) (xy 53.17834 -5.043897)
			(xy 53.162985 -5.09619) (xy 53.140343 -5.145765) (xy 53.110877 -5.191614) (xy 53.075185 -5.232802)
			(xy 53.033995 -5.268491) (xy 52.988144 -5.297955) (xy 52.938567 -5.320593) (xy 52.886273 -5.335945)
			(xy 52.832327 -5.343698) (xy 52.805076 -5.34416) (xy 51.941476 -5.34416) (xy 51.914222 -5.343768)
			(xy 51.860271 -5.336008) (xy 51.807972 -5.320649) (xy 51.758392 -5.298004) (xy 51.712538 -5.268533)
			(xy 51.671346 -5.232837) (xy 51.635653 -5.191642) (xy 51.606185 -5.145787) (xy 51.583543 -5.096205)
			(xy 51.568187 -5.043906) (xy 51.56043 -4.989954) (xy 45.575996 -4.989954) (xy 45.56824 -5.043896)
			(xy 45.552885 -5.096189) (xy 45.530244 -5.145764) (xy 45.500778 -5.191612) (xy 45.465087 -5.2328)
			(xy 45.423898 -5.268489) (xy 45.378048 -5.297953) (xy 45.328472 -5.320592) (xy 45.276178 -5.335944)
			(xy 45.222232 -5.343698) (xy 45.194982 -5.34416) (xy 44.331382 -5.34416) (xy 44.304128 -5.343769)
			(xy 44.250176 -5.336009) (xy 44.197876 -5.320651) (xy 44.148295 -5.298006) (xy 44.102441 -5.268535)
			(xy 44.061248 -5.232839) (xy 44.025554 -5.191644) (xy 43.996086 -5.145789) (xy 43.973443 -5.096207)
			(xy 43.958087 -5.043907) (xy 43.95033 -4.989954) (xy 41.975973 -4.989954) (xy 41.968219 -5.043883)
			(xy 41.952868 -5.096168) (xy 41.930233 -5.145737) (xy 41.900774 -5.191579) (xy 41.865091 -5.232763)
			(xy 41.823911 -5.26845) (xy 41.778072 -5.297914) (xy 41.728506 -5.320554) (xy 41.676222 -5.335911)
			(xy 41.622286 -5.343671) (xy 41.59504 -5.34416) (xy 40.73144 -5.34416) (xy 40.704182 -5.343796) (xy 40.65022 -5.336042)
			(xy 40.59791 -5.320688) (xy 40.548319 -5.298045) (xy 40.502455 -5.268574) (xy 40.461252 -5.232876)
			(xy 40.42555 -5.191677) (xy 40.396074 -5.145816) (xy 40.373426 -5.096227) (xy 40.358066 -5.043919)
			(xy 40.350307 -4.989958) (xy 32.866096 -4.989958) (xy 32.85834 -5.043897) (xy 32.842985 -5.09619)
			(xy 32.820343 -5.145765) (xy 32.790877 -5.191614) (xy 32.755185 -5.232802) (xy 32.713995 -5.268491)
			(xy 32.668144 -5.297955) (xy 32.618567 -5.320593) (xy 32.566273 -5.335945) (xy 32.512327 -5.343698)
			(xy 32.485076 -5.34416) (xy 31.621476 -5.34416) (xy 31.594222 -5.343768) (xy 31.540271 -5.336008)
			(xy 31.487972 -5.320649) (xy 31.438392 -5.298004) (xy 31.392538 -5.268533) (xy 31.351346 -5.232837)
			(xy 31.315653 -5.191642) (xy 31.286185 -5.145787) (xy 31.263543 -5.096205) (xy 31.248187 -5.043906)
			(xy 31.24043 -4.989954) (xy 29.265896 -4.989954) (xy 29.25814 -5.043896) (xy 29.242785 -5.096189)
			(xy 29.220144 -5.145764) (xy 29.190678 -5.191613) (xy 29.154986 -5.232801) (xy 29.113797 -5.26849)
			(xy 29.067947 -5.297954) (xy 29.01837 -5.320592) (xy 28.966077 -5.335944) (xy 28.91213 -5.343698)
			(xy 28.88488 -5.34416) (xy 28.02128 -5.34416) (xy 27.994026 -5.343769) (xy 27.940074 -5.336009) (xy 27.887775 -5.32065)
			(xy 27.838194 -5.298005) (xy 27.79234 -5.268534) (xy 27.751147 -5.232838) (xy 27.715454 -5.191644)
			(xy 27.685985 -5.145788) (xy 27.663343 -5.096206) (xy 27.647987 -5.043907) (xy 27.64023 -4.989954)
			(xy 25.66598 -4.989954) (xy 25.65823 -5.043854) (xy 25.642873 -5.096153) (xy 25.620231 -5.145733)
			(xy 25.590762 -5.191587) (xy 25.555068 -5.23278) (xy 25.513875 -5.268473) (xy 25.468021 -5.297942)
			(xy 25.418441 -5.320584) (xy 25.366143 -5.33594) (xy 25.312191 -5.343697) (xy 25.284938 -5.34416)
			(xy 24.421338 -5.34416) (xy 24.394087 -5.34367) (xy 24.34014 -5.335913) (xy 24.287846 -5.320558)
			(xy 24.238269 -5.297917) (xy 24.192419 -5.268451) (xy 24.151229 -5.232759) (xy 24.115538 -5.19157)
			(xy 24.086072 -5.145719) (xy 24.063431 -5.096143) (xy 24.048076 -5.043848) (xy 24.04032 -4.989901)
			(xy 22.066047 -4.989901) (xy 22.066047 -4.989903) (xy 22.05829 -5.043855) (xy 22.042933 -5.096153)
			(xy 22.02029 -5.145734) (xy 21.990822 -5.191587) (xy 21.955128 -5.23278) (xy 21.913934 -5.268474)
			(xy 21.86808 -5.297942) (xy 21.818499 -5.320585) (xy 21.766201 -5.33594) (xy 21.712249 -5.343697)
			(xy 21.684996 -5.34416) (xy 20.821396 -5.34416) (xy 20.794145 -5.34367) (xy 20.740198 -5.335913)
			(xy 20.687904 -5.320558) (xy 20.638328 -5.297916) (xy 20.592478 -5.26845) (xy 20.551288 -5.232759)
			(xy 20.515597 -5.191569) (xy 20.486132 -5.145719) (xy 20.463491 -5.096142) (xy 20.448136 -5.043848)
			(xy 20.44038 -4.989901) (xy 16.267242 -4.989901) (xy 16.279069 -5.068337) (xy 16.28426 -5.154921)
			(xy 16.281666 -5.241621) (xy 16.271308 -5.32774) (xy 16.25327 -5.412583) (xy 16.227697 -5.495466)
			(xy 16.194795 -5.575723) (xy 16.154829 -5.652707) (xy 16.108121 -5.725796) (xy 16.055047 -5.794403)
			(xy 15.996036 -5.857975) (xy 15.931562 -5.915999) (xy 15.897098 -5.94233) (xy 15.862919 -5.967431)
			(xy 15.790907 -6.012223) (xy 15.715244 -6.050528) (xy 15.636514 -6.08205) (xy 15.555322 -6.106547)
			(xy 15.472296 -6.12383) (xy 15.388073 -6.133766) (xy 15.303304 -6.136278) (xy 15.218641 -6.131346)
			(xy 15.134737 -6.11901) (xy 15.052238 -6.099363) (xy 14.971779 -6.072558) (xy 14.893981 -6.0388)
			(xy 14.819443 -5.998351) (xy 14.783816 -5.97535) (xy 14.772146 -5.96815) (xy 14.746092 -5.959633)
			(xy 14.718712 -5.958358) (xy 14.69198 -5.964418) (xy 14.667825 -5.977375) (xy 14.647991 -5.996294)
			(xy 14.633909 -6.019811) (xy 14.626595 -6.046227) (xy 14.626082 -6.059932) (xy 14.626082 -6.751654)
			(xy 18.635651 -6.751654) (xy 18.635651 -6.697146) (xy 18.643409 -6.643192) (xy 18.658767 -6.590891)
			(xy 18.681411 -6.541309) (xy 18.710882 -6.495454) (xy 18.746579 -6.45426) (xy 18.787775 -6.418566)
			(xy 18.833632 -6.389099) (xy 18.883216 -6.366458) (xy 18.935517 -6.351104) (xy 18.989472 -6.34335)
			(xy 19.016726 -6.342888) (xy 19.880326 -6.342888) (xy 19.907576 -6.343384) (xy 19.96152 -6.351143)
			(xy 20.013811 -6.3665) (xy 20.063385 -6.389143) (xy 20.109231 -6.418609) (xy 20.150418 -6.4543) (xy 20.186106 -6.49549)
			(xy 20.21557 -6.541338) (xy 20.238209 -6.590913) (xy 20.253563 -6.643205) (xy 20.261318 -6.69715)
			(xy 20.261318 -6.75165) (xy 22.235674 -6.75165) (xy 22.235674 -6.69715) (xy 22.243429 -6.643204)
			(xy 22.258783 -6.590912) (xy 22.281422 -6.541336) (xy 22.310886 -6.495487) (xy 22.346574 -6.454297)
			(xy 22.387761 -6.418605) (xy 22.433608 -6.389138) (xy 22.483182 -6.366494) (xy 22.535473 -6.351136)
			(xy 22.589418 -6.343376) (xy 22.616668 -6.342888) (xy 23.480268 -6.342888) (xy 23.507522 -6.343357)
			(xy 23.561476 -6.35111) (xy 23.613777 -6.366463) (xy 23.663361 -6.389104) (xy 23.709217 -6.418571)
			(xy 23.750413 -6.454264) (xy 23.78611 -6.495457) (xy 23.815581 -6.541311) (xy 23.838225 -6.590893)
			(xy 23.853583 -6.643193) (xy 23.861341 -6.697146) (xy 23.861341 -6.751654) (xy 25.835551 -6.751654)
			(xy 25.835551 -6.697146) (xy 25.843309 -6.643194) (xy 25.858665 -6.590895) (xy 25.881309 -6.541314)
			(xy 25.910778 -6.495459) (xy 25.946473 -6.454266) (xy 25.987667 -6.418572) (xy 26.033522 -6.389104)
			(xy 26.083104 -6.366462) (xy 26.135404 -6.351107) (xy 26.189356 -6.343351) (xy 26.21661 -6.342888)
			(xy 27.08021 -6.342888) (xy 27.10746 -6.343382) (xy 27.161407 -6.35114) (xy 27.2137 -6.366496) (xy 27.263275 -6.389137)
			(xy 27.309124 -6.418604) (xy 27.350312 -6.454295) (xy 27.386002 -6.495484) (xy 27.415467 -6.541334)
			(xy 27.438108 -6.59091) (xy 27.453462 -6.643203) (xy 27.461218 -6.697149) (xy 27.461218 -6.751651)
			(xy 27.461218 -6.751653) (xy 29.435751 -6.751653) (xy 29.435751 -6.697147) (xy 29.443509 -6.643195)
			(xy 29.458865 -6.590896) (xy 29.481508 -6.541315) (xy 29.510977 -6.495461) (xy 29.546672 -6.454268)
			(xy 29.587866 -6.418574) (xy 29.63372 -6.389105) (xy 29.683301 -6.366463) (xy 29.7356 -6.351107)
			(xy 29.789553 -6.343351) (xy 29.816806 -6.342888) (xy 30.680406 -6.342888) (xy 30.707657 -6.343382)
			(xy 30.761603 -6.351139) (xy 30.813897 -6.366495) (xy 30.863473 -6.389136) (xy 30.909322 -6.418602)
			(xy 30.950511 -6.454293) (xy 30.986201 -6.495483) (xy 31.015667 -6.541333) (xy 31.038307 -6.590909)
			(xy 31.053662 -6.643203) (xy 31.061418 -6.697149) (xy 31.061418 -6.75165) (xy 38.545774 -6.75165)
			(xy 38.545774 -6.69715) (xy 38.55353 -6.643204) (xy 38.568883 -6.590911) (xy 38.591522 -6.541336)
			(xy 38.620986 -6.495486) (xy 38.656675 -6.454296) (xy 38.697862 -6.418604) (xy 38.743709 -6.389137)
			(xy 38.793283 -6.366494) (xy 38.845575 -6.351136) (xy 38.89952 -6.343376) (xy 38.92677 -6.342888)
			(xy 39.79037 -6.342888) (xy 39.817624 -6.343357) (xy 39.871578 -6.351111) (xy 39.923878 -6.366464)
			(xy 39.973462 -6.389105) (xy 40.019318 -6.418571) (xy 40.060514 -6.454265) (xy 40.096211 -6.495458)
			(xy 40.125681 -6.541312) (xy 40.148326 -6.590893) (xy 40.163683 -6.643193) (xy 40.171441 -6.697146)
			(xy 40.171441 -6.751654) (xy 42.145651 -6.751654) (xy 42.145651 -6.697146) (xy 42.153409 -6.643194)
			(xy 42.168766 -6.590894) (xy 42.191409 -6.541313) (xy 42.220879 -6.495459) (xy 42.256574 -6.454265)
			(xy 42.297768 -6.418571) (xy 42.343624 -6.389103) (xy 42.393206 -6.366461) (xy 42.445506 -6.351106)
			(xy 42.499458 -6.343351) (xy 42.526712 -6.342888) (xy 43.390312 -6.342888) (xy 43.417562 -6.343383)
			(xy 43.471508 -6.35114) (xy 43.523801 -6.366496) (xy 43.573376 -6.389138) (xy 43.619225 -6.418604)
			(xy 43.660413 -6.454295) (xy 43.696103 -6.495485) (xy 43.725568 -6.541334) (xy 43.748208 -6.59091)
			(xy 43.763562 -6.643203) (xy 43.771318 -6.69715) (xy 43.771318 -6.75165) (xy 43.771318 -6.751653)
			(xy 49.755751 -6.751653) (xy 49.755751 -6.697147) (xy 49.763509 -6.643195) (xy 49.778865 -6.590896)
			(xy 49.801508 -6.541315) (xy 49.830977 -6.495461) (xy 49.866672 -6.454268) (xy 49.907866 -6.418574)
			(xy 49.95372 -6.389105) (xy 50.003301 -6.366463) (xy 50.0556 -6.351107) (xy 50.109553 -6.343351)
			(xy 50.136806 -6.342888) (xy 51.000406 -6.342888) (xy 51.027657 -6.343382) (xy 51.081603 -6.351139)
			(xy 51.133897 -6.366495) (xy 51.183473 -6.389136) (xy 51.229322 -6.418602) (xy 51.270511 -6.454293)
			(xy 51.306201 -6.495483) (xy 51.335667 -6.541333) (xy 51.358307 -6.590909) (xy 51.373662 -6.643203)
			(xy 51.381418 -6.697149) (xy 51.381418 -6.751651) (xy 51.381417 -6.751655) (xy 53.355652 -6.751655)
			(xy 53.355652 -6.697145) (xy 53.36341 -6.643189) (xy 53.378768 -6.590887) (xy 53.401415 -6.541303)
			(xy 53.430887 -6.495447) (xy 53.466587 -6.454253) (xy 53.507785 -6.418559) (xy 53.553645 -6.389092)
			(xy 53.603232 -6.366452) (xy 53.655536 -6.3511) (xy 53.709493 -6.343348) (xy 53.736748 -6.342888)
			(xy 54.600348 -6.342888) (xy 54.627597 -6.343385) (xy 54.681539 -6.351147) (xy 54.733827 -6.366506)
			(xy 54.783398 -6.38915) (xy 54.829242 -6.418617) (xy 54.870426 -6.454308) (xy 54.906112 -6.495497)
			(xy 54.935573 -6.541344) (xy 54.958211 -6.590918) (xy 54.973563 -6.643208) (xy 54.981318 -6.697151)
			(xy 54.981318 -6.751649) (xy 54.981318 -6.751651) (xy 56.955674 -6.751651) (xy 56.955674 -6.697149)
			(xy 56.96343 -6.643201) (xy 56.978785 -6.590907) (xy 57.001426 -6.54133) (xy 57.030891 -6.49548)
			(xy 57.066582 -6.454289) (xy 57.107771 -6.418597) (xy 57.153621 -6.38913) (xy 57.203198 -6.366488)
			(xy 57.255492 -6.351132) (xy 57.309439 -6.343374) (xy 57.33669 -6.342888) (xy 58.20029 -6.342888)
			(xy 58.227543 -6.343359) (xy 58.281494 -6.351114) (xy 58.333793 -6.366469) (xy 58.383374 -6.389111)
			(xy 58.429228 -6.418578) (xy 58.470421 -6.454272) (xy 58.506116 -6.495464) (xy 58.535584 -6.541317)
			(xy 58.558227 -6.590898) (xy 58.573583 -6.643196) (xy 58.581341 -6.697147) (xy 58.581341 -6.751651)
			(xy 70.950574 -6.751651) (xy 70.950574 -6.697149) (xy 70.95833 -6.643203) (xy 70.973684 -6.590909)
			(xy 70.996324 -6.541332) (xy 71.025789 -6.495482) (xy 71.061479 -6.454292) (xy 71.102668 -6.4186)
			(xy 71.148516 -6.389133) (xy 71.198092 -6.366491) (xy 71.250385 -6.351134) (xy 71.304331 -6.343375)
			(xy 71.331582 -6.342888) (xy 72.195182 -6.342888) (xy 72.222435 -6.343358) (xy 72.276388 -6.351113)
			(xy 72.328687 -6.366467) (xy 72.378269 -6.389108) (xy 72.424124 -6.418576) (xy 72.465318 -6.454269)
			(xy 72.501014 -6.495462) (xy 72.530483 -6.541315) (xy 72.553126 -6.590896) (xy 72.568483 -6.643195)
			(xy 72.576241 -6.697147) (xy 72.576241 -6.751653) (xy 72.568483 -6.805605) (xy 72.553126 -6.857904)
			(xy 72.530483 -6.907485) (xy 72.501014 -6.953338) (xy 72.465318 -6.994531) (xy 72.424124 -7.030224)
			(xy 72.378269 -7.059692) (xy 72.328687 -7.082333) (xy 72.276388 -7.097687) (xy 72.222435 -7.105442)
			(xy 72.195182 -7.105904) (xy 71.331582 -7.105904) (xy 71.304331 -7.105425) (xy 71.250385 -7.097666)
			(xy 71.198092 -7.082309) (xy 71.148516 -7.059667) (xy 71.102668 -7.0302) (xy 71.061479 -6.994508)
			(xy 71.025789 -6.953318) (xy 70.996324 -6.907468) (xy 70.973684 -6.857891) (xy 70.95833 -6.805597)
			(xy 70.950574 -6.751651) (xy 58.581341 -6.751651) (xy 58.581341 -6.751653) (xy 58.573583 -6.805604)
			(xy 58.558227 -6.857902) (xy 58.535584 -6.907483) (xy 58.506116 -6.953336) (xy 58.470421 -6.994528)
			(xy 58.429228 -7.030222) (xy 58.383374 -7.059689) (xy 58.333793 -7.082331) (xy 58.281494 -7.097686)
			(xy 58.227543 -7.105441) (xy 58.20029 -7.105904) (xy 57.33669 -7.105904) (xy 57.309439 -7.105426)
			(xy 57.255492 -7.097668) (xy 57.203198 -7.082312) (xy 57.153621 -7.05967) (xy 57.107771 -7.030203)
			(xy 57.066582 -6.994511) (xy 57.030891 -6.95332) (xy 57.001426 -6.90747) (xy 56.978785 -6.857893)
			(xy 56.96343 -6.805599) (xy 56.955674 -6.751651) (xy 54.981318 -6.751651) (xy 54.973563 -6.805592)
			(xy 54.958211 -6.857882) (xy 54.935573 -6.907456) (xy 54.906112 -6.953303) (xy 54.870426 -6.994492)
			(xy 54.829242 -7.030183) (xy 54.783398 -7.05965) (xy 54.733827 -7.082294) (xy 54.681539 -7.097653)
			(xy 54.627597 -7.105415) (xy 54.600348 -7.105904) (xy 53.736748 -7.105904) (xy 53.709493 -7.105452)
			(xy 53.655536 -7.0977) (xy 53.603232 -7.082348) (xy 53.553645 -7.059708) (xy 53.507785 -7.030241)
			(xy 53.466587 -6.994547) (xy 53.430887 -6.953353) (xy 53.401415 -6.907497) (xy 53.378768 -6.857913)
			(xy 53.36341 -6.805611) (xy 53.355652 -6.751655) (xy 51.381417 -6.751655) (xy 51.373662 -6.805597)
			(xy 51.358307 -6.857891) (xy 51.335667 -6.907467) (xy 51.306201 -6.953317) (xy 51.270511 -6.994507)
			(xy 51.229322 -7.030198) (xy 51.183473 -7.059664) (xy 51.133897 -7.082305) (xy 51.081603 -7.097661)
			(xy 51.027657 -7.105418) (xy 51.000406 -7.105904) (xy 50.136806 -7.105904) (xy 50.109553 -7.105449)
			(xy 50.0556 -7.097693) (xy 50.003301 -7.082337) (xy 49.95372 -7.059695) (xy 49.907866 -7.030226)
			(xy 49.866672 -6.994532) (xy 49.830977 -6.953339) (xy 49.801508 -6.907485) (xy 49.778865 -6.857904)
			(xy 49.763509 -6.805605) (xy 49.755751 -6.751653) (xy 43.771318 -6.751653) (xy 43.763562 -6.805597)
			(xy 43.748208 -6.85789) (xy 43.725568 -6.907466) (xy 43.696103 -6.953315) (xy 43.660413 -6.994505)
			(xy 43.619225 -7.030196) (xy 43.573376 -7.059662) (xy 43.523801 -7.082304) (xy 43.471508 -7.09766)
			(xy 43.417562 -7.105417) (xy 43.390312 -7.105904) (xy 42.526712 -7.105904) (xy 42.499458 -7.105449)
			(xy 42.445506 -7.097694) (xy 42.393206 -7.082339) (xy 42.343624 -7.059697) (xy 42.297768 -7.030229)
			(xy 42.256574 -6.994535) (xy 42.220879 -6.953341) (xy 42.191409 -6.907487) (xy 42.168766 -6.857906)
			(xy 42.153409 -6.805606) (xy 42.145651 -6.751654) (xy 40.171441 -6.751654) (xy 40.163683 -6.805607)
			(xy 40.148326 -6.857907) (xy 40.125681 -6.907488) (xy 40.096211 -6.953342) (xy 40.060514 -6.994535)
			(xy 40.019318 -7.030229) (xy 39.973462 -7.059695) (xy 39.923878 -7.082336) (xy 39.871578 -7.097689)
			(xy 39.817624 -7.105443) (xy 39.79037 -7.105904) (xy 38.92677 -7.105904) (xy 38.89952 -7.105424)
			(xy 38.845575 -7.097664) (xy 38.793283 -7.082306) (xy 38.743709 -7.059663) (xy 38.697862 -7.030196)
			(xy 38.656675 -6.994504) (xy 38.620986 -6.953314) (xy 38.591522 -6.907464) (xy 38.568883 -6.857889)
			(xy 38.55353 -6.805596) (xy 38.545774 -6.75165) (xy 31.061418 -6.75165) (xy 31.061418 -6.751651)
			(xy 31.053662 -6.805597) (xy 31.038307 -6.857891) (xy 31.015667 -6.907467) (xy 30.986201 -6.953317)
			(xy 30.950511 -6.994507) (xy 30.909322 -7.030198) (xy 30.863473 -7.059664) (xy 30.813897 -7.082305)
			(xy 30.761603 -7.097661) (xy 30.707657 -7.105418) (xy 30.680406 -7.105904) (xy 29.816806 -7.105904)
			(xy 29.789553 -7.105449) (xy 29.7356 -7.097693) (xy 29.683301 -7.082337) (xy 29.63372 -7.059695)
			(xy 29.587866 -7.030226) (xy 29.546672 -6.994532) (xy 29.510977 -6.953339) (xy 29.481508 -6.907485)
			(xy 29.458865 -6.857904) (xy 29.443509 -6.805605) (xy 29.435751 -6.751653) (xy 27.461218 -6.751653)
			(xy 27.453462 -6.805597) (xy 27.438108 -6.85789) (xy 27.415467 -6.907466) (xy 27.386002 -6.953316)
			(xy 27.350312 -6.994505) (xy 27.309124 -7.030196) (xy 27.263275 -7.059663) (xy 27.2137 -7.082304)
			(xy 27.161407 -7.09766) (xy 27.10746 -7.105418) (xy 27.08021 -7.105904) (xy 26.21661 -7.105904) (xy 26.189356 -7.105449)
			(xy 26.135404 -7.097693) (xy 26.083104 -7.082338) (xy 26.033522 -7.059696) (xy 25.987667 -7.030228)
			(xy 25.946473 -6.994534) (xy 25.910778 -6.953341) (xy 25.881309 -6.907486) (xy 25.858665 -6.857905)
			(xy 25.843309 -6.805606) (xy 25.835551 -6.751654) (xy 23.861341 -6.751654) (xy 23.853583 -6.805607)
			(xy 23.838225 -6.857907) (xy 23.815581 -6.907489) (xy 23.78611 -6.953343) (xy 23.750413 -6.994536)
			(xy 23.709217 -7.030229) (xy 23.663361 -7.059696) (xy 23.613777 -7.082337) (xy 23.561476 -7.09769)
			(xy 23.507522 -7.105443) (xy 23.480268 -7.105904) (xy 22.616668 -7.105904) (xy 22.589418 -7.105424)
			(xy 22.535473 -7.097664) (xy 22.483182 -7.082306) (xy 22.433608 -7.059662) (xy 22.387761 -7.030195)
			(xy 22.346574 -6.994503) (xy 22.310886 -6.953313) (xy 22.281422 -6.907464) (xy 22.258783 -6.857888)
			(xy 22.243429 -6.805596) (xy 22.235674 -6.75165) (xy 20.261318 -6.75165) (xy 20.253563 -6.805595)
			(xy 20.238209 -6.857887) (xy 20.21557 -6.907462) (xy 20.186106 -6.95331) (xy 20.150418 -6.9945) (xy 20.109231 -7.030191)
			(xy 20.063385 -7.059657) (xy 20.013811 -7.0823) (xy 19.96152 -7.097657) (xy 19.907576 -7.105416)
			(xy 19.880326 -7.105904) (xy 19.016726 -7.105904) (xy 18.989472 -7.10545) (xy 18.935517 -7.097696)
			(xy 18.883216 -7.082342) (xy 18.833632 -7.059701) (xy 18.787775 -7.030234) (xy 18.746579 -6.99454)
			(xy 18.710882 -6.953346) (xy 18.681411 -6.907491) (xy 18.658767 -6.857909) (xy 18.643409 -6.805608)
			(xy 18.635651 -6.751654) (xy 14.626082 -6.751654) (xy 14.626082 -9.780016) (xy 14.625583 -9.863891)
			(xy 14.617601 -10.03145) (xy 14.601655 -10.198441) (xy 14.577781 -10.364483) (xy 14.546034 -10.529201)
			(xy 14.506486 -10.692222) (xy 14.459225 -10.853176) (xy 14.404359 -11.0117) (xy 14.342013 -11.167433)
			(xy 14.272327 -11.320024) (xy 14.195459 -11.469125) (xy 14.111585 -11.614401) (xy 14.020892 -11.755521)
			(xy 13.923588 -11.892166) (xy 13.819892 -12.024026) (xy 13.710039 -12.150802) (xy 13.594279 -12.272209)
			(xy 13.472872 -12.387969) (xy 13.346096 -12.497822) (xy 13.214236 -12.601518) (xy 13.077591 -12.698822)
			(xy 12.936471 -12.789515) (xy 12.791195 -12.873389) (xy 12.756354 -12.891351) (xy 56.954662 -12.891351)
			(xy 56.954662 -12.836849) (xy 56.962418 -12.782901) (xy 56.977772 -12.730606) (xy 57.000413 -12.681029)
			(xy 57.029878 -12.635178) (xy 57.065568 -12.593986) (xy 57.106757 -12.558293) (xy 57.152606 -12.528825)
			(xy 57.202182 -12.506181) (xy 57.254476 -12.490823) (xy 57.308423 -12.483064) (xy 57.335674 -12.482576)
			(xy 58.199274 -12.482576) (xy 58.226527 -12.48307) (xy 58.280478 -12.490823) (xy 58.332777 -12.506176)
			(xy 58.382358 -12.528816) (xy 58.428213 -12.558282) (xy 58.469407 -12.593975) (xy 58.505102 -12.635166)
			(xy 58.534571 -12.681019) (xy 58.557215 -12.730598) (xy 58.572571 -12.782896) (xy 58.580329 -12.836847)
			(xy 58.580329 -12.891353) (xy 58.580329 -12.891355) (xy 70.949739 -12.891355) (xy 70.949739 -12.836845)
			(xy 70.957497 -12.78289) (xy 70.972854 -12.730588) (xy 70.995499 -12.681005) (xy 71.024971 -12.635149)
			(xy 71.060668 -12.593954) (xy 71.101865 -12.558259) (xy 71.147722 -12.52879) (xy 71.197307 -12.506147)
			(xy 71.24961 -12.490793) (xy 71.303565 -12.483038) (xy 71.33082 -12.482576) (xy 72.19442 -12.482576)
			(xy 72.221669 -12.483096) (xy 72.275612 -12.490854) (xy 72.327902 -12.50621) (xy 72.377475 -12.528852)
			(xy 72.423321 -12.558317) (xy 72.464507 -12.594007) (xy 72.500195 -12.635195) (xy 72.529658 -12.681043)
			(xy 72.552297 -12.730616) (xy 72.56765 -12.782907) (xy 72.575406 -12.836851) (xy 72.575406 -12.891349)
			(xy 72.56765 -12.945293) (xy 72.552297 -12.997584) (xy 72.529658 -13.047157) (xy 72.500195 -13.093005)
			(xy 72.464507 -13.134193) (xy 72.423321 -13.169883) (xy 72.377475 -13.199348) (xy 72.327902 -13.22199)
			(xy 72.275612 -13.237346) (xy 72.221669 -13.245104) (xy 72.19442 -13.245592) (xy 71.33082 -13.245592)
			(xy 71.303565 -13.245162) (xy 71.24961 -13.237407) (xy 71.197307 -13.222053) (xy 71.147722 -13.19941)
			(xy 71.101865 -13.169941) (xy 71.060668 -13.134246) (xy 71.024971 -13.093051) (xy 70.995499 -13.047195)
			(xy 70.972854 -12.997612) (xy 70.957497 -12.94531) (xy 70.949739 -12.891355) (xy 58.580329 -12.891355)
			(xy 58.572571 -12.945304) (xy 58.557215 -12.997602) (xy 58.534571 -13.047181) (xy 58.505102 -13.093034)
			(xy 58.469407 -13.134225) (xy 58.428213 -13.169918) (xy 58.382358 -13.199384) (xy 58.332777 -13.222024)
			(xy 58.280478 -13.237377) (xy 58.226527 -13.24513) (xy 58.199274 -13.245592) (xy 57.335674 -13.245592)
			(xy 57.308423 -13.245136) (xy 57.254476 -13.237377) (xy 57.202182 -13.222019) (xy 57.152606 -13.199375)
			(xy 57.106757 -13.169907) (xy 57.065568 -13.134214) (xy 57.029878 -13.093022) (xy 57.000413 -13.047171)
			(xy 56.977772 -12.997594) (xy 56.962418 -12.945299) (xy 56.954662 -12.891351) (xy 12.756354 -12.891351)
			(xy 12.642094 -12.950257) (xy 12.489503 -13.019943) (xy 12.33377 -13.082289) (xy 12.175246 -13.137155)
			(xy 12.014292 -13.184416) (xy 11.851271 -13.223964) (xy 11.686553 -13.255711) (xy 11.520511 -13.279585)
			(xy 11.35352 -13.295531) (xy 11.185961 -13.303513) (xy 11.102086 -13.304012) (xy 1.999996 -13.304012)
			(xy 1.96883 -13.3045) (xy 1.907031 -13.312637) (xy 1.846823 -13.32877) (xy 1.789236 -13.352624) (xy 1.735255 -13.383791)
			(xy 1.685804 -13.421737) (xy 1.641729 -13.465813) (xy 1.603784 -13.515265) (xy 1.572619 -13.569247)
			(xy 1.548766 -13.626834) (xy 1.532634 -13.687043) (xy 1.524499 -13.748842) (xy 1.524 -13.780008)
			(xy 1.524 -15.222054) (xy 135.233343 -15.222054) (xy 135.233343 -15.167546) (xy 135.2411 -15.113592)
			(xy 135.256457 -15.061292) (xy 135.279101 -15.011709) (xy 135.308571 -14.965854) (xy 135.344267 -14.92466)
			(xy 135.385462 -14.888965) (xy 135.431318 -14.859497) (xy 135.480901 -14.836854) (xy 135.533202 -14.821498)
			(xy 135.587156 -14.813742) (xy 135.61441 -14.81328) (xy 136.47801 -14.81328) (xy 136.50526 -14.813791)
			(xy 136.559205 -14.821548) (xy 136.611497 -14.836904) (xy 136.661071 -14.859545) (xy 136.706919 -14.88901)
			(xy 136.748106 -14.924701) (xy 136.783796 -14.965889) (xy 136.81326 -15.011738) (xy 136.8359 -15.061313)
			(xy 136.851254 -15.113605) (xy 136.85901 -15.16755) (xy 136.85901 -15.22205) (xy 136.851254 -15.275995)
			(xy 136.8359 -15.328287) (xy 136.81326 -15.377862) (xy 136.783796 -15.423711) (xy 136.748106 -15.464899)
			(xy 136.706919 -15.50059) (xy 136.661071 -15.530055) (xy 136.611497 -15.552696) (xy 136.559205 -15.568052)
			(xy 136.50526 -15.575809) (xy 136.47801 -15.576296) (xy 135.61441 -15.576296) (xy 135.587156 -15.575858)
			(xy 135.533202 -15.568102) (xy 135.480901 -15.552746) (xy 135.431318 -15.530103) (xy 135.385462 -15.500635)
			(xy 135.344267 -15.46494) (xy 135.308571 -15.423746) (xy 135.279101 -15.377891) (xy 135.256457 -15.328308)
			(xy 135.2411 -15.276008) (xy 135.233343 -15.222054) (xy 1.524 -15.222054) (xy 1.524 -22.29993) (xy 1.728222 -22.29993)
			(xy 1.732236 -22.094246) (xy 1.744272 -21.888876) (xy 1.764311 -21.684132) (xy 1.792324 -21.480325)
			(xy 1.828267 -21.277766) (xy 1.872086 -21.076764) (xy 1.923713 -20.877625) (xy 1.983071 -20.680652)
			(xy 2.050069 -20.486144) (xy 2.124605 -20.294399) (xy 2.206565 -20.105708) (xy 2.295825 -19.920358)
			(xy 2.392248 -19.738632) (xy 2.495689 -19.560806) (xy 2.605988 -19.387152) (xy 2.722979 -19.217933)
			(xy 2.846483 -19.053407) (xy 2.976312 -18.893826) (xy 3.112269 -18.739431) (xy 3.254146 -18.590459)
			(xy 3.401727 -18.447135) (xy 3.554788 -18.309679) (xy 3.713095 -18.178299) (xy 3.876408 -18.053196)
			(xy 4.044477 -17.934559) (xy 4.217047 -17.822571) (xy 4.393855 -17.7174) (xy 4.574632 -17.619209)
			(xy 4.759102 -17.528145) (xy 4.946984 -17.444348) (xy 5.137994 -17.367945) (xy 5.331838 -17.299052)
			(xy 5.528223 -17.237775) (xy 5.726849 -17.184207) (xy 5.927414 -17.13843) (xy 6.129612 -17.100512)
			(xy 6.333136 -17.070513) (xy 6.537675 -17.048476) (xy 6.742918 -17.034437) (xy 6.948553 -17.028417)
			(xy 7.154266 -17.030424) (xy 7.359744 -17.040456) (xy 7.564674 -17.058497) (xy 7.768744 -17.08452)
			(xy 7.971644 -17.118485) (xy 8.173064 -17.16034) (xy 8.372697 -17.210022) (xy 8.57024 -17.267456)
			(xy 8.765392 -17.332553) (xy 8.957856 -17.405214) (xy 9.147338 -17.48533) (xy 9.333549 -17.572777)
			(xy 9.462533 -17.639611) (xy 15.152858 -17.639611) (xy 15.152858 -17.585109) (xy 15.160614 -17.531161)
			(xy 15.175969 -17.478867) (xy 15.19861 -17.42929) (xy 15.228076 -17.383439) (xy 15.263768 -17.342249)
			(xy 15.304958 -17.306558) (xy 15.350808 -17.277091) (xy 15.400385 -17.25445) (xy 15.452679 -17.239095)
			(xy 15.506627 -17.231338) (xy 15.533878 -17.230852) (xy 16.397478 -17.230852) (xy 16.424731 -17.231315)
			(xy 16.478682 -17.239072) (xy 16.53098 -17.254428) (xy 16.580561 -17.27707) (xy 16.626414 -17.306538)
			(xy 16.667607 -17.342232) (xy 16.703301 -17.383424) (xy 16.732769 -17.429278) (xy 16.755412 -17.478858)
			(xy 16.770768 -17.531156) (xy 16.778525 -17.585107) (xy 16.778525 -17.639611) (xy 20.740858 -17.639611)
			(xy 20.740858 -17.585109) (xy 20.748614 -17.531161) (xy 20.763969 -17.478867) (xy 20.78661 -17.42929)
			(xy 20.816076 -17.383439) (xy 20.851768 -17.342249) (xy 20.892958 -17.306558) (xy 20.938808 -17.277091)
			(xy 20.988385 -17.25445) (xy 21.040679 -17.239095) (xy 21.094627 -17.231338) (xy 21.121878 -17.230852)
			(xy 21.985478 -17.230852) (xy 22.012729 -17.231394) (xy 22.066677 -17.239147) (xy 22.118972 -17.2545)
			(xy 22.168549 -17.277139) (xy 22.2144 -17.306603) (xy 22.255591 -17.342293) (xy 22.291284 -17.383482)
			(xy 22.320751 -17.429331) (xy 22.343392 -17.478908) (xy 22.358748 -17.531202) (xy 22.366505 -17.585149)
			(xy 22.366505 -17.639651) (xy 22.366505 -17.639653) (xy 26.328838 -17.639653) (xy 26.328838 -17.585147)
			(xy 26.336595 -17.531195) (xy 26.35195 -17.478897) (xy 26.374592 -17.429316) (xy 26.404059 -17.383462)
			(xy 26.439752 -17.342268) (xy 26.480944 -17.306573) (xy 26.526797 -17.277103) (xy 26.576376 -17.254458)
			(xy 26.628674 -17.239099) (xy 26.682625 -17.231339) (xy 26.709878 -17.230852) (xy 27.573478 -17.230852)
			(xy 27.600729 -17.231394) (xy 27.654677 -17.239147) (xy 27.706972 -17.2545) (xy 27.756549 -17.277139)
			(xy 27.8024 -17.306603) (xy 27.843591 -17.342293) (xy 27.879284 -17.383482) (xy 27.908751 -17.429331)
			(xy 27.931392 -17.478908) (xy 27.946748 -17.531202) (xy 27.954505 -17.585149) (xy 27.954505 -17.639651)
			(xy 27.954505 -17.639653) (xy 31.916838 -17.639653) (xy 31.916838 -17.585147) (xy 31.924595 -17.531195)
			(xy 31.93995 -17.478897) (xy 31.962592 -17.429316) (xy 31.992059 -17.383462) (xy 32.027752 -17.342268)
			(xy 32.068944 -17.306573) (xy 32.114797 -17.277103) (xy 32.164376 -17.254458) (xy 32.216674 -17.239099)
			(xy 32.270625 -17.231339) (xy 32.297878 -17.230852) (xy 33.161478 -17.230852) (xy 33.188729 -17.231394)
			(xy 33.242677 -17.239147) (xy 33.294972 -17.2545) (xy 33.344549 -17.277139) (xy 33.3904 -17.306603)
			(xy 33.431591 -17.342293) (xy 33.467284 -17.383482) (xy 33.496751 -17.429331) (xy 33.519392 -17.478908)
			(xy 33.534748 -17.531202) (xy 33.542505 -17.585149) (xy 33.542505 -17.639651) (xy 33.542505 -17.639653)
			(xy 37.504838 -17.639653) (xy 37.504838 -17.585147) (xy 37.512595 -17.531195) (xy 37.52795 -17.478897)
			(xy 37.550592 -17.429316) (xy 37.580059 -17.383462) (xy 37.615752 -17.342268) (xy 37.656944 -17.306573)
			(xy 37.702797 -17.277103) (xy 37.752376 -17.254458) (xy 37.804674 -17.239099) (xy 37.858625 -17.231339)
			(xy 37.885878 -17.230852) (xy 38.749478 -17.230852) (xy 38.776729 -17.231394) (xy 38.830677 -17.239147)
			(xy 38.882972 -17.2545) (xy 38.932549 -17.277139) (xy 38.9784 -17.306603) (xy 39.019591 -17.342293)
			(xy 39.055284 -17.383482) (xy 39.084751 -17.429331) (xy 39.107392 -17.478908) (xy 39.122748 -17.531202)
			(xy 39.130505 -17.585149) (xy 39.130505 -17.639651) (xy 39.130505 -17.639654) (xy 43.398638 -17.639654)
			(xy 43.398638 -17.585146) (xy 43.406395 -17.531193) (xy 43.421751 -17.478894) (xy 43.444395 -17.429312)
			(xy 43.473863 -17.383457) (xy 43.509558 -17.342262) (xy 43.550752 -17.306567) (xy 43.596606 -17.277097)
			(xy 43.646188 -17.254454) (xy 43.698487 -17.239096) (xy 43.75244 -17.231338) (xy 43.779694 -17.230852)
			(xy 44.643294 -17.230852) (xy 44.670544 -17.231395) (xy 44.72449 -17.23915) (xy 44.776783 -17.254504)
			(xy 44.826359 -17.277144) (xy 44.872208 -17.306609) (xy 44.913397 -17.342299) (xy 44.949088 -17.383487)
			(xy 44.978553 -17.429336) (xy 45.001194 -17.478911) (xy 45.016548 -17.531204) (xy 45.024305 -17.58515)
			(xy 45.024305 -17.63965) (xy 45.024304 -17.639654) (xy 48.986638 -17.639654) (xy 48.986638 -17.585146)
			(xy 48.994395 -17.531193) (xy 49.009751 -17.478894) (xy 49.032395 -17.429312) (xy 49.061863 -17.383457)
			(xy 49.097558 -17.342262) (xy 49.138752 -17.306567) (xy 49.184606 -17.277097) (xy 49.234188 -17.254454)
			(xy 49.286487 -17.239096) (xy 49.34044 -17.231338) (xy 49.367694 -17.230852) (xy 50.231294 -17.230852)
			(xy 50.258544 -17.231395) (xy 50.31249 -17.23915) (xy 50.364783 -17.254504) (xy 50.414359 -17.277144)
			(xy 50.460208 -17.306609) (xy 50.501397 -17.342299) (xy 50.537088 -17.383487) (xy 50.566553 -17.429336)
			(xy 50.589194 -17.478911) (xy 50.604548 -17.531204) (xy 50.612305 -17.58515) (xy 50.612305 -17.63965)
			(xy 50.612304 -17.639657) (xy 54.608615 -17.639657) (xy 54.608615 -17.585143) (xy 54.616374 -17.531184)
			(xy 54.631733 -17.478878) (xy 54.65438 -17.42929) (xy 54.683854 -17.383431) (xy 54.719554 -17.342233)
			(xy 54.760755 -17.306536) (xy 54.806617 -17.277065) (xy 54.856206 -17.254422) (xy 54.908513 -17.239067)
			(xy 54.962473 -17.231313) (xy 54.98973 -17.230852) (xy 55.85333 -17.230852) (xy 55.880577 -17.23142)
			(xy 55.934516 -17.239179) (xy 55.986801 -17.254535) (xy 56.03637 -17.277176) (xy 56.082211 -17.30664)
			(xy 56.123394 -17.342328) (xy 56.159078 -17.383513) (xy 56.188538 -17.429357) (xy 56.211175 -17.478927)
			(xy 56.226527 -17.531214) (xy 56.234282 -17.585153) (xy 56.234282 -17.639647) (xy 56.226527 -17.693586)
			(xy 56.211175 -17.745873) (xy 56.188538 -17.795443) (xy 56.159078 -17.841287) (xy 56.123394 -17.882472)
			(xy 56.082211 -17.91816) (xy 56.03637 -17.947624) (xy 55.986801 -17.970265) (xy 55.934516 -17.985621)
			(xy 55.880577 -17.99338) (xy 55.85333 -17.993868) (xy 54.98973 -17.993868) (xy 54.962473 -17.993487)
			(xy 54.908513 -17.985733) (xy 54.856206 -17.970378) (xy 54.806617 -17.947735) (xy 54.760755 -17.918264)
			(xy 54.719554 -17.882567) (xy 54.683854 -17.841369) (xy 54.65438 -17.79551) (xy 54.631733 -17.745922)
			(xy 54.616374 -17.693616) (xy 54.608615 -17.639657) (xy 50.612304 -17.639657) (xy 50.604548 -17.693596)
			(xy 50.589194 -17.745889) (xy 50.566553 -17.795464) (xy 50.537088 -17.841313) (xy 50.501397 -17.882501)
			(xy 50.460208 -17.918191) (xy 50.414359 -17.947656) (xy 50.364783 -17.970296) (xy 50.31249 -17.98565)
			(xy 50.258544 -17.993405) (xy 50.231294 -17.993868) (xy 49.367694 -17.993868) (xy 49.34044 -17.993462)
			(xy 49.286487 -17.985704) (xy 49.234188 -17.970346) (xy 49.184606 -17.947703) (xy 49.138752 -17.918233)
			(xy 49.097558 -17.882538) (xy 49.061863 -17.841343) (xy 49.032395 -17.795488) (xy 49.009751 -17.745906)
			(xy 48.994395 -17.693607) (xy 48.986638 -17.639654) (xy 45.024304 -17.639654) (xy 45.016548 -17.693596)
			(xy 45.001194 -17.745889) (xy 44.978553 -17.795464) (xy 44.949088 -17.841313) (xy 44.913397 -17.882501)
			(xy 44.872208 -17.918191) (xy 44.826359 -17.947656) (xy 44.776783 -17.970296) (xy 44.72449 -17.98565)
			(xy 44.670544 -17.993405) (xy 44.643294 -17.993868) (xy 43.779694 -17.993868) (xy 43.75244 -17.993462)
			(xy 43.698487 -17.985704) (xy 43.646188 -17.970346) (xy 43.596606 -17.947703) (xy 43.550752 -17.918233)
			(xy 43.509558 -17.882538) (xy 43.473863 -17.841343) (xy 43.444395 -17.795488) (xy 43.421751 -17.745906)
			(xy 43.406395 -17.693607) (xy 43.398638 -17.639654) (xy 39.130505 -17.639654) (xy 39.122748 -17.693598)
			(xy 39.107392 -17.745892) (xy 39.084751 -17.795469) (xy 39.055284 -17.841318) (xy 39.019591 -17.882507)
			(xy 38.9784 -17.918197) (xy 38.932549 -17.947661) (xy 38.882972 -17.9703) (xy 38.830677 -17.985653)
			(xy 38.776729 -17.993406) (xy 38.749478 -17.993868) (xy 37.885878 -17.993868) (xy 37.858625 -17.993461)
			(xy 37.804674 -17.985701) (xy 37.752376 -17.970342) (xy 37.702797 -17.947697) (xy 37.656944 -17.918227)
			(xy 37.615752 -17.882532) (xy 37.580059 -17.841338) (xy 37.550592 -17.795484) (xy 37.52795 -17.745903)
			(xy 37.512595 -17.693605) (xy 37.504838 -17.639653) (xy 33.542505 -17.639653) (xy 33.534748 -17.693598)
			(xy 33.519392 -17.745892) (xy 33.496751 -17.795469) (xy 33.467284 -17.841318) (xy 33.431591 -17.882507)
			(xy 33.3904 -17.918197) (xy 33.344549 -17.947661) (xy 33.294972 -17.9703) (xy 33.242677 -17.985653)
			(xy 33.188729 -17.993406) (xy 33.161478 -17.993868) (xy 32.297878 -17.993868) (xy 32.270625 -17.993461)
			(xy 32.216674 -17.985701) (xy 32.164376 -17.970342) (xy 32.114797 -17.947697) (xy 32.068944 -17.918227)
			(xy 32.027752 -17.882532) (xy 31.992059 -17.841338) (xy 31.962592 -17.795484) (xy 31.93995 -17.745903)
			(xy 31.924595 -17.693605) (xy 31.916838 -17.639653) (xy 27.954505 -17.639653) (xy 27.946748 -17.693598)
			(xy 27.931392 -17.745892) (xy 27.908751 -17.795469) (xy 27.879284 -17.841318) (xy 27.843591 -17.882507)
			(xy 27.8024 -17.918197) (xy 27.756549 -17.947661) (xy 27.706972 -17.9703) (xy 27.654677 -17.985653)
			(xy 27.600729 -17.993406) (xy 27.573478 -17.993868) (xy 26.709878 -17.993868) (xy 26.682625 -17.993461)
			(xy 26.628674 -17.985701) (xy 26.576376 -17.970342) (xy 26.526797 -17.947697) (xy 26.480944 -17.918227)
			(xy 26.439752 -17.882532) (xy 26.404059 -17.841338) (xy 26.374592 -17.795484) (xy 26.35195 -17.745903)
			(xy 26.336595 -17.693605) (xy 26.328838 -17.639653) (xy 22.366505 -17.639653) (xy 22.358748 -17.693598)
			(xy 22.343392 -17.745892) (xy 22.320751 -17.795469) (xy 22.291284 -17.841318) (xy 22.255591 -17.882507)
			(xy 22.2144 -17.918197) (xy 22.168549 -17.947661) (xy 22.118972 -17.9703) (xy 22.066677 -17.985653)
			(xy 22.012729 -17.993406) (xy 21.985478 -17.993868) (xy 21.121878 -17.993868) (xy 21.094627 -17.993382)
			(xy 21.040679 -17.985625) (xy 20.988385 -17.97027) (xy 20.938808 -17.947629) (xy 20.892958 -17.918162)
			(xy 20.851768 -17.882471) (xy 20.816076 -17.841281) (xy 20.78661 -17.79543) (xy 20.763969 -17.745853)
			(xy 20.748614 -17.693559) (xy 20.740858 -17.639611) (xy 16.778525 -17.639611) (xy 16.778525 -17.639613)
			(xy 16.770768 -17.693564) (xy 16.755412 -17.745862) (xy 16.732769 -17.795442) (xy 16.703301 -17.841296)
			(xy 16.667607 -17.882488) (xy 16.626414 -17.918182) (xy 16.580561 -17.94765) (xy 16.53098 -17.970292)
			(xy 16.478682 -17.985648) (xy 16.424731 -17.993405) (xy 16.397478 -17.993868) (xy 15.533878 -17.993868)
			(xy 15.506627 -17.993382) (xy 15.452679 -17.985625) (xy 15.400385 -17.97027) (xy 15.350808 -17.947629)
			(xy 15.304958 -17.918162) (xy 15.263768 -17.882471) (xy 15.228076 -17.841281) (xy 15.19861 -17.79543)
			(xy 15.175969 -17.745853) (xy 15.160614 -17.693559) (xy 15.152858 -17.639611) (xy 9.462533 -17.639611)
			(xy 9.516208 -17.667423) (xy 9.695034 -17.769123) (xy 9.869756 -17.877723) (xy 10.040109 -17.993058)
			(xy 10.205831 -18.114951) (xy 10.366672 -18.243217) (xy 10.522385 -18.37766) (xy 10.672735 -18.518077)
			(xy 10.817492 -18.664253) (xy 10.956435 -18.815965) (xy 11.089353 -18.972983) (xy 11.216044 -19.135068)
			(xy 11.236612 -19.163611) (xy 17.946858 -19.163611) (xy 17.946858 -19.109109) (xy 17.954614 -19.055161)
			(xy 17.969969 -19.002867) (xy 17.99261 -18.95329) (xy 18.022076 -18.907439) (xy 18.057768 -18.866249)
			(xy 18.098958 -18.830558) (xy 18.144808 -18.801091) (xy 18.194385 -18.77845) (xy 18.246679 -18.763095)
			(xy 18.300627 -18.755338) (xy 18.327878 -18.754852) (xy 19.191478 -18.754852) (xy 19.218731 -18.755315)
			(xy 19.272682 -18.763072) (xy 19.32498 -18.778428) (xy 19.374561 -18.80107) (xy 19.420414 -18.830538)
			(xy 19.461607 -18.866232) (xy 19.497301 -18.907424) (xy 19.526769 -18.953278) (xy 19.549412 -19.002858)
			(xy 19.564768 -19.055156) (xy 19.572525 -19.109107) (xy 19.572525 -19.163613) (xy 19.572519 -19.163653)
			(xy 23.534838 -19.163653) (xy 23.534838 -19.109147) (xy 23.542595 -19.055195) (xy 23.55795 -19.002897)
			(xy 23.580592 -18.953316) (xy 23.610059 -18.907462) (xy 23.645752 -18.866268) (xy 23.686944 -18.830573)
			(xy 23.732797 -18.801103) (xy 23.782376 -18.778458) (xy 23.834674 -18.763099) (xy 23.888625 -18.755339)
			(xy 23.915878 -18.754852) (xy 24.779478 -18.754852) (xy 24.806729 -18.755394) (xy 24.860677 -18.763147)
			(xy 24.912972 -18.7785) (xy 24.962549 -18.801139) (xy 25.0084 -18.830603) (xy 25.049591 -18.866293)
			(xy 25.085284 -18.907482) (xy 25.114751 -18.953331) (xy 25.137392 -19.002908) (xy 25.152748 -19.055202)
			(xy 25.160505 -19.109149) (xy 25.160505 -19.163651) (xy 25.160505 -19.163653) (xy 29.122838 -19.163653)
			(xy 29.122838 -19.109147) (xy 29.130595 -19.055195) (xy 29.14595 -19.002897) (xy 29.168592 -18.953316)
			(xy 29.198059 -18.907462) (xy 29.233752 -18.866268) (xy 29.274944 -18.830573) (xy 29.320797 -18.801103)
			(xy 29.370376 -18.778458) (xy 29.422674 -18.763099) (xy 29.476625 -18.755339) (xy 29.503878 -18.754852)
			(xy 30.367478 -18.754852) (xy 30.394729 -18.755394) (xy 30.448677 -18.763147) (xy 30.500972 -18.7785)
			(xy 30.550549 -18.801139) (xy 30.5964 -18.830603) (xy 30.637591 -18.866293) (xy 30.673284 -18.907482)
			(xy 30.702751 -18.953331) (xy 30.725392 -19.002908) (xy 30.740748 -19.055202) (xy 30.748505 -19.109149)
			(xy 30.748505 -19.163651) (xy 30.748505 -19.163653) (xy 34.710838 -19.163653) (xy 34.710838 -19.109147)
			(xy 34.718595 -19.055195) (xy 34.73395 -19.002897) (xy 34.756592 -18.953316) (xy 34.786059 -18.907462)
			(xy 34.821752 -18.866268) (xy 34.862944 -18.830573) (xy 34.908797 -18.801103) (xy 34.958376 -18.778458)
			(xy 35.010674 -18.763099) (xy 35.064625 -18.755339) (xy 35.091878 -18.754852) (xy 35.955478 -18.754852)
			(xy 35.982729 -18.755394) (xy 36.036677 -18.763147) (xy 36.088972 -18.7785) (xy 36.138549 -18.801139)
			(xy 36.1844 -18.830603) (xy 36.225591 -18.866293) (xy 36.261284 -18.907482) (xy 36.290751 -18.953331)
			(xy 36.313392 -19.002908) (xy 36.328748 -19.055202) (xy 36.336505 -19.109149) (xy 36.336505 -19.163651)
			(xy 36.336505 -19.163654) (xy 40.604638 -19.163654) (xy 40.604638 -19.109146) (xy 40.612395 -19.055193)
			(xy 40.627751 -19.002894) (xy 40.650395 -18.953312) (xy 40.679863 -18.907457) (xy 40.715558 -18.866262)
			(xy 40.756752 -18.830567) (xy 40.802606 -18.801097) (xy 40.852188 -18.778454) (xy 40.904487 -18.763096)
			(xy 40.95844 -18.755338) (xy 40.985694 -18.754852) (xy 41.849294 -18.754852) (xy 41.876544 -18.755395)
			(xy 41.93049 -18.76315) (xy 41.982783 -18.778504) (xy 42.032359 -18.801144) (xy 42.078208 -18.830609)
			(xy 42.119397 -18.866299) (xy 42.155088 -18.907487) (xy 42.184553 -18.953336) (xy 42.207194 -19.002911)
			(xy 42.222548 -19.055204) (xy 42.230305 -19.10915) (xy 42.230305 -19.16365) (xy 42.230304 -19.163654)
			(xy 46.192638 -19.163654) (xy 46.192638 -19.109146) (xy 46.200395 -19.055193) (xy 46.215751 -19.002894)
			(xy 46.238395 -18.953312) (xy 46.267863 -18.907457) (xy 46.303558 -18.866262) (xy 46.344752 -18.830567)
			(xy 46.390606 -18.801097) (xy 46.440188 -18.778454) (xy 46.492487 -18.763096) (xy 46.54644 -18.755338)
			(xy 46.573694 -18.754852) (xy 47.437294 -18.754852) (xy 47.464544 -18.755395) (xy 47.51849 -18.76315)
			(xy 47.570783 -18.778504) (xy 47.620359 -18.801144) (xy 47.666208 -18.830609) (xy 47.707397 -18.866299)
			(xy 47.743088 -18.907487) (xy 47.772553 -18.953336) (xy 47.795194 -19.002911) (xy 47.810548 -19.055204)
			(xy 47.818305 -19.10915) (xy 47.818305 -19.16365) (xy 47.818304 -19.163657) (xy 51.814615 -19.163657)
			(xy 51.814615 -19.109143) (xy 51.822374 -19.055184) (xy 51.837733 -19.002878) (xy 51.86038 -18.95329)
			(xy 51.889854 -18.907431) (xy 51.925554 -18.866233) (xy 51.966755 -18.830536) (xy 52.012617 -18.801065)
			(xy 52.062206 -18.778422) (xy 52.114513 -18.763067) (xy 52.168473 -18.755313) (xy 52.19573 -18.754852)
			(xy 53.05933 -18.754852) (xy 53.086577 -18.75542) (xy 53.140516 -18.763179) (xy 53.192801 -18.778535)
			(xy 53.24237 -18.801176) (xy 53.288211 -18.83064) (xy 53.329394 -18.866328) (xy 53.365078 -18.907513)
			(xy 53.394538 -18.953357) (xy 53.417175 -19.002927) (xy 53.432527 -19.055214) (xy 53.440282 -19.109153)
			(xy 53.440282 -19.163647) (xy 53.440281 -19.163657) (xy 57.402615 -19.163657) (xy 57.402615 -19.109143)
			(xy 57.410374 -19.055184) (xy 57.425733 -19.002878) (xy 57.44838 -18.95329) (xy 57.477854 -18.907431)
			(xy 57.513554 -18.866233) (xy 57.554755 -18.830536) (xy 57.600617 -18.801065) (xy 57.650206 -18.778422)
			(xy 57.702513 -18.763067) (xy 57.756473 -18.755313) (xy 57.78373 -18.754852) (xy 58.64733 -18.754852)
			(xy 58.674577 -18.75542) (xy 58.728516 -18.763179) (xy 58.780801 -18.778535) (xy 58.83037 -18.801176)
			(xy 58.876211 -18.83064) (xy 58.917394 -18.866328) (xy 58.953078 -18.907513) (xy 58.982538 -18.953357)
			(xy 59.005175 -19.002927) (xy 59.020527 -19.055214) (xy 59.028282 -19.109153) (xy 59.028282 -19.163647)
			(xy 59.020527 -19.217586) (xy 59.005175 -19.269873) (xy 58.982538 -19.319443) (xy 58.953078 -19.365287)
			(xy 58.917394 -19.406472) (xy 58.876211 -19.44216) (xy 58.83037 -19.471624) (xy 58.780801 -19.494265)
			(xy 58.728516 -19.509621) (xy 58.674577 -19.51738) (xy 58.64733 -19.517868) (xy 57.78373 -19.517868)
			(xy 57.756473 -19.517487) (xy 57.702513 -19.509733) (xy 57.650206 -19.494378) (xy 57.600617 -19.471735)
			(xy 57.554755 -19.442264) (xy 57.513554 -19.406567) (xy 57.477854 -19.365369) (xy 57.44838 -19.31951)
			(xy 57.425733 -19.269922) (xy 57.410374 -19.217616) (xy 57.402615 -19.163657) (xy 53.440281 -19.163657)
			(xy 53.432527 -19.217586) (xy 53.417175 -19.269873) (xy 53.394538 -19.319443) (xy 53.365078 -19.365287)
			(xy 53.329394 -19.406472) (xy 53.288211 -19.44216) (xy 53.24237 -19.471624) (xy 53.192801 -19.494265)
			(xy 53.140516 -19.509621) (xy 53.086577 -19.51738) (xy 53.05933 -19.517868) (xy 52.19573 -19.517868)
			(xy 52.168473 -19.517487) (xy 52.114513 -19.509733) (xy 52.062206 -19.494378) (xy 52.012617 -19.471735)
			(xy 51.966755 -19.442264) (xy 51.925554 -19.406567) (xy 51.889854 -19.365369) (xy 51.86038 -19.31951)
			(xy 51.837733 -19.269922) (xy 51.822374 -19.217616) (xy 51.814615 -19.163657) (xy 47.818304 -19.163657)
			(xy 47.810548 -19.217596) (xy 47.795194 -19.269889) (xy 47.772553 -19.319464) (xy 47.743088 -19.365313)
			(xy 47.707397 -19.406501) (xy 47.666208 -19.442191) (xy 47.620359 -19.471656) (xy 47.570783 -19.494296)
			(xy 47.51849 -19.50965) (xy 47.464544 -19.517405) (xy 47.437294 -19.517868) (xy 46.573694 -19.517868)
			(xy 46.54644 -19.517462) (xy 46.492487 -19.509704) (xy 46.440188 -19.494346) (xy 46.390606 -19.471703)
			(xy 46.344752 -19.442233) (xy 46.303558 -19.406538) (xy 46.267863 -19.365343) (xy 46.238395 -19.319488)
			(xy 46.215751 -19.269906) (xy 46.200395 -19.217607) (xy 46.192638 -19.163654) (xy 42.230304 -19.163654)
			(xy 42.222548 -19.217596) (xy 42.207194 -19.269889) (xy 42.184553 -19.319464) (xy 42.155088 -19.365313)
			(xy 42.119397 -19.406501) (xy 42.078208 -19.442191) (xy 42.032359 -19.471656) (xy 41.982783 -19.494296)
			(xy 41.93049 -19.50965) (xy 41.876544 -19.517405) (xy 41.849294 -19.517868) (xy 40.985694 -19.517868)
			(xy 40.95844 -19.517462) (xy 40.904487 -19.509704) (xy 40.852188 -19.494346) (xy 40.802606 -19.471703)
			(xy 40.756752 -19.442233) (xy 40.715558 -19.406538) (xy 40.679863 -19.365343) (xy 40.650395 -19.319488)
			(xy 40.627751 -19.269906) (xy 40.612395 -19.217607) (xy 40.604638 -19.163654) (xy 36.336505 -19.163654)
			(xy 36.328748 -19.217598) (xy 36.313392 -19.269892) (xy 36.290751 -19.319469) (xy 36.261284 -19.365318)
			(xy 36.225591 -19.406507) (xy 36.1844 -19.442197) (xy 36.138549 -19.471661) (xy 36.088972 -19.4943)
			(xy 36.036677 -19.509653) (xy 35.982729 -19.517406) (xy 35.955478 -19.517868) (xy 35.091878 -19.517868)
			(xy 35.064625 -19.517461) (xy 35.010674 -19.509701) (xy 34.958376 -19.494342) (xy 34.908797 -19.471697)
			(xy 34.862944 -19.442227) (xy 34.821752 -19.406532) (xy 34.786059 -19.365338) (xy 34.756592 -19.319484)
			(xy 34.73395 -19.269903) (xy 34.718595 -19.217605) (xy 34.710838 -19.163653) (xy 30.748505 -19.163653)
			(xy 30.740748 -19.217598) (xy 30.725392 -19.269892) (xy 30.702751 -19.319469) (xy 30.673284 -19.365318)
			(xy 30.637591 -19.406507) (xy 30.5964 -19.442197) (xy 30.550549 -19.471661) (xy 30.500972 -19.4943)
			(xy 30.448677 -19.509653) (xy 30.394729 -19.517406) (xy 30.367478 -19.517868) (xy 29.503878 -19.517868)
			(xy 29.476625 -19.517461) (xy 29.422674 -19.509701) (xy 29.370376 -19.494342) (xy 29.320797 -19.471697)
			(xy 29.274944 -19.442227) (xy 29.233752 -19.406532) (xy 29.198059 -19.365338) (xy 29.168592 -19.319484)
			(xy 29.14595 -19.269903) (xy 29.130595 -19.217605) (xy 29.122838 -19.163653) (xy 25.160505 -19.163653)
			(xy 25.152748 -19.217598) (xy 25.137392 -19.269892) (xy 25.114751 -19.319469) (xy 25.085284 -19.365318)
			(xy 25.049591 -19.406507) (xy 25.0084 -19.442197) (xy 24.962549 -19.471661) (xy 24.912972 -19.4943)
			(xy 24.860677 -19.509653) (xy 24.806729 -19.517406) (xy 24.779478 -19.517868) (xy 23.915878 -19.517868)
			(xy 23.888625 -19.517461) (xy 23.834674 -19.509701) (xy 23.782376 -19.494342) (xy 23.732797 -19.471697)
			(xy 23.686944 -19.442227) (xy 23.645752 -19.406532) (xy 23.610059 -19.365338) (xy 23.580592 -19.319484)
			(xy 23.55795 -19.269903) (xy 23.542595 -19.217605) (xy 23.534838 -19.163653) (xy 19.572519 -19.163653)
			(xy 19.564768 -19.217564) (xy 19.549412 -19.269862) (xy 19.526769 -19.319442) (xy 19.497301 -19.365296)
			(xy 19.461607 -19.406488) (xy 19.420414 -19.442182) (xy 19.374561 -19.47165) (xy 19.32498 -19.494292)
			(xy 19.272682 -19.509648) (xy 19.218731 -19.517405) (xy 19.191478 -19.517868) (xy 18.327878 -19.517868)
			(xy 18.300627 -19.517382) (xy 18.246679 -19.509625) (xy 18.194385 -19.49427) (xy 18.144808 -19.471629)
			(xy 18.098958 -19.442162) (xy 18.057768 -19.406471) (xy 18.022076 -19.365281) (xy 17.99261 -19.31943)
			(xy 17.969969 -19.269853) (xy 17.954614 -19.217559) (xy 17.946858 -19.163611) (xy 11.236612 -19.163611)
			(xy 11.336314 -19.301971) (xy 11.449981 -19.473441) (xy 11.556871 -19.649214) (xy 11.656822 -19.829024)
			(xy 11.749681 -20.012597) (xy 11.835308 -20.199653) (xy 11.91357 -20.389908) (xy 11.984351 -20.583071)
			(xy 12.047541 -20.778849) (xy 12.103044 -20.976943) (xy 12.150776 -21.177052) (xy 12.190665 -21.37887)
			(xy 12.213074 -21.521251) (xy 15.232366 -21.521251) (xy 15.232366 -21.466749) (xy 15.240122 -21.412801)
			(xy 15.255477 -21.360506) (xy 15.278117 -21.310929) (xy 15.307582 -21.265078) (xy 15.343273 -21.223887)
			(xy 15.384462 -21.188194) (xy 15.430311 -21.158727) (xy 15.479888 -21.136084) (xy 15.532182 -21.120726)
			(xy 15.586129 -21.112967) (xy 15.61338 -21.11248) (xy 16.47698 -21.11248) (xy 16.504233 -21.112966)
			(xy 16.558184 -21.12072) (xy 16.610483 -21.136074) (xy 16.660064 -21.158715) (xy 16.705918 -21.188181)
			(xy 16.747112 -21.223874) (xy 16.782807 -21.265066) (xy 16.812276 -21.310918) (xy 16.834919 -21.360498)
			(xy 16.850275 -21.412796) (xy 16.858033 -21.466747) (xy 16.858033 -21.521253) (xy 16.850275 -21.575204)
			(xy 16.834919 -21.627502) (xy 16.812276 -21.677082) (xy 16.782807 -21.722934) (xy 16.747112 -21.764126)
			(xy 16.705918 -21.799819) (xy 16.660064 -21.829285) (xy 16.610483 -21.851926) (xy 16.558184 -21.86728)
			(xy 16.504233 -21.875034) (xy 16.47698 -21.875496) (xy 15.61338 -21.875496) (xy 15.586129 -21.875033)
			(xy 15.532182 -21.867274) (xy 15.479888 -21.851916) (xy 15.430311 -21.829273) (xy 15.384462 -21.799806)
			(xy 15.343273 -21.764113) (xy 15.307582 -21.722922) (xy 15.278117 -21.677071) (xy 15.255477 -21.627494)
			(xy 15.240122 -21.575199) (xy 15.232366 -21.521251) (xy 12.213074 -21.521251) (xy 12.222649 -21.582092)
			(xy 12.246679 -21.786406) (xy 12.26272 -21.991502) (xy 12.270746 -22.197069) (xy 12.271248 -22.29993)
			(xy 89.628224 -22.29993) (xy 89.632238 -22.094246) (xy 89.644274 -21.888876) (xy 89.664313 -21.684132)
			(xy 89.692326 -21.480325) (xy 89.728269 -21.277766) (xy 89.772088 -21.076764) (xy 89.823715 -20.877625)
			(xy 89.883073 -20.680652) (xy 89.950071 -20.486144) (xy 90.024607 -20.294399) (xy 90.106567 -20.105708)
			(xy 90.195827 -19.920358) (xy 90.29225 -19.738632) (xy 90.395691 -19.560806) (xy 90.50599 -19.387152)
			(xy 90.622981 -19.217933) (xy 90.746485 -19.053407) (xy 90.876314 -18.893826) (xy 91.012271 -18.739431)
			(xy 91.154148 -18.590459) (xy 91.301729 -18.447135) (xy 91.45479 -18.309679) (xy 91.613097 -18.178299)
			(xy 91.77641 -18.053196) (xy 91.944479 -17.934559) (xy 92.117049 -17.822571) (xy 92.293857 -17.7174)
			(xy 92.474634 -17.619209) (xy 92.659104 -17.528145) (xy 92.846986 -17.444348) (xy 93.037996 -17.367945)
			(xy 93.23184 -17.299052) (xy 93.428225 -17.237775) (xy 93.626851 -17.184207) (xy 93.827416 -17.13843)
			(xy 94.029614 -17.100512) (xy 94.233138 -17.070513) (xy 94.437677 -17.048476) (xy 94.64292 -17.034437)
			(xy 94.848555 -17.028417) (xy 95.054268 -17.030424) (xy 95.259746 -17.040456) (xy 95.464676 -17.058497)
			(xy 95.668746 -17.08452) (xy 95.871646 -17.118485) (xy 96.073066 -17.16034) (xy 96.272699 -17.210022)
			(xy 96.470242 -17.267456) (xy 96.665394 -17.332553) (xy 96.857858 -17.405214) (xy 97.04734 -17.48533)
			(xy 97.233551 -17.572777) (xy 97.41621 -17.667423) (xy 97.595036 -17.769123) (xy 97.769758 -17.877723)
			(xy 97.940111 -17.993058) (xy 98.105833 -18.114951) (xy 98.177304 -18.171947) (xy 131.633522 -18.171947)
			(xy 131.633522 -18.117453) (xy 131.641277 -18.063515) (xy 131.656629 -18.011229) (xy 131.679265 -17.961659)
			(xy 131.708725 -17.915816) (xy 131.744409 -17.874631) (xy 131.78559 -17.838944) (xy 131.831431 -17.80948)
			(xy 131.880999 -17.78684) (xy 131.933283 -17.771484) (xy 131.987221 -17.763724) (xy 132.014468 -17.763236)
			(xy 132.878068 -17.763236) (xy 132.905326 -17.763609) (xy 132.959286 -17.771363) (xy 133.011594 -17.786718)
			(xy 133.061184 -17.809361) (xy 133.107046 -17.838832) (xy 133.148248 -17.87453) (xy 133.183949 -17.915728)
			(xy 133.213423 -17.961588) (xy 133.236071 -18.011176) (xy 133.25143 -18.063483) (xy 133.259189 -18.117443)
			(xy 133.259189 -18.17195) (xy 137.033499 -18.17195) (xy 137.033499 -18.11745) (xy 137.041256 -18.063505)
			(xy 137.05661 -18.011212) (xy 137.079251 -17.961637) (xy 137.108716 -17.915789) (xy 137.144406 -17.874601)
			(xy 137.185595 -17.838911) (xy 137.231444 -17.809447) (xy 137.28102 -17.786807) (xy 137.333312 -17.771454)
			(xy 137.387258 -17.763699) (xy 137.414508 -17.763236) (xy 138.278108 -17.763236) (xy 138.305362 -17.763634)
			(xy 138.359315 -17.771393) (xy 138.411615 -17.78675) (xy 138.461197 -17.809395) (xy 138.507052 -17.838864)
			(xy 138.548246 -17.87456) (xy 138.58394 -17.915755) (xy 138.613409 -17.96161) (xy 138.636052 -18.011193)
			(xy 138.651409 -18.063493) (xy 138.659166 -18.117446) (xy 138.659166 -18.171946) (xy 140.633522 -18.171946)
			(xy 140.633522 -18.117454) (xy 140.641276 -18.063517) (xy 140.656627 -18.011232) (xy 140.679262 -17.961664)
			(xy 140.70872 -17.915822) (xy 140.744402 -17.874638) (xy 140.785582 -17.83895) (xy 140.83142 -17.809486)
			(xy 140.880986 -17.786845) (xy 140.933268 -17.771487) (xy 140.987204 -17.763726) (xy 141.01445 -17.763236)
			(xy 141.87805 -17.763236) (xy 141.905308 -17.763608) (xy 141.959271 -17.77136) (xy 142.011581 -17.786713)
			(xy 142.061173 -17.809355) (xy 142.107038 -17.838825) (xy 142.148241 -17.874523) (xy 142.183945 -17.915722)
			(xy 142.213421 -17.961583) (xy 142.236069 -18.011172) (xy 142.25143 -18.06348) (xy 142.259189 -18.117442)
			(xy 142.259189 -18.171951) (xy 185.748399 -18.171951) (xy 185.748399 -18.117449) (xy 185.756156 -18.063503)
			(xy 185.771511 -18.011209) (xy 185.794153 -17.961633) (xy 185.823619 -17.915784) (xy 185.859311 -17.874596)
			(xy 185.900502 -17.838906) (xy 185.946353 -17.809442) (xy 185.99593 -17.786804) (xy 186.048224 -17.771451)
			(xy 186.102171 -17.763698) (xy 186.129422 -17.763236) (xy 186.993022 -17.763236) (xy 187.020275 -17.763635)
			(xy 187.074227 -17.771395) (xy 187.126525 -17.786754) (xy 187.176105 -17.809399) (xy 187.221958 -17.838869)
			(xy 187.263151 -17.874565) (xy 187.298844 -17.915759) (xy 187.328311 -17.961614) (xy 187.350954 -18.011196)
			(xy 187.366309 -18.063495) (xy 187.374066 -18.117447) (xy 187.374066 -18.171953) (xy 187.366309 -18.225905)
			(xy 187.350954 -18.278204) (xy 187.328311 -18.327786) (xy 187.298844 -18.373641) (xy 187.263151 -18.414835)
			(xy 187.221958 -18.450531) (xy 187.176105 -18.480001) (xy 187.126525 -18.502646) (xy 187.074227 -18.518005)
			(xy 187.020275 -18.525765) (xy 186.993022 -18.526252) (xy 186.129422 -18.526252) (xy 186.102171 -18.525702)
			(xy 186.048224 -18.517949) (xy 185.99593 -18.502596) (xy 185.946353 -18.479958) (xy 185.900502 -18.450494)
			(xy 185.859311 -18.414804) (xy 185.823619 -18.373616) (xy 185.794153 -18.327767) (xy 185.771511 -18.278191)
			(xy 185.756156 -18.225897) (xy 185.748399 -18.171951) (xy 142.259189 -18.171951) (xy 142.259189 -18.171958)
			(xy 142.25143 -18.22592) (xy 142.236069 -18.278228) (xy 142.213421 -18.327817) (xy 142.183945 -18.373678)
			(xy 142.148241 -18.414877) (xy 142.107038 -18.450575) (xy 142.061173 -18.480045) (xy 142.011581 -18.502687)
			(xy 141.959271 -18.51804) (xy 141.905308 -18.525792) (xy 141.87805 -18.526252) (xy 141.01445 -18.526252)
			(xy 140.987204 -18.525674) (xy 140.933268 -18.517913) (xy 140.880986 -18.502555) (xy 140.83142 -18.479914)
			(xy 140.785582 -18.45045) (xy 140.744402 -18.414762) (xy 140.70872 -18.373578) (xy 140.679262 -18.327736)
			(xy 140.656627 -18.278168) (xy 140.641276 -18.225883) (xy 140.633522 -18.171946) (xy 138.659166 -18.171946)
			(xy 138.659166 -18.171954) (xy 138.651409 -18.225907) (xy 138.636052 -18.278207) (xy 138.613409 -18.32779)
			(xy 138.58394 -18.373645) (xy 138.548246 -18.41484) (xy 138.507052 -18.450536) (xy 138.461197 -18.480005)
			(xy 138.411615 -18.50265) (xy 138.359315 -18.518007) (xy 138.305362 -18.525766) (xy 138.278108 -18.526252)
			(xy 137.414508 -18.526252) (xy 137.387258 -18.525701) (xy 137.333312 -18.517946) (xy 137.28102 -18.502593)
			(xy 137.231444 -18.479953) (xy 137.185595 -18.450489) (xy 137.144406 -18.414799) (xy 137.108716 -18.373611)
			(xy 137.079251 -18.327763) (xy 137.05661 -18.278188) (xy 137.041256 -18.225895) (xy 137.033499 -18.17195)
			(xy 133.259189 -18.17195) (xy 133.259189 -18.171957) (xy 133.25143 -18.225917) (xy 133.236071 -18.278224)
			(xy 133.213423 -18.327812) (xy 133.183949 -18.373672) (xy 133.148248 -18.41487) (xy 133.107046 -18.450568)
			(xy 133.061184 -18.480039) (xy 133.011594 -18.502682) (xy 132.959286 -18.518037) (xy 132.905326 -18.525791)
			(xy 132.878068 -18.526252) (xy 132.014468 -18.526252) (xy 131.987221 -18.525676) (xy 131.933283 -18.517916)
			(xy 131.880999 -18.50256) (xy 131.831431 -18.47992) (xy 131.78559 -18.450456) (xy 131.744409 -18.414769)
			(xy 131.708725 -18.373584) (xy 131.679265 -18.327741) (xy 131.656629 -18.278171) (xy 131.641277 -18.225885)
			(xy 131.633522 -18.171947) (xy 98.177304 -18.171947) (xy 98.266674 -18.243217) (xy 98.422387 -18.37766)
			(xy 98.572737 -18.518077) (xy 98.717494 -18.664253) (xy 98.856437 -18.815965) (xy 98.989355 -18.972983)
			(xy 99.116046 -19.135068) (xy 99.236316 -19.301971) (xy 99.349983 -19.473441) (xy 99.456873 -19.649214)
			(xy 99.556824 -19.829024) (xy 99.649683 -20.012597) (xy 99.729862 -20.187751) (xy 138.828766 -20.187751)
			(xy 138.828766 -20.133249) (xy 138.836522 -20.079301) (xy 138.851877 -20.027006) (xy 138.874517 -19.977429)
			(xy 138.903982 -19.931578) (xy 138.939673 -19.890387) (xy 138.980862 -19.854694) (xy 139.026711 -19.825227)
			(xy 139.076288 -19.802584) (xy 139.128582 -19.787226) (xy 139.182529 -19.779467) (xy 139.20978 -19.77898)
			(xy 140.07338 -19.77898) (xy 140.100633 -19.779466) (xy 140.154584 -19.78722) (xy 140.206883 -19.802574)
			(xy 140.256464 -19.825215) (xy 140.302318 -19.854681) (xy 140.343512 -19.890374) (xy 140.379207 -19.931566)
			(xy 140.408676 -19.977418) (xy 140.431319 -20.026998) (xy 140.446675 -20.079296) (xy 140.454433 -20.133247)
			(xy 140.454433 -20.187753) (xy 140.446675 -20.241704) (xy 140.431319 -20.294002) (xy 140.408676 -20.343582)
			(xy 140.379207 -20.389434) (xy 140.343512 -20.430626) (xy 140.302318 -20.466319) (xy 140.256464 -20.495785)
			(xy 140.206883 -20.518426) (xy 140.154584 -20.53378) (xy 140.100633 -20.541534) (xy 140.07338 -20.541996)
			(xy 139.20978 -20.541996) (xy 139.182529 -20.541533) (xy 139.128582 -20.533774) (xy 139.076288 -20.518416)
			(xy 139.026711 -20.495773) (xy 138.980862 -20.466306) (xy 138.939673 -20.430613) (xy 138.903982 -20.389422)
			(xy 138.874517 -20.343571) (xy 138.851877 -20.293994) (xy 138.836522 -20.241699) (xy 138.828766 -20.187751)
			(xy 99.729862 -20.187751) (xy 99.73531 -20.199653) (xy 99.813572 -20.389908) (xy 99.884353 -20.583071)
			(xy 99.947543 -20.778849) (xy 100.003046 -20.976943) (xy 100.050778 -21.177052) (xy 100.090667 -21.37887)
			(xy 100.122651 -21.582092) (xy 100.146681 -21.786406) (xy 100.162722 -21.991502) (xy 100.170748 -22.197069)
			(xy 100.17125 -22.29993) (xy 198.128134 -22.29993) (xy 198.132148 -22.094246) (xy 198.144184 -21.888876)
			(xy 198.164223 -21.684132) (xy 198.192236 -21.480325) (xy 198.228179 -21.277766) (xy 198.271998 -21.076764)
			(xy 198.323625 -20.877625) (xy 198.382983 -20.680652) (xy 198.449981 -20.486144) (xy 198.524517 -20.294399)
			(xy 198.606477 -20.105708) (xy 198.695737 -19.920358) (xy 198.79216 -19.738632) (xy 198.895601 -19.560806)
			(xy 199.0059 -19.387152) (xy 199.122891 -19.217933) (xy 199.246395 -19.053407) (xy 199.376224 -18.893826)
			(xy 199.512181 -18.739431) (xy 199.654058 -18.590459) (xy 199.801639 -18.447135) (xy 199.9547 -18.309679)
			(xy 200.113007 -18.178299) (xy 200.27632 -18.053196) (xy 200.444389 -17.934559) (xy 200.616959 -17.822571)
			(xy 200.793767 -17.7174) (xy 200.974544 -17.619209) (xy 201.159014 -17.528145) (xy 201.346896 -17.444348)
			(xy 201.537906 -17.367945) (xy 201.73175 -17.299052) (xy 201.928135 -17.237775) (xy 202.126761 -17.184207)
			(xy 202.327326 -17.13843) (xy 202.529524 -17.100512) (xy 202.733048 -17.070513) (xy 202.937587 -17.048476)
			(xy 203.14283 -17.034437) (xy 203.348465 -17.028417) (xy 203.554178 -17.030424) (xy 203.759656 -17.040456)
			(xy 203.964586 -17.058497) (xy 204.168656 -17.08452) (xy 204.371556 -17.118485) (xy 204.572976 -17.16034)
			(xy 204.772609 -17.210022) (xy 204.970152 -17.267456) (xy 205.165304 -17.332553) (xy 205.357768 -17.405214)
			(xy 205.54725 -17.48533) (xy 205.733461 -17.572777) (xy 205.91612 -17.667423) (xy 206.094946 -17.769123)
			(xy 206.185737 -17.825555) (xy 218.803143 -17.825555) (xy 218.803143 -17.771045) (xy 218.810901 -17.717091)
			(xy 218.826258 -17.66479) (xy 218.848903 -17.615207) (xy 218.878374 -17.569351) (xy 218.914071 -17.528157)
			(xy 218.955267 -17.492462) (xy 219.001124 -17.462993) (xy 219.050709 -17.440351) (xy 219.10301 -17.424996)
			(xy 219.156965 -17.417242) (xy 219.18422 -17.41678) (xy 220.04782 -17.41678) (xy 220.075069 -17.417292)
			(xy 220.129013 -17.42505) (xy 220.181304 -17.440407) (xy 220.230877 -17.463048) (xy 220.276723 -17.492514)
			(xy 220.31791 -17.528204) (xy 220.353598 -17.569393) (xy 220.383062 -17.615241) (xy 220.4057 -17.664815)
			(xy 220.421054 -17.717106) (xy 220.42881 -17.771051) (xy 220.42881 -17.825549) (xy 220.421054 -17.879494)
			(xy 220.4057 -17.931785) (xy 220.383062 -17.981359) (xy 220.353598 -18.027207) (xy 220.31791 -18.068396)
			(xy 220.276723 -18.104086) (xy 220.230877 -18.133552) (xy 220.181304 -18.156193) (xy 220.129013 -18.17155)
			(xy 220.075069 -18.179308) (xy 220.04782 -18.179796) (xy 219.18422 -18.179796) (xy 219.156965 -18.179358)
			(xy 219.10301 -18.171604) (xy 219.050709 -18.156249) (xy 219.001124 -18.133607) (xy 218.955267 -18.104138)
			(xy 218.914071 -18.068443) (xy 218.878374 -18.027249) (xy 218.848903 -17.981393) (xy 218.826258 -17.93181)
			(xy 218.810901 -17.879509) (xy 218.803143 -17.825555) (xy 206.185737 -17.825555) (xy 206.269668 -17.877723)
			(xy 206.440021 -17.993058) (xy 206.605743 -18.114951) (xy 206.766584 -18.243217) (xy 206.922297 -18.37766)
			(xy 207.072647 -18.518077) (xy 207.217404 -18.664253) (xy 207.356347 -18.815965) (xy 207.489265 -18.972983)
			(xy 207.615956 -19.135068) (xy 207.736226 -19.301971) (xy 207.849893 -19.473441) (xy 207.956783 -19.649214)
			(xy 208.056734 -19.829024) (xy 208.149593 -20.012597) (xy 208.23522 -20.199653) (xy 208.313482 -20.389908)
			(xy 208.384263 -20.583071) (xy 208.447453 -20.778849) (xy 208.502956 -20.976943) (xy 208.550688 -21.177052)
			(xy 208.590577 -21.37887) (xy 208.622561 -21.582092) (xy 208.646591 -21.786406) (xy 208.662632 -21.991502)
			(xy 208.670658 -22.197069) (xy 208.67116 -22.29993) (xy 208.670658 -22.402791) (xy 208.662632 -22.608358)
			(xy 208.646591 -22.813454) (xy 208.622561 -23.017768) (xy 208.590577 -23.22099) (xy 208.550688 -23.422808)
			(xy 208.502956 -23.622917) (xy 208.447453 -23.821011) (xy 208.384263 -24.016789) (xy 208.313482 -24.209952)
			(xy 208.23522 -24.400207) (xy 208.149593 -24.587263) (xy 208.056734 -24.770836) (xy 207.956783 -24.950646)
			(xy 207.849893 -25.126419) (xy 207.736226 -25.297889) (xy 207.615956 -25.464792) (xy 207.489265 -25.626877)
			(xy 207.356347 -25.783895) (xy 207.217404 -25.935607) (xy 207.072647 -26.081783) (xy 206.922297 -26.2222)
			(xy 206.766584 -26.356643) (xy 206.605743 -26.484909) (xy 206.440021 -26.606802) (xy 206.269668 -26.722137)
			(xy 206.094946 -26.830737) (xy 205.91612 -26.932437) (xy 205.733461 -27.027083) (xy 205.54725 -27.11453)
			(xy 205.357768 -27.194646) (xy 205.165304 -27.267307) (xy 204.970152 -27.332404) (xy 204.772609 -27.389838)
			(xy 204.572976 -27.43952) (xy 204.371556 -27.481375) (xy 204.168656 -27.51534) (xy 203.964586 -27.541363)
			(xy 203.759656 -27.559404) (xy 203.554178 -27.569436) (xy 203.348465 -27.571443) (xy 203.14283 -27.565423)
			(xy 202.937587 -27.551384) (xy 202.733048 -27.529347) (xy 202.529524 -27.499348) (xy 202.327326 -27.46143)
			(xy 202.126761 -27.415653) (xy 201.928135 -27.362085) (xy 201.73175 -27.300808) (xy 201.537906 -27.231915)
			(xy 201.346896 -27.155512) (xy 201.159014 -27.071715) (xy 200.974544 -26.980651) (xy 200.793767 -26.88246)
			(xy 200.616959 -26.777289) (xy 200.444389 -26.665301) (xy 200.27632 -26.546664) (xy 200.113007 -26.421561)
			(xy 199.9547 -26.290181) (xy 199.801639 -26.152725) (xy 199.654058 -26.009401) (xy 199.512181 -25.860429)
			(xy 199.376224 -25.706034) (xy 199.246395 -25.546453) (xy 199.122891 -25.381927) (xy 199.0059 -25.212708)
			(xy 198.895601 -25.039054) (xy 198.79216 -24.861228) (xy 198.695737 -24.679502) (xy 198.606477 -24.494152)
			(xy 198.524517 -24.305461) (xy 198.449981 -24.113716) (xy 198.382983 -23.919208) (xy 198.323625 -23.722235)
			(xy 198.271998 -23.523096) (xy 198.228179 -23.322094) (xy 198.192236 -23.119535) (xy 198.164223 -22.915728)
			(xy 198.144184 -22.710984) (xy 198.132148 -22.505614) (xy 198.128134 -22.29993) (xy 100.17125 -22.29993)
			(xy 100.170748 -22.402791) (xy 100.162722 -22.608358) (xy 100.146681 -22.813454) (xy 100.122651 -23.017768)
			(xy 100.090667 -23.22099) (xy 100.050778 -23.422808) (xy 100.003046 -23.622917) (xy 99.947543 -23.821011)
			(xy 99.884353 -24.016789) (xy 99.813572 -24.209952) (xy 99.73531 -24.400207) (xy 99.649683 -24.587263)
			(xy 99.556824 -24.770836) (xy 99.468717 -24.929338) (xy 133.555232 -24.929338) (xy 133.555232 -24.065738)
			(xy 133.555718 -24.038487) (xy 133.563474 -23.984539) (xy 133.578829 -23.932244) (xy 133.601471 -23.882667)
			(xy 133.630937 -23.836817) (xy 133.666628 -23.795626) (xy 133.707819 -23.759935) (xy 133.753669 -23.730469)
			(xy 133.803246 -23.707827) (xy 133.855541 -23.692472) (xy 133.909489 -23.684716) (xy 133.963991 -23.684716)
			(xy 134.017939 -23.692472) (xy 134.070234 -23.707827) (xy 134.119811 -23.730469) (xy 134.165661 -23.759935)
			(xy 134.206852 -23.795626) (xy 134.242543 -23.836817) (xy 134.272009 -23.882667) (xy 134.294651 -23.932244)
			(xy 134.310006 -23.984539) (xy 134.317762 -24.038487) (xy 134.318248 -24.065738) (xy 134.318248 -24.929338)
			(xy 134.317762 -24.956589) (xy 134.310006 -25.010537) (xy 134.294651 -25.062832) (xy 134.272009 -25.112409)
			(xy 134.242543 -25.158259) (xy 134.206852 -25.19945) (xy 134.165661 -25.235141) (xy 134.119811 -25.264607)
			(xy 134.070234 -25.287249) (xy 134.017939 -25.302604) (xy 133.963991 -25.31036) (xy 133.909489 -25.31036)
			(xy 133.855541 -25.302604) (xy 133.803246 -25.287249) (xy 133.753669 -25.264607) (xy 133.707819 -25.235141)
			(xy 133.666628 -25.19945) (xy 133.630937 -25.158259) (xy 133.601471 -25.112409) (xy 133.578829 -25.062832)
			(xy 133.563474 -25.010537) (xy 133.555718 -24.956589) (xy 133.555232 -24.929338) (xy 99.468717 -24.929338)
			(xy 99.456873 -24.950646) (xy 99.349983 -25.126419) (xy 99.236316 -25.297889) (xy 99.116046 -25.464792)
			(xy 98.989355 -25.626877) (xy 98.856437 -25.783895) (xy 98.717494 -25.935607) (xy 98.572737 -26.081783)
			(xy 98.422387 -26.2222) (xy 98.266674 -26.356643) (xy 98.105833 -26.484909) (xy 97.940111 -26.606802)
			(xy 97.769758 -26.722137) (xy 97.595036 -26.830737) (xy 97.41621 -26.932437) (xy 97.233551 -27.027083)
			(xy 97.04734 -27.11453) (xy 96.857858 -27.194646) (xy 96.665394 -27.267307) (xy 96.470242 -27.332404)
			(xy 96.272699 -27.389838) (xy 96.073066 -27.43952) (xy 95.871646 -27.481375) (xy 95.668746 -27.51534)
			(xy 95.464676 -27.541363) (xy 95.259746 -27.559404) (xy 95.054268 -27.569436) (xy 94.848555 -27.571443)
			(xy 94.64292 -27.565423) (xy 94.437677 -27.551384) (xy 94.233138 -27.529347) (xy 94.029614 -27.499348)
			(xy 93.827416 -27.46143) (xy 93.626851 -27.415653) (xy 93.428225 -27.362085) (xy 93.23184 -27.300808)
			(xy 93.037996 -27.231915) (xy 92.846986 -27.155512) (xy 92.659104 -27.071715) (xy 92.474634 -26.980651)
			(xy 92.293857 -26.88246) (xy 92.117049 -26.777289) (xy 91.944479 -26.665301) (xy 91.77641 -26.546664)
			(xy 91.613097 -26.421561) (xy 91.45479 -26.290181) (xy 91.301729 -26.152725) (xy 91.154148 -26.009401)
			(xy 91.012271 -25.860429) (xy 90.876314 -25.706034) (xy 90.746485 -25.546453) (xy 90.622981 -25.381927)
			(xy 90.50599 -25.212708) (xy 90.395691 -25.039054) (xy 90.29225 -24.861228) (xy 90.195827 -24.679502)
			(xy 90.106567 -24.494152) (xy 90.024607 -24.305461) (xy 89.950071 -24.113716) (xy 89.883073 -23.919208)
			(xy 89.823715 -23.722235) (xy 89.772088 -23.523096) (xy 89.728269 -23.322094) (xy 89.692326 -23.119535)
			(xy 89.664313 -22.915728) (xy 89.644274 -22.710984) (xy 89.632238 -22.505614) (xy 89.628224 -22.29993)
			(xy 12.271248 -22.29993) (xy 12.270746 -22.402791) (xy 12.26272 -22.608358) (xy 12.246679 -22.813454)
			(xy 12.222649 -23.017768) (xy 12.190665 -23.22099) (xy 12.150776 -23.422808) (xy 12.103044 -23.622917)
			(xy 12.047541 -23.821011) (xy 11.984351 -24.016789) (xy 11.91357 -24.209952) (xy 11.835308 -24.400207)
			(xy 11.749681 -24.587263) (xy 11.656822 -24.770836) (xy 11.556871 -24.950646) (xy 11.449981 -25.126419)
			(xy 11.336314 -25.297889) (xy 11.216044 -25.464792) (xy 11.089353 -25.626877) (xy 10.956435 -25.783895)
			(xy 10.817492 -25.935607) (xy 10.672735 -26.081783) (xy 10.522385 -26.2222) (xy 10.366672 -26.356643)
			(xy 10.205831 -26.484909) (xy 10.040109 -26.606802) (xy 9.869756 -26.722137) (xy 9.695034 -26.830737)
			(xy 9.516208 -26.932437) (xy 9.333549 -27.027083) (xy 9.147338 -27.11453) (xy 8.957856 -27.194646)
			(xy 8.765392 -27.267307) (xy 8.57024 -27.332404) (xy 8.372697 -27.389838) (xy 8.173064 -27.43952)
			(xy 7.971644 -27.481375) (xy 7.768744 -27.51534) (xy 7.564674 -27.541363) (xy 7.359744 -27.559404)
			(xy 7.154266 -27.569436) (xy 6.948553 -27.571443) (xy 6.742918 -27.565423) (xy 6.537675 -27.551384)
			(xy 6.333136 -27.529347) (xy 6.129612 -27.499348) (xy 5.927414 -27.46143) (xy 5.726849 -27.415653)
			(xy 5.528223 -27.362085) (xy 5.331838 -27.300808) (xy 5.137994 -27.231915) (xy 4.946984 -27.155512)
			(xy 4.759102 -27.071715) (xy 4.574632 -26.980651) (xy 4.393855 -26.88246) (xy 4.217047 -26.777289)
			(xy 4.044477 -26.665301) (xy 3.876408 -26.546664) (xy 3.713095 -26.421561) (xy 3.554788 -26.290181)
			(xy 3.401727 -26.152725) (xy 3.254146 -26.009401) (xy 3.112269 -25.860429) (xy 2.976312 -25.706034)
			(xy 2.846483 -25.546453) (xy 2.722979 -25.381927) (xy 2.605988 -25.212708) (xy 2.495689 -25.039054)
			(xy 2.392248 -24.861228) (xy 2.295825 -24.679502) (xy 2.206565 -24.494152) (xy 2.124605 -24.305461)
			(xy 2.050069 -24.113716) (xy 1.983071 -23.919208) (xy 1.923713 -23.722235) (xy 1.872086 -23.523096)
			(xy 1.828267 -23.322094) (xy 1.792324 -23.119535) (xy 1.764311 -22.915728) (xy 1.744272 -22.710984)
			(xy 1.732236 -22.505614) (xy 1.728222 -22.29993) (xy 1.524 -22.29993) (xy 1.524 -29.070615) (xy 12.244307 -29.070615)
			(xy 12.252198 -28.941486) (xy 12.268182 -28.813107) (xy 12.292195 -28.685984) (xy 12.324144 -28.560621)
			(xy 12.363901 -28.437511) (xy 12.41131 -28.31714) (xy 12.466183 -28.199984) (xy 12.528305 -28.086504)
			(xy 12.59743 -27.97715) (xy 12.673285 -27.872351) (xy 12.75557 -27.772522) (xy 12.843962 -27.678057)
			(xy 12.938111 -27.589329) (xy 13.037646 -27.506688) (xy 13.142173 -27.43046) (xy 13.25128 -27.360945)
			(xy 13.364537 -27.298419) (xy 13.481497 -27.243128) (xy 13.601698 -27.19529) (xy 13.724665 -27.155093)
			(xy 13.849914 -27.122698) (xy 13.97695 -27.098231) (xy 14.105271 -27.081789) (xy 14.234372 -27.073437)
			(xy 14.363742 -27.073208) (xy 14.492871 -27.081103) (xy 14.62125 -27.097091) (xy 14.748372 -27.121108)
			(xy 14.873734 -27.15306) (xy 14.996843 -27.19282) (xy 15.117212 -27.240232) (xy 15.234367 -27.295109)
			(xy 15.347845 -27.357234) (xy 15.457198 -27.426362) (xy 15.561994 -27.50222) (xy 15.661821 -27.584508)
			(xy 15.709392 -27.628342) (xy 16.877792 -28.721304) (xy 16.92464 -28.765906) (xy 17.013363 -28.860052)
			(xy 17.096 -28.959584) (xy 17.172224 -29.064107) (xy 17.241734 -29.17321) (xy 17.304257 -29.286463)
			(xy 17.359545 -29.403418) (xy 17.407381 -29.523614) (xy 17.447575 -29.646576) (xy 17.479969 -29.771819)
			(xy 17.504435 -29.898849) (xy 17.520877 -30.027165) (xy 17.529229 -30.15626) (xy 17.529459 -30.285624)
			(xy 17.521566 -30.414748) (xy 17.50558 -30.543122) (xy 17.481566 -30.670238) (xy 17.449617 -30.795596)
			(xy 17.40986 -30.9187) (xy 17.362452 -31.039065) (xy 17.30758 -31.156215) (xy 17.24546 -31.26969)
			(xy 17.176338 -31.379039) (xy 17.100486 -31.483833) (xy 17.018204 -31.583657) (xy 16.929816 -31.678118)
			(xy 16.835671 -31.766843) (xy 16.736141 -31.849481) (xy 16.631619 -31.925706) (xy 16.522517 -31.995218)
			(xy 16.409265 -32.057743) (xy 16.292311 -32.113033) (xy 16.172116 -32.16087) (xy 16.049154 -32.201066)
			(xy 15.923911 -32.233462) (xy 15.796882 -32.25793) (xy 15.668566 -32.274374) (xy 15.539471 -32.282728)
			(xy 15.410107 -32.28296) (xy 15.280983 -32.275069) (xy 15.152609 -32.259085) (xy 15.025493 -32.235073)
			(xy 14.900134 -32.203126) (xy 14.77703 -32.163371) (xy 14.656664 -32.115965) (xy 14.539512 -32.061094)
			(xy 14.426037 -31.998976) (xy 14.316687 -31.929855) (xy 14.211892 -31.854005) (xy 14.112066 -31.771724)
			(xy 14.064488 -31.727902) (xy 12.896088 -30.63494) (xy 12.849198 -30.590378) (xy 12.760467 -30.496232)
			(xy 12.677823 -30.3967) (xy 12.601592 -30.292174) (xy 12.532074 -30.183069) (xy 12.469545 -30.069814)
			(xy 12.41425 -29.952855) (xy 12.366409 -29.832656) (xy 12.32621 -29.70969) (xy 12.293811 -29.584442)
			(xy 12.26934 -29.457407) (xy 12.252895 -29.329086) (xy 12.244539 -29.199985) (xy 12.244307 -29.070615)
			(xy 1.524 -29.070615) (xy 1.524 -43.999912) (xy 16.983969 -43.999912) (xy 16.987993 -43.914144) (xy 17.000031 -43.82913)
			(xy 17.019978 -43.745616) (xy 17.047657 -43.664337) (xy 17.082825 -43.586008) (xy 17.125174 -43.511315)
			(xy 17.174331 -43.440917) (xy 17.229864 -43.375431) (xy 17.291286 -43.315433) (xy 17.358055 -43.26145)
			(xy 17.429587 -43.213957) (xy 17.505251 -43.173371) (xy 17.584384 -43.140048) (xy 17.666289 -43.114282)
			(xy 17.750247 -43.096299) (xy 17.835521 -43.086257) (xy 17.92136 -43.084244) (xy 18.00701 -43.090278)
			(xy 18.091718 -43.104306) (xy 18.174741 -43.126205) (xy 18.255349 -43.155782) (xy 18.332833 -43.192777)
			(xy 18.406512 -43.236865) (xy 18.475738 -43.287659) (xy 18.539905 -43.344712) (xy 18.598446 -43.407523)
			(xy 18.650849 -43.47554) (xy 18.696652 -43.548165) (xy 18.735453 -43.62476) (xy 18.766912 -43.704652)
			(xy 18.790751 -43.787139) (xy 18.806761 -43.871496) (xy 18.814801 -43.956981) (xy 18.815304 -43.999912)
			(xy 18.814801 -44.042843) (xy 18.806761 -44.128328) (xy 18.790751 -44.212685) (xy 18.766912 -44.295172)
			(xy 18.735453 -44.375064) (xy 18.696652 -44.451659) (xy 18.650849 -44.524284) (xy 18.598446 -44.592301)
			(xy 18.539905 -44.655112) (xy 18.475738 -44.712165) (xy 18.406512 -44.762959) (xy 18.332833 -44.807047)
			(xy 18.255349 -44.844042) (xy 18.174741 -44.873619) (xy 18.091718 -44.895518) (xy 18.00701 -44.909546)
			(xy 17.92136 -44.91558) (xy 17.835521 -44.913567) (xy 17.750247 -44.903525) (xy 17.666289 -44.885542)
			(xy 17.584384 -44.859776) (xy 17.505251 -44.826453) (xy 17.429587 -44.785867) (xy 17.358055 -44.738374)
			(xy 17.291286 -44.684391) (xy 17.229864 -44.624393) (xy 17.174331 -44.558907) (xy 17.125174 -44.488509)
			(xy 17.082825 -44.413816) (xy 17.047657 -44.335487) (xy 17.019978 -44.254208) (xy 17.000031 -44.170694)
			(xy 16.987993 -44.08568) (xy 16.983969 -43.999912) (xy 1.524 -43.999912) (xy 1.524 -59.99988) (xy 16.983969 -59.99988)
			(xy 16.987993 -59.914112) (xy 17.000031 -59.829098) (xy 17.019978 -59.745584) (xy 17.047657 -59.664305)
			(xy 17.082825 -59.585976) (xy 17.125174 -59.511283) (xy 17.174331 -59.440885) (xy 17.229864 -59.375399)
			(xy 17.291286 -59.315401) (xy 17.358055 -59.261418) (xy 17.429587 -59.213925) (xy 17.505251 -59.173339)
			(xy 17.584384 -59.140016) (xy 17.666289 -59.11425) (xy 17.750247 -59.096267) (xy 17.835521 -59.086225)
			(xy 17.92136 -59.084212) (xy 18.00701 -59.090246) (xy 18.091718 -59.104274) (xy 18.174741 -59.126173)
			(xy 18.255349 -59.15575) (xy 18.332833 -59.192745) (xy 18.406512 -59.236833) (xy 18.475738 -59.287627)
			(xy 18.539905 -59.34468) (xy 18.598446 -59.407491) (xy 18.650849 -59.475508) (xy 18.696652 -59.548133)
			(xy 18.735453 -59.624728) (xy 18.766912 -59.70462) (xy 18.790751 -59.787107) (xy 18.806761 -59.871464)
			(xy 18.814801 -59.956949) (xy 18.815304 -59.99988) (xy 18.814801 -60.042811) (xy 18.806761 -60.128296)
			(xy 18.790751 -60.212653) (xy 18.766912 -60.29514) (xy 18.735453 -60.375032) (xy 18.696652 -60.451627)
			(xy 18.650849 -60.524252) (xy 18.598446 -60.592269) (xy 18.539905 -60.65508) (xy 18.475738 -60.712133)
			(xy 18.406512 -60.762927) (xy 18.332833 -60.807015) (xy 18.255349 -60.84401) (xy 18.174741 -60.873587)
			(xy 18.091718 -60.895486) (xy 18.00701 -60.909514) (xy 17.92136 -60.915548) (xy 17.835521 -60.913535)
			(xy 17.750247 -60.903493) (xy 17.666289 -60.88551) (xy 17.584384 -60.859744) (xy 17.505251 -60.826421)
			(xy 17.429587 -60.785835) (xy 17.358055 -60.738342) (xy 17.291286 -60.684359) (xy 17.229864 -60.624361)
			(xy 17.174331 -60.558875) (xy 17.125174 -60.488477) (xy 17.082825 -60.413784) (xy 17.047657 -60.335455)
			(xy 17.019978 -60.254176) (xy 17.000031 -60.170662) (xy 16.987993 -60.085648) (xy 16.983969 -59.99988)
			(xy 1.524 -59.99988) (xy 1.524 -77.671676) (xy 1.524528 -77.702818) (xy 1.532691 -77.764566) (xy 1.548839 -77.824722)
			(xy 1.572695 -77.882257) (xy 1.603853 -77.936189) (xy 1.64178 -77.985596) (xy 1.663446 -78.007972)
			(xy 2.491994 -78.83652) (xy 2.552767 -78.898052) (xy 2.668915 -79.026219) (xy 2.778636 -79.15993)
			(xy 2.881665 -79.298863) (xy 2.977754 -79.442682) (xy 3.066672 -79.591043) (xy 3.148205 -79.743587)
			(xy 3.222155 -79.899947) (xy 3.288346 -80.059747) (xy 3.346618 -80.222601) (xy 3.39683 -80.388119)
			(xy 3.438862 -80.5559) (xy 3.472612 -80.725541) (xy 3.497999 -80.896634) (xy 3.514962 -81.068766)
			(xy 3.52346 -81.241523) (xy 3.523996 -81.328006) (xy 3.523996 -85.764678) (xy 10.421355 -85.764678)
			(xy 10.421355 -85.635538) (xy 10.429305 -85.506643) (xy 10.445175 -85.378483) (xy 10.468904 -85.251542)
			(xy 10.500403 -85.126303) (xy 10.539552 -85.00324) (xy 10.586203 -84.882821) (xy 10.640178 -84.765502)
			(xy 10.701273 -84.651728) (xy 10.769256 -84.541931) (xy 10.84387 -84.436528) (xy 10.924831 -84.335918)
			(xy 11.011831 -84.240483) (xy 11.104542 -84.150584) (xy 11.202612 -84.066563) (xy 11.305667 -83.988739)
			(xy 11.413318 -83.917407) (xy 11.525157 -83.852837) (xy 11.640758 -83.795275) (xy 11.759683 -83.744938)
			(xy 11.881482 -83.702018) (xy 12.005692 -83.666677) (xy 12.131841 -83.63905) (xy 12.259453 -83.619241)
			(xy 12.388042 -83.607325) (xy 12.51712 -83.603349) (xy 12.646198 -83.607325) (xy 12.774787 -83.619241)
			(xy 12.902399 -83.63905) (xy 13.028548 -83.666677) (xy 13.152758 -83.702018) (xy 13.274557 -83.744938)
			(xy 13.393482 -83.795275) (xy 13.509083 -83.852837) (xy 13.620922 -83.917407) (xy 13.728573 -83.988739)
			(xy 13.831628 -84.066563) (xy 13.929698 -84.150584) (xy 14.022409 -84.240483) (xy 14.109409 -84.335918)
			(xy 14.19037 -84.436528) (xy 14.264984 -84.541931) (xy 14.332967 -84.651728) (xy 14.394062 -84.765502)
			(xy 14.448037 -84.882821) (xy 14.494688 -85.00324) (xy 14.533837 -85.126303) (xy 14.565336 -85.251542)
			(xy 14.589065 -85.378483) (xy 14.604935 -85.506643) (xy 14.612885 -85.635538) (xy 14.613382 -85.700108)
			(xy 14.612885 -85.764678) (xy 14.604935 -85.893573) (xy 14.589065 -86.021733) (xy 14.565336 -86.148674)
			(xy 14.533837 -86.273913) (xy 14.494688 -86.396976) (xy 14.448037 -86.517395) (xy 14.394062 -86.634714)
			(xy 14.332967 -86.748488) (xy 14.264984 -86.858285) (xy 14.19037 -86.963688) (xy 14.109409 -87.064298)
			(xy 14.022409 -87.159733) (xy 13.929698 -87.249632) (xy 13.831628 -87.333653) (xy 13.728573 -87.411477)
			(xy 13.620922 -87.482809) (xy 13.509083 -87.547379) (xy 13.393482 -87.604941) (xy 13.274557 -87.655278)
			(xy 13.152758 -87.698198) (xy 13.028548 -87.733539) (xy 12.902399 -87.761166) (xy 12.774787 -87.780975)
			(xy 12.646198 -87.792891) (xy 12.51712 -87.796868) (xy 12.388042 -87.792891) (xy 12.259453 -87.780975)
			(xy 12.131841 -87.761166) (xy 12.005692 -87.733539) (xy 11.881482 -87.698198) (xy 11.759683 -87.655278)
			(xy 11.640758 -87.604941) (xy 11.525157 -87.547379) (xy 11.413318 -87.482809) (xy 11.305667 -87.411477)
			(xy 11.202612 -87.333653) (xy 11.104542 -87.249632) (xy 11.011831 -87.159733) (xy 10.924831 -87.064298)
			(xy 10.84387 -86.963688) (xy 10.769256 -86.858285) (xy 10.701273 -86.748488) (xy 10.640178 -86.634714)
			(xy 10.586203 -86.517395) (xy 10.539552 -86.396976) (xy 10.500403 -86.273913) (xy 10.468904 -86.148674)
			(xy 10.445175 -86.021733) (xy 10.429305 -85.893573) (xy 10.421355 -85.764678) (xy 3.523996 -85.764678)
			(xy 3.523996 -106.40187) (xy 11.713464 -106.40187) (xy 11.713464 -105.53827) (xy 11.71395 -105.511001)
			(xy 11.721712 -105.457017) (xy 11.737077 -105.404687) (xy 11.759734 -105.355077) (xy 11.78922 -105.309196)
			(xy 11.824935 -105.267979) (xy 11.866152 -105.232264) (xy 11.912033 -105.202778) (xy 11.961643 -105.180121)
			(xy 12.013973 -105.164756) (xy 12.067957 -105.156994) (xy 12.122495 -105.156994) (xy 12.176479 -105.164756)
			(xy 12.228809 -105.180121) (xy 12.278419 -105.202778) (xy 12.3243 -105.232264) (xy 12.365517 -105.267979)
			(xy 12.401232 -105.309196) (xy 12.430718 -105.355077) (xy 12.453375 -105.404687) (xy 12.46874 -105.457017)
			(xy 12.476502 -105.511001) (xy 12.476988 -105.53827) (xy 12.476988 -105.664) (xy 15.57274 -105.664)
			(xy 15.57274 -104.8004) (xy 15.573226 -104.773131) (xy 15.580988 -104.719147) (xy 15.596353 -104.666817)
			(xy 15.61901 -104.617207) (xy 15.648496 -104.571326) (xy 15.684211 -104.530109) (xy 15.725428 -104.494394)
			(xy 15.771309 -104.464908) (xy 15.820919 -104.442251) (xy 15.873249 -104.426886) (xy 15.927233 -104.419124)
			(xy 15.981771 -104.419124) (xy 16.035755 -104.426886) (xy 16.088085 -104.442251) (xy 16.137695 -104.464908)
			(xy 16.183576 -104.494394) (xy 16.224793 -104.530109) (xy 16.260508 -104.571326) (xy 16.289994 -104.617207)
			(xy 16.312651 -104.666817) (xy 16.328016 -104.719147) (xy 16.335778 -104.773131) (xy 16.336264 -104.8004)
			(xy 16.336264 -105.664) (xy 16.335778 -105.691269) (xy 16.328016 -105.745253) (xy 16.312651 -105.797583)
			(xy 16.289994 -105.847193) (xy 16.260508 -105.893074) (xy 16.224793 -105.934291) (xy 16.183576 -105.970006)
			(xy 16.137695 -105.999492) (xy 16.088085 -106.022149) (xy 16.035755 -106.037514) (xy 15.981771 -106.045276)
			(xy 15.927233 -106.045276) (xy 15.873249 -106.037514) (xy 15.820919 -106.022149) (xy 15.771309 -105.999492)
			(xy 15.725428 -105.970006) (xy 15.684211 -105.934291) (xy 15.648496 -105.893074) (xy 15.61901 -105.847193)
			(xy 15.596353 -105.797583) (xy 15.580988 -105.745253) (xy 15.573226 -105.691269) (xy 15.57274 -105.664)
			(xy 12.476988 -105.664) (xy 12.476988 -106.40187) (xy 12.476502 -106.429139) (xy 12.46874 -106.483123)
			(xy 12.453375 -106.535453) (xy 12.430718 -106.585063) (xy 12.401232 -106.630944) (xy 12.365517 -106.672161)
			(xy 12.3243 -106.707876) (xy 12.278419 -106.737362) (xy 12.228809 -106.760019) (xy 12.176479 -106.775384)
			(xy 12.122495 -106.783146) (xy 12.067957 -106.783146) (xy 12.013973 -106.775384) (xy 11.961643 -106.760019)
			(xy 11.912033 -106.737362) (xy 11.866152 -106.707876) (xy 11.824935 -106.672161) (xy 11.78922 -106.630944)
			(xy 11.759734 -106.585063) (xy 11.737077 -106.535453) (xy 11.721712 -106.483123) (xy 11.71395 -106.429139)
			(xy 11.713464 -106.40187) (xy 3.523996 -106.40187) (xy 3.523996 -108.943971) (xy 11.292822 -108.943971)
			(xy 11.292822 -108.889469) (xy 11.300578 -108.835522) (xy 11.315933 -108.783228) (xy 11.338574 -108.733651)
			(xy 11.36804 -108.687801) (xy 11.403731 -108.646611) (xy 11.444921 -108.61092) (xy 11.490771 -108.581454)
			(xy 11.540348 -108.558813) (xy 11.592642 -108.543458) (xy 11.646589 -108.535702) (xy 11.67384 -108.535216)
			(xy 12.53744 -108.535216) (xy 12.564692 -108.535694) (xy 12.61864 -108.54345) (xy 12.670935 -108.558806)
			(xy 12.720513 -108.581447) (xy 12.766364 -108.610914) (xy 12.807554 -108.646606) (xy 12.843246 -108.687796)
			(xy 12.872713 -108.733647) (xy 12.895354 -108.783225) (xy 12.91071 -108.83552) (xy 12.918466 -108.889468)
			(xy 12.918466 -108.943972) (xy 12.918466 -108.943973) (xy 15.156389 -108.943973) (xy 15.156389 -108.889467)
			(xy 15.164146 -108.835517) (xy 15.179502 -108.783219) (xy 15.202145 -108.733639) (xy 15.231613 -108.687786)
			(xy 15.267307 -108.646594) (xy 15.308499 -108.610901) (xy 15.354353 -108.581433) (xy 15.403933 -108.558791)
			(xy 15.45623 -108.543435) (xy 15.510181 -108.535679) (xy 15.537434 -108.535216) (xy 16.401034 -108.535216)
			(xy 16.428285 -108.535694) (xy 16.482233 -108.543451) (xy 16.534528 -108.558807) (xy 16.584105 -108.581448)
			(xy 16.629956 -108.610915) (xy 16.671146 -108.646607) (xy 16.706837 -108.687798) (xy 16.736304 -108.733648)
			(xy 16.758945 -108.783226) (xy 16.7743 -108.835521) (xy 16.782056 -108.889469) (xy 16.782056 -108.943971)
			(xy 16.7743 -108.997919) (xy 16.758945 -109.050214) (xy 16.736304 -109.099792) (xy 16.706837 -109.145642)
			(xy 16.671146 -109.186833) (xy 16.629956 -109.222525) (xy 16.584105 -109.251992) (xy 16.534528 -109.274633)
			(xy 16.482233 -109.289989) (xy 16.428285 -109.297746) (xy 16.401034 -109.298232) (xy 15.537434 -109.298232)
			(xy 15.510181 -109.297761) (xy 15.45623 -109.290005) (xy 15.403933 -109.274649) (xy 15.354353 -109.252007)
			(xy 15.308499 -109.222539) (xy 15.267307 -109.186846) (xy 15.231613 -109.145654) (xy 15.202145 -109.099801)
			(xy 15.179502 -109.050221) (xy 15.164146 -108.997923) (xy 15.156389 -108.943973) (xy 12.918466 -108.943973)
			(xy 12.91071 -108.99792) (xy 12.895354 -109.050215) (xy 12.872713 -109.099793) (xy 12.843246 -109.145644)
			(xy 12.807554 -109.186834) (xy 12.766364 -109.222526) (xy 12.720513 -109.251993) (xy 12.670935 -109.274634)
			(xy 12.61864 -109.28999) (xy 12.564692 -109.297746) (xy 12.53744 -109.298232) (xy 11.67384 -109.298232)
			(xy 11.646589 -109.297738) (xy 11.592642 -109.289982) (xy 11.540348 -109.274627) (xy 11.490771 -109.251986)
			(xy 11.444921 -109.22252) (xy 11.403731 -109.186829) (xy 11.36804 -109.145639) (xy 11.338574 -109.099789)
			(xy 11.315933 -109.050212) (xy 11.300578 -108.997918) (xy 11.292822 -108.943971) (xy 3.523996 -108.943971)
			(xy 3.523996 -114.734161) (xy 11.255226 -114.734161) (xy 11.255226 -114.679659) (xy 11.262982 -114.625711)
			(xy 11.278337 -114.573416) (xy 11.300979 -114.523839) (xy 11.330445 -114.477988) (xy 11.366136 -114.436798)
			(xy 11.407326 -114.401106) (xy 11.453177 -114.371639) (xy 11.502754 -114.348998) (xy 11.555049 -114.333643)
			(xy 11.608997 -114.325886) (xy 11.636248 -114.3254) (xy 12.499848 -114.3254) (xy 12.527101 -114.325867)
			(xy 12.581052 -114.333624) (xy 12.633349 -114.34898) (xy 12.68293 -114.371622) (xy 12.728783 -114.40109)
			(xy 12.769975 -114.436783) (xy 12.805669 -114.477976) (xy 12.835137 -114.523829) (xy 12.85778 -114.573409)
			(xy 12.873136 -114.625706) (xy 12.880893 -114.679657) (xy 12.880893 -114.734163) (xy 12.873136 -114.788114)
			(xy 12.85778 -114.840411) (xy 12.835137 -114.889991) (xy 12.805669 -114.935844) (xy 12.769975 -114.977037)
			(xy 12.728783 -115.01273) (xy 12.68293 -115.042198) (xy 12.633349 -115.06484) (xy 12.581052 -115.080196)
			(xy 12.527101 -115.087953) (xy 12.499848 -115.088416) (xy 11.636248 -115.088416) (xy 11.608997 -115.087934)
			(xy 11.555049 -115.080177) (xy 11.502754 -115.064822) (xy 11.453177 -115.042181) (xy 11.407326 -115.012714)
			(xy 11.366136 -114.977022) (xy 11.330445 -114.935832) (xy 11.300979 -114.889981) (xy 11.278337 -114.840404)
			(xy 11.262982 -114.788109) (xy 11.255226 -114.734161) (xy 3.523996 -114.734161) (xy 3.523996 -126.774448)
			(xy 24.95296 -126.774448) (xy 24.95296 -44.882308) (xy 24.953504 -44.857346) (xy 24.96324 -44.808381)
			(xy 24.982358 -44.762263) (xy 25.01012 -44.72077) (xy 25.027382 -44.70273) (xy 32.423862 -37.30625)
			(xy 32.441918 -37.28901) (xy 32.483415 -37.261268) (xy 32.529527 -37.242155) (xy 32.578482 -37.232405)
			(xy 32.60344 -37.231828) (xy 91.408504 -37.231828) (xy 96.955356 -31.684976) (xy 96.949514 -31.657798)
			(xy 96.94557 -31.638032) (xy 96.941368 -31.597943) (xy 96.941132 -31.577788) (xy 96.941544 -31.550533)
			(xy 96.949303 -31.496578) (xy 96.964663 -31.444277) (xy 96.98731 -31.394694) (xy 97.016783 -31.348839)
			(xy 97.052482 -31.307645) (xy 97.093681 -31.271952) (xy 97.13954 -31.242485) (xy 97.189126 -31.219845)
			(xy 97.241429 -31.204492) (xy 97.295385 -31.19674) (xy 97.32264 -31.19628) (xy 97.349611 -31.19671)
			(xy 97.403026 -31.204227) (xy 97.429066 -31.211266) (xy 97.435162 -31.20517) (xy 97.453221 -31.187933)
			(xy 97.494717 -31.16019) (xy 97.540828 -31.141076) (xy 97.589782 -31.131325) (xy 97.61474 -31.130748)
			(xy 139.629896 -31.130748) (xy 139.637516 -31.089092) (xy 139.643084 -31.061765) (xy 139.661096 -31.008987)
			(xy 139.6866 -30.959394) (xy 139.719052 -30.914042) (xy 139.757761 -30.873898) (xy 139.801902 -30.839817)
			(xy 139.850535 -30.812525) (xy 139.902623 -30.792605) (xy 139.957056 -30.780481) (xy 140.012674 -30.776411)
			(xy 140.068292 -30.780481) (xy 140.122725 -30.792605) (xy 140.174813 -30.812525) (xy 140.223446 -30.839817)
			(xy 140.267587 -30.873898) (xy 140.306296 -30.914042) (xy 140.338748 -30.959394) (xy 140.364252 -31.008987)
			(xy 140.382264 -31.061765) (xy 140.387832 -31.089092) (xy 140.395452 -31.130748) (xy 160.5788 -31.130748)
			(xy 160.603762 -31.13129) (xy 160.652727 -31.141027) (xy 160.698845 -31.160146) (xy 160.740338 -31.187908)
			(xy 160.758378 -31.20517) (xy 161.850578 -32.29737) (xy 161.867795 -32.315444) (xy 161.89553 -32.356938)
			(xy 161.914637 -32.403045) (xy 161.924384 -32.451993) (xy 161.925 -32.476948) (xy 161.925 -37.099629)
			(xy 170.600616 -37.099629) (xy 170.600616 -37.000299) (xy 170.608608 -36.901292) (xy 170.624542 -36.803249)
			(xy 170.648313 -36.706806) (xy 170.679768 -36.612588) (xy 170.718701 -36.521208) (xy 170.764862 -36.433256)
			(xy 170.81795 -36.349304) (xy 170.877621 -36.269895) (xy 170.943489 -36.195546) (xy 171.015126 -36.126738)
			(xy 171.092067 -36.063918) (xy 171.173813 -36.007493) (xy 171.259835 -35.957828) (xy 171.349574 -35.915246)
			(xy 171.442448 -35.880024) (xy 171.537856 -35.852388) (xy 171.635178 -35.83252) (xy 171.733783 -35.820547)
			(xy 171.833032 -35.816548) (xy 171.932281 -35.820547) (xy 172.030886 -35.83252) (xy 172.128208 -35.852388)
			(xy 172.223616 -35.880024) (xy 172.31649 -35.915246) (xy 172.406229 -35.957828) (xy 172.492251 -36.007493)
			(xy 172.573997 -36.063918) (xy 172.650938 -36.126738) (xy 172.722575 -36.195546) (xy 172.788443 -36.269895)
			(xy 172.848114 -36.349304) (xy 172.901202 -36.433256) (xy 172.947363 -36.521208) (xy 172.986296 -36.612588)
			(xy 173.017751 -36.706806) (xy 173.041522 -36.803249) (xy 173.057456 -36.901292) (xy 173.065448 -37.000299)
			(xy 173.065948 -37.049964) (xy 173.065448 -37.099629) (xy 173.057456 -37.198636) (xy 173.041522 -37.296679)
			(xy 173.017751 -37.393122) (xy 172.986296 -37.48734) (xy 172.947363 -37.57872) (xy 172.901202 -37.666672)
			(xy 172.848114 -37.750624) (xy 172.788443 -37.830033) (xy 172.722575 -37.904382) (xy 172.650938 -37.97319)
			(xy 172.573997 -38.03601) (xy 172.492251 -38.092435) (xy 172.406229 -38.1421) (xy 172.31649 -38.184682)
			(xy 172.223616 -38.219904) (xy 172.128208 -38.24754) (xy 172.030886 -38.267408) (xy 171.932281 -38.279381)
			(xy 171.833032 -38.283381) (xy 171.733783 -38.279381) (xy 171.635178 -38.267408) (xy 171.537856 -38.24754)
			(xy 171.442448 -38.219904) (xy 171.349574 -38.184682) (xy 171.259835 -38.1421) (xy 171.173813 -38.092435)
			(xy 171.092067 -38.03601) (xy 171.015126 -37.97319) (xy 170.943489 -37.904382) (xy 170.877621 -37.830033)
			(xy 170.81795 -37.750624) (xy 170.764862 -37.666672) (xy 170.718701 -37.57872) (xy 170.679768 -37.48734)
			(xy 170.648313 -37.393122) (xy 170.624542 -37.296679) (xy 170.608608 -37.198636) (xy 170.600616 -37.099629)
			(xy 161.925 -37.099629) (xy 161.925 -40.744902) (xy 235.083357 -40.744902) (xy 235.087362 -40.656994)
			(xy 235.099345 -40.569814) (xy 235.119205 -40.484085) (xy 235.14678 -40.400517) (xy 235.181839 -40.319803)
			(xy 235.224092 -40.242611) (xy 235.27319 -40.169582) (xy 235.328726 -40.10132) (xy 235.390238 -40.03839)
			(xy 235.457219 -39.981316) (xy 235.529112 -39.930568) (xy 235.605321 -39.886568) (xy 235.685216 -39.849681)
			(xy 235.768135 -39.820212) (xy 235.85339 -39.798405) (xy 235.940274 -39.784441) (xy 236.028068 -39.778435)
			(xy 236.116045 -39.780439) (xy 236.203475 -39.790434) (xy 236.289634 -39.808338) (xy 236.373808 -39.834002)
			(xy 236.455299 -39.867215) (xy 236.533433 -39.907701) (xy 236.607561 -39.955123) (xy 236.677069 -40.00909)
			(xy 236.741383 -40.069155) (xy 236.799967 -40.134819) (xy 236.852338 -40.205538) (xy 236.898061 -40.280726)
			(xy 236.936758 -40.359761) (xy 236.968107 -40.441987) (xy 236.991849 -40.526723) (xy 237.007787 -40.613267)
			(xy 237.015789 -40.700902) (xy 237.01629 -40.744902) (xy 237.015789 -40.788902) (xy 237.007787 -40.876537)
			(xy 236.991849 -40.963081) (xy 236.968107 -41.047817) (xy 236.936758 -41.130043) (xy 236.898061 -41.209078)
			(xy 236.852338 -41.284266) (xy 236.799967 -41.354985) (xy 236.741383 -41.420649) (xy 236.677069 -41.480714)
			(xy 236.607561 -41.534681) (xy 236.533433 -41.582103) (xy 236.455299 -41.622589) (xy 236.373808 -41.655802)
			(xy 236.289634 -41.681466) (xy 236.203475 -41.69937) (xy 236.116045 -41.709365) (xy 236.028068 -41.711369)
			(xy 235.940274 -41.705363) (xy 235.85339 -41.691399) (xy 235.768135 -41.669592) (xy 235.685216 -41.640123)
			(xy 235.605321 -41.603236) (xy 235.529112 -41.559236) (xy 235.457219 -41.508488) (xy 235.390238 -41.451414)
			(xy 235.328726 -41.388484) (xy 235.27319 -41.320222) (xy 235.224092 -41.247193) (xy 235.181839 -41.170001)
			(xy 235.14678 -41.089287) (xy 235.119205 -41.005719) (xy 235.099345 -40.91999) (xy 235.087362 -40.83281)
			(xy 235.083357 -40.744902) (xy 161.925 -40.744902) (xy 161.925 -43.481752) (xy 178.891692 -43.481752)
			(xy 178.891692 -42.618152) (xy 178.892178 -42.590901) (xy 178.899934 -42.536953) (xy 178.915289 -42.484658)
			(xy 178.937931 -42.435081) (xy 178.967397 -42.389231) (xy 179.003088 -42.34804) (xy 179.044279 -42.312349)
			(xy 179.090129 -42.282883) (xy 179.139706 -42.260241) (xy 179.192001 -42.244886) (xy 179.245949 -42.23713)
			(xy 179.300451 -42.23713) (xy 179.354399 -42.244886) (xy 179.406694 -42.260241) (xy 179.456271 -42.282883)
			(xy 179.502121 -42.312349) (xy 179.543312 -42.34804) (xy 179.579003 -42.389231) (xy 179.608469 -42.435081)
			(xy 179.631111 -42.484658) (xy 179.646466 -42.536953) (xy 179.654222 -42.590901) (xy 179.654708 -42.618152)
			(xy 179.654708 -43.481752) (xy 179.654222 -43.509003) (xy 179.646466 -43.562951) (xy 179.631111 -43.615246)
			(xy 179.608469 -43.664823) (xy 179.579003 -43.710673) (xy 179.543312 -43.751864) (xy 179.502121 -43.787555)
			(xy 179.456271 -43.817021) (xy 179.406694 -43.839663) (xy 179.354399 -43.855018) (xy 179.300451 -43.862774)
			(xy 179.245949 -43.862774) (xy 179.192001 -43.855018) (xy 179.139706 -43.839663) (xy 179.090129 -43.817021)
			(xy 179.044279 -43.787555) (xy 179.003088 -43.751864) (xy 178.967397 -43.710673) (xy 178.937931 -43.664823)
			(xy 178.915289 -43.615246) (xy 178.899934 -43.562951) (xy 178.892178 -43.509003) (xy 178.891692 -43.481752)
			(xy 161.925 -43.481752) (xy 161.925 -44.980098) (xy 181.659784 -44.980098) (xy 181.659784 -44.116498)
			(xy 181.66027 -44.089247) (xy 181.668026 -44.035299) (xy 181.683381 -43.983004) (xy 181.706023 -43.933427)
			(xy 181.735489 -43.887577) (xy 181.77118 -43.846386) (xy 181.812371 -43.810695) (xy 181.858221 -43.781229)
			(xy 181.907798 -43.758587) (xy 181.960093 -43.743232) (xy 182.014041 -43.735476) (xy 182.068543 -43.735476)
			(xy 182.122491 -43.743232) (xy 182.174786 -43.758587) (xy 182.224363 -43.781229) (xy 182.270213 -43.810695)
			(xy 182.311404 -43.846386) (xy 182.347095 -43.887577) (xy 182.376561 -43.933427) (xy 182.399203 -43.983004)
			(xy 182.414558 -44.035299) (xy 182.422314 -44.089247) (xy 182.4228 -44.116498) (xy 182.4228 -44.980098)
			(xy 182.422314 -45.007349) (xy 182.414558 -45.061297) (xy 182.399203 -45.113592) (xy 182.376561 -45.163169)
			(xy 182.347095 -45.209019) (xy 182.311404 -45.25021) (xy 182.270213 -45.285901) (xy 182.224363 -45.315367)
			(xy 182.174786 -45.338009) (xy 182.122491 -45.353364) (xy 182.068543 -45.36112) (xy 182.014041 -45.36112)
			(xy 181.960093 -45.353364) (xy 181.907798 -45.338009) (xy 181.858221 -45.315367) (xy 181.812371 -45.285901)
			(xy 181.77118 -45.25021) (xy 181.735489 -45.209019) (xy 181.706023 -45.163169) (xy 181.683381 -45.113592)
			(xy 181.668026 -45.061297) (xy 181.66027 -45.007349) (xy 181.659784 -44.980098) (xy 161.925 -44.980098)
			(xy 161.925 -46.481746) (xy 178.630072 -46.481746) (xy 178.630072 -45.618146) (xy 178.630558 -45.590895)
			(xy 178.638314 -45.536947) (xy 178.653669 -45.484652) (xy 178.676311 -45.435075) (xy 178.705777 -45.389225)
			(xy 178.741468 -45.348034) (xy 178.782659 -45.312343) (xy 178.828509 -45.282877) (xy 178.878086 -45.260235)
			(xy 178.930381 -45.24488) (xy 178.984329 -45.237124) (xy 179.038831 -45.237124) (xy 179.092779 -45.24488)
			(xy 179.145074 -45.260235) (xy 179.194651 -45.282877) (xy 179.240501 -45.312343) (xy 179.281692 -45.348034)
			(xy 179.317383 -45.389225) (xy 179.346849 -45.435075) (xy 179.369491 -45.484652) (xy 179.384846 -45.536947)
			(xy 179.392602 -45.590895) (xy 179.393088 -45.618146) (xy 179.393088 -46.481746) (xy 179.392602 -46.508997)
			(xy 179.384846 -46.562945) (xy 179.369491 -46.61524) (xy 179.346849 -46.664817) (xy 179.317383 -46.710667)
			(xy 179.281692 -46.751858) (xy 179.240501 -46.787549) (xy 179.194651 -46.817015) (xy 179.145074 -46.839657)
			(xy 179.092779 -46.855012) (xy 179.038831 -46.862768) (xy 178.984329 -46.862768) (xy 178.930381 -46.855012)
			(xy 178.878086 -46.839657) (xy 178.828509 -46.817015) (xy 178.782659 -46.787549) (xy 178.741468 -46.751858)
			(xy 178.705777 -46.710667) (xy 178.676311 -46.664817) (xy 178.653669 -46.61524) (xy 178.638314 -46.562945)
			(xy 178.630558 -46.508997) (xy 178.630072 -46.481746) (xy 161.925 -46.481746) (xy 161.925 -48.028098)
			(xy 181.659784 -48.028098) (xy 181.659784 -47.164498) (xy 181.66027 -47.137247) (xy 181.668026 -47.083299)
			(xy 181.683381 -47.031004) (xy 181.706023 -46.981427) (xy 181.735489 -46.935577) (xy 181.77118 -46.894386)
			(xy 181.812371 -46.858695) (xy 181.858221 -46.829229) (xy 181.907798 -46.806587) (xy 181.960093 -46.791232)
			(xy 182.014041 -46.783476) (xy 182.068543 -46.783476) (xy 182.122491 -46.791232) (xy 182.174786 -46.806587)
			(xy 182.224363 -46.829229) (xy 182.270213 -46.858695) (xy 182.311404 -46.894386) (xy 182.347095 -46.935577)
			(xy 182.376561 -46.981427) (xy 182.399203 -47.031004) (xy 182.414558 -47.083299) (xy 182.422314 -47.137247)
			(xy 182.4228 -47.164498) (xy 182.4228 -48.028098) (xy 182.422314 -48.055349) (xy 182.414558 -48.109297)
			(xy 182.399203 -48.161592) (xy 182.376561 -48.211169) (xy 182.347095 -48.257019) (xy 182.311404 -48.29821)
			(xy 182.270213 -48.333901) (xy 182.224363 -48.363367) (xy 182.174786 -48.386009) (xy 182.122491 -48.401364)
			(xy 182.068543 -48.40912) (xy 182.014041 -48.40912) (xy 181.960093 -48.401364) (xy 181.907798 -48.386009)
			(xy 181.858221 -48.363367) (xy 181.812371 -48.333901) (xy 181.77118 -48.29821) (xy 181.735489 -48.257019)
			(xy 181.706023 -48.211169) (xy 181.683381 -48.161592) (xy 181.668026 -48.109297) (xy 181.66027 -48.055349)
			(xy 181.659784 -48.028098) (xy 161.925 -48.028098) (xy 161.925 -49.48174) (xy 178.630072 -49.48174)
			(xy 178.630072 -48.61814) (xy 178.630558 -48.590889) (xy 178.638314 -48.536941) (xy 178.653669 -48.484646)
			(xy 178.676311 -48.435069) (xy 178.705777 -48.389219) (xy 178.741468 -48.348028) (xy 178.782659 -48.312337)
			(xy 178.828509 -48.282871) (xy 178.878086 -48.260229) (xy 178.930381 -48.244874) (xy 178.984329 -48.237118)
			(xy 179.038831 -48.237118) (xy 179.092779 -48.244874) (xy 179.145074 -48.260229) (xy 179.194651 -48.282871)
			(xy 179.240501 -48.312337) (xy 179.281692 -48.348028) (xy 179.317383 -48.389219) (xy 179.346849 -48.435069)
			(xy 179.369491 -48.484646) (xy 179.384846 -48.536941) (xy 179.392602 -48.590889) (xy 179.393088 -48.61814)
			(xy 179.393088 -49.48174) (xy 179.392602 -49.508991) (xy 179.384846 -49.562939) (xy 179.369491 -49.615234)
			(xy 179.346849 -49.664811) (xy 179.317383 -49.710661) (xy 179.281692 -49.751852) (xy 179.240501 -49.787543)
			(xy 179.194651 -49.817009) (xy 179.145074 -49.839651) (xy 179.092779 -49.855006) (xy 179.038831 -49.862762)
			(xy 178.984329 -49.862762) (xy 178.930381 -49.855006) (xy 178.878086 -49.839651) (xy 178.828509 -49.817009)
			(xy 178.782659 -49.787543) (xy 178.741468 -49.751852) (xy 178.705777 -49.710661) (xy 178.676311 -49.664811)
			(xy 178.653669 -49.615234) (xy 178.638314 -49.562939) (xy 178.630558 -49.508991) (xy 178.630072 -49.48174)
			(xy 161.925 -49.48174) (xy 161.925 -50.949098) (xy 181.659784 -50.949098) (xy 181.659784 -50.085498)
			(xy 181.66027 -50.058247) (xy 181.668026 -50.004299) (xy 181.683381 -49.952004) (xy 181.706023 -49.902427)
			(xy 181.735489 -49.856577) (xy 181.77118 -49.815386) (xy 181.812371 -49.779695) (xy 181.858221 -49.750229)
			(xy 181.907798 -49.727587) (xy 181.960093 -49.712232) (xy 182.014041 -49.704476) (xy 182.068543 -49.704476)
			(xy 182.122491 -49.712232) (xy 182.174786 -49.727587) (xy 182.224363 -49.750229) (xy 182.270213 -49.779695)
			(xy 182.311404 -49.815386) (xy 182.347095 -49.856577) (xy 182.376561 -49.902427) (xy 182.399203 -49.952004)
			(xy 182.414558 -50.004299) (xy 182.422314 -50.058247) (xy 182.4228 -50.085498) (xy 182.4228 -50.949098)
			(xy 182.422314 -50.976349) (xy 182.414558 -51.030297) (xy 182.399203 -51.082592) (xy 182.376561 -51.132169)
			(xy 182.347095 -51.178019) (xy 182.311404 -51.21921) (xy 182.270213 -51.254901) (xy 182.224363 -51.284367)
			(xy 182.174786 -51.307009) (xy 182.122491 -51.322364) (xy 182.068543 -51.33012) (xy 182.014041 -51.33012)
			(xy 181.960093 -51.322364) (xy 181.907798 -51.307009) (xy 181.858221 -51.284367) (xy 181.812371 -51.254901)
			(xy 181.77118 -51.21921) (xy 181.735489 -51.178019) (xy 181.706023 -51.132169) (xy 181.683381 -51.082592)
			(xy 181.668026 -51.030297) (xy 181.66027 -50.976349) (xy 181.659784 -50.949098) (xy 161.925 -50.949098)
			(xy 161.925 -52.481734) (xy 178.630072 -52.481734) (xy 178.630072 -51.618134) (xy 178.630558 -51.590883)
			(xy 178.638314 -51.536935) (xy 178.653669 -51.48464) (xy 178.676311 -51.435063) (xy 178.705777 -51.389213)
			(xy 178.741468 -51.348022) (xy 178.782659 -51.312331) (xy 178.828509 -51.282865) (xy 178.878086 -51.260223)
			(xy 178.930381 -51.244868) (xy 178.984329 -51.237112) (xy 179.038831 -51.237112) (xy 179.092779 -51.244868)
			(xy 179.145074 -51.260223) (xy 179.194651 -51.282865) (xy 179.240501 -51.312331) (xy 179.281692 -51.348022)
			(xy 179.317383 -51.389213) (xy 179.346849 -51.435063) (xy 179.369491 -51.48464) (xy 179.384846 -51.536935)
			(xy 179.392602 -51.590883) (xy 179.393088 -51.618134) (xy 179.393088 -51.999896) (xy 199.373496 -51.999896)
			(xy 199.37751 -51.794212) (xy 199.389546 -51.588842) (xy 199.409585 -51.384098) (xy 199.437598 -51.180291)
			(xy 199.473541 -50.977732) (xy 199.51736 -50.77673) (xy 199.568987 -50.577591) (xy 199.628345 -50.380618)
			(xy 199.695343 -50.18611) (xy 199.769879 -49.994365) (xy 199.851839 -49.805674) (xy 199.941099 -49.620324)
			(xy 200.037522 -49.438598) (xy 200.140963 -49.260772) (xy 200.251262 -49.087118) (xy 200.368253 -48.917899)
			(xy 200.491757 -48.753373) (xy 200.621586 -48.593792) (xy 200.757543 -48.439397) (xy 200.89942 -48.290425)
			(xy 201.047001 -48.147101) (xy 201.200062 -48.009645) (xy 201.358369 -47.878265) (xy 201.521682 -47.753162)
			(xy 201.689751 -47.634525) (xy 201.862321 -47.522537) (xy 202.039129 -47.417366) (xy 202.219906 -47.319175)
			(xy 202.404376 -47.228111) (xy 202.592258 -47.144314) (xy 202.783268 -47.067911) (xy 202.977112 -46.999018)
			(xy 203.173497 -46.937741) (xy 203.372123 -46.884173) (xy 203.572688 -46.838396) (xy 203.774886 -46.800478)
			(xy 203.97841 -46.770479) (xy 204.182949 -46.748442) (xy 204.388192 -46.734403) (xy 204.593827 -46.728383)
			(xy 204.79954 -46.73039) (xy 205.005018 -46.740422) (xy 205.209948 -46.758463) (xy 205.414018 -46.784486)
			(xy 205.616918 -46.818451) (xy 205.818338 -46.860306) (xy 206.017971 -46.909988) (xy 206.215514 -46.967422)
			(xy 206.410666 -47.032519) (xy 206.60313 -47.10518) (xy 206.792612 -47.185296) (xy 206.978823 -47.272743)
			(xy 207.161482 -47.367389) (xy 207.340308 -47.469089) (xy 207.51503 -47.577689) (xy 207.685383 -47.693024)
			(xy 207.851105 -47.814917) (xy 208.011946 -47.943183) (xy 208.167659 -48.077626) (xy 208.318009 -48.218043)
			(xy 208.462766 -48.364219) (xy 208.601709 -48.515931) (xy 208.734627 -48.672949) (xy 208.861318 -48.835034)
			(xy 208.981588 -49.001937) (xy 209.095255 -49.173407) (xy 209.202145 -49.34918) (xy 209.302096 -49.52899)
			(xy 209.394955 -49.712563) (xy 209.480582 -49.899619) (xy 209.558844 -50.089874) (xy 209.622578 -50.263806)
			(xy 239.457992 -50.263806) (xy 239.457992 -49.400206) (xy 239.458478 -49.372955) (xy 239.466234 -49.319007)
			(xy 239.481589 -49.266712) (xy 239.504231 -49.217135) (xy 239.533697 -49.171285) (xy 239.569388 -49.130094)
			(xy 239.610579 -49.094403) (xy 239.656429 -49.064937) (xy 239.706006 -49.042295) (xy 239.758301 -49.02694)
			(xy 239.812249 -49.019184) (xy 239.866751 -49.019184) (xy 239.920699 -49.02694) (xy 239.972994 -49.042295)
			(xy 240.022571 -49.064937) (xy 240.068421 -49.094403) (xy 240.109612 -49.130094) (xy 240.145303 -49.171285)
			(xy 240.174769 -49.217135) (xy 240.197411 -49.266712) (xy 240.212766 -49.319007) (xy 240.220522 -49.372955)
			(xy 240.221008 -49.400206) (xy 240.221008 -50.263806) (xy 240.220522 -50.291057) (xy 240.212766 -50.345005)
			(xy 240.197411 -50.3973) (xy 240.174769 -50.446877) (xy 240.145303 -50.492727) (xy 240.109612 -50.533918)
			(xy 240.068421 -50.569609) (xy 240.022571 -50.599075) (xy 239.972994 -50.621717) (xy 239.920699 -50.637072)
			(xy 239.866751 -50.644828) (xy 239.812249 -50.644828) (xy 239.758301 -50.637072) (xy 239.706006 -50.621717)
			(xy 239.656429 -50.599075) (xy 239.610579 -50.569609) (xy 239.569388 -50.533918) (xy 239.533697 -50.492727)
			(xy 239.504231 -50.446877) (xy 239.481589 -50.3973) (xy 239.466234 -50.345005) (xy 239.458478 -50.291057)
			(xy 239.457992 -50.263806) (xy 209.622578 -50.263806) (xy 209.629625 -50.283037) (xy 209.692815 -50.478815)
			(xy 209.748318 -50.676909) (xy 209.79605 -50.877018) (xy 209.835939 -51.078836) (xy 209.867923 -51.282058)
			(xy 209.891953 -51.486372) (xy 209.907994 -51.691468) (xy 209.91602 -51.897035) (xy 209.916522 -51.999896)
			(xy 209.91602 -52.102757) (xy 209.907994 -52.308324) (xy 209.891953 -52.51342) (xy 209.867923 -52.717734)
			(xy 209.838186 -52.906676) (xy 228.815392 -52.906676) (xy 228.815392 -52.043076) (xy 228.815878 -52.015825)
			(xy 228.823634 -51.961877) (xy 228.838989 -51.909582) (xy 228.861631 -51.860005) (xy 228.891097 -51.814155)
			(xy 228.926788 -51.772964) (xy 228.967979 -51.737273) (xy 229.013829 -51.707807) (xy 229.063406 -51.685165)
			(xy 229.115701 -51.66981) (xy 229.169649 -51.662054) (xy 229.224151 -51.662054) (xy 229.278099 -51.66981)
			(xy 229.330394 -51.685165) (xy 229.379971 -51.707807) (xy 229.425821 -51.737273) (xy 229.467012 -51.772964)
			(xy 229.502703 -51.814155) (xy 229.532169 -51.860005) (xy 229.554811 -51.909582) (xy 229.570166 -51.961877)
			(xy 229.577922 -52.015825) (xy 229.578408 -52.043076) (xy 229.578408 -52.90185) (xy 241.926872 -52.90185)
			(xy 241.926872 -52.03825) (xy 241.927358 -52.010999) (xy 241.935114 -51.957051) (xy 241.950469 -51.904756)
			(xy 241.973111 -51.855179) (xy 242.002577 -51.809329) (xy 242.038268 -51.768138) (xy 242.079459 -51.732447)
			(xy 242.125309 -51.702981) (xy 242.174886 -51.680339) (xy 242.227181 -51.664984) (xy 242.281129 -51.657228)
			(xy 242.335631 -51.657228) (xy 242.389579 -51.664984) (xy 242.441874 -51.680339) (xy 242.491451 -51.702981)
			(xy 242.537301 -51.732447) (xy 242.578492 -51.768138) (xy 242.614183 -51.809329) (xy 242.643649 -51.855179)
			(xy 242.666291 -51.904756) (xy 242.681646 -51.957051) (xy 242.689402 -52.010999) (xy 242.689888 -52.03825)
			(xy 242.689888 -52.90185) (xy 242.689402 -52.929101) (xy 242.681646 -52.983049) (xy 242.666291 -53.035344)
			(xy 242.643649 -53.084921) (xy 242.614183 -53.130771) (xy 242.578492 -53.171962) (xy 242.537301 -53.207653)
			(xy 242.491451 -53.237119) (xy 242.441874 -53.259761) (xy 242.389579 -53.275116) (xy 242.335631 -53.282872)
			(xy 242.281129 -53.282872) (xy 242.227181 -53.275116) (xy 242.174886 -53.259761) (xy 242.125309 -53.237119)
			(xy 242.079459 -53.207653) (xy 242.038268 -53.171962) (xy 242.002577 -53.130771) (xy 241.973111 -53.084921)
			(xy 241.950469 -53.035344) (xy 241.935114 -52.983049) (xy 241.927358 -52.929101) (xy 241.926872 -52.90185)
			(xy 229.578408 -52.90185) (xy 229.578408 -52.906676) (xy 229.577922 -52.933927) (xy 229.570166 -52.987875)
			(xy 229.554811 -53.04017) (xy 229.532169 -53.089747) (xy 229.502703 -53.135597) (xy 229.467012 -53.176788)
			(xy 229.425821 -53.212479) (xy 229.379971 -53.241945) (xy 229.330394 -53.264587) (xy 229.278099 -53.279942)
			(xy 229.224151 -53.287698) (xy 229.169649 -53.287698) (xy 229.115701 -53.279942) (xy 229.063406 -53.264587)
			(xy 229.013829 -53.241945) (xy 228.967979 -53.212479) (xy 228.926788 -53.176788) (xy 228.891097 -53.135597)
			(xy 228.861631 -53.089747) (xy 228.838989 -53.04017) (xy 228.823634 -52.987875) (xy 228.815878 -52.933927)
			(xy 228.815392 -52.906676) (xy 209.838186 -52.906676) (xy 209.835939 -52.920956) (xy 209.79605 -53.122774)
			(xy 209.748318 -53.322883) (xy 209.692815 -53.520977) (xy 209.629625 -53.716755) (xy 209.558844 -53.909918)
			(xy 209.480582 -54.100173) (xy 209.394955 -54.287229) (xy 209.302096 -54.470802) (xy 209.202145 -54.650612)
			(xy 209.168147 -54.70652) (xy 230.115872 -54.70652) (xy 230.115872 -53.84292) (xy 230.116358 -53.815669)
			(xy 230.124114 -53.761721) (xy 230.139469 -53.709426) (xy 230.162111 -53.659849) (xy 230.191577 -53.613999)
			(xy 230.227268 -53.572808) (xy 230.268459 -53.537117) (xy 230.314309 -53.507651) (xy 230.363886 -53.485009)
			(xy 230.416181 -53.469654) (xy 230.470129 -53.461898) (xy 230.524631 -53.461898) (xy 230.578579 -53.469654)
			(xy 230.630874 -53.485009) (xy 230.680451 -53.507651) (xy 230.726301 -53.537117) (xy 230.767492 -53.572808)
			(xy 230.803183 -53.613999) (xy 230.832649 -53.659849) (xy 230.855291 -53.709426) (xy 230.870646 -53.761721)
			(xy 230.878402 -53.815669) (xy 230.878888 -53.84292) (xy 230.878888 -54.70652) (xy 230.878811 -54.710838)
			(xy 240.282476 -54.710838) (xy 240.282476 -53.847238) (xy 240.282962 -53.819987) (xy 240.290718 -53.766039)
			(xy 240.306073 -53.713744) (xy 240.328715 -53.664167) (xy 240.358181 -53.618317) (xy 240.393872 -53.577126)
			(xy 240.435063 -53.541435) (xy 240.480913 -53.511969) (xy 240.53049 -53.489327) (xy 240.582785 -53.473972)
			(xy 240.636733 -53.466216) (xy 240.691235 -53.466216) (xy 240.745183 -53.473972) (xy 240.797478 -53.489327)
			(xy 240.847055 -53.511969) (xy 240.892905 -53.541435) (xy 240.934096 -53.577126) (xy 240.969787 -53.618317)
			(xy 240.999253 -53.664167) (xy 241.021895 -53.713744) (xy 241.03725 -53.766039) (xy 241.045006 -53.819987)
			(xy 241.045492 -53.847238) (xy 241.045492 -54.710838) (xy 241.045006 -54.738089) (xy 241.03725 -54.792037)
			(xy 241.021895 -54.844332) (xy 240.999253 -54.893909) (xy 240.969787 -54.939759) (xy 240.934096 -54.98095)
			(xy 240.892905 -55.016641) (xy 240.847055 -55.046107) (xy 240.797478 -55.068749) (xy 240.745183 -55.084104)
			(xy 240.691235 -55.09186) (xy 240.636733 -55.09186) (xy 240.582785 -55.084104) (xy 240.53049 -55.068749)
			(xy 240.480913 -55.046107) (xy 240.435063 -55.016641) (xy 240.393872 -54.98095) (xy 240.358181 -54.939759)
			(xy 240.328715 -54.893909) (xy 240.306073 -54.844332) (xy 240.290718 -54.792037) (xy 240.282962 -54.738089)
			(xy 240.282476 -54.710838) (xy 230.878811 -54.710838) (xy 230.878402 -54.733771) (xy 230.870646 -54.787719)
			(xy 230.855291 -54.840014) (xy 230.832649 -54.889591) (xy 230.803183 -54.935441) (xy 230.767492 -54.976632)
			(xy 230.726301 -55.012323) (xy 230.680451 -55.041789) (xy 230.630874 -55.064431) (xy 230.578579 -55.079786)
			(xy 230.524631 -55.087542) (xy 230.470129 -55.087542) (xy 230.416181 -55.079786) (xy 230.363886 -55.064431)
			(xy 230.314309 -55.041789) (xy 230.268459 -55.012323) (xy 230.227268 -54.976632) (xy 230.191577 -54.935441)
			(xy 230.162111 -54.889591) (xy 230.139469 -54.840014) (xy 230.124114 -54.787719) (xy 230.116358 -54.733771)
			(xy 230.115872 -54.70652) (xy 209.168147 -54.70652) (xy 209.095255 -54.826385) (xy 208.981588 -54.997855)
			(xy 208.861318 -55.164758) (xy 208.734627 -55.326843) (xy 208.601709 -55.483861) (xy 208.462766 -55.635573)
			(xy 208.318009 -55.781749) (xy 208.167659 -55.922166) (xy 208.011946 -56.056609) (xy 207.851105 -56.184875)
			(xy 207.685383 -56.306768) (xy 207.51503 -56.422103) (xy 207.378649 -56.506872) (xy 228.815392 -56.506872)
			(xy 228.815392 -55.643272) (xy 228.815878 -55.616021) (xy 228.823634 -55.562073) (xy 228.838989 -55.509778)
			(xy 228.861631 -55.460201) (xy 228.891097 -55.414351) (xy 228.926788 -55.37316) (xy 228.967979 -55.337469)
			(xy 229.013829 -55.308003) (xy 229.063406 -55.285361) (xy 229.115701 -55.270006) (xy 229.169649 -55.26225)
			(xy 229.224151 -55.26225) (xy 229.278099 -55.270006) (xy 229.330394 -55.285361) (xy 229.379971 -55.308003)
			(xy 229.425821 -55.337469) (xy 229.467012 -55.37316) (xy 229.502703 -55.414351) (xy 229.532169 -55.460201)
			(xy 229.554811 -55.509778) (xy 229.570166 -55.562073) (xy 229.577922 -55.616021) (xy 229.578408 -55.643272)
			(xy 229.578408 -56.506872) (xy 229.577922 -56.534123) (xy 229.570166 -56.588071) (xy 229.554811 -56.640366)
			(xy 229.532169 -56.689943) (xy 229.502703 -56.735793) (xy 229.467012 -56.776984) (xy 229.425821 -56.812675)
			(xy 229.379971 -56.842141) (xy 229.330394 -56.864783) (xy 229.278099 -56.880138) (xy 229.224151 -56.887894)
			(xy 229.169649 -56.887894) (xy 229.115701 -56.880138) (xy 229.063406 -56.864783) (xy 229.013829 -56.842141)
			(xy 228.967979 -56.812675) (xy 228.926788 -56.776984) (xy 228.891097 -56.735793) (xy 228.861631 -56.689943)
			(xy 228.838989 -56.640366) (xy 228.823634 -56.588071) (xy 228.815878 -56.534123) (xy 228.815392 -56.506872)
			(xy 207.378649 -56.506872) (xy 207.340308 -56.530703) (xy 207.161482 -56.632403) (xy 206.978823 -56.727049)
			(xy 206.792612 -56.814496) (xy 206.60313 -56.894612) (xy 206.410666 -56.967273) (xy 206.215514 -57.03237)
			(xy 206.017971 -57.089804) (xy 205.818338 -57.139486) (xy 205.616918 -57.181341) (xy 205.414018 -57.215306)
			(xy 205.209948 -57.241329) (xy 205.005018 -57.25937) (xy 204.79954 -57.269402) (xy 204.593827 -57.271409)
			(xy 204.388192 -57.265389) (xy 204.182949 -57.25135) (xy 203.97841 -57.229313) (xy 203.774886 -57.199314)
			(xy 203.572688 -57.161396) (xy 203.372123 -57.115619) (xy 203.173497 -57.062051) (xy 202.977112 -57.000774)
			(xy 202.783268 -56.931881) (xy 202.592258 -56.855478) (xy 202.404376 -56.771681) (xy 202.219906 -56.680617)
			(xy 202.039129 -56.582426) (xy 201.862321 -56.477255) (xy 201.689751 -56.365267) (xy 201.521682 -56.24663)
			(xy 201.358369 -56.121527) (xy 201.200062 -55.990147) (xy 201.047001 -55.852691) (xy 200.89942 -55.709367)
			(xy 200.757543 -55.560395) (xy 200.621586 -55.406) (xy 200.491757 -55.246419) (xy 200.368253 -55.081893)
			(xy 200.251262 -54.912674) (xy 200.140963 -54.73902) (xy 200.037522 -54.561194) (xy 199.941099 -54.379468)
			(xy 199.851839 -54.194118) (xy 199.769879 -54.005427) (xy 199.695343 -53.813682) (xy 199.628345 -53.619174)
			(xy 199.568987 -53.422201) (xy 199.51736 -53.223062) (xy 199.473541 -53.02206) (xy 199.437598 -52.819501)
			(xy 199.409585 -52.615694) (xy 199.389546 -52.41095) (xy 199.37751 -52.20558) (xy 199.373496 -51.999896)
			(xy 179.393088 -51.999896) (xy 179.393088 -52.481734) (xy 179.392602 -52.508985) (xy 179.384846 -52.562933)
			(xy 179.369491 -52.615228) (xy 179.346849 -52.664805) (xy 179.317383 -52.710655) (xy 179.281692 -52.751846)
			(xy 179.240501 -52.787537) (xy 179.194651 -52.817003) (xy 179.145074 -52.839645) (xy 179.092779 -52.855)
			(xy 179.038831 -52.862756) (xy 178.984329 -52.862756) (xy 178.930381 -52.855) (xy 178.878086 -52.839645)
			(xy 178.828509 -52.817003) (xy 178.782659 -52.787537) (xy 178.741468 -52.751846) (xy 178.705777 -52.710655)
			(xy 178.676311 -52.664805) (xy 178.653669 -52.615228) (xy 178.638314 -52.562933) (xy 178.630558 -52.508985)
			(xy 178.630072 -52.481734) (xy 161.925 -52.481734) (xy 161.925 -53.954934) (xy 181.659784 -53.954934)
			(xy 181.659784 -53.091334) (xy 181.66027 -53.064083) (xy 181.668026 -53.010135) (xy 181.683381 -52.95784)
			(xy 181.706023 -52.908263) (xy 181.735489 -52.862413) (xy 181.77118 -52.821222) (xy 181.812371 -52.785531)
			(xy 181.858221 -52.756065) (xy 181.907798 -52.733423) (xy 181.960093 -52.718068) (xy 182.014041 -52.710312)
			(xy 182.068543 -52.710312) (xy 182.122491 -52.718068) (xy 182.174786 -52.733423) (xy 182.224363 -52.756065)
			(xy 182.270213 -52.785531) (xy 182.311404 -52.821222) (xy 182.347095 -52.862413) (xy 182.376561 -52.908263)
			(xy 182.399203 -52.95784) (xy 182.414558 -53.010135) (xy 182.422314 -53.064083) (xy 182.4228 -53.091334)
			(xy 182.4228 -53.954934) (xy 182.422314 -53.982185) (xy 182.414558 -54.036133) (xy 182.399203 -54.088428)
			(xy 182.376561 -54.138005) (xy 182.347095 -54.183855) (xy 182.311404 -54.225046) (xy 182.270213 -54.260737)
			(xy 182.224363 -54.290203) (xy 182.174786 -54.312845) (xy 182.122491 -54.3282) (xy 182.068543 -54.335956)
			(xy 182.014041 -54.335956) (xy 181.960093 -54.3282) (xy 181.907798 -54.312845) (xy 181.858221 -54.290203)
			(xy 181.812371 -54.260737) (xy 181.77118 -54.225046) (xy 181.735489 -54.183855) (xy 181.706023 -54.138005)
			(xy 181.683381 -54.088428) (xy 181.668026 -54.036133) (xy 181.66027 -53.982185) (xy 181.659784 -53.954934)
			(xy 161.925 -53.954934) (xy 161.925 -55.481728) (xy 178.630072 -55.481728) (xy 178.630072 -54.618128)
			(xy 178.630558 -54.590877) (xy 178.638314 -54.536929) (xy 178.653669 -54.484634) (xy 178.676311 -54.435057)
			(xy 178.705777 -54.389207) (xy 178.741468 -54.348016) (xy 178.782659 -54.312325) (xy 178.828509 -54.282859)
			(xy 178.878086 -54.260217) (xy 178.930381 -54.244862) (xy 178.984329 -54.237106) (xy 179.038831 -54.237106)
			(xy 179.092779 -54.244862) (xy 179.145074 -54.260217) (xy 179.194651 -54.282859) (xy 179.240501 -54.312325)
			(xy 179.281692 -54.348016) (xy 179.317383 -54.389207) (xy 179.346849 -54.435057) (xy 179.369491 -54.484634)
			(xy 179.384846 -54.536929) (xy 179.392602 -54.590877) (xy 179.393088 -54.618128) (xy 179.393088 -55.481728)
			(xy 179.392602 -55.508979) (xy 179.384846 -55.562927) (xy 179.369491 -55.615222) (xy 179.346849 -55.664799)
			(xy 179.317383 -55.710649) (xy 179.281692 -55.75184) (xy 179.240501 -55.787531) (xy 179.194651 -55.816997)
			(xy 179.145074 -55.839639) (xy 179.092779 -55.854994) (xy 179.038831 -55.86275) (xy 178.984329 -55.86275)
			(xy 178.930381 -55.854994) (xy 178.878086 -55.839639) (xy 178.828509 -55.816997) (xy 178.782659 -55.787531)
			(xy 178.741468 -55.75184) (xy 178.705777 -55.710649) (xy 178.676311 -55.664799) (xy 178.653669 -55.615222)
			(xy 178.638314 -55.562927) (xy 178.630558 -55.508979) (xy 178.630072 -55.481728) (xy 161.925 -55.481728)
			(xy 161.925 -56.958992) (xy 162.060443 -57.094435) (xy 170.841915 -57.094435) (xy 170.841915 -57.005413)
			(xy 170.849895 -56.916749) (xy 170.865791 -56.829158) (xy 170.889474 -56.743343) (xy 170.920754 -56.659998)
			(xy 170.95938 -56.579792) (xy 171.005039 -56.503371) (xy 171.057365 -56.43135) (xy 171.115936 -56.36431)
			(xy 171.180281 -56.30279) (xy 171.249881 -56.247286) (xy 171.324177 -56.198244) (xy 171.402569 -56.156059)
			(xy 171.484428 -56.121071) (xy 171.569093 -56.093562) (xy 171.655883 -56.073752) (xy 171.744099 -56.061802)
			(xy 171.833032 -56.057809) (xy 171.921965 -56.061802) (xy 172.010181 -56.073752) (xy 172.096971 -56.093562)
			(xy 172.181636 -56.121071) (xy 172.263495 -56.156059) (xy 172.341887 -56.198244) (xy 172.416183 -56.247286)
			(xy 172.485783 -56.30279) (xy 172.550128 -56.36431) (xy 172.608699 -56.43135) (xy 172.661025 -56.503371)
			(xy 172.706684 -56.579792) (xy 172.74531 -56.659998) (xy 172.77659 -56.743343) (xy 172.800273 -56.829158)
			(xy 172.816169 -56.916749) (xy 172.824149 -57.005413) (xy 172.824648 -57.049924) (xy 172.824149 -57.094435)
			(xy 172.816169 -57.183099) (xy 172.800273 -57.27069) (xy 172.77659 -57.356505) (xy 172.74531 -57.43985)
			(xy 172.706684 -57.520056) (xy 172.661025 -57.596477) (xy 172.608699 -57.668498) (xy 172.550128 -57.735538)
			(xy 172.485783 -57.797058) (xy 172.416183 -57.852562) (xy 172.341887 -57.901604) (xy 172.263495 -57.943789)
			(xy 172.181636 -57.978777) (xy 172.096971 -58.006286) (xy 172.010181 -58.026096) (xy 171.921965 -58.038046)
			(xy 171.833032 -58.04204) (xy 171.744099 -58.038046) (xy 171.655883 -58.026096) (xy 171.569093 -58.006286)
			(xy 171.484428 -57.978777) (xy 171.402569 -57.943789) (xy 171.324177 -57.901604) (xy 171.249881 -57.852562)
			(xy 171.180281 -57.797058) (xy 171.115936 -57.735538) (xy 171.057365 -57.668498) (xy 171.005039 -57.596477)
			(xy 170.95938 -57.520056) (xy 170.920754 -57.43985) (xy 170.889474 -57.356505) (xy 170.865791 -57.27069)
			(xy 170.849895 -57.183099) (xy 170.841915 -57.094435) (xy 162.060443 -57.094435) (xy 163.272724 -58.306716)
			(xy 230.115872 -58.306716) (xy 230.115872 -57.443116) (xy 230.116358 -57.415865) (xy 230.124114 -57.361917)
			(xy 230.139469 -57.309622) (xy 230.162111 -57.260045) (xy 230.191577 -57.214195) (xy 230.227268 -57.173004)
			(xy 230.268459 -57.137313) (xy 230.314309 -57.107847) (xy 230.363886 -57.085205) (xy 230.416181 -57.06985)
			(xy 230.470129 -57.062094) (xy 230.524631 -57.062094) (xy 230.578579 -57.06985) (xy 230.630874 -57.085205)
			(xy 230.680451 -57.107847) (xy 230.726301 -57.137313) (xy 230.767492 -57.173004) (xy 230.803183 -57.214195)
			(xy 230.832649 -57.260045) (xy 230.855291 -57.309622) (xy 230.870646 -57.361917) (xy 230.878402 -57.415865)
			(xy 230.878888 -57.443116) (xy 230.878888 -58.30189) (xy 240.282476 -58.30189) (xy 240.282476 -57.43829)
			(xy 240.282962 -57.411039) (xy 240.290718 -57.357091) (xy 240.306073 -57.304796) (xy 240.328715 -57.255219)
			(xy 240.358181 -57.209369) (xy 240.393872 -57.168178) (xy 240.435063 -57.132487) (xy 240.480913 -57.103021)
			(xy 240.53049 -57.080379) (xy 240.582785 -57.065024) (xy 240.636733 -57.057268) (xy 240.691235 -57.057268)
			(xy 240.745183 -57.065024) (xy 240.797478 -57.080379) (xy 240.847055 -57.103021) (xy 240.892905 -57.132487)
			(xy 240.934096 -57.168178) (xy 240.969787 -57.209369) (xy 240.999253 -57.255219) (xy 241.021895 -57.304796)
			(xy 241.03725 -57.357091) (xy 241.045006 -57.411039) (xy 241.045492 -57.43829) (xy 241.045492 -58.30189)
			(xy 241.045006 -58.329141) (xy 241.03725 -58.383089) (xy 241.021895 -58.435384) (xy 240.999253 -58.484961)
			(xy 240.969787 -58.530811) (xy 240.941894 -58.563002) (xy 242.736116 -58.563002) (xy 242.736116 -57.699402)
			(xy 242.736602 -57.672151) (xy 242.744358 -57.618203) (xy 242.759713 -57.565908) (xy 242.782355 -57.516331)
			(xy 242.811821 -57.470481) (xy 242.847512 -57.42929) (xy 242.888703 -57.393599) (xy 242.934553 -57.364133)
			(xy 242.98413 -57.341491) (xy 243.036425 -57.326136) (xy 243.090373 -57.31838) (xy 243.144875 -57.31838)
			(xy 243.198823 -57.326136) (xy 243.251118 -57.341491) (xy 243.300695 -57.364133) (xy 243.346545 -57.393599)
			(xy 243.387736 -57.42929) (xy 243.423427 -57.470481) (xy 243.452893 -57.516331) (xy 243.475535 -57.565908)
			(xy 243.49089 -57.618203) (xy 243.498646 -57.672151) (xy 243.499132 -57.699402) (xy 243.499132 -58.563002)
			(xy 243.498646 -58.590253) (xy 243.49089 -58.644201) (xy 243.475535 -58.696496) (xy 243.452893 -58.746073)
			(xy 243.423427 -58.791923) (xy 243.387736 -58.833114) (xy 243.346545 -58.868805) (xy 243.300695 -58.898271)
			(xy 243.251118 -58.920913) (xy 243.198823 -58.936268) (xy 243.144875 -58.944024) (xy 243.090373 -58.944024)
			(xy 243.036425 -58.936268) (xy 242.98413 -58.920913) (xy 242.934553 -58.898271) (xy 242.888703 -58.868805)
			(xy 242.847512 -58.833114) (xy 242.811821 -58.791923) (xy 242.782355 -58.746073) (xy 242.759713 -58.696496)
			(xy 242.744358 -58.644201) (xy 242.736602 -58.590253) (xy 242.736116 -58.563002) (xy 240.941894 -58.563002)
			(xy 240.934096 -58.572002) (xy 240.892905 -58.607693) (xy 240.847055 -58.637159) (xy 240.797478 -58.659801)
			(xy 240.745183 -58.675156) (xy 240.691235 -58.682912) (xy 240.636733 -58.682912) (xy 240.582785 -58.675156)
			(xy 240.53049 -58.659801) (xy 240.480913 -58.637159) (xy 240.435063 -58.607693) (xy 240.393872 -58.572002)
			(xy 240.358181 -58.530811) (xy 240.328715 -58.484961) (xy 240.306073 -58.435384) (xy 240.290718 -58.383089)
			(xy 240.282962 -58.329141) (xy 240.282476 -58.30189) (xy 230.878888 -58.30189) (xy 230.878888 -58.306716)
			(xy 230.878402 -58.333967) (xy 230.870646 -58.387915) (xy 230.855291 -58.44021) (xy 230.832649 -58.489787)
			(xy 230.803183 -58.535637) (xy 230.767492 -58.576828) (xy 230.726301 -58.612519) (xy 230.680451 -58.641985)
			(xy 230.630874 -58.664627) (xy 230.578579 -58.679982) (xy 230.524631 -58.687738) (xy 230.470129 -58.687738)
			(xy 230.416181 -58.679982) (xy 230.363886 -58.664627) (xy 230.314309 -58.641985) (xy 230.268459 -58.612519)
			(xy 230.227268 -58.576828) (xy 230.191577 -58.535637) (xy 230.162111 -58.489787) (xy 230.139469 -58.44021)
			(xy 230.124114 -58.387915) (xy 230.116358 -58.333967) (xy 230.115872 -58.306716) (xy 163.272724 -58.306716)
			(xy 164.849556 -59.883548) (xy 209.33664 -59.883548) (xy 209.3616 -59.884127) (xy 209.410563 -59.893853)
			(xy 209.456682 -59.91296) (xy 209.498176 -59.940713) (xy 209.516218 -59.95797) (xy 209.933286 -60.375038)
			(xy 233.333297 -60.375038) (xy 233.337302 -60.28713) (xy 233.349285 -60.19995) (xy 233.369145 -60.114221)
			(xy 233.39672 -60.030653) (xy 233.431779 -59.949939) (xy 233.474032 -59.872747) (xy 233.52313 -59.799718)
			(xy 233.578666 -59.731456) (xy 233.640178 -59.668526) (xy 233.707159 -59.611452) (xy 233.779052 -59.560704)
			(xy 233.855261 -59.516704) (xy 233.935156 -59.479817) (xy 234.018075 -59.450348) (xy 234.10333 -59.428541)
			(xy 234.190214 -59.414577) (xy 234.278008 -59.408571) (xy 234.365985 -59.410575) (xy 234.453415 -59.42057)
			(xy 234.539574 -59.438474) (xy 234.623748 -59.464138) (xy 234.705239 -59.497351) (xy 234.783373 -59.537837)
			(xy 234.857501 -59.585259) (xy 234.927009 -59.639226) (xy 234.991323 -59.699291) (xy 235.049907 -59.764955)
			(xy 235.102278 -59.835674) (xy 235.148001 -59.910862) (xy 235.186698 -59.989897) (xy 235.218047 -60.072123)
			(xy 235.241789 -60.156859) (xy 235.257727 -60.243403) (xy 235.265729 -60.331038) (xy 235.26623 -60.375038)
			(xy 235.265729 -60.419038) (xy 235.257727 -60.506673) (xy 235.241789 -60.593217) (xy 235.218047 -60.677953)
			(xy 235.186698 -60.760179) (xy 235.148001 -60.839214) (xy 235.102278 -60.914402) (xy 235.049907 -60.985121)
			(xy 234.991323 -61.050785) (xy 234.927009 -61.11085) (xy 234.857501 -61.164817) (xy 234.783373 -61.212239)
			(xy 234.705239 -61.252725) (xy 234.623748 -61.285938) (xy 234.539574 -61.311602) (xy 234.453415 -61.329506)
			(xy 234.365985 -61.339501) (xy 234.278008 -61.341505) (xy 234.190214 -61.335499) (xy 234.10333 -61.321535)
			(xy 234.018075 -61.299728) (xy 233.935156 -61.270259) (xy 233.855261 -61.233372) (xy 233.779052 -61.189372)
			(xy 233.707159 -61.138624) (xy 233.640178 -61.08155) (xy 233.578666 -61.01862) (xy 233.52313 -60.950358)
			(xy 233.474032 -60.877329) (xy 233.431779 -60.800137) (xy 233.39672 -60.719423) (xy 233.369145 -60.635855)
			(xy 233.349285 -60.550126) (xy 233.337302 -60.462946) (xy 233.333297 -60.375038) (xy 209.933286 -60.375038)
			(xy 210.806538 -61.24829) (xy 210.823789 -61.266336) (xy 210.85153 -61.307837) (xy 210.87064 -61.353952)
			(xy 210.880386 -61.402909) (xy 210.88096 -61.427868) (xy 210.88096 -66.847974) (xy 210.909154 -66.861944)
			(xy 210.934166 -66.87496) (xy 210.980356 -66.907299) (xy 211.021284 -66.946082) (xy 211.056058 -66.990467)
			(xy 211.083923 -67.039485) (xy 211.104271 -67.09207) (xy 211.11666 -67.147078) (xy 211.120818 -67.203309)
			(xy 211.116657 -67.25954) (xy 211.104266 -67.314547) (xy 211.083916 -67.367131) (xy 211.056048 -67.416148)
			(xy 211.021272 -67.460531) (xy 210.980342 -67.499313) (xy 210.934151 -67.531649) (xy 210.909154 -67.544696)
			(xy 210.88096 -67.558666) (xy 210.88096 -68.61048) (xy 210.91271 -68.62318) (xy 210.938757 -68.634211)
			(xy 210.987455 -68.662992) (xy 211.031371 -68.698645) (xy 211.069543 -68.74039) (xy 211.101135 -68.787313)
			(xy 211.125454 -68.838385) (xy 211.141968 -68.892487) (xy 211.150316 -68.948435) (xy 211.150313 -69.005001)
			(xy 211.14196 -69.060948) (xy 211.125441 -69.115049) (xy 211.101117 -69.166118) (xy 211.06952 -69.213038)
			(xy 211.031344 -69.25478) (xy 210.987425 -69.290429) (xy 210.938724 -69.319205) (xy 210.91271 -69.330316)
			(xy 210.88096 -69.343016) (xy 210.88096 -69.493384) (xy 210.913218 -69.506084) (xy 210.939632 -69.517014)
			(xy 210.989166 -69.545544) (xy 211.03389 -69.581144) (xy 211.072803 -69.623016) (xy 211.105035 -69.670224)
			(xy 211.129865 -69.721712) (xy 211.146737 -69.776328) (xy 211.155274 -69.832849) (xy 211.155788 -69.86143)
			(xy 211.15524 -69.890584) (xy 211.14637 -69.948212) (xy 211.128841 -70.003822) (xy 211.103059 -70.05612)
			(xy 211.069626 -70.10389) (xy 211.04987 -70.125336) (xy 211.04 -70.136289) (xy 211.026531 -70.162504)
			(xy 211.021124 -70.191477) (xy 211.02423 -70.220786) (xy 211.035589 -70.247981) (xy 211.044536 -70.259702)
			(xy 211.060693 -70.280211) (xy 211.087869 -70.324789) (xy 211.108711 -70.372658) (xy 211.122828 -70.422923)
			(xy 211.129957 -70.474643) (xy 211.130388 -70.500748) (xy 211.129869 -70.528021) (xy 211.122101 -70.58201)
			(xy 211.106729 -70.634344) (xy 211.084067 -70.683958) (xy 211.054576 -70.729843) (xy 211.018855 -70.771065)
			(xy 210.998562 -70.789292) (xy 210.988338 -70.798766) (xy 210.972971 -70.822003) (xy 210.964466 -70.848532)
			(xy 210.96346 -70.876373) (xy 210.970027 -70.903447) (xy 210.983678 -70.927732) (xy 210.993228 -70.937882)
			(xy 211.014028 -70.959481) (xy 211.049286 -71.007981) (xy 211.076517 -71.061402) (xy 211.095051 -71.118427)
			(xy 211.104432 -71.177649) (xy 211.104988 -71.20763) (xy 211.104484 -71.234949) (xy 211.096686 -71.289027)
			(xy 211.081254 -71.341441) (xy 211.058503 -71.391117) (xy 211.0289 -71.43704) (xy 210.993048 -71.47827)
			(xy 210.951682 -71.513965) (xy 210.905648 -71.543395) (xy 210.88096 -71.555102) (xy 210.88096 -74.002138)
			(xy 210.91017 -74.015854) (xy 210.934498 -74.027705) (xy 210.979818 -74.057277) (xy 211.020502 -74.092958)
			(xy 211.055735 -74.134031) (xy 211.084808 -74.179672) (xy 211.107138 -74.228965) (xy 211.122276 -74.280919)
			(xy 211.129919 -74.334491) (xy 211.130388 -74.361548) (xy 211.130127 -74.38125) (xy 211.126051 -74.420444)
			(xy 211.12226 -74.43978) (xy 211.116672 -74.466704) (xy 213.195916 -76.545948) (xy 234.794298 -76.545948)
			(xy 234.903316 -76.523157) (xy 235.122884 -76.485664) (xy 235.343839 -76.457477) (xy 235.565787 -76.438644)
			(xy 235.788333 -76.429201) (xy 235.899706 -76.4286) (xy 236.011079 -76.429198) (xy 236.233626 -76.438629)
			(xy 236.455576 -76.457455) (xy 236.676531 -76.485644) (xy 236.896098 -76.523145) (xy 237.005114 -76.545948)
			(xy 257.923538 -76.545948) (xy 257.94208 -76.54544) (xy 257.960622 -76.545948) (xy 271.700244 -76.545948)
			(xy 271.9832 -76.262992) (xy 271.9832 -57.671208) (xy 271.983733 -57.646245) (xy 271.99347 -57.597279)
			(xy 272.012591 -57.55116) (xy 272.040358 -57.509669) (xy 272.057622 -57.49163) (xy 273.74596 -55.803292)
			(xy 273.74596 -53.968142) (xy 273.745572 -53.95406) (xy 273.737892 -53.926962) (xy 273.723103 -53.902993)
			(xy 273.70233 -53.883974) (xy 273.677152 -53.871351) (xy 273.649484 -53.866085) (xy 273.62143 -53.868574)
			(xy 273.595122 -53.878631) (xy 273.572561 -53.895491) (xy 273.555462 -53.917871) (xy 273.549872 -53.930804)
			(xy 273.512231 -54.025243) (xy 273.430502 -54.211419) (xy 273.341654 -54.394305) (xy 273.24582 -54.57363)
			(xy 273.143142 -54.749125) (xy 273.033773 -54.92053) (xy 272.917875 -55.08759) (xy 272.795621 -55.250056)
			(xy 272.667194 -55.407688) (xy 272.532783 -55.56025) (xy 272.392589 -55.707515) (xy 272.246821 -55.849264)
			(xy 272.095695 -55.985287) (xy 271.939435 -56.115381) (xy 271.778276 -56.239352) (xy 271.612456 -56.357017)
			(xy 271.442221 -56.4682) (xy 271.267826 -56.572735) (xy 271.089529 -56.670468) (xy 270.907597 -56.761252)
			(xy 270.722298 -56.844953) (xy 270.53391 -56.921447) (xy 270.342713 -56.990618) (xy 270.14899 -57.052366)
			(xy 269.95303 -57.106597) (xy 269.755124 -57.153231) (xy 269.555568 -57.192199) (xy 269.354657 -57.223443)
			(xy 269.152691 -57.246915) (xy 268.949969 -57.262582) (xy 268.746795 -57.27042) (xy 268.645132 -57.270904)
			(xy 268.54291 -57.270423) (xy 268.338619 -57.262497) (xy 268.13479 -57.246656) (xy 267.931728 -57.222922)
			(xy 267.729739 -57.191333) (xy 267.529127 -57.151935) (xy 267.330194 -57.104788) (xy 267.133238 -57.049963)
			(xy 266.938556 -56.987541) (xy 266.746441 -56.917618) (xy 266.557182 -56.840298) (xy 266.371063 -56.755698)
			(xy 266.188365 -56.663945) (xy 266.009361 -56.565176) (xy 265.834323 -56.45954) (xy 265.663512 -56.347197)
			(xy 265.497185 -56.228315) (xy 265.335594 -56.103073) (xy 265.17898 -55.971659) (xy 265.02758 -55.834272)
			(xy 264.88162 -55.691117) (xy 264.741322 -55.54241) (xy 264.606895 -55.388375) (xy 264.478542 -55.229243)
			(xy 264.356456 -55.065254) (xy 264.240821 -54.896654) (xy 264.13181 -54.723697) (xy 264.029587 -54.546644)
			(xy 263.934307 -54.36576) (xy 263.846113 -54.181317) (xy 263.765136 -53.993593) (xy 263.6915 -53.802871)
			(xy 263.625314 -53.609436) (xy 263.566678 -53.413581) (xy 263.515681 -53.215599) (xy 263.4724 -53.015789)
			(xy 263.436898 -52.814451) (xy 263.40923 -52.611888) (xy 263.389438 -52.408404) (xy 263.37755 -52.204306)
			(xy 263.373586 -51.9999) (xy 263.37755 -51.795494) (xy 263.389438 -51.591396) (xy 263.40923 -51.387912)
			(xy 263.436898 -51.185349) (xy 263.4724 -50.984011) (xy 263.515681 -50.784201) (xy 263.566678 -50.586219)
			(xy 263.625314 -50.390364) (xy 263.6915 -50.196929) (xy 263.765136 -50.006207) (xy 263.846113 -49.818483)
			(xy 263.934307 -49.63404) (xy 264.029587 -49.453156) (xy 264.13181 -49.276103) (xy 264.240821 -49.103146)
			(xy 264.356456 -48.934546) (xy 264.478542 -48.770557) (xy 264.606895 -48.611425) (xy 264.741322 -48.45739)
			(xy 264.88162 -48.308683) (xy 265.02758 -48.165528) (xy 265.17898 -48.028141) (xy 265.335594 -47.896727)
			(xy 265.497185 -47.771485) (xy 265.663512 -47.652603) (xy 265.834323 -47.54026) (xy 266.009361 -47.434624)
			(xy 266.188365 -47.335855) (xy 266.371063 -47.244102) (xy 266.557182 -47.159502) (xy 266.746441 -47.082182)
			(xy 266.938556 -47.012259) (xy 267.133238 -46.949837) (xy 267.330194 -46.895012) (xy 267.529127 -46.847865)
			(xy 267.729739 -46.808467) (xy 267.931728 -46.776878) (xy 268.13479 -46.753144) (xy 268.338619 -46.737303)
			(xy 268.54291 -46.729377) (xy 268.645132 -46.728888) (xy 268.746794 -46.729408) (xy 268.949966 -46.737249)
			(xy 269.152684 -46.75292) (xy 269.354647 -46.776395) (xy 269.555555 -46.807642) (xy 269.755109 -46.846612)
			(xy 269.953012 -46.893248) (xy 270.148969 -46.947481) (xy 270.342688 -47.00923) (xy 270.533883 -47.078403)
			(xy 270.722268 -47.154897) (xy 270.907564 -47.238598) (xy 271.089494 -47.329383) (xy 271.267788 -47.427115)
			(xy 271.44218 -47.53165) (xy 271.612412 -47.642832) (xy 271.77823 -47.760496) (xy 271.939387 -47.884466)
			(xy 272.095644 -48.014559) (xy 272.246769 -48.15058) (xy 272.392536 -48.292328) (xy 272.532728 -48.439591)
			(xy 272.667138 -48.59215) (xy 272.795565 -48.749779) (xy 272.917817 -48.912243) (xy 273.033715 -49.0793)
			(xy 273.143084 -49.250703) (xy 273.245762 -49.426195) (xy 273.341597 -49.605516) (xy 273.430445 -49.788399)
			(xy 273.512176 -49.974572) (xy 273.549872 -50.068988) (xy 273.555511 -50.081894) (xy 273.572599 -50.104263)
			(xy 273.595148 -50.121115) (xy 273.621441 -50.131167) (xy 273.649481 -50.133655) (xy 273.677134 -50.128391)
			(xy 273.702298 -50.115775) (xy 273.723059 -50.096765) (xy 273.737839 -50.072808) (xy 273.745514 -50.045725)
			(xy 273.74596 -50.03165) (xy 273.74596 -37.132768) (xy 273.746541 -37.107808) (xy 273.756265 -37.058844)
			(xy 273.775372 -37.012726) (xy 273.803125 -36.971232) (xy 273.820382 -36.95319) (xy 287.196022 -23.57755)
			(xy 287.214053 -23.560282) (xy 287.255559 -23.532545) (xy 287.301679 -23.513439) (xy 287.35064 -23.503699)
			(xy 287.3756 -23.503128) (xy 320.832988 -23.503128) (xy 320.842132 -23.464012) (xy 320.849192 -23.43652)
			(xy 320.870332 -23.383846) (xy 320.899041 -23.334884) (xy 320.934684 -23.290714) (xy 320.976475 -23.252309)
			(xy 321.023493 -23.220516) (xy 321.074701 -23.196037) (xy 321.128969 -23.179411) (xy 321.185101 -23.171006)
			(xy 321.241859 -23.171006) (xy 321.297991 -23.179411) (xy 321.352259 -23.196037) (xy 321.403467 -23.220516)
			(xy 321.450485 -23.252309) (xy 321.492276 -23.290714) (xy 321.527919 -23.334884) (xy 321.556628 -23.383846)
			(xy 321.577768 -23.43652) (xy 321.584828 -23.464012) (xy 321.593972 -23.503128) (xy 328.076306 -23.503128)
			(xy 328.088466 -23.480186) (xy 328.118489 -23.437823) (xy 328.154386 -23.400308) (xy 328.195385 -23.368448)
			(xy 328.240603 -23.342927) (xy 328.289068 -23.324296) (xy 328.339737 -23.312954) (xy 328.39152 -23.309146)
			(xy 328.443303 -23.312954) (xy 328.493972 -23.324296) (xy 328.542437 -23.342927) (xy 328.587655 -23.368448)
			(xy 328.628654 -23.400308) (xy 328.664551 -23.437823) (xy 328.694574 -23.480186) (xy 328.706734 -23.503128)
			(xy 329.526138 -23.503128) (xy 329.540362 -23.475696) (xy 329.55261 -23.452972) (xy 329.582692 -23.411024)
			(xy 329.618556 -23.373896) (xy 329.659437 -23.342379) (xy 329.704467 -23.317142) (xy 329.752689 -23.298723)
			(xy 329.803077 -23.287512) (xy 329.85456 -23.283748) (xy 329.906043 -23.287512) (xy 329.956431 -23.298723)
			(xy 330.004653 -23.317142) (xy 330.049683 -23.342379) (xy 330.090564 -23.373896) (xy 330.126428 -23.411024)
			(xy 330.15651 -23.452972) (xy 330.168758 -23.475696) (xy 330.182982 -23.503128) (xy 333.600806 -23.503128)
			(xy 333.610966 -23.498556) (xy 333.636156 -23.487416) (xy 333.688946 -23.471704) (xy 333.743447 -23.46375)
			(xy 333.770986 -23.46325) (xy 333.798524 -23.46376) (xy 333.853023 -23.471718) (xy 333.905812 -23.487427)
			(xy 333.931006 -23.498556) (xy 333.941166 -23.503128) (xy 334.01889 -23.503128) (xy 334.031844 -23.471378)
			(xy 334.042918 -23.445327) (xy 334.071637 -23.396547) (xy 334.107252 -23.352549) (xy 334.14898 -23.314301)
			(xy 334.195905 -23.282641) (xy 334.246994 -23.258267) (xy 334.301125 -23.241714) (xy 334.357109 -23.233345)
			(xy 334.413715 -23.233345) (xy 334.469699 -23.241714) (xy 334.52383 -23.258267) (xy 334.574919 -23.282641)
			(xy 334.621844 -23.314301) (xy 334.663572 -23.352549) (xy 334.699187 -23.396547) (xy 334.727906 -23.445327)
			(xy 334.73898 -23.471378) (xy 334.751934 -23.503128) (xy 353.740466 -23.503128) (xy 353.749864 -23.499318)
			(xy 353.771433 -23.490725) (xy 353.81626 -23.478633) (xy 353.862286 -23.472521) (xy 353.8855 -23.47214)
			(xy 353.908713 -23.472533) (xy 353.954736 -23.478653) (xy 353.999564 -23.490736) (xy 354.021136 -23.499318)
			(xy 354.030534 -23.503128) (xy 373.04472 -23.503128) (xy 373.069679 -23.503725) (xy 373.118641 -23.513446)
			(xy 373.164759 -23.532548) (xy 373.206255 -23.560295) (xy 373.224298 -23.57755) (xy 383.546858 -33.90011)
			(xy 462.69148 -33.90011) (xy 462.69148 -32.29991) (xy 462.691988 -32.23523) (xy 462.700111 -32.106124)
			(xy 462.716324 -31.977784) (xy 462.740564 -31.850714) (xy 462.772734 -31.725418) (xy 462.812709 -31.602388)
			(xy 462.86033 -31.482112) (xy 462.915409 -31.365063) (xy 462.977729 -31.251703) (xy 463.047044 -31.14248)
			(xy 463.12308 -31.037825) (xy 463.205538 -30.938151) (xy 463.294091 -30.843851) (xy 463.388391 -30.755298)
			(xy 463.488065 -30.67284) (xy 463.59272 -30.596804) (xy 463.701943 -30.527489) (xy 463.815303 -30.465169)
			(xy 463.932352 -30.41009) (xy 464.052628 -30.362469) (xy 464.175658 -30.322494) (xy 464.300954 -30.290324)
			(xy 464.428024 -30.266084) (xy 464.556364 -30.249871) (xy 464.68547 -30.241748) (xy 464.81483 -30.241748)
			(xy 464.943936 -30.249871) (xy 465.072276 -30.266084) (xy 465.199346 -30.290324) (xy 465.324642 -30.322494)
			(xy 465.447672 -30.362469) (xy 465.567948 -30.41009) (xy 465.684997 -30.465169) (xy 465.798357 -30.527489)
			(xy 465.90758 -30.596804) (xy 466.012235 -30.67284) (xy 466.111909 -30.755298) (xy 466.206209 -30.843851)
			(xy 466.294762 -30.938151) (xy 466.37722 -31.037825) (xy 466.453256 -31.14248) (xy 466.522571 -31.251703)
			(xy 466.584891 -31.365063) (xy 466.63997 -31.482112) (xy 466.687591 -31.602388) (xy 466.727566 -31.725418)
			(xy 466.759736 -31.850714) (xy 466.783976 -31.977784) (xy 466.800189 -32.106124) (xy 466.808312 -32.23523)
			(xy 466.80882 -32.29991) (xy 466.80882 -33.90011) (xy 466.808312 -33.96479) (xy 466.800189 -34.093896)
			(xy 466.783976 -34.222236) (xy 466.759736 -34.349306) (xy 466.727566 -34.474602) (xy 466.687591 -34.597632)
			(xy 466.63997 -34.717908) (xy 466.584891 -34.834957) (xy 466.522571 -34.948317) (xy 466.453256 -35.05754)
			(xy 466.37722 -35.162195) (xy 466.294762 -35.261869) (xy 466.206209 -35.356169) (xy 466.111909 -35.444722)
			(xy 466.012235 -35.52718) (xy 465.90758 -35.603216) (xy 465.798357 -35.672531) (xy 465.684997 -35.734851)
			(xy 465.567948 -35.78993) (xy 465.447672 -35.837551) (xy 465.324642 -35.877526) (xy 465.199346 -35.909696)
			(xy 465.072276 -35.933936) (xy 464.943936 -35.950149) (xy 464.81483 -35.958272) (xy 464.68547 -35.958272)
			(xy 464.556364 -35.950149) (xy 464.428024 -35.933936) (xy 464.300954 -35.909696) (xy 464.175658 -35.877526)
			(xy 464.052628 -35.837551) (xy 463.932352 -35.78993) (xy 463.815303 -35.734851) (xy 463.701943 -35.672531)
			(xy 463.59272 -35.603216) (xy 463.488065 -35.52718) (xy 463.388391 -35.444722) (xy 463.294091 -35.356169)
			(xy 463.205538 -35.261869) (xy 463.12308 -35.162195) (xy 463.047044 -35.05754) (xy 462.977729 -34.948317)
			(xy 462.915409 -34.834957) (xy 462.86033 -34.717908) (xy 462.812709 -34.597632) (xy 462.772734 -34.474602)
			(xy 462.740564 -34.349306) (xy 462.716324 -34.222236) (xy 462.700111 -34.093896) (xy 462.691988 -33.96479)
			(xy 462.69148 -33.90011) (xy 383.546858 -33.90011) (xy 386.291836 -36.645088) (xy 425.80052 -36.645088)
			(xy 425.817528 -36.606561) (xy 425.857724 -36.532548) (xy 425.904641 -36.462604) (xy 425.957873 -36.397336)
			(xy 426.016956 -36.337313) (xy 426.081375 -36.283057) (xy 426.15057 -36.235041) (xy 426.223939 -36.193683)
			(xy 426.300843 -36.159342) (xy 426.380613 -36.132317) (xy 426.462554 -36.112844) (xy 426.545953 -36.101091)
			(xy 426.630084 -36.097163) (xy 426.714215 -36.101091) (xy 426.797614 -36.112844) (xy 426.879555 -36.132317)
			(xy 426.959325 -36.159342) (xy 427.036229 -36.193683) (xy 427.109598 -36.235041) (xy 427.178793 -36.283057)
			(xy 427.243212 -36.337313) (xy 427.302295 -36.397336) (xy 427.355527 -36.462604) (xy 427.402444 -36.532548)
			(xy 427.44264 -36.606561) (xy 427.459648 -36.645088) (xy 428.34052 -36.645088) (xy 428.357528 -36.606561)
			(xy 428.397724 -36.532548) (xy 428.444641 -36.462604) (xy 428.497873 -36.397336) (xy 428.556956 -36.337313)
			(xy 428.621375 -36.283057) (xy 428.69057 -36.235041) (xy 428.763939 -36.193683) (xy 428.840843 -36.159342)
			(xy 428.920613 -36.132317) (xy 429.002554 -36.112844) (xy 429.085953 -36.101091) (xy 429.170084 -36.097163)
			(xy 429.254215 -36.101091) (xy 429.337614 -36.112844) (xy 429.419555 -36.132317) (xy 429.499325 -36.159342)
			(xy 429.576229 -36.193683) (xy 429.649598 -36.235041) (xy 429.718793 -36.283057) (xy 429.783212 -36.337313)
			(xy 429.842295 -36.397336) (xy 429.895527 -36.462604) (xy 429.942444 -36.532548) (xy 429.98264 -36.606561)
			(xy 429.999648 -36.645088) (xy 448.15252 -36.645088) (xy 448.17748 -36.645668) (xy 448.226444 -36.655391)
			(xy 448.272563 -36.674498) (xy 448.314057 -36.702252) (xy 448.332098 -36.71951) (xy 452.556118 -40.94353)
			(xy 452.573337 -40.961605) (xy 452.601085 -41.003095) (xy 452.620204 -41.049201) (xy 452.62996 -41.098152)
			(xy 452.63054 -41.123108) (xy 452.63054 -70.932548) (xy 452.629969 -70.957509) (xy 452.620241 -71.006472)
			(xy 452.601132 -71.052591) (xy 452.573377 -71.094085) (xy 452.556118 -71.112126) (xy 451.146418 -72.521826)
			(xy 451.128366 -72.539071) (xy 451.086868 -72.566813) (xy 451.040755 -72.585926) (xy 450.991798 -72.595673)
			(xy 450.96684 -72.596248) (xy 432.311556 -72.596248) (xy 432.311556 -74.767948) (xy 432.311051 -74.873472)
			(xy 432.302967 -75.084366) (xy 432.286811 -75.294795) (xy 432.262608 -75.504452) (xy 432.230391 -75.713027)
			(xy 432.190209 -75.920215) (xy 432.142121 -76.125712) (xy 432.086197 -76.329216) (xy 432.02252 -76.530429)
			(xy 431.951182 -76.729056) (xy 431.872288 -76.924804) (xy 431.785955 -77.117386) (xy 431.692308 -77.306521)
			(xy 431.591486 -77.49193) (xy 431.483636 -77.673341) (xy 431.368917 -77.850488) (xy 431.247497 -78.02311)
			(xy 431.119554 -78.190956) (xy 430.985276 -78.353778) (xy 430.84486 -78.511337) (xy 430.698512 -78.663402)
			(xy 430.546447 -78.80975) (xy 430.388888 -78.950166) (xy 430.226066 -79.084444) (xy 430.05822 -79.212387)
			(xy 429.885598 -79.333807) (xy 429.708451 -79.448526) (xy 429.52704 -79.556376) (xy 429.341631 -79.657198)
			(xy 429.152496 -79.750845) (xy 428.959914 -79.837178) (xy 428.764166 -79.916072) (xy 428.565539 -79.98741)
			(xy 428.364326 -80.051087) (xy 428.160822 -80.107011) (xy 427.955325 -80.155099) (xy 427.748137 -80.195281)
			(xy 427.539562 -80.227498) (xy 427.329905 -80.251701) (xy 427.119476 -80.267857) (xy 426.908582 -80.275941)
			(xy 426.697534 -80.275941) (xy 426.48664 -80.267857) (xy 426.276211 -80.251701) (xy 426.066554 -80.227498)
			(xy 425.857979 -80.195281) (xy 425.650791 -80.155099) (xy 425.445294 -80.107011) (xy 425.24179 -80.051087)
			(xy 425.040577 -79.98741) (xy 424.84195 -79.916072) (xy 424.646202 -79.837178) (xy 424.45362 -79.750845)
			(xy 424.264485 -79.657198) (xy 424.079076 -79.556376) (xy 423.897665 -79.448526) (xy 423.720518 -79.333807)
			(xy 423.547896 -79.212387) (xy 423.38005 -79.084444) (xy 423.217228 -78.950166) (xy 423.059669 -78.80975)
			(xy 422.907604 -78.663402) (xy 422.761256 -78.511337) (xy 422.62084 -78.353778) (xy 422.486562 -78.190956)
			(xy 422.358619 -78.02311) (xy 422.237199 -77.850488) (xy 422.12248 -77.673341) (xy 422.01463 -77.49193)
			(xy 421.913808 -77.306521) (xy 421.820161 -77.117386) (xy 421.733828 -76.924804) (xy 421.654934 -76.729056)
			(xy 421.583596 -76.530429) (xy 421.519919 -76.329216) (xy 421.463995 -76.125712) (xy 421.415907 -75.920215)
			(xy 421.375725 -75.713027) (xy 421.343508 -75.504452) (xy 421.319305 -75.294795) (xy 421.303149 -75.084366)
			(xy 421.295065 -74.873472) (xy 421.29456 -74.767948) (xy 421.29456 -72.596248) (xy 396.797276 -72.596248)
			(xy 391.13714 -78.256384) (xy 391.13714 -94.404688) (xy 391.136594 -94.42965) (xy 391.126859 -94.478615)
			(xy 391.107741 -94.524733) (xy 391.07998 -94.566226) (xy 391.062718 -94.584266) (xy 382.027938 -103.619046)
			(xy 382.009881 -103.636285) (xy 381.968384 -103.664028) (xy 381.922273 -103.683141) (xy 381.873318 -103.692891)
			(xy 381.84836 -103.693468) (xy 378.815854 -103.693468) (xy 378.797521 -103.712401) (xy 378.756243 -103.745163)
			(xy 378.710557 -103.771431) (xy 378.661476 -103.790621) (xy 378.610089 -103.802308) (xy 378.557536 -103.806233)
			(xy 378.504983 -103.802308) (xy 378.453596 -103.790621) (xy 378.404515 -103.771431) (xy 378.358829 -103.745163)
			(xy 378.317551 -103.712401) (xy 378.299218 -103.693468) (xy 368.427508 -103.693468) (xy 368.410817 -103.715167)
			(xy 368.372245 -103.754012) (xy 368.328515 -103.786944) (xy 368.280527 -103.813287) (xy 368.229267 -103.8325)
			(xy 368.175786 -103.844187) (xy 368.121184 -103.84811) (xy 368.066582 -103.844187) (xy 368.013101 -103.8325)
			(xy 367.961841 -103.813287) (xy 367.913853 -103.786944) (xy 367.870123 -103.754012) (xy 367.831551 -103.715167)
			(xy 367.81486 -103.693468) (xy 364.584996 -103.693468) (xy 340.586006 -127.692458) (xy 458.401155 -127.692458)
			(xy 458.401155 -127.563318) (xy 458.409105 -127.434423) (xy 458.424975 -127.306263) (xy 458.448704 -127.179322)
			(xy 458.480203 -127.054083) (xy 458.519352 -126.93102) (xy 458.566003 -126.810601) (xy 458.619978 -126.693282)
			(xy 458.681073 -126.579508) (xy 458.749056 -126.469711) (xy 458.82367 -126.364308) (xy 458.904631 -126.263698)
			(xy 458.991631 -126.168263) (xy 459.084342 -126.078364) (xy 459.182412 -125.994343) (xy 459.285467 -125.916519)
			(xy 459.393118 -125.845187) (xy 459.504957 -125.780617) (xy 459.620558 -125.723055) (xy 459.739483 -125.672718)
			(xy 459.861282 -125.629798) (xy 459.985492 -125.594457) (xy 460.111641 -125.56683) (xy 460.239253 -125.547021)
			(xy 460.367842 -125.535105) (xy 460.49692 -125.531129) (xy 460.625998 -125.535105) (xy 460.754587 -125.547021)
			(xy 460.882199 -125.56683) (xy 461.008348 -125.594457) (xy 461.132558 -125.629798) (xy 461.254357 -125.672718)
			(xy 461.373282 -125.723055) (xy 461.488883 -125.780617) (xy 461.600722 -125.845187) (xy 461.708373 -125.916519)
			(xy 461.811428 -125.994343) (xy 461.909498 -126.078364) (xy 462.002209 -126.168263) (xy 462.089209 -126.263698)
			(xy 462.17017 -126.364308) (xy 462.244784 -126.469711) (xy 462.312767 -126.579508) (xy 462.373862 -126.693282)
			(xy 462.427837 -126.810601) (xy 462.474488 -126.93102) (xy 462.513637 -127.054083) (xy 462.545136 -127.179322)
			(xy 462.568865 -127.306263) (xy 462.584735 -127.434423) (xy 462.592685 -127.563318) (xy 462.593182 -127.627888)
			(xy 462.592685 -127.692458) (xy 462.584735 -127.821353) (xy 462.568865 -127.949513) (xy 462.545136 -128.076454)
			(xy 462.513637 -128.201693) (xy 462.474488 -128.324756) (xy 462.427837 -128.445175) (xy 462.373862 -128.562494)
			(xy 462.312767 -128.676268) (xy 462.244784 -128.786065) (xy 462.17017 -128.891468) (xy 462.089209 -128.992078)
			(xy 462.002209 -129.087513) (xy 461.909498 -129.177412) (xy 461.811428 -129.261433) (xy 461.708373 -129.339257)
			(xy 461.600722 -129.410589) (xy 461.488883 -129.475159) (xy 461.373282 -129.532721) (xy 461.254357 -129.583058)
			(xy 461.132558 -129.625978) (xy 461.008348 -129.661319) (xy 460.882199 -129.688946) (xy 460.754587 -129.708755)
			(xy 460.625998 -129.720671) (xy 460.49692 -129.724648) (xy 460.367842 -129.720671) (xy 460.239253 -129.708755)
			(xy 460.111641 -129.688946) (xy 459.985492 -129.661319) (xy 459.861282 -129.625978) (xy 459.739483 -129.583058)
			(xy 459.620558 -129.532721) (xy 459.504957 -129.475159) (xy 459.393118 -129.410589) (xy 459.285467 -129.339257)
			(xy 459.182412 -129.261433) (xy 459.084342 -129.177412) (xy 458.991631 -129.087513) (xy 458.904631 -128.992078)
			(xy 458.82367 -128.891468) (xy 458.749056 -128.786065) (xy 458.681073 -128.676268) (xy 458.619978 -128.562494)
			(xy 458.566003 -128.445175) (xy 458.519352 -128.324756) (xy 458.480203 -128.201693) (xy 458.448704 -128.076454)
			(xy 458.424975 -127.949513) (xy 458.409105 -127.821353) (xy 458.401155 -127.692458) (xy 340.586006 -127.692458)
			(xy 334.087978 -134.190486) (xy 334.069927 -134.207729) (xy 334.028425 -134.235459) (xy 333.982311 -134.254559)
			(xy 333.933357 -134.264296) (xy 333.9084 -134.264908) (xy 298.202858 -134.264908) (xy 298.189226 -134.288055)
			(xy 298.156462 -134.330627) (xy 298.118051 -134.368181) (xy 298.074752 -134.399975) (xy 298.02742 -134.425381)
			(xy 297.976992 -134.443895) (xy 297.924466 -134.455153) (xy 297.87088 -134.45893) (xy 297.817294 -134.455153)
			(xy 297.764768 -134.443895) (xy 297.71434 -134.425381) (xy 297.667008 -134.399975) (xy 297.623709 -134.368181)
			(xy 297.585298 -134.330627) (xy 297.552534 -134.288055) (xy 297.538902 -134.264908) (xy 255.447038 -134.264908)
			(xy 255.422076 -134.264355) (xy 255.373111 -134.254623) (xy 255.326993 -134.235508) (xy 255.2855 -134.207748)
			(xy 255.26746 -134.190486) (xy 240.114582 -119.037608) (xy 223.203516 -119.037608) (xy 219.147136 -123.093988)
			(xy 227.217732 -123.093988) (xy 227.217732 -122.230388) (xy 227.218218 -122.203137) (xy 227.225974 -122.149189)
			(xy 227.241329 -122.096894) (xy 227.263971 -122.047317) (xy 227.293437 -122.001467) (xy 227.329128 -121.960276)
			(xy 227.370319 -121.924585) (xy 227.416169 -121.895119) (xy 227.465746 -121.872477) (xy 227.518041 -121.857122)
			(xy 227.571989 -121.849366) (xy 227.626491 -121.849366) (xy 227.680439 -121.857122) (xy 227.732734 -121.872477)
			(xy 227.782311 -121.895119) (xy 227.828161 -121.924585) (xy 227.869352 -121.960276) (xy 227.905043 -122.001467)
			(xy 227.934509 -122.047317) (xy 227.957151 -122.096894) (xy 227.972506 -122.149189) (xy 227.980262 -122.203137)
			(xy 227.980748 -122.230388) (xy 227.980748 -123.093988) (xy 227.980262 -123.121239) (xy 227.972506 -123.175187)
			(xy 227.957151 -123.227482) (xy 227.934509 -123.277059) (xy 227.905043 -123.322909) (xy 227.869352 -123.3641)
			(xy 227.828161 -123.399791) (xy 227.782311 -123.429257) (xy 227.732734 -123.451899) (xy 227.680439 -123.467254)
			(xy 227.626491 -123.47501) (xy 227.571989 -123.47501) (xy 227.518041 -123.467254) (xy 227.465746 -123.451899)
			(xy 227.416169 -123.429257) (xy 227.370319 -123.399791) (xy 227.329128 -123.3641) (xy 227.293437 -123.322909)
			(xy 227.263971 -123.277059) (xy 227.241329 -123.227482) (xy 227.225974 -123.175187) (xy 227.218218 -123.121239)
			(xy 227.217732 -123.093988) (xy 219.147136 -123.093988) (xy 217.019378 -125.221746) (xy 225.535744 -125.221746)
			(xy 225.535744 -124.358146) (xy 225.53623 -124.330877) (xy 225.543992 -124.276893) (xy 225.559357 -124.224563)
			(xy 225.582014 -124.174953) (xy 225.6115 -124.129072) (xy 225.647215 -124.087855) (xy 225.688432 -124.05214)
			(xy 225.734313 -124.022654) (xy 225.783923 -123.999997) (xy 225.836253 -123.984632) (xy 225.890237 -123.97687)
			(xy 225.944775 -123.97687) (xy 225.998759 -123.984632) (xy 226.051089 -123.999997) (xy 226.100699 -124.022654)
			(xy 226.14658 -124.05214) (xy 226.187797 -124.087855) (xy 226.223512 -124.129072) (xy 226.252998 -124.174953)
			(xy 226.275655 -124.224563) (xy 226.29102 -124.276893) (xy 226.298782 -124.330877) (xy 226.299268 -124.358146)
			(xy 226.299268 -125.221746) (xy 226.298782 -125.249015) (xy 226.29102 -125.302999) (xy 226.275655 -125.355329)
			(xy 226.252998 -125.404939) (xy 226.223512 -125.45082) (xy 226.187797 -125.492037) (xy 226.14658 -125.527752)
			(xy 226.100699 -125.557238) (xy 226.051089 -125.579895) (xy 225.998759 -125.59526) (xy 225.944775 -125.603022)
			(xy 225.890237 -125.603022) (xy 225.836253 -125.59526) (xy 225.783923 -125.579895) (xy 225.734313 -125.557238)
			(xy 225.688432 -125.527752) (xy 225.647215 -125.492037) (xy 225.6115 -125.45082) (xy 225.582014 -125.404939)
			(xy 225.559357 -125.355329) (xy 225.543992 -125.302999) (xy 225.53623 -125.249015) (xy 225.535744 -125.221746)
			(xy 217.019378 -125.221746) (xy 214.915496 -127.325628) (xy 227.034852 -127.325628) (xy 227.034852 -126.462028)
			(xy 227.035338 -126.434777) (xy 227.043094 -126.380829) (xy 227.058449 -126.328534) (xy 227.081091 -126.278957)
			(xy 227.110557 -126.233107) (xy 227.146248 -126.191916) (xy 227.187439 -126.156225) (xy 227.233289 -126.126759)
			(xy 227.282866 -126.104117) (xy 227.335161 -126.088762) (xy 227.389109 -126.081006) (xy 227.443611 -126.081006)
			(xy 227.497559 -126.088762) (xy 227.549854 -126.104117) (xy 227.599431 -126.126759) (xy 227.645281 -126.156225)
			(xy 227.686472 -126.191916) (xy 227.722163 -126.233107) (xy 227.751629 -126.278957) (xy 227.774271 -126.328534)
			(xy 227.789626 -126.380829) (xy 227.797382 -126.434777) (xy 227.797868 -126.462028) (xy 227.797868 -127.140208)
			(xy 242.041172 -127.140208) (xy 242.041172 -126.276608) (xy 242.041658 -126.249357) (xy 242.049414 -126.195409)
			(xy 242.064769 -126.143114) (xy 242.087411 -126.093537) (xy 242.116877 -126.047687) (xy 242.152568 -126.006496)
			(xy 242.193759 -125.970805) (xy 242.239609 -125.941339) (xy 242.289186 -125.918697) (xy 242.341481 -125.903342)
			(xy 242.395429 -125.895586) (xy 242.449931 -125.895586) (xy 242.503879 -125.903342) (xy 242.556174 -125.918697)
			(xy 242.605751 -125.941339) (xy 242.651601 -125.970805) (xy 242.692792 -126.006496) (xy 242.728483 -126.047687)
			(xy 242.757949 -126.093537) (xy 242.780591 -126.143114) (xy 242.795946 -126.195409) (xy 242.803702 -126.249357)
			(xy 242.804188 -126.276608) (xy 242.804188 -127.140208) (xy 242.803702 -127.167459) (xy 242.795946 -127.221407)
			(xy 242.780591 -127.273702) (xy 242.757949 -127.323279) (xy 242.728483 -127.369129) (xy 242.692792 -127.41032)
			(xy 242.651601 -127.446011) (xy 242.605751 -127.475477) (xy 242.556174 -127.498119) (xy 242.503879 -127.513474)
			(xy 242.449931 -127.52123) (xy 242.395429 -127.52123) (xy 242.341481 -127.513474) (xy 242.289186 -127.498119)
			(xy 242.239609 -127.475477) (xy 242.193759 -127.446011) (xy 242.152568 -127.41032) (xy 242.116877 -127.369129)
			(xy 242.087411 -127.323279) (xy 242.064769 -127.273702) (xy 242.049414 -127.221407) (xy 242.041658 -127.167459)
			(xy 242.041172 -127.140208) (xy 227.797868 -127.140208) (xy 227.797868 -127.325628) (xy 227.797382 -127.352879)
			(xy 227.789626 -127.406827) (xy 227.774271 -127.459122) (xy 227.751629 -127.508699) (xy 227.722163 -127.554549)
			(xy 227.686472 -127.59574) (xy 227.645281 -127.631431) (xy 227.599431 -127.660897) (xy 227.549854 -127.683539)
			(xy 227.497559 -127.698894) (xy 227.443611 -127.70665) (xy 227.389109 -127.70665) (xy 227.335161 -127.698894)
			(xy 227.282866 -127.683539) (xy 227.233289 -127.660897) (xy 227.187439 -127.631431) (xy 227.146248 -127.59574)
			(xy 227.110557 -127.554549) (xy 227.081091 -127.508699) (xy 227.058449 -127.459122) (xy 227.043094 -127.406827)
			(xy 227.035338 -127.352879) (xy 227.034852 -127.325628) (xy 214.915496 -127.325628) (xy 213.167976 -129.073148)
			(xy 223.562672 -129.073148) (xy 223.562672 -128.209548) (xy 223.563115 -128.182788) (xy 223.570596 -128.129795)
			(xy 223.585403 -128.078365) (xy 223.607247 -128.029506) (xy 223.621092 -128.006602) (xy 223.636032 -127.983032)
			(xy 223.671662 -127.940084) (xy 223.713174 -127.902792) (xy 223.759681 -127.871951) (xy 223.810187 -127.848221)
			(xy 223.863614 -127.832109) (xy 223.918819 -127.823961) (xy 223.94672 -127.823468) (xy 223.973934 -127.823967)
			(xy 224.027808 -127.831715) (xy 224.080031 -127.84705) (xy 224.12954 -127.869661) (xy 224.175327 -127.899088)
			(xy 224.216462 -127.93473) (xy 224.252105 -127.975863) (xy 224.281533 -128.02165) (xy 224.304145 -128.071158)
			(xy 224.319483 -128.123381) (xy 224.327232 -128.177254) (xy 224.32772 -128.204468) (xy 224.32772 -128.204722)
			(xy 224.325942 -128.241552) (xy 224.325688 -128.243838) (xy 224.325688 -129.019808) (xy 240.086896 -129.019808)
			(xy 240.086896 -128.156208) (xy 240.087382 -128.128939) (xy 240.095144 -128.074955) (xy 240.110509 -128.022625)
			(xy 240.133166 -127.973015) (xy 240.162652 -127.927134) (xy 240.198367 -127.885917) (xy 240.239584 -127.850202)
			(xy 240.285465 -127.820716) (xy 240.335075 -127.798059) (xy 240.387405 -127.782694) (xy 240.441389 -127.774932)
			(xy 240.495927 -127.774932) (xy 240.549911 -127.782694) (xy 240.602241 -127.798059) (xy 240.651851 -127.820716)
			(xy 240.697732 -127.850202) (xy 240.738949 -127.885917) (xy 240.774664 -127.927134) (xy 240.80415 -127.973015)
			(xy 240.826807 -128.022625) (xy 240.842172 -128.074955) (xy 240.849934 -128.128939) (xy 240.85042 -128.156208)
			(xy 240.85042 -129.019808) (xy 240.849934 -129.047077) (xy 240.842172 -129.101061) (xy 240.826807 -129.153391)
			(xy 240.80415 -129.203001) (xy 240.774664 -129.248882) (xy 240.738949 -129.290099) (xy 240.697732 -129.325814)
			(xy 240.651851 -129.3553) (xy 240.602241 -129.377957) (xy 240.549911 -129.393322) (xy 240.495927 -129.401084)
			(xy 240.441389 -129.401084) (xy 240.387405 -129.393322) (xy 240.335075 -129.377957) (xy 240.285465 -129.3553)
			(xy 240.239584 -129.325814) (xy 240.198367 -129.290099) (xy 240.162652 -129.248882) (xy 240.133166 -129.203001)
			(xy 240.110509 -129.153391) (xy 240.095144 -129.101061) (xy 240.087382 -129.047077) (xy 240.086896 -129.019808)
			(xy 224.325688 -129.019808) (xy 224.325942 -129.022602) (xy 224.327226 -129.033861) (xy 224.328622 -129.056482)
			(xy 224.328736 -129.067814) (xy 224.328736 -129.068068) (xy 224.328226 -129.095352) (xy 224.320425 -129.14936)
			(xy 224.305035 -129.201713) (xy 224.282367 -129.251351) (xy 224.26803 -129.27457) (xy 224.253042 -129.297814)
			(xy 224.217376 -129.340083) (xy 224.175977 -129.376756) (xy 224.129714 -129.407061) (xy 224.079557 -129.430365)
			(xy 224.026559 -129.446176) (xy 223.971833 -129.454165) (xy 223.94418 -129.454656) (xy 223.91693 -129.454141)
			(xy 223.862986 -129.446383) (xy 223.810695 -129.431028) (xy 223.761121 -129.408388) (xy 223.715273 -129.378924)
			(xy 223.674084 -129.343236) (xy 223.638393 -129.30205) (xy 223.608926 -129.256204) (xy 223.586282 -129.206631)
			(xy 223.570923 -129.154341) (xy 223.563161 -129.100398) (xy 223.562672 -129.073148) (xy 213.167976 -129.073148)
			(xy 211.946744 -130.29438) (xy 211.933032 -130.307622) (xy 211.902353 -130.330245) (xy 211.868625 -130.348004)
			(xy 211.850732 -130.354578) (xy 211.844096 -130.382581) (xy 211.823553 -130.436336) (xy 211.795173 -130.486397)
			(xy 211.759598 -130.531631) (xy 211.717636 -130.571011) (xy 211.670237 -130.603644) (xy 211.618476 -130.628792)
			(xy 211.563526 -130.645884) (xy 211.506633 -130.654532) (xy 211.47786 -130.65506) (xy 211.448595 -130.654545)
			(xy 211.390752 -130.645614) (xy 211.334951 -130.627953) (xy 211.282502 -130.601976) (xy 211.234637 -130.568292)
			(xy 211.192478 -130.527693) (xy 211.157015 -130.481131) (xy 211.129081 -130.429698) (xy 211.118704 -130.40233)
			(xy 211.106766 -130.368802) (xy 203.972668 -130.368802) (xy 203.961238 -130.404108) (xy 203.952088 -130.430876)
			(xy 203.927005 -130.481578) (xy 203.894711 -130.528021) (xy 203.855914 -130.569187) (xy 203.811464 -130.604174)
			(xy 203.762336 -130.632215) (xy 203.709606 -130.652695) (xy 203.65443 -130.665166) (xy 203.598018 -130.669353)
			(xy 203.541606 -130.665166) (xy 203.48643 -130.652695) (xy 203.4337 -130.632215) (xy 203.384572 -130.604174)
			(xy 203.340122 -130.569187) (xy 203.301325 -130.528021) (xy 203.269031 -130.481578) (xy 203.243948 -130.430876)
			(xy 203.234798 -130.404108) (xy 203.223368 -130.368802) (xy 202.873864 -130.368802) (xy 202.859053 -130.393001)
			(xy 202.823401 -130.437134) (xy 202.781609 -130.475505) (xy 202.734599 -130.507267) (xy 202.683406 -130.531722)
			(xy 202.629157 -130.548331) (xy 202.573047 -130.556728) (xy 202.516313 -130.556728) (xy 202.460203 -130.548331)
			(xy 202.405954 -130.531722) (xy 202.354761 -130.507267) (xy 202.307751 -130.475505) (xy 202.265959 -130.437134)
			(xy 202.230307 -130.393001) (xy 202.215496 -130.368802) (xy 201.962258 -130.368802) (xy 201.949812 -130.401568)
			(xy 201.939789 -130.426825) (xy 201.913617 -130.474445) (xy 201.880951 -130.517867) (xy 201.842451 -130.556213)
			(xy 201.798898 -130.588705) (xy 201.751174 -130.614686) (xy 201.700245 -130.633628) (xy 201.647142 -130.64515)
			(xy 201.592942 -130.649016) (xy 201.538742 -130.64515) (xy 201.485639 -130.633628) (xy 201.43471 -130.614686)
			(xy 201.386986 -130.588705) (xy 201.343433 -130.556213) (xy 201.304933 -130.517867) (xy 201.272267 -130.474445)
			(xy 201.246095 -130.426825) (xy 201.236072 -130.401568) (xy 201.223626 -130.368802) (xy 199.145398 -130.368802)
			(xy 199.135746 -130.37312) (xy 199.111637 -130.383096) (xy 199.061383 -130.397122) (xy 199.009688 -130.404187)
			(xy 198.9836 -130.404616) (xy 198.957509 -130.404237) (xy 198.905808 -130.397177) (xy 198.855556 -130.383121)
			(xy 198.831454 -130.37312) (xy 198.821802 -130.368802) (xy 155.752038 -130.368802) (xy 155.738713 -130.392948)
			(xy 155.706171 -130.437473) (xy 155.667555 -130.476845) (xy 155.623669 -130.510244) (xy 155.575429 -130.536972)
			(xy 155.523843 -130.556472) (xy 155.469985 -130.568337) (xy 155.41498 -130.57232) (xy 155.359975 -130.568337)
			(xy 155.306117 -130.556472) (xy 155.254531 -130.536972) (xy 155.206291 -130.510244) (xy 155.162405 -130.476845)
			(xy 155.123789 -130.437473) (xy 155.091247 -130.392948) (xy 155.077922 -130.368802) (xy 151.123904 -130.368802)
			(xy 151.112982 -130.374644) (xy 151.085643 -130.388193) (xy 151.02771 -130.407331) (xy 150.967467 -130.416996)
			(xy 150.93696 -130.41757) (xy 150.906456 -130.416967) (xy 150.84622 -130.407292) (xy 150.788289 -130.388162)
			(xy 150.760938 -130.374644) (xy 150.750016 -130.368802) (xy 109.843824 -130.368802) (xy 109.831559 -130.391474)
			(xy 109.801462 -130.43332) (xy 109.765607 -130.470352) (xy 109.724754 -130.501784) (xy 109.67977 -130.526951)
			(xy 109.631608 -130.545318) (xy 109.581289 -130.556496) (xy 109.52988 -130.560249) (xy 109.478471 -130.556496)
			(xy 109.428152 -130.545318) (xy 109.37999 -130.526951) (xy 109.335006 -130.501784) (xy 109.294153 -130.470352)
			(xy 109.258298 -130.43332) (xy 109.228201 -130.391474) (xy 109.215936 -130.368802) (xy 62.791848 -130.368802)
			(xy 62.786514 -130.413506) (xy 62.78277 -130.440979) (xy 62.768364 -130.494521) (xy 62.746357 -130.545412)
			(xy 62.717211 -130.59258) (xy 62.681542 -130.63503) (xy 62.640102 -130.671866) (xy 62.593764 -130.702313)
			(xy 62.543504 -130.725728) (xy 62.490384 -130.741618) (xy 62.435523 -130.749648) (xy 62.380077 -130.749648)
			(xy 62.325216 -130.741618) (xy 62.272096 -130.725728) (xy 62.221836 -130.702313) (xy 62.175498 -130.671866)
			(xy 62.134058 -130.63503) (xy 62.098389 -130.59258) (xy 62.069243 -130.545412) (xy 62.047236 -130.494521)
			(xy 62.03283 -130.440979) (xy 62.029086 -130.413506) (xy 62.023752 -130.368802) (xy 41.66743 -130.368802)
			(xy 41.652625 -130.392975) (xy 41.616992 -130.437058) (xy 41.575229 -130.475384) (xy 41.528254 -130.507109)
			(xy 41.477104 -130.531535) (xy 41.422902 -130.548124) (xy 41.366842 -130.55651) (xy 41.310158 -130.55651)
			(xy 41.254098 -130.548124) (xy 41.199896 -130.531535) (xy 41.148746 -130.507109) (xy 41.101771 -130.475384)
			(xy 41.060008 -130.437058) (xy 41.024375 -130.392975) (xy 41.00957 -130.368802) (xy 40.547798 -130.368802)
			(xy 39.81958 -131.09702) (xy 228.682804 -131.09702) (xy 228.682804 -130.23342) (xy 228.68329 -130.206151)
			(xy 228.691052 -130.152167) (xy 228.706417 -130.099837) (xy 228.729074 -130.050227) (xy 228.75856 -130.004346)
			(xy 228.794275 -129.963129) (xy 228.835492 -129.927414) (xy 228.881373 -129.897928) (xy 228.930983 -129.875271)
			(xy 228.983313 -129.859906) (xy 229.037297 -129.852144) (xy 229.091835 -129.852144) (xy 229.145819 -129.859906)
			(xy 229.198149 -129.875271) (xy 229.247759 -129.897928) (xy 229.29364 -129.927414) (xy 229.334857 -129.963129)
			(xy 229.370572 -130.004346) (xy 229.400058 -130.050227) (xy 229.422715 -130.099837) (xy 229.43808 -130.152167)
			(xy 229.445842 -130.206151) (xy 229.446328 -130.23342) (xy 229.446328 -130.721608) (xy 242.041172 -130.721608)
			(xy 242.041172 -129.858008) (xy 242.041658 -129.830757) (xy 242.049414 -129.776809) (xy 242.064769 -129.724514)
			(xy 242.087411 -129.674937) (xy 242.116877 -129.629087) (xy 242.152568 -129.587896) (xy 242.193759 -129.552205)
			(xy 242.239609 -129.522739) (xy 242.289186 -129.500097) (xy 242.341481 -129.484742) (xy 242.395429 -129.476986)
			(xy 242.449931 -129.476986) (xy 242.503879 -129.484742) (xy 242.556174 -129.500097) (xy 242.605751 -129.522739)
			(xy 242.651601 -129.552205) (xy 242.692792 -129.587896) (xy 242.728483 -129.629087) (xy 242.757949 -129.674937)
			(xy 242.780591 -129.724514) (xy 242.795946 -129.776809) (xy 242.803702 -129.830757) (xy 242.804188 -129.858008)
			(xy 242.804188 -130.721608) (xy 242.803702 -130.748859) (xy 242.795946 -130.802807) (xy 242.780591 -130.855102)
			(xy 242.757949 -130.904679) (xy 242.728483 -130.950529) (xy 242.692792 -130.99172) (xy 242.651601 -131.027411)
			(xy 242.605751 -131.056877) (xy 242.556174 -131.079519) (xy 242.503879 -131.094874) (xy 242.449931 -131.10263)
			(xy 242.395429 -131.10263) (xy 242.341481 -131.094874) (xy 242.289186 -131.079519) (xy 242.239609 -131.056877)
			(xy 242.193759 -131.027411) (xy 242.152568 -130.99172) (xy 242.116877 -130.950529) (xy 242.087411 -130.904679)
			(xy 242.064769 -130.855102) (xy 242.049414 -130.802807) (xy 242.041658 -130.748859) (xy 242.041172 -130.721608)
			(xy 229.446328 -130.721608) (xy 229.446328 -131.09702) (xy 229.445842 -131.124289) (xy 229.43808 -131.178273)
			(xy 229.422715 -131.230603) (xy 229.400058 -131.280213) (xy 229.370572 -131.326094) (xy 229.334857 -131.367311)
			(xy 229.29364 -131.403026) (xy 229.247759 -131.432512) (xy 229.198149 -131.455169) (xy 229.145819 -131.470534)
			(xy 229.091835 -131.478296) (xy 229.037297 -131.478296) (xy 228.983313 -131.470534) (xy 228.930983 -131.455169)
			(xy 228.881373 -131.432512) (xy 228.835492 -131.403026) (xy 228.794275 -131.367311) (xy 228.75856 -131.326094)
			(xy 228.729074 -131.280213) (xy 228.706417 -131.230603) (xy 228.691052 -131.178273) (xy 228.68329 -131.124289)
			(xy 228.682804 -131.09702) (xy 39.81958 -131.09702) (xy 39.027354 -131.889246) (xy 39.00929 -131.906478)
			(xy 38.967796 -131.934221) (xy 38.921686 -131.953337) (xy 38.872733 -131.963089) (xy 38.847776 -131.963668)
			(xy 30.14218 -131.963668) (xy 30.117221 -131.963072) (xy 30.068259 -131.953351) (xy 30.02214 -131.934248)
			(xy 29.980645 -131.906501) (xy 29.962602 -131.889246) (xy 25.027382 -126.954026) (xy 25.010142 -126.93597)
			(xy 24.982398 -126.894473) (xy 24.963285 -126.848361) (xy 24.953536 -126.799406) (xy 24.95296 -126.774448)
			(xy 3.523996 -126.774448) (xy 3.523996 -132.529347) (xy 231.621126 -132.529347) (xy 231.621126 -132.474853)
			(xy 231.628881 -132.420915) (xy 231.644233 -132.368628) (xy 231.666869 -132.319059) (xy 231.69633 -132.273216)
			(xy 231.732014 -132.232031) (xy 231.773196 -132.196344) (xy 231.819038 -132.166881) (xy 231.868606 -132.144241)
			(xy 231.920891 -132.128886) (xy 231.974829 -132.121128) (xy 232.002076 -132.12064) (xy 232.865676 -132.12064)
			(xy 232.892933 -132.121005) (xy 232.946894 -132.128761) (xy 232.999201 -132.144116) (xy 233.048791 -132.16676)
			(xy 233.094653 -132.196231) (xy 233.135853 -132.23193) (xy 233.171554 -132.273128) (xy 233.201028 -132.318988)
			(xy 233.223675 -132.368576) (xy 233.239034 -132.420883) (xy 233.246793 -132.474843) (xy 233.246793 -132.529357)
			(xy 233.239034 -132.583317) (xy 233.223675 -132.635624) (xy 233.201028 -132.685212) (xy 233.171554 -132.731072)
			(xy 233.135853 -132.77227) (xy 233.094653 -132.807968) (xy 233.048791 -132.83744) (xy 232.999201 -132.860084)
			(xy 232.946894 -132.875439) (xy 232.892933 -132.883195) (xy 232.865676 -132.883656) (xy 232.002076 -132.883656)
			(xy 231.974829 -132.883072) (xy 231.920891 -132.875314) (xy 231.868606 -132.859959) (xy 231.819038 -132.837319)
			(xy 231.773196 -132.807856) (xy 231.732014 -132.772169) (xy 231.69633 -132.730984) (xy 231.666869 -132.685141)
			(xy 231.644233 -132.635572) (xy 231.628881 -132.583285) (xy 231.621126 -132.529347) (xy 3.523996 -132.529347)
			(xy 3.523996 -135.31065) (xy 225.204003 -135.31065) (xy 225.204003 -135.25615) (xy 225.21176 -135.202204)
			(xy 225.227115 -135.149911) (xy 225.249756 -135.100336) (xy 225.279222 -135.054487) (xy 225.314914 -135.013299)
			(xy 225.356103 -134.97761) (xy 225.401953 -134.948146) (xy 225.45153 -134.925508) (xy 225.503823 -134.910156)
			(xy 225.55777 -134.902402) (xy 225.58502 -134.90194) (xy 226.44862 -134.90194) (xy 226.475874 -134.902331)
			(xy 226.529826 -134.910091) (xy 226.582125 -134.92545) (xy 226.631706 -134.948095) (xy 226.67756 -134.977566)
			(xy 226.718753 -135.013262) (xy 226.754446 -135.054456) (xy 226.755856 -135.05665) (xy 228.531403 -135.05665)
			(xy 228.531403 -135.00215) (xy 228.53916 -134.948204) (xy 228.554515 -134.895911) (xy 228.577156 -134.846336)
			(xy 228.606622 -134.800487) (xy 228.642314 -134.759299) (xy 228.683503 -134.72361) (xy 228.729353 -134.694146)
			(xy 228.77893 -134.671508) (xy 228.831223 -134.656156) (xy 228.88517 -134.648402) (xy 228.91242 -134.64794)
			(xy 229.77602 -134.64794) (xy 229.803274 -134.648331) (xy 229.857226 -134.656091) (xy 229.909525 -134.67145)
			(xy 229.959106 -134.694095) (xy 230.00496 -134.723566) (xy 230.046153 -134.759262) (xy 230.081846 -134.800456)
			(xy 230.111315 -134.846312) (xy 230.133957 -134.895894) (xy 230.149313 -134.948193) (xy 230.15707 -135.002146)
			(xy 230.15707 -135.056654) (xy 230.149313 -135.110607) (xy 230.145996 -135.121904) (xy 234.029504 -135.121904)
			(xy 234.029504 -134.258304) (xy 234.02999 -134.231035) (xy 234.037752 -134.177051) (xy 234.053117 -134.124721)
			(xy 234.075774 -134.075111) (xy 234.10526 -134.02923) (xy 234.140975 -133.988013) (xy 234.182192 -133.952298)
			(xy 234.228073 -133.922812) (xy 234.277683 -133.900155) (xy 234.330013 -133.88479) (xy 234.383997 -133.877028)
			(xy 234.438535 -133.877028) (xy 234.492519 -133.88479) (xy 234.544849 -133.900155) (xy 234.594459 -133.922812)
			(xy 234.64034 -133.952298) (xy 234.681557 -133.988013) (xy 234.717272 -134.02923) (xy 234.746758 -134.075111)
			(xy 234.769415 -134.124721) (xy 234.78478 -134.177051) (xy 234.792542 -134.231035) (xy 234.793028 -134.258304)
			(xy 234.793028 -134.768971) (xy 236.02439 -134.768971) (xy 236.02439 -134.714429) (xy 236.032152 -134.660443)
			(xy 236.047518 -134.608111) (xy 236.070174 -134.558498) (xy 236.09966 -134.512615) (xy 236.135376 -134.471394)
			(xy 236.176594 -134.435676) (xy 236.222475 -134.406186) (xy 236.272087 -134.383527) (xy 236.324418 -134.368158)
			(xy 236.378403 -134.360392) (xy 236.405674 -134.359904) (xy 237.178342 -134.359904) (xy 237.205607 -134.360461)
			(xy 237.259581 -134.368227) (xy 237.311901 -134.383595) (xy 237.361502 -134.406251) (xy 237.407373 -134.435736)
			(xy 237.448582 -134.471448) (xy 237.48429 -134.512661) (xy 237.513769 -134.558535) (xy 237.53642 -134.608138)
			(xy 237.551782 -134.66046) (xy 237.559542 -134.714435) (xy 237.559542 -134.768965) (xy 237.551782 -134.82294)
			(xy 237.53642 -134.875262) (xy 237.513769 -134.924865) (xy 237.48429 -134.970739) (xy 237.448582 -135.011952)
			(xy 237.407373 -135.047664) (xy 237.361502 -135.077149) (xy 237.311901 -135.099805) (xy 237.259581 -135.115173)
			(xy 237.205607 -135.122939) (xy 237.178342 -135.123428) (xy 236.405674 -135.123428) (xy 236.378403 -135.123008)
			(xy 236.324418 -135.115242) (xy 236.272087 -135.099873) (xy 236.222475 -135.077214) (xy 236.176594 -135.047724)
			(xy 236.135376 -135.012006) (xy 236.09966 -134.970785) (xy 236.070174 -134.924902) (xy 236.047518 -134.875289)
			(xy 236.032152 -134.822957) (xy 236.02439 -134.768971) (xy 234.793028 -134.768971) (xy 234.793028 -135.121904)
			(xy 234.792542 -135.149173) (xy 234.786383 -135.192008) (xy 238.645192 -135.192008) (xy 238.645192 -134.328408)
			(xy 238.645678 -134.301157) (xy 238.653434 -134.247209) (xy 238.668789 -134.194914) (xy 238.691431 -134.145337)
			(xy 238.720897 -134.099487) (xy 238.756588 -134.058296) (xy 238.797779 -134.022605) (xy 238.843629 -133.993139)
			(xy 238.893206 -133.970497) (xy 238.945501 -133.955142) (xy 238.999449 -133.947386) (xy 239.053951 -133.947386)
			(xy 239.107899 -133.955142) (xy 239.160194 -133.970497) (xy 239.209771 -133.993139) (xy 239.255621 -134.022605)
			(xy 239.271831 -134.036651) (xy 242.034062 -134.036651) (xy 242.034062 -133.982149) (xy 242.041817 -133.928203)
			(xy 242.057171 -133.875909) (xy 242.07981 -133.826333) (xy 242.109274 -133.780482) (xy 242.144963 -133.739291)
			(xy 242.18615 -133.703598) (xy 242.231997 -133.67413) (xy 242.281572 -133.651485) (xy 242.333864 -133.636126)
			(xy 242.387809 -133.628365) (xy 242.41506 -133.627876) (xy 243.27866 -133.627876) (xy 243.305914 -133.628369)
			(xy 243.359867 -133.636121) (xy 243.412167 -133.651473) (xy 243.46175 -133.674112) (xy 243.507606 -133.703577)
			(xy 243.548802 -133.73927) (xy 243.584499 -133.780462) (xy 243.613969 -133.826315) (xy 243.636613 -133.875895)
			(xy 243.651971 -133.928194) (xy 243.659729 -133.982146) (xy 243.659729 -134.036654) (xy 243.651971 -134.090606)
			(xy 243.636613 -134.142905) (xy 243.613969 -134.192485) (xy 243.584499 -134.238338) (xy 243.548802 -134.27953)
			(xy 243.507606 -134.315223) (xy 243.46175 -134.344688) (xy 243.412167 -134.367327) (xy 243.359867 -134.382679)
			(xy 243.305914 -134.390431) (xy 243.27866 -134.390892) (xy 242.41506 -134.390892) (xy 242.387809 -134.390435)
			(xy 242.333864 -134.382674) (xy 242.281572 -134.367315) (xy 242.231997 -134.34467) (xy 242.18615 -134.315202)
			(xy 242.144963 -134.279509) (xy 242.109274 -134.238318) (xy 242.07981 -134.192467) (xy 242.057171 -134.142891)
			(xy 242.041817 -134.090597) (xy 242.034062 -134.036651) (xy 239.271831 -134.036651) (xy 239.296812 -134.058296)
			(xy 239.332503 -134.099487) (xy 239.361969 -134.145337) (xy 239.384611 -134.194914) (xy 239.399966 -134.247209)
			(xy 239.407722 -134.301157) (xy 239.408208 -134.328408) (xy 239.408208 -135.192008) (xy 239.407722 -135.219259)
			(xy 239.399966 -135.273207) (xy 239.384611 -135.325502) (xy 239.361969 -135.375079) (xy 239.332503 -135.420929)
			(xy 239.296812 -135.46212) (xy 239.255621 -135.497811) (xy 239.250425 -135.50115) (xy 244.457203 -135.50115)
			(xy 244.457203 -135.44665) (xy 244.46496 -135.392704) (xy 244.480315 -135.340411) (xy 244.502956 -135.290836)
			(xy 244.532422 -135.244987) (xy 244.568114 -135.203799) (xy 244.609303 -135.16811) (xy 244.655153 -135.138646)
			(xy 244.70473 -135.116008) (xy 244.757023 -135.100656) (xy 244.81097 -135.092902) (xy 244.83822 -135.09244)
			(xy 245.70182 -135.09244) (xy 245.729074 -135.092831) (xy 245.783026 -135.100591) (xy 245.835325 -135.11595)
			(xy 245.884906 -135.138595) (xy 245.93076 -135.168066) (xy 245.971953 -135.203762) (xy 246.007646 -135.244956)
			(xy 246.037115 -135.290812) (xy 246.059757 -135.340394) (xy 246.075113 -135.392693) (xy 246.08287 -135.446646)
			(xy 246.08287 -135.501154) (xy 246.075113 -135.555107) (xy 246.059757 -135.607406) (xy 246.037115 -135.656988)
			(xy 246.007646 -135.702844) (xy 245.971953 -135.744038) (xy 245.93076 -135.779734) (xy 245.884906 -135.809205)
			(xy 245.835325 -135.83185) (xy 245.783026 -135.847209) (xy 245.729074 -135.854969) (xy 245.70182 -135.855456)
			(xy 244.83822 -135.855456) (xy 244.81097 -135.854898) (xy 244.757023 -135.847144) (xy 244.70473 -135.831792)
			(xy 244.655153 -135.809154) (xy 244.609303 -135.77969) (xy 244.568114 -135.744001) (xy 244.532422 -135.702813)
			(xy 244.502956 -135.656964) (xy 244.480315 -135.607389) (xy 244.46496 -135.555096) (xy 244.457203 -135.50115)
			(xy 239.250425 -135.50115) (xy 239.209771 -135.527277) (xy 239.160194 -135.549919) (xy 239.107899 -135.565274)
			(xy 239.053951 -135.57303) (xy 238.999449 -135.57303) (xy 238.945501 -135.565274) (xy 238.893206 -135.549919)
			(xy 238.843629 -135.527277) (xy 238.797779 -135.497811) (xy 238.756588 -135.46212) (xy 238.720897 -135.420929)
			(xy 238.691431 -135.375079) (xy 238.668789 -135.325502) (xy 238.653434 -135.273207) (xy 238.645678 -135.219259)
			(xy 238.645192 -135.192008) (xy 234.786383 -135.192008) (xy 234.78478 -135.203157) (xy 234.769415 -135.255487)
			(xy 234.746758 -135.305097) (xy 234.717272 -135.350978) (xy 234.681557 -135.392195) (xy 234.64034 -135.42791)
			(xy 234.594459 -135.457396) (xy 234.544849 -135.480053) (xy 234.492519 -135.495418) (xy 234.438535 -135.50318)
			(xy 234.383997 -135.50318) (xy 234.330013 -135.495418) (xy 234.277683 -135.480053) (xy 234.228073 -135.457396)
			(xy 234.182192 -135.42791) (xy 234.140975 -135.392195) (xy 234.10526 -135.350978) (xy 234.075774 -135.305097)
			(xy 234.053117 -135.255487) (xy 234.037752 -135.203157) (xy 234.02999 -135.149173) (xy 234.029504 -135.121904)
			(xy 230.145996 -135.121904) (xy 230.133957 -135.162906) (xy 230.111315 -135.212488) (xy 230.081846 -135.258344)
			(xy 230.046153 -135.299538) (xy 230.00496 -135.335234) (xy 229.959106 -135.364705) (xy 229.909525 -135.38735)
			(xy 229.857226 -135.402709) (xy 229.803274 -135.410469) (xy 229.77602 -135.410956) (xy 228.91242 -135.410956)
			(xy 228.88517 -135.410398) (xy 228.831223 -135.402644) (xy 228.77893 -135.387292) (xy 228.729353 -135.364654)
			(xy 228.683503 -135.33519) (xy 228.642314 -135.299501) (xy 228.606622 -135.258313) (xy 228.577156 -135.212464)
			(xy 228.554515 -135.162889) (xy 228.53916 -135.110596) (xy 228.531403 -135.05665) (xy 226.755856 -135.05665)
			(xy 226.783915 -135.100312) (xy 226.806557 -135.149894) (xy 226.821913 -135.202193) (xy 226.82967 -135.256146)
			(xy 226.82967 -135.310654) (xy 226.821913 -135.364607) (xy 226.806557 -135.416906) (xy 226.783915 -135.466488)
			(xy 226.754446 -135.512344) (xy 226.718753 -135.553538) (xy 226.67756 -135.589234) (xy 226.631706 -135.618705)
			(xy 226.582125 -135.64135) (xy 226.529826 -135.656709) (xy 226.475874 -135.664469) (xy 226.44862 -135.664956)
			(xy 225.58502 -135.664956) (xy 225.55777 -135.664398) (xy 225.503823 -135.656644) (xy 225.45153 -135.641292)
			(xy 225.401953 -135.618654) (xy 225.356103 -135.58919) (xy 225.314914 -135.553501) (xy 225.279222 -135.512313)
			(xy 225.249756 -135.466464) (xy 225.227115 -135.416889) (xy 225.21176 -135.364596) (xy 225.204003 -135.31065)
			(xy 3.523996 -135.31065) (xy 3.523996 -137.199664) (xy 337.46447 -137.199664) (xy 337.46447 -137.145136)
			(xy 337.47223 -137.091163) (xy 337.487591 -137.038843) (xy 337.510241 -136.989242) (xy 337.539719 -136.943369)
			(xy 337.575425 -136.902158) (xy 337.616632 -136.866447) (xy 337.662502 -136.836963) (xy 337.7121 -136.814307)
			(xy 337.764418 -136.79894) (xy 337.81839 -136.791173) (xy 337.845654 -136.790684) (xy 338.618322 -136.790684)
			(xy 338.645594 -136.79108) (xy 338.699581 -136.798845) (xy 338.751915 -136.814214) (xy 338.801528 -136.836874)
			(xy 338.847412 -136.866364) (xy 338.888632 -136.902084) (xy 338.924349 -136.943306) (xy 338.953836 -136.989191)
			(xy 338.976493 -137.038806) (xy 338.991859 -137.09114) (xy 338.999622 -137.145128) (xy 338.999622 -137.199672)
			(xy 338.991859 -137.25366) (xy 338.976493 -137.305994) (xy 338.953836 -137.355609) (xy 338.924349 -137.401494)
			(xy 338.888632 -137.442716) (xy 338.847412 -137.478436) (xy 338.801528 -137.507926) (xy 338.751915 -137.530586)
			(xy 338.699581 -137.545955) (xy 338.645594 -137.55372) (xy 338.618322 -137.554208) (xy 337.845654 -137.554208)
			(xy 337.81839 -137.553627) (xy 337.764418 -137.54586) (xy 337.7121 -137.530493) (xy 337.662502 -137.507837)
			(xy 337.616632 -137.478353) (xy 337.575425 -137.442642) (xy 337.539719 -137.401431) (xy 337.510241 -137.355558)
			(xy 337.487591 -137.305957) (xy 337.47223 -137.253637) (xy 337.46447 -137.199664) (xy 3.523996 -137.199664)
			(xy 3.523996 -137.622788) (xy 340.085172 -137.622788) (xy 340.085172 -136.759188) (xy 340.085658 -136.731937)
			(xy 340.093414 -136.677989) (xy 340.108769 -136.625694) (xy 340.131411 -136.576117) (xy 340.160877 -136.530267)
			(xy 340.196568 -136.489076) (xy 340.237759 -136.453385) (xy 340.283609 -136.423919) (xy 340.333186 -136.401277)
			(xy 340.385481 -136.385922) (xy 340.439429 -136.378166) (xy 340.493931 -136.378166) (xy 340.547879 -136.385922)
			(xy 340.600174 -136.401277) (xy 340.649751 -136.423919) (xy 340.695601 -136.453385) (xy 340.736792 -136.489076)
			(xy 340.772483 -136.530267) (xy 340.801949 -136.576117) (xy 340.824591 -136.625694) (xy 340.839946 -136.677989)
			(xy 340.847702 -136.731937) (xy 340.848188 -136.759188) (xy 340.848188 -137.622788) (xy 340.847702 -137.650039)
			(xy 340.839946 -137.703987) (xy 340.824591 -137.756282) (xy 340.801949 -137.805859) (xy 340.772483 -137.851709)
			(xy 340.736792 -137.8929) (xy 340.695601 -137.928591) (xy 340.649751 -137.958057) (xy 340.600174 -137.980699)
			(xy 340.547879 -137.996054) (xy 340.493931 -138.00381) (xy 340.439429 -138.00381) (xy 340.385481 -137.996054)
			(xy 340.333186 -137.980699) (xy 340.283609 -137.958057) (xy 340.237759 -137.928591) (xy 340.196568 -137.8929)
			(xy 340.160877 -137.851709) (xy 340.131411 -137.805859) (xy 340.108769 -137.756282) (xy 340.093414 -137.703987)
			(xy 340.085658 -137.650039) (xy 340.085172 -137.622788) (xy 3.523996 -137.622788) (xy 3.523996 -160.465845)
			(xy 5.068429 -160.465845) (xy 5.073758 -160.260626) (xy 5.087074 -160.05577) (xy 5.108356 -159.851588)
			(xy 5.137571 -159.64839) (xy 5.174676 -159.446483) (xy 5.219614 -159.246174) (xy 5.272318 -159.047766)
			(xy 5.332706 -158.851561) (xy 5.400688 -158.657856) (xy 5.47616 -158.466945) (xy 5.559009 -158.279117)
			(xy 5.649107 -158.094658) (xy 5.74632 -157.913846) (xy 5.850499 -157.736956) (xy 5.961486 -157.564257)
			(xy 6.079113 -157.39601) (xy 6.203201 -157.232471) (xy 6.333563 -157.073886) (xy 6.470001 -156.920498)
			(xy 6.612307 -156.772539) (xy 6.760267 -156.630232) (xy 6.913655 -156.493795) (xy 7.072239 -156.363432)
			(xy 7.235778 -156.239344) (xy 7.404025 -156.121717) (xy 7.576725 -156.01073) (xy 7.753614 -155.906551)
			(xy 7.934426 -155.809338) (xy 8.118886 -155.719239) (xy 8.306713 -155.636391) (xy 8.497625 -155.560919)
			(xy 8.69133 -155.492937) (xy 8.887535 -155.432548) (xy 9.085942 -155.379845) (xy 9.286251 -155.334907)
			(xy 9.488158 -155.297802) (xy 9.691356 -155.268586) (xy 9.895538 -155.247304) (xy 10.100394 -155.233988)
			(xy 10.305613 -155.228659) (xy 10.510883 -155.231324) (xy 10.715895 -155.241979) (xy 10.920336 -155.260609)
			(xy 11.123896 -155.287184) (xy 11.326268 -155.321665) (xy 11.527143 -155.363999) (xy 11.726218 -155.414122)
			(xy 11.923191 -155.471958) (xy 12.117762 -155.53742) (xy 12.309637 -155.610408) (xy 12.498524 -155.690811)
			(xy 12.684138 -155.778507) (xy 12.866196 -155.873364) (xy 13.044424 -155.975238) (xy 13.218549 -156.083974)
			(xy 13.388309 -156.199407) (xy 13.553445 -156.321362) (xy 13.713708 -156.449655) (xy 13.868855 -156.58409)
			(xy 14.018649 -156.724463) (xy 14.162864 -156.870563) (xy 14.301282 -157.022167) (xy 14.433691 -157.179045)
			(xy 14.559893 -157.34096) (xy 14.679694 -157.507666) (xy 14.792913 -157.67891) (xy 14.89938 -157.854432)
			(xy 14.998931 -158.033967) (xy 15.091417 -158.217242) (xy 15.176697 -158.403978) (xy 15.254641 -158.593893)
			(xy 15.325132 -158.7867) (xy 15.388062 -158.982104) (xy 15.443337 -159.179811) (xy 15.490871 -159.379519)
			(xy 15.530594 -159.580928) (xy 15.562445 -159.78373) (xy 15.586376 -159.987618) (xy 15.60235 -160.192284)
			(xy 15.610343 -160.397416) (xy 15.61084 -160.50006) (xy 15.610795 -160.537466) (xy 15.60978 -160.612272)
			(xy 15.608808 -160.649666) (xy 15.608941 -160.664851) (xy 15.617041 -160.694101) (xy 15.633374 -160.719682)
			(xy 15.656499 -160.739339) (xy 15.684376 -160.751339) (xy 15.714549 -160.754624) (xy 15.744355 -160.748903)
			(xy 15.771168 -160.734681) (xy 15.78229 -160.724342) (xy 17.600422 -158.90621) (xy 17.618472 -158.888966)
			(xy 17.659975 -158.861237) (xy 17.706089 -158.842137) (xy 17.755043 -158.832399) (xy 17.78 -158.831788)
			(xy 27.341322 -158.831788) (xy 27.356351 -158.831252) (xy 27.385106 -158.822499) (xy 27.410069 -158.805757)
			(xy 27.42908 -158.782475) (xy 27.440494 -158.754669) (xy 27.443321 -158.724744) (xy 27.437318 -158.695292)
			(xy 27.423005 -158.668862) (xy 27.401619 -158.64774) (xy 27.388566 -158.640272) (xy 27.297508 -158.591788)
			(xy 27.118677 -158.48889) (xy 26.943824 -158.379368) (xy 26.773195 -158.263376) (xy 26.607029 -158.141076)
			(xy 26.445559 -158.012641) (xy 26.289011 -157.878249) (xy 26.137605 -157.738089) (xy 25.991553 -157.592359)
			(xy 25.85106 -157.441262) (xy 25.716324 -157.285011) (xy 25.587532 -157.123824) (xy 25.464867 -156.957927)
			(xy 25.348499 -156.787554) (xy 25.238592 -156.612944) (xy 25.1353 -156.43434) (xy 25.038769 -156.251994)
			(xy 24.949133 -156.066161) (xy 24.866518 -155.877102) (xy 24.79104 -155.685083) (xy 24.722804 -155.490372)
			(xy 24.661908 -155.293242) (xy 24.608435 -155.093971) (xy 24.562462 -154.892837) (xy 24.524051 -154.690123)
			(xy 24.493259 -154.486112) (xy 24.470126 -154.281092) (xy 24.454687 -154.075349) (xy 24.446962 -153.869173)
			(xy 24.446484 -153.766012) (xy 24.446989 -153.660488) (xy 24.455073 -153.449594) (xy 24.471229 -153.239165)
			(xy 24.495432 -153.029508) (xy 24.527649 -152.820933) (xy 24.567831 -152.613745) (xy 24.615919 -152.408248)
			(xy 24.671843 -152.204744) (xy 24.73552 -152.003531) (xy 24.806858 -151.804904) (xy 24.885752 -151.609156)
			(xy 24.972085 -151.416574) (xy 25.065732 -151.227439) (xy 25.166554 -151.04203) (xy 25.274404 -150.860619)
			(xy 25.389123 -150.683472) (xy 25.510543 -150.51085) (xy 25.638486 -150.343004) (xy 25.772764 -150.180182)
			(xy 25.91318 -150.022623) (xy 26.059528 -149.870558) (xy 26.211593 -149.72421) (xy 26.369152 -149.583794)
			(xy 26.531974 -149.449516) (xy 26.69982 -149.321573) (xy 26.872442 -149.200153) (xy 27.049589 -149.085434)
			(xy 27.231 -148.977584) (xy 27.416409 -148.876762) (xy 27.605544 -148.783115) (xy 27.798126 -148.696782)
			(xy 27.993874 -148.617888) (xy 28.192501 -148.54655) (xy 28.393714 -148.482873) (xy 28.597218 -148.426949)
			(xy 28.802715 -148.378861) (xy 29.009903 -148.338679) (xy 29.218478 -148.306462) (xy 29.428135 -148.282259)
			(xy 29.638564 -148.266103) (xy 29.849458 -148.258019) (xy 30.060506 -148.258019) (xy 30.2714 -148.266103)
			(xy 30.481829 -148.282259) (xy 30.691486 -148.306462) (xy 30.900061 -148.338679) (xy 31.107249 -148.378861)
			(xy 31.312746 -148.426949) (xy 31.51625 -148.482873) (xy 31.717463 -148.54655) (xy 31.91609 -148.617888)
			(xy 32.111838 -148.696782) (xy 32.30442 -148.783115) (xy 32.493555 -148.876762) (xy 32.678964 -148.977584)
			(xy 32.860375 -149.085434) (xy 33.037522 -149.200153) (xy 33.210144 -149.321573) (xy 33.37799 -149.449516)
			(xy 33.540812 -149.583794) (xy 33.698371 -149.72421) (xy 33.850436 -149.870558) (xy 33.996784 -150.022623)
			(xy 34.1372 -150.180182) (xy 34.271478 -150.343004) (xy 34.399421 -150.51085) (xy 34.520841 -150.683472)
			(xy 34.63556 -150.860619) (xy 34.74341 -151.04203) (xy 34.844232 -151.227439) (xy 34.937879 -151.416574)
			(xy 35.024212 -151.609156) (xy 35.103106 -151.804904) (xy 35.174444 -152.003531) (xy 35.238121 -152.204744)
			(xy 35.294045 -152.408248) (xy 35.342133 -152.613745) (xy 35.382315 -152.820933) (xy 35.414532 -153.029508)
			(xy 35.438735 -153.239165) (xy 35.454891 -153.449594) (xy 35.462975 -153.660488) (xy 35.46348 -153.766012)
			(xy 35.462984 -153.869172) (xy 35.455258 -154.075348) (xy 35.439818 -154.28109) (xy 35.416685 -154.48611)
			(xy 35.385892 -154.690119) (xy 35.347481 -154.892833) (xy 35.301507 -155.093966) (xy 35.248034 -155.293237)
			(xy 35.187137 -155.490365) (xy 35.118902 -155.685076) (xy 35.043424 -155.877095) (xy 34.96081 -156.066153)
			(xy 34.871174 -156.251985) (xy 34.774643 -156.43433) (xy 34.671352 -156.612934) (xy 34.561446 -156.787544)
			(xy 34.445079 -156.957917) (xy 34.322414 -157.123813) (xy 34.193624 -157.285) (xy 34.058889 -157.441251)
			(xy 33.918397 -157.592348) (xy 33.772347 -157.738079) (xy 33.620942 -157.878239) (xy 33.464395 -158.012631)
			(xy 33.302926 -158.141068) (xy 33.136762 -158.263368) (xy 32.966134 -158.379361) (xy 32.791283 -158.488884)
			(xy 32.612454 -158.591783) (xy 32.521398 -158.640272) (xy 32.508325 -158.647715) (xy 32.486922 -158.668835)
			(xy 32.472595 -158.695272) (xy 32.466585 -158.724735) (xy 32.469413 -158.754671) (xy 32.480833 -158.782487)
			(xy 32.499857 -158.805774) (xy 32.524836 -158.822513) (xy 32.553607 -158.831255) (xy 32.568642 -158.831788)
			(xy 47.834296 -158.831788) (xy 48.884078 -157.782006) (xy 48.884078 -139.22883) (xy 48.88463 -139.203868)
			(xy 48.894363 -139.154903) (xy 48.913478 -139.108785) (xy 48.941239 -139.067292) (xy 48.9585 -139.049252)
			(xy 49.74082 -138.266932) (xy 49.758849 -138.249662) (xy 49.800356 -138.221926) (xy 49.846476 -138.202821)
			(xy 49.895438 -138.193081) (xy 49.920398 -138.19251) (xy 98.095562 -138.19251) (xy 98.120522 -138.193086)
			(xy 98.169485 -138.202815) (xy 98.215603 -138.221923) (xy 98.257098 -138.249675) (xy 98.27514 -138.266932)
			(xy 114.247676 -154.239468) (xy 186.742832 -154.239468) (xy 186.742832 -153.375868) (xy 186.743318 -153.348617)
			(xy 186.751074 -153.294669) (xy 186.766429 -153.242374) (xy 186.789071 -153.192797) (xy 186.818537 -153.146947)
			(xy 186.854228 -153.105756) (xy 186.895419 -153.070065) (xy 186.941269 -153.040599) (xy 186.990846 -153.017957)
			(xy 187.043141 -153.002602) (xy 187.097089 -152.994846) (xy 187.151591 -152.994846) (xy 187.205539 -153.002602)
			(xy 187.257834 -153.017957) (xy 187.307411 -153.040599) (xy 187.353261 -153.070065) (xy 187.394452 -153.105756)
			(xy 187.430143 -153.146947) (xy 187.459609 -153.192797) (xy 187.482251 -153.242374) (xy 187.497606 -153.294669)
			(xy 187.505362 -153.348617) (xy 187.505848 -153.375868) (xy 187.505848 -153.774902) (xy 188.445657 -153.774902)
			(xy 188.44965 -153.565161) (xy 188.461626 -153.355724) (xy 188.481567 -153.146895) (xy 188.509444 -152.938976)
			(xy 188.545216 -152.732269) (xy 188.588831 -152.527074) (xy 188.640227 -152.323689) (xy 188.699329 -152.122407)
			(xy 188.766051 -151.923521) (xy 188.840296 -151.72732) (xy 188.921956 -151.534088) (xy 189.010914 -151.344104)
			(xy 189.107041 -151.157645) (xy 189.210196 -150.974981) (xy 189.320231 -150.796376) (xy 189.436985 -150.62209)
			(xy 189.56029 -150.452375) (xy 189.689967 -150.287477) (xy 189.825828 -150.127636) (xy 189.967675 -149.973083)
			(xy 190.115304 -149.824043) (xy 190.268499 -149.68073) (xy 190.42704 -149.543354) (xy 190.590695 -149.412113)
			(xy 190.759229 -149.287198) (xy 190.932395 -149.16879) (xy 191.109945 -149.05706) (xy 191.291619 -148.95217)
			(xy 191.477154 -148.854273) (xy 191.666282 -148.763511) (xy 191.858729 -148.680014) (xy 192.054214 -148.603904)
			(xy 192.252456 -148.535292) (xy 192.453166 -148.474277) (xy 192.656053 -148.420948) (xy 192.860823 -148.375381)
			(xy 193.06718 -148.337642) (xy 193.274824 -148.307788) (xy 193.483454 -148.28586) (xy 193.692767 -148.271891)
			(xy 193.902461 -148.2659) (xy 194.11223 -148.267897) (xy 194.321772 -148.277879) (xy 194.530782 -148.295831)
			(xy 194.738956 -148.321727) (xy 194.945994 -148.355529) (xy 195.151595 -148.397189) (xy 195.355461 -148.446647)
			(xy 195.557296 -148.50383) (xy 195.756808 -148.568655) (xy 195.953707 -148.641029) (xy 196.147708 -148.720846)
			(xy 196.33853 -148.807992) (xy 196.525896 -148.902339) (xy 196.709534 -149.00375) (xy 196.889178 -149.11208)
			(xy 197.064568 -149.22717) (xy 197.235449 -149.348854) (xy 197.401573 -149.476955) (xy 197.5627 -149.611288)
			(xy 197.718597 -149.751657) (xy 197.869036 -149.89786) (xy 198.0138 -150.049684) (xy 198.152679 -150.20691)
			(xy 198.285472 -150.369309) (xy 198.411986 -150.536645) (xy 198.532038 -150.708677) (xy 198.645453 -150.885154)
			(xy 198.752067 -151.065822) (xy 198.851726 -151.250417) (xy 198.944285 -151.438672) (xy 199.02961 -151.630315)
			(xy 199.107577 -151.825067) (xy 199.178073 -152.022647) (xy 199.240996 -152.222766) (xy 199.296255 -152.425137)
			(xy 199.343769 -152.629464) (xy 199.38347 -152.835452) (xy 199.4153 -153.042803) (xy 199.439213 -153.251214)
			(xy 199.455174 -153.460385) (xy 199.463161 -153.670012) (xy 199.463618 -153.766012) (xy 272.385799 -153.766012)
			(xy 272.389792 -153.556271) (xy 272.401768 -153.346834) (xy 272.421709 -153.138005) (xy 272.449586 -152.930086)
			(xy 272.485358 -152.723379) (xy 272.528973 -152.518184) (xy 272.580369 -152.314799) (xy 272.639471 -152.113517)
			(xy 272.706193 -151.914631) (xy 272.780438 -151.71843) (xy 272.862098 -151.525198) (xy 272.951056 -151.335214)
			(xy 273.047183 -151.148755) (xy 273.150338 -150.966091) (xy 273.260373 -150.787486) (xy 273.377127 -150.6132)
			(xy 273.500432 -150.443485) (xy 273.630109 -150.278587) (xy 273.76597 -150.118746) (xy 273.907817 -149.964193)
			(xy 274.055446 -149.815153) (xy 274.208641 -149.67184) (xy 274.367182 -149.534464) (xy 274.530837 -149.403223)
			(xy 274.699371 -149.278308) (xy 274.872537 -149.1599) (xy 275.050087 -149.04817) (xy 275.231761 -148.94328)
			(xy 275.417296 -148.845383) (xy 275.606424 -148.754621) (xy 275.798871 -148.671124) (xy 275.994356 -148.595014)
			(xy 276.192598 -148.526402) (xy 276.393308 -148.465387) (xy 276.596195 -148.412058) (xy 276.800965 -148.366491)
			(xy 277.007322 -148.328752) (xy 277.214966 -148.298898) (xy 277.423596 -148.27697) (xy 277.632909 -148.263001)
			(xy 277.842603 -148.25701) (xy 278.052372 -148.259007) (xy 278.261914 -148.268989) (xy 278.470924 -148.286941)
			(xy 278.679098 -148.312837) (xy 278.886136 -148.346639) (xy 279.091737 -148.388299) (xy 279.295603 -148.437757)
			(xy 279.497438 -148.49494) (xy 279.69695 -148.559765) (xy 279.893849 -148.632139) (xy 280.08785 -148.711956)
			(xy 280.278672 -148.799102) (xy 280.466038 -148.893449) (xy 280.649676 -148.99486) (xy 280.82932 -149.10319)
			(xy 281.00471 -149.21828) (xy 281.175591 -149.339964) (xy 281.341715 -149.468065) (xy 281.502842 -149.602398)
			(xy 281.658739 -149.742767) (xy 281.809178 -149.88897) (xy 281.953942 -150.040794) (xy 282.092821 -150.19802)
			(xy 282.225614 -150.360419) (xy 282.352128 -150.527755) (xy 282.47218 -150.699787) (xy 282.585595 -150.876264)
			(xy 282.692209 -151.056932) (xy 282.791868 -151.241527) (xy 282.884427 -151.429782) (xy 282.969752 -151.621425)
			(xy 283.047719 -151.816177) (xy 283.118215 -152.013757) (xy 283.181138 -152.213876) (xy 283.236397 -152.416247)
			(xy 283.283911 -152.620574) (xy 283.323612 -152.826562) (xy 283.355442 -153.033913) (xy 283.379355 -153.242324)
			(xy 283.395316 -153.451495) (xy 283.403303 -153.661122) (xy 283.403802 -153.766012) (xy 283.403303 -153.870902)
			(xy 283.395316 -154.080529) (xy 283.379355 -154.2897) (xy 283.355442 -154.498111) (xy 283.323612 -154.705462)
			(xy 283.283911 -154.91145) (xy 283.236397 -155.115777) (xy 283.181138 -155.318148) (xy 283.118215 -155.518267)
			(xy 283.047719 -155.715847) (xy 282.969752 -155.910599) (xy 282.884427 -156.102242) (xy 282.791868 -156.290497)
			(xy 282.692209 -156.475092) (xy 282.585595 -156.65576) (xy 282.47218 -156.832237) (xy 282.352128 -157.004269)
			(xy 282.225614 -157.171605) (xy 282.092821 -157.334004) (xy 281.953942 -157.49123) (xy 281.809178 -157.643054)
			(xy 281.658739 -157.789257) (xy 281.502842 -157.929626) (xy 281.341715 -158.063959) (xy 281.175591 -158.19206)
			(xy 281.00471 -158.313744) (xy 280.82932 -158.428834) (xy 280.649676 -158.537164) (xy 280.466038 -158.638575)
			(xy 280.278672 -158.732922) (xy 280.08785 -158.820068) (xy 279.893849 -158.899885) (xy 279.69695 -158.972259)
			(xy 279.497438 -159.037084) (xy 279.295603 -159.094267) (xy 279.091737 -159.143725) (xy 278.886136 -159.185385)
			(xy 278.679098 -159.219187) (xy 278.470924 -159.245083) (xy 278.261914 -159.263035) (xy 278.052372 -159.273017)
			(xy 277.842603 -159.275014) (xy 277.632909 -159.269023) (xy 277.423596 -159.255054) (xy 277.214966 -159.233126)
			(xy 277.007322 -159.203272) (xy 276.800965 -159.165533) (xy 276.596195 -159.119966) (xy 276.393308 -159.066637)
			(xy 276.192598 -159.005622) (xy 275.994356 -158.93701) (xy 275.798871 -158.8609) (xy 275.606424 -158.777403)
			(xy 275.417296 -158.686641) (xy 275.231761 -158.588744) (xy 275.050087 -158.483854) (xy 274.872537 -158.372124)
			(xy 274.699371 -158.253716) (xy 274.530837 -158.128801) (xy 274.367182 -157.99756) (xy 274.208641 -157.860184)
			(xy 274.055446 -157.716871) (xy 273.907817 -157.567831) (xy 273.76597 -157.413278) (xy 273.630109 -157.253437)
			(xy 273.500432 -157.088539) (xy 273.377127 -156.918824) (xy 273.260373 -156.744538) (xy 273.150338 -156.565933)
			(xy 273.047183 -156.383269) (xy 272.951056 -156.19681) (xy 272.862098 -156.006826) (xy 272.780438 -155.813594)
			(xy 272.706193 -155.617393) (xy 272.639471 -155.418507) (xy 272.580369 -155.217225) (xy 272.528973 -155.01384)
			(xy 272.485358 -154.808645) (xy 272.449586 -154.601938) (xy 272.421709 -154.394019) (xy 272.401768 -154.18519)
			(xy 272.389792 -153.975753) (xy 272.385799 -153.766012) (xy 199.463618 -153.766012) (xy 199.46366 -153.774902)
			(xy 199.463161 -153.879792) (xy 199.455174 -154.089419) (xy 199.439213 -154.29859) (xy 199.4153 -154.507001)
			(xy 199.38347 -154.714352) (xy 199.343769 -154.92034) (xy 199.296255 -155.124667) (xy 199.240996 -155.327038)
			(xy 199.178073 -155.527157) (xy 199.107577 -155.724737) (xy 199.02961 -155.919489) (xy 198.944285 -156.111132)
			(xy 198.851726 -156.299387) (xy 198.752067 -156.483982) (xy 198.645453 -156.66465) (xy 198.532038 -156.841127)
			(xy 198.411986 -157.013159) (xy 198.285472 -157.180495) (xy 198.152679 -157.342894) (xy 198.0138 -157.50012)
			(xy 197.869036 -157.651944) (xy 197.718597 -157.798147) (xy 197.5627 -157.938516) (xy 197.401573 -158.072849)
			(xy 197.235449 -158.20095) (xy 197.064568 -158.322634) (xy 196.889178 -158.437724) (xy 196.709534 -158.546054)
			(xy 196.525896 -158.647465) (xy 196.33853 -158.741812) (xy 196.147708 -158.828958) (xy 195.953707 -158.908775)
			(xy 195.756808 -158.981149) (xy 195.557296 -159.045974) (xy 195.355461 -159.103157) (xy 195.151595 -159.152615)
			(xy 194.945994 -159.194275) (xy 194.738956 -159.228077) (xy 194.530782 -159.253973) (xy 194.321772 -159.271925)
			(xy 194.11223 -159.281907) (xy 193.902461 -159.283904) (xy 193.692767 -159.277913) (xy 193.483454 -159.263944)
			(xy 193.274824 -159.242016) (xy 193.06718 -159.212162) (xy 192.860823 -159.174423) (xy 192.656053 -159.128856)
			(xy 192.453166 -159.075527) (xy 192.252456 -159.014512) (xy 192.054214 -158.9459) (xy 191.858729 -158.86979)
			(xy 191.666282 -158.786293) (xy 191.477154 -158.695531) (xy 191.291619 -158.597634) (xy 191.109945 -158.492744)
			(xy 190.932395 -158.381014) (xy 190.759229 -158.262606) (xy 190.590695 -158.137691) (xy 190.42704 -158.00645)
			(xy 190.268499 -157.869074) (xy 190.115304 -157.725761) (xy 189.967675 -157.576721) (xy 189.825828 -157.422168)
			(xy 189.689967 -157.262327) (xy 189.56029 -157.097429) (xy 189.436985 -156.927714) (xy 189.320231 -156.753428)
			(xy 189.210196 -156.574823) (xy 189.107041 -156.392159) (xy 189.010914 -156.2057) (xy 188.921956 -156.015716)
			(xy 188.840296 -155.822484) (xy 188.766051 -155.626283) (xy 188.699329 -155.427397) (xy 188.640227 -155.226115)
			(xy 188.588831 -155.02273) (xy 188.545216 -154.817535) (xy 188.509444 -154.610828) (xy 188.481567 -154.402909)
			(xy 188.461626 -154.19408) (xy 188.44965 -153.984643) (xy 188.445657 -153.774902) (xy 187.505848 -153.774902)
			(xy 187.505848 -154.239468) (xy 187.505362 -154.266719) (xy 187.497606 -154.320667) (xy 187.482251 -154.372962)
			(xy 187.459609 -154.422539) (xy 187.430143 -154.468389) (xy 187.394452 -154.50958) (xy 187.353261 -154.545271)
			(xy 187.307411 -154.574737) (xy 187.257834 -154.597379) (xy 187.205539 -154.612734) (xy 187.151591 -154.62049)
			(xy 187.097089 -154.62049) (xy 187.043141 -154.612734) (xy 186.990846 -154.597379) (xy 186.941269 -154.574737)
			(xy 186.895419 -154.545271) (xy 186.854228 -154.50958) (xy 186.818537 -154.468389) (xy 186.789071 -154.422539)
			(xy 186.766429 -154.372962) (xy 186.751074 -154.320667) (xy 186.743318 -154.266719) (xy 186.742832 -154.239468)
			(xy 114.247676 -154.239468) (xy 120.508268 -160.50006) (xy 162.628078 -160.50006) (xy 162.632092 -160.294376)
			(xy 162.644128 -160.089006) (xy 162.664167 -159.884262) (xy 162.69218 -159.680455) (xy 162.728123 -159.477896)
			(xy 162.771942 -159.276894) (xy 162.823569 -159.077755) (xy 162.882927 -158.880782) (xy 162.949925 -158.686274)
			(xy 163.024461 -158.494529) (xy 163.106421 -158.305838) (xy 163.195681 -158.120488) (xy 163.292104 -157.938762)
			(xy 163.395545 -157.760936) (xy 163.505844 -157.587282) (xy 163.622835 -157.418063) (xy 163.746339 -157.253537)
			(xy 163.876168 -157.093956) (xy 164.012125 -156.939561) (xy 164.154002 -156.790589) (xy 164.301583 -156.647265)
			(xy 164.454644 -156.509809) (xy 164.612951 -156.378429) (xy 164.776264 -156.253326) (xy 164.944333 -156.134689)
			(xy 165.116903 -156.022701) (xy 165.293711 -155.91753) (xy 165.474488 -155.819339) (xy 165.658958 -155.728275)
			(xy 165.84684 -155.644478) (xy 166.03785 -155.568075) (xy 166.231694 -155.499182) (xy 166.428079 -155.437905)
			(xy 166.626705 -155.384337) (xy 166.82727 -155.33856) (xy 167.029468 -155.300642) (xy 167.232992 -155.270643)
			(xy 167.437531 -155.248606) (xy 167.642774 -155.234567) (xy 167.848409 -155.228547) (xy 168.054122 -155.230554)
			(xy 168.2596 -155.240586) (xy 168.46453 -155.258627) (xy 168.6686 -155.28465) (xy 168.8715 -155.318615)
			(xy 169.07292 -155.36047) (xy 169.272553 -155.410152) (xy 169.470096 -155.467586) (xy 169.665248 -155.532683)
			(xy 169.857712 -155.605344) (xy 170.047194 -155.68546) (xy 170.233405 -155.772907) (xy 170.416064 -155.867553)
			(xy 170.59489 -155.969253) (xy 170.769612 -156.077853) (xy 170.939965 -156.193188) (xy 171.105687 -156.315081)
			(xy 171.266528 -156.443347) (xy 171.422241 -156.57779) (xy 171.572591 -156.718207) (xy 171.717348 -156.864383)
			(xy 171.856291 -157.016095) (xy 171.989209 -157.173113) (xy 172.1159 -157.335198) (xy 172.23617 -157.502101)
			(xy 172.349837 -157.673571) (xy 172.456727 -157.849344) (xy 172.556678 -158.029154) (xy 172.649537 -158.212727)
			(xy 172.735164 -158.399783) (xy 172.813426 -158.590038) (xy 172.884207 -158.783201) (xy 172.947397 -158.978979)
			(xy 173.0029 -159.177073) (xy 173.050632 -159.377182) (xy 173.090521 -159.579) (xy 173.122505 -159.782222)
			(xy 173.146535 -159.986536) (xy 173.162576 -160.191632) (xy 173.170602 -160.397199) (xy 173.171104 -160.50006)
			(xy 317.628276 -160.50006) (xy 317.63229 -160.294376) (xy 317.644326 -160.089006) (xy 317.664365 -159.884262)
			(xy 317.692378 -159.680455) (xy 317.728321 -159.477896) (xy 317.77214 -159.276894) (xy 317.823767 -159.077755)
			(xy 317.883125 -158.880782) (xy 317.950123 -158.686274) (xy 318.024659 -158.494529) (xy 318.106619 -158.305838)
			(xy 318.195879 -158.120488) (xy 318.292302 -157.938762) (xy 318.395743 -157.760936) (xy 318.506042 -157.587282)
			(xy 318.623033 -157.418063) (xy 318.746537 -157.253537) (xy 318.876366 -157.093956) (xy 319.012323 -156.939561)
			(xy 319.1542 -156.790589) (xy 319.301781 -156.647265) (xy 319.454842 -156.509809) (xy 319.613149 -156.378429)
			(xy 319.776462 -156.253326) (xy 319.944531 -156.134689) (xy 320.117101 -156.022701) (xy 320.293909 -155.91753)
			(xy 320.474686 -155.819339) (xy 320.659156 -155.728275) (xy 320.847038 -155.644478) (xy 321.038048 -155.568075)
			(xy 321.231892 -155.499182) (xy 321.428277 -155.437905) (xy 321.626903 -155.384337) (xy 321.827468 -155.33856)
			(xy 322.029666 -155.300642) (xy 322.23319 -155.270643) (xy 322.437729 -155.248606) (xy 322.642972 -155.234567)
			(xy 322.848607 -155.228547) (xy 323.05432 -155.230554) (xy 323.259798 -155.240586) (xy 323.464728 -155.258627)
			(xy 323.668798 -155.28465) (xy 323.871698 -155.318615) (xy 324.073118 -155.36047) (xy 324.272751 -155.410152)
			(xy 324.470294 -155.467586) (xy 324.665446 -155.532683) (xy 324.85791 -155.605344) (xy 325.047392 -155.68546)
			(xy 325.233603 -155.772907) (xy 325.416262 -155.867553) (xy 325.595088 -155.969253) (xy 325.76981 -156.077853)
			(xy 325.940163 -156.193188) (xy 326.105885 -156.315081) (xy 326.266726 -156.443347) (xy 326.422439 -156.57779)
			(xy 326.572789 -156.718207) (xy 326.717546 -156.864383) (xy 326.856489 -157.016095) (xy 326.989407 -157.173113)
			(xy 327.116098 -157.335198) (xy 327.236368 -157.502101) (xy 327.350035 -157.673571) (xy 327.456925 -157.849344)
			(xy 327.556876 -158.029154) (xy 327.649735 -158.212727) (xy 327.735362 -158.399783) (xy 327.813624 -158.590038)
			(xy 327.884405 -158.783201) (xy 327.947595 -158.978979) (xy 328.003098 -159.177073) (xy 328.05083 -159.377182)
			(xy 328.090719 -159.579) (xy 328.122703 -159.782222) (xy 328.146733 -159.986536) (xy 328.162774 -160.191632)
			(xy 328.1708 -160.397199) (xy 328.171302 -160.50006) (xy 328.1708 -160.602921) (xy 328.162774 -160.808488)
			(xy 328.146733 -161.013584) (xy 328.122703 -161.217898) (xy 328.090719 -161.42112) (xy 328.05083 -161.622938)
			(xy 328.003098 -161.823047) (xy 327.947595 -162.021141) (xy 327.884405 -162.216919) (xy 327.813624 -162.410082)
			(xy 327.735362 -162.600337) (xy 327.649735 -162.787393) (xy 327.556876 -162.970966) (xy 327.456925 -163.150776)
			(xy 327.350035 -163.326549) (xy 327.236368 -163.498019) (xy 327.116098 -163.664922) (xy 326.989407 -163.827007)
			(xy 326.856489 -163.984025) (xy 326.717546 -164.135737) (xy 326.572789 -164.281913) (xy 326.422439 -164.42233)
			(xy 326.266726 -164.556773) (xy 326.105885 -164.685039) (xy 325.940163 -164.806932) (xy 325.76981 -164.922267)
			(xy 325.595088 -165.030867) (xy 325.416262 -165.132567) (xy 325.233603 -165.227213) (xy 325.047392 -165.31466)
			(xy 324.85791 -165.394776) (xy 324.665446 -165.467437) (xy 324.470294 -165.532534) (xy 324.272751 -165.589968)
			(xy 324.073118 -165.63965) (xy 323.871698 -165.681505) (xy 323.668798 -165.71547) (xy 323.464728 -165.741493)
			(xy 323.259798 -165.759534) (xy 323.05432 -165.769566) (xy 322.848607 -165.771573) (xy 322.642972 -165.765553)
			(xy 322.437729 -165.751514) (xy 322.23319 -165.729477) (xy 322.029666 -165.699478) (xy 321.827468 -165.66156)
			(xy 321.626903 -165.615783) (xy 321.428277 -165.562215) (xy 321.231892 -165.500938) (xy 321.038048 -165.432045)
			(xy 320.847038 -165.355642) (xy 320.659156 -165.271845) (xy 320.474686 -165.180781) (xy 320.293909 -165.08259)
			(xy 320.117101 -164.977419) (xy 319.944531 -164.865431) (xy 319.776462 -164.746794) (xy 319.613149 -164.621691)
			(xy 319.454842 -164.490311) (xy 319.301781 -164.352855) (xy 319.1542 -164.209531) (xy 319.012323 -164.060559)
			(xy 318.876366 -163.906164) (xy 318.746537 -163.746583) (xy 318.623033 -163.582057) (xy 318.506042 -163.412838)
			(xy 318.395743 -163.239184) (xy 318.292302 -163.061358) (xy 318.195879 -162.879632) (xy 318.106619 -162.694282)
			(xy 318.024659 -162.505591) (xy 317.950123 -162.313846) (xy 317.883125 -162.119338) (xy 317.823767 -161.922365)
			(xy 317.77214 -161.723226) (xy 317.728321 -161.522224) (xy 317.692378 -161.319665) (xy 317.664365 -161.115858)
			(xy 317.644326 -160.911114) (xy 317.63229 -160.705744) (xy 317.628276 -160.50006) (xy 173.171104 -160.50006)
			(xy 173.170602 -160.602921) (xy 173.162576 -160.808488) (xy 173.146535 -161.013584) (xy 173.122505 -161.217898)
			(xy 173.090521 -161.42112) (xy 173.058239 -161.58445) (xy 296.753286 -161.58445) (xy 296.753286 -161.52995)
			(xy 296.761042 -161.476005) (xy 296.776395 -161.423713) (xy 296.799035 -161.374138) (xy 296.828498 -161.32829)
			(xy 296.864187 -161.287101) (xy 296.905374 -161.25141) (xy 296.951221 -161.221944) (xy 297.000795 -161.199302)
			(xy 297.053086 -161.183946) (xy 297.10703 -161.176187) (xy 297.13428 -161.1757) (xy 297.99788 -161.1757)
			(xy 298.025134 -161.176146) (xy 298.079089 -161.183901) (xy 298.13139 -161.199255) (xy 298.180974 -161.221897)
			(xy 298.22683 -161.251365) (xy 298.268026 -161.28706) (xy 298.303723 -161.328254) (xy 298.333193 -161.374109)
			(xy 298.355838 -161.423691) (xy 298.371195 -161.475992) (xy 298.378953 -161.529946) (xy 298.378953 -161.584454)
			(xy 298.371195 -161.638408) (xy 298.355838 -161.690709) (xy 298.333193 -161.740291) (xy 298.303723 -161.786146)
			(xy 298.268026 -161.82734) (xy 298.22683 -161.863035) (xy 298.180974 -161.892503) (xy 298.13139 -161.915145)
			(xy 298.079089 -161.930499) (xy 298.025134 -161.938254) (xy 297.99788 -161.938716) (xy 297.13428 -161.938716)
			(xy 297.10703 -161.938213) (xy 297.053086 -161.930454) (xy 297.000795 -161.915098) (xy 296.951221 -161.892456)
			(xy 296.905374 -161.86299) (xy 296.864187 -161.827299) (xy 296.828498 -161.78611) (xy 296.799035 -161.740262)
			(xy 296.776395 -161.690687) (xy 296.761042 -161.638395) (xy 296.753286 -161.58445) (xy 173.058239 -161.58445)
			(xy 173.050632 -161.622938) (xy 173.0029 -161.823047) (xy 172.947397 -162.021141) (xy 172.91289 -162.128053)
			(xy 292.574946 -162.128053) (xy 292.574946 -162.073547) (xy 292.582702 -162.019597) (xy 292.598058 -161.967299)
			(xy 292.620699 -161.917719) (xy 292.650166 -161.871866) (xy 292.685859 -161.830673) (xy 292.72705 -161.794978)
			(xy 292.772902 -161.765509) (xy 292.822481 -161.742865) (xy 292.874777 -161.727507) (xy 292.928727 -161.719747)
			(xy 292.95598 -161.71926) (xy 293.81958 -161.71926) (xy 293.846832 -161.719786) (xy 293.90078 -161.72754)
			(xy 293.953076 -161.742893) (xy 294.002654 -161.765532) (xy 294.048506 -161.794997) (xy 294.089698 -161.830688)
			(xy 294.125391 -161.871878) (xy 294.154858 -161.917728) (xy 294.1775 -161.967305) (xy 294.192856 -162.0196)
			(xy 294.200613 -162.073549) (xy 294.200613 -162.128051) (xy 294.192856 -162.182) (xy 294.1775 -162.234295)
			(xy 294.154858 -162.283872) (xy 294.125391 -162.329722) (xy 294.089698 -162.370912) (xy 294.048506 -162.406603)
			(xy 294.002654 -162.436068) (xy 293.953076 -162.458707) (xy 293.90078 -162.47406) (xy 293.846832 -162.481814)
			(xy 293.81958 -162.482276) (xy 292.95598 -162.482276) (xy 292.928727 -162.481853) (xy 292.874777 -162.474093)
			(xy 292.822481 -162.458735) (xy 292.772902 -162.436091) (xy 292.72705 -162.406622) (xy 292.685859 -162.370927)
			(xy 292.650166 -162.329734) (xy 292.620699 -162.283881) (xy 292.598058 -162.234301) (xy 292.582702 -162.182003)
			(xy 292.574946 -162.128053) (xy 172.91289 -162.128053) (xy 172.884207 -162.216919) (xy 172.813426 -162.410082)
			(xy 172.735164 -162.600337) (xy 172.649537 -162.787393) (xy 172.556678 -162.970966) (xy 172.471805 -163.123651)
			(xy 294.731403 -163.123651) (xy 294.731403 -163.069149) (xy 294.73916 -163.015201) (xy 294.754516 -162.962907)
			(xy 294.777159 -162.91333) (xy 294.806627 -162.867481) (xy 294.842321 -162.826292) (xy 294.883513 -162.790603)
			(xy 294.929365 -162.76114) (xy 294.978944 -162.738502) (xy 295.03124 -162.723152) (xy 295.085189 -162.7154)
			(xy 295.11244 -162.71494) (xy 295.97604 -162.71494) (xy 296.003293 -162.715333) (xy 296.057243 -162.723095)
			(xy 296.10954 -162.738455) (xy 296.159118 -162.761102) (xy 296.204969 -162.790573) (xy 296.24616 -162.826269)
			(xy 296.281851 -162.867463) (xy 296.311318 -162.913317) (xy 296.333959 -162.962898) (xy 296.349314 -163.015196)
			(xy 296.35707 -163.069147) (xy 296.35707 -163.110951) (xy 300.192403 -163.110951) (xy 300.192403 -163.056449)
			(xy 300.20016 -163.002501) (xy 300.215516 -162.950207) (xy 300.238159 -162.90063) (xy 300.267627 -162.854781)
			(xy 300.303321 -162.813592) (xy 300.344513 -162.777903) (xy 300.390365 -162.74844) (xy 300.439944 -162.725802)
			(xy 300.49224 -162.710452) (xy 300.546189 -162.7027) (xy 300.57344 -162.70224) (xy 301.43704 -162.70224)
			(xy 301.464293 -162.702633) (xy 301.518243 -162.710395) (xy 301.57054 -162.725755) (xy 301.620118 -162.748402)
			(xy 301.665969 -162.777873) (xy 301.70716 -162.813569) (xy 301.742851 -162.854763) (xy 301.772318 -162.900617)
			(xy 301.794959 -162.950198) (xy 301.810314 -163.002496) (xy 301.81807 -163.056447) (xy 301.81807 -163.110953)
			(xy 301.810314 -163.164904) (xy 301.794959 -163.217202) (xy 301.772318 -163.266783) (xy 301.742851 -163.312637)
			(xy 301.70716 -163.353831) (xy 301.665969 -163.389527) (xy 301.620118 -163.418998) (xy 301.57054 -163.441645)
			(xy 301.518243 -163.457005) (xy 301.464293 -163.464767) (xy 301.43704 -163.465256) (xy 300.57344 -163.465256)
			(xy 300.546189 -163.4647) (xy 300.49224 -163.456948) (xy 300.439944 -163.441598) (xy 300.390365 -163.41896)
			(xy 300.344513 -163.389497) (xy 300.303321 -163.353808) (xy 300.267627 -163.312619) (xy 300.238159 -163.26677)
			(xy 300.215516 -163.217193) (xy 300.20016 -163.164899) (xy 300.192403 -163.110951) (xy 296.35707 -163.110951)
			(xy 296.35707 -163.123653) (xy 296.349314 -163.177604) (xy 296.333959 -163.229902) (xy 296.311318 -163.279483)
			(xy 296.281851 -163.325337) (xy 296.24616 -163.366531) (xy 296.204969 -163.402227) (xy 296.159118 -163.431698)
			(xy 296.10954 -163.454345) (xy 296.057243 -163.469705) (xy 296.003293 -163.477467) (xy 295.97604 -163.477956)
			(xy 295.11244 -163.477956) (xy 295.085189 -163.4774) (xy 295.03124 -163.469648) (xy 294.978944 -163.454298)
			(xy 294.929365 -163.43166) (xy 294.883513 -163.402197) (xy 294.842321 -163.366508) (xy 294.806627 -163.325319)
			(xy 294.777159 -163.27947) (xy 294.754516 -163.229893) (xy 294.73916 -163.177599) (xy 294.731403 -163.123651)
			(xy 172.471805 -163.123651) (xy 172.456727 -163.150776) (xy 172.349837 -163.326549) (xy 172.23617 -163.498019)
			(xy 172.1159 -163.664922) (xy 171.989209 -163.827007) (xy 171.856291 -163.984025) (xy 171.717348 -164.135737)
			(xy 171.572591 -164.281913) (xy 171.422241 -164.42233) (xy 171.266528 -164.556773) (xy 171.105687 -164.685039)
			(xy 170.939965 -164.806932) (xy 170.769612 -164.922267) (xy 170.59489 -165.030867) (xy 170.416064 -165.132567)
			(xy 170.233405 -165.227213) (xy 170.047194 -165.31466) (xy 169.857712 -165.394776) (xy 169.665248 -165.467437)
			(xy 169.470096 -165.532534) (xy 169.272553 -165.589968) (xy 169.07292 -165.63965) (xy 168.8715 -165.681505)
			(xy 168.6686 -165.71547) (xy 168.46453 -165.741493) (xy 168.2596 -165.759534) (xy 168.054122 -165.769566)
			(xy 167.848409 -165.771573) (xy 167.642774 -165.765553) (xy 167.437531 -165.751514) (xy 167.232992 -165.729477)
			(xy 167.029468 -165.699478) (xy 166.82727 -165.66156) (xy 166.626705 -165.615783) (xy 166.428079 -165.562215)
			(xy 166.231694 -165.500938) (xy 166.03785 -165.432045) (xy 165.84684 -165.355642) (xy 165.658958 -165.271845)
			(xy 165.474488 -165.180781) (xy 165.293711 -165.08259) (xy 165.116903 -164.977419) (xy 164.944333 -164.865431)
			(xy 164.776264 -164.746794) (xy 164.612951 -164.621691) (xy 164.454644 -164.490311) (xy 164.301583 -164.352855)
			(xy 164.154002 -164.209531) (xy 164.012125 -164.060559) (xy 163.876168 -163.906164) (xy 163.746339 -163.746583)
			(xy 163.622835 -163.582057) (xy 163.505844 -163.412838) (xy 163.395545 -163.239184) (xy 163.292104 -163.061358)
			(xy 163.195681 -162.879632) (xy 163.106421 -162.694282) (xy 163.024461 -162.505591) (xy 162.949925 -162.313846)
			(xy 162.882927 -162.119338) (xy 162.823569 -161.922365) (xy 162.771942 -161.723226) (xy 162.728123 -161.522224)
			(xy 162.69218 -161.319665) (xy 162.664167 -161.115858) (xy 162.644128 -160.911114) (xy 162.632092 -160.705744)
			(xy 162.628078 -160.50006) (xy 120.508268 -160.50006) (xy 152.701498 -192.69329) (xy 169.92981 -192.69329)
			(xy 169.951923 -192.680751) (xy 169.998764 -192.660999) (xy 170.04781 -192.647631) (xy 170.098195 -192.640881)
			(xy 170.123612 -192.640458) (xy 170.149032 -192.640864) (xy 170.199423 -192.64759) (xy 170.248472 -192.66096)
			(xy 170.295306 -192.680738) (xy 170.317414 -192.69329) (xy 193.326512 -192.69329) (xy 193.336672 -192.655952)
			(xy 193.344464 -192.629432) (xy 193.366639 -192.578803) (xy 193.395885 -192.531901) (xy 193.43159 -192.489708)
			(xy 193.473007 -192.453107) (xy 193.519271 -192.422863) (xy 193.569414 -192.399608) (xy 193.622387 -192.38383)
			(xy 193.677082 -192.375857) (xy 193.732354 -192.375857) (xy 193.787049 -192.38383) (xy 193.840022 -192.399608)
			(xy 193.890165 -192.422863) (xy 193.936429 -192.453107) (xy 193.977846 -192.489708) (xy 194.013551 -192.531901)
			(xy 194.042797 -192.578803) (xy 194.064972 -192.629432) (xy 194.072764 -192.655952) (xy 194.082924 -192.69329)
			(xy 212.28558 -192.69329) (xy 212.297772 -192.659762) (xy 212.307453 -192.634488) (xy 212.333387 -192.586988)
			(xy 212.366257 -192.543996) (xy 212.405296 -192.506515) (xy 212.449591 -192.475423) (xy 212.498108 -192.451444)
			(xy 212.549712 -192.435141) (xy 212.603199 -192.426892) (xy 212.657317 -192.426892) (xy 212.710804 -192.435141)
			(xy 212.762408 -192.451444) (xy 212.810925 -192.475423) (xy 212.845933 -192.499996) (xy 231.378004 -192.499996)
			(xy 231.382018 -192.294312) (xy 231.394054 -192.088942) (xy 231.414093 -191.884198) (xy 231.442106 -191.680391)
			(xy 231.478049 -191.477832) (xy 231.521868 -191.27683) (xy 231.573495 -191.077691) (xy 231.632853 -190.880718)
			(xy 231.699851 -190.68621) (xy 231.774387 -190.494465) (xy 231.856347 -190.305774) (xy 231.945607 -190.120424)
			(xy 232.04203 -189.938698) (xy 232.145471 -189.760872) (xy 232.25577 -189.587218) (xy 232.372761 -189.417999)
			(xy 232.496265 -189.253473) (xy 232.626094 -189.093892) (xy 232.762051 -188.939497) (xy 232.903928 -188.790525)
			(xy 233.051509 -188.647201) (xy 233.20457 -188.509745) (xy 233.362877 -188.378365) (xy 233.52619 -188.253262)
			(xy 233.694259 -188.134625) (xy 233.866829 -188.022637) (xy 234.043637 -187.917466) (xy 234.224414 -187.819275)
			(xy 234.408884 -187.728211) (xy 234.596766 -187.644414) (xy 234.787776 -187.568011) (xy 234.98162 -187.499118)
			(xy 235.178005 -187.437841) (xy 235.376631 -187.384273) (xy 235.577196 -187.338496) (xy 235.779394 -187.300578)
			(xy 235.982918 -187.270579) (xy 236.187457 -187.248542) (xy 236.3927 -187.234503) (xy 236.598335 -187.228483)
			(xy 236.804048 -187.23049) (xy 237.009526 -187.240522) (xy 237.214456 -187.258563) (xy 237.418526 -187.284586)
			(xy 237.621426 -187.318551) (xy 237.822846 -187.360406) (xy 238.022479 -187.410088) (xy 238.220022 -187.467522)
			(xy 238.415174 -187.532619) (xy 238.607638 -187.60528) (xy 238.79712 -187.685396) (xy 238.983331 -187.772843)
			(xy 239.16599 -187.867489) (xy 239.344816 -187.969189) (xy 239.519538 -188.077789) (xy 239.689891 -188.193124)
			(xy 239.855613 -188.315017) (xy 240.016454 -188.443283) (xy 240.172167 -188.577726) (xy 240.322517 -188.718143)
			(xy 240.467274 -188.864319) (xy 240.606217 -189.016031) (xy 240.739135 -189.173049) (xy 240.865826 -189.335134)
			(xy 240.986096 -189.502037) (xy 241.099763 -189.673507) (xy 241.206653 -189.84928) (xy 241.306604 -190.02909)
			(xy 241.399463 -190.212663) (xy 241.48509 -190.399719) (xy 241.563352 -190.589974) (xy 241.634133 -190.783137)
			(xy 241.697323 -190.978915) (xy 241.752826 -191.177009) (xy 241.800558 -191.377118) (xy 241.840447 -191.578936)
			(xy 241.872431 -191.782158) (xy 241.896461 -191.986472) (xy 241.912502 -192.191568) (xy 241.920528 -192.397135)
			(xy 241.92103 -192.499996) (xy 241.920528 -192.602857) (xy 241.912502 -192.808424) (xy 241.896461 -193.01352)
			(xy 241.872431 -193.217834) (xy 241.840447 -193.421056) (xy 241.800558 -193.622874) (xy 241.752826 -193.822983)
			(xy 241.697323 -194.021077) (xy 241.634133 -194.216855) (xy 241.563352 -194.410018) (xy 241.48509 -194.600273)
			(xy 241.399463 -194.787329) (xy 241.306604 -194.970902) (xy 241.206653 -195.150712) (xy 241.099763 -195.326485)
			(xy 240.986096 -195.497955) (xy 240.865826 -195.664858) (xy 240.739135 -195.826943) (xy 240.606217 -195.983961)
			(xy 240.467274 -196.135673) (xy 240.322517 -196.281849) (xy 240.172167 -196.422266) (xy 240.016454 -196.556709)
			(xy 239.855613 -196.684975) (xy 239.689891 -196.806868) (xy 239.519538 -196.922203) (xy 239.344816 -197.030803)
			(xy 239.16599 -197.132503) (xy 238.983331 -197.227149) (xy 238.79712 -197.314596) (xy 238.607638 -197.394712)
			(xy 238.415174 -197.467373) (xy 238.220022 -197.53247) (xy 238.022479 -197.589904) (xy 237.822846 -197.639586)
			(xy 237.621426 -197.681441) (xy 237.418526 -197.715406) (xy 237.214456 -197.741429) (xy 237.009526 -197.75947)
			(xy 236.804048 -197.769502) (xy 236.598335 -197.771509) (xy 236.3927 -197.765489) (xy 236.187457 -197.75145)
			(xy 235.982918 -197.729413) (xy 235.779394 -197.699414) (xy 235.577196 -197.661496) (xy 235.376631 -197.615719)
			(xy 235.178005 -197.562151) (xy 234.98162 -197.500874) (xy 234.787776 -197.431981) (xy 234.596766 -197.355578)
			(xy 234.408884 -197.271781) (xy 234.224414 -197.180717) (xy 234.043637 -197.082526) (xy 233.866829 -196.977355)
			(xy 233.694259 -196.865367) (xy 233.52619 -196.74673) (xy 233.362877 -196.621627) (xy 233.20457 -196.490247)
			(xy 233.051509 -196.352791) (xy 232.903928 -196.209467) (xy 232.762051 -196.060495) (xy 232.626094 -195.9061)
			(xy 232.496265 -195.746519) (xy 232.372761 -195.581993) (xy 232.25577 -195.412774) (xy 232.145471 -195.23912)
			(xy 232.04203 -195.061294) (xy 231.945607 -194.879568) (xy 231.856347 -194.694218) (xy 231.774387 -194.505527)
			(xy 231.699851 -194.313782) (xy 231.632853 -194.119274) (xy 231.573495 -193.922301) (xy 231.521868 -193.723162)
			(xy 231.478049 -193.52216) (xy 231.442106 -193.319601) (xy 231.414093 -193.115794) (xy 231.394054 -192.91105)
			(xy 231.382018 -192.70568) (xy 231.378004 -192.499996) (xy 212.845933 -192.499996) (xy 212.85522 -192.506515)
			(xy 212.894259 -192.543996) (xy 212.927129 -192.586988) (xy 212.953063 -192.634488) (xy 212.962744 -192.659762)
			(xy 212.974936 -192.69329) (xy 216.315798 -192.69329) (xy 216.340761 -192.693821) (xy 216.389727 -192.70356)
			(xy 216.435845 -192.722681) (xy 216.477337 -192.750448) (xy 216.495376 -192.767712) (xy 216.878408 -193.150744)
			(xy 216.902041 -193.135554) (xy 216.952824 -193.111529) (xy 217.006583 -193.09522) (xy 217.062155 -193.086979)
			(xy 217.090244 -193.086482) (xy 217.090498 -193.086482) (xy 217.117749 -193.08698) (xy 217.171696 -193.094736)
			(xy 217.223989 -193.11009) (xy 217.273566 -193.13273) (xy 217.319416 -193.162195) (xy 217.360606 -193.197886)
			(xy 217.396298 -193.239074) (xy 217.425764 -193.284923) (xy 217.448406 -193.334499) (xy 217.463762 -193.386793)
			(xy 217.47152 -193.440739) (xy 217.472006 -193.46799) (xy 217.472006 -193.468244) (xy 217.471473 -193.496331)
			(xy 217.463223 -193.551896) (xy 217.446922 -193.605653) (xy 217.422921 -193.656441) (xy 217.407744 -193.68008)
			(xy 217.973656 -194.245992) (xy 217.990911 -194.264035) (xy 218.01865 -194.305537) (xy 218.037759 -194.351653)
			(xy 218.047504 -194.400611) (xy 218.048078 -194.42557) (xy 218.048078 -247.620536) (xy 228.175312 -247.620536)
			(xy 228.175312 -246.756936) (xy 228.175798 -246.729685) (xy 228.183554 -246.675737) (xy 228.198909 -246.623442)
			(xy 228.221551 -246.573865) (xy 228.251017 -246.528015) (xy 228.286708 -246.486824) (xy 228.327899 -246.451133)
			(xy 228.373749 -246.421667) (xy 228.423326 -246.399025) (xy 228.475621 -246.38367) (xy 228.529569 -246.375914)
			(xy 228.584071 -246.375914) (xy 228.638019 -246.38367) (xy 228.690314 -246.399025) (xy 228.739891 -246.421667)
			(xy 228.785741 -246.451133) (xy 228.826932 -246.486824) (xy 228.862623 -246.528015) (xy 228.892089 -246.573865)
			(xy 228.914731 -246.623442) (xy 228.930086 -246.675737) (xy 228.937842 -246.729685) (xy 228.938328 -246.756936)
			(xy 228.938328 -247.620536) (xy 228.937842 -247.647787) (xy 228.930086 -247.701735) (xy 228.914731 -247.75403)
			(xy 228.892089 -247.803607) (xy 228.862623 -247.849457) (xy 228.826932 -247.890648) (xy 228.785741 -247.926339)
			(xy 228.739891 -247.955805) (xy 228.690314 -247.978447) (xy 228.638019 -247.993802) (xy 228.584071 -248.001558)
			(xy 228.529569 -248.001558) (xy 228.475621 -247.993802) (xy 228.423326 -247.978447) (xy 228.373749 -247.955805)
			(xy 228.327899 -247.926339) (xy 228.286708 -247.890648) (xy 228.251017 -247.849457) (xy 228.221551 -247.803607)
			(xy 228.198909 -247.75403) (xy 228.183554 -247.701735) (xy 228.175798 -247.647787) (xy 228.175312 -247.620536)
			(xy 218.048078 -247.620536) (xy 218.048078 -272.499836) (xy 231.378004 -272.499836) (xy 231.382018 -272.294152)
			(xy 231.394054 -272.088782) (xy 231.414093 -271.884038) (xy 231.442106 -271.680231) (xy 231.478049 -271.477672)
			(xy 231.521868 -271.27667) (xy 231.573495 -271.077531) (xy 231.632853 -270.880558) (xy 231.699851 -270.68605)
			(xy 231.774387 -270.494305) (xy 231.856347 -270.305614) (xy 231.945607 -270.120264) (xy 232.04203 -269.938538)
			(xy 232.145471 -269.760712) (xy 232.25577 -269.587058) (xy 232.372761 -269.417839) (xy 232.496265 -269.253313)
			(xy 232.626094 -269.093732) (xy 232.762051 -268.939337) (xy 232.903928 -268.790365) (xy 233.051509 -268.647041)
			(xy 233.20457 -268.509585) (xy 233.362877 -268.378205) (xy 233.52619 -268.253102) (xy 233.694259 -268.134465)
			(xy 233.866829 -268.022477) (xy 234.043637 -267.917306) (xy 234.224414 -267.819115) (xy 234.408884 -267.728051)
			(xy 234.596766 -267.644254) (xy 234.787776 -267.567851) (xy 234.98162 -267.498958) (xy 235.178005 -267.437681)
			(xy 235.376631 -267.384113) (xy 235.577196 -267.338336) (xy 235.779394 -267.300418) (xy 235.982918 -267.270419)
			(xy 236.187457 -267.248382) (xy 236.3927 -267.234343) (xy 236.598335 -267.228323) (xy 236.804048 -267.23033)
			(xy 237.009526 -267.240362) (xy 237.214456 -267.258403) (xy 237.418526 -267.284426) (xy 237.621426 -267.318391)
			(xy 237.822846 -267.360246) (xy 238.022479 -267.409928) (xy 238.220022 -267.467362) (xy 238.415174 -267.532459)
			(xy 238.607638 -267.60512) (xy 238.79712 -267.685236) (xy 238.983331 -267.772683) (xy 239.16599 -267.867329)
			(xy 239.344816 -267.969029) (xy 239.519538 -268.077629) (xy 239.689891 -268.192964) (xy 239.855613 -268.314857)
			(xy 240.016454 -268.443123) (xy 240.172167 -268.577566) (xy 240.322517 -268.717983) (xy 240.467274 -268.864159)
			(xy 240.606217 -269.015871) (xy 240.739135 -269.172889) (xy 240.865826 -269.334974) (xy 240.986096 -269.501877)
			(xy 241.099763 -269.673347) (xy 241.206653 -269.84912) (xy 241.306604 -270.02893) (xy 241.399463 -270.212503)
			(xy 241.48509 -270.399559) (xy 241.563352 -270.589814) (xy 241.634133 -270.782977) (xy 241.697323 -270.978755)
			(xy 241.752826 -271.176849) (xy 241.800558 -271.376958) (xy 241.840447 -271.578776) (xy 241.872431 -271.781998)
			(xy 241.896461 -271.986312) (xy 241.912502 -272.191408) (xy 241.920528 -272.396975) (xy 241.92103 -272.499836)
			(xy 241.920528 -272.602697) (xy 241.912502 -272.808264) (xy 241.896461 -273.01336) (xy 241.872431 -273.217674)
			(xy 241.840447 -273.420896) (xy 241.800558 -273.622714) (xy 241.752826 -273.822823) (xy 241.697323 -274.020917)
			(xy 241.634133 -274.216695) (xy 241.563352 -274.409858) (xy 241.48509 -274.600113) (xy 241.399463 -274.787169)
			(xy 241.306604 -274.970742) (xy 241.206653 -275.150552) (xy 241.099763 -275.326325) (xy 240.986096 -275.497795)
			(xy 240.865826 -275.664698) (xy 240.739135 -275.826783) (xy 240.606217 -275.983801) (xy 240.467274 -276.135513)
			(xy 240.322517 -276.281689) (xy 240.172167 -276.422106) (xy 240.016454 -276.556549) (xy 239.855613 -276.684815)
			(xy 239.689891 -276.806708) (xy 239.519538 -276.922043) (xy 239.344816 -277.030643) (xy 239.16599 -277.132343)
			(xy 238.983331 -277.226989) (xy 238.79712 -277.314436) (xy 238.607638 -277.394552) (xy 238.415174 -277.467213)
			(xy 238.220022 -277.53231) (xy 238.022479 -277.589744) (xy 237.822846 -277.639426) (xy 237.621426 -277.681281)
			(xy 237.418526 -277.715246) (xy 237.214456 -277.741269) (xy 237.009526 -277.75931) (xy 236.804048 -277.769342)
			(xy 236.598335 -277.771349) (xy 236.3927 -277.765329) (xy 236.187457 -277.75129) (xy 235.982918 -277.729253)
			(xy 235.779394 -277.699254) (xy 235.577196 -277.661336) (xy 235.376631 -277.615559) (xy 235.178005 -277.561991)
			(xy 234.98162 -277.500714) (xy 234.787776 -277.431821) (xy 234.596766 -277.355418) (xy 234.408884 -277.271621)
			(xy 234.224414 -277.180557) (xy 234.043637 -277.082366) (xy 233.866829 -276.977195) (xy 233.694259 -276.865207)
			(xy 233.52619 -276.74657) (xy 233.362877 -276.621467) (xy 233.20457 -276.490087) (xy 233.051509 -276.352631)
			(xy 232.903928 -276.209307) (xy 232.762051 -276.060335) (xy 232.626094 -275.90594) (xy 232.496265 -275.746359)
			(xy 232.372761 -275.581833) (xy 232.25577 -275.412614) (xy 232.145471 -275.23896) (xy 232.04203 -275.061134)
			(xy 231.945607 -274.879408) (xy 231.856347 -274.694058) (xy 231.774387 -274.505367) (xy 231.699851 -274.313622)
			(xy 231.632853 -274.119114) (xy 231.573495 -273.922141) (xy 231.521868 -273.723002) (xy 231.478049 -273.522)
			(xy 231.442106 -273.319441) (xy 231.414093 -273.115634) (xy 231.394054 -272.91089) (xy 231.382018 -272.70552)
			(xy 231.378004 -272.499836) (xy 218.048078 -272.499836) (xy 218.048078 -352.49993) (xy 231.378004 -352.49993)
			(xy 231.382018 -352.294246) (xy 231.394054 -352.088876) (xy 231.414093 -351.884132) (xy 231.442106 -351.680325)
			(xy 231.478049 -351.477766) (xy 231.521868 -351.276764) (xy 231.573495 -351.077625) (xy 231.632853 -350.880652)
			(xy 231.699851 -350.686144) (xy 231.774387 -350.494399) (xy 231.856347 -350.305708) (xy 231.945607 -350.120358)
			(xy 232.04203 -349.938632) (xy 232.145471 -349.760806) (xy 232.25577 -349.587152) (xy 232.372761 -349.417933)
			(xy 232.496265 -349.253407) (xy 232.626094 -349.093826) (xy 232.762051 -348.939431) (xy 232.903928 -348.790459)
			(xy 233.051509 -348.647135) (xy 233.20457 -348.509679) (xy 233.362877 -348.378299) (xy 233.52619 -348.253196)
			(xy 233.694259 -348.134559) (xy 233.866829 -348.022571) (xy 234.043637 -347.9174) (xy 234.224414 -347.819209)
			(xy 234.408884 -347.728145) (xy 234.596766 -347.644348) (xy 234.787776 -347.567945) (xy 234.98162 -347.499052)
			(xy 235.178005 -347.437775) (xy 235.376631 -347.384207) (xy 235.577196 -347.33843) (xy 235.779394 -347.300512)
			(xy 235.982918 -347.270513) (xy 236.187457 -347.248476) (xy 236.3927 -347.234437) (xy 236.598335 -347.228417)
			(xy 236.804048 -347.230424) (xy 237.009526 -347.240456) (xy 237.214456 -347.258497) (xy 237.418526 -347.28452)
			(xy 237.621426 -347.318485) (xy 237.822846 -347.36034) (xy 238.022479 -347.410022) (xy 238.220022 -347.467456)
			(xy 238.415174 -347.532553) (xy 238.607638 -347.605214) (xy 238.79712 -347.68533) (xy 238.983331 -347.772777)
			(xy 239.16599 -347.867423) (xy 239.344816 -347.969123) (xy 239.519538 -348.077723) (xy 239.689891 -348.193058)
			(xy 239.855613 -348.314951) (xy 240.016454 -348.443217) (xy 240.172167 -348.57766) (xy 240.322517 -348.718077)
			(xy 240.467274 -348.864253) (xy 240.606217 -349.015965) (xy 240.739135 -349.172983) (xy 240.865826 -349.335068)
			(xy 240.986096 -349.501971) (xy 241.099763 -349.673441) (xy 241.206653 -349.849214) (xy 241.306604 -350.029024)
			(xy 241.399463 -350.212597) (xy 241.48509 -350.399653) (xy 241.563352 -350.589908) (xy 241.634133 -350.783071)
			(xy 241.697323 -350.978849) (xy 241.752826 -351.176943) (xy 241.800558 -351.377052) (xy 241.840447 -351.57887)
			(xy 241.872431 -351.782092) (xy 241.896461 -351.986406) (xy 241.912502 -352.191502) (xy 241.920528 -352.397069)
			(xy 241.92103 -352.49993) (xy 241.920528 -352.602791) (xy 241.912502 -352.808358) (xy 241.896461 -353.013454)
			(xy 241.872431 -353.217768) (xy 241.840447 -353.42099) (xy 241.800558 -353.622808) (xy 241.752826 -353.822917)
			(xy 241.697323 -354.021011) (xy 241.634133 -354.216789) (xy 241.563352 -354.409952) (xy 241.48509 -354.600207)
			(xy 241.399463 -354.787263) (xy 241.306604 -354.970836) (xy 241.206653 -355.150646) (xy 241.099763 -355.326419)
			(xy 240.986096 -355.497889) (xy 240.865826 -355.664792) (xy 240.739135 -355.826877) (xy 240.606217 -355.983895)
			(xy 240.467274 -356.135607) (xy 240.322517 -356.281783) (xy 240.172167 -356.4222) (xy 240.016454 -356.556643)
			(xy 239.855613 -356.684909) (xy 239.689891 -356.806802) (xy 239.519538 -356.922137) (xy 239.344816 -357.030737)
			(xy 239.16599 -357.132437) (xy 238.983331 -357.227083) (xy 238.79712 -357.31453) (xy 238.607638 -357.394646)
			(xy 238.415174 -357.467307) (xy 238.220022 -357.532404) (xy 238.022479 -357.589838) (xy 237.822846 -357.63952)
			(xy 237.621426 -357.681375) (xy 237.418526 -357.71534) (xy 237.214456 -357.741363) (xy 237.009526 -357.759404)
			(xy 236.804048 -357.769436) (xy 236.598335 -357.771443) (xy 236.3927 -357.765423) (xy 236.187457 -357.751384)
			(xy 235.982918 -357.729347) (xy 235.779394 -357.699348) (xy 235.577196 -357.66143) (xy 235.376631 -357.615653)
			(xy 235.178005 -357.562085) (xy 234.98162 -357.500808) (xy 234.787776 -357.431915) (xy 234.596766 -357.355512)
			(xy 234.408884 -357.271715) (xy 234.224414 -357.180651) (xy 234.043637 -357.08246) (xy 233.866829 -356.977289)
			(xy 233.694259 -356.865301) (xy 233.52619 -356.746664) (xy 233.362877 -356.621561) (xy 233.20457 -356.490181)
			(xy 233.051509 -356.352725) (xy 232.903928 -356.209401) (xy 232.762051 -356.060429) (xy 232.626094 -355.906034)
			(xy 232.496265 -355.746453) (xy 232.372761 -355.581927) (xy 232.25577 -355.412708) (xy 232.145471 -355.239054)
			(xy 232.04203 -355.061228) (xy 231.945607 -354.879502) (xy 231.856347 -354.694152) (xy 231.774387 -354.505461)
			(xy 231.699851 -354.313716) (xy 231.632853 -354.119208) (xy 231.573495 -353.922235) (xy 231.521868 -353.723096)
			(xy 231.478049 -353.522094) (xy 231.442106 -353.319535) (xy 231.414093 -353.115728) (xy 231.394054 -352.910984)
			(xy 231.382018 -352.705614) (xy 231.378004 -352.49993) (xy 218.048078 -352.49993) (xy 218.048078 -356.32771)
			(xy 218.047534 -356.352672) (xy 218.037796 -356.401636) (xy 218.018678 -356.447754) (xy 217.990917 -356.489247)
			(xy 217.973656 -356.507288) (xy 217.423492 -357.057452) (xy 217.45829 -357.09352) (xy 217.528605 -357.166715)
			(xy 217.664237 -357.317745) (xy 217.793953 -357.473884) (xy 217.91756 -357.634903) (xy 218.034877 -357.800561)
			(xy 218.145728 -357.970614) (xy 218.249949 -358.144808) (xy 218.347386 -358.322887) (xy 218.437894 -358.504585)
			(xy 218.521339 -358.689633) (xy 218.597597 -358.877757) (xy 218.666554 -359.068677) (xy 218.72811 -359.262111)
			(xy 218.782172 -359.457772) (xy 218.82866 -359.655369) (xy 218.867506 -359.85461) (xy 218.898651 -360.055198)
			(xy 218.92205 -360.256838) (xy 218.937668 -360.459228) (xy 218.945482 -360.66207) (xy 218.945968 -360.763566)
			(xy 218.945968 -360.76382) (xy 252.853952 -360.76382) (xy 252.854424 -360.661891) (xy 252.862306 -360.458186)
			(xy 252.878057 -360.254937) (xy 252.901656 -360.05245) (xy 252.933066 -359.851027) (xy 252.97224 -359.650968)
			(xy 253.01912 -359.452574) (xy 253.073637 -359.256141) (xy 253.135707 -359.061962) (xy 253.205239 -358.870329)
			(xy 253.282128 -358.681527) (xy 253.36626 -358.49584) (xy 253.457508 -358.313544) (xy 253.555737 -358.134913)
			(xy 253.660799 -357.960213) (xy 253.772537 -357.789706) (xy 253.890784 -357.623647) (xy 254.015363 -357.462284)
			(xy 254.146088 -357.305859) (xy 254.282764 -357.154605) (xy 254.425186 -357.008748) (xy 254.57314 -356.868508)
			(xy 254.726407 -356.734093) (xy 254.884756 -356.605704) (xy 255.04795 -356.483534) (xy 255.13157 -356.425246)
			(xy 255.143523 -356.416384) (xy 255.162137 -356.393191) (xy 255.173274 -356.365615) (xy 255.175986 -356.335999)
			(xy 255.170044 -356.306859) (xy 255.155952 -356.28067) (xy 255.145794 -356.269798) (xy 253.619 -354.743004)
			(xy 253.601767 -354.724944) (xy 253.574036 -354.683445) (xy 253.554933 -354.637334) (xy 253.545192 -354.588382)
			(xy 253.544578 -354.563426) (xy 253.544578 -194.91071) (xy 253.545118 -194.885748) (xy 253.554854 -194.836782)
			(xy 253.573973 -194.790664) (xy 253.601737 -194.749171) (xy 253.619 -194.731132) (xy 254.39624 -193.953892)
			(xy 254.414322 -193.936684) (xy 254.455814 -193.908949) (xy 254.501918 -193.889839) (xy 254.550864 -193.880089)
			(xy 254.575818 -193.87947) (xy 318.06388 -193.87947) (xy 318.06388 -185.969148) (xy 318.064443 -185.944187)
			(xy 318.074172 -185.895222) (xy 318.093284 -185.849104) (xy 318.121042 -185.807611) (xy 318.138302 -185.78957)
			(xy 355.746304 -148.181568) (xy 355.764345 -148.164311) (xy 355.805847 -148.136571) (xy 355.851964 -148.117463)
			(xy 355.900923 -148.107719) (xy 355.925882 -148.107146) (xy 396.387574 -148.107146) (xy 396.409883 -148.09071)
			(xy 396.458302 -148.063769) (xy 396.510108 -148.044111) (xy 396.564212 -148.032148) (xy 396.619476 -148.028133)
			(xy 396.67474 -148.032148) (xy 396.728844 -148.044111) (xy 396.78065 -148.063769) (xy 396.829069 -148.09071)
			(xy 396.851378 -148.107146) (xy 407.916634 -148.107146) (xy 407.933209 -148.084393) (xy 407.971957 -148.04356)
			(xy 408.016288 -148.008868) (xy 408.065238 -147.98107) (xy 408.117743 -147.960772) (xy 408.172661 -147.948414)
			(xy 408.2288 -147.944265) (xy 408.284939 -147.948414) (xy 408.339857 -147.960772) (xy 408.392362 -147.98107)
			(xy 408.441312 -148.008868) (xy 408.485643 -148.04356) (xy 408.524391 -148.084393) (xy 408.540966 -148.107146)
			(xy 410.120338 -148.107146) (xy 410.138575 -148.086119) (xy 410.1801 -148.049055) (xy 410.226566 -148.018415)
			(xy 410.27699 -147.994848) (xy 410.330301 -147.978853) (xy 410.38537 -147.97077) (xy 410.44103 -147.97077)
			(xy 410.496099 -147.978853) (xy 410.54941 -147.994848) (xy 410.599834 -148.018415) (xy 410.6463 -148.049055)
			(xy 410.687825 -148.086119) (xy 410.706062 -148.107146) (xy 418.927534 -148.107146) (xy 418.952494 -148.10773)
			(xy 419.001457 -148.117454) (xy 419.047575 -148.13656) (xy 419.08907 -148.164311) (xy 419.107112 -148.181568)
			(xy 421.235886 -150.310342) (xy 421.253091 -150.328427) (xy 421.280828 -150.369917) (xy 421.299938 -150.416021)
			(xy 421.309689 -150.464966) (xy 421.310308 -150.48992) (xy 421.310308 -153.774902) (xy 436.385725 -153.774902)
			(xy 436.389718 -153.565161) (xy 436.401694 -153.355724) (xy 436.421635 -153.146895) (xy 436.449512 -152.938976)
			(xy 436.485284 -152.732269) (xy 436.528899 -152.527074) (xy 436.580295 -152.323689) (xy 436.639397 -152.122407)
			(xy 436.706119 -151.923521) (xy 436.780364 -151.72732) (xy 436.862024 -151.534088) (xy 436.950982 -151.344104)
			(xy 437.047109 -151.157645) (xy 437.150264 -150.974981) (xy 437.260299 -150.796376) (xy 437.377053 -150.62209)
			(xy 437.500358 -150.452375) (xy 437.630035 -150.287477) (xy 437.765896 -150.127636) (xy 437.907743 -149.973083)
			(xy 438.055372 -149.824043) (xy 438.208567 -149.68073) (xy 438.367108 -149.543354) (xy 438.530763 -149.412113)
			(xy 438.699297 -149.287198) (xy 438.872463 -149.16879) (xy 439.050013 -149.05706) (xy 439.231687 -148.95217)
			(xy 439.417222 -148.854273) (xy 439.60635 -148.763511) (xy 439.798797 -148.680014) (xy 439.994282 -148.603904)
			(xy 440.192524 -148.535292) (xy 440.393234 -148.474277) (xy 440.596121 -148.420948) (xy 440.800891 -148.375381)
			(xy 441.007248 -148.337642) (xy 441.214892 -148.307788) (xy 441.423522 -148.28586) (xy 441.632835 -148.271891)
			(xy 441.842529 -148.2659) (xy 442.052298 -148.267897) (xy 442.26184 -148.277879) (xy 442.47085 -148.295831)
			(xy 442.679024 -148.321727) (xy 442.886062 -148.355529) (xy 443.091663 -148.397189) (xy 443.295529 -148.446647)
			(xy 443.497364 -148.50383) (xy 443.696876 -148.568655) (xy 443.893775 -148.641029) (xy 444.087776 -148.720846)
			(xy 444.278598 -148.807992) (xy 444.465964 -148.902339) (xy 444.649602 -149.00375) (xy 444.829246 -149.11208)
			(xy 445.004636 -149.22717) (xy 445.175517 -149.348854) (xy 445.341641 -149.476955) (xy 445.502768 -149.611288)
			(xy 445.658665 -149.751657) (xy 445.809104 -149.89786) (xy 445.953868 -150.049684) (xy 446.092747 -150.20691)
			(xy 446.22554 -150.369309) (xy 446.352054 -150.536645) (xy 446.472106 -150.708677) (xy 446.585521 -150.885154)
			(xy 446.692135 -151.065822) (xy 446.791794 -151.250417) (xy 446.884353 -151.438672) (xy 446.969678 -151.630315)
			(xy 447.047645 -151.825067) (xy 447.118141 -152.022647) (xy 447.181064 -152.222766) (xy 447.236323 -152.425137)
			(xy 447.283837 -152.629464) (xy 447.323538 -152.835452) (xy 447.355368 -153.042803) (xy 447.379281 -153.251214)
			(xy 447.395242 -153.460385) (xy 447.403229 -153.670012) (xy 447.403728 -153.774902) (xy 447.403229 -153.879792)
			(xy 447.395242 -154.089419) (xy 447.379281 -154.29859) (xy 447.355368 -154.507001) (xy 447.323538 -154.714352)
			(xy 447.283837 -154.92034) (xy 447.236323 -155.124667) (xy 447.181064 -155.327038) (xy 447.118141 -155.527157)
			(xy 447.047645 -155.724737) (xy 446.969678 -155.919489) (xy 446.884353 -156.111132) (xy 446.791794 -156.299387)
			(xy 446.692135 -156.483982) (xy 446.585521 -156.66465) (xy 446.472106 -156.841127) (xy 446.352054 -157.013159)
			(xy 446.22554 -157.180495) (xy 446.092747 -157.342894) (xy 445.953868 -157.50012) (xy 445.809104 -157.651944)
			(xy 445.658665 -157.798147) (xy 445.502768 -157.938516) (xy 445.341641 -158.072849) (xy 445.175517 -158.20095)
			(xy 445.004636 -158.322634) (xy 444.829246 -158.437724) (xy 444.649602 -158.546054) (xy 444.465964 -158.647465)
			(xy 444.278598 -158.741812) (xy 444.087776 -158.828958) (xy 443.893775 -158.908775) (xy 443.696876 -158.981149)
			(xy 443.497364 -159.045974) (xy 443.295529 -159.103157) (xy 443.091663 -159.152615) (xy 442.886062 -159.194275)
			(xy 442.679024 -159.228077) (xy 442.47085 -159.253973) (xy 442.26184 -159.271925) (xy 442.052298 -159.281907)
			(xy 441.842529 -159.283904) (xy 441.632835 -159.277913) (xy 441.423522 -159.263944) (xy 441.214892 -159.242016)
			(xy 441.007248 -159.212162) (xy 440.800891 -159.174423) (xy 440.596121 -159.128856) (xy 440.393234 -159.075527)
			(xy 440.192524 -159.014512) (xy 439.994282 -158.9459) (xy 439.798797 -158.86979) (xy 439.60635 -158.786293)
			(xy 439.417222 -158.695531) (xy 439.231687 -158.597634) (xy 439.050013 -158.492744) (xy 438.872463 -158.381014)
			(xy 438.699297 -158.262606) (xy 438.530763 -158.137691) (xy 438.367108 -158.00645) (xy 438.208567 -157.869074)
			(xy 438.055372 -157.725761) (xy 437.907743 -157.576721) (xy 437.765896 -157.422168) (xy 437.630035 -157.262327)
			(xy 437.500358 -157.097429) (xy 437.377053 -156.927714) (xy 437.260299 -156.753428) (xy 437.150264 -156.574823)
			(xy 437.047109 -156.392159) (xy 436.950982 -156.2057) (xy 436.862024 -156.015716) (xy 436.780364 -155.822484)
			(xy 436.706119 -155.626283) (xy 436.639397 -155.427397) (xy 436.580295 -155.226115) (xy 436.528899 -155.02273)
			(xy 436.485284 -154.817535) (xy 436.449512 -154.610828) (xy 436.421635 -154.402909) (xy 436.401694 -154.19408)
			(xy 436.389718 -153.984643) (xy 436.385725 -153.774902) (xy 421.310308 -153.774902) (xy 421.310308 -157.585918)
			(xy 421.310816 -157.589728) (xy 421.312941 -157.60424) (xy 421.31523 -157.633482) (xy 421.315388 -157.648148)
			(xy 421.315228 -157.662814) (xy 421.312943 -157.692056) (xy 421.310816 -157.706568) (xy 421.310308 -157.710378)
			(xy 421.310308 -162.088068) (xy 421.335068 -162.099742) (xy 421.381259 -162.129115) (xy 421.422775 -162.164791)
			(xy 421.458763 -162.206037) (xy 421.488483 -162.252005) (xy 421.511325 -162.301751) (xy 421.526819 -162.354251)
			(xy 421.534646 -162.408428) (xy 421.534647 -162.463167) (xy 421.52682 -162.517344) (xy 421.511327 -162.569845)
			(xy 421.488485 -162.61959) (xy 421.458766 -162.665559) (xy 421.422778 -162.706805) (xy 421.381263 -162.742482)
			(xy 421.335072 -162.771856) (xy 421.310308 -162.78352) (xy 421.310308 -169.35323) (xy 421.594788 -169.63771)
			(xy 426.620432 -169.63771) (xy 426.636192 -169.597723) (xy 426.67435 -169.520702) (xy 426.719758 -169.44772)
			(xy 426.771992 -169.379457) (xy 426.830567 -169.31655) (xy 426.894936 -169.259586) (xy 426.964499 -169.209095)
			(xy 427.038606 -169.165548) (xy 427.116568 -169.129352) (xy 427.197658 -169.100843) (xy 427.281119 -169.080287)
			(xy 427.366173 -169.067877) (xy 427.452028 -169.063727) (xy 427.537883 -169.067877) (xy 427.622937 -169.080287)
			(xy 427.706398 -169.100843) (xy 427.787488 -169.129352) (xy 427.86545 -169.165548) (xy 427.939557 -169.209095)
			(xy 428.00912 -169.259586) (xy 428.073489 -169.31655) (xy 428.132064 -169.379457) (xy 428.184298 -169.44772)
			(xy 428.229706 -169.520702) (xy 428.267864 -169.597723) (xy 428.283624 -169.63771) (xy 442.700918 -169.63771)
			(xy 442.725877 -169.638313) (xy 442.774838 -169.648033) (xy 442.820956 -169.667134) (xy 442.862453 -169.694878)
			(xy 442.880496 -169.712132) (xy 443.525656 -170.357292) (xy 443.542911 -170.375335) (xy 443.57065 -170.416837)
			(xy 443.589759 -170.462953) (xy 443.599504 -170.511911) (xy 443.600078 -170.53687) (xy 443.600078 -194.497198)
			(xy 443.620781 -194.515774) (xy 443.65674 -194.558206) (xy 443.685659 -194.605715) (xy 443.706834 -194.657146)
			(xy 443.719749 -194.711245) (xy 443.72409 -194.766695) (xy 443.719751 -194.822144) (xy 443.706837 -194.876244)
			(xy 443.685664 -194.927675) (xy 443.656746 -194.975186) (xy 443.620788 -195.017619) (xy 443.600078 -195.036186)
			(xy 443.600078 -195.347082) (xy 443.620765 -195.365675) (xy 443.656724 -195.408104) (xy 443.685644 -195.455612)
			(xy 443.706819 -195.50704) (xy 443.719736 -195.561137) (xy 443.724078 -195.616584) (xy 443.719741 -195.672032)
			(xy 443.706829 -195.72613) (xy 443.685658 -195.77756) (xy 443.656742 -195.82507) (xy 443.620787 -195.867503)
			(xy 443.600078 -195.88607) (xy 443.600078 -197.047104) (xy 443.620787 -197.065673) (xy 443.656746 -197.108106)
			(xy 443.685665 -197.155617) (xy 443.70684 -197.207049) (xy 443.719754 -197.261148) (xy 443.724095 -197.316599)
			(xy 443.719755 -197.372049) (xy 443.70684 -197.426149) (xy 443.685666 -197.477581) (xy 443.656747 -197.525092)
			(xy 443.620789 -197.567525) (xy 443.600078 -197.586092) (xy 443.600078 -198.747126) (xy 443.620809 -198.765672)
			(xy 443.656768 -198.808108) (xy 443.685686 -198.855622) (xy 443.70686 -198.907057) (xy 443.719773 -198.96116)
			(xy 443.724111 -199.016613) (xy 443.719769 -199.072066) (xy 443.706852 -199.126168) (xy 443.685674 -199.177601)
			(xy 443.656753 -199.225113) (xy 443.620791 -199.267547) (xy 443.600078 -199.286114) (xy 443.600078 -201.297286)
			(xy 443.620769 -201.315875) (xy 443.656728 -201.358305) (xy 443.685647 -201.405813) (xy 443.706823 -201.457242)
			(xy 443.719739 -201.511339) (xy 443.724081 -201.566787) (xy 443.719743 -201.622235) (xy 443.706831 -201.676334)
			(xy 443.685659 -201.727764) (xy 443.656743 -201.775274) (xy 443.620787 -201.817707) (xy 443.600078 -201.836274)
			(xy 443.600078 -202.997308) (xy 443.620791 -203.015873) (xy 443.65675 -203.058307) (xy 443.685669 -203.105818)
			(xy 443.706843 -203.15725) (xy 443.719758 -203.21135) (xy 443.724098 -203.266801) (xy 443.719757 -203.322252)
			(xy 443.706843 -203.376352) (xy 443.685668 -203.427784) (xy 443.656748 -203.475296) (xy 443.620789 -203.517729)
			(xy 443.600078 -203.536296) (xy 443.600078 -204.697076) (xy 443.620759 -204.715675) (xy 443.656718 -204.758104)
			(xy 443.685638 -204.80561) (xy 443.706814 -204.857038) (xy 443.719731 -204.911134) (xy 443.724074 -204.96658)
			(xy 443.719737 -205.022028) (xy 443.706826 -205.076125) (xy 443.685655 -205.127555) (xy 443.656741 -205.175064)
			(xy 443.620787 -205.217497) (xy 443.600078 -205.236064) (xy 443.600078 -206.397098) (xy 443.620781 -206.415674)
			(xy 443.65674 -206.458106) (xy 443.685659 -206.505615) (xy 443.706834 -206.557046) (xy 443.719749 -206.611145)
			(xy 443.72409 -206.666595) (xy 443.719751 -206.722044) (xy 443.706837 -206.776144) (xy 443.685664 -206.827575)
			(xy 443.656746 -206.875086) (xy 443.620788 -206.917519) (xy 443.600078 -206.936086) (xy 443.600078 -208.09712)
			(xy 443.620803 -208.115672) (xy 443.656762 -208.158108) (xy 443.68568 -208.205621) (xy 443.706854 -208.257055)
			(xy 443.719768 -208.311157) (xy 443.724107 -208.366609) (xy 443.719765 -208.422061) (xy 443.706849 -208.476163)
			(xy 443.685672 -208.527596) (xy 443.656751 -208.575107) (xy 443.62079 -208.617541) (xy 443.600078 -208.636108)
			(xy 443.600078 -210.64728) (xy 443.620763 -210.665875) (xy 443.656722 -210.708304) (xy 443.685642 -210.755811)
			(xy 443.706818 -210.807239) (xy 443.719734 -210.861336) (xy 443.724077 -210.916783) (xy 443.719739 -210.972231)
			(xy 443.706828 -211.026328) (xy 443.685657 -211.077759) (xy 443.656742 -211.125268) (xy 443.620787 -211.167701)
			(xy 443.600078 -211.186268) (xy 443.600078 -212.347302) (xy 443.620785 -212.365874) (xy 443.656744 -212.408306)
			(xy 443.685663 -212.455816) (xy 443.706838 -212.507248) (xy 443.719753 -212.561347) (xy 443.724093 -212.616797)
			(xy 443.719754 -212.672248) (xy 443.706839 -212.726347) (xy 443.685665 -212.777779) (xy 443.656747 -212.82529)
			(xy 443.620789 -212.867723) (xy 443.600078 -212.88629) (xy 443.600078 -214.04707) (xy 443.620753 -214.065676)
			(xy 443.656712 -214.108103) (xy 443.685632 -214.155609) (xy 443.706808 -214.207035) (xy 443.719726 -214.26113)
			(xy 443.724069 -214.316576) (xy 443.719733 -214.372023) (xy 443.706823 -214.42612) (xy 443.685653 -214.477549)
			(xy 443.65674 -214.525059) (xy 443.620786 -214.567491) (xy 443.600078 -214.586058) (xy 443.600078 -215.747092)
			(xy 443.620775 -215.765674) (xy 443.656734 -215.808105) (xy 443.685653 -215.855614) (xy 443.706829 -215.907044)
			(xy 443.719744 -215.961142) (xy 443.724086 -216.016591) (xy 443.719747 -216.07204) (xy 443.706834 -216.126139)
			(xy 443.685661 -216.17757) (xy 443.656745 -216.22508) (xy 443.620788 -216.267513) (xy 443.600078 -216.28608)
			(xy 443.600078 -217.447114) (xy 443.620797 -217.465673) (xy 443.656756 -217.508107) (xy 443.685675 -217.555619)
			(xy 443.706849 -217.607052) (xy 443.719763 -217.661154) (xy 443.724102 -217.716605) (xy 443.719761 -217.772057)
			(xy 443.706846 -217.826158) (xy 443.68567 -217.87759) (xy 443.65675 -217.925101) (xy 443.62079 -217.967535)
			(xy 443.600078 -217.986102) (xy 443.600078 -219.997274) (xy 443.620757 -220.015875) (xy 443.656716 -220.058304)
			(xy 443.685636 -220.10581) (xy 443.706812 -220.157237) (xy 443.719729 -220.211332) (xy 443.724072 -220.266779)
			(xy 443.719735 -220.322226) (xy 443.706825 -220.376323) (xy 443.685655 -220.427753) (xy 443.65674 -220.475263)
			(xy 443.620787 -220.517695) (xy 443.600078 -220.536262) (xy 443.600078 -221.697296) (xy 443.620779 -221.715874)
			(xy 443.656738 -221.758305) (xy 443.685657 -221.805815) (xy 443.706832 -221.857245) (xy 443.719748 -221.911344)
			(xy 443.724089 -221.966793) (xy 443.71975 -222.022243) (xy 443.706836 -222.076342) (xy 443.685663 -222.127773)
			(xy 443.656746 -222.175284) (xy 443.620788 -222.217717) (xy 443.600078 -222.236284) (xy 443.600078 -223.397064)
			(xy 443.620747 -223.415676) (xy 443.656706 -223.458103) (xy 443.685626 -223.505607) (xy 443.706803 -223.557033)
			(xy 443.71972 -223.611127) (xy 443.724064 -223.666573) (xy 443.719729 -223.722019) (xy 443.70682 -223.776115)
			(xy 443.685651 -223.827544) (xy 443.656738 -223.875053) (xy 443.620786 -223.917485) (xy 443.600078 -223.936052)
			(xy 443.600078 -225.097086) (xy 443.620769 -225.115675) (xy 443.656728 -225.158105) (xy 443.685647 -225.205613)
			(xy 443.706823 -225.257042) (xy 443.719739 -225.311139) (xy 443.724081 -225.366587) (xy 443.719743 -225.422035)
			(xy 443.706831 -225.476134) (xy 443.685659 -225.527564) (xy 443.656743 -225.575074) (xy 443.620787 -225.617507)
			(xy 443.600078 -225.636074) (xy 443.600078 -226.797108) (xy 443.620791 -226.815673) (xy 443.65675 -226.858107)
			(xy 443.685669 -226.905618) (xy 443.706843 -226.95705) (xy 443.719758 -227.01115) (xy 443.724098 -227.066601)
			(xy 443.719757 -227.122052) (xy 443.706843 -227.176152) (xy 443.685668 -227.227584) (xy 443.656748 -227.275096)
			(xy 443.620789 -227.317529) (xy 443.600078 -227.336096) (xy 443.600078 -229.347268) (xy 443.620751 -229.365876)
			(xy 443.65671 -229.408303) (xy 443.68563 -229.455808) (xy 443.706806 -229.507235) (xy 443.719724 -229.561329)
			(xy 443.724067 -229.616775) (xy 443.719732 -229.672222) (xy 443.706822 -229.726318) (xy 443.685652 -229.777747)
			(xy 443.656739 -229.825257) (xy 443.620786 -229.867689) (xy 443.600078 -229.886256) (xy 443.600078 -231.04729)
			(xy 443.620773 -231.065874) (xy 443.656732 -231.108305) (xy 443.685651 -231.155814) (xy 443.706827 -231.207243)
			(xy 443.719743 -231.261341) (xy 443.724084 -231.31679) (xy 443.719746 -231.372238) (xy 443.706833 -231.426337)
			(xy 443.685661 -231.477768) (xy 443.656744 -231.525278) (xy 443.620788 -231.567711) (xy 443.600078 -231.586278)
			(xy 443.600078 -232.747312) (xy 443.620795 -232.765873) (xy 443.656754 -232.808307) (xy 443.685673 -232.855819)
			(xy 443.706847 -232.907252) (xy 443.719761 -232.961353) (xy 443.724101 -233.016804) (xy 443.71976 -233.072255)
			(xy 443.706845 -233.126356) (xy 443.685669 -233.177788) (xy 443.656749 -233.225299) (xy 443.620789 -233.267733)
			(xy 443.600078 -233.2863) (xy 443.600078 -234.44708) (xy 443.620763 -234.465675) (xy 443.656722 -234.508104)
			(xy 443.685642 -234.555611) (xy 443.706818 -234.607039) (xy 443.719734 -234.661136) (xy 443.724077 -234.716583)
			(xy 443.719739 -234.772031) (xy 443.706828 -234.826128) (xy 443.685657 -234.877559) (xy 443.656742 -234.925068)
			(xy 443.620787 -234.967501) (xy 443.600078 -234.986068) (xy 443.600078 -236.147102) (xy 443.620785 -236.165674)
			(xy 443.656744 -236.208106) (xy 443.685663 -236.255616) (xy 443.706838 -236.307048) (xy 443.719753 -236.361147)
			(xy 443.724093 -236.416597) (xy 443.719754 -236.472048) (xy 443.706839 -236.526147) (xy 443.685665 -236.577579)
			(xy 443.656747 -236.62509) (xy 443.620789 -236.667523) (xy 443.600078 -236.68609) (xy 443.600078 -238.697262)
			(xy 443.620745 -238.715876) (xy 443.656704 -238.758303) (xy 443.685624 -238.805807) (xy 443.706801 -238.857232)
			(xy 443.719719 -238.911326) (xy 443.724063 -238.966771) (xy 443.719728 -239.022217) (xy 443.706819 -239.076313)
			(xy 443.68565 -239.127742) (xy 443.656738 -239.175251) (xy 443.620786 -239.217683) (xy 443.600078 -239.23625)
			(xy 443.600078 -240.397284) (xy 443.620767 -240.415875) (xy 443.656726 -240.458304) (xy 443.685645 -240.505812)
			(xy 443.706821 -240.557241) (xy 443.719737 -240.611338) (xy 443.72408 -240.666786) (xy 443.719742 -240.722234)
			(xy 443.70683 -240.776332) (xy 443.685658 -240.827762) (xy 443.656743 -240.875272) (xy 443.620787 -240.917705)
			(xy 443.600078 -240.936272) (xy 443.600078 -242.097306) (xy 443.620789 -242.115873) (xy 443.656748 -242.158306)
			(xy 443.685667 -242.205817) (xy 443.706841 -242.257249) (xy 443.719756 -242.311349) (xy 443.724096 -242.3668)
			(xy 443.719756 -242.422251) (xy 443.706841 -242.476351) (xy 443.685667 -242.527783) (xy 443.656748 -242.575294)
			(xy 443.620789 -242.617727) (xy 443.600078 -242.636294) (xy 443.600078 -242.98529) (xy 443.617828 -243.003876)
			(xy 443.647943 -243.045516) (xy 443.671199 -243.091342) (xy 443.687026 -243.140233) (xy 443.695039 -243.190994)
			(xy 443.695041 -243.242383) (xy 443.687032 -243.293145) (xy 443.671207 -243.342037) (xy 443.647955 -243.387864)
			(xy 443.617842 -243.429507) (xy 443.600078 -243.448078) (xy 443.600078 -243.835174) (xy 443.617812 -243.853774)
			(xy 443.647927 -243.895412) (xy 443.671184 -243.941236) (xy 443.687013 -243.990125) (xy 443.695027 -244.040884)
			(xy 443.69503 -244.092271) (xy 443.687023 -244.143031) (xy 443.671201 -244.191922) (xy 443.647951 -244.237749)
			(xy 443.617841 -244.279391) (xy 443.600078 -244.297962) (xy 443.600078 -244.647212) (xy 443.620795 -244.665773)
			(xy 443.656754 -244.708207) (xy 443.685673 -244.755719) (xy 443.706847 -244.807152) (xy 443.719761 -244.861253)
			(xy 443.724101 -244.916704) (xy 443.71976 -244.972155) (xy 443.706845 -245.026256) (xy 443.685669 -245.077688)
			(xy 443.656749 -245.125199) (xy 443.620789 -245.167633) (xy 443.600078 -245.1862) (xy 443.600078 -245.535196)
			(xy 443.617834 -245.553776) (xy 443.647949 -245.595418) (xy 443.671204 -245.641245) (xy 443.687031 -245.690137)
			(xy 443.695044 -245.740898) (xy 443.695045 -245.792288) (xy 443.687035 -245.84305) (xy 443.67121 -245.891942)
			(xy 443.647956 -245.93777) (xy 443.617843 -245.979413) (xy 443.600078 -245.997984) (xy 443.600078 -246.347234)
			(xy 443.620817 -246.365771) (xy 443.656776 -246.408209) (xy 443.685694 -246.455724) (xy 443.706867 -246.50716)
			(xy 443.71978 -246.561264) (xy 443.724117 -246.616718) (xy 443.719774 -246.672172) (xy 443.706856 -246.726275)
			(xy 443.685677 -246.777708) (xy 443.656754 -246.825221) (xy 443.620791 -246.867655) (xy 443.600078 -246.886222)
			(xy 443.600078 -248.047256) (xy 443.620839 -248.06577) (xy 443.656798 -248.108211) (xy 443.685715 -248.155729)
			(xy 443.706888 -248.207169) (xy 443.719799 -248.261276) (xy 443.724134 -248.316733) (xy 443.719788 -248.372189)
			(xy 443.706867 -248.426293) (xy 443.685686 -248.477729) (xy 443.656759 -248.525242) (xy 443.620793 -248.567677)
			(xy 443.600078 -248.586244) (xy 443.600078 -249.747278) (xy 443.620761 -249.765875) (xy 443.65672 -249.808304)
			(xy 443.68564 -249.855811) (xy 443.706816 -249.907238) (xy 443.719732 -249.961335) (xy 443.724075 -250.016782)
			(xy 443.719738 -250.072229) (xy 443.706827 -250.126327) (xy 443.685656 -250.177757) (xy 443.656741 -250.225266)
			(xy 443.620787 -250.267699) (xy 443.600078 -250.286266) (xy 443.600078 -251.4473) (xy 443.620783 -251.465874)
			(xy 443.656742 -251.508306) (xy 443.685661 -251.555816) (xy 443.706836 -251.607247) (xy 443.719751 -251.661346)
			(xy 443.724092 -251.716796) (xy 443.719752 -251.772246) (xy 443.706838 -251.826346) (xy 443.685665 -251.877777)
			(xy 443.656746 -251.925288) (xy 443.620789 -251.967721) (xy 443.600078 -251.986288) (xy 443.600078 -258.247134)
			(xy 443.620817 -258.265671) (xy 443.656776 -258.308109) (xy 443.685694 -258.355624) (xy 443.706867 -258.40706)
			(xy 443.71978 -258.461164) (xy 443.724117 -258.516618) (xy 443.719774 -258.572072) (xy 443.706856 -258.626175)
			(xy 443.685677 -258.677608) (xy 443.656754 -258.725121) (xy 443.620791 -258.767555) (xy 443.600078 -258.786122)
			(xy 443.600078 -259.947156) (xy 443.620839 -259.96567) (xy 443.656798 -260.008111) (xy 443.685715 -260.055629)
			(xy 443.706888 -260.107069) (xy 443.719799 -260.161176) (xy 443.724134 -260.216633) (xy 443.719788 -260.272089)
			(xy 443.706867 -260.326193) (xy 443.685686 -260.377629) (xy 443.656759 -260.425142) (xy 443.620793 -260.467577)
			(xy 443.600078 -260.486144) (xy 443.600078 -261.647178) (xy 443.620761 -261.665775) (xy 443.65672 -261.708204)
			(xy 443.68564 -261.755711) (xy 443.706816 -261.807138) (xy 443.719732 -261.861235) (xy 443.724075 -261.916682)
			(xy 443.719738 -261.972129) (xy 443.706827 -262.026227) (xy 443.685656 -262.077657) (xy 443.656741 -262.125166)
			(xy 443.620787 -262.167599) (xy 443.600078 -262.186166) (xy 443.600078 -263.3472) (xy 443.620783 -263.365774)
			(xy 443.656742 -263.408206) (xy 443.685661 -263.455716) (xy 443.706836 -263.507147) (xy 443.719751 -263.561246)
			(xy 443.724092 -263.616696) (xy 443.719752 -263.672146) (xy 443.706838 -263.726246) (xy 443.685665 -263.777677)
			(xy 443.656746 -263.825188) (xy 443.620789 -263.867621) (xy 443.600078 -263.886188) (xy 443.600078 -265.047222)
			(xy 443.620805 -265.065772) (xy 443.656764 -265.108208) (xy 443.685682 -265.155721) (xy 443.706856 -265.207156)
			(xy 443.71977 -265.261258) (xy 443.724108 -265.31671) (xy 443.719766 -265.372163) (xy 443.70685 -265.426264)
			(xy 443.685673 -265.477697) (xy 443.656752 -265.525209) (xy 443.62079 -265.567643) (xy 443.600078 -265.58621)
			(xy 443.600078 -266.747244) (xy 443.620827 -266.765771) (xy 443.656786 -266.80821) (xy 443.685704 -266.855727)
			(xy 443.706876 -266.907164) (xy 443.719788 -266.961269) (xy 443.724125 -267.016725) (xy 443.719781 -267.07218)
			(xy 443.706861 -267.126283) (xy 443.685681 -267.177718) (xy 443.656757 -267.225231) (xy 443.620792 -267.267665)
			(xy 443.600078 -267.286232) (xy 443.600078 -267.635228) (xy 443.617866 -267.653779) (xy 443.64798 -267.695425)
			(xy 443.671234 -267.741257) (xy 443.687059 -267.790153) (xy 443.695068 -267.840919) (xy 443.695065 -267.892312)
			(xy 443.687051 -267.943077) (xy 443.671222 -267.991972) (xy 443.647964 -268.037801) (xy 443.617845 -268.079445)
			(xy 443.600078 -268.098016) (xy 443.600078 -268.447266) (xy 443.620749 -268.465876) (xy 443.656708 -268.508303)
			(xy 443.685628 -268.555808) (xy 443.706805 -268.607234) (xy 443.719722 -268.661328) (xy 443.724066 -268.716774)
			(xy 443.71973 -268.77222) (xy 443.706821 -268.826316) (xy 443.685652 -268.877746) (xy 443.656739 -268.925255)
			(xy 443.620786 -268.967687) (xy 443.600078 -268.986254) (xy 443.600078 -270.147288) (xy 443.620771 -270.165874)
			(xy 443.65673 -270.208305) (xy 443.685649 -270.255813) (xy 443.706825 -270.307242) (xy 443.719741 -270.36134)
			(xy 443.724083 -270.416788) (xy 443.719744 -270.472237) (xy 443.706832 -270.526335) (xy 443.68566 -270.577766)
			(xy 443.656744 -270.625276) (xy 443.620788 -270.667709) (xy 443.600078 -270.686276) (xy 443.600078 -271.84731)
			(xy 443.620793 -271.865873) (xy 443.656752 -271.908307) (xy 443.685671 -271.955818) (xy 443.706845 -272.007251)
			(xy 443.71976 -272.061352) (xy 443.724099 -272.116803) (xy 443.719759 -272.172254) (xy 443.706844 -272.226354)
			(xy 443.685668 -272.277786) (xy 443.656749 -272.325298) (xy 443.620789 -272.367731) (xy 443.600078 -272.386298)
			(xy 443.600078 -273.547078) (xy 443.620761 -273.565675) (xy 443.65672 -273.608104) (xy 443.68564 -273.655611)
			(xy 443.706816 -273.707038) (xy 443.719732 -273.761135) (xy 443.724075 -273.816582) (xy 443.719738 -273.872029)
			(xy 443.706827 -273.926127) (xy 443.685656 -273.977557) (xy 443.656741 -274.025066) (xy 443.620787 -274.067499)
			(xy 443.600078 -274.086066) (xy 443.600078 -276.097238) (xy 443.620821 -276.115771) (xy 443.65678 -276.158209)
			(xy 443.685698 -276.205725) (xy 443.706871 -276.257162) (xy 443.719783 -276.311266) (xy 443.72412 -276.366721)
			(xy 443.719777 -276.422175) (xy 443.706858 -276.476278) (xy 443.685679 -276.527712) (xy 443.656755 -276.575225)
			(xy 443.620791 -276.617659) (xy 443.600078 -276.636226) (xy 443.600078 -277.79726) (xy 443.620743 -277.815876)
			(xy 443.656702 -277.858302) (xy 443.685622 -277.905806) (xy 443.706799 -277.957231) (xy 443.719717 -278.011325)
			(xy 443.724061 -278.06677) (xy 443.719726 -278.122215) (xy 443.706818 -278.176311) (xy 443.685649 -278.22774)
			(xy 443.656737 -278.275249) (xy 443.620785 -278.317681) (xy 443.600078 -278.336248) (xy 443.600078 -279.497282)
			(xy 443.620765 -279.515875) (xy 443.656724 -279.558304) (xy 443.685644 -279.605812) (xy 443.706819 -279.65724)
			(xy 443.719736 -279.711337) (xy 443.724078 -279.766784) (xy 443.719741 -279.822232) (xy 443.706829 -279.87633)
			(xy 443.685658 -279.92776) (xy 443.656742 -279.97527) (xy 443.620787 -280.017703) (xy 443.600078 -280.03627)
			(xy 443.600078 -281.197304) (xy 443.620787 -281.215873) (xy 443.656746 -281.258306) (xy 443.685665 -281.305817)
			(xy 443.70684 -281.357249) (xy 443.719754 -281.411348) (xy 443.724095 -281.466799) (xy 443.719755 -281.522249)
			(xy 443.70684 -281.576349) (xy 443.685666 -281.627781) (xy 443.656747 -281.675292) (xy 443.620789 -281.717725)
			(xy 443.600078 -281.736292) (xy 443.600078 -282.897072) (xy 443.620755 -282.915676) (xy 443.656714 -282.958103)
			(xy 443.685634 -283.005609) (xy 443.70681 -283.057036) (xy 443.719727 -283.111131) (xy 443.72407 -283.166578)
			(xy 443.719734 -283.222025) (xy 443.706824 -283.276122) (xy 443.685654 -283.327551) (xy 443.65674 -283.375061)
			(xy 443.620786 -283.417493) (xy 443.600078 -283.43606) (xy 443.600078 -285.447232) (xy 443.620815 -285.465771)
			(xy 443.656774 -285.508209) (xy 443.685692 -285.555724) (xy 443.706865 -285.607159) (xy 443.719778 -285.661263)
			(xy 443.724116 -285.716717) (xy 443.719773 -285.77217) (xy 443.706855 -285.826273) (xy 443.685677 -285.877707)
			(xy 443.656754 -285.925219) (xy 443.620791 -285.967653) (xy 443.600078 -285.98622) (xy 443.600078 -287.147254)
			(xy 443.620837 -287.16577) (xy 443.656796 -287.208211) (xy 443.685713 -287.255729) (xy 443.706886 -287.307168)
			(xy 443.719797 -287.361275) (xy 443.724133 -287.416731) (xy 443.719787 -287.472187) (xy 443.706866 -287.526292)
			(xy 443.685685 -287.577727) (xy 443.656759 -287.62524) (xy 443.620793 -287.667675) (xy 443.600078 -287.686242)
			(xy 443.600078 -288.847276) (xy 443.620759 -288.865875) (xy 443.656718 -288.908304) (xy 443.685638 -288.95581)
			(xy 443.706814 -289.007238) (xy 443.719731 -289.061334) (xy 443.724074 -289.11678) (xy 443.719737 -289.172228)
			(xy 443.706826 -289.226325) (xy 443.685655 -289.277755) (xy 443.656741 -289.325264) (xy 443.620787 -289.367697)
			(xy 443.600078 -289.386264) (xy 443.600078 -290.547298) (xy 443.620781 -290.565874) (xy 443.65674 -290.608306)
			(xy 443.685659 -290.655815) (xy 443.706834 -290.707246) (xy 443.719749 -290.761345) (xy 443.72409 -290.816795)
			(xy 443.719751 -290.872244) (xy 443.706837 -290.926344) (xy 443.685664 -290.977775) (xy 443.656746 -291.025286)
			(xy 443.620788 -291.067719) (xy 443.600078 -291.086286) (xy 443.600078 -292.24732) (xy 443.620803 -292.265872)
			(xy 443.656762 -292.308308) (xy 443.68568 -292.355821) (xy 443.706854 -292.407255) (xy 443.719768 -292.461357)
			(xy 443.724107 -292.516809) (xy 443.719765 -292.572261) (xy 443.706849 -292.626363) (xy 443.685672 -292.677796)
			(xy 443.656751 -292.725307) (xy 443.62079 -292.767741) (xy 443.600078 -292.786308) (xy 443.600078 -294.797226)
			(xy 443.620809 -294.815772) (xy 443.656768 -294.858208) (xy 443.685686 -294.905722) (xy 443.70686 -294.957157)
			(xy 443.719773 -295.01126) (xy 443.724111 -295.066713) (xy 443.719769 -295.122166) (xy 443.706852 -295.176268)
			(xy 443.685674 -295.227701) (xy 443.656753 -295.275213) (xy 443.620791 -295.317647) (xy 443.600078 -295.336214)
			(xy 443.600078 -296.497248) (xy 443.620831 -296.51577) (xy 443.65679 -296.55821) (xy 443.685708 -296.605728)
			(xy 443.70688 -296.657166) (xy 443.719792 -296.711272) (xy 443.724128 -296.766727) (xy 443.719783 -296.822183)
			(xy 443.706863 -296.876287) (xy 443.685683 -296.927721) (xy 443.656758 -296.975235) (xy 443.620792 -297.017669)
			(xy 443.600078 -297.036236) (xy 443.600078 -298.19727) (xy 443.620753 -298.215876) (xy 443.656712 -298.258303)
			(xy 443.685632 -298.305809) (xy 443.706808 -298.357235) (xy 443.719726 -298.41133) (xy 443.724069 -298.466776)
			(xy 443.719733 -298.522223) (xy 443.706823 -298.57632) (xy 443.685653 -298.627749) (xy 443.65674 -298.675259)
			(xy 443.620786 -298.717691) (xy 443.600078 -298.736258) (xy 443.600078 -299.897292) (xy 443.620775 -299.915874)
			(xy 443.656734 -299.958305) (xy 443.685653 -300.005814) (xy 443.706829 -300.057244) (xy 443.719744 -300.111342)
			(xy 443.724086 -300.166791) (xy 443.719747 -300.22224) (xy 443.706834 -300.276339) (xy 443.685661 -300.32777)
			(xy 443.656745 -300.37528) (xy 443.620788 -300.417713) (xy 443.600078 -300.43628) (xy 443.600078 -301.597314)
			(xy 443.620797 -301.615873) (xy 443.656756 -301.658307) (xy 443.685675 -301.705819) (xy 443.706849 -301.757252)
			(xy 443.719763 -301.811354) (xy 443.724102 -301.866805) (xy 443.719761 -301.922257) (xy 443.706846 -301.976358)
			(xy 443.68567 -302.02779) (xy 443.65675 -302.075301) (xy 443.62079 -302.117735) (xy 443.600078 -302.136302)
			(xy 443.600078 -304.14722) (xy 443.620803 -304.165772) (xy 443.656762 -304.208208) (xy 443.68568 -304.255721)
			(xy 443.706854 -304.307155) (xy 443.719768 -304.361257) (xy 443.724107 -304.416709) (xy 443.719765 -304.472161)
			(xy 443.706849 -304.526263) (xy 443.685672 -304.577696) (xy 443.656751 -304.625207) (xy 443.62079 -304.667641)
			(xy 443.600078 -304.686208) (xy 443.600078 -305.847242) (xy 443.620825 -305.865771) (xy 443.656784 -305.908209)
			(xy 443.685702 -305.955726) (xy 443.706875 -306.007163) (xy 443.719787 -306.061268) (xy 443.724124 -306.116724)
			(xy 443.719779 -306.172178) (xy 443.70686 -306.226281) (xy 443.68568 -306.277716) (xy 443.656756 -306.325229)
			(xy 443.620792 -306.367663) (xy 443.600078 -306.38623) (xy 443.600078 -307.547264) (xy 443.620747 -307.565876)
			(xy 443.656706 -307.608303) (xy 443.685626 -307.655807) (xy 443.706803 -307.707233) (xy 443.71972 -307.761327)
			(xy 443.724064 -307.816773) (xy 443.719729 -307.872219) (xy 443.70682 -307.926315) (xy 443.685651 -307.977744)
			(xy 443.656738 -308.025253) (xy 443.620786 -308.067685) (xy 443.600078 -308.086252) (xy 443.600078 -309.247286)
			(xy 443.620769 -309.265875) (xy 443.656728 -309.308305) (xy 443.685647 -309.355813) (xy 443.706823 -309.407242)
			(xy 443.719739 -309.461339) (xy 443.724081 -309.516787) (xy 443.719743 -309.572235) (xy 443.706831 -309.626334)
			(xy 443.685659 -309.677764) (xy 443.656743 -309.725274) (xy 443.620787 -309.767707) (xy 443.600078 -309.786274)
			(xy 443.600078 -310.947308) (xy 443.620791 -310.965873) (xy 443.65675 -311.008307) (xy 443.685669 -311.055818)
			(xy 443.706843 -311.10725) (xy 443.719758 -311.16135) (xy 443.724098 -311.216801) (xy 443.719757 -311.272252)
			(xy 443.706843 -311.326352) (xy 443.685668 -311.377784) (xy 443.656748 -311.425296) (xy 443.620789 -311.467729)
			(xy 443.600078 -311.486296) (xy 443.600078 -312.07837) (xy 443.59951 -312.103331) (xy 443.58978 -312.152294)
			(xy 443.570669 -312.198412) (xy 443.542914 -312.239906) (xy 443.525656 -312.257948) (xy 442.761116 -313.022488)
			(xy 442.743049 -313.039713) (xy 442.701553 -313.067446) (xy 442.655443 -313.086551) (xy 442.606493 -313.096295)
			(xy 442.581538 -313.09691) (xy 442.440568 -313.09691) (xy 442.42675 -313.119484) (xy 442.39349 -313.160652)
			(xy 442.354504 -313.196444) (xy 442.31065 -313.226073) (xy 442.262893 -313.248885) (xy 442.212287 -313.264378)
			(xy 442.159944 -313.27221) (xy 442.10702 -313.27221) (xy 442.054677 -313.264378) (xy 442.004071 -313.248885)
			(xy 441.956314 -313.226073) (xy 441.91246 -313.196444) (xy 441.873474 -313.160652) (xy 441.840214 -313.119484)
			(xy 441.826396 -313.09691) (xy 440.230768 -313.09691) (xy 440.21695 -313.119484) (xy 440.18369 -313.160652)
			(xy 440.144704 -313.196444) (xy 440.10085 -313.226073) (xy 440.053093 -313.248885) (xy 440.002487 -313.264378)
			(xy 439.950144 -313.27221) (xy 439.89722 -313.27221) (xy 439.844877 -313.264378) (xy 439.794271 -313.248885)
			(xy 439.746514 -313.226073) (xy 439.70266 -313.196444) (xy 439.663674 -313.160652) (xy 439.630414 -313.119484)
			(xy 439.616596 -313.09691) (xy 436.09768 -313.09691) (xy 436.083575 -313.117523) (xy 436.050136 -313.154622)
			(xy 436.011458 -313.186221) (xy 435.968435 -313.21159) (xy 435.922063 -313.230141) (xy 435.873414 -313.241447)
			(xy 435.823614 -313.245245) (xy 435.773814 -313.241447) (xy 435.725165 -313.230141) (xy 435.678793 -313.21159)
			(xy 435.63577 -313.186221) (xy 435.597092 -313.154622) (xy 435.563653 -313.117523) (xy 435.549548 -313.09691)
			(xy 434.896768 -313.09691) (xy 434.88295 -313.119484) (xy 434.84969 -313.160652) (xy 434.810704 -313.196444)
			(xy 434.76685 -313.226073) (xy 434.719093 -313.248885) (xy 434.668487 -313.264378) (xy 434.616144 -313.27221)
			(xy 434.56322 -313.27221) (xy 434.510877 -313.264378) (xy 434.460271 -313.248885) (xy 434.412514 -313.226073)
			(xy 434.36866 -313.196444) (xy 434.329674 -313.160652) (xy 434.296414 -313.119484) (xy 434.282596 -313.09691)
			(xy 432.686968 -313.09691) (xy 432.67315 -313.119484) (xy 432.63989 -313.160652) (xy 432.600904 -313.196444)
			(xy 432.55705 -313.226073) (xy 432.509293 -313.248885) (xy 432.458687 -313.264378) (xy 432.406344 -313.27221)
			(xy 432.35342 -313.27221) (xy 432.301077 -313.264378) (xy 432.250471 -313.248885) (xy 432.202714 -313.226073)
			(xy 432.15886 -313.196444) (xy 432.119874 -313.160652) (xy 432.086614 -313.119484) (xy 432.072796 -313.09691)
			(xy 429.743616 -313.09691) (xy 429.429672 -313.410854) (xy 429.420119 -313.420177) (xy 429.399376 -313.436978)
			(xy 429.38827 -313.444382) (xy 429.365156 -313.459622) (xy 429.365156 -321.272408) (xy 429.381412 -321.287394)
			(xy 429.694848 -321.60083) (xy 452.871078 -321.60083) (xy 452.896039 -321.601391) (xy 452.945003 -321.611123)
			(xy 452.991121 -321.630236) (xy 453.032615 -321.657993) (xy 453.050656 -321.675252) (xy 453.383396 -322.007992)
			(xy 453.400626 -322.026054) (xy 453.428358 -322.067552) (xy 453.447462 -322.113663) (xy 453.457204 -322.162614)
			(xy 453.457818 -322.18757) (xy 453.457818 -327.949814) (xy 454.394316 -328.886312) (xy 454.411559 -328.904363)
			(xy 454.439288 -328.945865) (xy 454.458388 -328.991979) (xy 454.468126 -329.040933) (xy 454.468738 -329.06589)
			(xy 454.468738 -334.6069) (xy 454.4682 -334.631862) (xy 454.458462 -334.680828) (xy 454.439343 -334.726946)
			(xy 454.411579 -334.768438) (xy 454.394316 -334.786478) (xy 453.787002 -335.393792) (xy 453.768942 -335.411025)
			(xy 453.727443 -335.438756) (xy 453.681332 -335.457859) (xy 453.63238 -335.4676) (xy 453.607424 -335.468214)
			(xy 453.582278 -335.466944) (xy 453.579738 -335.46669) (xy 446.087754 -335.46669) (xy 445.639698 -335.914746)
			(xy 445.639698 -357.95585) (xy 445.63914 -357.980812) (xy 445.629411 -358.029777) (xy 445.610297 -358.075895)
			(xy 445.582537 -358.117388) (xy 445.565276 -358.135428) (xy 440.927236 -362.773468) (xy 440.909158 -362.790681)
			(xy 440.867666 -362.818417) (xy 440.82156 -362.837526) (xy 440.772612 -362.847273) (xy 440.747658 -362.84789)
			(xy 432.078384 -362.84789) (xy 432.070002 -362.888276) (xy 432.063889 -362.914976) (xy 432.04504 -362.966403)
			(xy 432.019032 -363.014608) (xy 431.986399 -363.058598) (xy 431.947811 -363.097471) (xy 431.904062 -363.130427)
			(xy 431.856051 -363.156789) (xy 431.804764 -363.176016) (xy 431.751254 -363.187713) (xy 431.696622 -363.191639)
			(xy 431.64199 -363.187713) (xy 431.58848 -363.176016) (xy 431.537193 -363.156789) (xy 431.489182 -363.130427)
			(xy 431.445433 -363.097471) (xy 431.406845 -363.058598) (xy 431.374212 -363.014608) (xy 431.348204 -362.966403)
			(xy 431.329355 -362.914976) (xy 431.323242 -362.888276) (xy 431.31486 -362.84789) (xy 425.9072 -362.84789)
			(xy 425.892484 -362.870357) (xy 425.857634 -362.911223) (xy 425.817277 -362.946659) (xy 425.772248 -362.975932)
			(xy 425.723482 -362.998434) (xy 425.67199 -363.0137) (xy 425.61884 -363.021411) (xy 425.591986 -363.02188)
			(xy 425.565565 -363.021411) (xy 425.513251 -363.013961) (xy 425.462513 -362.999198) (xy 425.414368 -362.977417)
			(xy 425.369782 -362.949055) (xy 425.349416 -362.932218) (xy 425.338146 -362.923235) (xy 425.311895 -362.911369)
			(xy 425.283376 -362.907306) (xy 425.254857 -362.911369) (xy 425.228606 -362.923235) (xy 425.217336 -362.932218)
			(xy 425.196947 -362.949027) (xy 425.152365 -362.977389) (xy 425.104226 -362.999175) (xy 425.053495 -363.01395)
			(xy 425.001186 -363.021416) (xy 424.974766 -363.02188) (xy 424.947827 -363.02143) (xy 424.894512 -363.013657)
			(xy 424.842874 -362.998277) (xy 424.793994 -362.975614) (xy 424.748892 -362.946139) (xy 424.728386 -362.928662)
			(xy 424.717008 -362.919272) (xy 424.690256 -362.906869) (xy 424.661076 -362.902617) (xy 424.631896 -362.906869)
			(xy 424.605144 -362.919272) (xy 424.593766 -362.928662) (xy 424.573226 -362.946093) (xy 424.528118 -362.975538)
			(xy 424.479244 -362.998189) (xy 424.42762 -363.013576) (xy 424.37432 -363.021379) (xy 424.347386 -363.02188)
			(xy 424.320535 -363.021382) (xy 424.26739 -363.013659) (xy 424.215904 -362.99839) (xy 424.167142 -362.975891)
			(xy 424.122113 -362.946626) (xy 424.08175 -362.911203) (xy 424.046888 -362.870354) (xy 424.032172 -362.84789)
			(xy 416.218878 -362.84789) (xy 416.204176 -362.870367) (xy 416.169324 -362.911233) (xy 416.128964 -362.946668)
			(xy 416.083934 -362.97594) (xy 416.035165 -362.998441) (xy 415.983671 -363.013704) (xy 415.930518 -363.021413)
			(xy 415.903664 -363.02188) (xy 415.877242 -363.021424) (xy 415.824928 -363.013971) (xy 415.77419 -362.999204)
			(xy 415.726045 -362.977421) (xy 415.68146 -362.949056) (xy 415.661094 -362.932218) (xy 415.649824 -362.923235)
			(xy 415.623573 -362.911369) (xy 415.595054 -362.907306) (xy 415.566535 -362.911369) (xy 415.540284 -362.923235)
			(xy 415.529014 -362.932218) (xy 415.508633 -362.949037) (xy 415.464049 -362.977398) (xy 415.415908 -362.999182)
			(xy 415.365175 -363.013954) (xy 415.312864 -363.021418) (xy 415.286444 -363.02188) (xy 415.259506 -363.021383)
			(xy 415.206193 -363.013621) (xy 415.154557 -362.998253) (xy 415.105676 -362.975599) (xy 415.060572 -362.946135)
			(xy 415.040064 -362.928662) (xy 415.028686 -362.919272) (xy 415.001934 -362.906869) (xy 414.972754 -362.902617)
			(xy 414.943574 -362.906869) (xy 414.916822 -362.919272) (xy 414.905444 -362.928662) (xy 414.884913 -362.946103)
			(xy 414.839802 -362.975547) (xy 414.790926 -362.998196) (xy 414.7393 -363.013581) (xy 414.685998 -363.02138)
			(xy 414.659064 -363.02188) (xy 414.632212 -363.021399) (xy 414.579067 -363.013673) (xy 414.52758 -362.998401)
			(xy 414.478818 -362.975899) (xy 414.43379 -362.946632) (xy 414.393427 -362.911206) (xy 414.358566 -362.870355)
			(xy 414.34385 -362.84789) (xy 384.424936 -362.84789) (xy 384.411304 -362.871037) (xy 384.37854 -362.913609)
			(xy 384.340129 -362.951163) (xy 384.29683 -362.982957) (xy 384.249498 -363.008363) (xy 384.19907 -363.026877)
			(xy 384.146544 -363.038135) (xy 384.092958 -363.041912) (xy 384.039372 -363.038135) (xy 383.986846 -363.026877)
			(xy 383.936418 -363.008363) (xy 383.889086 -362.982957) (xy 383.845787 -362.951163) (xy 383.807376 -362.913609)
			(xy 383.774612 -362.871037) (xy 383.76098 -362.84789) (xy 363.960918 -362.84789) (xy 363.944194 -362.869314)
			(xy 363.905683 -362.907663) (xy 363.862118 -362.940158) (xy 363.814383 -362.96614) (xy 363.763442 -362.985084)
			(xy 363.710329 -362.996606) (xy 363.656118 -363.000473) (xy 363.601907 -362.996606) (xy 363.548794 -362.985084)
			(xy 363.497853 -362.96614) (xy 363.450118 -362.940158) (xy 363.406553 -362.907663) (xy 363.368042 -362.869314)
			(xy 363.351318 -362.84789) (xy 354.349812 -362.84789) (xy 354.324851 -362.847329) (xy 354.275887 -362.837596)
			(xy 354.22977 -362.818483) (xy 354.188276 -362.790727) (xy 354.170234 -362.773468) (xy 354.105718 -362.708952)
			(xy 354.077524 -362.716064) (xy 354.054059 -362.721755) (xy 354.006162 -362.727868) (xy 353.98202 -362.728256)
			(xy 353.954771 -362.727703) (xy 353.900829 -362.719951) (xy 353.848538 -362.704601) (xy 353.798964 -362.681965)
			(xy 353.753116 -362.652506) (xy 353.711927 -362.616821) (xy 353.676235 -362.575638) (xy 353.646767 -362.529795)
			(xy 353.624123 -362.480226) (xy 353.608764 -362.427938) (xy 353.601002 -362.373996) (xy 353.600512 -362.346748)
			(xy 353.600881 -362.322605) (xy 353.607 -362.274707) (xy 353.612704 -362.251244) (xy 353.619816 -362.22305)
			(xy 353.340416 -361.94365) (xy 353.320832 -361.960695) (xy 353.277631 -361.989491) (xy 353.230684 -362.011659)
			(xy 353.181 -362.026722) (xy 353.129646 -362.034357) (xy 353.103688 -362.034836) (xy 353.10318 -362.034836)
			(xy 353.075392 -362.03437) (xy 353.020501 -362.025672) (xy 352.967646 -362.008495) (xy 352.91813 -361.983261)
			(xy 352.87317 -361.950591) (xy 352.833875 -361.91129) (xy 352.801212 -361.866326) (xy 352.775985 -361.816805)
			(xy 352.758815 -361.763948) (xy 352.750126 -361.709056) (xy 352.749612 -361.681268) (xy 352.749612 -361.68076)
			(xy 352.750109 -361.654802) (xy 352.757737 -361.603447) (xy 352.772792 -361.553761) (xy 352.794952 -361.50681)
			(xy 352.823739 -361.463604) (xy 352.840798 -361.444032) (xy 347.442536 -356.04577) (xy 337.985354 -356.04577)
			(xy 331.4065 -362.624624) (xy 331.388456 -362.641878) (xy 331.346955 -362.669618) (xy 331.300839 -362.688728)
			(xy 331.251881 -362.698472) (xy 331.226922 -362.699046) (xy 300.905926 -362.699046) (xy 300.885271 -362.717071)
			(xy 300.839665 -362.747489) (xy 300.790093 -362.770895) (xy 300.737628 -362.786786) (xy 300.6834 -362.794818)
			(xy 300.62858 -362.794818) (xy 300.574352 -362.786786) (xy 300.521887 -362.770895) (xy 300.472315 -362.747489)
			(xy 300.426709 -362.717071) (xy 300.406054 -362.699046) (xy 298.734226 -362.699046) (xy 298.713968 -362.715609)
			(xy 298.669686 -362.743487) (xy 298.621937 -362.76489) (xy 298.571662 -362.779398) (xy 298.519851 -362.786724)
			(xy 298.467525 -362.786724) (xy 298.415714 -362.779398) (xy 298.365439 -362.76489) (xy 298.31769 -362.743487)
			(xy 298.273408 -362.715609) (xy 298.25315 -362.699046) (xy 298.073826 -362.699046) (xy 298.053568 -362.715609)
			(xy 298.009286 -362.743487) (xy 297.961537 -362.76489) (xy 297.911262 -362.779398) (xy 297.859451 -362.786724)
			(xy 297.807125 -362.786724) (xy 297.755314 -362.779398) (xy 297.705039 -362.76489) (xy 297.65729 -362.743487)
			(xy 297.613008 -362.715609) (xy 297.59275 -362.699046) (xy 291.217604 -362.699046) (xy 291.196949 -362.717071)
			(xy 291.151343 -362.747489) (xy 291.101771 -362.770895) (xy 291.049306 -362.786786) (xy 290.995078 -362.794818)
			(xy 290.940258 -362.794818) (xy 290.88603 -362.786786) (xy 290.833565 -362.770895) (xy 290.783993 -362.747489)
			(xy 290.738387 -362.717071) (xy 290.717732 -362.699046) (xy 289.045904 -362.699046) (xy 289.025646 -362.715609)
			(xy 288.981364 -362.743487) (xy 288.933615 -362.76489) (xy 288.88334 -362.779398) (xy 288.831529 -362.786724)
			(xy 288.779203 -362.786724) (xy 288.727392 -362.779398) (xy 288.677117 -362.76489) (xy 288.629368 -362.743487)
			(xy 288.585086 -362.715609) (xy 288.564828 -362.699046) (xy 288.385504 -362.699046) (xy 288.365246 -362.715609)
			(xy 288.320964 -362.743487) (xy 288.273215 -362.76489) (xy 288.22294 -362.779398) (xy 288.171129 -362.786724)
			(xy 288.118803 -362.786724) (xy 288.066992 -362.779398) (xy 288.016717 -362.76489) (xy 287.968968 -362.743487)
			(xy 287.924686 -362.715609) (xy 287.904428 -362.699046) (xy 263.027922 -362.699046) (xy 262.990134 -362.793343)
			(xy 262.908311 -362.97931) (xy 262.819383 -363.161986) (xy 262.723482 -363.3411) (xy 262.620751 -363.516385)
			(xy 262.511341 -363.687582) (xy 262.395416 -363.854435) (xy 262.273148 -364.016698) (xy 262.144717 -364.174128)
			(xy 262.010316 -364.326493) (xy 261.870144 -364.473565) (xy 261.724408 -364.615127) (xy 261.573326 -364.750969)
			(xy 261.417121 -364.880887) (xy 261.256026 -365.00469) (xy 261.090281 -365.122194) (xy 260.92013 -365.233223)
			(xy 260.745828 -365.337614) (xy 260.567633 -365.43521) (xy 260.385809 -365.525868) (xy 260.200627 -365.609452)
			(xy 260.012361 -365.685838) (xy 259.821292 -365.754913) (xy 259.627704 -365.816574) (xy 259.431883 -365.870729)
			(xy 259.23412 -365.917299) (xy 259.03471 -365.956213) (xy 258.833949 -365.987415) (xy 258.632134 -366.010858)
			(xy 258.429566 -366.026506) (xy 258.226546 -366.034337) (xy 258.12496 -366.034828) (xy 258.021461 -366.034339)
			(xy 257.814622 -366.026211) (xy 257.608261 -366.009968) (xy 257.402697 -365.985637) (xy 257.198247 -365.953254)
			(xy 256.995226 -365.912869) (xy 256.793947 -365.864545) (xy 256.594721 -365.808356) (xy 256.397853 -365.744389)
			(xy 256.203649 -365.672742) (xy 256.012408 -365.593526) (xy 255.824424 -365.506864) (xy 255.639987 -365.412887)
			(xy 255.459382 -365.311743) (xy 255.282887 -365.203585) (xy 255.110774 -365.088583) (xy 254.943309 -364.966911)
			(xy 254.78075 -364.838759) (xy 254.623347 -364.704324) (xy 254.471343 -364.563813) (xy 254.324973 -364.417442)
			(xy 254.184463 -364.265438) (xy 254.050028 -364.108035) (xy 253.921877 -363.945475) (xy 253.800206 -363.77801)
			(xy 253.685204 -363.605896) (xy 253.577047 -363.429401) (xy 253.475903 -363.248795) (xy 253.381928 -363.064358)
			(xy 253.295266 -362.876374) (xy 253.21605 -362.685132) (xy 253.144404 -362.490928) (xy 253.080438 -362.29406)
			(xy 253.02425 -362.094833) (xy 252.975926 -361.893554) (xy 252.935543 -361.690533) (xy 252.90316 -361.486083)
			(xy 252.87883 -361.280519) (xy 252.862588 -361.074158) (xy 252.854461 -360.867319) (xy 252.853952 -360.76382)
			(xy 218.945968 -360.76382) (xy 218.945526 -360.86732) (xy 218.937398 -361.074161) (xy 218.921156 -361.280523)
			(xy 218.896825 -361.486088) (xy 218.864443 -361.690539) (xy 218.824058 -361.893562) (xy 218.775734 -362.094843)
			(xy 218.719545 -362.294071) (xy 218.655577 -362.490939) (xy 218.58393 -362.685145) (xy 218.504714 -362.876388)
			(xy 218.41805 -363.064373) (xy 218.324073 -363.248811) (xy 218.222927 -363.429417) (xy 218.114769 -363.605914)
			(xy 217.999765 -363.778027) (xy 217.878093 -363.945493) (xy 217.749939 -364.108053) (xy 217.615502 -364.265457)
			(xy 217.47499 -364.417461) (xy 217.328618 -364.563831) (xy 217.176612 -364.704342) (xy 217.019207 -364.838777)
			(xy 216.856645 -364.966929) (xy 216.689178 -365.0886) (xy 216.517063 -365.203602) (xy 216.340566 -365.311758)
			(xy 216.159958 -365.412901) (xy 215.975519 -365.506876) (xy 215.787533 -365.593538) (xy 215.596289 -365.672752)
			(xy 215.402083 -365.744397) (xy 215.205213 -365.808362) (xy 215.005985 -365.864549) (xy 214.804703 -365.912871)
			(xy 214.60168 -365.953253) (xy 214.397228 -365.985634) (xy 214.191663 -366.009962) (xy 213.985301 -366.026202)
			(xy 213.77846 -366.034327) (xy 213.67496 -366.034828) (xy 213.572213 -366.034308) (xy 213.366875 -366.026305)
			(xy 213.162006 -366.010305) (xy 212.957915 -365.986333) (xy 212.754914 -365.954424) (xy 212.553311 -365.914627)
			(xy 212.353412 -365.867003) (xy 212.155521 -365.811624) (xy 211.959939 -365.748574) (xy 211.766963 -365.67795)
			(xy 211.576886 -365.599857) (xy 211.389997 -365.514416) (xy 211.20658 -365.421755) (xy 211.026915 -365.322017)
			(xy 210.851273 -365.215351) (xy 210.679921 -365.101921) (xy 210.513121 -364.981899) (xy 210.351126 -364.855467)
			(xy 210.194181 -364.722816) (xy 210.042526 -364.58415) (xy 209.896391 -364.439679) (xy 209.755997 -364.289621)
			(xy 209.621559 -364.134206) (xy 209.49328 -363.973669) (xy 209.371355 -363.808254) (xy 209.255971 -363.638213)
			(xy 209.147301 -363.463803) (xy 209.045512 -363.285291) (xy 208.950757 -363.102948) (xy 208.863181 -362.91705)
			(xy 208.782918 -362.727879) (xy 208.710088 -362.535725) (xy 208.644803 -362.340877) (xy 208.587162 -362.143633)
			(xy 208.537252 -361.944293) (xy 208.515712 -361.843828) (xy 176.508918 -361.843828) (xy 176.486234 -361.857232)
			(xy 176.43799 -361.878409) (xy 176.387295 -361.892762) (xy 176.33511 -361.900018) (xy 176.308766 -361.90047)
			(xy 176.282418 -361.900047) (xy 176.23022 -361.892829) (xy 176.179516 -361.878481) (xy 176.131276 -361.857276)
			(xy 176.108614 -361.843828) (xy 175.746918 -361.843828) (xy 175.724234 -361.857232) (xy 175.67599 -361.878409)
			(xy 175.625295 -361.892762) (xy 175.57311 -361.900018) (xy 175.546766 -361.90047) (xy 175.520418 -361.900047)
			(xy 175.46822 -361.892829) (xy 175.417516 -361.878481) (xy 175.369276 -361.857276) (xy 175.346614 -361.843828)
			(xy 166.595298 -361.843828) (xy 166.582598 -361.87634) (xy 166.572535 -361.900878) (xy 166.546125 -361.946871)
			(xy 166.513142 -361.988402) (xy 166.474326 -362.024541) (xy 166.430546 -362.054476) (xy 166.382786 -362.077536)
			(xy 166.332118 -362.093202) (xy 166.279678 -362.101124) (xy 166.226642 -362.101124) (xy 166.174202 -362.093202)
			(xy 166.123534 -362.077536) (xy 166.075774 -362.054476) (xy 166.031994 -362.024541) (xy 165.993178 -361.988402)
			(xy 165.960195 -361.946871) (xy 165.933785 -361.900878) (xy 165.923722 -361.87634) (xy 165.911022 -361.843828)
			(xy 146.694652 -361.843828) (xy 146.681165 -361.867504) (xy 146.648505 -361.911118) (xy 146.609971 -361.949641)
			(xy 146.566348 -361.982289) (xy 146.518524 -362.008397) (xy 146.467471 -362.027435) (xy 146.414228 -362.039016)
			(xy 146.35988 -362.042902) (xy 146.305532 -362.039016) (xy 146.252289 -362.027435) (xy 146.201236 -362.008397)
			(xy 146.153412 -361.982289) (xy 146.109789 -361.949641) (xy 146.071255 -361.911118) (xy 146.038595 -361.867504)
			(xy 146.025108 -361.843828) (xy 145.574766 -361.843828) (xy 145.5674 -361.885992) (xy 145.562114 -361.91361)
			(xy 145.544501 -361.96701) (xy 145.519241 -362.017247) (xy 145.48688 -362.063231) (xy 145.448119 -362.103968)
			(xy 145.403799 -362.138573) (xy 145.35488 -362.166298) (xy 145.30242 -362.186543) (xy 145.247557 -362.198867)
			(xy 145.19148 -362.203005) (xy 145.135403 -362.198867) (xy 145.08054 -362.186543) (xy 145.02808 -362.166298)
			(xy 144.979161 -362.138573) (xy 144.934841 -362.103968) (xy 144.89608 -362.063231) (xy 144.863719 -362.017247)
			(xy 144.838459 -361.96701) (xy 144.820846 -361.91361) (xy 144.81556 -361.885992) (xy 144.808194 -361.843828)
			(xy 132.81914 -361.843828) (xy 132.794179 -361.843268) (xy 132.745214 -361.833537) (xy 132.699096 -361.814424)
			(xy 132.657603 -361.786666) (xy 132.639562 -361.769406) (xy 129.346198 -358.476042) (xy 129.318512 -358.482646)
			(xy 129.296496 -358.487623) (xy 129.251674 -358.492968) (xy 129.229104 -358.493314) (xy 129.22885 -358.493314)
			(xy 129.201599 -358.492798) (xy 129.14765 -358.485048) (xy 129.095353 -358.469699) (xy 129.045774 -358.447063)
			(xy 128.999921 -358.4176) (xy 128.958728 -358.381912) (xy 128.923033 -358.340724) (xy 128.893564 -358.294875)
			(xy 128.870921 -358.245299) (xy 128.855564 -358.193005) (xy 128.847806 -358.139057) (xy 128.847342 -358.111806)
			(xy 128.847342 -358.109012) (xy 128.847038 -358.095624) (xy 128.840262 -358.069723) (xy 128.826988 -358.046474)
			(xy 128.808127 -358.027473) (xy 128.784977 -358.014027) (xy 128.759128 -358.007059) (xy 128.745742 -358.00665)
			(xy 116.089176 -358.00665) (xy 116.077238 -358.04094) (xy 116.067789 -358.067177) (xy 116.042312 -358.116783)
			(xy 116.009881 -358.162149) (xy 115.971189 -358.202307) (xy 115.927059 -358.236401) (xy 115.878434 -358.263704)
			(xy 115.826351 -358.283632) (xy 115.771921 -358.295762) (xy 115.716304 -358.299834) (xy 115.660687 -358.295762)
			(xy 115.606257 -358.283632) (xy 115.554174 -358.263704) (xy 115.505549 -358.236401) (xy 115.461419 -358.202307)
			(xy 115.422727 -358.162149) (xy 115.390296 -358.116783) (xy 115.364819 -358.067177) (xy 115.35537 -358.04094)
			(xy 115.343432 -358.00665) (xy 104.641142 -358.00665) (xy 104.619552 -358.005634) (xy 104.598024 -358.017349)
			(xy 104.552613 -358.035785) (xy 104.505213 -358.048248) (xy 104.456606 -358.054531) (xy 104.4321 -358.05491)
			(xy 104.404849 -358.054422) (xy 104.350901 -358.046666) (xy 104.298607 -358.031311) (xy 104.24903 -358.00867)
			(xy 104.203179 -357.979204) (xy 104.161989 -357.943512) (xy 104.126298 -357.902322) (xy 104.096831 -357.856472)
			(xy 104.07419 -357.806895) (xy 104.058835 -357.754601) (xy 104.051078 -357.700653) (xy 104.050592 -357.673402)
			(xy 104.051047 -357.647611) (xy 104.058053 -357.596508) (xy 104.064562 -357.571548) (xy 104.072436 -357.5431)
			(xy 101.584506 -355.05517) (xy 100.192586 -355.05517) (xy 100.18649 -355.099112) (xy 100.182367 -355.126221)
			(xy 100.167354 -355.178959) (xy 100.144943 -355.229004) (xy 100.115595 -355.275322) (xy 100.079916 -355.31696)
			(xy 100.038641 -355.353058) (xy 99.992622 -355.382873) (xy 99.942806 -355.405789) (xy 99.890223 -355.421334)
			(xy 99.835955 -355.429187) (xy 99.781121 -355.429187) (xy 99.726853 -355.421334) (xy 99.67427 -355.405789)
			(xy 99.624454 -355.382873) (xy 99.578435 -355.353058) (xy 99.53716 -355.31696) (xy 99.501481 -355.275322)
			(xy 99.472133 -355.229004) (xy 99.449722 -355.178959) (xy 99.434709 -355.126221) (xy 99.430586 -355.099112)
			(xy 99.42449 -355.05517) (xy 88.326214 -355.05517) (xy 87.588598 -355.792786) (xy 87.588598 -358.41559)
			(xy 87.588065 -358.440553) (xy 87.578327 -358.489519) (xy 87.559207 -358.535638) (xy 87.53144 -358.577129)
			(xy 87.514176 -358.595168) (xy 86.096856 -360.012488) (xy 86.078772 -360.029694) (xy 86.037282 -360.057431)
			(xy 85.991178 -360.076541) (xy 85.942232 -360.086291) (xy 85.917278 -360.08691) (xy 57.254394 -360.08691)
			(xy 57.241164 -360.111389) (xy 57.208692 -360.156574) (xy 57.170001 -360.196561) (xy 57.12591 -360.230504)
			(xy 57.077356 -360.25768) (xy 57.025369 -360.277515) (xy 56.971052 -360.289587) (xy 56.915558 -360.293639)
			(xy 56.860064 -360.289587) (xy 56.805747 -360.277515) (xy 56.75376 -360.25768) (xy 56.705206 -360.230504)
			(xy 56.661115 -360.196561) (xy 56.622424 -360.156574) (xy 56.589952 -360.111389) (xy 56.576722 -360.08691)
			(xy 36.981892 -360.08691) (xy 36.956929 -360.086385) (xy 36.907962 -360.076644) (xy 36.861844 -360.057521)
			(xy 36.820353 -360.029753) (xy 36.802314 -360.012488) (xy 24.88946 -348.099634) (xy 24.87222 -348.081578)
			(xy 24.844477 -348.040081) (xy 24.825364 -347.993969) (xy 24.815615 -347.945014) (xy 24.815038 -347.920056)
			(xy 24.815038 -340.275926) (xy 22.223222 -337.68411) (xy 8.797798 -337.68411) (xy 8.772835 -337.683581)
			(xy 8.723869 -337.673842) (xy 8.67775 -337.65472) (xy 8.636259 -337.626953) (xy 8.61822 -337.609688)
			(xy 6.181852 -335.17332) (xy 6.164604 -335.155271) (xy 6.136863 -335.113771) (xy 6.117752 -335.067657)
			(xy 6.108005 -335.018701) (xy 6.10743 -334.993742) (xy 6.10743 -327.654158) (xy 6.107938 -327.63968)
			(xy 6.107938 -194.806062) (xy 6.082484 -194.793169) (xy 6.035383 -194.760969) (xy 5.993599 -194.722117)
			(xy 5.958064 -194.677478) (xy 5.92957 -194.628047) (xy 5.908751 -194.574926) (xy 5.896071 -194.519297)
			(xy 5.891813 -194.4624) (xy 5.896071 -194.405503) (xy 5.908751 -194.349874) (xy 5.92957 -194.296753)
			(xy 5.958064 -194.247322) (xy 5.993599 -194.202683) (xy 6.035383 -194.163831) (xy 6.082484 -194.131631)
			(xy 6.107938 -194.118738) (xy 6.107938 -189.54623) (xy 6.106922 -189.54115) (xy 6.104544 -189.528649)
			(xy 6.101998 -189.503328) (xy 6.101842 -189.490604) (xy 6.102199 -189.471247) (xy 6.108069 -189.43298)
			(xy 6.113526 -189.414404) (xy 6.117806 -189.395973) (xy 6.131082 -189.360543) (xy 6.149488 -189.327485)
			(xy 6.16077 -189.312296) (xy 6.163564 -189.308486) (xy 12.681458 -176.589436) (xy 12.681458 -165.383464)
			(xy 12.680904 -165.368923) (xy 12.672672 -165.341028) (xy 12.656912 -165.316583) (xy 12.634903 -165.29757)
			(xy 12.608429 -165.285529) (xy 12.579634 -165.281436) (xy 12.550852 -165.285623) (xy 12.53744 -165.291262)
			(xy 12.443605 -165.333751) (xy 12.253132 -165.412238) (xy 12.059739 -165.483225) (xy 11.86372 -165.546603)
			(xy 11.665374 -165.602274) (xy 11.465006 -165.650155) (xy 11.262919 -165.690171) (xy 11.059424 -165.722263)
			(xy 10.854831 -165.746381) (xy 10.649451 -165.762487) (xy 10.443599 -165.770558) (xy 10.340594 -165.771068)
			(xy 10.339832 -165.771068) (xy 10.237188 -165.770573) (xy 10.032056 -165.76258) (xy 9.82739 -165.746606)
			(xy 9.623502 -165.722675) (xy 9.4207 -165.690825) (xy 9.219291 -165.651102) (xy 9.019583 -165.603567)
			(xy 8.821876 -165.548293) (xy 8.626471 -165.485363) (xy 8.433665 -165.414872) (xy 8.24375 -165.336927)
			(xy 8.057013 -165.251648) (xy 7.873739 -165.159162) (xy 7.694204 -165.059611) (xy 7.518682 -164.953144)
			(xy 7.347438 -164.839925) (xy 7.180732 -164.720124) (xy 7.018817 -164.593923) (xy 6.861939 -164.461513)
			(xy 6.710335 -164.323096) (xy 6.564235 -164.17888) (xy 6.423861 -164.029086) (xy 6.289426 -163.87394)
			(xy 6.161133 -163.713677) (xy 6.039178 -163.54854) (xy 5.923745 -163.378781) (xy 5.815009 -163.204655)
			(xy 5.713135 -163.026428) (xy 5.618278 -162.84437) (xy 5.530582 -162.658756) (xy 5.450178 -162.469868)
			(xy 5.377191 -162.277994) (xy 5.311729 -162.083423) (xy 5.253892 -161.88645) (xy 5.203769 -161.687375)
			(xy 5.161435 -161.4865) (xy 5.126954 -161.284128) (xy 5.100379 -161.080568) (xy 5.081749 -160.876127)
			(xy 5.071094 -160.671115) (xy 5.068429 -160.465845) (xy 3.523996 -160.465845) (xy 3.523996 -347.699838)
			(xy 5.068068 -347.699838) (xy 5.072082 -347.494154) (xy 5.084118 -347.288784) (xy 5.104157 -347.08404)
			(xy 5.13217 -346.880233) (xy 5.168113 -346.677674) (xy 5.211932 -346.476672) (xy 5.263559 -346.277533)
			(xy 5.322917 -346.08056) (xy 5.389915 -345.886052) (xy 5.464451 -345.694307) (xy 5.546411 -345.505616)
			(xy 5.635671 -345.320266) (xy 5.732094 -345.13854) (xy 5.835535 -344.960714) (xy 5.945834 -344.78706)
			(xy 6.062825 -344.617841) (xy 6.186329 -344.453315) (xy 6.316158 -344.293734) (xy 6.452115 -344.139339)
			(xy 6.593992 -343.990367) (xy 6.741573 -343.847043) (xy 6.894634 -343.709587) (xy 7.052941 -343.578207)
			(xy 7.216254 -343.453104) (xy 7.384323 -343.334467) (xy 7.556893 -343.222479) (xy 7.733701 -343.117308)
			(xy 7.914478 -343.019117) (xy 8.098948 -342.928053) (xy 8.28683 -342.844256) (xy 8.47784 -342.767853)
			(xy 8.671684 -342.69896) (xy 8.868069 -342.637683) (xy 9.066695 -342.584115) (xy 9.26726 -342.538338)
			(xy 9.469458 -342.50042) (xy 9.672982 -342.470421) (xy 9.877521 -342.448384) (xy 10.082764 -342.434345)
			(xy 10.288399 -342.428325) (xy 10.494112 -342.430332) (xy 10.69959 -342.440364) (xy 10.90452 -342.458405)
			(xy 11.10859 -342.484428) (xy 11.31149 -342.518393) (xy 11.51291 -342.560248) (xy 11.712543 -342.60993)
			(xy 11.910086 -342.667364) (xy 12.105238 -342.732461) (xy 12.297702 -342.805122) (xy 12.487184 -342.885238)
			(xy 12.673395 -342.972685) (xy 12.856054 -343.067331) (xy 13.03488 -343.169031) (xy 13.209602 -343.277631)
			(xy 13.379955 -343.392966) (xy 13.545677 -343.514859) (xy 13.706518 -343.643125) (xy 13.862231 -343.777568)
			(xy 14.012581 -343.917985) (xy 14.157338 -344.064161) (xy 14.296281 -344.215873) (xy 14.429199 -344.372891)
			(xy 14.55589 -344.534976) (xy 14.67616 -344.701879) (xy 14.789827 -344.873349) (xy 14.896717 -345.049122)
			(xy 14.996668 -345.228932) (xy 15.089527 -345.412505) (xy 15.175154 -345.599561) (xy 15.253416 -345.789816)
			(xy 15.324197 -345.982979) (xy 15.387387 -346.178757) (xy 15.44289 -346.376851) (xy 15.490622 -346.57696)
			(xy 15.530511 -346.778778) (xy 15.562495 -346.982) (xy 15.586525 -347.186314) (xy 15.602566 -347.39141)
			(xy 15.610592 -347.596977) (xy 15.611094 -347.699838) (xy 15.610592 -347.802699) (xy 15.602566 -348.008266)
			(xy 15.586525 -348.213362) (xy 15.562495 -348.417676) (xy 15.530511 -348.620898) (xy 15.490622 -348.822716)
			(xy 15.44289 -349.022825) (xy 15.387387 -349.220919) (xy 15.324197 -349.416697) (xy 15.253416 -349.60986)
			(xy 15.175154 -349.800115) (xy 15.089527 -349.987171) (xy 14.996668 -350.170744) (xy 14.896717 -350.350554)
			(xy 14.789827 -350.526327) (xy 14.67616 -350.697797) (xy 14.55589 -350.8647) (xy 14.429199 -351.026785)
			(xy 14.296281 -351.183803) (xy 14.157338 -351.335515) (xy 14.012581 -351.481691) (xy 13.862231 -351.622108)
			(xy 13.706518 -351.756551) (xy 13.545677 -351.884817) (xy 13.379955 -352.00671) (xy 13.209602 -352.122045)
			(xy 13.03488 -352.230645) (xy 12.856054 -352.332345) (xy 12.673395 -352.426991) (xy 12.487184 -352.514438)
			(xy 12.297702 -352.594554) (xy 12.105238 -352.667215) (xy 11.910086 -352.732312) (xy 11.712543 -352.789746)
			(xy 11.51291 -352.839428) (xy 11.31149 -352.881283) (xy 11.10859 -352.915248) (xy 10.90452 -352.941271)
			(xy 10.69959 -352.959312) (xy 10.494112 -352.969344) (xy 10.288399 -352.971351) (xy 10.082764 -352.965331)
			(xy 9.877521 -352.951292) (xy 9.672982 -352.929255) (xy 9.469458 -352.899256) (xy 9.26726 -352.861338)
			(xy 9.066695 -352.815561) (xy 8.868069 -352.761993) (xy 8.671684 -352.700716) (xy 8.47784 -352.631823)
			(xy 8.28683 -352.55542) (xy 8.098948 -352.471623) (xy 7.914478 -352.380559) (xy 7.733701 -352.282368)
			(xy 7.556893 -352.177197) (xy 7.384323 -352.065209) (xy 7.216254 -351.946572) (xy 7.052941 -351.821469)
			(xy 6.894634 -351.690089) (xy 6.741573 -351.552633) (xy 6.593992 -351.409309) (xy 6.452115 -351.260337)
			(xy 6.316158 -351.105942) (xy 6.186329 -350.946361) (xy 6.062825 -350.781835) (xy 5.945834 -350.612616)
			(xy 5.835535 -350.438962) (xy 5.732094 -350.261136) (xy 5.635671 -350.07941) (xy 5.546411 -349.89406)
			(xy 5.464451 -349.705369) (xy 5.389915 -349.513624) (xy 5.322917 -349.319116) (xy 5.263559 -349.122143)
			(xy 5.211932 -348.923004) (xy 5.168113 -348.722002) (xy 5.13217 -348.519443) (xy 5.104157 -348.315636)
			(xy 5.084118 -348.110892) (xy 5.072082 -347.905522) (xy 5.068068 -347.699838) (xy 3.523996 -347.699838)
			(xy 3.523996 -360.76382) (xy 4.226823 -360.76382) (xy 4.230819 -360.553934) (xy 4.242804 -360.344352)
			(xy 4.262758 -360.135378) (xy 4.290654 -359.927316) (xy 4.326451 -359.720466) (xy 4.370096 -359.515129)
			(xy 4.421528 -359.311603) (xy 4.48067 -359.110182) (xy 4.547438 -358.911159) (xy 4.621734 -358.714822)
			(xy 4.703452 -358.521456) (xy 4.792471 -358.331341) (xy 4.888664 -358.144753) (xy 4.991891 -357.961962)
			(xy 5.102002 -357.783234) (xy 5.218837 -357.608827) (xy 5.342227 -357.438995) (xy 5.471994 -357.273983)
			(xy 5.607948 -357.114032) (xy 5.749894 -356.959372) (xy 5.897624 -356.810228) (xy 6.050926 -356.666817)
			(xy 6.209576 -356.529346) (xy 6.373345 -356.398014) (xy 6.541995 -356.273013) (xy 6.715281 -356.154522)
			(xy 6.892953 -356.042715) (xy 7.074753 -355.937753) (xy 7.260417 -355.839788) (xy 7.449675 -355.748963)
			(xy 7.642255 -355.665409) (xy 7.837876 -355.589246) (xy 8.036254 -355.520587) (xy 8.237103 -355.45953)
			(xy 8.44013 -355.406163) (xy 8.645043 -355.360565) (xy 8.851542 -355.3228) (xy 9.059329 -355.292925)
			(xy 9.268104 -355.270982) (xy 9.477562 -355.257003) (xy 9.687401 -355.251008) (xy 9.897315 -355.253007)
			(xy 10.107002 -355.262995) (xy 10.316156 -355.28096) (xy 10.524474 -355.306874) (xy 10.731655 -355.340699)
			(xy 10.937399 -355.382388) (xy 11.141405 -355.43188) (xy 11.34338 -355.489102) (xy 11.54303 -355.553972)
			(xy 11.740065 -355.626396) (xy 11.934201 -355.706269) (xy 12.125154 -355.793475) (xy 12.31265 -355.887887)
			(xy 12.496415 -355.989369) (xy 12.676183 -356.097773) (xy 12.851694 -356.212943) (xy 13.022693 -356.334711)
			(xy 13.188933 -356.4629) (xy 13.350172 -356.597326) (xy 13.506176 -356.737793) (xy 13.656719 -356.884097)
			(xy 13.801583 -357.036026) (xy 13.940558 -357.19336) (xy 14.073443 -357.355871) (xy 14.200044 -357.523324)
			(xy 14.320179 -357.695474) (xy 14.433673 -357.872074) (xy 14.540361 -358.052866) (xy 14.640088 -358.237589)
			(xy 14.732711 -358.425975) (xy 14.818095 -358.61775) (xy 14.896116 -358.812637) (xy 14.966661 -359.010353)
			(xy 15.029628 -359.210611) (xy 15.084925 -359.413121) (xy 15.132472 -359.61759) (xy 15.1722 -359.823721)
			(xy 15.204052 -360.031214) (xy 15.227982 -360.23977) (xy 15.243954 -360.449086) (xy 15.251946 -360.658858)
			(xy 15.252446 -360.76382) (xy 15.251946 -360.868782) (xy 15.243954 -361.078554) (xy 15.239789 -361.133136)
			(xy 121.446286 -361.133136) (xy 121.450375 -361.077254) (xy 121.462558 -361.022564) (xy 121.482574 -360.97023)
			(xy 121.509997 -360.921368) (xy 121.544242 -360.87702) (xy 121.584578 -360.83813) (xy 121.630148 -360.805528)
			(xy 121.679979 -360.779909) (xy 121.733009 -360.761817) (xy 121.788107 -360.75164) (xy 121.844101 -360.749594)
			(xy 121.899796 -360.755722) (xy 121.954005 -360.769894) (xy 122.005573 -360.791808) (xy 122.053401 -360.820997)
			(xy 122.096469 -360.856838) (xy 122.133859 -360.898568) (xy 122.164775 -360.945298) (xy 122.188558 -360.996031)
			(xy 122.2047 -361.049687) (xy 122.212859 -361.105121) (xy 122.21337 -361.133136) (xy 122.212859 -361.161151)
			(xy 122.2047 -361.216585) (xy 122.188558 -361.270241) (xy 122.164775 -361.320974) (xy 122.133859 -361.367704)
			(xy 122.096469 -361.409434) (xy 122.053401 -361.445275) (xy 122.005573 -361.474464) (xy 121.954005 -361.496378)
			(xy 121.899796 -361.51055) (xy 121.844101 -361.516678) (xy 121.788107 -361.514632) (xy 121.733009 -361.504455)
			(xy 121.679979 -361.486363) (xy 121.630148 -361.460744) (xy 121.584578 -361.428142) (xy 121.544242 -361.389252)
			(xy 121.509997 -361.344904) (xy 121.482574 -361.296042) (xy 121.462558 -361.243708) (xy 121.450375 -361.189018)
			(xy 121.446286 -361.133136) (xy 15.239789 -361.133136) (xy 15.227982 -361.28787) (xy 15.204052 -361.496426)
			(xy 15.1722 -361.703919) (xy 15.132472 -361.91005) (xy 15.084925 -362.114519) (xy 15.029628 -362.317029)
			(xy 14.966661 -362.517287) (xy 14.896116 -362.715003) (xy 14.818095 -362.90989) (xy 14.732711 -363.101665)
			(xy 14.640088 -363.290051) (xy 14.540361 -363.474774) (xy 14.433673 -363.655566) (xy 14.320179 -363.832166)
			(xy 14.200044 -364.004316) (xy 14.073443 -364.171769) (xy 13.940558 -364.33428) (xy 13.801583 -364.491614)
			(xy 13.656719 -364.643543) (xy 13.506176 -364.789847) (xy 13.350172 -364.930314) (xy 13.188933 -365.06474)
			(xy 13.022693 -365.192929) (xy 12.851694 -365.314697) (xy 12.676183 -365.429867) (xy 12.496415 -365.538271)
			(xy 12.31265 -365.639753) (xy 12.125154 -365.734165) (xy 11.934201 -365.821371) (xy 11.740065 -365.901244)
			(xy 11.54303 -365.973668) (xy 11.34338 -366.038538) (xy 11.141405 -366.09576) (xy 10.937399 -366.145252)
			(xy 10.731655 -366.186941) (xy 10.524474 -366.220766) (xy 10.316156 -366.24668) (xy 10.107002 -366.264645)
			(xy 9.897315 -366.274633) (xy 9.687401 -366.276632) (xy 9.477562 -366.270637) (xy 9.268104 -366.256658)
			(xy 9.059329 -366.234715) (xy 8.851542 -366.20484) (xy 8.645043 -366.167075) (xy 8.44013 -366.121477)
			(xy 8.237103 -366.06811) (xy 8.036254 -366.007053) (xy 7.837876 -365.938394) (xy 7.642255 -365.862231)
			(xy 7.449675 -365.778677) (xy 7.260417 -365.687852) (xy 7.074753 -365.589887) (xy 6.892953 -365.484925)
			(xy 6.715281 -365.373118) (xy 6.541995 -365.254627) (xy 6.373345 -365.129626) (xy 6.209576 -364.998294)
			(xy 6.050926 -364.860823) (xy 5.897624 -364.717412) (xy 5.749894 -364.568268) (xy 5.607948 -364.413608)
			(xy 5.471994 -364.253657) (xy 5.342227 -364.088645) (xy 5.218837 -363.918813) (xy 5.102002 -363.744406)
			(xy 4.991891 -363.565678) (xy 4.888664 -363.382887) (xy 4.792471 -363.196299) (xy 4.703452 -363.006184)
			(xy 4.621734 -362.812818) (xy 4.547438 -362.616481) (xy 4.48067 -362.417458) (xy 4.421528 -362.216037)
			(xy 4.370096 -362.012511) (xy 4.326451 -361.807174) (xy 4.290654 -361.600324) (xy 4.262758 -361.392262)
			(xy 4.242804 -361.183288) (xy 4.230819 -360.973706) (xy 4.226823 -360.76382) (xy 3.523996 -360.76382)
			(xy 3.523996 -383.932484) (xy 8.539215 -383.932484) (xy 8.539215 -383.803344) (xy 8.547165 -383.674449)
			(xy 8.563035 -383.546289) (xy 8.586764 -383.419348) (xy 8.618263 -383.294109) (xy 8.657412 -383.171046)
			(xy 8.704063 -383.050627) (xy 8.758038 -382.933308) (xy 8.819133 -382.819534) (xy 8.887116 -382.709737)
			(xy 8.96173 -382.604334) (xy 9.042691 -382.503724) (xy 9.129691 -382.408289) (xy 9.222402 -382.31839)
			(xy 9.320472 -382.234369) (xy 9.423527 -382.156545) (xy 9.531178 -382.085213) (xy 9.643017 -382.020643)
			(xy 9.758618 -381.963081) (xy 9.877543 -381.912744) (xy 9.999342 -381.869824) (xy 10.123552 -381.834483)
			(xy 10.249701 -381.806856) (xy 10.377313 -381.787047) (xy 10.505902 -381.775131) (xy 10.63498 -381.771155)
			(xy 10.764058 -381.775131) (xy 10.892647 -381.787047) (xy 11.020259 -381.806856) (xy 11.146408 -381.834483)
			(xy 11.270618 -381.869824) (xy 11.392417 -381.912744) (xy 11.511342 -381.963081) (xy 11.626943 -382.020643)
			(xy 11.738782 -382.085213) (xy 11.846433 -382.156545) (xy 11.949488 -382.234369) (xy 12.047558 -382.31839)
			(xy 12.140269 -382.408289) (xy 12.227269 -382.503724) (xy 12.30823 -382.604334) (xy 12.382844 -382.709737)
			(xy 12.450827 -382.819534) (xy 12.505341 -382.921052) (xy 19.016679 -382.921052) (xy 19.016679 -382.866548)
			(xy 19.024437 -382.812598) (xy 19.039793 -382.760301) (xy 19.062436 -382.710722) (xy 19.091904 -382.664871)
			(xy 19.127599 -382.62368) (xy 19.168792 -382.587989) (xy 19.214645 -382.558523) (xy 19.264226 -382.535884)
			(xy 19.316523 -382.520531) (xy 19.370474 -382.512778) (xy 19.397726 -382.512316) (xy 20.261326 -382.512316)
			(xy 20.288578 -382.512756) (xy 20.342526 -382.520516) (xy 20.394821 -382.535874) (xy 20.444398 -382.558518)
			(xy 20.490248 -382.587987) (xy 20.531438 -382.623681) (xy 20.567129 -382.664873) (xy 20.596594 -382.710725)
			(xy 20.619235 -382.760303) (xy 20.63459 -382.812599) (xy 20.642346 -382.866548) (xy 20.642346 -382.921052)
			(xy 20.636681 -382.960459) (xy 22.291788 -382.960459) (xy 22.291788 -382.905921) (xy 22.29955 -382.851938)
			(xy 22.314915 -382.79961) (xy 22.337571 -382.75) (xy 22.367056 -382.70412) (xy 22.40277 -382.662903)
			(xy 22.443987 -382.627188) (xy 22.489867 -382.597702) (xy 22.539476 -382.575046) (xy 22.591804 -382.559681)
			(xy 22.645787 -382.551919) (xy 22.673056 -382.551432) (xy 23.536656 -382.551432) (xy 23.563927 -382.551887)
			(xy 23.617915 -382.559649) (xy 23.670249 -382.575015) (xy 23.719863 -382.597673) (xy 23.765748 -382.62716)
			(xy 23.806969 -382.662878) (xy 23.842687 -382.704099) (xy 23.872175 -382.749983) (xy 23.894834 -382.799597)
			(xy 23.9102 -382.851931) (xy 23.917962 -382.905919) (xy 23.917962 -382.960461) (xy 23.9102 -383.014449)
			(xy 23.894834 -383.066783) (xy 23.872175 -383.116397) (xy 23.842687 -383.162281) (xy 23.806969 -383.203502)
			(xy 23.765748 -383.23922) (xy 23.719863 -383.268707) (xy 23.670249 -383.291365) (xy 23.617915 -383.306731)
			(xy 23.563927 -383.314493) (xy 23.536656 -383.314956) (xy 22.673056 -383.314956) (xy 22.645787 -383.314461)
			(xy 22.591804 -383.306699) (xy 22.539476 -383.291334) (xy 22.489867 -383.268678) (xy 22.443987 -383.239192)
			(xy 22.40277 -383.203477) (xy 22.367056 -383.16226) (xy 22.337571 -383.11638) (xy 22.314915 -383.06677)
			(xy 22.29955 -383.014442) (xy 22.291788 -382.960459) (xy 20.636681 -382.960459) (xy 20.63459 -382.975001)
			(xy 20.619235 -383.027297) (xy 20.596594 -383.076875) (xy 20.567129 -383.122727) (xy 20.531438 -383.163919)
			(xy 20.490248 -383.199613) (xy 20.444398 -383.229082) (xy 20.394821 -383.251726) (xy 20.342526 -383.267084)
			(xy 20.288578 -383.274844) (xy 20.261326 -383.275332) (xy 19.397726 -383.275332) (xy 19.370474 -383.274822)
			(xy 19.316523 -383.267069) (xy 19.264226 -383.251716) (xy 19.214645 -383.229077) (xy 19.168792 -383.199611)
			(xy 19.127599 -383.16392) (xy 19.091904 -383.122729) (xy 19.062436 -383.076878) (xy 19.039793 -383.027299)
			(xy 19.024437 -382.975002) (xy 19.016679 -382.921052) (xy 12.505341 -382.921052) (xy 12.511922 -382.933308)
			(xy 12.565897 -383.050627) (xy 12.612548 -383.171046) (xy 12.651697 -383.294109) (xy 12.683196 -383.419348)
			(xy 12.706925 -383.546289) (xy 12.722795 -383.674449) (xy 12.727298 -383.747461) (xy 271.909282 -383.747461)
			(xy 271.909282 -383.662739) (xy 271.917335 -383.578402) (xy 271.933369 -383.495212) (xy 271.957237 -383.413922)
			(xy 271.988725 -383.33527) (xy 272.027547 -383.259967) (xy 272.07335 -383.188695) (xy 272.125721 -383.122099)
			(xy 272.184186 -383.060784) (xy 272.248214 -383.005303) (xy 272.317226 -382.95616) (xy 272.390596 -382.9138)
			(xy 272.467661 -382.878605) (xy 272.547723 -382.850896) (xy 272.630056 -382.830922) (xy 272.713915 -382.818865)
			(xy 272.79854 -382.814834) (xy 272.883165 -382.818865) (xy 272.967024 -382.830922) (xy 273.049357 -382.850896)
			(xy 273.129419 -382.878605) (xy 273.206484 -382.9138) (xy 273.279854 -382.95616) (xy 273.348866 -383.005303)
			(xy 273.412894 -383.060784) (xy 273.471359 -383.122099) (xy 273.52373 -383.188695) (xy 273.569533 -383.259967)
			(xy 273.608355 -383.33527) (xy 273.639843 -383.413922) (xy 273.663711 -383.495212) (xy 273.679745 -383.578402)
			(xy 273.687798 -383.662739) (xy 273.688302 -383.7051) (xy 273.687798 -383.747461) (xy 273.679745 -383.831798)
			(xy 273.663711 -383.914988) (xy 273.639843 -383.996278) (xy 273.608355 -384.07493) (xy 273.569533 -384.150233)
			(xy 273.52373 -384.221505) (xy 273.471359 -384.288101) (xy 273.412894 -384.349416) (xy 273.348866 -384.404897)
			(xy 273.279854 -384.45404) (xy 273.206484 -384.4964) (xy 273.129419 -384.531595) (xy 273.049357 -384.559304)
			(xy 272.967024 -384.579278) (xy 272.883165 -384.591335) (xy 272.79854 -384.595367) (xy 272.713915 -384.591335)
			(xy 272.630056 -384.579278) (xy 272.547723 -384.559304) (xy 272.467661 -384.531595) (xy 272.390596 -384.4964)
			(xy 272.317226 -384.45404) (xy 272.248214 -384.404897) (xy 272.184186 -384.349416) (xy 272.125721 -384.288101)
			(xy 272.07335 -384.221505) (xy 272.027547 -384.150233) (xy 271.988725 -384.07493) (xy 271.957237 -383.996278)
			(xy 271.933369 -383.914988) (xy 271.917335 -383.831798) (xy 271.909282 -383.747461) (xy 12.727298 -383.747461)
			(xy 12.730745 -383.803344) (xy 12.731242 -383.867914) (xy 12.730745 -383.932484) (xy 12.722795 -384.061379)
			(xy 12.706925 -384.189539) (xy 12.683196 -384.31648) (xy 12.651697 -384.441719) (xy 12.612548 -384.564782)
			(xy 12.565897 -384.685201) (xy 12.511922 -384.80252) (xy 12.450827 -384.916294) (xy 12.382844 -385.026091)
			(xy 12.30823 -385.131494) (xy 12.227269 -385.232104) (xy 12.140269 -385.327539) (xy 12.047558 -385.417438)
			(xy 11.949488 -385.501459) (xy 11.846433 -385.579283) (xy 11.738782 -385.650615) (xy 11.626943 -385.715185)
			(xy 11.511342 -385.772747) (xy 11.483943 -385.784344) (xy 19.460972 -385.784344) (xy 19.460972 -384.920744)
			(xy 19.461458 -384.893493) (xy 19.469214 -384.839545) (xy 19.484569 -384.78725) (xy 19.507211 -384.737673)
			(xy 19.536677 -384.691823) (xy 19.572368 -384.650632) (xy 19.613559 -384.614941) (xy 19.659409 -384.585475)
			(xy 19.708986 -384.562833) (xy 19.761281 -384.547478) (xy 19.815229 -384.539722) (xy 19.869731 -384.539722)
			(xy 19.923679 -384.547478) (xy 19.975974 -384.562833) (xy 20.025551 -384.585475) (xy 20.071401 -384.614941)
			(xy 20.112592 -384.650632) (xy 20.148283 -384.691823) (xy 20.177749 -384.737673) (xy 20.200391 -384.78725)
			(xy 20.215746 -384.839545) (xy 20.223502 -384.893493) (xy 20.223988 -384.920744) (xy 20.223988 -385.784344)
			(xy 20.22353 -385.809998) (xy 22.731984 -385.809998) (xy 22.731984 -384.946398) (xy 22.73247 -384.919147)
			(xy 22.740226 -384.865199) (xy 22.755581 -384.812904) (xy 22.778223 -384.763327) (xy 22.807689 -384.717477)
			(xy 22.84338 -384.676286) (xy 22.884571 -384.640595) (xy 22.930421 -384.611129) (xy 22.979998 -384.588487)
			(xy 23.032293 -384.573132) (xy 23.086241 -384.565376) (xy 23.140743 -384.565376) (xy 23.194691 -384.573132)
			(xy 23.246986 -384.588487) (xy 23.296563 -384.611129) (xy 23.342413 -384.640595) (xy 23.383604 -384.676286)
			(xy 23.419295 -384.717477) (xy 23.448761 -384.763327) (xy 23.471403 -384.812904) (xy 23.486758 -384.865199)
			(xy 23.494514 -384.919147) (xy 23.495 -384.946398) (xy 23.495 -385.440249) (xy 36.585674 -385.440249)
			(xy 36.585674 -385.385751) (xy 36.593429 -385.331807) (xy 36.608782 -385.279515) (xy 36.63142 -385.229941)
			(xy 36.660882 -385.184092) (xy 36.696569 -385.142903) (xy 36.737753 -385.107211) (xy 36.783598 -385.077743)
			(xy 36.83317 -385.055099) (xy 36.88546 -385.039739) (xy 36.939403 -385.031977) (xy 36.966652 -385.031488)
			(xy 37.830252 -385.031488) (xy 37.857507 -385.031956) (xy 37.911462 -385.039707) (xy 37.963765 -385.055059)
			(xy 38.013351 -385.077699) (xy 38.05921 -385.107165) (xy 38.100408 -385.142858) (xy 38.136106 -385.184052)
			(xy 38.165578 -385.229907) (xy 38.188224 -385.27949) (xy 38.203582 -385.331791) (xy 38.211341 -385.385745)
			(xy 38.211341 -385.440255) (xy 38.203582 -385.494209) (xy 38.188224 -385.54651) (xy 38.165578 -385.596093)
			(xy 38.16123 -385.602858) (xy 41.455211 -385.602858) (xy 41.455211 -385.548342) (xy 41.46297 -385.494381)
			(xy 41.47833 -385.442074) (xy 41.500978 -385.392486) (xy 41.530453 -385.346625) (xy 41.566155 -385.305427)
			(xy 41.607357 -385.269729) (xy 41.653221 -385.240259) (xy 41.702812 -385.217616) (xy 41.755121 -385.202261)
			(xy 41.809082 -385.194508) (xy 41.83634 -385.194048) (xy 42.69994 -385.194048) (xy 42.727186 -385.194625)
			(xy 42.781123 -385.202385) (xy 42.833407 -385.217742) (xy 42.882974 -385.240383) (xy 42.928814 -385.269847)
			(xy 42.969994 -385.305534) (xy 43.005677 -385.346718) (xy 43.035136 -385.392562) (xy 43.057772 -385.44213)
			(xy 43.073123 -385.494416) (xy 43.080878 -385.548354) (xy 43.080878 -385.602846) (xy 43.073123 -385.656784)
			(xy 43.057772 -385.70907) (xy 43.035136 -385.758638) (xy 43.005677 -385.804482) (xy 42.969994 -385.845666)
			(xy 42.928814 -385.881353) (xy 42.882974 -385.910817) (xy 42.833407 -385.933458) (xy 42.781123 -385.948815)
			(xy 42.727186 -385.956575) (xy 42.69994 -385.957064) (xy 41.83634 -385.957064) (xy 41.809082 -385.956692)
			(xy 41.755121 -385.948939) (xy 41.702812 -385.933584) (xy 41.653221 -385.910941) (xy 41.607357 -385.881471)
			(xy 41.566155 -385.845773) (xy 41.530453 -385.804575) (xy 41.500978 -385.758714) (xy 41.47833 -385.709126)
			(xy 41.46297 -385.656819) (xy 41.455211 -385.602858) (xy 38.16123 -385.602858) (xy 38.136106 -385.641948)
			(xy 38.100408 -385.683142) (xy 38.05921 -385.718835) (xy 38.013351 -385.748301) (xy 37.963765 -385.770941)
			(xy 37.911462 -385.786293) (xy 37.857507 -385.794044) (xy 37.830252 -385.794504) (xy 36.966652 -385.794504)
			(xy 36.939403 -385.794023) (xy 36.88546 -385.786261) (xy 36.83317 -385.770901) (xy 36.783598 -385.748257)
			(xy 36.737753 -385.718789) (xy 36.696569 -385.683097) (xy 36.660882 -385.641908) (xy 36.63142 -385.596059)
			(xy 36.608782 -385.546485) (xy 36.593429 -385.494193) (xy 36.585674 -385.440249) (xy 23.495 -385.440249)
			(xy 23.495 -385.809998) (xy 23.494514 -385.837249) (xy 23.486758 -385.891197) (xy 23.471403 -385.943492)
			(xy 23.448761 -385.993069) (xy 23.419295 -386.038919) (xy 23.383604 -386.08011) (xy 23.342413 -386.115801)
			(xy 23.297425 -386.144713) (xy 269.99209 -386.144713) (xy 269.99209 -386.059991) (xy 270.000143 -385.975654)
			(xy 270.016177 -385.892464) (xy 270.040045 -385.811174) (xy 270.071533 -385.732522) (xy 270.110355 -385.657219)
			(xy 270.156158 -385.585947) (xy 270.208529 -385.519351) (xy 270.266994 -385.458036) (xy 270.331022 -385.402555)
			(xy 270.400034 -385.353412) (xy 270.473404 -385.311052) (xy 270.550469 -385.275857) (xy 270.630531 -385.248148)
			(xy 270.712864 -385.228174) (xy 270.796723 -385.216117) (xy 270.881348 -385.212086) (xy 270.965973 -385.216117)
			(xy 271.049832 -385.228174) (xy 271.132165 -385.248148) (xy 271.212227 -385.275857) (xy 271.289292 -385.311052)
			(xy 271.362662 -385.353412) (xy 271.431674 -385.402555) (xy 271.495702 -385.458036) (xy 271.554167 -385.519351)
			(xy 271.606538 -385.585947) (xy 271.652341 -385.657219) (xy 271.691163 -385.732522) (xy 271.722651 -385.811174)
			(xy 271.746519 -385.892464) (xy 271.762553 -385.975654) (xy 271.770606 -386.059991) (xy 271.77111 -386.102352)
			(xy 271.770606 -386.144713) (xy 271.762553 -386.22905) (xy 271.746519 -386.31224) (xy 271.722651 -386.39353)
			(xy 271.691163 -386.472182) (xy 271.652341 -386.547485) (xy 271.606538 -386.618757) (xy 271.554167 -386.685353)
			(xy 271.495702 -386.746668) (xy 271.431674 -386.802149) (xy 271.362662 -386.851292) (xy 271.289292 -386.893652)
			(xy 271.212227 -386.928847) (xy 271.132165 -386.956556) (xy 271.049832 -386.97653) (xy 270.965973 -386.988587)
			(xy 270.881348 -386.992619) (xy 270.796723 -386.988587) (xy 270.712864 -386.97653) (xy 270.630531 -386.956556)
			(xy 270.550469 -386.928847) (xy 270.473404 -386.893652) (xy 270.400034 -386.851292) (xy 270.331022 -386.802149)
			(xy 270.266994 -386.746668) (xy 270.208529 -386.685353) (xy 270.156158 -386.618757) (xy 270.110355 -386.547485)
			(xy 270.071533 -386.472182) (xy 270.040045 -386.39353) (xy 270.016177 -386.31224) (xy 270.000143 -386.22905)
			(xy 269.99209 -386.144713) (xy 23.297425 -386.144713) (xy 23.296563 -386.145267) (xy 23.246986 -386.167909)
			(xy 23.194691 -386.183264) (xy 23.140743 -386.19102) (xy 23.086241 -386.19102) (xy 23.032293 -386.183264)
			(xy 22.979998 -386.167909) (xy 22.930421 -386.145267) (xy 22.884571 -386.115801) (xy 22.84338 -386.08011)
			(xy 22.807689 -386.038919) (xy 22.778223 -385.993069) (xy 22.755581 -385.943492) (xy 22.740226 -385.891197)
			(xy 22.73247 -385.837249) (xy 22.731984 -385.809998) (xy 20.22353 -385.809998) (xy 20.223502 -385.811595)
			(xy 20.215746 -385.865543) (xy 20.200391 -385.917838) (xy 20.177749 -385.967415) (xy 20.148283 -386.013265)
			(xy 20.112592 -386.054456) (xy 20.071401 -386.090147) (xy 20.025551 -386.119613) (xy 19.975974 -386.142255)
			(xy 19.923679 -386.15761) (xy 19.869731 -386.165366) (xy 19.815229 -386.165366) (xy 19.761281 -386.15761)
			(xy 19.708986 -386.142255) (xy 19.659409 -386.119613) (xy 19.613559 -386.090147) (xy 19.572368 -386.054456)
			(xy 19.536677 -386.013265) (xy 19.507211 -385.967415) (xy 19.484569 -385.917838) (xy 19.469214 -385.865543)
			(xy 19.461458 -385.811595) (xy 19.460972 -385.784344) (xy 11.483943 -385.784344) (xy 11.392417 -385.823084)
			(xy 11.270618 -385.866004) (xy 11.146408 -385.901345) (xy 11.020259 -385.928972) (xy 10.892647 -385.948781)
			(xy 10.764058 -385.960697) (xy 10.63498 -385.964674) (xy 10.505902 -385.960697) (xy 10.377313 -385.948781)
			(xy 10.249701 -385.928972) (xy 10.123552 -385.901345) (xy 9.999342 -385.866004) (xy 9.877543 -385.823084)
			(xy 9.758618 -385.772747) (xy 9.643017 -385.715185) (xy 9.531178 -385.650615) (xy 9.423527 -385.579283)
			(xy 9.320472 -385.501459) (xy 9.222402 -385.417438) (xy 9.129691 -385.327539) (xy 9.042691 -385.232104)
			(xy 8.96173 -385.131494) (xy 8.887116 -385.026091) (xy 8.819133 -384.916294) (xy 8.758038 -384.80252)
			(xy 8.704063 -384.685201) (xy 8.657412 -384.564782) (xy 8.618263 -384.441719) (xy 8.586764 -384.31648)
			(xy 8.563035 -384.189539) (xy 8.547165 -384.061379) (xy 8.539215 -383.932484) (xy 3.523996 -383.932484)
			(xy 3.523996 -389.402275) (xy 286.566098 -389.402275) (xy 286.566098 -389.317529) (xy 286.574154 -389.233168)
			(xy 286.590192 -389.149954) (xy 286.614067 -389.068641) (xy 286.645564 -388.989966) (xy 286.684397 -388.914642)
			(xy 286.730213 -388.843349) (xy 286.7826 -388.776735) (xy 286.84108 -388.715402) (xy 286.905127 -388.659906)
			(xy 286.974158 -388.610748) (xy 287.04755 -388.568376) (xy 287.124637 -388.533171) (xy 287.204721 -388.505454)
			(xy 287.287078 -388.485474) (xy 287.370961 -388.473414) (xy 287.45561 -388.469382) (xy 287.540259 -388.473414)
			(xy 287.624142 -388.485474) (xy 287.706499 -388.505454) (xy 287.786583 -388.533171) (xy 287.86367 -388.568376)
			(xy 287.937062 -388.610748) (xy 288.006093 -388.659906) (xy 288.07014 -388.715402) (xy 288.12862 -388.776735)
			(xy 288.181007 -388.843349) (xy 288.226823 -388.914642) (xy 288.265656 -388.989966) (xy 288.297153 -389.068641)
			(xy 288.321028 -389.149954) (xy 288.337066 -389.233168) (xy 288.345122 -389.317529) (xy 288.345626 -389.359902)
			(xy 288.345122 -389.402275) (xy 297.615098 -389.402275) (xy 297.615098 -389.317529) (xy 297.623154 -389.233168)
			(xy 297.639192 -389.149954) (xy 297.663067 -389.068641) (xy 297.694564 -388.989966) (xy 297.733397 -388.914642)
			(xy 297.779213 -388.843349) (xy 297.8316 -388.776735) (xy 297.89008 -388.715402) (xy 297.954127 -388.659906)
			(xy 298.023158 -388.610748) (xy 298.09655 -388.568376) (xy 298.173637 -388.533171) (xy 298.253721 -388.505454)
			(xy 298.336078 -388.485474) (xy 298.419961 -388.473414) (xy 298.50461 -388.469382) (xy 298.589259 -388.473414)
			(xy 298.673142 -388.485474) (xy 298.755499 -388.505454) (xy 298.835583 -388.533171) (xy 298.91267 -388.568376)
			(xy 298.986062 -388.610748) (xy 299.055093 -388.659906) (xy 299.11914 -388.715402) (xy 299.17762 -388.776735)
			(xy 299.230007 -388.843349) (xy 299.275823 -388.914642) (xy 299.314656 -388.989966) (xy 299.346153 -389.068641)
			(xy 299.370028 -389.149954) (xy 299.386066 -389.233168) (xy 299.394122 -389.317529) (xy 299.394626 -389.359902)
			(xy 299.394122 -389.402275) (xy 299.386066 -389.486636) (xy 299.370028 -389.56985) (xy 299.346153 -389.651163)
			(xy 299.314656 -389.729838) (xy 299.275823 -389.805162) (xy 299.230007 -389.876455) (xy 299.17762 -389.943069)
			(xy 299.11914 -390.004402) (xy 299.055093 -390.059898) (xy 298.986062 -390.109056) (xy 298.91267 -390.151428)
			(xy 298.835583 -390.186633) (xy 298.755499 -390.21435) (xy 298.673142 -390.23433) (xy 298.589259 -390.24639)
			(xy 298.50461 -390.250423) (xy 298.419961 -390.24639) (xy 298.336078 -390.23433) (xy 298.253721 -390.21435)
			(xy 298.173637 -390.186633) (xy 298.09655 -390.151428) (xy 298.023158 -390.109056) (xy 297.954127 -390.059898)
			(xy 297.89008 -390.004402) (xy 297.8316 -389.943069) (xy 297.779213 -389.876455) (xy 297.733397 -389.805162)
			(xy 297.694564 -389.729838) (xy 297.663067 -389.651163) (xy 297.639192 -389.56985) (xy 297.623154 -389.486636)
			(xy 297.615098 -389.402275) (xy 288.345122 -389.402275) (xy 288.337066 -389.486636) (xy 288.321028 -389.56985)
			(xy 288.297153 -389.651163) (xy 288.265656 -389.729838) (xy 288.226823 -389.805162) (xy 288.181007 -389.876455)
			(xy 288.12862 -389.943069) (xy 288.07014 -390.004402) (xy 288.006093 -390.059898) (xy 287.937062 -390.109056)
			(xy 287.86367 -390.151428) (xy 287.786583 -390.186633) (xy 287.706499 -390.21435) (xy 287.624142 -390.23433)
			(xy 287.540259 -390.24639) (xy 287.45561 -390.250423) (xy 287.370961 -390.24639) (xy 287.287078 -390.23433)
			(xy 287.204721 -390.21435) (xy 287.124637 -390.186633) (xy 287.04755 -390.151428) (xy 286.974158 -390.109056)
			(xy 286.905127 -390.059898) (xy 286.84108 -390.004402) (xy 286.7826 -389.943069) (xy 286.730213 -389.876455)
			(xy 286.684397 -389.805162) (xy 286.645564 -389.729838) (xy 286.614067 -389.651163) (xy 286.590192 -389.56985)
			(xy 286.574154 -389.486636) (xy 286.566098 -389.402275) (xy 3.523996 -389.402275) (xy 3.523996 -390.74852)
			(xy 289.828732 -390.74852) (xy 289.829157 -390.717787) (xy 289.836564 -390.656768) (xy 289.851272 -390.597088)
			(xy 289.873068 -390.539615) (xy 289.901633 -390.485189) (xy 289.93655 -390.434604) (xy 289.97731 -390.388596)
			(xy 290.023319 -390.347837) (xy 290.073907 -390.312922) (xy 290.128334 -390.28436) (xy 290.185807 -390.262566)
			(xy 290.245488 -390.24786) (xy 290.306507 -390.240455) (xy 290.33724 -390.240012) (xy 290.369283 -390.240508)
			(xy 290.432859 -390.248584) (xy 290.494917 -390.264579) (xy 290.554476 -390.288239) (xy 290.610594 -390.31919)
			(xy 290.662381 -390.356941) (xy 290.709019 -390.400896) (xy 290.749768 -390.450359) (xy 290.783985 -390.504546)
			(xy 290.811128 -390.562601) (xy 290.830767 -390.623604) (xy 290.842591 -390.686591) (xy 290.844986 -390.718548)
			(xy 290.846452 -390.733661) (xy 290.857061 -390.762093) (xy 290.875562 -390.786147) (xy 290.900318 -390.803698)
			(xy 290.929141 -390.813192) (xy 290.9443 -390.814052) (xy 290.977155 -390.815239) (xy 291.042167 -390.825028)
			(xy 291.105376 -390.843112) (xy 291.165728 -390.86919) (xy 291.222216 -390.902827) (xy 291.2739 -390.943462)
			(xy 291.319917 -390.990417) (xy 291.359501 -391.04291) (xy 291.391992 -391.100065) (xy 291.416847 -391.160931)
			(xy 291.433653 -391.224491) (xy 291.442129 -391.289688) (xy 291.442648 -391.32256) (xy 291.442106 -391.353289)
			(xy 291.434703 -391.414298) (xy 291.42 -391.473971) (xy 291.398212 -391.531436) (xy 291.369656 -391.585856)
			(xy 291.334748 -391.636437) (xy 291.293998 -391.682441) (xy 291.248 -391.723199) (xy 291.197424 -391.758114)
			(xy 291.143009 -391.786679) (xy 291.085547 -391.808477) (xy 291.025877 -391.823189) (xy 290.964869 -391.830602)
			(xy 290.93414 -391.831068) (xy 290.902098 -391.830516) (xy 290.838523 -391.822449) (xy 290.776465 -391.806463)
			(xy 290.716905 -391.78281) (xy 290.660787 -391.751866) (xy 290.608999 -391.71412) (xy 290.56236 -391.670169)
			(xy 290.521609 -391.620711) (xy 290.487392 -391.566526) (xy 290.460249 -391.508474) (xy 290.440611 -391.447473)
			(xy 290.428788 -391.384488) (xy 290.426394 -391.352532) (xy 290.424962 -391.337414) (xy 290.414346 -391.308979)
			(xy 290.395837 -391.284924) (xy 290.371072 -391.267376) (xy 290.342242 -391.257886) (xy 290.32708 -391.257028)
			(xy 290.294229 -391.25578) (xy 290.229223 -391.24599) (xy 290.166019 -391.227907) (xy 290.105673 -391.201832)
			(xy 290.049188 -391.1682) (xy 289.997507 -391.127571) (xy 289.95149 -391.080623) (xy 289.911906 -391.028137)
			(xy 289.879413 -390.97099) (xy 289.854553 -390.910132) (xy 289.837741 -390.846579) (xy 289.829256 -390.78139)
			(xy 289.828732 -390.74852) (xy 3.523996 -390.74852) (xy 3.523996 -394.8085) (xy 243.179528 -394.8085)
			(xy 243.183558 -394.723892) (xy 243.195613 -394.640051) (xy 243.215583 -394.557735) (xy 243.243287 -394.47769)
			(xy 243.278475 -394.400641) (xy 243.320827 -394.327286) (xy 243.36996 -394.258289) (xy 243.42543 -394.194274)
			(xy 243.486733 -394.135823) (xy 243.553315 -394.083463) (xy 243.624573 -394.03767) (xy 243.699861 -393.998857)
			(xy 243.778498 -393.967377) (xy 243.859771 -393.943515) (xy 243.942944 -393.927486) (xy 244.027264 -393.919435)
			(xy 244.069616 -393.918948) (xy 244.11084 -393.919417) (xy 244.192933 -393.927053) (xy 244.273968 -393.94225)
			(xy 244.35325 -393.964876) (xy 244.430099 -393.994739) (xy 244.503857 -394.031582) (xy 244.573891 -394.075088)
			(xy 244.639601 -394.124886) (xy 244.670326 -394.152374) (xy 244.677558 -394.158461) (xy 244.695171 -394.165287)
			(xy 244.714061 -394.165287) (xy 244.731674 -394.158461) (xy 244.738906 -394.152374) (xy 244.769639 -394.124894)
			(xy 244.835341 -394.075085) (xy 244.905371 -394.03157) (xy 244.979128 -393.994723) (xy 245.055977 -393.964858)
			(xy 245.13526 -393.942233) (xy 245.216297 -393.927041) (xy 245.298392 -393.919413) (xy 245.339616 -393.918948)
			(xy 245.381408 -393.919476) (xy 245.464624 -393.927312) (xy 245.546738 -393.942923) (xy 245.627024 -393.96617)
			(xy 245.704775 -393.996849) (xy 245.779303 -394.034689) (xy 245.849951 -394.079356) (xy 245.916096 -394.130456)
			(xy 245.977154 -394.187537) (xy 246.032585 -394.250097) (xy 246.081902 -394.317582) (xy 246.124667 -394.389397)
			(xy 246.143018 -394.426948) (xy 246.170089 -394.428781) (xy 246.223268 -394.43954) (xy 246.274197 -394.458246)
			(xy 246.321697 -394.484466) (xy 246.364667 -394.51759) (xy 246.402111 -394.556853) (xy 246.433163 -394.601345)
			(xy 246.457102 -394.650034) (xy 246.473374 -394.701792) (xy 246.481601 -394.75542) (xy 246.482108 -394.782548)
			(xy 246.481601 -394.8085) (xy 249.114543 -394.8085) (xy 249.118574 -394.723896) (xy 249.130628 -394.640058)
			(xy 249.150596 -394.557746) (xy 249.178298 -394.477704) (xy 249.213483 -394.400658) (xy 249.255833 -394.327305)
			(xy 249.304963 -394.25831) (xy 249.360429 -394.194298) (xy 249.421729 -394.135847) (xy 249.488307 -394.083488)
			(xy 249.55956 -394.037695) (xy 249.634844 -393.998882) (xy 249.713476 -393.967401) (xy 249.794745 -393.943537)
			(xy 249.877914 -393.927506) (xy 249.96223 -393.919453) (xy 250.00458 -393.918948) (xy 250.045803 -393.919439)
			(xy 250.127896 -393.927072) (xy 250.20893 -393.942266) (xy 250.288212 -393.964889) (xy 250.365061 -393.994749)
			(xy 250.438819 -394.031588) (xy 250.508854 -394.075092) (xy 250.574564 -394.124887) (xy 250.60529 -394.152374)
			(xy 250.612522 -394.158461) (xy 250.630135 -394.165287) (xy 250.649025 -394.165287) (xy 250.666638 -394.158461)
			(xy 250.67387 -394.152374) (xy 250.704576 -394.124863) (xy 250.770283 -394.075057) (xy 250.840317 -394.031545)
			(xy 250.914078 -393.994701) (xy 250.990931 -393.96484) (xy 251.070218 -393.942219) (xy 251.151257 -393.927032)
			(xy 251.233355 -393.91941) (xy 251.27458 -393.918948) (xy 251.316356 -393.919458) (xy 251.399539 -393.927298)
			(xy 251.481621 -393.942901) (xy 251.561879 -393.966129) (xy 251.639606 -393.996779) (xy 251.714118 -394.03458)
			(xy 251.784758 -394.079199) (xy 251.850904 -394.130243) (xy 251.911974 -394.187264) (xy 251.96743 -394.249758)
			(xy 252.016784 -394.317175) (xy 252.059601 -394.388922) (xy 252.077982 -394.42644) (xy 252.086364 -394.42644)
			(xy 252.114351 -394.426946) (xy 252.169636 -394.435698) (xy 252.222871 -394.452992) (xy 252.272744 -394.478402)
			(xy 252.318028 -394.511302) (xy 252.357606 -394.550881) (xy 252.390505 -394.596166) (xy 252.415913 -394.646041)
			(xy 252.433205 -394.699276) (xy 252.441955 -394.754561) (xy 252.442472 -394.782548) (xy 252.441992 -394.8085)
			(xy 255.049428 -394.8085) (xy 255.053459 -394.723891) (xy 255.065514 -394.640048) (xy 255.085484 -394.55773)
			(xy 255.11319 -394.477684) (xy 255.148379 -394.400634) (xy 255.190732 -394.327277) (xy 255.239868 -394.258279)
			(xy 255.295339 -394.194265) (xy 255.356645 -394.135813) (xy 255.423229 -394.083453) (xy 255.494489 -394.03766)
			(xy 255.56978 -393.998849) (xy 255.648419 -393.96737) (xy 255.729694 -393.943509) (xy 255.812869 -393.927482)
			(xy 255.897191 -393.919434) (xy 255.939544 -393.918948) (xy 255.980768 -393.919399) (xy 256.062862 -393.927038)
			(xy 256.143897 -393.942237) (xy 256.223179 -393.964866) (xy 256.300029 -393.994731) (xy 256.373786 -394.031576)
			(xy 256.44382 -394.075085) (xy 256.509529 -394.124885) (xy 256.540254 -394.152374) (xy 256.547486 -394.158461)
			(xy 256.565099 -394.165287) (xy 256.583989 -394.165287) (xy 256.601602 -394.158461) (xy 256.608834 -394.152374)
			(xy 256.639555 -394.12488) (xy 256.70526 -394.075073) (xy 256.775292 -394.031559) (xy 256.849049 -393.994713)
			(xy 256.925901 -393.96485) (xy 257.005185 -393.942227) (xy 257.086223 -393.927037) (xy 257.168319 -393.919412)
			(xy 257.209544 -393.918948) (xy 257.251493 -393.919491) (xy 257.335018 -393.927401) (xy 257.417428 -393.943137)
			(xy 257.497991 -393.96656) (xy 257.575991 -393.997462) (xy 257.650737 -394.035568) (xy 257.721565 -394.08054)
			(xy 257.787845 -394.131979) (xy 257.848989 -394.189427) (xy 257.904455 -394.252376) (xy 257.95375 -394.320266)
			(xy 257.996436 -394.392494) (xy 258.014724 -394.43025) (xy 258.027542 -394.428485) (xy 258.053348 -394.426578)
			(xy 258.066286 -394.42644) (xy 258.067048 -394.42644) (xy 258.093699 -394.426845) (xy 258.146403 -394.434796)
			(xy 258.197335 -394.450512) (xy 258.245356 -394.473643) (xy 258.289393 -394.503673) (xy 258.328463 -394.539929)
			(xy 258.361693 -394.581604) (xy 258.388341 -394.627765) (xy 258.407813 -394.677383) (xy 258.419673 -394.729348)
			(xy 258.423656 -394.7825) (xy 258.421708 -394.8085) (xy 260.984428 -394.8085) (xy 260.988458 -394.723893)
			(xy 261.000513 -394.640052) (xy 261.020483 -394.557736) (xy 261.048186 -394.477692) (xy 261.083374 -394.400643)
			(xy 261.125725 -394.327288) (xy 261.174858 -394.258291) (xy 261.230327 -394.194277) (xy 261.29163 -394.135826)
			(xy 261.358212 -394.083466) (xy 261.429469 -394.037672) (xy 261.504756 -393.99886) (xy 261.583392 -393.967379)
			(xy 261.664664 -393.943516) (xy 261.747837 -393.927487) (xy 261.832156 -393.919436) (xy 261.874508 -393.918948)
			(xy 261.915732 -393.919422) (xy 261.997825 -393.927057) (xy 262.078859 -393.942253) (xy 262.158141 -393.964879)
			(xy 262.234991 -393.994741) (xy 262.308749 -394.031583) (xy 262.378783 -394.075089) (xy 262.444493 -394.124886)
			(xy 262.475218 -394.152374) (xy 262.48245 -394.158461) (xy 262.500063 -394.165287) (xy 262.518953 -394.165287)
			(xy 262.536566 -394.158461) (xy 262.543798 -394.152374) (xy 262.574534 -394.124897) (xy 262.640236 -394.075089)
			(xy 262.710266 -394.031574) (xy 262.784021 -393.994725) (xy 262.86087 -393.96486) (xy 262.940153 -393.942234)
			(xy 263.021189 -393.927042) (xy 263.103284 -393.919413) (xy 263.144508 -393.918948) (xy 263.18635 -393.919404)
			(xy 263.269665 -393.927258) (xy 263.351874 -393.942906) (xy 263.432248 -393.966208) (xy 263.510078 -393.996959)
			(xy 263.584674 -394.034887) (xy 263.655376 -394.079656) (xy 263.721559 -394.130869) (xy 263.782638 -394.188075)
			(xy 263.838071 -394.250766) (xy 263.887369 -394.318389) (xy 263.930095 -394.390344) (xy 263.948418 -394.427964)
			(xy 263.981692 -394.42644) (xy 264.008347 -394.426817) (xy 264.061062 -394.434761) (xy 264.112004 -394.450474)
			(xy 264.160035 -394.473603) (xy 264.204083 -394.503633) (xy 264.243162 -394.539893) (xy 264.276401 -394.581572)
			(xy 264.303057 -394.62774) (xy 264.322533 -394.677365) (xy 264.334396 -394.729339) (xy 264.33838 -394.7825)
			(xy 264.336432 -394.8085) (xy 266.919443 -394.8085) (xy 266.923474 -394.723896) (xy 266.935527 -394.640059)
			(xy 266.955496 -394.557747) (xy 266.983198 -394.477706) (xy 267.018382 -394.40066) (xy 267.060731 -394.327308)
			(xy 267.109861 -394.258313) (xy 267.165326 -394.194301) (xy 267.226625 -394.13585) (xy 267.293203 -394.083491)
			(xy 267.364456 -394.037698) (xy 267.439739 -393.998885) (xy 267.51837 -393.967403) (xy 267.599638 -393.943538)
			(xy 267.682807 -393.927507) (xy 267.767122 -393.919453) (xy 267.809472 -393.918948) (xy 267.850695 -393.919444)
			(xy 267.932787 -393.927077) (xy 268.013822 -393.942269) (xy 268.093103 -393.964892) (xy 268.169953 -393.994751)
			(xy 268.243711 -394.03159) (xy 268.313746 -394.075093) (xy 268.379456 -394.124888) (xy 268.410182 -394.152374)
			(xy 268.417414 -394.158461) (xy 268.435027 -394.165287) (xy 268.453917 -394.165287) (xy 268.47153 -394.158461)
			(xy 268.478762 -394.152374) (xy 268.509471 -394.124866) (xy 268.575178 -394.07506) (xy 268.645212 -394.031548)
			(xy 268.718971 -393.994703) (xy 268.795824 -393.964842) (xy 268.87511 -393.942221) (xy 268.95615 -393.927033)
			(xy 269.038247 -393.91941) (xy 269.079472 -393.918948) (xy 269.121265 -393.919428) (xy 269.204483 -393.927269)
			(xy 269.286598 -393.942885) (xy 269.366885 -393.966137) (xy 269.444636 -393.996821) (xy 269.519164 -394.034666)
			(xy 269.589812 -394.079337) (xy 269.655956 -394.130441) (xy 269.717013 -394.187526) (xy 269.772444 -394.250089)
			(xy 269.821759 -394.317577) (xy 269.864524 -394.389396) (xy 269.882874 -394.426948) (xy 269.909949 -394.428731)
			(xy 269.963129 -394.439499) (xy 270.014058 -394.458212) (xy 270.061558 -394.484438) (xy 270.104527 -394.517569)
			(xy 270.141971 -394.556837) (xy 270.173021 -394.601333) (xy 270.19696 -394.650026) (xy 270.213231 -394.701787)
			(xy 270.221458 -394.755419) (xy 270.221964 -394.782548) (xy 270.221496 -394.8085) (xy 272.854328 -394.8085)
			(xy 272.858359 -394.723891) (xy 272.870414 -394.640048) (xy 272.890384 -394.557731) (xy 272.918089 -394.477686)
			(xy 272.953277 -394.400636) (xy 272.995631 -394.32728) (xy 273.044766 -394.258282) (xy 273.100237 -394.194267)
			(xy 273.161542 -394.135816) (xy 273.228125 -394.083456) (xy 273.299385 -394.037663) (xy 273.374675 -393.998851)
			(xy 273.453313 -393.967372) (xy 273.534587 -393.943511) (xy 273.617762 -393.927483) (xy 273.702084 -393.919434)
			(xy 273.744436 -393.918948) (xy 273.78566 -393.919404) (xy 273.867754 -393.927042) (xy 273.948789 -393.942241)
			(xy 274.028071 -393.964869) (xy 274.10492 -393.994734) (xy 274.178678 -394.031578) (xy 274.248712 -394.075086)
			(xy 274.314421 -394.124886) (xy 274.345146 -394.152374) (xy 274.352378 -394.158461) (xy 274.369991 -394.165287)
			(xy 274.388881 -394.165287) (xy 274.406494 -394.158461) (xy 274.413726 -394.152374) (xy 274.44445 -394.124884)
			(xy 274.510154 -394.075076) (xy 274.580186 -394.031562) (xy 274.653943 -393.994716) (xy 274.730794 -393.964852)
			(xy 274.810078 -393.942228) (xy 274.891116 -393.927038) (xy 274.973211 -393.919412) (xy 275.014436 -393.918948)
			(xy 275.056229 -393.919459) (xy 275.139445 -393.927297) (xy 275.221559 -393.942909) (xy 275.301846 -393.966158)
			(xy 275.379596 -393.996839) (xy 275.454125 -394.034681) (xy 275.524773 -394.079349) (xy 275.590918 -394.130451)
			(xy 275.651975 -394.187533) (xy 275.707406 -394.250094) (xy 275.756722 -394.31758) (xy 275.799488 -394.389397)
			(xy 275.817838 -394.426948) (xy 275.844911 -394.428763) (xy 275.898089 -394.439526) (xy 275.949019 -394.458234)
			(xy 275.996518 -394.484456) (xy 276.039488 -394.517583) (xy 276.076932 -394.556848) (xy 276.107984 -394.601341)
			(xy 276.131922 -394.650031) (xy 276.148194 -394.70179) (xy 276.156421 -394.75542) (xy 276.156928 -394.782548)
			(xy 276.156405 -394.808456) (xy 278.916892 -394.808456) (xy 278.917356 -394.766262) (xy 278.925335 -394.682252)
			(xy 278.941234 -394.599376) (xy 278.964912 -394.518378) (xy 278.996156 -394.439987) (xy 279.034684 -394.364908)
			(xy 279.08015 -394.293815) (xy 279.132146 -394.227349) (xy 279.190203 -394.166106) (xy 279.2538 -394.110638)
			(xy 279.322365 -394.061443) (xy 279.395282 -394.018964) (xy 279.471894 -393.983582) (xy 279.551513 -393.955615)
			(xy 279.633423 -393.935316) (xy 279.675082 -393.9286) (xy 279.689459 -393.925944) (xy 279.715949 -393.913606)
			(xy 279.737852 -393.894262) (xy 279.753368 -393.869499) (xy 279.761223 -393.841352) (xy 279.760772 -393.812133)
			(xy 279.75687 -393.798044) (xy 279.744165 -393.755179) (xy 279.726399 -393.667554) (xy 279.717507 -393.578589)
			(xy 279.716992 -393.533884) (xy 279.717496 -393.491536) (xy 279.725547 -393.407222) (xy 279.741576 -393.324056)
			(xy 279.765437 -393.242789) (xy 279.796916 -393.164159) (xy 279.835727 -393.088878) (xy 279.881517 -393.017626)
			(xy 279.933873 -392.95105) (xy 279.992321 -392.889752) (xy 280.056331 -392.834287) (xy 280.125323 -392.785158)
			(xy 280.198673 -392.742809) (xy 280.275716 -392.707625) (xy 280.355755 -392.679923) (xy 280.438064 -392.659955)
			(xy 280.521899 -392.647902) (xy 280.6065 -392.643872) (xy 280.691101 -392.647902) (xy 280.774936 -392.659955)
			(xy 280.857245 -392.679923) (xy 280.937284 -392.707625) (xy 281.014327 -392.742809) (xy 281.087677 -392.785158)
			(xy 281.156669 -392.834287) (xy 281.220679 -392.889752) (xy 281.279127 -392.95105) (xy 281.331483 -393.017626)
			(xy 281.377273 -393.088878) (xy 281.416084 -393.164159) (xy 281.447563 -393.242789) (xy 281.471424 -393.324056)
			(xy 281.487453 -393.407222) (xy 281.495504 -393.491536) (xy 281.496008 -393.533884) (xy 281.495487 -393.576077)
			(xy 281.487514 -393.660085) (xy 281.47162 -393.74296) (xy 281.461756 -393.776708) (xy 289.471608 -393.776708)
			(xy 289.471608 -393.776454) (xy 289.47211 -393.744493) (xy 289.480121 -393.681075) (xy 289.496018 -393.619161)
			(xy 289.51955 -393.559728) (xy 289.550344 -393.503713) (xy 289.587917 -393.451998) (xy 289.631674 -393.405401)
			(xy 289.680927 -393.364656) (xy 289.734898 -393.330405) (xy 289.792737 -393.303188) (xy 289.85353 -393.283435)
			(xy 289.91632 -393.271457) (xy 289.980116 -393.267444) (xy 290.043912 -393.271457) (xy 290.106702 -393.283435)
			(xy 290.167495 -393.303188) (xy 290.225334 -393.330405) (xy 290.279305 -393.364656) (xy 290.328558 -393.405401)
			(xy 290.372315 -393.451998) (xy 290.409888 -393.503713) (xy 290.440682 -393.559728) (xy 290.464214 -393.619161)
			(xy 290.480111 -393.681075) (xy 290.488122 -393.744493) (xy 290.488624 -393.776454) (xy 290.488624 -393.7765)
			(xy 291.470768 -393.7765) (xy 291.474784 -393.712663) (xy 291.48677 -393.649832) (xy 291.506536 -393.589)
			(xy 291.533771 -393.531124) (xy 291.568045 -393.477118) (xy 291.608817 -393.427834) (xy 291.655445 -393.384049)
			(xy 291.707193 -393.346453) (xy 291.763245 -393.315639) (xy 291.822717 -393.292094) (xy 291.884671 -393.276188)
			(xy 291.94813 -393.268172) (xy 291.980112 -393.267692) (xy 292.010658 -393.268138) (xy 292.071311 -393.275449)
			(xy 292.13065 -393.289975) (xy 292.187822 -393.311508) (xy 292.242001 -393.339737) (xy 292.292406 -393.374254)
			(xy 292.338312 -393.414564) (xy 292.379057 -393.460084) (xy 292.396926 -393.484862) (xy 292.405296 -393.496027)
			(xy 292.426903 -393.51367) (xy 292.452477 -393.52481) (xy 292.480111 -393.528618) (xy 292.507745 -393.52481)
			(xy 292.533319 -393.51367) (xy 292.554926 -393.496027) (xy 292.563296 -393.484862) (xy 292.582389 -393.458454)
			(xy 292.626241 -393.410247) (xy 292.675892 -393.368039) (xy 292.730528 -393.332518) (xy 292.789254 -393.304269)
			(xy 292.851108 -393.283754) (xy 292.915076 -393.271309) (xy 292.98011 -393.267138) (xy 293.045144 -393.271309)
			(xy 293.109112 -393.283754) (xy 293.170966 -393.304269) (xy 293.229692 -393.332518) (xy 293.284328 -393.368039)
			(xy 293.333979 -393.410247) (xy 293.377831 -393.458454) (xy 293.396924 -393.484862) (xy 293.405294 -393.496027)
			(xy 293.426901 -393.51367) (xy 293.452475 -393.52481) (xy 293.480109 -393.528618) (xy 293.507743 -393.52481)
			(xy 293.533317 -393.51367) (xy 293.554924 -393.496027) (xy 293.563294 -393.484862) (xy 293.582387 -393.458454)
			(xy 293.626239 -393.410247) (xy 293.67589 -393.368039) (xy 293.730526 -393.332518) (xy 293.789252 -393.304269)
			(xy 293.851106 -393.283754) (xy 293.915074 -393.271309) (xy 293.980108 -393.267138) (xy 294.045142 -393.271309)
			(xy 294.10911 -393.283754) (xy 294.170964 -393.304269) (xy 294.22969 -393.332518) (xy 294.284326 -393.368039)
			(xy 294.333977 -393.410247) (xy 294.377829 -393.458454) (xy 294.396922 -393.484862) (xy 294.405292 -393.496027)
			(xy 294.426899 -393.51367) (xy 294.452473 -393.52481) (xy 294.480107 -393.528618) (xy 294.507741 -393.52481)
			(xy 294.533315 -393.51367) (xy 294.554922 -393.496027) (xy 294.563292 -393.484862) (xy 294.582385 -393.458454)
			(xy 294.626237 -393.410247) (xy 294.675888 -393.368039) (xy 294.730524 -393.332518) (xy 294.78925 -393.304269)
			(xy 294.851104 -393.283754) (xy 294.915072 -393.271309) (xy 294.980106 -393.267138) (xy 295.04514 -393.271309)
			(xy 295.109108 -393.283754) (xy 295.170962 -393.304269) (xy 295.229688 -393.332518) (xy 295.284324 -393.368039)
			(xy 295.333975 -393.410247) (xy 295.377827 -393.458454) (xy 295.39692 -393.484862) (xy 295.40529 -393.496027)
			(xy 295.426897 -393.51367) (xy 295.452471 -393.52481) (xy 295.480105 -393.528618) (xy 295.507739 -393.52481)
			(xy 295.533313 -393.51367) (xy 295.55492 -393.496027) (xy 295.56329 -393.484862) (xy 295.582383 -393.458454)
			(xy 295.626235 -393.410247) (xy 295.675886 -393.368039) (xy 295.730522 -393.332518) (xy 295.789248 -393.304269)
			(xy 295.851102 -393.283754) (xy 295.91507 -393.271309) (xy 295.980104 -393.267138) (xy 296.045138 -393.271309)
			(xy 296.109106 -393.283754) (xy 296.17096 -393.304269) (xy 296.229686 -393.332518) (xy 296.284322 -393.368039)
			(xy 296.333973 -393.410247) (xy 296.377825 -393.458454) (xy 296.396918 -393.484862) (xy 296.405288 -393.496027)
			(xy 296.426895 -393.51367) (xy 296.452469 -393.52481) (xy 296.480103 -393.528618) (xy 296.507737 -393.52481)
			(xy 296.533311 -393.51367) (xy 296.554918 -393.496027) (xy 296.563288 -393.484862) (xy 296.581151 -393.46008)
			(xy 296.621903 -393.414568) (xy 296.667813 -393.374265) (xy 296.71822 -393.339752) (xy 296.772399 -393.311525)
			(xy 296.829568 -393.289992) (xy 296.888906 -393.275462) (xy 296.949557 -393.268144) (xy 296.980102 -393.267692)
			(xy 297.012076 -393.268286) (xy 297.07552 -393.276301) (xy 297.137459 -393.292204) (xy 297.196916 -393.315745)
			(xy 297.252954 -393.346553) (xy 297.304689 -393.384141) (xy 297.351305 -393.427916) (xy 297.392067 -393.477189)
			(xy 297.426332 -393.531182) (xy 297.45356 -393.589044) (xy 297.473321 -393.649863) (xy 297.485304 -393.712678)
			(xy 297.489319 -393.7765) (xy 297.485304 -393.840322) (xy 297.473321 -393.903137) (xy 297.45356 -393.963956)
			(xy 297.426332 -394.021818) (xy 297.392067 -394.075811) (xy 297.351305 -394.125084) (xy 297.304689 -394.168859)
			(xy 297.252954 -394.206447) (xy 297.196916 -394.237255) (xy 297.137459 -394.260796) (xy 297.07552 -394.276699)
			(xy 297.012076 -394.284714) (xy 296.980102 -394.285216) (xy 296.949556 -394.284756) (xy 296.888904 -394.277447)
			(xy 296.829565 -394.262922) (xy 296.772394 -394.241392) (xy 296.718215 -394.213165) (xy 296.667809 -394.178649)
			(xy 296.621903 -394.138341) (xy 296.581158 -394.092823) (xy 296.563288 -394.068046) (xy 296.554946 -394.056837)
			(xy 296.53336 -394.03911) (xy 296.507771 -394.027912) (xy 296.480103 -394.024083) (xy 296.452435 -394.027912)
			(xy 296.426846 -394.03911) (xy 296.40526 -394.056837) (xy 296.396918 -394.068046) (xy 296.377825 -394.094454)
			(xy 296.333973 -394.142661) (xy 296.284322 -394.184869) (xy 296.229686 -394.22039) (xy 296.17096 -394.248639)
			(xy 296.109106 -394.269154) (xy 296.045138 -394.281599) (xy 295.980104 -394.28577) (xy 295.91507 -394.281599)
			(xy 295.851102 -394.269154) (xy 295.789248 -394.248639) (xy 295.730522 -394.22039) (xy 295.675886 -394.184869)
			(xy 295.626235 -394.142661) (xy 295.582383 -394.094454) (xy 295.56329 -394.068046) (xy 295.554948 -394.056837)
			(xy 295.533362 -394.03911) (xy 295.507773 -394.027912) (xy 295.480105 -394.024083) (xy 295.452437 -394.027912)
			(xy 295.426848 -394.03911) (xy 295.405262 -394.056837) (xy 295.39692 -394.068046) (xy 295.377827 -394.094454)
			(xy 295.333975 -394.142661) (xy 295.284324 -394.184869) (xy 295.229688 -394.22039) (xy 295.170962 -394.248639)
			(xy 295.109108 -394.269154) (xy 295.04514 -394.281599) (xy 294.980106 -394.28577) (xy 294.915072 -394.281599)
			(xy 294.851104 -394.269154) (xy 294.78925 -394.248639) (xy 294.730524 -394.22039) (xy 294.675888 -394.184869)
			(xy 294.626237 -394.142661) (xy 294.582385 -394.094454) (xy 294.563292 -394.068046) (xy 294.55495 -394.056837)
			(xy 294.533364 -394.03911) (xy 294.507775 -394.027912) (xy 294.480107 -394.024083) (xy 294.452439 -394.027912)
			(xy 294.42685 -394.03911) (xy 294.405264 -394.056837) (xy 294.396922 -394.068046) (xy 294.377829 -394.094454)
			(xy 294.333977 -394.142661) (xy 294.284326 -394.184869) (xy 294.22969 -394.22039) (xy 294.170964 -394.248639)
			(xy 294.10911 -394.269154) (xy 294.045142 -394.281599) (xy 293.980108 -394.28577) (xy 293.915074 -394.281599)
			(xy 293.851106 -394.269154) (xy 293.789252 -394.248639) (xy 293.730526 -394.22039) (xy 293.67589 -394.184869)
			(xy 293.626239 -394.142661) (xy 293.582387 -394.094454) (xy 293.563294 -394.068046) (xy 293.554952 -394.056837)
			(xy 293.533366 -394.03911) (xy 293.507777 -394.027912) (xy 293.480109 -394.024083) (xy 293.452441 -394.027912)
			(xy 293.426852 -394.03911) (xy 293.405266 -394.056837) (xy 293.396924 -394.068046) (xy 293.377831 -394.094454)
			(xy 293.333979 -394.142661) (xy 293.284328 -394.184869) (xy 293.229692 -394.22039) (xy 293.170966 -394.248639)
			(xy 293.109112 -394.269154) (xy 293.045144 -394.281599) (xy 292.98011 -394.28577) (xy 292.915076 -394.281599)
			(xy 292.851108 -394.269154) (xy 292.789254 -394.248639) (xy 292.730528 -394.22039) (xy 292.675892 -394.184869)
			(xy 292.626241 -394.142661) (xy 292.582389 -394.094454) (xy 292.563296 -394.068046) (xy 292.554954 -394.056837)
			(xy 292.533368 -394.03911) (xy 292.507779 -394.027912) (xy 292.480111 -394.024083) (xy 292.452443 -394.027912)
			(xy 292.426854 -394.03911) (xy 292.405268 -394.056837) (xy 292.396926 -394.068046) (xy 292.379057 -394.092823)
			(xy 292.338306 -394.138335) (xy 292.292396 -394.178638) (xy 292.24199 -394.213151) (xy 292.187812 -394.241378)
			(xy 292.130644 -394.262913) (xy 292.071307 -394.277444) (xy 292.010657 -394.284763) (xy 291.980112 -394.285216)
			(xy 291.94813 -394.284828) (xy 291.884671 -394.276812) (xy 291.822717 -394.260906) (xy 291.763245 -394.237361)
			(xy 291.707193 -394.206547) (xy 291.655445 -394.168951) (xy 291.608817 -394.125166) (xy 291.568045 -394.075882)
			(xy 291.533771 -394.021876) (xy 291.506536 -393.964) (xy 291.48677 -393.903168) (xy 291.474784 -393.840337)
			(xy 291.470768 -393.7765) (xy 290.488624 -393.7765) (xy 290.488624 -393.776962) (xy 290.488202 -393.806564)
			(xy 290.481324 -393.865367) (xy 290.467658 -393.922971) (xy 290.447389 -393.978597) (xy 290.420792 -394.03149)
			(xy 290.388226 -394.080932) (xy 290.369498 -394.10386) (xy 290.389588 -394.127178) (xy 290.424612 -394.17779)
			(xy 290.453267 -394.232263) (xy 290.475133 -394.289797) (xy 290.48989 -394.349552) (xy 290.497321 -394.410651)
			(xy 290.497768 -394.441426) (xy 290.497768 -394.44168) (xy 290.497266 -394.473641) (xy 290.489255 -394.537059)
			(xy 290.473358 -394.598973) (xy 290.449826 -394.658406) (xy 290.419032 -394.714421) (xy 290.381459 -394.766136)
			(xy 290.337702 -394.812733) (xy 290.288449 -394.853478) (xy 290.234478 -394.887729) (xy 290.176639 -394.914946)
			(xy 290.115846 -394.934699) (xy 290.053056 -394.946677) (xy 289.98926 -394.950691) (xy 289.925464 -394.946677)
			(xy 289.862674 -394.934699) (xy 289.801881 -394.914946) (xy 289.744042 -394.887729) (xy 289.690071 -394.853478)
			(xy 289.640818 -394.812733) (xy 289.597061 -394.766136) (xy 289.559488 -394.714421) (xy 289.528694 -394.658406)
			(xy 289.505162 -394.598973) (xy 289.489265 -394.537059) (xy 289.481254 -394.473641) (xy 289.480752 -394.44168)
			(xy 289.480752 -394.441172) (xy 289.481141 -394.411569) (xy 289.488026 -394.352765) (xy 289.501699 -394.29516)
			(xy 289.521974 -394.239535) (xy 289.548577 -394.186643) (xy 289.581148 -394.137202) (xy 289.599878 -394.114274)
			(xy 289.579769 -394.090972) (xy 289.544745 -394.040357) (xy 289.516091 -393.985882) (xy 289.494228 -393.928344)
			(xy 289.479476 -393.868586) (xy 289.472051 -393.807484) (xy 289.471608 -393.776708) (xy 281.461756 -393.776708)
			(xy 281.447947 -393.823957) (xy 281.416708 -393.902348) (xy 281.378185 -393.977427) (xy 281.332723 -394.04852)
			(xy 281.280732 -394.114986) (xy 281.222678 -394.176229) (xy 281.159084 -394.231698) (xy 281.090523 -394.280894)
			(xy 281.017609 -394.323374) (xy 280.941 -394.358757) (xy 280.861383 -394.386724) (xy 280.779476 -394.407024)
			(xy 280.737818 -394.41374) (xy 280.72343 -394.416347) (xy 280.696933 -394.428691) (xy 280.675026 -394.448046)
			(xy 280.659511 -394.472819) (xy 280.651661 -394.500977) (xy 280.652122 -394.530204) (xy 280.65603 -394.544296)
			(xy 280.668744 -394.587158) (xy 280.686507 -394.674785) (xy 280.695395 -394.763751) (xy 280.695908 -394.808456)
			(xy 280.695404 -394.850804) (xy 280.687353 -394.935118) (xy 280.671324 -395.018284) (xy 280.647463 -395.099551)
			(xy 280.615984 -395.178181) (xy 280.577173 -395.253462) (xy 280.531383 -395.324714) (xy 280.479027 -395.39129)
			(xy 280.420579 -395.452588) (xy 280.356569 -395.508053) (xy 280.287577 -395.557182) (xy 280.214227 -395.599531)
			(xy 280.137184 -395.634715) (xy 280.057145 -395.662417) (xy 279.974836 -395.682385) (xy 279.891001 -395.694438)
			(xy 279.8064 -395.698469) (xy 279.721799 -395.694438) (xy 279.637964 -395.682385) (xy 279.555655 -395.662417)
			(xy 279.475616 -395.634715) (xy 279.398573 -395.599531) (xy 279.325223 -395.557182) (xy 279.256231 -395.508053)
			(xy 279.192221 -395.452588) (xy 279.133773 -395.39129) (xy 279.081417 -395.324714) (xy 279.035627 -395.253462)
			(xy 278.996816 -395.178181) (xy 278.965337 -395.099551) (xy 278.941476 -395.018284) (xy 278.925447 -394.935118)
			(xy 278.917396 -394.850804) (xy 278.916892 -394.808456) (xy 276.156405 -394.808456) (xy 276.156404 -394.808503)
			(xy 276.148874 -394.859865) (xy 276.133965 -394.909589) (xy 276.111994 -394.956621) (xy 276.083427 -394.999964)
			(xy 276.048869 -395.038699) (xy 276.009052 -395.072006) (xy 275.964821 -395.099179) (xy 275.917114 -395.11964)
			(xy 275.86694 -395.132958) (xy 275.841206 -395.13637) (xy 275.825747 -395.174161) (xy 275.788816 -395.246988)
			(xy 275.745365 -395.316123) (xy 275.695761 -395.380985) (xy 275.64042 -395.441027) (xy 275.579808 -395.495744)
			(xy 275.514437 -395.544676) (xy 275.444856 -395.587409) (xy 275.371651 -395.623585) (xy 275.295438 -395.652899)
			(xy 275.216859 -395.675104) (xy 275.136576 -395.690013) (xy 275.055264 -395.6975) (xy 275.014436 -395.697964)
			(xy 274.973213 -395.69746) (xy 274.891121 -395.689828) (xy 274.810087 -395.674636) (xy 274.730806 -395.652015)
			(xy 274.653956 -395.622157) (xy 274.580198 -395.585319) (xy 274.510163 -395.541817) (xy 274.444452 -395.492024)
			(xy 274.413726 -395.464538) (xy 274.406494 -395.458451) (xy 274.388881 -395.451625) (xy 274.369991 -395.451625)
			(xy 274.352378 -395.458451) (xy 274.345146 -395.464538) (xy 274.314435 -395.492044) (xy 274.248729 -395.54185)
			(xy 274.178695 -395.585362) (xy 274.104936 -395.622207) (xy 274.028083 -395.652068) (xy 273.948797 -395.67469)
			(xy 273.867758 -395.689878) (xy 273.785661 -395.697501) (xy 273.744436 -395.697964) (xy 273.702084 -395.697566)
			(xy 273.617762 -395.689517) (xy 273.534587 -395.673489) (xy 273.453313 -395.649628) (xy 273.374675 -395.618149)
			(xy 273.299385 -395.579337) (xy 273.228125 -395.533544) (xy 273.161542 -395.481184) (xy 273.100237 -395.422733)
			(xy 273.044766 -395.358718) (xy 272.995631 -395.28972) (xy 272.953277 -395.216364) (xy 272.918089 -395.139314)
			(xy 272.890384 -395.059269) (xy 272.870414 -394.976952) (xy 272.858359 -394.893109) (xy 272.854328 -394.8085)
			(xy 270.221496 -394.8085) (xy 270.221496 -394.808506) (xy 270.213964 -394.859873) (xy 270.199053 -394.909601)
			(xy 270.177077 -394.956636) (xy 270.148504 -394.999982) (xy 270.113939 -395.038718) (xy 270.074115 -395.072025)
			(xy 270.029876 -395.099194) (xy 269.98216 -395.119651) (xy 269.93198 -395.132962) (xy 269.906242 -395.13637)
			(xy 269.890753 -395.174148) (xy 269.853824 -395.246974) (xy 269.810375 -395.316109) (xy 269.760773 -395.38097)
			(xy 269.705435 -395.441012) (xy 269.644826 -395.49573) (xy 269.579457 -395.544662) (xy 269.509879 -395.587396)
			(xy 269.436676 -395.623574) (xy 269.360466 -395.652889) (xy 269.28189 -395.675096) (xy 269.201609 -395.690008)
			(xy 269.120299 -395.697499) (xy 269.079472 -395.697964) (xy 269.038248 -395.6975) (xy 268.956155 -395.689862)
			(xy 268.87512 -395.674665) (xy 268.795838 -395.652037) (xy 268.718989 -395.622174) (xy 268.645231 -395.585331)
			(xy 268.575197 -395.541824) (xy 268.509487 -395.492026) (xy 268.478762 -395.464538) (xy 268.47153 -395.458451)
			(xy 268.453917 -395.451625) (xy 268.435027 -395.451625) (xy 268.417414 -395.458451) (xy 268.410182 -395.464538)
			(xy 268.379456 -395.492026) (xy 268.313752 -395.541834) (xy 268.243721 -395.585348) (xy 268.169964 -395.622194)
			(xy 268.093113 -395.652058) (xy 268.013829 -395.674682) (xy 267.932792 -395.689873) (xy 267.850696 -395.6975)
			(xy 267.809472 -395.697964) (xy 267.767122 -395.697547) (xy 267.682807 -395.689493) (xy 267.599638 -395.673462)
			(xy 267.51837 -395.649597) (xy 267.439739 -395.618115) (xy 267.364456 -395.579302) (xy 267.293203 -395.533509)
			(xy 267.226625 -395.48115) (xy 267.165326 -395.422699) (xy 267.109861 -395.358687) (xy 267.060731 -395.289692)
			(xy 267.018382 -395.21634) (xy 266.983198 -395.139294) (xy 266.955496 -395.059253) (xy 266.935527 -394.976941)
			(xy 266.923474 -394.893104) (xy 266.919443 -394.8085) (xy 264.336432 -394.8085) (xy 264.334396 -394.835661)
			(xy 264.322533 -394.887635) (xy 264.303057 -394.93726) (xy 264.276401 -394.983428) (xy 264.243162 -395.025107)
			(xy 264.204083 -395.061367) (xy 264.160035 -395.091397) (xy 264.112004 -395.114526) (xy 264.061062 -395.130239)
			(xy 264.008347 -395.138183) (xy 263.981692 -395.138656) (xy 263.970516 -395.138402) (xy 263.954928 -395.17605)
			(xy 263.917915 -395.248648) (xy 263.874417 -395.317555) (xy 263.824797 -395.382194) (xy 263.769471 -395.442023)
			(xy 263.708905 -395.496539) (xy 263.643605 -395.545287) (xy 263.57412 -395.587856) (xy 263.501032 -395.623891)
			(xy 263.424953 -395.653088) (xy 263.346523 -395.675203) (xy 263.266399 -395.69005) (xy 263.185252 -395.697505)
			(xy 263.144508 -395.697964) (xy 263.103285 -395.697477) (xy 263.021192 -395.689843) (xy 262.940158 -395.674649)
			(xy 262.860876 -395.652025) (xy 262.784027 -395.622164) (xy 262.710269 -395.585324) (xy 262.640234 -395.54182)
			(xy 262.574524 -395.492025) (xy 262.543798 -395.464538) (xy 262.536566 -395.458451) (xy 262.518953 -395.451625)
			(xy 262.500063 -395.451625) (xy 262.48245 -395.458451) (xy 262.475218 -395.464538) (xy 262.444477 -395.492009)
			(xy 262.378775 -395.541818) (xy 262.308747 -395.585333) (xy 262.234992 -395.622182) (xy 262.158144 -395.652048)
			(xy 262.078861 -395.674675) (xy 261.997826 -395.689868) (xy 261.915732 -395.697498) (xy 261.874508 -395.697964)
			(xy 261.832156 -395.697564) (xy 261.747837 -395.689513) (xy 261.664664 -395.673484) (xy 261.583392 -395.649621)
			(xy 261.504756 -395.61814) (xy 261.429469 -395.579328) (xy 261.358212 -395.533534) (xy 261.29163 -395.481174)
			(xy 261.230327 -395.422723) (xy 261.174858 -395.358709) (xy 261.125725 -395.289712) (xy 261.083374 -395.216357)
			(xy 261.048186 -395.139308) (xy 261.020483 -395.059264) (xy 261.000513 -394.976948) (xy 260.988458 -394.893107)
			(xy 260.984428 -394.8085) (xy 258.421708 -394.8085) (xy 258.419673 -394.835652) (xy 258.407813 -394.887617)
			(xy 258.388341 -394.937235) (xy 258.361693 -394.983396) (xy 258.328463 -395.025071) (xy 258.289393 -395.061327)
			(xy 258.245356 -395.091357) (xy 258.197335 -395.114488) (xy 258.146403 -395.130204) (xy 258.093699 -395.138155)
			(xy 258.067048 -395.138656) (xy 258.03606 -395.137386) (xy 258.020546 -395.175113) (xy 257.983557 -395.247826)
			(xy 257.940067 -395.316846) (xy 257.89044 -395.381595) (xy 257.835094 -395.441529) (xy 257.774494 -395.496144)
			(xy 257.709147 -395.544982) (xy 257.639604 -395.587632) (xy 257.566448 -395.623736) (xy 257.490294 -395.65299)
			(xy 257.411782 -395.67515) (xy 257.331571 -395.690029) (xy 257.250334 -395.697502) (xy 257.209544 -395.697964)
			(xy 257.168321 -395.697455) (xy 257.08623 -395.689824) (xy 257.005196 -395.674633) (xy 256.925914 -395.652012)
			(xy 256.849065 -395.622155) (xy 256.775306 -395.585317) (xy 256.705271 -395.541816) (xy 256.63956 -395.492023)
			(xy 256.608834 -395.464538) (xy 256.601602 -395.458451) (xy 256.583989 -395.451625) (xy 256.565099 -395.451625)
			(xy 256.547486 -395.458451) (xy 256.540254 -395.464538) (xy 256.50954 -395.49204) (xy 256.443834 -395.541846)
			(xy 256.373801 -395.585359) (xy 256.300042 -395.622204) (xy 256.22319 -395.652066) (xy 256.143904 -395.674688)
			(xy 256.062865 -395.689877) (xy 255.980769 -395.697501) (xy 255.939544 -395.697964) (xy 255.897191 -395.697566)
			(xy 255.812869 -395.689518) (xy 255.729694 -395.673491) (xy 255.648419 -395.64963) (xy 255.56978 -395.618151)
			(xy 255.494489 -395.57934) (xy 255.423229 -395.533547) (xy 255.356645 -395.481187) (xy 255.295339 -395.422735)
			(xy 255.239868 -395.358721) (xy 255.190732 -395.289723) (xy 255.148379 -395.216366) (xy 255.11319 -395.139316)
			(xy 255.085484 -395.05927) (xy 255.065514 -394.976952) (xy 255.053459 -394.893109) (xy 255.049428 -394.8085)
			(xy 252.441992 -394.8085) (xy 252.441968 -394.809821) (xy 252.433657 -394.863731) (xy 252.417221 -394.915743)
			(xy 252.393046 -394.964639) (xy 252.361695 -395.009276) (xy 252.323904 -395.04861) (xy 252.280556 -395.081721)
			(xy 252.232666 -395.107832) (xy 252.181353 -395.126335) (xy 252.127819 -395.136795) (xy 252.100588 -395.138402)
			(xy 252.085024 -395.17606) (xy 252.048009 -395.248659) (xy 252.004509 -395.317566) (xy 251.954887 -395.382206)
			(xy 251.89956 -395.442034) (xy 251.838991 -395.496551) (xy 251.773689 -395.545298) (xy 251.704202 -395.587866)
			(xy 251.631111 -395.623899) (xy 251.555031 -395.653095) (xy 251.476599 -395.675208) (xy 251.396473 -395.690054)
			(xy 251.315325 -395.697507) (xy 251.27458 -395.697964) (xy 251.233356 -395.697495) (xy 251.151263 -395.689858)
			(xy 251.070228 -395.674661) (xy 250.990947 -395.652035) (xy 250.914097 -395.622172) (xy 250.840339 -395.58533)
			(xy 250.770305 -395.541823) (xy 250.704595 -395.492026) (xy 250.67387 -395.464538) (xy 250.666638 -395.458451)
			(xy 250.649025 -395.451625) (xy 250.630135 -395.451625) (xy 250.612522 -395.458451) (xy 250.60529 -395.464538)
			(xy 250.574561 -395.492023) (xy 250.508857 -395.54183) (xy 250.438827 -395.585344) (xy 250.36507 -395.622192)
			(xy 250.28822 -395.652056) (xy 250.208936 -395.67468) (xy 250.127899 -395.689872) (xy 250.045804 -395.697499)
			(xy 250.00458 -395.697964) (xy 249.96223 -395.697547) (xy 249.877914 -395.689494) (xy 249.794745 -395.673463)
			(xy 249.713476 -395.649599) (xy 249.634844 -395.618118) (xy 249.55956 -395.579305) (xy 249.488307 -395.533512)
			(xy 249.421729 -395.481153) (xy 249.360429 -395.422702) (xy 249.304963 -395.35869) (xy 249.255833 -395.289695)
			(xy 249.213483 -395.216342) (xy 249.178298 -395.139296) (xy 249.150596 -395.059254) (xy 249.130628 -394.976942)
			(xy 249.118574 -394.893104) (xy 249.114543 -394.8085) (xy 246.481601 -394.8085) (xy 246.481601 -394.808504)
			(xy 246.474071 -394.859867) (xy 246.459161 -394.909593) (xy 246.437189 -394.956626) (xy 246.40862 -394.999969)
			(xy 246.374059 -395.038705) (xy 246.334241 -395.072012) (xy 246.290007 -395.099183) (xy 246.242297 -395.119644)
			(xy 246.192121 -395.132959) (xy 246.166386 -395.13637) (xy 246.15086 -395.174132) (xy 246.113933 -395.246957)
			(xy 246.070488 -395.316091) (xy 246.020888 -395.380952) (xy 245.965553 -395.440994) (xy 245.904948 -395.495712)
			(xy 245.839582 -395.544645) (xy 245.770007 -395.587381) (xy 245.696808 -395.62356) (xy 245.620601 -395.652878)
			(xy 245.542028 -395.675088) (xy 245.461749 -395.690002) (xy 245.380442 -395.697497) (xy 245.339616 -395.697964)
			(xy 245.298393 -395.697472) (xy 245.216301 -395.689839) (xy 245.135266 -395.674645) (xy 245.055985 -395.652022)
			(xy 244.979135 -395.622162) (xy 244.905377 -395.585323) (xy 244.835342 -395.541819) (xy 244.769632 -395.492024)
			(xy 244.738906 -395.464538) (xy 244.731674 -395.458451) (xy 244.714061 -395.451625) (xy 244.695171 -395.451625)
			(xy 244.677558 -395.458451) (xy 244.670326 -395.464538) (xy 244.639624 -395.492053) (xy 244.573916 -395.541859)
			(xy 244.503881 -395.58537) (xy 244.43012 -395.622214) (xy 244.353266 -395.652074) (xy 244.273979 -395.674694)
			(xy 244.192939 -395.68988) (xy 244.110841 -395.697502) (xy 244.069616 -395.697964) (xy 244.027264 -395.697565)
			(xy 243.942944 -395.689514) (xy 243.859771 -395.673485) (xy 243.778498 -395.649623) (xy 243.699861 -395.618143)
			(xy 243.624573 -395.57933) (xy 243.553315 -395.533537) (xy 243.486733 -395.481177) (xy 243.42543 -395.422726)
			(xy 243.36996 -395.358711) (xy 243.320827 -395.289714) (xy 243.278475 -395.216359) (xy 243.243287 -395.13931)
			(xy 243.215583 -395.059265) (xy 243.195613 -394.976949) (xy 243.183558 -394.893108) (xy 243.179528 -394.8085)
			(xy 3.523996 -394.8085) (xy 3.523996 -396.842996) (xy 18.90268 -396.842996) (xy 18.90268 -395.979396)
			(xy 18.903166 -395.952145) (xy 18.910922 -395.898197) (xy 18.926277 -395.845902) (xy 18.948919 -395.796325)
			(xy 18.978385 -395.750475) (xy 19.014076 -395.709284) (xy 19.055267 -395.673593) (xy 19.101117 -395.644127)
			(xy 19.150694 -395.621485) (xy 19.202989 -395.60613) (xy 19.256937 -395.598374) (xy 19.311439 -395.598374)
			(xy 19.365387 -395.60613) (xy 19.417682 -395.621485) (xy 19.467259 -395.644127) (xy 19.513109 -395.673593)
			(xy 19.5543 -395.709284) (xy 19.589991 -395.750475) (xy 19.601933 -395.769057) (xy 288.471858 -395.769057)
			(xy 288.471858 -395.705103) (xy 288.479873 -395.641653) (xy 288.495778 -395.579708) (xy 288.519321 -395.520246)
			(xy 288.550131 -395.464202) (xy 288.587723 -395.412462) (xy 288.631502 -395.365842) (xy 288.68078 -395.325076)
			(xy 288.734778 -395.290808) (xy 288.792645 -395.263577) (xy 288.853469 -395.243814) (xy 288.91629 -395.231831)
			(xy 288.980118 -395.227815) (xy 289.043946 -395.231831) (xy 289.106767 -395.243814) (xy 289.167591 -395.263577)
			(xy 289.225458 -395.290808) (xy 289.279456 -395.325076) (xy 289.328734 -395.365842) (xy 289.372513 -395.412462)
			(xy 289.410105 -395.464202) (xy 289.440915 -395.520246) (xy 289.464458 -395.579708) (xy 289.480363 -395.641653)
			(xy 289.488378 -395.705103) (xy 289.48888 -395.73708) (xy 289.488378 -395.769057) (xy 289.480363 -395.832507)
			(xy 289.464458 -395.894452) (xy 289.440915 -395.953914) (xy 289.410105 -396.009958) (xy 289.372513 -396.061698)
			(xy 289.328734 -396.108318) (xy 289.279456 -396.149084) (xy 289.225458 -396.183352) (xy 289.167591 -396.210583)
			(xy 289.106767 -396.230346) (xy 289.043946 -396.242329) (xy 288.980118 -396.246345) (xy 288.91629 -396.242329)
			(xy 288.853469 -396.230346) (xy 288.792645 -396.210583) (xy 288.734778 -396.183352) (xy 288.68078 -396.149084)
			(xy 288.631502 -396.108318) (xy 288.587723 -396.061698) (xy 288.550131 -396.009958) (xy 288.519321 -395.953914)
			(xy 288.495778 -395.894452) (xy 288.479873 -395.832507) (xy 288.471858 -395.769057) (xy 19.601933 -395.769057)
			(xy 19.619457 -395.796325) (xy 19.642099 -395.845902) (xy 19.657454 -395.898197) (xy 19.66521 -395.952145)
			(xy 19.665696 -395.979396) (xy 19.665696 -396.842996) (xy 19.66521 -396.870247) (xy 19.657454 -396.924195)
			(xy 19.642099 -396.97649) (xy 19.619457 -397.026067) (xy 19.589991 -397.071917) (xy 19.5543 -397.113108)
			(xy 19.513109 -397.148799) (xy 19.467259 -397.178265) (xy 19.417682 -397.200907) (xy 19.365387 -397.216262)
			(xy 19.311439 -397.224018) (xy 19.256937 -397.224018) (xy 19.202989 -397.216262) (xy 19.150694 -397.200907)
			(xy 19.101117 -397.178265) (xy 19.055267 -397.148799) (xy 19.014076 -397.113108) (xy 18.978385 -397.071917)
			(xy 18.948919 -397.026067) (xy 18.926277 -396.97649) (xy 18.910922 -396.924195) (xy 18.903166 -396.870247)
			(xy 18.90268 -396.842996) (xy 3.523996 -396.842996) (xy 3.523996 -397.606012) (xy 24.954992 -397.606012)
			(xy 24.954992 -396.742412) (xy 24.955478 -396.715161) (xy 24.963234 -396.661213) (xy 24.978589 -396.608918)
			(xy 25.001231 -396.559341) (xy 25.030697 -396.513491) (xy 25.066388 -396.4723) (xy 25.107579 -396.436609)
			(xy 25.153429 -396.407143) (xy 25.203006 -396.384501) (xy 25.255301 -396.369146) (xy 25.309249 -396.36139)
			(xy 25.363751 -396.36139) (xy 25.417699 -396.369146) (xy 25.469994 -396.384501) (xy 25.519571 -396.407143)
			(xy 25.565421 -396.436609) (xy 25.606612 -396.4723) (xy 25.642303 -396.513491) (xy 25.671769 -396.559341)
			(xy 25.694411 -396.608918) (xy 25.709766 -396.661213) (xy 25.717522 -396.715161) (xy 25.718008 -396.742412)
			(xy 25.718008 -397.606012) (xy 25.717522 -397.633263) (xy 25.709766 -397.687211) (xy 25.694411 -397.739506)
			(xy 25.671769 -397.789083) (xy 25.642303 -397.834933) (xy 25.606612 -397.876124) (xy 25.565421 -397.911815)
			(xy 25.519571 -397.941281) (xy 25.469994 -397.963923) (xy 25.417699 -397.979278) (xy 25.363751 -397.987034)
			(xy 25.309249 -397.987034) (xy 25.255301 -397.979278) (xy 25.203006 -397.963923) (xy 25.153429 -397.941281)
			(xy 25.107579 -397.911815) (xy 25.066388 -397.876124) (xy 25.030697 -397.834933) (xy 25.001231 -397.789083)
			(xy 24.978589 -397.739506) (xy 24.963234 -397.687211) (xy 24.955478 -397.633263) (xy 24.954992 -397.606012)
			(xy 3.523996 -397.606012) (xy 3.523996 -398.68657) (xy 36.781952 -398.68657) (xy 36.781952 -398.63203)
			(xy 36.789714 -398.578046) (xy 36.805081 -398.525717) (xy 36.827739 -398.476107) (xy 36.857227 -398.430227)
			(xy 36.892945 -398.389011) (xy 36.934165 -398.353298) (xy 36.980049 -398.323816) (xy 37.029662 -398.301164)
			(xy 37.081993 -398.285804) (xy 37.135978 -398.278048) (xy 37.163248 -398.277588) (xy 38.026848 -398.277588)
			(xy 38.054119 -398.277978) (xy 38.108104 -398.285746) (xy 38.160435 -398.301118) (xy 38.210045 -398.323779)
			(xy 38.255926 -398.353271) (xy 38.297144 -398.38899) (xy 38.332858 -398.430212) (xy 38.362344 -398.476097)
			(xy 38.384999 -398.52571) (xy 38.400364 -398.578043) (xy 38.408126 -398.632029) (xy 38.408126 -398.686571)
			(xy 38.400364 -398.740557) (xy 38.384999 -398.79289) (xy 38.38214 -398.799152) (xy 42.10455 -398.799152)
			(xy 42.10455 -398.744648) (xy 42.112306 -398.6907) (xy 42.12766 -398.638404) (xy 42.150301 -398.588826)
			(xy 42.179766 -398.542974) (xy 42.215456 -398.501781) (xy 42.256645 -398.466087) (xy 42.302494 -398.436618)
			(xy 42.35207 -398.413973) (xy 42.404365 -398.398614) (xy 42.458312 -398.390852) (xy 42.485564 -398.390364)
			(xy 43.349164 -398.390364) (xy 43.376417 -398.390881) (xy 43.430367 -398.398633) (xy 43.482666 -398.413985)
			(xy 43.532247 -398.436624) (xy 43.578101 -398.466088) (xy 43.619295 -398.50178) (xy 43.65499 -398.54297)
			(xy 43.684459 -398.588822) (xy 43.707103 -398.638401) (xy 43.722459 -398.690697) (xy 43.730217 -398.744648)
			(xy 43.730217 -398.799152) (xy 43.722459 -398.853103) (xy 43.707103 -398.9054) (xy 43.684459 -398.954978)
			(xy 43.65499 -399.00083) (xy 43.619295 -399.04202) (xy 43.578101 -399.077712) (xy 43.532247 -399.107176)
			(xy 43.482666 -399.129815) (xy 43.430367 -399.145167) (xy 43.376417 -399.152919) (xy 43.349164 -399.15338)
			(xy 42.485564 -399.15338) (xy 42.458312 -399.152948) (xy 42.404365 -399.145186) (xy 42.35207 -399.129827)
			(xy 42.302494 -399.107182) (xy 42.256645 -399.077713) (xy 42.215456 -399.042019) (xy 42.179766 -399.000826)
			(xy 42.150301 -398.954974) (xy 42.12766 -398.905396) (xy 42.112306 -398.8531) (xy 42.10455 -398.799152)
			(xy 38.38214 -398.799152) (xy 38.362344 -398.842503) (xy 38.332858 -398.888388) (xy 38.297144 -398.92961)
			(xy 38.255926 -398.965329) (xy 38.210045 -398.994821) (xy 38.160435 -399.017482) (xy 38.108104 -399.032854)
			(xy 38.054119 -399.040622) (xy 38.026848 -399.041112) (xy 37.163248 -399.041112) (xy 37.135978 -399.040552)
			(xy 37.081993 -399.032796) (xy 37.029662 -399.017436) (xy 36.980049 -398.994784) (xy 36.934165 -398.965302)
			(xy 36.892945 -398.929589) (xy 36.857227 -398.888373) (xy 36.827739 -398.842493) (xy 36.805081 -398.792883)
			(xy 36.789714 -398.740554) (xy 36.781952 -398.68657) (xy 3.523996 -398.68657) (xy 3.523996 -399.443249)
			(xy 18.470394 -399.443249) (xy 18.470394 -399.388751) (xy 18.47815 -399.334808) (xy 18.493503 -399.282518)
			(xy 18.516141 -399.232945) (xy 18.545603 -399.187098) (xy 18.58129 -399.14591) (xy 18.622475 -399.11022)
			(xy 18.66832 -399.080754) (xy 18.717892 -399.058112) (xy 18.770181 -399.042756) (xy 18.824123 -399.034996)
			(xy 18.851372 -399.034508) (xy 19.714972 -399.034508) (xy 19.742227 -399.034937) (xy 19.796184 -399.042691)
			(xy 19.848487 -399.058045) (xy 19.898073 -399.080687) (xy 19.943931 -399.110156) (xy 19.985129 -399.145851)
			(xy 20.020827 -399.187046) (xy 20.050299 -399.232903) (xy 20.072945 -399.282487) (xy 20.088303 -399.334789)
			(xy 20.096061 -399.388745) (xy 20.096061 -399.443255) (xy 20.088303 -399.497211) (xy 20.072945 -399.549513)
			(xy 20.050299 -399.599097) (xy 20.020828 -399.644954) (xy 19.985129 -399.686149) (xy 19.943931 -399.721844)
			(xy 19.898073 -399.751313) (xy 19.848487 -399.773955) (xy 19.796184 -399.789309) (xy 19.742227 -399.797063)
			(xy 19.714972 -399.797524) (xy 18.851372 -399.797524) (xy 18.824123 -399.797004) (xy 18.770181 -399.789244)
			(xy 18.717892 -399.773888) (xy 18.66832 -399.751246) (xy 18.622475 -399.72178) (xy 18.58129 -399.68609)
			(xy 18.545603 -399.644902) (xy 18.516141 -399.599055) (xy 18.493503 -399.549482) (xy 18.47815 -399.497192)
			(xy 18.470394 -399.443249) (xy 3.523996 -399.443249) (xy 3.523996 -400.459248) (xy 25.590794 -400.459248)
			(xy 25.590794 -400.404752) (xy 25.598549 -400.350811) (xy 25.613901 -400.298522) (xy 25.636538 -400.24895)
			(xy 25.665999 -400.203104) (xy 25.701684 -400.161916) (xy 25.742867 -400.126226) (xy 25.788709 -400.09676)
			(xy 25.838279 -400.074117) (xy 25.890566 -400.058759) (xy 25.944506 -400.050997) (xy 25.971754 -400.050508)
			(xy 26.835354 -400.050508) (xy 26.86261 -400.050936) (xy 26.916568 -400.058688) (xy 26.968874 -400.07404)
			(xy 27.018462 -400.096681) (xy 27.064323 -400.126149) (xy 27.105523 -400.161845) (xy 27.141223 -400.20304)
			(xy 27.170697 -400.248897) (xy 27.193343 -400.298483) (xy 27.208702 -400.350787) (xy 27.216461 -400.404744)
			(xy 27.216461 -400.459256) (xy 27.208702 -400.513213) (xy 27.193343 -400.565517) (xy 27.170697 -400.615103)
			(xy 27.141223 -400.66096) (xy 27.105523 -400.702155) (xy 27.064323 -400.737851) (xy 27.018462 -400.767319)
			(xy 26.968874 -400.78996) (xy 26.916568 -400.805312) (xy 26.86261 -400.813064) (xy 26.835354 -400.813524)
			(xy 25.971754 -400.813524) (xy 25.944506 -400.813003) (xy 25.890566 -400.805241) (xy 25.838279 -400.789883)
			(xy 25.788709 -400.76724) (xy 25.742867 -400.737774) (xy 25.701684 -400.702084) (xy 25.665999 -400.660896)
			(xy 25.636538 -400.61505) (xy 25.613901 -400.565478) (xy 25.598549 -400.513189) (xy 25.590794 -400.459248)
			(xy 3.523996 -400.459248) (xy 3.523996 -400.885453) (xy 47.598783 -400.885453) (xy 47.598783 -400.830947)
			(xy 47.606541 -400.776997) (xy 47.621898 -400.7247) (xy 47.644541 -400.675121) (xy 47.674011 -400.629269)
			(xy 47.709706 -400.588079) (xy 47.7509 -400.552388) (xy 47.796754 -400.522923) (xy 47.846336 -400.500284)
			(xy 47.898634 -400.484933) (xy 47.952585 -400.477181) (xy 47.979838 -400.47672) (xy 48.843438 -400.47672)
			(xy 48.870689 -400.477152) (xy 48.924637 -400.484914) (xy 48.976931 -400.500273) (xy 49.026507 -400.522918)
			(xy 49.072356 -400.552388) (xy 49.113545 -400.588082) (xy 49.149235 -400.629274) (xy 49.1787 -400.675126)
			(xy 49.20134 -400.724705) (xy 49.216694 -400.777) (xy 49.22445 -400.830948) (xy 49.22445 -400.885448)
			(xy 50.662106 -400.885448) (xy 50.662106 -400.830952) (xy 50.669862 -400.77701) (xy 50.685214 -400.724721)
			(xy 50.707852 -400.675149) (xy 50.737314 -400.629303) (xy 50.773001 -400.588116) (xy 50.814185 -400.552427)
			(xy 50.86003 -400.522963) (xy 50.9096 -400.500322) (xy 50.961888 -400.484966) (xy 51.01583 -400.477208)
			(xy 51.043078 -400.47672) (xy 51.906678 -400.47672) (xy 51.933934 -400.477125) (xy 51.987891 -400.48488)
			(xy 52.040196 -400.500236) (xy 52.089782 -400.522879) (xy 52.135642 -400.552348) (xy 52.17684 -400.588045)
			(xy 52.212539 -400.629241) (xy 52.242011 -400.675098) (xy 52.264657 -400.724684) (xy 52.280015 -400.776987)
			(xy 52.287773 -400.830944) (xy 52.287773 -400.885452) (xy 53.725283 -400.885452) (xy 53.725283 -400.830948)
			(xy 53.73304 -400.777) (xy 53.748396 -400.724704) (xy 53.771038 -400.675127) (xy 53.800506 -400.629276)
			(xy 53.836199 -400.588086) (xy 53.87739 -400.552395) (xy 53.923242 -400.52293) (xy 53.972821 -400.50029)
			(xy 54.025117 -400.484936) (xy 54.079066 -400.477182) (xy 54.106318 -400.47672) (xy 54.969918 -400.47672)
			(xy 54.99717 -400.477151) (xy 55.05112 -400.48491) (xy 55.103417 -400.500268) (xy 55.152995 -400.522912)
			(xy 55.198847 -400.552381) (xy 55.240038 -400.588075) (xy 55.27573 -400.629268) (xy 55.305197 -400.675121)
			(xy 55.327838 -400.7247) (xy 55.343194 -400.776997) (xy 55.35095 -400.830948) (xy 55.35095 -400.885447)
			(xy 56.788606 -400.885447) (xy 56.788606 -400.830953) (xy 56.796361 -400.777013) (xy 56.811713 -400.724725)
			(xy 56.834349 -400.675154) (xy 56.863809 -400.629309) (xy 56.899494 -400.588123) (xy 56.940676 -400.552435)
			(xy 56.986518 -400.522969) (xy 57.036086 -400.500327) (xy 57.088372 -400.48497) (xy 57.142311 -400.477209)
			(xy 57.169558 -400.47672) (xy 58.033158 -400.47672) (xy 58.060415 -400.477124) (xy 58.114374 -400.484877)
			(xy 58.166681 -400.50023) (xy 58.21627 -400.522872) (xy 58.262132 -400.552341) (xy 58.303333 -400.588037)
			(xy 58.339034 -400.629234) (xy 58.368508 -400.675093) (xy 58.391155 -400.724679) (xy 58.406514 -400.776985)
			(xy 58.414273 -400.830943) (xy 58.414273 -400.885449) (xy 59.851806 -400.885449) (xy 59.851806 -400.830951)
			(xy 59.859562 -400.777007) (xy 59.874916 -400.724717) (xy 59.897555 -400.675143) (xy 59.927019 -400.629296)
			(xy 59.962708 -400.588109) (xy 60.003895 -400.55242) (xy 60.049742 -400.522956) (xy 60.099315 -400.500317)
			(xy 60.151605 -400.484963) (xy 60.205549 -400.477206) (xy 60.232798 -400.47672) (xy 61.096398 -400.47672)
			(xy 61.123653 -400.477127) (xy 61.177608 -400.484884) (xy 61.22991 -400.500241) (xy 61.279494 -400.522885)
			(xy 61.325351 -400.552355) (xy 61.366547 -400.588052) (xy 61.402243 -400.629247) (xy 61.431714 -400.675104)
			(xy 61.454358 -400.724688) (xy 61.469715 -400.77699) (xy 61.477473 -400.830945) (xy 61.477473 -400.885453)
			(xy 62.914983 -400.885453) (xy 62.914983 -400.830947) (xy 62.922741 -400.776997) (xy 62.938098 -400.7247)
			(xy 62.960741 -400.675121) (xy 62.990211 -400.629269) (xy 63.025906 -400.588079) (xy 63.0671 -400.552388)
			(xy 63.112954 -400.522923) (xy 63.162536 -400.500284) (xy 63.214834 -400.484933) (xy 63.268785 -400.477181)
			(xy 63.296038 -400.47672) (xy 64.159638 -400.47672) (xy 64.186889 -400.477152) (xy 64.240837 -400.484914)
			(xy 64.293131 -400.500273) (xy 64.342707 -400.522918) (xy 64.388556 -400.552388) (xy 64.429745 -400.588082)
			(xy 64.465435 -400.629274) (xy 64.4949 -400.675126) (xy 64.51754 -400.724705) (xy 64.532894 -400.777)
			(xy 64.54065 -400.830948) (xy 64.54065 -400.885448) (xy 65.978306 -400.885448) (xy 65.978306 -400.830952)
			(xy 65.986062 -400.77701) (xy 66.001414 -400.724721) (xy 66.024052 -400.675149) (xy 66.053514 -400.629303)
			(xy 66.089201 -400.588116) (xy 66.130385 -400.552427) (xy 66.17623 -400.522963) (xy 66.2258 -400.500322)
			(xy 66.278088 -400.484966) (xy 66.33203 -400.477208) (xy 66.359278 -400.47672) (xy 67.222878 -400.47672)
			(xy 67.250134 -400.477125) (xy 67.304091 -400.48488) (xy 67.356396 -400.500236) (xy 67.405982 -400.522879)
			(xy 67.451842 -400.552348) (xy 67.49304 -400.588045) (xy 67.528739 -400.629241) (xy 67.558211 -400.675098)
			(xy 67.580857 -400.724684) (xy 67.596215 -400.776987) (xy 67.603973 -400.830944) (xy 67.603973 -400.885452)
			(xy 69.041483 -400.885452) (xy 69.041483 -400.830948) (xy 69.04924 -400.777) (xy 69.064596 -400.724704)
			(xy 69.087238 -400.675127) (xy 69.116706 -400.629276) (xy 69.152399 -400.588086) (xy 69.19359 -400.552395)
			(xy 69.239442 -400.52293) (xy 69.289021 -400.50029) (xy 69.341317 -400.484936) (xy 69.395266 -400.477182)
			(xy 69.422518 -400.47672) (xy 70.286118 -400.47672) (xy 70.31337 -400.477151) (xy 70.36732 -400.48491)
			(xy 70.419617 -400.500268) (xy 70.469195 -400.522912) (xy 70.515047 -400.552381) (xy 70.556238 -400.588075)
			(xy 70.59193 -400.629268) (xy 70.621397 -400.675121) (xy 70.644038 -400.7247) (xy 70.659394 -400.776997)
			(xy 70.66715 -400.830948) (xy 70.66715 -400.885447) (xy 72.104806 -400.885447) (xy 72.104806 -400.830953)
			(xy 72.112561 -400.777013) (xy 72.127913 -400.724725) (xy 72.150549 -400.675154) (xy 72.180009 -400.629309)
			(xy 72.215694 -400.588123) (xy 72.256876 -400.552435) (xy 72.302718 -400.522969) (xy 72.352286 -400.500327)
			(xy 72.404572 -400.48497) (xy 72.458511 -400.477209) (xy 72.485758 -400.47672) (xy 73.349358 -400.47672)
			(xy 73.376615 -400.477124) (xy 73.430574 -400.484877) (xy 73.482881 -400.50023) (xy 73.53247 -400.522872)
			(xy 73.578332 -400.552341) (xy 73.619533 -400.588037) (xy 73.655234 -400.629234) (xy 73.684708 -400.675093)
			(xy 73.707355 -400.724679) (xy 73.722714 -400.776985) (xy 73.730473 -400.830943) (xy 73.730473 -400.885449)
			(xy 75.168006 -400.885449) (xy 75.168006 -400.830951) (xy 75.175762 -400.777007) (xy 75.191116 -400.724717)
			(xy 75.213755 -400.675143) (xy 75.243219 -400.629296) (xy 75.278908 -400.588109) (xy 75.320095 -400.55242)
			(xy 75.365942 -400.522956) (xy 75.415515 -400.500317) (xy 75.467805 -400.484963) (xy 75.521749 -400.477206)
			(xy 75.548998 -400.47672) (xy 76.412598 -400.47672) (xy 76.439853 -400.477127) (xy 76.493808 -400.484884)
			(xy 76.54611 -400.500241) (xy 76.595694 -400.522885) (xy 76.641551 -400.552355) (xy 76.682747 -400.588052)
			(xy 76.718443 -400.629247) (xy 76.747914 -400.675104) (xy 76.770558 -400.724688) (xy 76.785915 -400.77699)
			(xy 76.793673 -400.830945) (xy 76.793673 -400.885453) (xy 78.231183 -400.885453) (xy 78.231183 -400.830947)
			(xy 78.238941 -400.776997) (xy 78.254298 -400.7247) (xy 78.276941 -400.675121) (xy 78.306411 -400.629269)
			(xy 78.342106 -400.588079) (xy 78.3833 -400.552388) (xy 78.429154 -400.522923) (xy 78.478736 -400.500284)
			(xy 78.531034 -400.484933) (xy 78.584985 -400.477181) (xy 78.612238 -400.47672) (xy 79.475838 -400.47672)
			(xy 79.503089 -400.477152) (xy 79.557037 -400.484914) (xy 79.609331 -400.500273) (xy 79.658907 -400.522918)
			(xy 79.704756 -400.552388) (xy 79.745945 -400.588082) (xy 79.781635 -400.629274) (xy 79.8111 -400.675126)
			(xy 79.83374 -400.724705) (xy 79.849094 -400.777) (xy 79.85685 -400.830948) (xy 79.85685 -400.885448)
			(xy 81.294506 -400.885448) (xy 81.294506 -400.830952) (xy 81.302262 -400.77701) (xy 81.317614 -400.724721)
			(xy 81.340252 -400.675149) (xy 81.369714 -400.629303) (xy 81.405401 -400.588116) (xy 81.446585 -400.552427)
			(xy 81.49243 -400.522963) (xy 81.542 -400.500322) (xy 81.594288 -400.484966) (xy 81.64823 -400.477208)
			(xy 81.675478 -400.47672) (xy 82.539078 -400.47672) (xy 82.566334 -400.477125) (xy 82.620291 -400.48488)
			(xy 82.672596 -400.500236) (xy 82.722182 -400.522879) (xy 82.768042 -400.552348) (xy 82.80924 -400.588045)
			(xy 82.844939 -400.629241) (xy 82.874411 -400.675098) (xy 82.897057 -400.724684) (xy 82.912415 -400.776987)
			(xy 82.920173 -400.830944) (xy 82.920173 -400.885452) (xy 84.357683 -400.885452) (xy 84.357683 -400.830948)
			(xy 84.36544 -400.777) (xy 84.380796 -400.724704) (xy 84.403438 -400.675127) (xy 84.432906 -400.629276)
			(xy 84.468599 -400.588086) (xy 84.50979 -400.552395) (xy 84.555642 -400.52293) (xy 84.605221 -400.50029)
			(xy 84.657517 -400.484936) (xy 84.711466 -400.477182) (xy 84.738718 -400.47672) (xy 85.602318 -400.47672)
			(xy 85.62957 -400.477151) (xy 85.68352 -400.48491) (xy 85.735817 -400.500268) (xy 85.785395 -400.522912)
			(xy 85.831247 -400.552381) (xy 85.872438 -400.588075) (xy 85.90813 -400.629268) (xy 85.937597 -400.675121)
			(xy 85.960238 -400.7247) (xy 85.975594 -400.776997) (xy 85.98335 -400.830948) (xy 85.98335 -400.885447)
			(xy 87.421006 -400.885447) (xy 87.421006 -400.830953) (xy 87.428761 -400.777013) (xy 87.444113 -400.724725)
			(xy 87.466749 -400.675154) (xy 87.496209 -400.629309) (xy 87.531894 -400.588123) (xy 87.573076 -400.552435)
			(xy 87.618918 -400.522969) (xy 87.668486 -400.500327) (xy 87.720772 -400.48497) (xy 87.774711 -400.477209)
			(xy 87.801958 -400.47672) (xy 88.665558 -400.47672) (xy 88.692815 -400.477124) (xy 88.746774 -400.484877)
			(xy 88.799081 -400.50023) (xy 88.84867 -400.522872) (xy 88.894532 -400.552341) (xy 88.935733 -400.588037)
			(xy 88.971434 -400.629234) (xy 89.000908 -400.675093) (xy 89.023555 -400.724679) (xy 89.038914 -400.776985)
			(xy 89.046673 -400.830943) (xy 89.046673 -400.885449) (xy 90.484206 -400.885449) (xy 90.484206 -400.830951)
			(xy 90.491962 -400.777007) (xy 90.507316 -400.724717) (xy 90.529955 -400.675143) (xy 90.559419 -400.629296)
			(xy 90.595108 -400.588109) (xy 90.636295 -400.55242) (xy 90.682142 -400.522956) (xy 90.731715 -400.500317)
			(xy 90.784005 -400.484963) (xy 90.837949 -400.477206) (xy 90.865198 -400.47672) (xy 91.728798 -400.47672)
			(xy 91.756053 -400.477127) (xy 91.810008 -400.484884) (xy 91.86231 -400.500241) (xy 91.911894 -400.522885)
			(xy 91.957751 -400.552355) (xy 91.998947 -400.588052) (xy 92.034643 -400.629247) (xy 92.064114 -400.675104)
			(xy 92.086758 -400.724688) (xy 92.102115 -400.77699) (xy 92.109873 -400.830945) (xy 92.109873 -400.885453)
			(xy 93.547383 -400.885453) (xy 93.547383 -400.830947) (xy 93.555141 -400.776997) (xy 93.570498 -400.7247)
			(xy 93.593141 -400.675121) (xy 93.622611 -400.629269) (xy 93.658306 -400.588079) (xy 93.6995 -400.552388)
			(xy 93.745354 -400.522923) (xy 93.794936 -400.500284) (xy 93.847234 -400.484933) (xy 93.901185 -400.477181)
			(xy 93.928438 -400.47672) (xy 94.792038 -400.47672) (xy 94.819289 -400.477152) (xy 94.873237 -400.484914)
			(xy 94.925531 -400.500273) (xy 94.975107 -400.522918) (xy 95.020956 -400.552388) (xy 95.062145 -400.588082)
			(xy 95.097835 -400.629274) (xy 95.1273 -400.675126) (xy 95.14994 -400.724705) (xy 95.165294 -400.777)
			(xy 95.17305 -400.830948) (xy 95.17305 -400.885447) (xy 119.774006 -400.885447) (xy 119.774006 -400.830953)
			(xy 119.781761 -400.777013) (xy 119.797112 -400.724726) (xy 119.819749 -400.675156) (xy 119.849208 -400.629311)
			(xy 119.884892 -400.588125) (xy 119.926074 -400.552436) (xy 119.971915 -400.522971) (xy 120.021483 -400.500329)
			(xy 120.073768 -400.484971) (xy 120.127707 -400.477209) (xy 120.154954 -400.47672) (xy 121.018554 -400.47672)
			(xy 121.045811 -400.477124) (xy 121.099771 -400.484876) (xy 121.152078 -400.500229) (xy 121.201668 -400.522871)
			(xy 121.24753 -400.55234) (xy 121.288731 -400.588036) (xy 121.324433 -400.629233) (xy 121.353907 -400.675092)
			(xy 121.376555 -400.724679) (xy 121.391914 -400.776984) (xy 121.399673 -400.830943) (xy 121.399673 -400.885449)
			(xy 122.837206 -400.885449) (xy 122.837206 -400.830951) (xy 122.844962 -400.777008) (xy 122.860316 -400.724717)
			(xy 122.882955 -400.675144) (xy 122.912418 -400.629298) (xy 122.948106 -400.588111) (xy 122.989293 -400.552422)
			(xy 123.035139 -400.522958) (xy 123.084712 -400.500318) (xy 123.137002 -400.484963) (xy 123.190945 -400.477207)
			(xy 123.218194 -400.47672) (xy 124.081794 -400.47672) (xy 124.109049 -400.477127) (xy 124.163005 -400.484883)
			(xy 124.215307 -400.50024) (xy 124.264892 -400.522884) (xy 124.310749 -400.552354) (xy 124.351946 -400.58805)
			(xy 124.387643 -400.629246) (xy 124.417113 -400.675103) (xy 124.439758 -400.724687) (xy 124.455115 -400.776989)
			(xy 124.462873 -400.830945) (xy 124.462873 -400.885452) (xy 125.900383 -400.885452) (xy 125.900383 -400.830948)
			(xy 125.908141 -400.776998) (xy 125.923497 -400.724701) (xy 125.946141 -400.675122) (xy 125.97561 -400.629271)
			(xy 126.011304 -400.58808) (xy 126.052498 -400.552389) (xy 126.098352 -400.522924) (xy 126.147933 -400.500285)
			(xy 126.200231 -400.484933) (xy 126.254182 -400.477181) (xy 126.281434 -400.47672) (xy 127.145034 -400.47672)
			(xy 127.172286 -400.477152) (xy 127.226234 -400.484913) (xy 127.278528 -400.500272) (xy 127.328105 -400.522917)
			(xy 127.373954 -400.552386) (xy 127.415143 -400.588081) (xy 127.450834 -400.629273) (xy 127.480299 -400.675125)
			(xy 127.50294 -400.724704) (xy 127.518294 -400.777) (xy 127.52605 -400.830948) (xy 127.52605 -400.885448)
			(xy 128.963706 -400.885448) (xy 128.963706 -400.830952) (xy 128.971461 -400.777011) (xy 128.986814 -400.724722)
			(xy 129.009452 -400.67515) (xy 129.038913 -400.629304) (xy 129.074599 -400.588118) (xy 129.115783 -400.552429)
			(xy 129.161627 -400.522964) (xy 129.211197 -400.500323) (xy 129.263485 -400.484967) (xy 129.317426 -400.477208)
			(xy 129.344674 -400.47672) (xy 130.208274 -400.47672) (xy 130.23553 -400.477125) (xy 130.289488 -400.48488)
			(xy 130.341793 -400.500235) (xy 130.39138 -400.522877) (xy 130.43724 -400.552347) (xy 130.478438 -400.588043)
			(xy 130.514138 -400.62924) (xy 130.54361 -400.675097) (xy 130.566256 -400.724683) (xy 130.581615 -400.776987)
			(xy 130.589373 -400.830944) (xy 130.589373 -400.885451) (xy 132.026883 -400.885451) (xy 132.026883 -400.830949)
			(xy 132.03464 -400.777) (xy 132.049996 -400.724705) (xy 132.072638 -400.675128) (xy 132.102105 -400.629277)
			(xy 132.137797 -400.588087) (xy 132.178989 -400.552396) (xy 132.22484 -400.522931) (xy 132.274418 -400.500291)
			(xy 132.326714 -400.484937) (xy 132.380662 -400.477182) (xy 132.407914 -400.47672) (xy 133.271514 -400.47672)
			(xy 133.298767 -400.477151) (xy 133.352717 -400.48491) (xy 133.405014 -400.500267) (xy 133.454593 -400.522911)
			(xy 133.500445 -400.552379) (xy 133.541636 -400.588074) (xy 133.577329 -400.629266) (xy 133.606796 -400.67512)
			(xy 133.629438 -400.724699) (xy 133.644793 -400.776997) (xy 133.65255 -400.830947) (xy 133.65255 -400.885447)
			(xy 135.090206 -400.885447) (xy 135.090206 -400.830953) (xy 135.097961 -400.777013) (xy 135.113312 -400.724726)
			(xy 135.135949 -400.675156) (xy 135.165408 -400.629311) (xy 135.201092 -400.588125) (xy 135.242274 -400.552436)
			(xy 135.288115 -400.522971) (xy 135.337683 -400.500329) (xy 135.389968 -400.484971) (xy 135.443907 -400.477209)
			(xy 135.471154 -400.47672) (xy 136.334754 -400.47672) (xy 136.362011 -400.477124) (xy 136.415971 -400.484876)
			(xy 136.468278 -400.500229) (xy 136.517868 -400.522871) (xy 136.56373 -400.55234) (xy 136.604931 -400.588036)
			(xy 136.640633 -400.629233) (xy 136.670107 -400.675092) (xy 136.692755 -400.724679) (xy 136.708114 -400.776984)
			(xy 136.715873 -400.830943) (xy 136.715873 -400.885449) (xy 138.153406 -400.885449) (xy 138.153406 -400.830951)
			(xy 138.161162 -400.777008) (xy 138.176516 -400.724717) (xy 138.199155 -400.675144) (xy 138.228618 -400.629298)
			(xy 138.264306 -400.588111) (xy 138.305493 -400.552422) (xy 138.351339 -400.522958) (xy 138.400912 -400.500318)
			(xy 138.453202 -400.484963) (xy 138.507145 -400.477207) (xy 138.534394 -400.47672) (xy 139.397994 -400.47672)
			(xy 139.425249 -400.477127) (xy 139.479205 -400.484883) (xy 139.531507 -400.50024) (xy 139.581092 -400.522884)
			(xy 139.626949 -400.552354) (xy 139.668146 -400.58805) (xy 139.703843 -400.629246) (xy 139.733313 -400.675103)
			(xy 139.755958 -400.724687) (xy 139.771315 -400.776989) (xy 139.779073 -400.830945) (xy 139.779073 -400.885452)
			(xy 141.216583 -400.885452) (xy 141.216583 -400.830948) (xy 141.224341 -400.776998) (xy 141.239697 -400.724701)
			(xy 141.262341 -400.675122) (xy 141.29181 -400.629271) (xy 141.327504 -400.58808) (xy 141.368698 -400.552389)
			(xy 141.414552 -400.522924) (xy 141.464133 -400.500285) (xy 141.516431 -400.484933) (xy 141.570382 -400.477181)
			(xy 141.597634 -400.47672) (xy 142.461234 -400.47672) (xy 142.488486 -400.477152) (xy 142.542434 -400.484913)
			(xy 142.594728 -400.500272) (xy 142.644305 -400.522917) (xy 142.690154 -400.552386) (xy 142.731343 -400.588081)
			(xy 142.767034 -400.629273) (xy 142.796499 -400.675125) (xy 142.81914 -400.724704) (xy 142.834494 -400.777)
			(xy 142.84225 -400.830948) (xy 142.84225 -400.885448) (xy 144.279906 -400.885448) (xy 144.279906 -400.830952)
			(xy 144.287661 -400.777011) (xy 144.303014 -400.724722) (xy 144.325652 -400.67515) (xy 144.355113 -400.629304)
			(xy 144.390799 -400.588118) (xy 144.431983 -400.552429) (xy 144.477827 -400.522964) (xy 144.527397 -400.500323)
			(xy 144.579685 -400.484967) (xy 144.633626 -400.477208) (xy 144.660874 -400.47672) (xy 145.524474 -400.47672)
			(xy 145.55173 -400.477125) (xy 145.605688 -400.48488) (xy 145.657993 -400.500235) (xy 145.70758 -400.522877)
			(xy 145.75344 -400.552347) (xy 145.794638 -400.588043) (xy 145.830338 -400.62924) (xy 145.85981 -400.675097)
			(xy 145.882456 -400.724683) (xy 145.897815 -400.776987) (xy 145.905573 -400.830944) (xy 145.905573 -400.885451)
			(xy 147.343083 -400.885451) (xy 147.343083 -400.830949) (xy 147.35084 -400.777) (xy 147.366196 -400.724705)
			(xy 147.388838 -400.675128) (xy 147.418305 -400.629277) (xy 147.453997 -400.588087) (xy 147.495189 -400.552396)
			(xy 147.54104 -400.522931) (xy 147.590618 -400.500291) (xy 147.642914 -400.484937) (xy 147.696862 -400.477182)
			(xy 147.724114 -400.47672) (xy 148.587714 -400.47672) (xy 148.614967 -400.477151) (xy 148.668917 -400.48491)
			(xy 148.721214 -400.500267) (xy 148.770793 -400.522911) (xy 148.816645 -400.552379) (xy 148.857836 -400.588074)
			(xy 148.893529 -400.629266) (xy 148.922996 -400.67512) (xy 148.945638 -400.724699) (xy 148.960993 -400.776997)
			(xy 148.96875 -400.830947) (xy 148.96875 -400.885447) (xy 150.406406 -400.885447) (xy 150.406406 -400.830953)
			(xy 150.414161 -400.777013) (xy 150.429512 -400.724726) (xy 150.452149 -400.675156) (xy 150.481608 -400.629311)
			(xy 150.517292 -400.588125) (xy 150.558474 -400.552436) (xy 150.604315 -400.522971) (xy 150.653883 -400.500329)
			(xy 150.706168 -400.484971) (xy 150.760107 -400.477209) (xy 150.787354 -400.47672) (xy 151.650954 -400.47672)
			(xy 151.678211 -400.477124) (xy 151.732171 -400.484876) (xy 151.784478 -400.500229) (xy 151.834068 -400.522871)
			(xy 151.87993 -400.55234) (xy 151.921131 -400.588036) (xy 151.956833 -400.629233) (xy 151.986307 -400.675092)
			(xy 152.008955 -400.724679) (xy 152.024314 -400.776984) (xy 152.032073 -400.830943) (xy 152.032073 -400.885449)
			(xy 153.469606 -400.885449) (xy 153.469606 -400.830951) (xy 153.477362 -400.777008) (xy 153.492716 -400.724717)
			(xy 153.515355 -400.675144) (xy 153.544818 -400.629298) (xy 153.580506 -400.588111) (xy 153.621693 -400.552422)
			(xy 153.667539 -400.522958) (xy 153.717112 -400.500318) (xy 153.769402 -400.484963) (xy 153.823345 -400.477207)
			(xy 153.850594 -400.47672) (xy 154.714194 -400.47672) (xy 154.741449 -400.477127) (xy 154.795405 -400.484883)
			(xy 154.847707 -400.50024) (xy 154.897292 -400.522884) (xy 154.943149 -400.552354) (xy 154.984346 -400.58805)
			(xy 155.020043 -400.629246) (xy 155.049513 -400.675103) (xy 155.072158 -400.724687) (xy 155.087515 -400.776989)
			(xy 155.095273 -400.830945) (xy 155.095273 -400.885452) (xy 156.532783 -400.885452) (xy 156.532783 -400.830948)
			(xy 156.540541 -400.776998) (xy 156.555897 -400.724701) (xy 156.578541 -400.675122) (xy 156.60801 -400.629271)
			(xy 156.643704 -400.58808) (xy 156.684898 -400.552389) (xy 156.730752 -400.522924) (xy 156.780333 -400.500285)
			(xy 156.832631 -400.484933) (xy 156.886582 -400.477181) (xy 156.913834 -400.47672) (xy 157.777434 -400.47672)
			(xy 157.804686 -400.477152) (xy 157.858634 -400.484913) (xy 157.910928 -400.500272) (xy 157.960505 -400.522917)
			(xy 158.006354 -400.552386) (xy 158.047543 -400.588081) (xy 158.083234 -400.629273) (xy 158.112699 -400.675125)
			(xy 158.13534 -400.724704) (xy 158.150694 -400.777) (xy 158.15845 -400.830948) (xy 158.15845 -400.885448)
			(xy 159.596106 -400.885448) (xy 159.596106 -400.830952) (xy 159.603861 -400.777011) (xy 159.619214 -400.724722)
			(xy 159.641852 -400.67515) (xy 159.671313 -400.629304) (xy 159.706999 -400.588118) (xy 159.748183 -400.552429)
			(xy 159.794027 -400.522964) (xy 159.843597 -400.500323) (xy 159.895885 -400.484967) (xy 159.949826 -400.477208)
			(xy 159.977074 -400.47672) (xy 160.840674 -400.47672) (xy 160.86793 -400.477125) (xy 160.921888 -400.48488)
			(xy 160.974193 -400.500235) (xy 161.02378 -400.522877) (xy 161.06964 -400.552347) (xy 161.110838 -400.588043)
			(xy 161.146538 -400.62924) (xy 161.17601 -400.675097) (xy 161.198656 -400.724683) (xy 161.214015 -400.776987)
			(xy 161.221773 -400.830944) (xy 161.221773 -400.885451) (xy 162.659283 -400.885451) (xy 162.659283 -400.830949)
			(xy 162.66704 -400.777) (xy 162.682396 -400.724705) (xy 162.705038 -400.675128) (xy 162.734505 -400.629277)
			(xy 162.770197 -400.588087) (xy 162.811389 -400.552396) (xy 162.85724 -400.522931) (xy 162.906818 -400.500291)
			(xy 162.959114 -400.484937) (xy 163.013062 -400.477182) (xy 163.040314 -400.47672) (xy 163.903914 -400.47672)
			(xy 163.931167 -400.477151) (xy 163.985117 -400.48491) (xy 164.037414 -400.500267) (xy 164.086993 -400.522911)
			(xy 164.132845 -400.552379) (xy 164.174036 -400.588074) (xy 164.209729 -400.629266) (xy 164.239196 -400.67512)
			(xy 164.261838 -400.724699) (xy 164.277193 -400.776997) (xy 164.28495 -400.830947) (xy 164.28495 -400.885447)
			(xy 165.722606 -400.885447) (xy 165.722606 -400.830953) (xy 165.730361 -400.777013) (xy 165.745712 -400.724726)
			(xy 165.768349 -400.675156) (xy 165.797808 -400.629311) (xy 165.833492 -400.588125) (xy 165.874674 -400.552436)
			(xy 165.920515 -400.522971) (xy 165.970083 -400.500329) (xy 166.022368 -400.484971) (xy 166.076307 -400.477209)
			(xy 166.103554 -400.47672) (xy 166.967154 -400.47672) (xy 166.994411 -400.477124) (xy 167.048371 -400.484876)
			(xy 167.100678 -400.500229) (xy 167.150268 -400.522871) (xy 167.19613 -400.55234) (xy 167.237331 -400.588036)
			(xy 167.273033 -400.629233) (xy 167.302507 -400.675092) (xy 167.325155 -400.724679) (xy 167.340514 -400.776984)
			(xy 167.348273 -400.830943) (xy 167.348273 -400.885457) (xy 167.340514 -400.939416) (xy 167.325155 -400.991721)
			(xy 167.302507 -401.041308) (xy 167.273033 -401.087167) (xy 167.237331 -401.128364) (xy 167.19613 -401.16406)
			(xy 167.150268 -401.193529) (xy 167.100678 -401.216171) (xy 167.048371 -401.231524) (xy 166.994411 -401.239276)
			(xy 166.967154 -401.239736) (xy 166.103554 -401.239736) (xy 166.076307 -401.239191) (xy 166.022368 -401.231429)
			(xy 165.970083 -401.216071) (xy 165.920515 -401.193429) (xy 165.874674 -401.163964) (xy 165.833492 -401.128275)
			(xy 165.797808 -401.087089) (xy 165.768349 -401.041244) (xy 165.745712 -400.991674) (xy 165.730361 -400.939387)
			(xy 165.722606 -400.885447) (xy 164.28495 -400.885447) (xy 164.28495 -400.885453) (xy 164.277193 -400.939403)
			(xy 164.261838 -400.991701) (xy 164.239196 -401.04128) (xy 164.209729 -401.087134) (xy 164.174036 -401.128326)
			(xy 164.132845 -401.164021) (xy 164.086993 -401.193489) (xy 164.037414 -401.216133) (xy 163.985117 -401.23149)
			(xy 163.931167 -401.239249) (xy 163.903914 -401.239736) (xy 163.040314 -401.239736) (xy 163.013062 -401.239218)
			(xy 162.959114 -401.231463) (xy 162.906818 -401.216109) (xy 162.85724 -401.193469) (xy 162.811389 -401.164004)
			(xy 162.770197 -401.128313) (xy 162.734505 -401.087123) (xy 162.705038 -401.041272) (xy 162.682396 -400.991695)
			(xy 162.66704 -400.9394) (xy 162.659283 -400.885451) (xy 161.221773 -400.885451) (xy 161.221773 -400.885456)
			(xy 161.214015 -400.939413) (xy 161.198656 -400.991717) (xy 161.17601 -401.041303) (xy 161.146538 -401.08716)
			(xy 161.110838 -401.128357) (xy 161.06964 -401.164053) (xy 161.02378 -401.193523) (xy 160.974193 -401.216165)
			(xy 160.921888 -401.23152) (xy 160.86793 -401.239275) (xy 160.840674 -401.239736) (xy 159.977074 -401.239736)
			(xy 159.949826 -401.239192) (xy 159.895885 -401.231433) (xy 159.843597 -401.216077) (xy 159.794027 -401.193436)
			(xy 159.748183 -401.163971) (xy 159.706999 -401.128282) (xy 159.671313 -401.087096) (xy 159.641852 -401.04125)
			(xy 159.619214 -400.991678) (xy 159.603861 -400.939389) (xy 159.596106 -400.885448) (xy 158.15845 -400.885448)
			(xy 158.15845 -400.885452) (xy 158.150694 -400.9394) (xy 158.13534 -400.991696) (xy 158.112699 -401.041275)
			(xy 158.083234 -401.087127) (xy 158.047543 -401.128319) (xy 158.006354 -401.164014) (xy 157.960505 -401.193483)
			(xy 157.910928 -401.216128) (xy 157.858634 -401.231487) (xy 157.804686 -401.239248) (xy 157.777434 -401.239736)
			(xy 156.913834 -401.239736) (xy 156.886582 -401.239219) (xy 156.832631 -401.231467) (xy 156.780333 -401.216115)
			(xy 156.730752 -401.193476) (xy 156.684898 -401.164011) (xy 156.643704 -401.12832) (xy 156.60801 -401.087129)
			(xy 156.578541 -401.041278) (xy 156.555897 -400.991699) (xy 156.540541 -400.939402) (xy 156.532783 -400.885452)
			(xy 155.095273 -400.885452) (xy 155.095273 -400.885455) (xy 155.087515 -400.939411) (xy 155.072158 -400.991713)
			(xy 155.049513 -401.041297) (xy 155.020043 -401.087154) (xy 154.984346 -401.12835) (xy 154.943149 -401.164046)
			(xy 154.897292 -401.193516) (xy 154.847707 -401.21616) (xy 154.795405 -401.231517) (xy 154.741449 -401.239273)
			(xy 154.714194 -401.239736) (xy 153.850594 -401.239736) (xy 153.823345 -401.239193) (xy 153.769402 -401.231437)
			(xy 153.717112 -401.216082) (xy 153.667539 -401.193442) (xy 153.621693 -401.163978) (xy 153.580506 -401.128289)
			(xy 153.544818 -401.087102) (xy 153.515355 -401.041256) (xy 153.492716 -400.991683) (xy 153.477362 -400.939392)
			(xy 153.469606 -400.885449) (xy 152.032073 -400.885449) (xy 152.032073 -400.885457) (xy 152.024314 -400.939416)
			(xy 152.008955 -400.991721) (xy 151.986307 -401.041308) (xy 151.956833 -401.087167) (xy 151.921131 -401.128364)
			(xy 151.87993 -401.16406) (xy 151.834068 -401.193529) (xy 151.784478 -401.216171) (xy 151.732171 -401.231524)
			(xy 151.678211 -401.239276) (xy 151.650954 -401.239736) (xy 150.787354 -401.239736) (xy 150.760107 -401.239191)
			(xy 150.706168 -401.231429) (xy 150.653883 -401.216071) (xy 150.604315 -401.193429) (xy 150.558474 -401.163964)
			(xy 150.517292 -401.128275) (xy 150.481608 -401.087089) (xy 150.452149 -401.041244) (xy 150.429512 -400.991674)
			(xy 150.414161 -400.939387) (xy 150.406406 -400.885447) (xy 148.96875 -400.885447) (xy 148.96875 -400.885453)
			(xy 148.960993 -400.939403) (xy 148.945638 -400.991701) (xy 148.922996 -401.04128) (xy 148.893529 -401.087134)
			(xy 148.857836 -401.128326) (xy 148.816645 -401.164021) (xy 148.770793 -401.193489) (xy 148.721214 -401.216133)
			(xy 148.668917 -401.23149) (xy 148.614967 -401.239249) (xy 148.587714 -401.239736) (xy 147.724114 -401.239736)
			(xy 147.696862 -401.239218) (xy 147.642914 -401.231463) (xy 147.590618 -401.216109) (xy 147.54104 -401.193469)
			(xy 147.495189 -401.164004) (xy 147.453997 -401.128313) (xy 147.418305 -401.087123) (xy 147.388838 -401.041272)
			(xy 147.366196 -400.991695) (xy 147.35084 -400.9394) (xy 147.343083 -400.885451) (xy 145.905573 -400.885451)
			(xy 145.905573 -400.885456) (xy 145.897815 -400.939413) (xy 145.882456 -400.991717) (xy 145.85981 -401.041303)
			(xy 145.830338 -401.08716) (xy 145.794638 -401.128357) (xy 145.75344 -401.164053) (xy 145.70758 -401.193523)
			(xy 145.657993 -401.216165) (xy 145.605688 -401.23152) (xy 145.55173 -401.239275) (xy 145.524474 -401.239736)
			(xy 144.660874 -401.239736) (xy 144.633626 -401.239192) (xy 144.579685 -401.231433) (xy 144.527397 -401.216077)
			(xy 144.477827 -401.193436) (xy 144.431983 -401.163971) (xy 144.390799 -401.128282) (xy 144.355113 -401.087096)
			(xy 144.325652 -401.04125) (xy 144.303014 -400.991678) (xy 144.287661 -400.939389) (xy 144.279906 -400.885448)
			(xy 142.84225 -400.885448) (xy 142.84225 -400.885452) (xy 142.834494 -400.9394) (xy 142.81914 -400.991696)
			(xy 142.796499 -401.041275) (xy 142.767034 -401.087127) (xy 142.731343 -401.128319) (xy 142.690154 -401.164014)
			(xy 142.644305 -401.193483) (xy 142.594728 -401.216128) (xy 142.542434 -401.231487) (xy 142.488486 -401.239248)
			(xy 142.461234 -401.239736) (xy 141.597634 -401.239736) (xy 141.570382 -401.239219) (xy 141.516431 -401.231467)
			(xy 141.464133 -401.216115) (xy 141.414552 -401.193476) (xy 141.368698 -401.164011) (xy 141.327504 -401.12832)
			(xy 141.29181 -401.087129) (xy 141.262341 -401.041278) (xy 141.239697 -400.991699) (xy 141.224341 -400.939402)
			(xy 141.216583 -400.885452) (xy 139.779073 -400.885452) (xy 139.779073 -400.885455) (xy 139.771315 -400.939411)
			(xy 139.755958 -400.991713) (xy 139.733313 -401.041297) (xy 139.703843 -401.087154) (xy 139.668146 -401.12835)
			(xy 139.626949 -401.164046) (xy 139.581092 -401.193516) (xy 139.531507 -401.21616) (xy 139.479205 -401.231517)
			(xy 139.425249 -401.239273) (xy 139.397994 -401.239736) (xy 138.534394 -401.239736) (xy 138.507145 -401.239193)
			(xy 138.453202 -401.231437) (xy 138.400912 -401.216082) (xy 138.351339 -401.193442) (xy 138.305493 -401.163978)
			(xy 138.264306 -401.128289) (xy 138.228618 -401.087102) (xy 138.199155 -401.041256) (xy 138.176516 -400.991683)
			(xy 138.161162 -400.939392) (xy 138.153406 -400.885449) (xy 136.715873 -400.885449) (xy 136.715873 -400.885457)
			(xy 136.708114 -400.939416) (xy 136.692755 -400.991721) (xy 136.670107 -401.041308) (xy 136.640633 -401.087167)
			(xy 136.604931 -401.128364) (xy 136.56373 -401.16406) (xy 136.517868 -401.193529) (xy 136.468278 -401.216171)
			(xy 136.415971 -401.231524) (xy 136.362011 -401.239276) (xy 136.334754 -401.239736) (xy 135.471154 -401.239736)
			(xy 135.443907 -401.239191) (xy 135.389968 -401.231429) (xy 135.337683 -401.216071) (xy 135.288115 -401.193429)
			(xy 135.242274 -401.163964) (xy 135.201092 -401.128275) (xy 135.165408 -401.087089) (xy 135.135949 -401.041244)
			(xy 135.113312 -400.991674) (xy 135.097961 -400.939387) (xy 135.090206 -400.885447) (xy 133.65255 -400.885447)
			(xy 133.65255 -400.885453) (xy 133.644793 -400.939403) (xy 133.629438 -400.991701) (xy 133.606796 -401.04128)
			(xy 133.577329 -401.087134) (xy 133.541636 -401.128326) (xy 133.500445 -401.164021) (xy 133.454593 -401.193489)
			(xy 133.405014 -401.216133) (xy 133.352717 -401.23149) (xy 133.298767 -401.239249) (xy 133.271514 -401.239736)
			(xy 132.407914 -401.239736) (xy 132.380662 -401.239218) (xy 132.326714 -401.231463) (xy 132.274418 -401.216109)
			(xy 132.22484 -401.193469) (xy 132.178989 -401.164004) (xy 132.137797 -401.128313) (xy 132.102105 -401.087123)
			(xy 132.072638 -401.041272) (xy 132.049996 -400.991695) (xy 132.03464 -400.9394) (xy 132.026883 -400.885451)
			(xy 130.589373 -400.885451) (xy 130.589373 -400.885456) (xy 130.581615 -400.939413) (xy 130.566256 -400.991717)
			(xy 130.54361 -401.041303) (xy 130.514138 -401.08716) (xy 130.478438 -401.128357) (xy 130.43724 -401.164053)
			(xy 130.39138 -401.193523) (xy 130.341793 -401.216165) (xy 130.289488 -401.23152) (xy 130.23553 -401.239275)
			(xy 130.208274 -401.239736) (xy 129.344674 -401.239736) (xy 129.317426 -401.239192) (xy 129.263485 -401.231433)
			(xy 129.211197 -401.216077) (xy 129.161627 -401.193436) (xy 129.115783 -401.163971) (xy 129.074599 -401.128282)
			(xy 129.038913 -401.087096) (xy 129.009452 -401.04125) (xy 128.986814 -400.991678) (xy 128.971461 -400.939389)
			(xy 128.963706 -400.885448) (xy 127.52605 -400.885448) (xy 127.52605 -400.885452) (xy 127.518294 -400.9394)
			(xy 127.50294 -400.991696) (xy 127.480299 -401.041275) (xy 127.450834 -401.087127) (xy 127.415143 -401.128319)
			(xy 127.373954 -401.164014) (xy 127.328105 -401.193483) (xy 127.278528 -401.216128) (xy 127.226234 -401.231487)
			(xy 127.172286 -401.239248) (xy 127.145034 -401.239736) (xy 126.281434 -401.239736) (xy 126.254182 -401.239219)
			(xy 126.200231 -401.231467) (xy 126.147933 -401.216115) (xy 126.098352 -401.193476) (xy 126.052498 -401.164011)
			(xy 126.011304 -401.12832) (xy 125.97561 -401.087129) (xy 125.946141 -401.041278) (xy 125.923497 -400.991699)
			(xy 125.908141 -400.939402) (xy 125.900383 -400.885452) (xy 124.462873 -400.885452) (xy 124.462873 -400.885455)
			(xy 124.455115 -400.939411) (xy 124.439758 -400.991713) (xy 124.417113 -401.041297) (xy 124.387643 -401.087154)
			(xy 124.351946 -401.12835) (xy 124.310749 -401.164046) (xy 124.264892 -401.193516) (xy 124.215307 -401.21616)
			(xy 124.163005 -401.231517) (xy 124.109049 -401.239273) (xy 124.081794 -401.239736) (xy 123.218194 -401.239736)
			(xy 123.190945 -401.239193) (xy 123.137002 -401.231437) (xy 123.084712 -401.216082) (xy 123.035139 -401.193442)
			(xy 122.989293 -401.163978) (xy 122.948106 -401.128289) (xy 122.912418 -401.087102) (xy 122.882955 -401.041256)
			(xy 122.860316 -400.991683) (xy 122.844962 -400.939392) (xy 122.837206 -400.885449) (xy 121.399673 -400.885449)
			(xy 121.399673 -400.885457) (xy 121.391914 -400.939416) (xy 121.376555 -400.991721) (xy 121.353907 -401.041308)
			(xy 121.324433 -401.087167) (xy 121.288731 -401.128364) (xy 121.24753 -401.16406) (xy 121.201668 -401.193529)
			(xy 121.152078 -401.216171) (xy 121.099771 -401.231524) (xy 121.045811 -401.239276) (xy 121.018554 -401.239736)
			(xy 120.154954 -401.239736) (xy 120.127707 -401.239191) (xy 120.073768 -401.231429) (xy 120.021483 -401.216071)
			(xy 119.971915 -401.193429) (xy 119.926074 -401.163964) (xy 119.884892 -401.128275) (xy 119.849208 -401.087089)
			(xy 119.819749 -401.041244) (xy 119.797112 -400.991674) (xy 119.781761 -400.939387) (xy 119.774006 -400.885447)
			(xy 95.17305 -400.885447) (xy 95.17305 -400.885452) (xy 95.165294 -400.9394) (xy 95.14994 -400.991695)
			(xy 95.1273 -401.041274) (xy 95.097835 -401.087126) (xy 95.062145 -401.128318) (xy 95.020956 -401.164012)
			(xy 94.975107 -401.193482) (xy 94.925531 -401.216127) (xy 94.873237 -401.231486) (xy 94.819289 -401.239248)
			(xy 94.792038 -401.239736) (xy 93.928438 -401.239736) (xy 93.901185 -401.239219) (xy 93.847234 -401.231467)
			(xy 93.794936 -401.216116) (xy 93.745354 -401.193477) (xy 93.6995 -401.164012) (xy 93.658306 -401.128321)
			(xy 93.622611 -401.087131) (xy 93.593141 -401.041279) (xy 93.570498 -400.9917) (xy 93.555141 -400.939403)
			(xy 93.547383 -400.885453) (xy 92.109873 -400.885453) (xy 92.109873 -400.885455) (xy 92.102115 -400.93941)
			(xy 92.086758 -400.991712) (xy 92.064114 -401.041296) (xy 92.034643 -401.087153) (xy 91.998947 -401.128348)
			(xy 91.957751 -401.164045) (xy 91.911894 -401.193515) (xy 91.86231 -401.216159) (xy 91.810008 -401.231516)
			(xy 91.756053 -401.239273) (xy 91.728798 -401.239736) (xy 90.865198 -401.239736) (xy 90.837949 -401.239194)
			(xy 90.784005 -401.231437) (xy 90.731715 -401.216083) (xy 90.682142 -401.193444) (xy 90.636295 -401.16398)
			(xy 90.595108 -401.128291) (xy 90.559419 -401.087104) (xy 90.529955 -401.041257) (xy 90.507316 -400.991683)
			(xy 90.491962 -400.939393) (xy 90.484206 -400.885449) (xy 89.046673 -400.885449) (xy 89.046673 -400.885457)
			(xy 89.038914 -400.939415) (xy 89.023555 -400.991721) (xy 89.000908 -401.041307) (xy 88.971434 -401.087166)
			(xy 88.935733 -401.128363) (xy 88.894532 -401.164059) (xy 88.84867 -401.193528) (xy 88.799081 -401.21617)
			(xy 88.746774 -401.231523) (xy 88.692815 -401.239276) (xy 88.665558 -401.239736) (xy 87.801958 -401.239736)
			(xy 87.774711 -401.239191) (xy 87.720772 -401.23143) (xy 87.668486 -401.216073) (xy 87.618918 -401.193431)
			(xy 87.573076 -401.163965) (xy 87.531894 -401.128277) (xy 87.496209 -401.087091) (xy 87.466749 -401.041246)
			(xy 87.444113 -400.991675) (xy 87.428761 -400.939387) (xy 87.421006 -400.885447) (xy 85.98335 -400.885447)
			(xy 85.98335 -400.885452) (xy 85.975594 -400.939403) (xy 85.960238 -400.9917) (xy 85.937597 -401.041279)
			(xy 85.90813 -401.087132) (xy 85.872438 -401.128325) (xy 85.831247 -401.164019) (xy 85.785395 -401.193488)
			(xy 85.735817 -401.216132) (xy 85.68352 -401.23149) (xy 85.62957 -401.239249) (xy 85.602318 -401.239736)
			(xy 84.738718 -401.239736) (xy 84.711466 -401.239218) (xy 84.657517 -401.231464) (xy 84.605221 -401.21611)
			(xy 84.555642 -401.19347) (xy 84.50979 -401.164005) (xy 84.468599 -401.128314) (xy 84.432906 -401.087124)
			(xy 84.403438 -401.041273) (xy 84.380796 -400.991696) (xy 84.36544 -400.9394) (xy 84.357683 -400.885452)
			(xy 82.920173 -400.885452) (xy 82.920173 -400.885456) (xy 82.912415 -400.939413) (xy 82.897057 -400.991716)
			(xy 82.874411 -401.041302) (xy 82.844939 -401.087159) (xy 82.80924 -401.128355) (xy 82.768042 -401.164052)
			(xy 82.722182 -401.193521) (xy 82.672596 -401.216164) (xy 82.620291 -401.23152) (xy 82.566334 -401.239275)
			(xy 82.539078 -401.239736) (xy 81.675478 -401.239736) (xy 81.64823 -401.239192) (xy 81.594288 -401.231434)
			(xy 81.542 -401.216078) (xy 81.49243 -401.193437) (xy 81.446585 -401.163973) (xy 81.405401 -401.128284)
			(xy 81.369714 -401.087097) (xy 81.340252 -401.041251) (xy 81.317614 -400.991679) (xy 81.302262 -400.93939)
			(xy 81.294506 -400.885448) (xy 79.85685 -400.885448) (xy 79.85685 -400.885452) (xy 79.849094 -400.9394)
			(xy 79.83374 -400.991695) (xy 79.8111 -401.041274) (xy 79.781635 -401.087126) (xy 79.745945 -401.128318)
			(xy 79.704756 -401.164012) (xy 79.658907 -401.193482) (xy 79.609331 -401.216127) (xy 79.557037 -401.231486)
			(xy 79.503089 -401.239248) (xy 79.475838 -401.239736) (xy 78.612238 -401.239736) (xy 78.584985 -401.239219)
			(xy 78.531034 -401.231467) (xy 78.478736 -401.216116) (xy 78.429154 -401.193477) (xy 78.3833 -401.164012)
			(xy 78.342106 -401.128321) (xy 78.306411 -401.087131) (xy 78.276941 -401.041279) (xy 78.254298 -400.9917)
			(xy 78.238941 -400.939403) (xy 78.231183 -400.885453) (xy 76.793673 -400.885453) (xy 76.793673 -400.885455)
			(xy 76.785915 -400.93941) (xy 76.770558 -400.991712) (xy 76.747914 -401.041296) (xy 76.718443 -401.087153)
			(xy 76.682747 -401.128348) (xy 76.641551 -401.164045) (xy 76.595694 -401.193515) (xy 76.54611 -401.216159)
			(xy 76.493808 -401.231516) (xy 76.439853 -401.239273) (xy 76.412598 -401.239736) (xy 75.548998 -401.239736)
			(xy 75.521749 -401.239194) (xy 75.467805 -401.231437) (xy 75.415515 -401.216083) (xy 75.365942 -401.193444)
			(xy 75.320095 -401.16398) (xy 75.278908 -401.128291) (xy 75.243219 -401.087104) (xy 75.213755 -401.041257)
			(xy 75.191116 -400.991683) (xy 75.175762 -400.939393) (xy 75.168006 -400.885449) (xy 73.730473 -400.885449)
			(xy 73.730473 -400.885457) (xy 73.722714 -400.939415) (xy 73.707355 -400.991721) (xy 73.684708 -401.041307)
			(xy 73.655234 -401.087166) (xy 73.619533 -401.128363) (xy 73.578332 -401.164059) (xy 73.53247 -401.193528)
			(xy 73.482881 -401.21617) (xy 73.430574 -401.231523) (xy 73.376615 -401.239276) (xy 73.349358 -401.239736)
			(xy 72.485758 -401.239736) (xy 72.458511 -401.239191) (xy 72.404572 -401.23143) (xy 72.352286 -401.216073)
			(xy 72.302718 -401.193431) (xy 72.256876 -401.163965) (xy 72.215694 -401.128277) (xy 72.180009 -401.087091)
			(xy 72.150549 -401.041246) (xy 72.127913 -400.991675) (xy 72.112561 -400.939387) (xy 72.104806 -400.885447)
			(xy 70.66715 -400.885447) (xy 70.66715 -400.885452) (xy 70.659394 -400.939403) (xy 70.644038 -400.9917)
			(xy 70.621397 -401.041279) (xy 70.59193 -401.087132) (xy 70.556238 -401.128325) (xy 70.515047 -401.164019)
			(xy 70.469195 -401.193488) (xy 70.419617 -401.216132) (xy 70.36732 -401.23149) (xy 70.31337 -401.239249)
			(xy 70.286118 -401.239736) (xy 69.422518 -401.239736) (xy 69.395266 -401.239218) (xy 69.341317 -401.231464)
			(xy 69.289021 -401.21611) (xy 69.239442 -401.19347) (xy 69.19359 -401.164005) (xy 69.152399 -401.128314)
			(xy 69.116706 -401.087124) (xy 69.087238 -401.041273) (xy 69.064596 -400.991696) (xy 69.04924 -400.9394)
			(xy 69.041483 -400.885452) (xy 67.603973 -400.885452) (xy 67.603973 -400.885456) (xy 67.596215 -400.939413)
			(xy 67.580857 -400.991716) (xy 67.558211 -401.041302) (xy 67.528739 -401.087159) (xy 67.49304 -401.128355)
			(xy 67.451842 -401.164052) (xy 67.405982 -401.193521) (xy 67.356396 -401.216164) (xy 67.304091 -401.23152)
			(xy 67.250134 -401.239275) (xy 67.222878 -401.239736) (xy 66.359278 -401.239736) (xy 66.33203 -401.239192)
			(xy 66.278088 -401.231434) (xy 66.2258 -401.216078) (xy 66.17623 -401.193437) (xy 66.130385 -401.163973)
			(xy 66.089201 -401.128284) (xy 66.053514 -401.087097) (xy 66.024052 -401.041251) (xy 66.001414 -400.991679)
			(xy 65.986062 -400.93939) (xy 65.978306 -400.885448) (xy 64.54065 -400.885448) (xy 64.54065 -400.885452)
			(xy 64.532894 -400.9394) (xy 64.51754 -400.991695) (xy 64.4949 -401.041274) (xy 64.465435 -401.087126)
			(xy 64.429745 -401.128318) (xy 64.388556 -401.164012) (xy 64.342707 -401.193482) (xy 64.293131 -401.216127)
			(xy 64.240837 -401.231486) (xy 64.186889 -401.239248) (xy 64.159638 -401.239736) (xy 63.296038 -401.239736)
			(xy 63.268785 -401.239219) (xy 63.214834 -401.231467) (xy 63.162536 -401.216116) (xy 63.112954 -401.193477)
			(xy 63.0671 -401.164012) (xy 63.025906 -401.128321) (xy 62.990211 -401.087131) (xy 62.960741 -401.041279)
			(xy 62.938098 -400.9917) (xy 62.922741 -400.939403) (xy 62.914983 -400.885453) (xy 61.477473 -400.885453)
			(xy 61.477473 -400.885455) (xy 61.469715 -400.93941) (xy 61.454358 -400.991712) (xy 61.431714 -401.041296)
			(xy 61.402243 -401.087153) (xy 61.366547 -401.128348) (xy 61.325351 -401.164045) (xy 61.279494 -401.193515)
			(xy 61.22991 -401.216159) (xy 61.177608 -401.231516) (xy 61.123653 -401.239273) (xy 61.096398 -401.239736)
			(xy 60.232798 -401.239736) (xy 60.205549 -401.239194) (xy 60.151605 -401.231437) (xy 60.099315 -401.216083)
			(xy 60.049742 -401.193444) (xy 60.003895 -401.16398) (xy 59.962708 -401.128291) (xy 59.927019 -401.087104)
			(xy 59.897555 -401.041257) (xy 59.874916 -400.991683) (xy 59.859562 -400.939393) (xy 59.851806 -400.885449)
			(xy 58.414273 -400.885449) (xy 58.414273 -400.885457) (xy 58.406514 -400.939415) (xy 58.391155 -400.991721)
			(xy 58.368508 -401.041307) (xy 58.339034 -401.087166) (xy 58.303333 -401.128363) (xy 58.262132 -401.164059)
			(xy 58.21627 -401.193528) (xy 58.166681 -401.21617) (xy 58.114374 -401.231523) (xy 58.060415 -401.239276)
			(xy 58.033158 -401.239736) (xy 57.169558 -401.239736) (xy 57.142311 -401.239191) (xy 57.088372 -401.23143)
			(xy 57.036086 -401.216073) (xy 56.986518 -401.193431) (xy 56.940676 -401.163965) (xy 56.899494 -401.128277)
			(xy 56.863809 -401.087091) (xy 56.834349 -401.041246) (xy 56.811713 -400.991675) (xy 56.796361 -400.939387)
			(xy 56.788606 -400.885447) (xy 55.35095 -400.885447) (xy 55.35095 -400.885452) (xy 55.343194 -400.939403)
			(xy 55.327838 -400.9917) (xy 55.305197 -401.041279) (xy 55.27573 -401.087132) (xy 55.240038 -401.128325)
			(xy 55.198847 -401.164019) (xy 55.152995 -401.193488) (xy 55.103417 -401.216132) (xy 55.05112 -401.23149)
			(xy 54.99717 -401.239249) (xy 54.969918 -401.239736) (xy 54.106318 -401.239736) (xy 54.079066 -401.239218)
			(xy 54.025117 -401.231464) (xy 53.972821 -401.21611) (xy 53.923242 -401.19347) (xy 53.87739 -401.164005)
			(xy 53.836199 -401.128314) (xy 53.800506 -401.087124) (xy 53.771038 -401.041273) (xy 53.748396 -400.991696)
			(xy 53.73304 -400.9394) (xy 53.725283 -400.885452) (xy 52.287773 -400.885452) (xy 52.287773 -400.885456)
			(xy 52.280015 -400.939413) (xy 52.264657 -400.991716) (xy 52.242011 -401.041302) (xy 52.212539 -401.087159)
			(xy 52.17684 -401.128355) (xy 52.135642 -401.164052) (xy 52.089782 -401.193521) (xy 52.040196 -401.216164)
			(xy 51.987891 -401.23152) (xy 51.933934 -401.239275) (xy 51.906678 -401.239736) (xy 51.043078 -401.239736)
			(xy 51.01583 -401.239192) (xy 50.961888 -401.231434) (xy 50.9096 -401.216078) (xy 50.86003 -401.193437)
			(xy 50.814185 -401.163973) (xy 50.773001 -401.128284) (xy 50.737314 -401.087097) (xy 50.707852 -401.041251)
			(xy 50.685214 -400.991679) (xy 50.669862 -400.93939) (xy 50.662106 -400.885448) (xy 49.22445 -400.885448)
			(xy 49.22445 -400.885452) (xy 49.216694 -400.9394) (xy 49.20134 -400.991695) (xy 49.1787 -401.041274)
			(xy 49.149235 -401.087126) (xy 49.113545 -401.128318) (xy 49.072356 -401.164012) (xy 49.026507 -401.193482)
			(xy 48.976931 -401.216127) (xy 48.924637 -401.231486) (xy 48.870689 -401.239248) (xy 48.843438 -401.239736)
			(xy 47.979838 -401.239736) (xy 47.952585 -401.239219) (xy 47.898634 -401.231467) (xy 47.846336 -401.216116)
			(xy 47.796754 -401.193477) (xy 47.7509 -401.164012) (xy 47.709706 -401.128321) (xy 47.674011 -401.087131)
			(xy 47.644541 -401.041279) (xy 47.621898 -400.9917) (xy 47.606541 -400.939403) (xy 47.598783 -400.885453)
			(xy 3.523996 -400.885453) (xy 3.523996 -402.656674) (xy 98.152872 -402.656674) (xy 98.152872 -402.602126)
			(xy 98.160635 -402.548133) (xy 98.176003 -402.495795) (xy 98.198664 -402.446176) (xy 98.228156 -402.400288)
			(xy 98.263878 -402.359064) (xy 98.305104 -402.323344) (xy 98.350994 -402.293855) (xy 98.400613 -402.271196)
			(xy 98.452953 -402.255831) (xy 98.506946 -402.24807) (xy 98.53422 -402.247608) (xy 99.39782 -402.247608)
			(xy 99.425086 -402.248156) (xy 99.479063 -402.255919) (xy 99.531387 -402.271285) (xy 99.58099 -402.293941)
			(xy 99.626865 -402.323425) (xy 99.668077 -402.359137) (xy 99.703787 -402.400351) (xy 99.733269 -402.446227)
			(xy 99.755922 -402.495832) (xy 99.771285 -402.548156) (xy 99.779046 -402.602134) (xy 99.779046 -402.656666)
			(xy 99.771285 -402.710644) (xy 99.755922 -402.762968) (xy 99.733269 -402.812573) (xy 99.703787 -402.858449)
			(xy 99.668077 -402.899663) (xy 99.626865 -402.935375) (xy 99.58099 -402.964859) (xy 99.531387 -402.987515)
			(xy 99.479063 -403.002881) (xy 99.425086 -403.010644) (xy 99.39782 -403.011132) (xy 98.53422 -403.011132)
			(xy 98.506946 -403.01073) (xy 98.452953 -403.002969) (xy 98.400613 -402.987604) (xy 98.350994 -402.964945)
			(xy 98.305104 -402.935456) (xy 98.263878 -402.899736) (xy 98.228156 -402.858512) (xy 98.198664 -402.812624)
			(xy 98.176003 -402.763005) (xy 98.160635 -402.710667) (xy 98.152872 -402.656674) (xy 3.523996 -402.656674)
			(xy 3.523996 -403.371812) (xy 3.524525 -403.402954) (xy 3.532689 -403.464702) (xy 3.548837 -403.524857)
			(xy 3.572694 -403.582392) (xy 3.603851 -403.636324) (xy 3.641776 -403.685732) (xy 3.663442 -403.708108)
			(xy 3.86649 -403.911156) (xy 47.598731 -403.911156) (xy 47.598731 -403.856644) (xy 47.606489 -403.802686)
			(xy 47.621848 -403.750382) (xy 47.644495 -403.700796) (xy 47.673969 -403.654938) (xy 47.709669 -403.613742)
			(xy 47.750868 -403.578046) (xy 47.796729 -403.548577) (xy 47.846317 -403.525935) (xy 47.898623 -403.510581)
			(xy 47.952582 -403.502828) (xy 47.979838 -403.502368) (xy 48.843438 -403.502368) (xy 48.870686 -403.502905)
			(xy 48.924626 -403.510665) (xy 48.976913 -403.526023) (xy 49.026482 -403.548665) (xy 49.072325 -403.57813)
			(xy 49.113508 -403.613819) (xy 49.149193 -403.655006) (xy 49.178654 -403.700851) (xy 49.201291 -403.750423)
			(xy 49.216643 -403.802711) (xy 49.224398 -403.856652) (xy 49.224398 -403.911148) (xy 49.224397 -403.911152)
			(xy 50.662054 -403.911152) (xy 50.662054 -403.856648) (xy 50.66981 -403.802699) (xy 50.685165 -403.750403)
			(xy 50.707806 -403.700824) (xy 50.737272 -403.654971) (xy 50.772964 -403.613779) (xy 50.814154 -403.578085)
			(xy 50.860004 -403.548617) (xy 50.909582 -403.525973) (xy 50.961877 -403.510615) (xy 51.015826 -403.502855)
			(xy 51.043078 -403.502368) (xy 51.906678 -403.502368) (xy 51.93393 -403.502878) (xy 51.98788 -403.510632)
			(xy 52.040177 -403.525985) (xy 52.089757 -403.548625) (xy 52.13561 -403.57809) (xy 52.176803 -403.613782)
			(xy 52.212497 -403.654972) (xy 52.241965 -403.700824) (xy 52.264607 -403.750402) (xy 52.279964 -403.802698)
			(xy 52.287721 -403.856648) (xy 52.287721 -403.911152) (xy 52.287721 -403.911155) (xy 53.725231 -403.911155)
			(xy 53.725231 -403.856645) (xy 53.732989 -403.802689) (xy 53.748347 -403.750386) (xy 53.770992 -403.700801)
			(xy 53.800464 -403.654945) (xy 53.836162 -403.613749) (xy 53.877359 -403.578053) (xy 53.923217 -403.548583)
			(xy 53.972803 -403.525941) (xy 54.025106 -403.510585) (xy 54.079063 -403.50283) (xy 54.106318 -403.502368)
			(xy 54.969918 -403.502368) (xy 54.997167 -403.502903) (xy 55.051109 -403.510662) (xy 55.103398 -403.526017)
			(xy 55.15297 -403.548658) (xy 55.198815 -403.578123) (xy 55.240001 -403.613812) (xy 55.275688 -403.654999)
			(xy 55.305151 -403.700846) (xy 55.327789 -403.750419) (xy 55.343142 -403.802709) (xy 55.350898 -403.856651)
			(xy 55.350898 -403.911149) (xy 55.350898 -403.911151) (xy 56.788554 -403.911151) (xy 56.788554 -403.856649)
			(xy 56.79631 -403.802702) (xy 56.811664 -403.750407) (xy 56.834303 -403.700829) (xy 56.863767 -403.654978)
			(xy 56.899457 -403.613786) (xy 56.940644 -403.578093) (xy 56.986492 -403.548623) (xy 57.036067 -403.525978)
			(xy 57.08836 -403.510619) (xy 57.142307 -403.502857) (xy 57.169558 -403.502368) (xy 58.033158 -403.502368)
			(xy 58.060411 -403.502876) (xy 58.114363 -403.510628) (xy 58.166663 -403.525979) (xy 58.216245 -403.548618)
			(xy 58.262101 -403.578083) (xy 58.303296 -403.613775) (xy 58.338992 -403.654966) (xy 58.368462 -403.700818)
			(xy 58.391106 -403.750398) (xy 58.406463 -403.802696) (xy 58.414221 -403.856647) (xy 58.414221 -403.911153)
			(xy 59.851754 -403.911153) (xy 59.851754 -403.856647) (xy 59.859511 -403.802696) (xy 59.874867 -403.750398)
			(xy 59.897509 -403.700818) (xy 59.926977 -403.654965) (xy 59.962671 -403.613772) (xy 60.003863 -403.578078)
			(xy 60.049716 -403.54861) (xy 60.099296 -403.525967) (xy 60.151594 -403.510611) (xy 60.205545 -403.502854)
			(xy 60.232798 -403.502368) (xy 61.096398 -403.502368) (xy 61.123649 -403.502879) (xy 61.177597 -403.510635)
			(xy 61.229892 -403.52599) (xy 61.279469 -403.548631) (xy 61.32532 -403.578097) (xy 61.36651 -403.613789)
			(xy 61.402201 -403.654979) (xy 61.431668 -403.700829) (xy 61.454309 -403.750406) (xy 61.469664 -403.802701)
			(xy 61.477421 -403.856649) (xy 61.477421 -403.911151) (xy 61.47742 -403.911156) (xy 62.914931 -403.911156)
			(xy 62.914931 -403.856644) (xy 62.922689 -403.802686) (xy 62.938048 -403.750382) (xy 62.960695 -403.700796)
			(xy 62.990169 -403.654938) (xy 63.025869 -403.613742) (xy 63.067068 -403.578046) (xy 63.112929 -403.548577)
			(xy 63.162517 -403.525935) (xy 63.214823 -403.510581) (xy 63.268782 -403.502828) (xy 63.296038 -403.502368)
			(xy 64.159638 -403.502368) (xy 64.186886 -403.502905) (xy 64.240826 -403.510665) (xy 64.293113 -403.526023)
			(xy 64.342682 -403.548665) (xy 64.388525 -403.57813) (xy 64.429708 -403.613819) (xy 64.465393 -403.655006)
			(xy 64.494854 -403.700851) (xy 64.517491 -403.750423) (xy 64.532843 -403.802711) (xy 64.540598 -403.856652)
			(xy 64.540598 -403.911148) (xy 64.540597 -403.911152) (xy 65.978254 -403.911152) (xy 65.978254 -403.856648)
			(xy 65.98601 -403.802699) (xy 66.001365 -403.750403) (xy 66.024006 -403.700824) (xy 66.053472 -403.654971)
			(xy 66.089164 -403.613779) (xy 66.130354 -403.578085) (xy 66.176204 -403.548617) (xy 66.225782 -403.525973)
			(xy 66.278077 -403.510615) (xy 66.332026 -403.502855) (xy 66.359278 -403.502368) (xy 67.222878 -403.502368)
			(xy 67.25013 -403.502878) (xy 67.30408 -403.510632) (xy 67.356377 -403.525985) (xy 67.405957 -403.548625)
			(xy 67.45181 -403.57809) (xy 67.493003 -403.613782) (xy 67.528697 -403.654972) (xy 67.558165 -403.700824)
			(xy 67.580807 -403.750402) (xy 67.596164 -403.802698) (xy 67.603921 -403.856648) (xy 67.603921 -403.911152)
			(xy 67.603921 -403.911155) (xy 69.041431 -403.911155) (xy 69.041431 -403.856645) (xy 69.049189 -403.802689)
			(xy 69.064547 -403.750386) (xy 69.087192 -403.700801) (xy 69.116664 -403.654945) (xy 69.152362 -403.613749)
			(xy 69.193559 -403.578053) (xy 69.239417 -403.548583) (xy 69.289003 -403.525941) (xy 69.341306 -403.510585)
			(xy 69.395263 -403.50283) (xy 69.422518 -403.502368) (xy 70.286118 -403.502368) (xy 70.313367 -403.502903)
			(xy 70.367309 -403.510662) (xy 70.419598 -403.526017) (xy 70.46917 -403.548658) (xy 70.515015 -403.578123)
			(xy 70.556201 -403.613812) (xy 70.591888 -403.654999) (xy 70.621351 -403.700846) (xy 70.643989 -403.750419)
			(xy 70.659342 -403.802709) (xy 70.667098 -403.856651) (xy 70.667098 -403.911149) (xy 70.667098 -403.911151)
			(xy 72.104754 -403.911151) (xy 72.104754 -403.856649) (xy 72.11251 -403.802702) (xy 72.127864 -403.750407)
			(xy 72.150503 -403.700829) (xy 72.179967 -403.654978) (xy 72.215657 -403.613786) (xy 72.256844 -403.578093)
			(xy 72.302692 -403.548623) (xy 72.352267 -403.525978) (xy 72.40456 -403.510619) (xy 72.458507 -403.502857)
			(xy 72.485758 -403.502368) (xy 73.349358 -403.502368) (xy 73.376611 -403.502876) (xy 73.430563 -403.510628)
			(xy 73.482863 -403.525979) (xy 73.532445 -403.548618) (xy 73.578301 -403.578083) (xy 73.619496 -403.613775)
			(xy 73.655192 -403.654966) (xy 73.684662 -403.700818) (xy 73.707306 -403.750398) (xy 73.722663 -403.802696)
			(xy 73.730421 -403.856647) (xy 73.730421 -403.911153) (xy 75.167954 -403.911153) (xy 75.167954 -403.856647)
			(xy 75.175711 -403.802696) (xy 75.191067 -403.750398) (xy 75.213709 -403.700818) (xy 75.243177 -403.654965)
			(xy 75.278871 -403.613772) (xy 75.320063 -403.578078) (xy 75.365916 -403.54861) (xy 75.415496 -403.525967)
			(xy 75.467794 -403.510611) (xy 75.521745 -403.502854) (xy 75.548998 -403.502368) (xy 76.412598 -403.502368)
			(xy 76.439849 -403.502879) (xy 76.493797 -403.510635) (xy 76.546092 -403.52599) (xy 76.595669 -403.548631)
			(xy 76.64152 -403.578097) (xy 76.68271 -403.613789) (xy 76.718401 -403.654979) (xy 76.747868 -403.700829)
			(xy 76.770509 -403.750406) (xy 76.785864 -403.802701) (xy 76.793621 -403.856649) (xy 76.793621 -403.911151)
			(xy 76.79362 -403.911156) (xy 78.231131 -403.911156) (xy 78.231131 -403.856644) (xy 78.238889 -403.802686)
			(xy 78.254248 -403.750382) (xy 78.276895 -403.700796) (xy 78.306369 -403.654938) (xy 78.342069 -403.613742)
			(xy 78.383268 -403.578046) (xy 78.429129 -403.548577) (xy 78.478717 -403.525935) (xy 78.531023 -403.510581)
			(xy 78.584982 -403.502828) (xy 78.612238 -403.502368) (xy 79.475838 -403.502368) (xy 79.503086 -403.502905)
			(xy 79.557026 -403.510665) (xy 79.609313 -403.526023) (xy 79.658882 -403.548665) (xy 79.704725 -403.57813)
			(xy 79.745908 -403.613819) (xy 79.781593 -403.655006) (xy 79.811054 -403.700851) (xy 79.833691 -403.750423)
			(xy 79.849043 -403.802711) (xy 79.856798 -403.856652) (xy 79.856798 -403.911148) (xy 79.856797 -403.911152)
			(xy 81.294454 -403.911152) (xy 81.294454 -403.856648) (xy 81.30221 -403.802699) (xy 81.317565 -403.750403)
			(xy 81.340206 -403.700824) (xy 81.369672 -403.654971) (xy 81.405364 -403.613779) (xy 81.446554 -403.578085)
			(xy 81.492404 -403.548617) (xy 81.541982 -403.525973) (xy 81.594277 -403.510615) (xy 81.648226 -403.502855)
			(xy 81.675478 -403.502368) (xy 82.539078 -403.502368) (xy 82.56633 -403.502878) (xy 82.62028 -403.510632)
			(xy 82.672577 -403.525985) (xy 82.722157 -403.548625) (xy 82.76801 -403.57809) (xy 82.809203 -403.613782)
			(xy 82.844897 -403.654972) (xy 82.874365 -403.700824) (xy 82.897007 -403.750402) (xy 82.912364 -403.802698)
			(xy 82.920121 -403.856648) (xy 82.920121 -403.911152) (xy 82.920121 -403.911155) (xy 84.357631 -403.911155)
			(xy 84.357631 -403.856645) (xy 84.365389 -403.802689) (xy 84.380747 -403.750386) (xy 84.403392 -403.700801)
			(xy 84.432864 -403.654945) (xy 84.468562 -403.613749) (xy 84.509759 -403.578053) (xy 84.555617 -403.548583)
			(xy 84.605203 -403.525941) (xy 84.657506 -403.510585) (xy 84.711463 -403.50283) (xy 84.738718 -403.502368)
			(xy 85.602318 -403.502368) (xy 85.629567 -403.502903) (xy 85.683509 -403.510662) (xy 85.735798 -403.526017)
			(xy 85.78537 -403.548658) (xy 85.831215 -403.578123) (xy 85.872401 -403.613812) (xy 85.908088 -403.654999)
			(xy 85.937551 -403.700846) (xy 85.960189 -403.750419) (xy 85.975542 -403.802709) (xy 85.983298 -403.856651)
			(xy 85.983298 -403.911149) (xy 85.983298 -403.911151) (xy 87.420954 -403.911151) (xy 87.420954 -403.856649)
			(xy 87.42871 -403.802702) (xy 87.444064 -403.750407) (xy 87.466703 -403.700829) (xy 87.496167 -403.654978)
			(xy 87.531857 -403.613786) (xy 87.573044 -403.578093) (xy 87.618892 -403.548623) (xy 87.668467 -403.525978)
			(xy 87.72076 -403.510619) (xy 87.774707 -403.502857) (xy 87.801958 -403.502368) (xy 88.665558 -403.502368)
			(xy 88.692811 -403.502876) (xy 88.746763 -403.510628) (xy 88.799063 -403.525979) (xy 88.848645 -403.548618)
			(xy 88.894501 -403.578083) (xy 88.935696 -403.613775) (xy 88.971392 -403.654966) (xy 89.000862 -403.700818)
			(xy 89.023506 -403.750398) (xy 89.038863 -403.802696) (xy 89.046621 -403.856647) (xy 89.046621 -403.911153)
			(xy 90.484154 -403.911153) (xy 90.484154 -403.856647) (xy 90.491911 -403.802696) (xy 90.507267 -403.750398)
			(xy 90.529909 -403.700818) (xy 90.559377 -403.654965) (xy 90.595071 -403.613772) (xy 90.636263 -403.578078)
			(xy 90.682116 -403.54861) (xy 90.731696 -403.525967) (xy 90.783994 -403.510611) (xy 90.837945 -403.502854)
			(xy 90.865198 -403.502368) (xy 91.728798 -403.502368) (xy 91.756049 -403.502879) (xy 91.809997 -403.510635)
			(xy 91.862292 -403.52599) (xy 91.911869 -403.548631) (xy 91.95772 -403.578097) (xy 91.99891 -403.613789)
			(xy 92.034601 -403.654979) (xy 92.064068 -403.700829) (xy 92.086709 -403.750406) (xy 92.102064 -403.802701)
			(xy 92.109821 -403.856649) (xy 92.109821 -403.911151) (xy 92.10982 -403.911156) (xy 93.547331 -403.911156)
			(xy 93.547331 -403.856644) (xy 93.555089 -403.802686) (xy 93.570448 -403.750382) (xy 93.593095 -403.700796)
			(xy 93.622569 -403.654938) (xy 93.658269 -403.613742) (xy 93.699468 -403.578046) (xy 93.745329 -403.548577)
			(xy 93.794917 -403.525935) (xy 93.847223 -403.510581) (xy 93.901182 -403.502828) (xy 93.928438 -403.502368)
			(xy 94.792038 -403.502368) (xy 94.819286 -403.502905) (xy 94.873226 -403.510665) (xy 94.925513 -403.526023)
			(xy 94.975082 -403.548665) (xy 95.020925 -403.57813) (xy 95.062108 -403.613819) (xy 95.097793 -403.655006)
			(xy 95.127254 -403.700851) (xy 95.149891 -403.750423) (xy 95.165243 -403.802711) (xy 95.172998 -403.856652)
			(xy 95.172998 -403.911148) (xy 95.172998 -403.911151) (xy 119.773954 -403.911151) (xy 119.773954 -403.856649)
			(xy 119.78171 -403.802702) (xy 119.797063 -403.750408) (xy 119.819702 -403.70083) (xy 119.849166 -403.654979)
			(xy 119.884855 -403.613788) (xy 119.926042 -403.578094) (xy 119.97189 -403.548625) (xy 120.021465 -403.525979)
			(xy 120.073757 -403.510619) (xy 120.127703 -403.502857) (xy 120.154954 -403.502368) (xy 121.018554 -403.502368)
			(xy 121.045807 -403.502876) (xy 121.09976 -403.510627) (xy 121.15206 -403.525978) (xy 121.201643 -403.548617)
			(xy 121.247499 -403.578082) (xy 121.288694 -403.613773) (xy 121.324391 -403.654964) (xy 121.353861 -403.700817)
			(xy 121.376506 -403.750397) (xy 121.391863 -403.802695) (xy 121.399621 -403.856647) (xy 121.399621 -403.911153)
			(xy 122.837154 -403.911153) (xy 122.837154 -403.856647) (xy 122.844911 -403.802697) (xy 122.860266 -403.750399)
			(xy 122.882909 -403.700819) (xy 122.912376 -403.654966) (xy 122.948069 -403.613774) (xy 122.989261 -403.57808)
			(xy 123.035114 -403.548611) (xy 123.084694 -403.525969) (xy 123.136991 -403.510612) (xy 123.190941 -403.502854)
			(xy 123.218194 -403.502368) (xy 124.081794 -403.502368) (xy 124.109045 -403.502879) (xy 124.162994 -403.510635)
			(xy 124.215289 -403.525989) (xy 124.264867 -403.54863) (xy 124.310718 -403.578096) (xy 124.351908 -403.613787)
			(xy 124.3876 -403.654978) (xy 124.417067 -403.700828) (xy 124.439709 -403.750406) (xy 124.455064 -403.802701)
			(xy 124.462821 -403.856649) (xy 124.462821 -403.911151) (xy 124.46282 -403.911156) (xy 125.900331 -403.911156)
			(xy 125.900331 -403.856644) (xy 125.908089 -403.802686) (xy 125.923448 -403.750383) (xy 125.946095 -403.700797)
			(xy 125.975568 -403.654939) (xy 126.011267 -403.613743) (xy 126.052467 -403.578047) (xy 126.098327 -403.548578)
			(xy 126.147914 -403.525936) (xy 126.20022 -403.510582) (xy 126.254178 -403.502829) (xy 126.281434 -403.502368)
			(xy 127.145034 -403.502368) (xy 127.172282 -403.502905) (xy 127.226223 -403.510664) (xy 127.27851 -403.526022)
			(xy 127.32808 -403.548663) (xy 127.373923 -403.578129) (xy 127.415106 -403.613818) (xy 127.450792 -403.655004)
			(xy 127.480253 -403.70085) (xy 127.50289 -403.750422) (xy 127.518243 -403.802711) (xy 127.525998 -403.856652)
			(xy 127.525998 -403.911148) (xy 127.525997 -403.911152) (xy 128.963654 -403.911152) (xy 128.963654 -403.856648)
			(xy 128.97141 -403.802699) (xy 128.986765 -403.750403) (xy 129.009406 -403.700825) (xy 129.038871 -403.654973)
			(xy 129.074562 -403.613781) (xy 129.115752 -403.578087) (xy 129.161602 -403.548618) (xy 129.211179 -403.525974)
			(xy 129.263474 -403.510616) (xy 129.317422 -403.502856) (xy 129.344674 -403.502368) (xy 130.208274 -403.502368)
			(xy 130.235526 -403.502878) (xy 130.289477 -403.510631) (xy 130.341774 -403.525984) (xy 130.391355 -403.548623)
			(xy 130.437208 -403.578089) (xy 130.478401 -403.61378) (xy 130.514096 -403.654971) (xy 130.543564 -403.700822)
			(xy 130.566207 -403.750401) (xy 130.581563 -403.802698) (xy 130.589321 -403.856648) (xy 130.589321 -403.911152)
			(xy 130.589321 -403.911155) (xy 132.026831 -403.911155) (xy 132.026831 -403.856645) (xy 132.034589 -403.802689)
			(xy 132.049946 -403.750387) (xy 132.072591 -403.700803) (xy 132.102063 -403.654946) (xy 132.13776 -403.61375)
			(xy 132.178957 -403.578054) (xy 132.224815 -403.548585) (xy 132.2744 -403.525942) (xy 132.326703 -403.510586)
			(xy 132.380659 -403.50283) (xy 132.407914 -403.502368) (xy 133.271514 -403.502368) (xy 133.298763 -403.502903)
			(xy 133.352706 -403.510661) (xy 133.404995 -403.526016) (xy 133.454568 -403.548657) (xy 133.500413 -403.578121)
			(xy 133.541599 -403.613811) (xy 133.577287 -403.654998) (xy 133.60675 -403.700845) (xy 133.629389 -403.750418)
			(xy 133.644742 -403.802708) (xy 133.652498 -403.856651) (xy 133.652498 -403.911149) (xy 133.652498 -403.911151)
			(xy 135.090154 -403.911151) (xy 135.090154 -403.856649) (xy 135.09791 -403.802702) (xy 135.113263 -403.750408)
			(xy 135.135902 -403.70083) (xy 135.165366 -403.654979) (xy 135.201055 -403.613788) (xy 135.242242 -403.578094)
			(xy 135.28809 -403.548625) (xy 135.337665 -403.525979) (xy 135.389957 -403.510619) (xy 135.443903 -403.502857)
			(xy 135.471154 -403.502368) (xy 136.334754 -403.502368) (xy 136.362007 -403.502876) (xy 136.41596 -403.510627)
			(xy 136.46826 -403.525978) (xy 136.517843 -403.548617) (xy 136.563699 -403.578082) (xy 136.604894 -403.613773)
			(xy 136.640591 -403.654964) (xy 136.670061 -403.700817) (xy 136.692706 -403.750397) (xy 136.708063 -403.802695)
			(xy 136.715821 -403.856647) (xy 136.715821 -403.911153) (xy 138.153354 -403.911153) (xy 138.153354 -403.856647)
			(xy 138.161111 -403.802697) (xy 138.176466 -403.750399) (xy 138.199109 -403.700819) (xy 138.228576 -403.654966)
			(xy 138.264269 -403.613774) (xy 138.305461 -403.57808) (xy 138.351314 -403.548611) (xy 138.400894 -403.525969)
			(xy 138.453191 -403.510612) (xy 138.507141 -403.502854) (xy 138.534394 -403.502368) (xy 139.397994 -403.502368)
			(xy 139.425245 -403.502879) (xy 139.479194 -403.510635) (xy 139.531489 -403.525989) (xy 139.581067 -403.54863)
			(xy 139.626918 -403.578096) (xy 139.668108 -403.613787) (xy 139.7038 -403.654978) (xy 139.733267 -403.700828)
			(xy 139.755909 -403.750406) (xy 139.771264 -403.802701) (xy 139.779021 -403.856649) (xy 139.779021 -403.911151)
			(xy 139.77902 -403.911156) (xy 141.216531 -403.911156) (xy 141.216531 -403.856644) (xy 141.224289 -403.802686)
			(xy 141.239648 -403.750383) (xy 141.262295 -403.700797) (xy 141.291768 -403.654939) (xy 141.327467 -403.613743)
			(xy 141.368667 -403.578047) (xy 141.414527 -403.548578) (xy 141.464114 -403.525936) (xy 141.51642 -403.510582)
			(xy 141.570378 -403.502829) (xy 141.597634 -403.502368) (xy 142.461234 -403.502368) (xy 142.488482 -403.502905)
			(xy 142.542423 -403.510664) (xy 142.59471 -403.526022) (xy 142.64428 -403.548663) (xy 142.690123 -403.578129)
			(xy 142.731306 -403.613818) (xy 142.766992 -403.655004) (xy 142.796453 -403.70085) (xy 142.81909 -403.750422)
			(xy 142.834443 -403.802711) (xy 142.842198 -403.856652) (xy 142.842198 -403.911148) (xy 142.842197 -403.911152)
			(xy 144.279854 -403.911152) (xy 144.279854 -403.856648) (xy 144.28761 -403.802699) (xy 144.302965 -403.750403)
			(xy 144.325606 -403.700825) (xy 144.355071 -403.654973) (xy 144.390762 -403.613781) (xy 144.431952 -403.578087)
			(xy 144.477802 -403.548618) (xy 144.527379 -403.525974) (xy 144.579674 -403.510616) (xy 144.633622 -403.502856)
			(xy 144.660874 -403.502368) (xy 145.524474 -403.502368) (xy 145.551726 -403.502878) (xy 145.605677 -403.510631)
			(xy 145.657974 -403.525984) (xy 145.707555 -403.548623) (xy 145.753408 -403.578089) (xy 145.794601 -403.61378)
			(xy 145.830296 -403.654971) (xy 145.859764 -403.700822) (xy 145.882407 -403.750401) (xy 145.897763 -403.802698)
			(xy 145.905521 -403.856648) (xy 145.905521 -403.911152) (xy 145.905521 -403.911155) (xy 147.343031 -403.911155)
			(xy 147.343031 -403.856645) (xy 147.350789 -403.802689) (xy 147.366146 -403.750387) (xy 147.388791 -403.700803)
			(xy 147.418263 -403.654946) (xy 147.45396 -403.61375) (xy 147.495157 -403.578054) (xy 147.541015 -403.548585)
			(xy 147.5906 -403.525942) (xy 147.642903 -403.510586) (xy 147.696859 -403.50283) (xy 147.724114 -403.502368)
			(xy 148.587714 -403.502368) (xy 148.614963 -403.502903) (xy 148.668906 -403.510661) (xy 148.721195 -403.526016)
			(xy 148.770768 -403.548657) (xy 148.816613 -403.578121) (xy 148.857799 -403.613811) (xy 148.893487 -403.654998)
			(xy 148.92295 -403.700845) (xy 148.945589 -403.750418) (xy 148.960942 -403.802708) (xy 148.968698 -403.856651)
			(xy 148.968698 -403.911149) (xy 148.968698 -403.911151) (xy 150.406354 -403.911151) (xy 150.406354 -403.856649)
			(xy 150.41411 -403.802702) (xy 150.429463 -403.750408) (xy 150.452102 -403.70083) (xy 150.481566 -403.654979)
			(xy 150.517255 -403.613788) (xy 150.558442 -403.578094) (xy 150.60429 -403.548625) (xy 150.653865 -403.525979)
			(xy 150.706157 -403.510619) (xy 150.760103 -403.502857) (xy 150.787354 -403.502368) (xy 151.650954 -403.502368)
			(xy 151.678207 -403.502876) (xy 151.73216 -403.510627) (xy 151.78446 -403.525978) (xy 151.834043 -403.548617)
			(xy 151.879899 -403.578082) (xy 151.921094 -403.613773) (xy 151.956791 -403.654964) (xy 151.986261 -403.700817)
			(xy 152.008906 -403.750397) (xy 152.024263 -403.802695) (xy 152.032021 -403.856647) (xy 152.032021 -403.911153)
			(xy 153.469554 -403.911153) (xy 153.469554 -403.856647) (xy 153.477311 -403.802697) (xy 153.492666 -403.750399)
			(xy 153.515309 -403.700819) (xy 153.544776 -403.654966) (xy 153.580469 -403.613774) (xy 153.621661 -403.57808)
			(xy 153.667514 -403.548611) (xy 153.717094 -403.525969) (xy 153.769391 -403.510612) (xy 153.823341 -403.502854)
			(xy 153.850594 -403.502368) (xy 154.714194 -403.502368) (xy 154.741445 -403.502879) (xy 154.795394 -403.510635)
			(xy 154.847689 -403.525989) (xy 154.897267 -403.54863) (xy 154.943118 -403.578096) (xy 154.984308 -403.613787)
			(xy 155.02 -403.654978) (xy 155.049467 -403.700828) (xy 155.072109 -403.750406) (xy 155.087464 -403.802701)
			(xy 155.095221 -403.856649) (xy 155.095221 -403.911151) (xy 155.09522 -403.911156) (xy 156.532731 -403.911156)
			(xy 156.532731 -403.856644) (xy 156.540489 -403.802686) (xy 156.555848 -403.750383) (xy 156.578495 -403.700797)
			(xy 156.607968 -403.654939) (xy 156.643667 -403.613743) (xy 156.684867 -403.578047) (xy 156.730727 -403.548578)
			(xy 156.780314 -403.525936) (xy 156.83262 -403.510582) (xy 156.886578 -403.502829) (xy 156.913834 -403.502368)
			(xy 157.777434 -403.502368) (xy 157.804682 -403.502905) (xy 157.858623 -403.510664) (xy 157.91091 -403.526022)
			(xy 157.96048 -403.548663) (xy 158.006323 -403.578129) (xy 158.047506 -403.613818) (xy 158.083192 -403.655004)
			(xy 158.112653 -403.70085) (xy 158.13529 -403.750422) (xy 158.150643 -403.802711) (xy 158.158398 -403.856652)
			(xy 158.158398 -403.911148) (xy 158.158397 -403.911152) (xy 159.596054 -403.911152) (xy 159.596054 -403.856648)
			(xy 159.60381 -403.802699) (xy 159.619165 -403.750403) (xy 159.641806 -403.700825) (xy 159.671271 -403.654973)
			(xy 159.706962 -403.613781) (xy 159.748152 -403.578087) (xy 159.794002 -403.548618) (xy 159.843579 -403.525974)
			(xy 159.895874 -403.510616) (xy 159.949822 -403.502856) (xy 159.977074 -403.502368) (xy 160.840674 -403.502368)
			(xy 160.867926 -403.502878) (xy 160.921877 -403.510631) (xy 160.974174 -403.525984) (xy 161.023755 -403.548623)
			(xy 161.069608 -403.578089) (xy 161.110801 -403.61378) (xy 161.146496 -403.654971) (xy 161.175964 -403.700822)
			(xy 161.198607 -403.750401) (xy 161.213963 -403.802698) (xy 161.221721 -403.856648) (xy 161.221721 -403.911152)
			(xy 161.221721 -403.911155) (xy 162.659231 -403.911155) (xy 162.659231 -403.856645) (xy 162.666989 -403.802689)
			(xy 162.682346 -403.750387) (xy 162.704991 -403.700803) (xy 162.734463 -403.654946) (xy 162.77016 -403.61375)
			(xy 162.811357 -403.578054) (xy 162.857215 -403.548585) (xy 162.9068 -403.525942) (xy 162.959103 -403.510586)
			(xy 163.013059 -403.50283) (xy 163.040314 -403.502368) (xy 163.903914 -403.502368) (xy 163.931163 -403.502903)
			(xy 163.985106 -403.510661) (xy 164.037395 -403.526016) (xy 164.086968 -403.548657) (xy 164.132813 -403.578121)
			(xy 164.173999 -403.613811) (xy 164.209687 -403.654998) (xy 164.23915 -403.700845) (xy 164.261789 -403.750418)
			(xy 164.277142 -403.802708) (xy 164.284898 -403.856651) (xy 164.284898 -403.911149) (xy 164.284898 -403.911151)
			(xy 165.722554 -403.911151) (xy 165.722554 -403.856649) (xy 165.73031 -403.802702) (xy 165.745663 -403.750408)
			(xy 165.768302 -403.70083) (xy 165.797766 -403.654979) (xy 165.833455 -403.613788) (xy 165.874642 -403.578094)
			(xy 165.92049 -403.548625) (xy 165.970065 -403.525979) (xy 166.022357 -403.510619) (xy 166.076303 -403.502857)
			(xy 166.103554 -403.502368) (xy 166.967154 -403.502368) (xy 166.994407 -403.502876) (xy 167.04836 -403.510627)
			(xy 167.10066 -403.525978) (xy 167.150243 -403.548617) (xy 167.196099 -403.578082) (xy 167.237294 -403.613773)
			(xy 167.272991 -403.654964) (xy 167.302461 -403.700817) (xy 167.325106 -403.750397) (xy 167.340463 -403.802695)
			(xy 167.348221 -403.856647) (xy 167.348221 -403.911153) (xy 167.340463 -403.965105) (xy 167.325106 -404.017403)
			(xy 167.302461 -404.066983) (xy 167.272991 -404.112836) (xy 167.237294 -404.154027) (xy 167.196099 -404.189718)
			(xy 167.150243 -404.219183) (xy 167.10066 -404.241822) (xy 167.04836 -404.257173) (xy 166.994407 -404.264924)
			(xy 166.967154 -404.265384) (xy 166.103554 -404.265384) (xy 166.076303 -404.264943) (xy 166.022357 -404.257181)
			(xy 165.970065 -404.241821) (xy 165.92049 -404.219175) (xy 165.874642 -404.189706) (xy 165.833455 -404.154012)
			(xy 165.797766 -404.112821) (xy 165.768302 -404.06697) (xy 165.745663 -404.017392) (xy 165.73031 -403.965098)
			(xy 165.722554 -403.911151) (xy 164.284898 -403.911151) (xy 164.277142 -403.965092) (xy 164.261789 -404.017382)
			(xy 164.23915 -404.066955) (xy 164.209687 -404.112802) (xy 164.173999 -404.153989) (xy 164.132813 -404.189679)
			(xy 164.086968 -404.219143) (xy 164.037395 -404.241784) (xy 163.985106 -404.257139) (xy 163.931163 -404.264897)
			(xy 163.903914 -404.265384) (xy 163.040314 -404.265384) (xy 163.013059 -404.26497) (xy 162.959103 -404.257214)
			(xy 162.9068 -404.241858) (xy 162.857215 -404.219215) (xy 162.811357 -404.189746) (xy 162.77016 -404.15405)
			(xy 162.734463 -404.112854) (xy 162.704991 -404.066997) (xy 162.682346 -404.017413) (xy 162.666989 -403.965111)
			(xy 162.659231 -403.911155) (xy 161.221721 -403.911155) (xy 161.213963 -403.965102) (xy 161.198607 -404.017399)
			(xy 161.175964 -404.066978) (xy 161.146496 -404.112829) (xy 161.110801 -404.15402) (xy 161.069608 -404.189711)
			(xy 161.023755 -404.219177) (xy 160.974174 -404.241816) (xy 160.921877 -404.257169) (xy 160.867926 -404.264922)
			(xy 160.840674 -404.265384) (xy 159.977074 -404.265384) (xy 159.949822 -404.264944) (xy 159.895874 -404.257184)
			(xy 159.843579 -404.241826) (xy 159.794002 -404.219182) (xy 159.748152 -404.189713) (xy 159.706962 -404.154019)
			(xy 159.671271 -404.112827) (xy 159.641806 -404.066975) (xy 159.619165 -404.017397) (xy 159.60381 -403.965101)
			(xy 159.596054 -403.911152) (xy 158.158397 -403.911152) (xy 158.150643 -403.965089) (xy 158.13529 -404.017378)
			(xy 158.112653 -404.06695) (xy 158.083192 -404.112796) (xy 158.047506 -404.153982) (xy 158.006323 -404.189671)
			(xy 157.96048 -404.219137) (xy 157.91091 -404.241778) (xy 157.858623 -404.257136) (xy 157.804682 -404.264895)
			(xy 157.777434 -404.265384) (xy 156.913834 -404.265384) (xy 156.886578 -404.264971) (xy 156.83262 -404.257218)
			(xy 156.780314 -404.241864) (xy 156.730727 -404.219222) (xy 156.684867 -404.189753) (xy 156.643667 -404.154057)
			(xy 156.607968 -404.112861) (xy 156.578495 -404.067003) (xy 156.555848 -404.017417) (xy 156.540489 -403.965114)
			(xy 156.532731 -403.911156) (xy 155.09522 -403.911156) (xy 155.087464 -403.965099) (xy 155.072109 -404.017394)
			(xy 155.049467 -404.066972) (xy 155.02 -404.112822) (xy 154.984308 -404.154013) (xy 154.943118 -404.189704)
			(xy 154.897267 -404.21917) (xy 154.847689 -404.241811) (xy 154.795394 -404.257165) (xy 154.741445 -404.264921)
			(xy 154.714194 -404.265384) (xy 153.850594 -404.265384) (xy 153.823341 -404.264946) (xy 153.769391 -404.257188)
			(xy 153.717094 -404.241831) (xy 153.667514 -404.219189) (xy 153.621661 -404.18972) (xy 153.580469 -404.154026)
			(xy 153.544776 -404.112834) (xy 153.515309 -404.066981) (xy 153.492666 -404.017401) (xy 153.477311 -403.965103)
			(xy 153.469554 -403.911153) (xy 152.032021 -403.911153) (xy 152.024263 -403.965105) (xy 152.008906 -404.017403)
			(xy 151.986261 -404.066983) (xy 151.956791 -404.112836) (xy 151.921094 -404.154027) (xy 151.879899 -404.189718)
			(xy 151.834043 -404.219183) (xy 151.78446 -404.241822) (xy 151.73216 -404.257173) (xy 151.678207 -404.264924)
			(xy 151.650954 -404.265384) (xy 150.787354 -404.265384) (xy 150.760103 -404.264943) (xy 150.706157 -404.257181)
			(xy 150.653865 -404.241821) (xy 150.60429 -404.219175) (xy 150.558442 -404.189706) (xy 150.517255 -404.154012)
			(xy 150.481566 -404.112821) (xy 150.452102 -404.06697) (xy 150.429463 -404.017392) (xy 150.41411 -403.965098)
			(xy 150.406354 -403.911151) (xy 148.968698 -403.911151) (xy 148.960942 -403.965092) (xy 148.945589 -404.017382)
			(xy 148.92295 -404.066955) (xy 148.893487 -404.112802) (xy 148.857799 -404.153989) (xy 148.816613 -404.189679)
			(xy 148.770768 -404.219143) (xy 148.721195 -404.241784) (xy 148.668906 -404.257139) (xy 148.614963 -404.264897)
			(xy 148.587714 -404.265384) (xy 147.724114 -404.265384) (xy 147.696859 -404.26497) (xy 147.642903 -404.257214)
			(xy 147.5906 -404.241858) (xy 147.541015 -404.219215) (xy 147.495157 -404.189746) (xy 147.45396 -404.15405)
			(xy 147.418263 -404.112854) (xy 147.388791 -404.066997) (xy 147.366146 -404.017413) (xy 147.350789 -403.965111)
			(xy 147.343031 -403.911155) (xy 145.905521 -403.911155) (xy 145.897763 -403.965102) (xy 145.882407 -404.017399)
			(xy 145.859764 -404.066978) (xy 145.830296 -404.112829) (xy 145.794601 -404.15402) (xy 145.753408 -404.189711)
			(xy 145.707555 -404.219177) (xy 145.657974 -404.241816) (xy 145.605677 -404.257169) (xy 145.551726 -404.264922)
			(xy 145.524474 -404.265384) (xy 144.660874 -404.265384) (xy 144.633622 -404.264944) (xy 144.579674 -404.257184)
			(xy 144.527379 -404.241826) (xy 144.477802 -404.219182) (xy 144.431952 -404.189713) (xy 144.390762 -404.154019)
			(xy 144.355071 -404.112827) (xy 144.325606 -404.066975) (xy 144.302965 -404.017397) (xy 144.28761 -403.965101)
			(xy 144.279854 -403.911152) (xy 142.842197 -403.911152) (xy 142.834443 -403.965089) (xy 142.81909 -404.017378)
			(xy 142.796453 -404.06695) (xy 142.766992 -404.112796) (xy 142.731306 -404.153982) (xy 142.690123 -404.189671)
			(xy 142.64428 -404.219137) (xy 142.59471 -404.241778) (xy 142.542423 -404.257136) (xy 142.488482 -404.264895)
			(xy 142.461234 -404.265384) (xy 141.597634 -404.265384) (xy 141.570378 -404.264971) (xy 141.51642 -404.257218)
			(xy 141.464114 -404.241864) (xy 141.414527 -404.219222) (xy 141.368667 -404.189753) (xy 141.327467 -404.154057)
			(xy 141.291768 -404.112861) (xy 141.262295 -404.067003) (xy 141.239648 -404.017417) (xy 141.224289 -403.965114)
			(xy 141.216531 -403.911156) (xy 139.77902 -403.911156) (xy 139.771264 -403.965099) (xy 139.755909 -404.017394)
			(xy 139.733267 -404.066972) (xy 139.7038 -404.112822) (xy 139.668108 -404.154013) (xy 139.626918 -404.189704)
			(xy 139.581067 -404.21917) (xy 139.531489 -404.241811) (xy 139.479194 -404.257165) (xy 139.425245 -404.264921)
			(xy 139.397994 -404.265384) (xy 138.534394 -404.265384) (xy 138.507141 -404.264946) (xy 138.453191 -404.257188)
			(xy 138.400894 -404.241831) (xy 138.351314 -404.219189) (xy 138.305461 -404.18972) (xy 138.264269 -404.154026)
			(xy 138.228576 -404.112834) (xy 138.199109 -404.066981) (xy 138.176466 -404.017401) (xy 138.161111 -403.965103)
			(xy 138.153354 -403.911153) (xy 136.715821 -403.911153) (xy 136.708063 -403.965105) (xy 136.692706 -404.017403)
			(xy 136.670061 -404.066983) (xy 136.640591 -404.112836) (xy 136.604894 -404.154027) (xy 136.563699 -404.189718)
			(xy 136.517843 -404.219183) (xy 136.46826 -404.241822) (xy 136.41596 -404.257173) (xy 136.362007 -404.264924)
			(xy 136.334754 -404.265384) (xy 135.471154 -404.265384) (xy 135.443903 -404.264943) (xy 135.389957 -404.257181)
			(xy 135.337665 -404.241821) (xy 135.28809 -404.219175) (xy 135.242242 -404.189706) (xy 135.201055 -404.154012)
			(xy 135.165366 -404.112821) (xy 135.135902 -404.06697) (xy 135.113263 -404.017392) (xy 135.09791 -403.965098)
			(xy 135.090154 -403.911151) (xy 133.652498 -403.911151) (xy 133.644742 -403.965092) (xy 133.629389 -404.017382)
			(xy 133.60675 -404.066955) (xy 133.577287 -404.112802) (xy 133.541599 -404.153989) (xy 133.500413 -404.189679)
			(xy 133.454568 -404.219143) (xy 133.404995 -404.241784) (xy 133.352706 -404.257139) (xy 133.298763 -404.264897)
			(xy 133.271514 -404.265384) (xy 132.407914 -404.265384) (xy 132.380659 -404.26497) (xy 132.326703 -404.257214)
			(xy 132.2744 -404.241858) (xy 132.224815 -404.219215) (xy 132.178957 -404.189746) (xy 132.13776 -404.15405)
			(xy 132.102063 -404.112854) (xy 132.072591 -404.066997) (xy 132.049946 -404.017413) (xy 132.034589 -403.965111)
			(xy 132.026831 -403.911155) (xy 130.589321 -403.911155) (xy 130.581563 -403.965102) (xy 130.566207 -404.017399)
			(xy 130.543564 -404.066978) (xy 130.514096 -404.112829) (xy 130.478401 -404.15402) (xy 130.437208 -404.189711)
			(xy 130.391355 -404.219177) (xy 130.341774 -404.241816) (xy 130.289477 -404.257169) (xy 130.235526 -404.264922)
			(xy 130.208274 -404.265384) (xy 129.344674 -404.265384) (xy 129.317422 -404.264944) (xy 129.263474 -404.257184)
			(xy 129.211179 -404.241826) (xy 129.161602 -404.219182) (xy 129.115752 -404.189713) (xy 129.074562 -404.154019)
			(xy 129.038871 -404.112827) (xy 129.009406 -404.066975) (xy 128.986765 -404.017397) (xy 128.97141 -403.965101)
			(xy 128.963654 -403.911152) (xy 127.525997 -403.911152) (xy 127.518243 -403.965089) (xy 127.50289 -404.017378)
			(xy 127.480253 -404.06695) (xy 127.450792 -404.112796) (xy 127.415106 -404.153982) (xy 127.373923 -404.189671)
			(xy 127.32808 -404.219137) (xy 127.27851 -404.241778) (xy 127.226223 -404.257136) (xy 127.172282 -404.264895)
			(xy 127.145034 -404.265384) (xy 126.281434 -404.265384) (xy 126.254178 -404.264971) (xy 126.20022 -404.257218)
			(xy 126.147914 -404.241864) (xy 126.098327 -404.219222) (xy 126.052467 -404.189753) (xy 126.011267 -404.154057)
			(xy 125.975568 -404.112861) (xy 125.946095 -404.067003) (xy 125.923448 -404.017417) (xy 125.908089 -403.965114)
			(xy 125.900331 -403.911156) (xy 124.46282 -403.911156) (xy 124.455064 -403.965099) (xy 124.439709 -404.017394)
			(xy 124.417067 -404.066972) (xy 124.3876 -404.112822) (xy 124.351908 -404.154013) (xy 124.310718 -404.189704)
			(xy 124.264867 -404.21917) (xy 124.215289 -404.241811) (xy 124.162994 -404.257165) (xy 124.109045 -404.264921)
			(xy 124.081794 -404.265384) (xy 123.218194 -404.265384) (xy 123.190941 -404.264946) (xy 123.136991 -404.257188)
			(xy 123.084694 -404.241831) (xy 123.035114 -404.219189) (xy 122.989261 -404.18972) (xy 122.948069 -404.154026)
			(xy 122.912376 -404.112834) (xy 122.882909 -404.066981) (xy 122.860266 -404.017401) (xy 122.844911 -403.965103)
			(xy 122.837154 -403.911153) (xy 121.399621 -403.911153) (xy 121.391863 -403.965105) (xy 121.376506 -404.017403)
			(xy 121.353861 -404.066983) (xy 121.324391 -404.112836) (xy 121.288694 -404.154027) (xy 121.247499 -404.189718)
			(xy 121.201643 -404.219183) (xy 121.15206 -404.241822) (xy 121.09976 -404.257173) (xy 121.045807 -404.264924)
			(xy 121.018554 -404.265384) (xy 120.154954 -404.265384) (xy 120.127703 -404.264943) (xy 120.073757 -404.257181)
			(xy 120.021465 -404.241821) (xy 119.97189 -404.219175) (xy 119.926042 -404.189706) (xy 119.884855 -404.154012)
			(xy 119.849166 -404.112821) (xy 119.819702 -404.06697) (xy 119.797063 -404.017392) (xy 119.78171 -403.965098)
			(xy 119.773954 -403.911151) (xy 95.172998 -403.911151) (xy 95.165243 -403.965089) (xy 95.149891 -404.017377)
			(xy 95.127254 -404.066949) (xy 95.097793 -404.112794) (xy 95.062108 -404.153981) (xy 95.020925 -404.18967)
			(xy 94.975082 -404.219135) (xy 94.925513 -404.241777) (xy 94.873226 -404.257135) (xy 94.819286 -404.264895)
			(xy 94.792038 -404.265384) (xy 93.928438 -404.265384) (xy 93.901182 -404.264972) (xy 93.847223 -404.257219)
			(xy 93.794917 -404.241865) (xy 93.745329 -404.219223) (xy 93.699468 -404.189754) (xy 93.658269 -404.154058)
			(xy 93.622569 -404.112862) (xy 93.593095 -404.067004) (xy 93.570448 -404.017418) (xy 93.555089 -403.965114)
			(xy 93.547331 -403.911156) (xy 92.10982 -403.911156) (xy 92.102064 -403.965099) (xy 92.086709 -404.017394)
			(xy 92.064068 -404.066971) (xy 92.034601 -404.112821) (xy 91.99891 -404.154011) (xy 91.95772 -404.189703)
			(xy 91.911869 -404.219169) (xy 91.862292 -404.24181) (xy 91.809997 -404.257165) (xy 91.756049 -404.264921)
			(xy 91.728798 -404.265384) (xy 90.865198 -404.265384) (xy 90.837945 -404.264946) (xy 90.783994 -404.257189)
			(xy 90.731696 -404.241833) (xy 90.682116 -404.21919) (xy 90.636263 -404.189722) (xy 90.595071 -404.154028)
			(xy 90.559377 -404.112835) (xy 90.529909 -404.066982) (xy 90.507267 -404.017402) (xy 90.491911 -403.965104)
			(xy 90.484154 -403.911153) (xy 89.046621 -403.911153) (xy 89.038863 -403.965104) (xy 89.023506 -404.017402)
			(xy 89.000862 -404.066982) (xy 88.971392 -404.112834) (xy 88.935696 -404.154025) (xy 88.894501 -404.189717)
			(xy 88.848645 -404.219182) (xy 88.799063 -404.241821) (xy 88.746763 -404.257172) (xy 88.692811 -404.264924)
			(xy 88.665558 -404.265384) (xy 87.801958 -404.265384) (xy 87.774707 -404.264943) (xy 87.72076 -404.257181)
			(xy 87.668467 -404.241822) (xy 87.618892 -404.219177) (xy 87.573044 -404.189707) (xy 87.531857 -404.154014)
			(xy 87.496167 -404.112822) (xy 87.466703 -404.066971) (xy 87.444064 -404.017393) (xy 87.42871 -403.965098)
			(xy 87.420954 -403.911151) (xy 85.983298 -403.911151) (xy 85.975542 -403.965091) (xy 85.960189 -404.017381)
			(xy 85.937551 -404.066954) (xy 85.908088 -404.112801) (xy 85.872401 -404.153988) (xy 85.831215 -404.189677)
			(xy 85.78537 -404.219142) (xy 85.735798 -404.241783) (xy 85.683509 -404.257138) (xy 85.629567 -404.264897)
			(xy 85.602318 -404.265384) (xy 84.738718 -404.265384) (xy 84.711463 -404.26497) (xy 84.657506 -404.257215)
			(xy 84.605203 -404.241859) (xy 84.555617 -404.219217) (xy 84.509759 -404.189747) (xy 84.468562 -404.154051)
			(xy 84.432864 -404.112855) (xy 84.403392 -404.066999) (xy 84.380747 -404.017414) (xy 84.365389 -403.965111)
			(xy 84.357631 -403.911155) (xy 82.920121 -403.911155) (xy 82.912364 -403.965102) (xy 82.897007 -404.017398)
			(xy 82.874365 -404.066976) (xy 82.844897 -404.112828) (xy 82.809203 -404.154018) (xy 82.76801 -404.18971)
			(xy 82.722157 -404.219175) (xy 82.672577 -404.241815) (xy 82.62028 -404.257168) (xy 82.56633 -404.264922)
			(xy 82.539078 -404.265384) (xy 81.675478 -404.265384) (xy 81.648226 -404.264945) (xy 81.594277 -404.257185)
			(xy 81.541982 -404.241827) (xy 81.492404 -404.219183) (xy 81.446554 -404.189715) (xy 81.405364 -404.154021)
			(xy 81.369672 -404.112829) (xy 81.340206 -404.066976) (xy 81.317565 -404.017397) (xy 81.30221 -403.965101)
			(xy 81.294454 -403.911152) (xy 79.856797 -403.911152) (xy 79.849043 -403.965089) (xy 79.833691 -404.017377)
			(xy 79.811054 -404.066949) (xy 79.781593 -404.112794) (xy 79.745908 -404.153981) (xy 79.704725 -404.18967)
			(xy 79.658882 -404.219135) (xy 79.609313 -404.241777) (xy 79.557026 -404.257135) (xy 79.503086 -404.264895)
			(xy 79.475838 -404.265384) (xy 78.612238 -404.265384) (xy 78.584982 -404.264972) (xy 78.531023 -404.257219)
			(xy 78.478717 -404.241865) (xy 78.429129 -404.219223) (xy 78.383268 -404.189754) (xy 78.342069 -404.154058)
			(xy 78.306369 -404.112862) (xy 78.276895 -404.067004) (xy 78.254248 -404.017418) (xy 78.238889 -403.965114)
			(xy 78.231131 -403.911156) (xy 76.79362 -403.911156) (xy 76.785864 -403.965099) (xy 76.770509 -404.017394)
			(xy 76.747868 -404.066971) (xy 76.718401 -404.112821) (xy 76.68271 -404.154011) (xy 76.64152 -404.189703)
			(xy 76.595669 -404.219169) (xy 76.546092 -404.24181) (xy 76.493797 -404.257165) (xy 76.439849 -404.264921)
			(xy 76.412598 -404.265384) (xy 75.548998 -404.265384) (xy 75.521745 -404.264946) (xy 75.467794 -404.257189)
			(xy 75.415496 -404.241833) (xy 75.365916 -404.21919) (xy 75.320063 -404.189722) (xy 75.278871 -404.154028)
			(xy 75.243177 -404.112835) (xy 75.213709 -404.066982) (xy 75.191067 -404.017402) (xy 75.175711 -403.965104)
			(xy 75.167954 -403.911153) (xy 73.730421 -403.911153) (xy 73.722663 -403.965104) (xy 73.707306 -404.017402)
			(xy 73.684662 -404.066982) (xy 73.655192 -404.112834) (xy 73.619496 -404.154025) (xy 73.578301 -404.189717)
			(xy 73.532445 -404.219182) (xy 73.482863 -404.241821) (xy 73.430563 -404.257172) (xy 73.376611 -404.264924)
			(xy 73.349358 -404.265384) (xy 72.485758 -404.265384) (xy 72.458507 -404.264943) (xy 72.40456 -404.257181)
			(xy 72.352267 -404.241822) (xy 72.302692 -404.219177) (xy 72.256844 -404.189707) (xy 72.215657 -404.154014)
			(xy 72.179967 -404.112822) (xy 72.150503 -404.066971) (xy 72.127864 -404.017393) (xy 72.11251 -403.965098)
			(xy 72.104754 -403.911151) (xy 70.667098 -403.911151) (xy 70.659342 -403.965091) (xy 70.643989 -404.017381)
			(xy 70.621351 -404.066954) (xy 70.591888 -404.112801) (xy 70.556201 -404.153988) (xy 70.515015 -404.189677)
			(xy 70.46917 -404.219142) (xy 70.419598 -404.241783) (xy 70.367309 -404.257138) (xy 70.313367 -404.264897)
			(xy 70.286118 -404.265384) (xy 69.422518 -404.265384) (xy 69.395263 -404.26497) (xy 69.341306 -404.257215)
			(xy 69.289003 -404.241859) (xy 69.239417 -404.219217) (xy 69.193559 -404.189747) (xy 69.152362 -404.154051)
			(xy 69.116664 -404.112855) (xy 69.087192 -404.066999) (xy 69.064547 -404.017414) (xy 69.049189 -403.965111)
			(xy 69.041431 -403.911155) (xy 67.603921 -403.911155) (xy 67.596164 -403.965102) (xy 67.580807 -404.017398)
			(xy 67.558165 -404.066976) (xy 67.528697 -404.112828) (xy 67.493003 -404.154018) (xy 67.45181 -404.18971)
			(xy 67.405957 -404.219175) (xy 67.356377 -404.241815) (xy 67.30408 -404.257168) (xy 67.25013 -404.264922)
			(xy 67.222878 -404.265384) (xy 66.359278 -404.265384) (xy 66.332026 -404.264945) (xy 66.278077 -404.257185)
			(xy 66.225782 -404.241827) (xy 66.176204 -404.219183) (xy 66.130354 -404.189715) (xy 66.089164 -404.154021)
			(xy 66.053472 -404.112829) (xy 66.024006 -404.066976) (xy 66.001365 -404.017397) (xy 65.98601 -403.965101)
			(xy 65.978254 -403.911152) (xy 64.540597 -403.911152) (xy 64.532843 -403.965089) (xy 64.517491 -404.017377)
			(xy 64.494854 -404.066949) (xy 64.465393 -404.112794) (xy 64.429708 -404.153981) (xy 64.388525 -404.18967)
			(xy 64.342682 -404.219135) (xy 64.293113 -404.241777) (xy 64.240826 -404.257135) (xy 64.186886 -404.264895)
			(xy 64.159638 -404.265384) (xy 63.296038 -404.265384) (xy 63.268782 -404.264972) (xy 63.214823 -404.257219)
			(xy 63.162517 -404.241865) (xy 63.112929 -404.219223) (xy 63.067068 -404.189754) (xy 63.025869 -404.154058)
			(xy 62.990169 -404.112862) (xy 62.960695 -404.067004) (xy 62.938048 -404.017418) (xy 62.922689 -403.965114)
			(xy 62.914931 -403.911156) (xy 61.47742 -403.911156) (xy 61.469664 -403.965099) (xy 61.454309 -404.017394)
			(xy 61.431668 -404.066971) (xy 61.402201 -404.112821) (xy 61.36651 -404.154011) (xy 61.32532 -404.189703)
			(xy 61.279469 -404.219169) (xy 61.229892 -404.24181) (xy 61.177597 -404.257165) (xy 61.123649 -404.264921)
			(xy 61.096398 -404.265384) (xy 60.232798 -404.265384) (xy 60.205545 -404.264946) (xy 60.151594 -404.257189)
			(xy 60.099296 -404.241833) (xy 60.049716 -404.21919) (xy 60.003863 -404.189722) (xy 59.962671 -404.154028)
			(xy 59.926977 -404.112835) (xy 59.897509 -404.066982) (xy 59.874867 -404.017402) (xy 59.859511 -403.965104)
			(xy 59.851754 -403.911153) (xy 58.414221 -403.911153) (xy 58.406463 -403.965104) (xy 58.391106 -404.017402)
			(xy 58.368462 -404.066982) (xy 58.338992 -404.112834) (xy 58.303296 -404.154025) (xy 58.262101 -404.189717)
			(xy 58.216245 -404.219182) (xy 58.166663 -404.241821) (xy 58.114363 -404.257172) (xy 58.060411 -404.264924)
			(xy 58.033158 -404.265384) (xy 57.169558 -404.265384) (xy 57.142307 -404.264943) (xy 57.08836 -404.257181)
			(xy 57.036067 -404.241822) (xy 56.986492 -404.219177) (xy 56.940644 -404.189707) (xy 56.899457 -404.154014)
			(xy 56.863767 -404.112822) (xy 56.834303 -404.066971) (xy 56.811664 -404.017393) (xy 56.79631 -403.965098)
			(xy 56.788554 -403.911151) (xy 55.350898 -403.911151) (xy 55.343142 -403.965091) (xy 55.327789 -404.017381)
			(xy 55.305151 -404.066954) (xy 55.275688 -404.112801) (xy 55.240001 -404.153988) (xy 55.198815 -404.189677)
			(xy 55.15297 -404.219142) (xy 55.103398 -404.241783) (xy 55.051109 -404.257138) (xy 54.997167 -404.264897)
			(xy 54.969918 -404.265384) (xy 54.106318 -404.265384) (xy 54.079063 -404.26497) (xy 54.025106 -404.257215)
			(xy 53.972803 -404.241859) (xy 53.923217 -404.219217) (xy 53.877359 -404.189747) (xy 53.836162 -404.154051)
			(xy 53.800464 -404.112855) (xy 53.770992 -404.066999) (xy 53.748347 -404.017414) (xy 53.732989 -403.965111)
			(xy 53.725231 -403.911155) (xy 52.287721 -403.911155) (xy 52.279964 -403.965102) (xy 52.264607 -404.017398)
			(xy 52.241965 -404.066976) (xy 52.212497 -404.112828) (xy 52.176803 -404.154018) (xy 52.13561 -404.18971)
			(xy 52.089757 -404.219175) (xy 52.040177 -404.241815) (xy 51.98788 -404.257168) (xy 51.93393 -404.264922)
			(xy 51.906678 -404.265384) (xy 51.043078 -404.265384) (xy 51.015826 -404.264945) (xy 50.961877 -404.257185)
			(xy 50.909582 -404.241827) (xy 50.860004 -404.219183) (xy 50.814154 -404.189715) (xy 50.772964 -404.154021)
			(xy 50.737272 -404.112829) (xy 50.707806 -404.066976) (xy 50.685165 -404.017397) (xy 50.66981 -403.965101)
			(xy 50.662054 -403.911152) (xy 49.224397 -403.911152) (xy 49.216643 -403.965089) (xy 49.201291 -404.017377)
			(xy 49.178654 -404.066949) (xy 49.149193 -404.112794) (xy 49.113508 -404.153981) (xy 49.072325 -404.18967)
			(xy 49.026482 -404.219135) (xy 48.976913 -404.241777) (xy 48.924626 -404.257135) (xy 48.870686 -404.264895)
			(xy 48.843438 -404.265384) (xy 47.979838 -404.265384) (xy 47.952582 -404.264972) (xy 47.898623 -404.257219)
			(xy 47.846317 -404.241865) (xy 47.796729 -404.219223) (xy 47.750868 -404.189754) (xy 47.709669 -404.154058)
			(xy 47.673969 -404.112862) (xy 47.644495 -404.067004) (xy 47.621848 -404.017418) (xy 47.606489 -403.965114)
			(xy 47.598731 -403.911156) (xy 3.86649 -403.911156) (xy 5.184394 -405.22906) (xy 102.242112 -405.22906)
			(xy 102.242112 -404.36546) (xy 102.242598 -404.338209) (xy 102.250354 -404.284261) (xy 102.265709 -404.231966)
			(xy 102.288351 -404.182389) (xy 102.317817 -404.136539) (xy 102.353508 -404.095348) (xy 102.394699 -404.059657)
			(xy 102.440549 -404.030191) (xy 102.490126 -404.007549) (xy 102.542421 -403.992194) (xy 102.596369 -403.984438)
			(xy 102.650871 -403.984438) (xy 102.704819 -403.992194) (xy 102.757114 -404.007549) (xy 102.806691 -404.030191)
			(xy 102.852541 -404.059657) (xy 102.893732 -404.095348) (xy 102.929423 -404.136539) (xy 102.958889 -404.182389)
			(xy 102.981531 -404.231966) (xy 102.996886 -404.284261) (xy 103.004642 -404.338209) (xy 103.005128 -404.36546)
			(xy 103.005128 -405.22906) (xy 103.004642 -405.256311) (xy 102.996886 -405.310259) (xy 102.981531 -405.362554)
			(xy 102.958889 -405.412131) (xy 102.929423 -405.457981) (xy 102.893732 -405.499172) (xy 102.852541 -405.534863)
			(xy 102.806691 -405.564329) (xy 102.757114 -405.586971) (xy 102.704819 -405.602326) (xy 102.650871 -405.610082)
			(xy 102.596369 -405.610082) (xy 102.542421 -405.602326) (xy 102.490126 -405.586971) (xy 102.440549 -405.564329)
			(xy 102.394699 -405.534863) (xy 102.353508 -405.499172) (xy 102.317817 -405.457981) (xy 102.288351 -405.412131)
			(xy 102.265709 -405.362554) (xy 102.250354 -405.310259) (xy 102.242598 -405.256311) (xy 102.242112 -405.22906)
			(xy 5.184394 -405.22906) (xy 6.990842 -407.035508) (xy 15.978632 -407.035508) (xy 15.978632 -406.171908)
			(xy 15.979118 -406.144657) (xy 15.986874 -406.090709) (xy 16.002229 -406.038414) (xy 16.024871 -405.988837)
			(xy 16.054337 -405.942987) (xy 16.090028 -405.901796) (xy 16.131219 -405.866105) (xy 16.177069 -405.836639)
			(xy 16.226646 -405.813997) (xy 16.278941 -405.798642) (xy 16.332889 -405.790886) (xy 16.387391 -405.790886)
			(xy 16.441339 -405.798642) (xy 16.493634 -405.813997) (xy 16.543211 -405.836639) (xy 16.589061 -405.866105)
			(xy 16.630252 -405.901796) (xy 16.665943 -405.942987) (xy 16.695409 -405.988837) (xy 16.718051 -406.038414)
			(xy 16.733406 -406.090709) (xy 16.741162 -406.144657) (xy 16.741648 -406.171908) (xy 16.741648 -407.031753)
			(xy 48.944975 -407.031753) (xy 48.944975 -406.977247) (xy 48.952733 -406.923295) (xy 48.96809 -406.870997)
			(xy 48.990734 -406.821417) (xy 49.020204 -406.775565) (xy 49.0559 -406.734373) (xy 49.097095 -406.698681)
			(xy 49.142951 -406.669216) (xy 49.192533 -406.646577) (xy 49.244833 -406.631225) (xy 49.298785 -406.623473)
			(xy 49.326038 -406.623012) (xy 50.189638 -406.623012) (xy 50.216889 -406.62346) (xy 50.270835 -406.631222)
			(xy 50.323128 -406.646581) (xy 50.372703 -406.669225) (xy 50.418551 -406.698694) (xy 50.459739 -406.734388)
			(xy 50.495428 -406.775579) (xy 50.524893 -406.82143) (xy 50.547532 -406.871007) (xy 50.562886 -406.923302)
			(xy 50.570642 -406.977249) (xy 50.570642 -407.031749) (xy 52.008298 -407.031749) (xy 52.008298 -406.977251)
			(xy 52.016054 -406.923308) (xy 52.031407 -406.871018) (xy 52.054045 -406.821445) (xy 52.083508 -406.775598)
			(xy 52.119195 -406.734411) (xy 52.16038 -406.698721) (xy 52.206226 -406.669256) (xy 52.255797 -406.646615)
			(xy 52.308087 -406.631258) (xy 52.362029 -406.6235) (xy 52.389278 -406.623012) (xy 53.252878 -406.623012)
			(xy 53.280133 -406.623433) (xy 53.33409 -406.631188) (xy 53.386393 -406.646543) (xy 53.435978 -406.669186)
			(xy 53.481837 -406.698655) (xy 53.523034 -406.73435) (xy 53.558732 -406.775546) (xy 53.588204 -406.821402)
			(xy 53.610849 -406.870987) (xy 53.626207 -406.923289) (xy 53.633965 -406.977245) (xy 53.633965 -407.031752)
			(xy 55.071475 -407.031752) (xy 55.071475 -406.977248) (xy 55.079232 -406.923298) (xy 55.094589 -406.871002)
			(xy 55.117231 -406.821423) (xy 55.146699 -406.775571) (xy 55.182393 -406.73438) (xy 55.223586 -406.698688)
			(xy 55.269439 -406.669222) (xy 55.319018 -406.646582) (xy 55.371316 -406.631229) (xy 55.425266 -406.623474)
			(xy 55.452518 -406.623012) (xy 56.316118 -406.623012) (xy 56.34337 -406.623459) (xy 56.397318 -406.631218)
			(xy 56.449614 -406.646576) (xy 56.499191 -406.669219) (xy 56.545042 -406.698687) (xy 56.586232 -406.734381)
			(xy 56.621924 -406.775573) (xy 56.65139 -406.821424) (xy 56.674031 -406.871003) (xy 56.689386 -406.923299)
			(xy 56.697142 -406.977248) (xy 56.697142 -407.031748) (xy 58.134798 -407.031748) (xy 58.134798 -406.977252)
			(xy 58.142553 -406.923311) (xy 58.157905 -406.871022) (xy 58.180542 -406.821451) (xy 58.210003 -406.775605)
			(xy 58.245688 -406.734418) (xy 58.286871 -406.698728) (xy 58.332714 -406.669262) (xy 58.382283 -406.64662)
			(xy 58.43457 -406.631262) (xy 58.48851 -406.623501) (xy 58.515758 -406.623012) (xy 59.379358 -406.623012)
			(xy 59.406614 -406.623432) (xy 59.460573 -406.631185) (xy 59.512878 -406.646538) (xy 59.562466 -406.669179)
			(xy 59.608327 -406.698648) (xy 59.649527 -406.734343) (xy 59.685227 -406.775539) (xy 59.714701 -406.821397)
			(xy 59.737348 -406.870982) (xy 59.752707 -406.923286) (xy 59.760465 -406.977244) (xy 59.760465 -407.03175)
			(xy 61.197998 -407.03175) (xy 61.197998 -406.97725) (xy 61.205754 -406.923306) (xy 61.221108 -406.871014)
			(xy 61.243748 -406.821439) (xy 61.273213 -406.775592) (xy 61.308902 -406.734404) (xy 61.35009 -406.698714)
			(xy 61.395938 -406.669249) (xy 61.445512 -406.646609) (xy 61.497804 -406.631255) (xy 61.551748 -406.623498)
			(xy 61.578998 -406.623012) (xy 62.442598 -406.623012) (xy 62.469852 -406.623435) (xy 62.523806 -406.631192)
			(xy 62.576107 -406.646549) (xy 62.62569 -406.669192) (xy 62.671546 -406.698662) (xy 62.712741 -406.734357)
			(xy 62.748437 -406.775552) (xy 62.777907 -406.821408) (xy 62.800551 -406.870991) (xy 62.815908 -406.923292)
			(xy 62.823665 -406.977246) (xy 62.823665 -407.031753) (xy 64.261175 -407.031753) (xy 64.261175 -406.977247)
			(xy 64.268933 -406.923295) (xy 64.28429 -406.870997) (xy 64.306934 -406.821417) (xy 64.336404 -406.775565)
			(xy 64.3721 -406.734373) (xy 64.413295 -406.698681) (xy 64.459151 -406.669216) (xy 64.508733 -406.646577)
			(xy 64.561033 -406.631225) (xy 64.614985 -406.623473) (xy 64.642238 -406.623012) (xy 65.505838 -406.623012)
			(xy 65.533089 -406.62346) (xy 65.587035 -406.631222) (xy 65.639328 -406.646581) (xy 65.688903 -406.669225)
			(xy 65.734751 -406.698694) (xy 65.775939 -406.734388) (xy 65.811628 -406.775579) (xy 65.841093 -406.82143)
			(xy 65.863732 -406.871007) (xy 65.879086 -406.923302) (xy 65.886842 -406.977249) (xy 65.886842 -407.031749)
			(xy 67.324498 -407.031749) (xy 67.324498 -406.977251) (xy 67.332254 -406.923308) (xy 67.347607 -406.871018)
			(xy 67.370245 -406.821445) (xy 67.399708 -406.775598) (xy 67.435395 -406.734411) (xy 67.47658 -406.698721)
			(xy 67.522426 -406.669256) (xy 67.571997 -406.646615) (xy 67.624287 -406.631258) (xy 67.678229 -406.6235)
			(xy 67.705478 -406.623012) (xy 68.569078 -406.623012) (xy 68.596333 -406.623433) (xy 68.65029 -406.631188)
			(xy 68.702593 -406.646543) (xy 68.752178 -406.669186) (xy 68.798037 -406.698655) (xy 68.839234 -406.73435)
			(xy 68.874932 -406.775546) (xy 68.904404 -406.821402) (xy 68.927049 -406.870987) (xy 68.942407 -406.923289)
			(xy 68.950165 -406.977245) (xy 68.950165 -407.031752) (xy 70.387675 -407.031752) (xy 70.387675 -406.977248)
			(xy 70.395432 -406.923298) (xy 70.410789 -406.871002) (xy 70.433431 -406.821423) (xy 70.462899 -406.775571)
			(xy 70.498593 -406.73438) (xy 70.539786 -406.698688) (xy 70.585639 -406.669222) (xy 70.635218 -406.646582)
			(xy 70.687516 -406.631229) (xy 70.741466 -406.623474) (xy 70.768718 -406.623012) (xy 71.632318 -406.623012)
			(xy 71.65957 -406.623459) (xy 71.713518 -406.631218) (xy 71.765814 -406.646576) (xy 71.815391 -406.669219)
			(xy 71.861242 -406.698687) (xy 71.902432 -406.734381) (xy 71.938124 -406.775573) (xy 71.96759 -406.821424)
			(xy 71.990231 -406.871003) (xy 72.005586 -406.923299) (xy 72.013342 -406.977248) (xy 72.013342 -407.031748)
			(xy 73.450998 -407.031748) (xy 73.450998 -406.977252) (xy 73.458753 -406.923311) (xy 73.474105 -406.871022)
			(xy 73.496742 -406.821451) (xy 73.526203 -406.775605) (xy 73.561888 -406.734418) (xy 73.603071 -406.698728)
			(xy 73.648914 -406.669262) (xy 73.698483 -406.64662) (xy 73.75077 -406.631262) (xy 73.80471 -406.623501)
			(xy 73.831958 -406.623012) (xy 74.695558 -406.623012) (xy 74.722814 -406.623432) (xy 74.776773 -406.631185)
			(xy 74.829078 -406.646538) (xy 74.878666 -406.669179) (xy 74.924527 -406.698648) (xy 74.965727 -406.734343)
			(xy 75.001427 -406.775539) (xy 75.030901 -406.821397) (xy 75.053548 -406.870982) (xy 75.068907 -406.923286)
			(xy 75.076665 -406.977244) (xy 75.076665 -407.03175) (xy 76.514198 -407.03175) (xy 76.514198 -406.97725)
			(xy 76.521954 -406.923306) (xy 76.537308 -406.871014) (xy 76.559948 -406.821439) (xy 76.589413 -406.775592)
			(xy 76.625102 -406.734404) (xy 76.66629 -406.698714) (xy 76.712138 -406.669249) (xy 76.761712 -406.646609)
			(xy 76.814004 -406.631255) (xy 76.867948 -406.623498) (xy 76.895198 -406.623012) (xy 77.758798 -406.623012)
			(xy 77.786052 -406.623435) (xy 77.840006 -406.631192) (xy 77.892307 -406.646549) (xy 77.94189 -406.669192)
			(xy 77.987746 -406.698662) (xy 78.028941 -406.734357) (xy 78.064637 -406.775552) (xy 78.094107 -406.821408)
			(xy 78.116751 -406.870991) (xy 78.132108 -406.923292) (xy 78.139865 -406.977246) (xy 78.139865 -407.031753)
			(xy 79.577375 -407.031753) (xy 79.577375 -406.977247) (xy 79.585133 -406.923295) (xy 79.60049 -406.870997)
			(xy 79.623134 -406.821417) (xy 79.652604 -406.775565) (xy 79.6883 -406.734373) (xy 79.729495 -406.698681)
			(xy 79.775351 -406.669216) (xy 79.824933 -406.646577) (xy 79.877233 -406.631225) (xy 79.931185 -406.623473)
			(xy 79.958438 -406.623012) (xy 80.822038 -406.623012) (xy 80.849289 -406.62346) (xy 80.903235 -406.631222)
			(xy 80.955528 -406.646581) (xy 81.005103 -406.669225) (xy 81.050951 -406.698694) (xy 81.092139 -406.734388)
			(xy 81.127828 -406.775579) (xy 81.157293 -406.82143) (xy 81.179932 -406.871007) (xy 81.195286 -406.923302)
			(xy 81.203042 -406.977249) (xy 81.203042 -407.031749) (xy 82.640698 -407.031749) (xy 82.640698 -406.977251)
			(xy 82.648454 -406.923308) (xy 82.663807 -406.871018) (xy 82.686445 -406.821445) (xy 82.715908 -406.775598)
			(xy 82.751595 -406.734411) (xy 82.79278 -406.698721) (xy 82.838626 -406.669256) (xy 82.888197 -406.646615)
			(xy 82.940487 -406.631258) (xy 82.994429 -406.6235) (xy 83.021678 -406.623012) (xy 83.885278 -406.623012)
			(xy 83.912533 -406.623433) (xy 83.96649 -406.631188) (xy 84.018793 -406.646543) (xy 84.068378 -406.669186)
			(xy 84.114237 -406.698655) (xy 84.155434 -406.73435) (xy 84.191132 -406.775546) (xy 84.220604 -406.821402)
			(xy 84.243249 -406.870987) (xy 84.258607 -406.923289) (xy 84.266365 -406.977245) (xy 84.266365 -407.031752)
			(xy 85.703875 -407.031752) (xy 85.703875 -406.977248) (xy 85.711632 -406.923298) (xy 85.726989 -406.871002)
			(xy 85.749631 -406.821423) (xy 85.779099 -406.775571) (xy 85.814793 -406.73438) (xy 85.855986 -406.698688)
			(xy 85.901839 -406.669222) (xy 85.951418 -406.646582) (xy 86.003716 -406.631229) (xy 86.057666 -406.623474)
			(xy 86.084918 -406.623012) (xy 86.948518 -406.623012) (xy 86.97577 -406.623459) (xy 87.029718 -406.631218)
			(xy 87.082014 -406.646576) (xy 87.131591 -406.669219) (xy 87.177442 -406.698687) (xy 87.218632 -406.734381)
			(xy 87.254324 -406.775573) (xy 87.28379 -406.821424) (xy 87.306431 -406.871003) (xy 87.321786 -406.923299)
			(xy 87.329542 -406.977248) (xy 87.329542 -407.031748) (xy 88.767198 -407.031748) (xy 88.767198 -406.977252)
			(xy 88.774953 -406.923311) (xy 88.790305 -406.871022) (xy 88.812942 -406.821451) (xy 88.842403 -406.775605)
			(xy 88.878088 -406.734418) (xy 88.919271 -406.698728) (xy 88.965114 -406.669262) (xy 89.014683 -406.64662)
			(xy 89.06697 -406.631262) (xy 89.12091 -406.623501) (xy 89.148158 -406.623012) (xy 90.011758 -406.623012)
			(xy 90.039014 -406.623432) (xy 90.092973 -406.631185) (xy 90.145278 -406.646538) (xy 90.194866 -406.669179)
			(xy 90.240727 -406.698648) (xy 90.281927 -406.734343) (xy 90.317627 -406.775539) (xy 90.347101 -406.821397)
			(xy 90.369748 -406.870982) (xy 90.385107 -406.923286) (xy 90.392865 -406.977244) (xy 90.392865 -407.03175)
			(xy 91.830398 -407.03175) (xy 91.830398 -406.97725) (xy 91.838154 -406.923306) (xy 91.853508 -406.871014)
			(xy 91.876148 -406.821439) (xy 91.905613 -406.775592) (xy 91.941302 -406.734404) (xy 91.98249 -406.698714)
			(xy 92.028338 -406.669249) (xy 92.077912 -406.646609) (xy 92.130204 -406.631255) (xy 92.184148 -406.623498)
			(xy 92.211398 -406.623012) (xy 93.074998 -406.623012) (xy 93.102252 -406.623435) (xy 93.156206 -406.631192)
			(xy 93.208507 -406.646549) (xy 93.25809 -406.669192) (xy 93.303946 -406.698662) (xy 93.345141 -406.734357)
			(xy 93.380837 -406.775552) (xy 93.410307 -406.821408) (xy 93.432951 -406.870991) (xy 93.448308 -406.923292)
			(xy 93.456065 -406.977246) (xy 93.456065 -407.031753) (xy 94.893575 -407.031753) (xy 94.893575 -406.977247)
			(xy 94.901333 -406.923295) (xy 94.91669 -406.870997) (xy 94.939334 -406.821417) (xy 94.968804 -406.775565)
			(xy 95.0045 -406.734373) (xy 95.045695 -406.698681) (xy 95.091551 -406.669216) (xy 95.141133 -406.646577)
			(xy 95.193433 -406.631225) (xy 95.247385 -406.623473) (xy 95.274638 -406.623012) (xy 96.138238 -406.623012)
			(xy 96.165489 -406.62346) (xy 96.219435 -406.631222) (xy 96.271728 -406.646581) (xy 96.321303 -406.669225)
			(xy 96.367151 -406.698694) (xy 96.408339 -406.734388) (xy 96.444028 -406.775579) (xy 96.473493 -406.82143)
			(xy 96.496132 -406.871007) (xy 96.511486 -406.923302) (xy 96.519242 -406.977249) (xy 96.519242 -407.031751)
			(xy 96.511486 -407.085698) (xy 96.496132 -407.137993) (xy 96.495694 -407.138953) (xy 106.243063 -407.138953)
			(xy 106.243063 -407.084447) (xy 106.250821 -407.030495) (xy 106.266177 -406.978197) (xy 106.288821 -406.928617)
			(xy 106.31829 -406.882763) (xy 106.353985 -406.841571) (xy 106.395179 -406.805878) (xy 106.441034 -406.776411)
			(xy 106.490616 -406.75377) (xy 106.542915 -406.738416) (xy 106.596867 -406.730662) (xy 106.62412 -406.7302)
			(xy 107.48772 -406.7302) (xy 107.514971 -406.730671) (xy 107.568918 -406.73843) (xy 107.621211 -406.753787)
			(xy 107.670787 -406.77643) (xy 107.716636 -406.805898) (xy 107.757824 -406.84159) (xy 107.793514 -406.88278)
			(xy 107.82298 -406.928631) (xy 107.84562 -406.978208) (xy 107.860974 -407.030502) (xy 107.861153 -407.031748)
			(xy 121.120198 -407.031748) (xy 121.120198 -406.977252) (xy 121.127953 -406.923312) (xy 121.143305 -406.871023)
			(xy 121.165942 -406.821452) (xy 121.195402 -406.775606) (xy 121.231087 -406.734419) (xy 121.272269 -406.69873)
			(xy 121.318111 -406.669264) (xy 121.36768 -406.646621) (xy 121.419967 -406.631263) (xy 121.473906 -406.623501)
			(xy 121.501154 -406.623012) (xy 122.364754 -406.623012) (xy 122.39201 -406.623432) (xy 122.445969 -406.631184)
			(xy 122.498275 -406.646537) (xy 122.547864 -406.669178) (xy 122.593725 -406.698646) (xy 122.634926 -406.734342)
			(xy 122.670626 -406.775538) (xy 122.7001 -406.821396) (xy 122.722747 -406.870981) (xy 122.738106 -406.923286)
			(xy 122.745865 -406.977244) (xy 122.745865 -407.03175) (xy 124.183398 -407.03175) (xy 124.183398 -406.97725)
			(xy 124.191154 -406.923306) (xy 124.206508 -406.871015) (xy 124.229148 -406.821441) (xy 124.258612 -406.775593)
			(xy 124.294301 -406.734405) (xy 124.335488 -406.698715) (xy 124.381335 -406.669251) (xy 124.430909 -406.64661)
			(xy 124.4832 -406.631255) (xy 124.537144 -406.623499) (xy 124.564394 -406.623012) (xy 125.427994 -406.623012)
			(xy 125.455249 -406.623434) (xy 125.509203 -406.631191) (xy 125.561504 -406.646548) (xy 125.611088 -406.669191)
			(xy 125.656944 -406.69866) (xy 125.69814 -406.734356) (xy 125.733836 -406.775551) (xy 125.763306 -406.821407)
			(xy 125.78595 -406.87099) (xy 125.801308 -406.923291) (xy 125.809065 -406.977245) (xy 125.809065 -407.031753)
			(xy 127.246575 -407.031753) (xy 127.246575 -406.977247) (xy 127.254333 -406.923296) (xy 127.26969 -406.870998)
			(xy 127.292334 -406.821418) (xy 127.321803 -406.775566) (xy 127.357499 -406.734375) (xy 127.398693 -406.698683)
			(xy 127.444548 -406.669217) (xy 127.49413 -406.646578) (xy 127.546429 -406.631226) (xy 127.600381 -406.623473)
			(xy 127.627634 -406.623012) (xy 128.491234 -406.623012) (xy 128.518485 -406.62346) (xy 128.572432 -406.631221)
			(xy 128.624725 -406.64658) (xy 128.674301 -406.669224) (xy 128.720149 -406.698693) (xy 128.761338 -406.734386)
			(xy 128.797028 -406.775578) (xy 128.826492 -406.821429) (xy 128.849132 -406.871007) (xy 128.864486 -406.923301)
			(xy 128.872242 -406.977249) (xy 128.872242 -407.031749) (xy 130.309898 -407.031749) (xy 130.309898 -406.977251)
			(xy 130.317654 -406.923309) (xy 130.333007 -406.871019) (xy 130.355645 -406.821446) (xy 130.385107 -406.775599)
			(xy 130.420794 -406.734412) (xy 130.461979 -406.698722) (xy 130.507823 -406.669257) (xy 130.557395 -406.646616)
			(xy 130.609683 -406.631259) (xy 130.663625 -406.6235) (xy 130.690874 -406.623012) (xy 131.554474 -406.623012)
			(xy 131.58173 -406.623433) (xy 131.635686 -406.631187) (xy 131.68799 -406.646542) (xy 131.737576 -406.669184)
			(xy 131.783435 -406.698653) (xy 131.824633 -406.734349) (xy 131.860331 -406.775544) (xy 131.889803 -406.821401)
			(xy 131.912449 -406.870986) (xy 131.927807 -406.923288) (xy 131.935565 -406.977245) (xy 131.935565 -407.031752)
			(xy 133.373075 -407.031752) (xy 133.373075 -406.977248) (xy 133.380832 -406.923299) (xy 133.396188 -406.871002)
			(xy 133.418831 -406.821424) (xy 133.448298 -406.775573) (xy 133.483992 -406.734382) (xy 133.525184 -406.69869)
			(xy 133.571036 -406.669224) (xy 133.620616 -406.646583) (xy 133.672912 -406.631229) (xy 133.726862 -406.623474)
			(xy 133.754114 -406.623012) (xy 134.617714 -406.623012) (xy 134.644966 -406.623459) (xy 134.698915 -406.631217)
			(xy 134.751211 -406.646574) (xy 134.800789 -406.669218) (xy 134.84664 -406.698686) (xy 134.887831 -406.734379)
			(xy 134.923523 -406.775571) (xy 134.952989 -406.821423) (xy 134.97563 -406.871002) (xy 134.990986 -406.923299)
			(xy 134.998742 -406.977248) (xy 134.998742 -407.031748) (xy 136.436398 -407.031748) (xy 136.436398 -406.977252)
			(xy 136.444153 -406.923312) (xy 136.459505 -406.871023) (xy 136.482142 -406.821452) (xy 136.511602 -406.775606)
			(xy 136.547287 -406.734419) (xy 136.588469 -406.69873) (xy 136.634311 -406.669264) (xy 136.68388 -406.646621)
			(xy 136.736167 -406.631263) (xy 136.790106 -406.623501) (xy 136.817354 -406.623012) (xy 137.680954 -406.623012)
			(xy 137.70821 -406.623432) (xy 137.762169 -406.631184) (xy 137.814475 -406.646537) (xy 137.864064 -406.669178)
			(xy 137.909925 -406.698646) (xy 137.951126 -406.734342) (xy 137.986826 -406.775538) (xy 138.0163 -406.821396)
			(xy 138.038947 -406.870981) (xy 138.054306 -406.923286) (xy 138.062065 -406.977244) (xy 138.062065 -407.03175)
			(xy 139.499598 -407.03175) (xy 139.499598 -406.97725) (xy 139.507354 -406.923306) (xy 139.522708 -406.871015)
			(xy 139.545348 -406.821441) (xy 139.574812 -406.775593) (xy 139.610501 -406.734405) (xy 139.651688 -406.698715)
			(xy 139.697535 -406.669251) (xy 139.747109 -406.64661) (xy 139.7994 -406.631255) (xy 139.853344 -406.623499)
			(xy 139.880594 -406.623012) (xy 140.744194 -406.623012) (xy 140.771449 -406.623434) (xy 140.825403 -406.631191)
			(xy 140.877704 -406.646548) (xy 140.927288 -406.669191) (xy 140.973144 -406.69866) (xy 141.01434 -406.734356)
			(xy 141.050036 -406.775551) (xy 141.079506 -406.821407) (xy 141.10215 -406.87099) (xy 141.117508 -406.923291)
			(xy 141.125265 -406.977245) (xy 141.125265 -407.031753) (xy 142.562775 -407.031753) (xy 142.562775 -406.977247)
			(xy 142.570533 -406.923296) (xy 142.58589 -406.870998) (xy 142.608534 -406.821418) (xy 142.638003 -406.775566)
			(xy 142.673699 -406.734375) (xy 142.714893 -406.698683) (xy 142.760748 -406.669217) (xy 142.81033 -406.646578)
			(xy 142.862629 -406.631226) (xy 142.916581 -406.623473) (xy 142.943834 -406.623012) (xy 143.807434 -406.623012)
			(xy 143.834685 -406.62346) (xy 143.888632 -406.631221) (xy 143.940925 -406.64658) (xy 143.990501 -406.669224)
			(xy 144.036349 -406.698693) (xy 144.077538 -406.734386) (xy 144.113228 -406.775578) (xy 144.142692 -406.821429)
			(xy 144.165332 -406.871007) (xy 144.180686 -406.923301) (xy 144.188442 -406.977249) (xy 144.188442 -407.031749)
			(xy 145.626098 -407.031749) (xy 145.626098 -406.977251) (xy 145.633854 -406.923309) (xy 145.649207 -406.871019)
			(xy 145.671845 -406.821446) (xy 145.701307 -406.775599) (xy 145.736994 -406.734412) (xy 145.778179 -406.698722)
			(xy 145.824023 -406.669257) (xy 145.873595 -406.646616) (xy 145.925883 -406.631259) (xy 145.979825 -406.6235)
			(xy 146.007074 -406.623012) (xy 146.870674 -406.623012) (xy 146.89793 -406.623433) (xy 146.951886 -406.631187)
			(xy 147.00419 -406.646542) (xy 147.053776 -406.669184) (xy 147.099635 -406.698653) (xy 147.140833 -406.734349)
			(xy 147.176531 -406.775544) (xy 147.206003 -406.821401) (xy 147.228649 -406.870986) (xy 147.244007 -406.923288)
			(xy 147.251765 -406.977245) (xy 147.251765 -407.031752) (xy 148.689275 -407.031752) (xy 148.689275 -406.977248)
			(xy 148.697032 -406.923299) (xy 148.712388 -406.871002) (xy 148.735031 -406.821424) (xy 148.764498 -406.775573)
			(xy 148.800192 -406.734382) (xy 148.841384 -406.69869) (xy 148.887236 -406.669224) (xy 148.936816 -406.646583)
			(xy 148.989112 -406.631229) (xy 149.043062 -406.623474) (xy 149.070314 -406.623012) (xy 149.933914 -406.623012)
			(xy 149.961166 -406.623459) (xy 150.015115 -406.631217) (xy 150.067411 -406.646574) (xy 150.116989 -406.669218)
			(xy 150.16284 -406.698686) (xy 150.204031 -406.734379) (xy 150.239723 -406.775571) (xy 150.269189 -406.821423)
			(xy 150.29183 -406.871002) (xy 150.307186 -406.923299) (xy 150.314942 -406.977248) (xy 150.314942 -407.031748)
			(xy 151.752598 -407.031748) (xy 151.752598 -406.977252) (xy 151.760353 -406.923312) (xy 151.775705 -406.871023)
			(xy 151.798342 -406.821452) (xy 151.827802 -406.775606) (xy 151.863487 -406.734419) (xy 151.904669 -406.69873)
			(xy 151.950511 -406.669264) (xy 152.00008 -406.646621) (xy 152.052367 -406.631263) (xy 152.106306 -406.623501)
			(xy 152.133554 -406.623012) (xy 152.997154 -406.623012) (xy 153.02441 -406.623432) (xy 153.078369 -406.631184)
			(xy 153.130675 -406.646537) (xy 153.180264 -406.669178) (xy 153.226125 -406.698646) (xy 153.267326 -406.734342)
			(xy 153.303026 -406.775538) (xy 153.3325 -406.821396) (xy 153.355147 -406.870981) (xy 153.370506 -406.923286)
			(xy 153.378265 -406.977244) (xy 153.378265 -407.03175) (xy 154.815798 -407.03175) (xy 154.815798 -406.97725)
			(xy 154.823554 -406.923306) (xy 154.838908 -406.871015) (xy 154.861548 -406.821441) (xy 154.891012 -406.775593)
			(xy 154.926701 -406.734405) (xy 154.967888 -406.698715) (xy 155.013735 -406.669251) (xy 155.063309 -406.64661)
			(xy 155.1156 -406.631255) (xy 155.169544 -406.623499) (xy 155.196794 -406.623012) (xy 156.060394 -406.623012)
			(xy 156.087649 -406.623434) (xy 156.141603 -406.631191) (xy 156.193904 -406.646548) (xy 156.243488 -406.669191)
			(xy 156.289344 -406.69866) (xy 156.33054 -406.734356) (xy 156.366236 -406.775551) (xy 156.395706 -406.821407)
			(xy 156.41835 -406.87099) (xy 156.433708 -406.923291) (xy 156.441465 -406.977245) (xy 156.441465 -407.031753)
			(xy 157.878975 -407.031753) (xy 157.878975 -406.977247) (xy 157.886733 -406.923296) (xy 157.90209 -406.870998)
			(xy 157.924734 -406.821418) (xy 157.954203 -406.775566) (xy 157.989899 -406.734375) (xy 158.031093 -406.698683)
			(xy 158.076948 -406.669217) (xy 158.12653 -406.646578) (xy 158.178829 -406.631226) (xy 158.232781 -406.623473)
			(xy 158.260034 -406.623012) (xy 159.123634 -406.623012) (xy 159.150885 -406.62346) (xy 159.204832 -406.631221)
			(xy 159.257125 -406.64658) (xy 159.306701 -406.669224) (xy 159.352549 -406.698693) (xy 159.393738 -406.734386)
			(xy 159.429428 -406.775578) (xy 159.458892 -406.821429) (xy 159.481532 -406.871007) (xy 159.496886 -406.923301)
			(xy 159.504642 -406.977249) (xy 159.504642 -407.031749) (xy 160.942298 -407.031749) (xy 160.942298 -406.977251)
			(xy 160.950054 -406.923309) (xy 160.965407 -406.871019) (xy 160.988045 -406.821446) (xy 161.017507 -406.775599)
			(xy 161.053194 -406.734412) (xy 161.094379 -406.698722) (xy 161.140223 -406.669257) (xy 161.189795 -406.646616)
			(xy 161.242083 -406.631259) (xy 161.296025 -406.6235) (xy 161.323274 -406.623012) (xy 162.186874 -406.623012)
			(xy 162.21413 -406.623433) (xy 162.268086 -406.631187) (xy 162.32039 -406.646542) (xy 162.369976 -406.669184)
			(xy 162.415835 -406.698653) (xy 162.457033 -406.734349) (xy 162.492731 -406.775544) (xy 162.522203 -406.821401)
			(xy 162.544849 -406.870986) (xy 162.560207 -406.923288) (xy 162.567965 -406.977245) (xy 162.567965 -407.031752)
			(xy 164.005475 -407.031752) (xy 164.005475 -406.977248) (xy 164.013232 -406.923299) (xy 164.028588 -406.871002)
			(xy 164.051231 -406.821424) (xy 164.080698 -406.775573) (xy 164.116392 -406.734382) (xy 164.157584 -406.69869)
			(xy 164.203436 -406.669224) (xy 164.253016 -406.646583) (xy 164.305312 -406.631229) (xy 164.359262 -406.623474)
			(xy 164.386514 -406.623012) (xy 165.250114 -406.623012) (xy 165.277366 -406.623459) (xy 165.331315 -406.631217)
			(xy 165.383611 -406.646574) (xy 165.433189 -406.669218) (xy 165.47904 -406.698686) (xy 165.520231 -406.734379)
			(xy 165.555923 -406.775571) (xy 165.585389 -406.821423) (xy 165.60803 -406.871002) (xy 165.623386 -406.923299)
			(xy 165.631142 -406.977248) (xy 165.631142 -407.031748) (xy 167.068798 -407.031748) (xy 167.068798 -406.977252)
			(xy 167.076553 -406.923312) (xy 167.091905 -406.871023) (xy 167.114542 -406.821452) (xy 167.144002 -406.775606)
			(xy 167.179687 -406.734419) (xy 167.220869 -406.69873) (xy 167.266711 -406.669264) (xy 167.31628 -406.646621)
			(xy 167.368567 -406.631263) (xy 167.422506 -406.623501) (xy 167.449754 -406.623012) (xy 168.313354 -406.623012)
			(xy 168.34061 -406.623432) (xy 168.394569 -406.631184) (xy 168.446875 -406.646537) (xy 168.496464 -406.669178)
			(xy 168.542325 -406.698646) (xy 168.583526 -406.734342) (xy 168.619226 -406.775538) (xy 168.6487 -406.821396)
			(xy 168.671347 -406.870981) (xy 168.686706 -406.923286) (xy 168.694465 -406.977244) (xy 168.694465 -407.031756)
			(xy 168.686706 -407.085714) (xy 168.671347 -407.138019) (xy 168.6487 -407.187604) (xy 168.619226 -407.233462)
			(xy 168.583526 -407.274658) (xy 168.542325 -407.310354) (xy 168.496464 -407.339822) (xy 168.446875 -407.362463)
			(xy 168.394569 -407.377816) (xy 168.34061 -407.385568) (xy 168.313354 -407.386028) (xy 167.449754 -407.386028)
			(xy 167.422506 -407.385499) (xy 167.368567 -407.377737) (xy 167.31628 -407.362379) (xy 167.266711 -407.339736)
			(xy 167.220869 -407.31027) (xy 167.179687 -407.274581) (xy 167.144002 -407.233394) (xy 167.114542 -407.187548)
			(xy 167.091905 -407.137977) (xy 167.076553 -407.085688) (xy 167.068798 -407.031748) (xy 165.631142 -407.031748)
			(xy 165.631142 -407.031752) (xy 165.623386 -407.085701) (xy 165.60803 -407.137998) (xy 165.585389 -407.187577)
			(xy 165.555923 -407.233429) (xy 165.520231 -407.274621) (xy 165.47904 -407.310314) (xy 165.433189 -407.339782)
			(xy 165.383611 -407.362426) (xy 165.331315 -407.377783) (xy 165.277366 -407.385541) (xy 165.250114 -407.386028)
			(xy 164.386514 -407.386028) (xy 164.359262 -407.385526) (xy 164.305312 -407.377771) (xy 164.253016 -407.362417)
			(xy 164.203436 -407.339776) (xy 164.157584 -407.31031) (xy 164.116392 -407.274618) (xy 164.080698 -407.233427)
			(xy 164.051231 -407.187576) (xy 164.028588 -407.137998) (xy 164.013232 -407.085701) (xy 164.005475 -407.031752)
			(xy 162.567965 -407.031752) (xy 162.567965 -407.031755) (xy 162.560207 -407.085712) (xy 162.544849 -407.138014)
			(xy 162.522203 -407.187599) (xy 162.492731 -407.233456) (xy 162.457033 -407.274651) (xy 162.415835 -407.310347)
			(xy 162.369976 -407.339816) (xy 162.32039 -407.362458) (xy 162.268086 -407.377813) (xy 162.21413 -407.385567)
			(xy 162.186874 -407.386028) (xy 161.323274 -407.386028) (xy 161.296025 -407.3855) (xy 161.242083 -407.377741)
			(xy 161.189795 -407.362384) (xy 161.140223 -407.339743) (xy 161.094379 -407.310278) (xy 161.053194 -407.274588)
			(xy 161.017507 -407.233401) (xy 160.988045 -407.187554) (xy 160.965407 -407.137981) (xy 160.950054 -407.085691)
			(xy 160.942298 -407.031749) (xy 159.504642 -407.031749) (xy 159.504642 -407.031751) (xy 159.496886 -407.085699)
			(xy 159.481532 -407.137993) (xy 159.458892 -407.187571) (xy 159.429428 -407.233422) (xy 159.393738 -407.274614)
			(xy 159.352549 -407.310307) (xy 159.306701 -407.339776) (xy 159.257125 -407.36242) (xy 159.204832 -407.377779)
			(xy 159.150885 -407.38554) (xy 159.123634 -407.386028) (xy 158.260034 -407.386028) (xy 158.232781 -407.385527)
			(xy 158.178829 -407.377774) (xy 158.12653 -407.362422) (xy 158.076948 -407.339783) (xy 158.031093 -407.310317)
			(xy 157.989899 -407.274625) (xy 157.954203 -407.233434) (xy 157.924734 -407.187582) (xy 157.90209 -407.138002)
			(xy 157.886733 -407.085704) (xy 157.878975 -407.031753) (xy 156.441465 -407.031753) (xy 156.441465 -407.031755)
			(xy 156.433708 -407.085709) (xy 156.41835 -407.13801) (xy 156.395706 -407.187593) (xy 156.366236 -407.233449)
			(xy 156.33054 -407.274644) (xy 156.289344 -407.31034) (xy 156.243488 -407.339809) (xy 156.193904 -407.362452)
			(xy 156.141603 -407.377809) (xy 156.087649 -407.385566) (xy 156.060394 -407.386028) (xy 155.196794 -407.386028)
			(xy 155.169544 -407.385501) (xy 155.1156 -407.377745) (xy 155.063309 -407.36239) (xy 155.013735 -407.339749)
			(xy 154.967888 -407.310285) (xy 154.926701 -407.274595) (xy 154.891012 -407.233407) (xy 154.861548 -407.187559)
			(xy 154.838908 -407.137985) (xy 154.823554 -407.085694) (xy 154.815798 -407.03175) (xy 153.378265 -407.03175)
			(xy 153.378265 -407.031756) (xy 153.370506 -407.085714) (xy 153.355147 -407.138019) (xy 153.3325 -407.187604)
			(xy 153.303026 -407.233462) (xy 153.267326 -407.274658) (xy 153.226125 -407.310354) (xy 153.180264 -407.339822)
			(xy 153.130675 -407.362463) (xy 153.078369 -407.377816) (xy 153.02441 -407.385568) (xy 152.997154 -407.386028)
			(xy 152.133554 -407.386028) (xy 152.106306 -407.385499) (xy 152.052367 -407.377737) (xy 152.00008 -407.362379)
			(xy 151.950511 -407.339736) (xy 151.904669 -407.31027) (xy 151.863487 -407.274581) (xy 151.827802 -407.233394)
			(xy 151.798342 -407.187548) (xy 151.775705 -407.137977) (xy 151.760353 -407.085688) (xy 151.752598 -407.031748)
			(xy 150.314942 -407.031748) (xy 150.314942 -407.031752) (xy 150.307186 -407.085701) (xy 150.29183 -407.137998)
			(xy 150.269189 -407.187577) (xy 150.239723 -407.233429) (xy 150.204031 -407.274621) (xy 150.16284 -407.310314)
			(xy 150.116989 -407.339782) (xy 150.067411 -407.362426) (xy 150.015115 -407.377783) (xy 149.961166 -407.385541)
			(xy 149.933914 -407.386028) (xy 149.070314 -407.386028) (xy 149.043062 -407.385526) (xy 148.989112 -407.377771)
			(xy 148.936816 -407.362417) (xy 148.887236 -407.339776) (xy 148.841384 -407.31031) (xy 148.800192 -407.274618)
			(xy 148.764498 -407.233427) (xy 148.735031 -407.187576) (xy 148.712388 -407.137998) (xy 148.697032 -407.085701)
			(xy 148.689275 -407.031752) (xy 147.251765 -407.031752) (xy 147.251765 -407.031755) (xy 147.244007 -407.085712)
			(xy 147.228649 -407.138014) (xy 147.206003 -407.187599) (xy 147.176531 -407.233456) (xy 147.140833 -407.274651)
			(xy 147.099635 -407.310347) (xy 147.053776 -407.339816) (xy 147.00419 -407.362458) (xy 146.951886 -407.377813)
			(xy 146.89793 -407.385567) (xy 146.870674 -407.386028) (xy 146.007074 -407.386028) (xy 145.979825 -407.3855)
			(xy 145.925883 -407.377741) (xy 145.873595 -407.362384) (xy 145.824023 -407.339743) (xy 145.778179 -407.310278)
			(xy 145.736994 -407.274588) (xy 145.701307 -407.233401) (xy 145.671845 -407.187554) (xy 145.649207 -407.137981)
			(xy 145.633854 -407.085691) (xy 145.626098 -407.031749) (xy 144.188442 -407.031749) (xy 144.188442 -407.031751)
			(xy 144.180686 -407.085699) (xy 144.165332 -407.137993) (xy 144.142692 -407.187571) (xy 144.113228 -407.233422)
			(xy 144.077538 -407.274614) (xy 144.036349 -407.310307) (xy 143.990501 -407.339776) (xy 143.940925 -407.36242)
			(xy 143.888632 -407.377779) (xy 143.834685 -407.38554) (xy 143.807434 -407.386028) (xy 142.943834 -407.386028)
			(xy 142.916581 -407.385527) (xy 142.862629 -407.377774) (xy 142.81033 -407.362422) (xy 142.760748 -407.339783)
			(xy 142.714893 -407.310317) (xy 142.673699 -407.274625) (xy 142.638003 -407.233434) (xy 142.608534 -407.187582)
			(xy 142.58589 -407.138002) (xy 142.570533 -407.085704) (xy 142.562775 -407.031753) (xy 141.125265 -407.031753)
			(xy 141.125265 -407.031755) (xy 141.117508 -407.085709) (xy 141.10215 -407.13801) (xy 141.079506 -407.187593)
			(xy 141.050036 -407.233449) (xy 141.01434 -407.274644) (xy 140.973144 -407.31034) (xy 140.927288 -407.339809)
			(xy 140.877704 -407.362452) (xy 140.825403 -407.377809) (xy 140.771449 -407.385566) (xy 140.744194 -407.386028)
			(xy 139.880594 -407.386028) (xy 139.853344 -407.385501) (xy 139.7994 -407.377745) (xy 139.747109 -407.36239)
			(xy 139.697535 -407.339749) (xy 139.651688 -407.310285) (xy 139.610501 -407.274595) (xy 139.574812 -407.233407)
			(xy 139.545348 -407.187559) (xy 139.522708 -407.137985) (xy 139.507354 -407.085694) (xy 139.499598 -407.03175)
			(xy 138.062065 -407.03175) (xy 138.062065 -407.031756) (xy 138.054306 -407.085714) (xy 138.038947 -407.138019)
			(xy 138.0163 -407.187604) (xy 137.986826 -407.233462) (xy 137.951126 -407.274658) (xy 137.909925 -407.310354)
			(xy 137.864064 -407.339822) (xy 137.814475 -407.362463) (xy 137.762169 -407.377816) (xy 137.70821 -407.385568)
			(xy 137.680954 -407.386028) (xy 136.817354 -407.386028) (xy 136.790106 -407.385499) (xy 136.736167 -407.377737)
			(xy 136.68388 -407.362379) (xy 136.634311 -407.339736) (xy 136.588469 -407.31027) (xy 136.547287 -407.274581)
			(xy 136.511602 -407.233394) (xy 136.482142 -407.187548) (xy 136.459505 -407.137977) (xy 136.444153 -407.085688)
			(xy 136.436398 -407.031748) (xy 134.998742 -407.031748) (xy 134.998742 -407.031752) (xy 134.990986 -407.085701)
			(xy 134.97563 -407.137998) (xy 134.952989 -407.187577) (xy 134.923523 -407.233429) (xy 134.887831 -407.274621)
			(xy 134.84664 -407.310314) (xy 134.800789 -407.339782) (xy 134.751211 -407.362426) (xy 134.698915 -407.377783)
			(xy 134.644966 -407.385541) (xy 134.617714 -407.386028) (xy 133.754114 -407.386028) (xy 133.726862 -407.385526)
			(xy 133.672912 -407.377771) (xy 133.620616 -407.362417) (xy 133.571036 -407.339776) (xy 133.525184 -407.31031)
			(xy 133.483992 -407.274618) (xy 133.448298 -407.233427) (xy 133.418831 -407.187576) (xy 133.396188 -407.137998)
			(xy 133.380832 -407.085701) (xy 133.373075 -407.031752) (xy 131.935565 -407.031752) (xy 131.935565 -407.031755)
			(xy 131.927807 -407.085712) (xy 131.912449 -407.138014) (xy 131.889803 -407.187599) (xy 131.860331 -407.233456)
			(xy 131.824633 -407.274651) (xy 131.783435 -407.310347) (xy 131.737576 -407.339816) (xy 131.68799 -407.362458)
			(xy 131.635686 -407.377813) (xy 131.58173 -407.385567) (xy 131.554474 -407.386028) (xy 130.690874 -407.386028)
			(xy 130.663625 -407.3855) (xy 130.609683 -407.377741) (xy 130.557395 -407.362384) (xy 130.507823 -407.339743)
			(xy 130.461979 -407.310278) (xy 130.420794 -407.274588) (xy 130.385107 -407.233401) (xy 130.355645 -407.187554)
			(xy 130.333007 -407.137981) (xy 130.317654 -407.085691) (xy 130.309898 -407.031749) (xy 128.872242 -407.031749)
			(xy 128.872242 -407.031751) (xy 128.864486 -407.085699) (xy 128.849132 -407.137993) (xy 128.826492 -407.187571)
			(xy 128.797028 -407.233422) (xy 128.761338 -407.274614) (xy 128.720149 -407.310307) (xy 128.674301 -407.339776)
			(xy 128.624725 -407.36242) (xy 128.572432 -407.377779) (xy 128.518485 -407.38554) (xy 128.491234 -407.386028)
			(xy 127.627634 -407.386028) (xy 127.600381 -407.385527) (xy 127.546429 -407.377774) (xy 127.49413 -407.362422)
			(xy 127.444548 -407.339783) (xy 127.398693 -407.310317) (xy 127.357499 -407.274625) (xy 127.321803 -407.233434)
			(xy 127.292334 -407.187582) (xy 127.26969 -407.138002) (xy 127.254333 -407.085704) (xy 127.246575 -407.031753)
			(xy 125.809065 -407.031753) (xy 125.809065 -407.031755) (xy 125.801308 -407.085709) (xy 125.78595 -407.13801)
			(xy 125.763306 -407.187593) (xy 125.733836 -407.233449) (xy 125.69814 -407.274644) (xy 125.656944 -407.31034)
			(xy 125.611088 -407.339809) (xy 125.561504 -407.362452) (xy 125.509203 -407.377809) (xy 125.455249 -407.385566)
			(xy 125.427994 -407.386028) (xy 124.564394 -407.386028) (xy 124.537144 -407.385501) (xy 124.4832 -407.377745)
			(xy 124.430909 -407.36239) (xy 124.381335 -407.339749) (xy 124.335488 -407.310285) (xy 124.294301 -407.274595)
			(xy 124.258612 -407.233407) (xy 124.229148 -407.187559) (xy 124.206508 -407.137985) (xy 124.191154 -407.085694)
			(xy 124.183398 -407.03175) (xy 122.745865 -407.03175) (xy 122.745865 -407.031756) (xy 122.738106 -407.085714)
			(xy 122.722747 -407.138019) (xy 122.7001 -407.187604) (xy 122.670626 -407.233462) (xy 122.634926 -407.274658)
			(xy 122.593725 -407.310354) (xy 122.547864 -407.339822) (xy 122.498275 -407.362463) (xy 122.445969 -407.377816)
			(xy 122.39201 -407.385568) (xy 122.364754 -407.386028) (xy 121.501154 -407.386028) (xy 121.473906 -407.385499)
			(xy 121.419967 -407.377737) (xy 121.36768 -407.362379) (xy 121.318111 -407.339736) (xy 121.272269 -407.31027)
			(xy 121.231087 -407.274581) (xy 121.195402 -407.233394) (xy 121.165942 -407.187548) (xy 121.143305 -407.137977)
			(xy 121.127953 -407.085688) (xy 121.120198 -407.031748) (xy 107.861153 -407.031748) (xy 107.86873 -407.084449)
			(xy 107.86873 -407.138951) (xy 107.860974 -407.192898) (xy 107.84562 -407.245192) (xy 107.822979 -407.294769)
			(xy 107.793514 -407.34062) (xy 107.757824 -407.38181) (xy 107.716636 -407.417502) (xy 107.670787 -407.44697)
			(xy 107.621211 -407.469613) (xy 107.568918 -407.48497) (xy 107.514971 -407.492729) (xy 107.48772 -407.493216)
			(xy 106.62412 -407.493216) (xy 106.596867 -407.492738) (xy 106.542915 -407.484984) (xy 106.490616 -407.46963)
			(xy 106.441034 -407.446989) (xy 106.395179 -407.417522) (xy 106.353985 -407.381829) (xy 106.31829 -407.340637)
			(xy 106.288821 -407.294783) (xy 106.266177 -407.245203) (xy 106.250821 -407.192905) (xy 106.243063 -407.138953)
			(xy 96.495694 -407.138953) (xy 96.473493 -407.18757) (xy 96.444028 -407.233421) (xy 96.408339 -407.274612)
			(xy 96.367151 -407.310306) (xy 96.321303 -407.339775) (xy 96.271728 -407.362419) (xy 96.219435 -407.377778)
			(xy 96.165489 -407.38554) (xy 96.138238 -407.386028) (xy 95.274638 -407.386028) (xy 95.247385 -407.385527)
			(xy 95.193433 -407.377775) (xy 95.141133 -407.362423) (xy 95.091551 -407.339784) (xy 95.045695 -407.310319)
			(xy 95.0045 -407.274627) (xy 94.968804 -407.233435) (xy 94.939334 -407.187583) (xy 94.91669 -407.138003)
			(xy 94.901333 -407.085705) (xy 94.893575 -407.031753) (xy 93.456065 -407.031753) (xy 93.456065 -407.031754)
			(xy 93.448308 -407.085708) (xy 93.432951 -407.138009) (xy 93.410307 -407.187592) (xy 93.380837 -407.233448)
			(xy 93.345141 -407.274643) (xy 93.303946 -407.310338) (xy 93.25809 -407.339808) (xy 93.208507 -407.362451)
			(xy 93.156206 -407.377808) (xy 93.102252 -407.385565) (xy 93.074998 -407.386028) (xy 92.211398 -407.386028)
			(xy 92.184148 -407.385502) (xy 92.130204 -407.377745) (xy 92.077912 -407.362391) (xy 92.028338 -407.339751)
			(xy 91.98249 -407.310286) (xy 91.941302 -407.274596) (xy 91.905613 -407.233408) (xy 91.876148 -407.187561)
			(xy 91.853508 -407.137986) (xy 91.838154 -407.085694) (xy 91.830398 -407.03175) (xy 90.392865 -407.03175)
			(xy 90.392865 -407.031756) (xy 90.385107 -407.085714) (xy 90.369748 -407.138018) (xy 90.347101 -407.187603)
			(xy 90.317627 -407.233461) (xy 90.281927 -407.274657) (xy 90.240727 -407.310352) (xy 90.194866 -407.339821)
			(xy 90.145278 -407.362462) (xy 90.092973 -407.377815) (xy 90.039014 -407.385568) (xy 90.011758 -407.386028)
			(xy 89.148158 -407.386028) (xy 89.12091 -407.385499) (xy 89.06697 -407.377738) (xy 89.014683 -407.36238)
			(xy 88.965114 -407.339738) (xy 88.919271 -407.310272) (xy 88.878088 -407.274582) (xy 88.842403 -407.233395)
			(xy 88.812942 -407.187549) (xy 88.790305 -407.137978) (xy 88.774953 -407.085689) (xy 88.767198 -407.031748)
			(xy 87.329542 -407.031748) (xy 87.329542 -407.031752) (xy 87.321786 -407.085701) (xy 87.306431 -407.137997)
			(xy 87.28379 -407.187576) (xy 87.254324 -407.233427) (xy 87.218632 -407.274619) (xy 87.177442 -407.310313)
			(xy 87.131591 -407.339781) (xy 87.082014 -407.362424) (xy 87.029718 -407.377782) (xy 86.97577 -407.385541)
			(xy 86.948518 -407.386028) (xy 86.084918 -407.386028) (xy 86.057666 -407.385526) (xy 86.003716 -407.377771)
			(xy 85.951418 -407.362418) (xy 85.901839 -407.339778) (xy 85.855986 -407.310312) (xy 85.814793 -407.27462)
			(xy 85.779099 -407.233429) (xy 85.749631 -407.187577) (xy 85.726989 -407.137998) (xy 85.711632 -407.085702)
			(xy 85.703875 -407.031752) (xy 84.266365 -407.031752) (xy 84.266365 -407.031755) (xy 84.258607 -407.085711)
			(xy 84.243249 -407.138013) (xy 84.220604 -407.187598) (xy 84.191132 -407.233454) (xy 84.155434 -407.27465)
			(xy 84.114237 -407.310345) (xy 84.068378 -407.339814) (xy 84.018793 -407.362457) (xy 83.96649 -407.377812)
			(xy 83.912533 -407.385567) (xy 83.885278 -407.386028) (xy 83.021678 -407.386028) (xy 82.994429 -407.3855)
			(xy 82.940487 -407.377742) (xy 82.888197 -407.362385) (xy 82.838626 -407.339744) (xy 82.79278 -407.310279)
			(xy 82.751595 -407.274589) (xy 82.715908 -407.233402) (xy 82.686445 -407.187555) (xy 82.663807 -407.137982)
			(xy 82.648454 -407.085692) (xy 82.640698 -407.031749) (xy 81.203042 -407.031749) (xy 81.203042 -407.031751)
			(xy 81.195286 -407.085698) (xy 81.179932 -407.137993) (xy 81.157293 -407.18757) (xy 81.127828 -407.233421)
			(xy 81.092139 -407.274612) (xy 81.050951 -407.310306) (xy 81.005103 -407.339775) (xy 80.955528 -407.362419)
			(xy 80.903235 -407.377778) (xy 80.849289 -407.38554) (xy 80.822038 -407.386028) (xy 79.958438 -407.386028)
			(xy 79.931185 -407.385527) (xy 79.877233 -407.377775) (xy 79.824933 -407.362423) (xy 79.775351 -407.339784)
			(xy 79.729495 -407.310319) (xy 79.6883 -407.274627) (xy 79.652604 -407.233435) (xy 79.623134 -407.187583)
			(xy 79.60049 -407.138003) (xy 79.585133 -407.085705) (xy 79.577375 -407.031753) (xy 78.139865 -407.031753)
			(xy 78.139865 -407.031754) (xy 78.132108 -407.085708) (xy 78.116751 -407.138009) (xy 78.094107 -407.187592)
			(xy 78.064637 -407.233448) (xy 78.028941 -407.274643) (xy 77.987746 -407.310338) (xy 77.94189 -407.339808)
			(xy 77.892307 -407.362451) (xy 77.840006 -407.377808) (xy 77.786052 -407.385565) (xy 77.758798 -407.386028)
			(xy 76.895198 -407.386028) (xy 76.867948 -407.385502) (xy 76.814004 -407.377745) (xy 76.761712 -407.362391)
			(xy 76.712138 -407.339751) (xy 76.66629 -407.310286) (xy 76.625102 -407.274596) (xy 76.589413 -407.233408)
			(xy 76.559948 -407.187561) (xy 76.537308 -407.137986) (xy 76.521954 -407.085694) (xy 76.514198 -407.03175)
			(xy 75.076665 -407.03175) (xy 75.076665 -407.031756) (xy 75.068907 -407.085714) (xy 75.053548 -407.138018)
			(xy 75.030901 -407.187603) (xy 75.001427 -407.233461) (xy 74.965727 -407.274657) (xy 74.924527 -407.310352)
			(xy 74.878666 -407.339821) (xy 74.829078 -407.362462) (xy 74.776773 -407.377815) (xy 74.722814 -407.385568)
			(xy 74.695558 -407.386028) (xy 73.831958 -407.386028) (xy 73.80471 -407.385499) (xy 73.75077 -407.377738)
			(xy 73.698483 -407.36238) (xy 73.648914 -407.339738) (xy 73.603071 -407.310272) (xy 73.561888 -407.274582)
			(xy 73.526203 -407.233395) (xy 73.496742 -407.187549) (xy 73.474105 -407.137978) (xy 73.458753 -407.085689)
			(xy 73.450998 -407.031748) (xy 72.013342 -407.031748) (xy 72.013342 -407.031752) (xy 72.005586 -407.085701)
			(xy 71.990231 -407.137997) (xy 71.96759 -407.187576) (xy 71.938124 -407.233427) (xy 71.902432 -407.274619)
			(xy 71.861242 -407.310313) (xy 71.815391 -407.339781) (xy 71.765814 -407.362424) (xy 71.713518 -407.377782)
			(xy 71.65957 -407.385541) (xy 71.632318 -407.386028) (xy 70.768718 -407.386028) (xy 70.741466 -407.385526)
			(xy 70.687516 -407.377771) (xy 70.635218 -407.362418) (xy 70.585639 -407.339778) (xy 70.539786 -407.310312)
			(xy 70.498593 -407.27462) (xy 70.462899 -407.233429) (xy 70.433431 -407.187577) (xy 70.410789 -407.137998)
			(xy 70.395432 -407.085702) (xy 70.387675 -407.031752) (xy 68.950165 -407.031752) (xy 68.950165 -407.031755)
			(xy 68.942407 -407.085711) (xy 68.927049 -407.138013) (xy 68.904404 -407.187598) (xy 68.874932 -407.233454)
			(xy 68.839234 -407.27465) (xy 68.798037 -407.310345) (xy 68.752178 -407.339814) (xy 68.702593 -407.362457)
			(xy 68.65029 -407.377812) (xy 68.596333 -407.385567) (xy 68.569078 -407.386028) (xy 67.705478 -407.386028)
			(xy 67.678229 -407.3855) (xy 67.624287 -407.377742) (xy 67.571997 -407.362385) (xy 67.522426 -407.339744)
			(xy 67.47658 -407.310279) (xy 67.435395 -407.274589) (xy 67.399708 -407.233402) (xy 67.370245 -407.187555)
			(xy 67.347607 -407.137982) (xy 67.332254 -407.085692) (xy 67.324498 -407.031749) (xy 65.886842 -407.031749)
			(xy 65.886842 -407.031751) (xy 65.879086 -407.085698) (xy 65.863732 -407.137993) (xy 65.841093 -407.18757)
			(xy 65.811628 -407.233421) (xy 65.775939 -407.274612) (xy 65.734751 -407.310306) (xy 65.688903 -407.339775)
			(xy 65.639328 -407.362419) (xy 65.587035 -407.377778) (xy 65.533089 -407.38554) (xy 65.505838 -407.386028)
			(xy 64.642238 -407.386028) (xy 64.614985 -407.385527) (xy 64.561033 -407.377775) (xy 64.508733 -407.362423)
			(xy 64.459151 -407.339784) (xy 64.413295 -407.310319) (xy 64.3721 -407.274627) (xy 64.336404 -407.233435)
			(xy 64.306934 -407.187583) (xy 64.28429 -407.138003) (xy 64.268933 -407.085705) (xy 64.261175 -407.031753)
			(xy 62.823665 -407.031753) (xy 62.823665 -407.031754) (xy 62.815908 -407.085708) (xy 62.800551 -407.138009)
			(xy 62.777907 -407.187592) (xy 62.748437 -407.233448) (xy 62.712741 -407.274643) (xy 62.671546 -407.310338)
			(xy 62.62569 -407.339808) (xy 62.576107 -407.362451) (xy 62.523806 -407.377808) (xy 62.469852 -407.385565)
			(xy 62.442598 -407.386028) (xy 61.578998 -407.386028) (xy 61.551748 -407.385502) (xy 61.497804 -407.377745)
			(xy 61.445512 -407.362391) (xy 61.395938 -407.339751) (xy 61.35009 -407.310286) (xy 61.308902 -407.274596)
			(xy 61.273213 -407.233408) (xy 61.243748 -407.187561) (xy 61.221108 -407.137986) (xy 61.205754 -407.085694)
			(xy 61.197998 -407.03175) (xy 59.760465 -407.03175) (xy 59.760465 -407.031756) (xy 59.752707 -407.085714)
			(xy 59.737348 -407.138018) (xy 59.714701 -407.187603) (xy 59.685227 -407.233461) (xy 59.649527 -407.274657)
			(xy 59.608327 -407.310352) (xy 59.562466 -407.339821) (xy 59.512878 -407.362462) (xy 59.460573 -407.377815)
			(xy 59.406614 -407.385568) (xy 59.379358 -407.386028) (xy 58.515758 -407.386028) (xy 58.48851 -407.385499)
			(xy 58.43457 -407.377738) (xy 58.382283 -407.36238) (xy 58.332714 -407.339738) (xy 58.286871 -407.310272)
			(xy 58.245688 -407.274582) (xy 58.210003 -407.233395) (xy 58.180542 -407.187549) (xy 58.157905 -407.137978)
			(xy 58.142553 -407.085689) (xy 58.134798 -407.031748) (xy 56.697142 -407.031748) (xy 56.697142 -407.031752)
			(xy 56.689386 -407.085701) (xy 56.674031 -407.137997) (xy 56.65139 -407.187576) (xy 56.621924 -407.233427)
			(xy 56.586232 -407.274619) (xy 56.545042 -407.310313) (xy 56.499191 -407.339781) (xy 56.449614 -407.362424)
			(xy 56.397318 -407.377782) (xy 56.34337 -407.385541) (xy 56.316118 -407.386028) (xy 55.452518 -407.386028)
			(xy 55.425266 -407.385526) (xy 55.371316 -407.377771) (xy 55.319018 -407.362418) (xy 55.269439 -407.339778)
			(xy 55.223586 -407.310312) (xy 55.182393 -407.27462) (xy 55.146699 -407.233429) (xy 55.117231 -407.187577)
			(xy 55.094589 -407.137998) (xy 55.079232 -407.085702) (xy 55.071475 -407.031752) (xy 53.633965 -407.031752)
			(xy 53.633965 -407.031755) (xy 53.626207 -407.085711) (xy 53.610849 -407.138013) (xy 53.588204 -407.187598)
			(xy 53.558732 -407.233454) (xy 53.523034 -407.27465) (xy 53.481837 -407.310345) (xy 53.435978 -407.339814)
			(xy 53.386393 -407.362457) (xy 53.33409 -407.377812) (xy 53.280133 -407.385567) (xy 53.252878 -407.386028)
			(xy 52.389278 -407.386028) (xy 52.362029 -407.3855) (xy 52.308087 -407.377742) (xy 52.255797 -407.362385)
			(xy 52.206226 -407.339744) (xy 52.16038 -407.310279) (xy 52.119195 -407.274589) (xy 52.083508 -407.233402)
			(xy 52.054045 -407.187555) (xy 52.031407 -407.137982) (xy 52.016054 -407.085692) (xy 52.008298 -407.031749)
			(xy 50.570642 -407.031749) (xy 50.570642 -407.031751) (xy 50.562886 -407.085698) (xy 50.547532 -407.137993)
			(xy 50.524893 -407.18757) (xy 50.495428 -407.233421) (xy 50.459739 -407.274612) (xy 50.418551 -407.310306)
			(xy 50.372703 -407.339775) (xy 50.323128 -407.362419) (xy 50.270835 -407.377778) (xy 50.216889 -407.38554)
			(xy 50.189638 -407.386028) (xy 49.326038 -407.386028) (xy 49.298785 -407.385527) (xy 49.244833 -407.377775)
			(xy 49.192533 -407.362423) (xy 49.142951 -407.339784) (xy 49.097095 -407.310319) (xy 49.0559 -407.274627)
			(xy 49.020204 -407.233435) (xy 48.990734 -407.187583) (xy 48.96809 -407.138003) (xy 48.952733 -407.085705)
			(xy 48.944975 -407.031753) (xy 16.741648 -407.031753) (xy 16.741648 -407.035508) (xy 16.741162 -407.062759)
			(xy 16.733406 -407.116707) (xy 16.718051 -407.169002) (xy 16.695409 -407.218579) (xy 16.665943 -407.264429)
			(xy 16.630252 -407.30562) (xy 16.589061 -407.341311) (xy 16.543211 -407.370777) (xy 16.493634 -407.393419)
			(xy 16.441339 -407.408774) (xy 16.387391 -407.41653) (xy 16.332889 -407.41653) (xy 16.278941 -407.408774)
			(xy 16.226646 -407.393419) (xy 16.177069 -407.370777) (xy 16.131219 -407.341311) (xy 16.090028 -407.30562)
			(xy 16.054337 -407.264429) (xy 16.024871 -407.218579) (xy 16.002229 -407.169002) (xy 15.986874 -407.116707)
			(xy 15.979118 -407.062759) (xy 15.978632 -407.035508) (xy 6.990842 -407.035508) (xy 6.992366 -407.037032)
			(xy 7.053122 -407.098555) (xy 7.169238 -407.226701) (xy 7.278928 -407.360388) (xy 7.381928 -407.499295)
			(xy 7.477991 -407.643088) (xy 7.566884 -407.791419) (xy 7.648395 -407.943932) (xy 7.722326 -408.10026)
			(xy 7.7885 -408.260026) (xy 7.846758 -408.422846) (xy 7.896958 -408.588328) (xy 7.938981 -408.756072)
			(xy 7.972725 -408.925677) (xy 7.998109 -409.096732) (xy 8.015072 -409.268826) (xy 8.023573 -409.441546)
			(xy 8.024114 -409.52801) (xy 8.024114 -410.057457) (xy 48.944923 -410.057457) (xy 48.944923 -410.002943)
			(xy 48.952682 -409.948984) (xy 48.968041 -409.896679) (xy 48.990688 -409.847092) (xy 49.020162 -409.801233)
			(xy 49.055863 -409.760036) (xy 49.097064 -409.724339) (xy 49.142925 -409.69487) (xy 49.192515 -409.672228)
			(xy 49.244821 -409.656874) (xy 49.298781 -409.64912) (xy 49.326038 -409.64866) (xy 50.189638 -409.64866)
			(xy 50.216885 -409.649213) (xy 50.270824 -409.656973) (xy 50.32311 -409.67233) (xy 50.372678 -409.694972)
			(xy 50.41852 -409.724436) (xy 50.459702 -409.760125) (xy 50.495386 -409.801311) (xy 50.524847 -409.847155)
			(xy 50.547483 -409.896726) (xy 50.562835 -409.949013) (xy 50.57059 -410.002953) (xy 50.57059 -410.057447)
			(xy 50.570589 -410.057453) (xy 52.008246 -410.057453) (xy 52.008246 -410.002947) (xy 52.016002 -409.948997)
			(xy 52.031358 -409.8967) (xy 52.053999 -409.84712) (xy 52.083466 -409.801267) (xy 52.119158 -409.760074)
			(xy 52.160349 -409.724379) (xy 52.206201 -409.69491) (xy 52.255779 -409.672265) (xy 52.308076 -409.656907)
			(xy 52.362025 -409.649147) (xy 52.389278 -409.64866) (xy 53.252878 -409.64866) (xy 53.28013 -409.649186)
			(xy 53.334078 -409.65694) (xy 53.386374 -409.672292) (xy 53.435953 -409.694932) (xy 53.481805 -409.724397)
			(xy 53.522997 -409.760087) (xy 53.55869 -409.801277) (xy 53.588158 -409.847127) (xy 53.6108 -409.896705)
			(xy 53.626156 -409.949) (xy 53.633913 -410.002948) (xy 53.633913 -410.057452) (xy 53.633912 -410.057456)
			(xy 55.071423 -410.057456) (xy 55.071423 -410.002944) (xy 55.079181 -409.948987) (xy 55.094539 -409.896683)
			(xy 55.117185 -409.847098) (xy 55.146657 -409.80124) (xy 55.182356 -409.760043) (xy 55.223554 -409.724346)
			(xy 55.269413 -409.694876) (xy 55.319 -409.672233) (xy 55.371305 -409.656877) (xy 55.425262 -409.649122)
			(xy 55.452518 -409.64866) (xy 56.316118 -409.64866) (xy 56.343366 -409.649211) (xy 56.397307 -409.656969)
			(xy 56.449595 -409.672325) (xy 56.499166 -409.694965) (xy 56.54501 -409.724429) (xy 56.586195 -409.760118)
			(xy 56.621882 -409.801304) (xy 56.651344 -409.84715) (xy 56.673982 -409.896721) (xy 56.689334 -409.94901)
			(xy 56.69709 -410.002952) (xy 56.69709 -410.057448) (xy 56.697089 -410.057452) (xy 58.134746 -410.057452)
			(xy 58.134746 -410.002948) (xy 58.142502 -409.949) (xy 58.157856 -409.896704) (xy 58.180496 -409.847125)
			(xy 58.209961 -409.801273) (xy 58.245651 -409.760081) (xy 58.28684 -409.724386) (xy 58.332689 -409.694916)
			(xy 58.382265 -409.672271) (xy 58.434559 -409.656911) (xy 58.488506 -409.649149) (xy 58.515758 -409.64866)
			(xy 59.379358 -409.64866) (xy 59.406611 -409.649184) (xy 59.460561 -409.656936) (xy 59.51286 -409.672287)
			(xy 59.562441 -409.694925) (xy 59.608296 -409.72439) (xy 59.64949 -409.76008) (xy 59.685185 -409.801271)
			(xy 59.714655 -409.847122) (xy 59.737298 -409.896701) (xy 59.752655 -409.948997) (xy 59.760413 -410.002948)
			(xy 59.760413 -410.057452) (xy 59.760413 -410.057453) (xy 61.197946 -410.057453) (xy 61.197946 -410.002947)
			(xy 61.205703 -409.948994) (xy 61.221059 -409.896695) (xy 61.243702 -409.847114) (xy 61.273171 -409.80126)
			(xy 61.308865 -409.760066) (xy 61.350059 -409.724372) (xy 61.395913 -409.694903) (xy 61.445494 -409.67226)
			(xy 61.497793 -409.656903) (xy 61.551745 -409.649146) (xy 61.578998 -409.64866) (xy 62.442598 -409.64866)
			(xy 62.469849 -409.649187) (xy 62.523795 -409.656943) (xy 62.576089 -409.672298) (xy 62.625665 -409.694938)
			(xy 62.671515 -409.724404) (xy 62.712704 -409.760094) (xy 62.748395 -409.801284) (xy 62.777861 -409.847133)
			(xy 62.800502 -409.896709) (xy 62.815856 -409.949003) (xy 62.823613 -410.002949) (xy 62.823613 -410.057451)
			(xy 62.823612 -410.057457) (xy 64.261123 -410.057457) (xy 64.261123 -410.002943) (xy 64.268882 -409.948984)
			(xy 64.284241 -409.896679) (xy 64.306888 -409.847092) (xy 64.336362 -409.801233) (xy 64.372063 -409.760036)
			(xy 64.413264 -409.724339) (xy 64.459125 -409.69487) (xy 64.508715 -409.672228) (xy 64.561021 -409.656874)
			(xy 64.614981 -409.64912) (xy 64.642238 -409.64866) (xy 65.505838 -409.64866) (xy 65.533085 -409.649213)
			(xy 65.587024 -409.656973) (xy 65.63931 -409.67233) (xy 65.688878 -409.694972) (xy 65.73472 -409.724436)
			(xy 65.775902 -409.760125) (xy 65.811586 -409.801311) (xy 65.841047 -409.847155) (xy 65.863683 -409.896726)
			(xy 65.879035 -409.949013) (xy 65.88679 -410.002953) (xy 65.88679 -410.057447) (xy 65.886789 -410.057453)
			(xy 67.324446 -410.057453) (xy 67.324446 -410.002947) (xy 67.332202 -409.948997) (xy 67.347558 -409.8967)
			(xy 67.370199 -409.84712) (xy 67.399666 -409.801267) (xy 67.435358 -409.760074) (xy 67.476549 -409.724379)
			(xy 67.522401 -409.69491) (xy 67.571979 -409.672265) (xy 67.624276 -409.656907) (xy 67.678225 -409.649147)
			(xy 67.705478 -409.64866) (xy 68.569078 -409.64866) (xy 68.59633 -409.649186) (xy 68.650278 -409.65694)
			(xy 68.702574 -409.672292) (xy 68.752153 -409.694932) (xy 68.798005 -409.724397) (xy 68.839197 -409.760087)
			(xy 68.87489 -409.801277) (xy 68.904358 -409.847127) (xy 68.927 -409.896705) (xy 68.942356 -409.949)
			(xy 68.950113 -410.002948) (xy 68.950113 -410.057452) (xy 68.950112 -410.057456) (xy 70.387623 -410.057456)
			(xy 70.387623 -410.002944) (xy 70.395381 -409.948987) (xy 70.410739 -409.896683) (xy 70.433385 -409.847098)
			(xy 70.462857 -409.80124) (xy 70.498556 -409.760043) (xy 70.539754 -409.724346) (xy 70.585613 -409.694876)
			(xy 70.6352 -409.672233) (xy 70.687505 -409.656877) (xy 70.741462 -409.649122) (xy 70.768718 -409.64866)
			(xy 71.632318 -409.64866) (xy 71.659566 -409.649211) (xy 71.713507 -409.656969) (xy 71.765795 -409.672325)
			(xy 71.815366 -409.694965) (xy 71.86121 -409.724429) (xy 71.902395 -409.760118) (xy 71.938082 -409.801304)
			(xy 71.967544 -409.84715) (xy 71.990182 -409.896721) (xy 72.005534 -409.94901) (xy 72.01329 -410.002952)
			(xy 72.01329 -410.057448) (xy 72.013289 -410.057452) (xy 73.450946 -410.057452) (xy 73.450946 -410.002948)
			(xy 73.458702 -409.949) (xy 73.474056 -409.896704) (xy 73.496696 -409.847125) (xy 73.526161 -409.801273)
			(xy 73.561851 -409.760081) (xy 73.60304 -409.724386) (xy 73.648889 -409.694916) (xy 73.698465 -409.672271)
			(xy 73.750759 -409.656911) (xy 73.804706 -409.649149) (xy 73.831958 -409.64866) (xy 74.695558 -409.64866)
			(xy 74.722811 -409.649184) (xy 74.776761 -409.656936) (xy 74.82906 -409.672287) (xy 74.878641 -409.694925)
			(xy 74.924496 -409.72439) (xy 74.96569 -409.76008) (xy 75.001385 -409.801271) (xy 75.030855 -409.847122)
			(xy 75.053498 -409.896701) (xy 75.068855 -409.948997) (xy 75.076613 -410.002948) (xy 75.076613 -410.057452)
			(xy 75.076613 -410.057453) (xy 76.514146 -410.057453) (xy 76.514146 -410.002947) (xy 76.521903 -409.948994)
			(xy 76.537259 -409.896695) (xy 76.559902 -409.847114) (xy 76.589371 -409.80126) (xy 76.625065 -409.760066)
			(xy 76.666259 -409.724372) (xy 76.712113 -409.694903) (xy 76.761694 -409.67226) (xy 76.813993 -409.656903)
			(xy 76.867945 -409.649146) (xy 76.895198 -409.64866) (xy 77.758798 -409.64866) (xy 77.786049 -409.649187)
			(xy 77.839995 -409.656943) (xy 77.892289 -409.672298) (xy 77.941865 -409.694938) (xy 77.987715 -409.724404)
			(xy 78.028904 -409.760094) (xy 78.064595 -409.801284) (xy 78.094061 -409.847133) (xy 78.116702 -409.896709)
			(xy 78.132056 -409.949003) (xy 78.139813 -410.002949) (xy 78.139813 -410.057451) (xy 78.139812 -410.057457)
			(xy 79.577323 -410.057457) (xy 79.577323 -410.002943) (xy 79.585082 -409.948984) (xy 79.600441 -409.896679)
			(xy 79.623088 -409.847092) (xy 79.652562 -409.801233) (xy 79.688263 -409.760036) (xy 79.729464 -409.724339)
			(xy 79.775325 -409.69487) (xy 79.824915 -409.672228) (xy 79.877221 -409.656874) (xy 79.931181 -409.64912)
			(xy 79.958438 -409.64866) (xy 80.822038 -409.64866) (xy 80.849285 -409.649213) (xy 80.903224 -409.656973)
			(xy 80.95551 -409.67233) (xy 81.005078 -409.694972) (xy 81.05092 -409.724436) (xy 81.092102 -409.760125)
			(xy 81.127786 -409.801311) (xy 81.157247 -409.847155) (xy 81.179883 -409.896726) (xy 81.195235 -409.949013)
			(xy 81.20299 -410.002953) (xy 81.20299 -410.057447) (xy 81.202989 -410.057453) (xy 82.640646 -410.057453)
			(xy 82.640646 -410.002947) (xy 82.648402 -409.948997) (xy 82.663758 -409.8967) (xy 82.686399 -409.84712)
			(xy 82.715866 -409.801267) (xy 82.751558 -409.760074) (xy 82.792749 -409.724379) (xy 82.838601 -409.69491)
			(xy 82.888179 -409.672265) (xy 82.940476 -409.656907) (xy 82.994425 -409.649147) (xy 83.021678 -409.64866)
			(xy 83.885278 -409.64866) (xy 83.91253 -409.649186) (xy 83.966478 -409.65694) (xy 84.018774 -409.672292)
			(xy 84.068353 -409.694932) (xy 84.114205 -409.724397) (xy 84.155397 -409.760087) (xy 84.19109 -409.801277)
			(xy 84.220558 -409.847127) (xy 84.2432 -409.896705) (xy 84.258556 -409.949) (xy 84.266313 -410.002948)
			(xy 84.266313 -410.057452) (xy 84.266312 -410.057456) (xy 85.703823 -410.057456) (xy 85.703823 -410.002944)
			(xy 85.711581 -409.948987) (xy 85.726939 -409.896683) (xy 85.749585 -409.847098) (xy 85.779057 -409.80124)
			(xy 85.814756 -409.760043) (xy 85.855954 -409.724346) (xy 85.901813 -409.694876) (xy 85.9514 -409.672233)
			(xy 86.003705 -409.656877) (xy 86.057662 -409.649122) (xy 86.084918 -409.64866) (xy 86.948518 -409.64866)
			(xy 86.975766 -409.649211) (xy 87.029707 -409.656969) (xy 87.081995 -409.672325) (xy 87.131566 -409.694965)
			(xy 87.17741 -409.724429) (xy 87.218595 -409.760118) (xy 87.254282 -409.801304) (xy 87.283744 -409.84715)
			(xy 87.306382 -409.896721) (xy 87.321734 -409.94901) (xy 87.32949 -410.002952) (xy 87.32949 -410.057448)
			(xy 87.329489 -410.057452) (xy 88.767146 -410.057452) (xy 88.767146 -410.002948) (xy 88.774902 -409.949)
			(xy 88.790256 -409.896704) (xy 88.812896 -409.847125) (xy 88.842361 -409.801273) (xy 88.878051 -409.760081)
			(xy 88.91924 -409.724386) (xy 88.965089 -409.694916) (xy 89.014665 -409.672271) (xy 89.066959 -409.656911)
			(xy 89.120906 -409.649149) (xy 89.148158 -409.64866) (xy 90.011758 -409.64866) (xy 90.039011 -409.649184)
			(xy 90.092961 -409.656936) (xy 90.14526 -409.672287) (xy 90.194841 -409.694925) (xy 90.240696 -409.72439)
			(xy 90.28189 -409.76008) (xy 90.317585 -409.801271) (xy 90.347055 -409.847122) (xy 90.369698 -409.896701)
			(xy 90.385055 -409.948997) (xy 90.392813 -410.002948) (xy 90.392813 -410.057452) (xy 90.392813 -410.057453)
			(xy 91.830346 -410.057453) (xy 91.830346 -410.002947) (xy 91.838103 -409.948994) (xy 91.853459 -409.896695)
			(xy 91.876102 -409.847114) (xy 91.905571 -409.80126) (xy 91.941265 -409.760066) (xy 91.982459 -409.724372)
			(xy 92.028313 -409.694903) (xy 92.077894 -409.67226) (xy 92.130193 -409.656903) (xy 92.184145 -409.649146)
			(xy 92.211398 -409.64866) (xy 93.074998 -409.64866) (xy 93.102249 -409.649187) (xy 93.156195 -409.656943)
			(xy 93.208489 -409.672298) (xy 93.258065 -409.694938) (xy 93.303915 -409.724404) (xy 93.345104 -409.760094)
			(xy 93.380795 -409.801284) (xy 93.410261 -409.847133) (xy 93.432902 -409.896709) (xy 93.448256 -409.949003)
			(xy 93.456013 -410.002949) (xy 93.456013 -410.057451) (xy 93.456012 -410.057457) (xy 94.893523 -410.057457)
			(xy 94.893523 -410.002943) (xy 94.901282 -409.948984) (xy 94.916641 -409.896679) (xy 94.939288 -409.847092)
			(xy 94.968762 -409.801233) (xy 95.004463 -409.760036) (xy 95.045664 -409.724339) (xy 95.091525 -409.69487)
			(xy 95.141115 -409.672228) (xy 95.193421 -409.656874) (xy 95.247381 -409.64912) (xy 95.274638 -409.64866)
			(xy 96.138238 -409.64866) (xy 96.165485 -409.649213) (xy 96.219424 -409.656973) (xy 96.27171 -409.67233)
			(xy 96.321278 -409.694972) (xy 96.36712 -409.724436) (xy 96.408302 -409.760125) (xy 96.443986 -409.801311)
			(xy 96.473447 -409.847155) (xy 96.496083 -409.896726) (xy 96.511435 -409.949013) (xy 96.51919 -410.002953)
			(xy 96.51919 -410.057447) (xy 96.519189 -410.057451) (xy 121.120146 -410.057451) (xy 121.120146 -410.002949)
			(xy 121.127902 -409.949) (xy 121.143256 -409.896705) (xy 121.165895 -409.847127) (xy 121.19536 -409.801275)
			(xy 121.231049 -409.760082) (xy 121.272238 -409.724388) (xy 121.318086 -409.694918) (xy 121.367662 -409.672272)
			(xy 121.419955 -409.656911) (xy 121.473903 -409.649149) (xy 121.501154 -409.64866) (xy 122.364754 -409.64866)
			(xy 122.392007 -409.649184) (xy 122.445958 -409.656935) (xy 122.498257 -409.672286) (xy 122.547839 -409.694924)
			(xy 122.593694 -409.724388) (xy 122.634889 -409.760079) (xy 122.670584 -409.801269) (xy 122.700054 -409.847121)
			(xy 122.722698 -409.8967) (xy 122.738055 -409.948997) (xy 122.745813 -410.002947) (xy 122.745813 -410.057453)
			(xy 124.183346 -410.057453) (xy 124.183346 -410.002947) (xy 124.191103 -409.948995) (xy 124.206459 -409.896696)
			(xy 124.229102 -409.847115) (xy 124.25857 -409.801261) (xy 124.294264 -409.760068) (xy 124.335457 -409.724373)
			(xy 124.38131 -409.694904) (xy 124.430891 -409.672261) (xy 124.483189 -409.656904) (xy 124.537141 -409.649146)
			(xy 124.564394 -409.64866) (xy 125.427994 -409.64866) (xy 125.455245 -409.649187) (xy 125.509192 -409.656942)
			(xy 125.561486 -409.672297) (xy 125.611063 -409.694937) (xy 125.656913 -409.724402) (xy 125.698103 -409.760093)
			(xy 125.733794 -409.801282) (xy 125.76326 -409.847132) (xy 125.785901 -409.896708) (xy 125.801256 -409.949002)
			(xy 125.809013 -410.002949) (xy 125.809013 -410.057451) (xy 125.809012 -410.057457) (xy 127.246523 -410.057457)
			(xy 127.246523 -410.002943) (xy 127.254282 -409.948985) (xy 127.269641 -409.89668) (xy 127.292287 -409.847093)
			(xy 127.321761 -409.801235) (xy 127.357462 -409.760037) (xy 127.398662 -409.724341) (xy 127.444523 -409.694871)
			(xy 127.494112 -409.672229) (xy 127.546418 -409.656874) (xy 127.600377 -409.649121) (xy 127.627634 -409.64866)
			(xy 128.491234 -409.64866) (xy 128.518481 -409.649213) (xy 128.572421 -409.656972) (xy 128.624707 -409.672329)
			(xy 128.674276 -409.69497) (xy 128.720118 -409.724435) (xy 128.761301 -409.760123) (xy 128.796985 -409.801309)
			(xy 128.826446 -409.847154) (xy 128.849083 -409.896725) (xy 128.864435 -409.949012) (xy 128.87219 -410.002953)
			(xy 128.87219 -410.057447) (xy 128.872189 -410.057452) (xy 130.309846 -410.057452) (xy 130.309846 -410.002948)
			(xy 130.317602 -409.948998) (xy 130.332957 -409.896701) (xy 130.355599 -409.847121) (xy 130.385065 -409.801268)
			(xy 130.420757 -409.760075) (xy 130.461947 -409.72438) (xy 130.507798 -409.694911) (xy 130.557376 -409.672266)
			(xy 130.609672 -409.656908) (xy 130.663622 -409.649148) (xy 130.690874 -409.64866) (xy 131.554474 -409.64866)
			(xy 131.581726 -409.649185) (xy 131.635675 -409.656939) (xy 131.687972 -409.672291) (xy 131.737551 -409.69493)
			(xy 131.783403 -409.724395) (xy 131.824596 -409.760086) (xy 131.860289 -409.801276) (xy 131.889757 -409.847126)
			(xy 131.9124 -409.896704) (xy 131.927756 -409.949) (xy 131.935513 -410.002948) (xy 131.935513 -410.057452)
			(xy 131.935512 -410.057456) (xy 133.373023 -410.057456) (xy 133.373023 -410.002944) (xy 133.380781 -409.948987)
			(xy 133.396139 -409.896684) (xy 133.418784 -409.847099) (xy 133.448256 -409.801241) (xy 133.483954 -409.760045)
			(xy 133.525152 -409.724348) (xy 133.571011 -409.694878) (xy 133.620597 -409.672234) (xy 133.672901 -409.656878)
			(xy 133.726858 -409.649122) (xy 133.754114 -409.64866) (xy 134.617714 -409.64866) (xy 134.644962 -409.649211)
			(xy 134.698904 -409.656969) (xy 134.751193 -409.672324) (xy 134.800764 -409.694964) (xy 134.846609 -409.724428)
			(xy 134.887794 -409.760116) (xy 134.923481 -409.801303) (xy 134.952943 -409.847149) (xy 134.975581 -409.896721)
			(xy 134.990934 -409.94901) (xy 134.99869 -410.002952) (xy 134.99869 -410.057448) (xy 134.99869 -410.057451)
			(xy 136.436346 -410.057451) (xy 136.436346 -410.002949) (xy 136.444102 -409.949) (xy 136.459456 -409.896705)
			(xy 136.482095 -409.847127) (xy 136.51156 -409.801275) (xy 136.547249 -409.760082) (xy 136.588438 -409.724388)
			(xy 136.634286 -409.694918) (xy 136.683862 -409.672272) (xy 136.736155 -409.656911) (xy 136.790103 -409.649149)
			(xy 136.817354 -409.64866) (xy 137.680954 -409.64866) (xy 137.708207 -409.649184) (xy 137.762158 -409.656935)
			(xy 137.814457 -409.672286) (xy 137.864039 -409.694924) (xy 137.909894 -409.724388) (xy 137.951089 -409.760079)
			(xy 137.986784 -409.801269) (xy 138.016254 -409.847121) (xy 138.038898 -409.8967) (xy 138.054255 -409.948997)
			(xy 138.062013 -410.002947) (xy 138.062013 -410.057453) (xy 139.499546 -410.057453) (xy 139.499546 -410.002947)
			(xy 139.507303 -409.948995) (xy 139.522659 -409.896696) (xy 139.545302 -409.847115) (xy 139.57477 -409.801261)
			(xy 139.610464 -409.760068) (xy 139.651657 -409.724373) (xy 139.69751 -409.694904) (xy 139.747091 -409.672261)
			(xy 139.799389 -409.656904) (xy 139.853341 -409.649146) (xy 139.880594 -409.64866) (xy 140.744194 -409.64866)
			(xy 140.771445 -409.649187) (xy 140.825392 -409.656942) (xy 140.877686 -409.672297) (xy 140.927263 -409.694937)
			(xy 140.973113 -409.724402) (xy 141.014303 -409.760093) (xy 141.049994 -409.801282) (xy 141.07946 -409.847132)
			(xy 141.102101 -409.896708) (xy 141.117456 -409.949002) (xy 141.125213 -410.002949) (xy 141.125213 -410.057451)
			(xy 141.125212 -410.057457) (xy 142.562723 -410.057457) (xy 142.562723 -410.002943) (xy 142.570482 -409.948985)
			(xy 142.585841 -409.89668) (xy 142.608487 -409.847093) (xy 142.637961 -409.801235) (xy 142.673662 -409.760037)
			(xy 142.714862 -409.724341) (xy 142.760723 -409.694871) (xy 142.810312 -409.672229) (xy 142.862618 -409.656874)
			(xy 142.916577 -409.649121) (xy 142.943834 -409.64866) (xy 143.807434 -409.64866) (xy 143.834681 -409.649213)
			(xy 143.888621 -409.656972) (xy 143.940907 -409.672329) (xy 143.990476 -409.69497) (xy 144.036318 -409.724435)
			(xy 144.077501 -409.760123) (xy 144.113185 -409.801309) (xy 144.142646 -409.847154) (xy 144.165283 -409.896725)
			(xy 144.180635 -409.949012) (xy 144.18839 -410.002953) (xy 144.18839 -410.057447) (xy 144.188389 -410.057452)
			(xy 145.626046 -410.057452) (xy 145.626046 -410.002948) (xy 145.633802 -409.948998) (xy 145.649157 -409.896701)
			(xy 145.671799 -409.847121) (xy 145.701265 -409.801268) (xy 145.736957 -409.760075) (xy 145.778147 -409.72438)
			(xy 145.823998 -409.694911) (xy 145.873576 -409.672266) (xy 145.925872 -409.656908) (xy 145.979822 -409.649148)
			(xy 146.007074 -409.64866) (xy 146.870674 -409.64866) (xy 146.897926 -409.649185) (xy 146.951875 -409.656939)
			(xy 147.004172 -409.672291) (xy 147.053751 -409.69493) (xy 147.099603 -409.724395) (xy 147.140796 -409.760086)
			(xy 147.176489 -409.801276) (xy 147.205957 -409.847126) (xy 147.2286 -409.896704) (xy 147.243956 -409.949)
			(xy 147.251713 -410.002948) (xy 147.251713 -410.057452) (xy 147.251712 -410.057456) (xy 148.689223 -410.057456)
			(xy 148.689223 -410.002944) (xy 148.696981 -409.948987) (xy 148.712339 -409.896684) (xy 148.734984 -409.847099)
			(xy 148.764456 -409.801241) (xy 148.800154 -409.760045) (xy 148.841352 -409.724348) (xy 148.887211 -409.694878)
			(xy 148.936797 -409.672234) (xy 148.989101 -409.656878) (xy 149.043058 -409.649122) (xy 149.070314 -409.64866)
			(xy 149.933914 -409.64866) (xy 149.961162 -409.649211) (xy 150.015104 -409.656969) (xy 150.067393 -409.672324)
			(xy 150.116964 -409.694964) (xy 150.162809 -409.724428) (xy 150.203994 -409.760116) (xy 150.239681 -409.801303)
			(xy 150.269143 -409.847149) (xy 150.291781 -409.896721) (xy 150.307134 -409.94901) (xy 150.31489 -410.002952)
			(xy 150.31489 -410.057448) (xy 150.31489 -410.057451) (xy 151.752546 -410.057451) (xy 151.752546 -410.002949)
			(xy 151.760302 -409.949) (xy 151.775656 -409.896705) (xy 151.798295 -409.847127) (xy 151.82776 -409.801275)
			(xy 151.863449 -409.760082) (xy 151.904638 -409.724388) (xy 151.950486 -409.694918) (xy 152.000062 -409.672272)
			(xy 152.052355 -409.656911) (xy 152.106303 -409.649149) (xy 152.133554 -409.64866) (xy 152.997154 -409.64866)
			(xy 153.024407 -409.649184) (xy 153.078358 -409.656935) (xy 153.130657 -409.672286) (xy 153.180239 -409.694924)
			(xy 153.226094 -409.724388) (xy 153.267289 -409.760079) (xy 153.302984 -409.801269) (xy 153.332454 -409.847121)
			(xy 153.355098 -409.8967) (xy 153.370455 -409.948997) (xy 153.378213 -410.002947) (xy 153.378213 -410.057453)
			(xy 154.815746 -410.057453) (xy 154.815746 -410.002947) (xy 154.823503 -409.948995) (xy 154.838859 -409.896696)
			(xy 154.861502 -409.847115) (xy 154.89097 -409.801261) (xy 154.926664 -409.760068) (xy 154.967857 -409.724373)
			(xy 155.01371 -409.694904) (xy 155.063291 -409.672261) (xy 155.115589 -409.656904) (xy 155.169541 -409.649146)
			(xy 155.196794 -409.64866) (xy 156.060394 -409.64866) (xy 156.087645 -409.649187) (xy 156.141592 -409.656942)
			(xy 156.193886 -409.672297) (xy 156.243463 -409.694937) (xy 156.289313 -409.724402) (xy 156.330503 -409.760093)
			(xy 156.366194 -409.801282) (xy 156.39566 -409.847132) (xy 156.418301 -409.896708) (xy 156.433656 -409.949002)
			(xy 156.441413 -410.002949) (xy 156.441413 -410.057451) (xy 156.441412 -410.057457) (xy 157.878923 -410.057457)
			(xy 157.878923 -410.002943) (xy 157.886682 -409.948985) (xy 157.902041 -409.89668) (xy 157.924687 -409.847093)
			(xy 157.954161 -409.801235) (xy 157.989862 -409.760037) (xy 158.031062 -409.724341) (xy 158.076923 -409.694871)
			(xy 158.126512 -409.672229) (xy 158.178818 -409.656874) (xy 158.232777 -409.649121) (xy 158.260034 -409.64866)
			(xy 159.123634 -409.64866) (xy 159.150881 -409.649213) (xy 159.204821 -409.656972) (xy 159.257107 -409.672329)
			(xy 159.306676 -409.69497) (xy 159.352518 -409.724435) (xy 159.393701 -409.760123) (xy 159.429385 -409.801309)
			(xy 159.458846 -409.847154) (xy 159.481483 -409.896725) (xy 159.496835 -409.949012) (xy 159.50459 -410.002953)
			(xy 159.50459 -410.057447) (xy 159.504589 -410.057452) (xy 160.942246 -410.057452) (xy 160.942246 -410.002948)
			(xy 160.950002 -409.948998) (xy 160.965357 -409.896701) (xy 160.987999 -409.847121) (xy 161.017465 -409.801268)
			(xy 161.053157 -409.760075) (xy 161.094347 -409.72438) (xy 161.140198 -409.694911) (xy 161.189776 -409.672266)
			(xy 161.242072 -409.656908) (xy 161.296022 -409.649148) (xy 161.323274 -409.64866) (xy 162.186874 -409.64866)
			(xy 162.214126 -409.649185) (xy 162.268075 -409.656939) (xy 162.320372 -409.672291) (xy 162.369951 -409.69493)
			(xy 162.415803 -409.724395) (xy 162.456996 -409.760086) (xy 162.492689 -409.801276) (xy 162.522157 -409.847126)
			(xy 162.5448 -409.896704) (xy 162.560156 -409.949) (xy 162.567913 -410.002948) (xy 162.567913 -410.057452)
			(xy 162.567912 -410.057456) (xy 164.005423 -410.057456) (xy 164.005423 -410.002944) (xy 164.013181 -409.948987)
			(xy 164.028539 -409.896684) (xy 164.051184 -409.847099) (xy 164.080656 -409.801241) (xy 164.116354 -409.760045)
			(xy 164.157552 -409.724348) (xy 164.203411 -409.694878) (xy 164.252997 -409.672234) (xy 164.305301 -409.656878)
			(xy 164.359258 -409.649122) (xy 164.386514 -409.64866) (xy 165.250114 -409.64866) (xy 165.277362 -409.649211)
			(xy 165.331304 -409.656969) (xy 165.383593 -409.672324) (xy 165.433164 -409.694964) (xy 165.479009 -409.724428)
			(xy 165.520194 -409.760116) (xy 165.555881 -409.801303) (xy 165.585343 -409.847149) (xy 165.607981 -409.896721)
			(xy 165.623334 -409.94901) (xy 165.63109 -410.002952) (xy 165.63109 -410.057448) (xy 165.63109 -410.057451)
			(xy 167.068746 -410.057451) (xy 167.068746 -410.002949) (xy 167.076502 -409.949) (xy 167.091856 -409.896705)
			(xy 167.114495 -409.847127) (xy 167.14396 -409.801275) (xy 167.179649 -409.760082) (xy 167.220838 -409.724388)
			(xy 167.266686 -409.694918) (xy 167.316262 -409.672272) (xy 167.368555 -409.656911) (xy 167.422503 -409.649149)
			(xy 167.449754 -409.64866) (xy 168.313354 -409.64866) (xy 168.340607 -409.649184) (xy 168.394558 -409.656935)
			(xy 168.446857 -409.672286) (xy 168.496439 -409.694924) (xy 168.542294 -409.724388) (xy 168.583489 -409.760079)
			(xy 168.619184 -409.801269) (xy 168.648654 -409.847121) (xy 168.671298 -409.8967) (xy 168.686655 -409.948997)
			(xy 168.694413 -410.002947) (xy 168.694413 -410.057453) (xy 168.686655 -410.111403) (xy 168.671298 -410.1637)
			(xy 168.648654 -410.213279) (xy 168.619184 -410.259131) (xy 168.583489 -410.300321) (xy 168.542294 -410.336012)
			(xy 168.496439 -410.365476) (xy 168.446857 -410.388114) (xy 168.394558 -410.403465) (xy 168.340607 -410.411216)
			(xy 168.313354 -410.411676) (xy 167.449754 -410.411676) (xy 167.422503 -410.411251) (xy 167.368555 -410.403489)
			(xy 167.316262 -410.388128) (xy 167.266686 -410.365482) (xy 167.220838 -410.336012) (xy 167.179649 -410.300318)
			(xy 167.14396 -410.259125) (xy 167.114495 -410.213273) (xy 167.091856 -410.163695) (xy 167.076502 -410.1114)
			(xy 167.068746 -410.057451) (xy 165.63109 -410.057451) (xy 165.623334 -410.11139) (xy 165.607981 -410.163679)
			(xy 165.585343 -410.213251) (xy 165.555881 -410.259097) (xy 165.520194 -410.300284) (xy 165.479009 -410.335972)
			(xy 165.433164 -410.365436) (xy 165.383593 -410.388076) (xy 165.331304 -410.403431) (xy 165.277362 -410.411189)
			(xy 165.250114 -410.411676) (xy 164.386514 -410.411676) (xy 164.359258 -410.411278) (xy 164.305301 -410.403522)
			(xy 164.252997 -410.388166) (xy 164.203411 -410.365522) (xy 164.157552 -410.336052) (xy 164.116354 -410.300355)
			(xy 164.080656 -410.259159) (xy 164.051184 -410.213301) (xy 164.028539 -410.163716) (xy 164.013181 -410.111413)
			(xy 164.005423 -410.057456) (xy 162.567912 -410.057456) (xy 162.560156 -410.1114) (xy 162.5448 -410.163696)
			(xy 162.522157 -410.213274) (xy 162.492689 -410.259124) (xy 162.456996 -410.300314) (xy 162.415803 -410.336005)
			(xy 162.369951 -410.36547) (xy 162.320372 -410.388109) (xy 162.268075 -410.403461) (xy 162.214126 -410.411215)
			(xy 162.186874 -410.411676) (xy 161.323274 -410.411676) (xy 161.296022 -410.411252) (xy 161.242072 -410.403492)
			(xy 161.189776 -410.388134) (xy 161.140198 -410.365489) (xy 161.094347 -410.33602) (xy 161.053157 -410.300325)
			(xy 161.017465 -410.259132) (xy 160.987999 -410.213279) (xy 160.965357 -410.163699) (xy 160.950002 -410.111402)
			(xy 160.942246 -410.057452) (xy 159.504589 -410.057452) (xy 159.496835 -410.111388) (xy 159.481483 -410.163675)
			(xy 159.458846 -410.213246) (xy 159.429385 -410.259091) (xy 159.393701 -410.300277) (xy 159.352518 -410.335965)
			(xy 159.306676 -410.36543) (xy 159.257107 -410.388071) (xy 159.204821 -410.403428) (xy 159.150881 -410.411187)
			(xy 159.123634 -410.411676) (xy 158.260034 -410.411676) (xy 158.232777 -410.411279) (xy 158.178818 -410.403526)
			(xy 158.126512 -410.388171) (xy 158.076923 -410.365529) (xy 158.031062 -410.336059) (xy 157.989862 -410.300363)
			(xy 157.954161 -410.259165) (xy 157.924687 -410.213307) (xy 157.902041 -410.16372) (xy 157.886682 -410.111415)
			(xy 157.878923 -410.057457) (xy 156.441412 -410.057457) (xy 156.433656 -410.111398) (xy 156.418301 -410.163692)
			(xy 156.39566 -410.213268) (xy 156.366194 -410.259118) (xy 156.330503 -410.300307) (xy 156.289313 -410.335998)
			(xy 156.243463 -410.365463) (xy 156.193886 -410.388103) (xy 156.141592 -410.403458) (xy 156.087645 -410.411213)
			(xy 156.060394 -410.411676) (xy 155.196794 -410.411676) (xy 155.169541 -410.411254) (xy 155.115589 -410.403496)
			(xy 155.063291 -410.388139) (xy 155.01371 -410.365496) (xy 154.967857 -410.336027) (xy 154.926664 -410.300332)
			(xy 154.89097 -410.259139) (xy 154.861502 -410.213285) (xy 154.838859 -410.163704) (xy 154.823503 -410.111405)
			(xy 154.815746 -410.057453) (xy 153.378213 -410.057453) (xy 153.370455 -410.111403) (xy 153.355098 -410.1637)
			(xy 153.332454 -410.213279) (xy 153.302984 -410.259131) (xy 153.267289 -410.300321) (xy 153.226094 -410.336012)
			(xy 153.180239 -410.365476) (xy 153.130657 -410.388114) (xy 153.078358 -410.403465) (xy 153.024407 -410.411216)
			(xy 152.997154 -410.411676) (xy 152.133554 -410.411676) (xy 152.106303 -410.411251) (xy 152.052355 -410.403489)
			(xy 152.000062 -410.388128) (xy 151.950486 -410.365482) (xy 151.904638 -410.336012) (xy 151.863449 -410.300318)
			(xy 151.82776 -410.259125) (xy 151.798295 -410.213273) (xy 151.775656 -410.163695) (xy 151.760302 -410.1114)
			(xy 151.752546 -410.057451) (xy 150.31489 -410.057451) (xy 150.307134 -410.11139) (xy 150.291781 -410.163679)
			(xy 150.269143 -410.213251) (xy 150.239681 -410.259097) (xy 150.203994 -410.300284) (xy 150.162809 -410.335972)
			(xy 150.116964 -410.365436) (xy 150.067393 -410.388076) (xy 150.015104 -410.403431) (xy 149.961162 -410.411189)
			(xy 149.933914 -410.411676) (xy 149.070314 -410.411676) (xy 149.043058 -410.411278) (xy 148.989101 -410.403522)
			(xy 148.936797 -410.388166) (xy 148.887211 -410.365522) (xy 148.841352 -410.336052) (xy 148.800154 -410.300355)
			(xy 148.764456 -410.259159) (xy 148.734984 -410.213301) (xy 148.712339 -410.163716) (xy 148.696981 -410.111413)
			(xy 148.689223 -410.057456) (xy 147.251712 -410.057456) (xy 147.243956 -410.1114) (xy 147.2286 -410.163696)
			(xy 147.205957 -410.213274) (xy 147.176489 -410.259124) (xy 147.140796 -410.300314) (xy 147.099603 -410.336005)
			(xy 147.053751 -410.36547) (xy 147.004172 -410.388109) (xy 146.951875 -410.403461) (xy 146.897926 -410.411215)
			(xy 146.870674 -410.411676) (xy 146.007074 -410.411676) (xy 145.979822 -410.411252) (xy 145.925872 -410.403492)
			(xy 145.873576 -410.388134) (xy 145.823998 -410.365489) (xy 145.778147 -410.33602) (xy 145.736957 -410.300325)
			(xy 145.701265 -410.259132) (xy 145.671799 -410.213279) (xy 145.649157 -410.163699) (xy 145.633802 -410.111402)
			(xy 145.626046 -410.057452) (xy 144.188389 -410.057452) (xy 144.180635 -410.111388) (xy 144.165283 -410.163675)
			(xy 144.142646 -410.213246) (xy 144.113185 -410.259091) (xy 144.077501 -410.300277) (xy 144.036318 -410.335965)
			(xy 143.990476 -410.36543) (xy 143.940907 -410.388071) (xy 143.888621 -410.403428) (xy 143.834681 -410.411187)
			(xy 143.807434 -410.411676) (xy 142.943834 -410.411676) (xy 142.916577 -410.411279) (xy 142.862618 -410.403526)
			(xy 142.810312 -410.388171) (xy 142.760723 -410.365529) (xy 142.714862 -410.336059) (xy 142.673662 -410.300363)
			(xy 142.637961 -410.259165) (xy 142.608487 -410.213307) (xy 142.585841 -410.16372) (xy 142.570482 -410.111415)
			(xy 142.562723 -410.057457) (xy 141.125212 -410.057457) (xy 141.117456 -410.111398) (xy 141.102101 -410.163692)
			(xy 141.07946 -410.213268) (xy 141.049994 -410.259118) (xy 141.014303 -410.300307) (xy 140.973113 -410.335998)
			(xy 140.927263 -410.365463) (xy 140.877686 -410.388103) (xy 140.825392 -410.403458) (xy 140.771445 -410.411213)
			(xy 140.744194 -410.411676) (xy 139.880594 -410.411676) (xy 139.853341 -410.411254) (xy 139.799389 -410.403496)
			(xy 139.747091 -410.388139) (xy 139.69751 -410.365496) (xy 139.651657 -410.336027) (xy 139.610464 -410.300332)
			(xy 139.57477 -410.259139) (xy 139.545302 -410.213285) (xy 139.522659 -410.163704) (xy 139.507303 -410.111405)
			(xy 139.499546 -410.057453) (xy 138.062013 -410.057453) (xy 138.054255 -410.111403) (xy 138.038898 -410.1637)
			(xy 138.016254 -410.213279) (xy 137.986784 -410.259131) (xy 137.951089 -410.300321) (xy 137.909894 -410.336012)
			(xy 137.864039 -410.365476) (xy 137.814457 -410.388114) (xy 137.762158 -410.403465) (xy 137.708207 -410.411216)
			(xy 137.680954 -410.411676) (xy 136.817354 -410.411676) (xy 136.790103 -410.411251) (xy 136.736155 -410.403489)
			(xy 136.683862 -410.388128) (xy 136.634286 -410.365482) (xy 136.588438 -410.336012) (xy 136.547249 -410.300318)
			(xy 136.51156 -410.259125) (xy 136.482095 -410.213273) (xy 136.459456 -410.163695) (xy 136.444102 -410.1114)
			(xy 136.436346 -410.057451) (xy 134.99869 -410.057451) (xy 134.990934 -410.11139) (xy 134.975581 -410.163679)
			(xy 134.952943 -410.213251) (xy 134.923481 -410.259097) (xy 134.887794 -410.300284) (xy 134.846609 -410.335972)
			(xy 134.800764 -410.365436) (xy 134.751193 -410.388076) (xy 134.698904 -410.403431) (xy 134.644962 -410.411189)
			(xy 134.617714 -410.411676) (xy 133.754114 -410.411676) (xy 133.726858 -410.411278) (xy 133.672901 -410.403522)
			(xy 133.620597 -410.388166) (xy 133.571011 -410.365522) (xy 133.525152 -410.336052) (xy 133.483954 -410.300355)
			(xy 133.448256 -410.259159) (xy 133.418784 -410.213301) (xy 133.396139 -410.163716) (xy 133.380781 -410.111413)
			(xy 133.373023 -410.057456) (xy 131.935512 -410.057456) (xy 131.927756 -410.1114) (xy 131.9124 -410.163696)
			(xy 131.889757 -410.213274) (xy 131.860289 -410.259124) (xy 131.824596 -410.300314) (xy 131.783403 -410.336005)
			(xy 131.737551 -410.36547) (xy 131.687972 -410.388109) (xy 131.635675 -410.403461) (xy 131.581726 -410.411215)
			(xy 131.554474 -410.411676) (xy 130.690874 -410.411676) (xy 130.663622 -410.411252) (xy 130.609672 -410.403492)
			(xy 130.557376 -410.388134) (xy 130.507798 -410.365489) (xy 130.461947 -410.33602) (xy 130.420757 -410.300325)
			(xy 130.385065 -410.259132) (xy 130.355599 -410.213279) (xy 130.332957 -410.163699) (xy 130.317602 -410.111402)
			(xy 130.309846 -410.057452) (xy 128.872189 -410.057452) (xy 128.864435 -410.111388) (xy 128.849083 -410.163675)
			(xy 128.826446 -410.213246) (xy 128.796985 -410.259091) (xy 128.761301 -410.300277) (xy 128.720118 -410.335965)
			(xy 128.674276 -410.36543) (xy 128.624707 -410.388071) (xy 128.572421 -410.403428) (xy 128.518481 -410.411187)
			(xy 128.491234 -410.411676) (xy 127.627634 -410.411676) (xy 127.600377 -410.411279) (xy 127.546418 -410.403526)
			(xy 127.494112 -410.388171) (xy 127.444523 -410.365529) (xy 127.398662 -410.336059) (xy 127.357462 -410.300363)
			(xy 127.321761 -410.259165) (xy 127.292287 -410.213307) (xy 127.269641 -410.16372) (xy 127.254282 -410.111415)
			(xy 127.246523 -410.057457) (xy 125.809012 -410.057457) (xy 125.801256 -410.111398) (xy 125.785901 -410.163692)
			(xy 125.76326 -410.213268) (xy 125.733794 -410.259118) (xy 125.698103 -410.300307) (xy 125.656913 -410.335998)
			(xy 125.611063 -410.365463) (xy 125.561486 -410.388103) (xy 125.509192 -410.403458) (xy 125.455245 -410.411213)
			(xy 125.427994 -410.411676) (xy 124.564394 -410.411676) (xy 124.537141 -410.411254) (xy 124.483189 -410.403496)
			(xy 124.430891 -410.388139) (xy 124.38131 -410.365496) (xy 124.335457 -410.336027) (xy 124.294264 -410.300332)
			(xy 124.25857 -410.259139) (xy 124.229102 -410.213285) (xy 124.206459 -410.163704) (xy 124.191103 -410.111405)
			(xy 124.183346 -410.057453) (xy 122.745813 -410.057453) (xy 122.738055 -410.111403) (xy 122.722698 -410.1637)
			(xy 122.700054 -410.213279) (xy 122.670584 -410.259131) (xy 122.634889 -410.300321) (xy 122.593694 -410.336012)
			(xy 122.547839 -410.365476) (xy 122.498257 -410.388114) (xy 122.445958 -410.403465) (xy 122.392007 -410.411216)
			(xy 122.364754 -410.411676) (xy 121.501154 -410.411676) (xy 121.473903 -410.411251) (xy 121.419955 -410.403489)
			(xy 121.367662 -410.388128) (xy 121.318086 -410.365482) (xy 121.272238 -410.336012) (xy 121.231049 -410.300318)
			(xy 121.19536 -410.259125) (xy 121.165895 -410.213273) (xy 121.143256 -410.163695) (xy 121.127902 -410.1114)
			(xy 121.120146 -410.057451) (xy 96.519189 -410.057451) (xy 96.511435 -410.111387) (xy 96.496083 -410.163674)
			(xy 96.473447 -410.213245) (xy 96.443986 -410.259089) (xy 96.408302 -410.300275) (xy 96.36712 -410.335964)
			(xy 96.321278 -410.365428) (xy 96.27171 -410.38807) (xy 96.219424 -410.403427) (xy 96.165485 -410.411187)
			(xy 96.138238 -410.411676) (xy 95.274638 -410.411676) (xy 95.247381 -410.41128) (xy 95.193421 -410.403526)
			(xy 95.141115 -410.388172) (xy 95.091525 -410.36553) (xy 95.045664 -410.336061) (xy 95.004463 -410.300364)
			(xy 94.968762 -410.259167) (xy 94.939288 -410.213308) (xy 94.916641 -410.163721) (xy 94.901282 -410.111416)
			(xy 94.893523 -410.057457) (xy 93.456012 -410.057457) (xy 93.448256 -410.111397) (xy 93.432902 -410.163691)
			(xy 93.410261 -410.213267) (xy 93.380795 -410.259116) (xy 93.345104 -410.300306) (xy 93.303915 -410.335996)
			(xy 93.258065 -410.365462) (xy 93.208489 -410.388102) (xy 93.156195 -410.403457) (xy 93.102249 -410.411213)
			(xy 93.074998 -410.411676) (xy 92.211398 -410.411676) (xy 92.184145 -410.411254) (xy 92.130193 -410.403497)
			(xy 92.077894 -410.38814) (xy 92.028313 -410.365497) (xy 91.982459 -410.336028) (xy 91.941265 -410.300334)
			(xy 91.905571 -410.25914) (xy 91.876102 -410.213286) (xy 91.853459 -410.163705) (xy 91.838103 -410.111406)
			(xy 91.830346 -410.057453) (xy 90.392813 -410.057453) (xy 90.385055 -410.111403) (xy 90.369698 -410.163699)
			(xy 90.347055 -410.213278) (xy 90.317585 -410.259129) (xy 90.28189 -410.30032) (xy 90.240696 -410.33601)
			(xy 90.194841 -410.365475) (xy 90.14526 -410.388113) (xy 90.092961 -410.403464) (xy 90.039011 -410.411216)
			(xy 90.011758 -410.411676) (xy 89.148158 -410.411676) (xy 89.120906 -410.411251) (xy 89.066959 -410.403489)
			(xy 89.014665 -410.388129) (xy 88.965089 -410.365484) (xy 88.91924 -410.336014) (xy 88.878051 -410.300319)
			(xy 88.842361 -410.259127) (xy 88.812896 -410.213275) (xy 88.790256 -410.163696) (xy 88.774902 -410.1114)
			(xy 88.767146 -410.057452) (xy 87.329489 -410.057452) (xy 87.321734 -410.11139) (xy 87.306382 -410.163679)
			(xy 87.283744 -410.21325) (xy 87.254282 -410.259096) (xy 87.218595 -410.300282) (xy 87.17741 -410.335971)
			(xy 87.131566 -410.365435) (xy 87.081995 -410.388075) (xy 87.029707 -410.403431) (xy 86.975766 -410.411189)
			(xy 86.948518 -410.411676) (xy 86.084918 -410.411676) (xy 86.057662 -410.411278) (xy 86.003705 -410.403523)
			(xy 85.9514 -410.388167) (xy 85.901813 -410.365524) (xy 85.855954 -410.336054) (xy 85.814756 -410.300357)
			(xy 85.779057 -410.25916) (xy 85.749585 -410.213302) (xy 85.726939 -410.163717) (xy 85.711581 -410.111413)
			(xy 85.703823 -410.057456) (xy 84.266312 -410.057456) (xy 84.258556 -410.1114) (xy 84.2432 -410.163695)
			(xy 84.220558 -410.213273) (xy 84.19109 -410.259123) (xy 84.155397 -410.300313) (xy 84.114205 -410.336003)
			(xy 84.068353 -410.365468) (xy 84.018774 -410.388108) (xy 83.966478 -410.40346) (xy 83.91253 -410.411214)
			(xy 83.885278 -410.411676) (xy 83.021678 -410.411676) (xy 82.994425 -410.411253) (xy 82.940476 -410.403493)
			(xy 82.888179 -410.388135) (xy 82.838601 -410.36549) (xy 82.792749 -410.336021) (xy 82.751558 -410.300326)
			(xy 82.715866 -410.259133) (xy 82.686399 -410.21328) (xy 82.663758 -410.1637) (xy 82.648402 -410.111403)
			(xy 82.640646 -410.057453) (xy 81.202989 -410.057453) (xy 81.195235 -410.111387) (xy 81.179883 -410.163674)
			(xy 81.157247 -410.213245) (xy 81.127786 -410.259089) (xy 81.092102 -410.300275) (xy 81.05092 -410.335964)
			(xy 81.005078 -410.365428) (xy 80.95551 -410.38807) (xy 80.903224 -410.403427) (xy 80.849285 -410.411187)
			(xy 80.822038 -410.411676) (xy 79.958438 -410.411676) (xy 79.931181 -410.41128) (xy 79.877221 -410.403526)
			(xy 79.824915 -410.388172) (xy 79.775325 -410.36553) (xy 79.729464 -410.336061) (xy 79.688263 -410.300364)
			(xy 79.652562 -410.259167) (xy 79.623088 -410.213308) (xy 79.600441 -410.163721) (xy 79.585082 -410.111416)
			(xy 79.577323 -410.057457) (xy 78.139812 -410.057457) (xy 78.132056 -410.111397) (xy 78.116702 -410.163691)
			(xy 78.094061 -410.213267) (xy 78.064595 -410.259116) (xy 78.028904 -410.300306) (xy 77.987715 -410.335996)
			(xy 77.941865 -410.365462) (xy 77.892289 -410.388102) (xy 77.839995 -410.403457) (xy 77.786049 -410.411213)
			(xy 77.758798 -410.411676) (xy 76.895198 -410.411676) (xy 76.867945 -410.411254) (xy 76.813993 -410.403497)
			(xy 76.761694 -410.38814) (xy 76.712113 -410.365497) (xy 76.666259 -410.336028) (xy 76.625065 -410.300334)
			(xy 76.589371 -410.25914) (xy 76.559902 -410.213286) (xy 76.537259 -410.163705) (xy 76.521903 -410.111406)
			(xy 76.514146 -410.057453) (xy 75.076613 -410.057453) (xy 75.068855 -410.111403) (xy 75.053498 -410.163699)
			(xy 75.030855 -410.213278) (xy 75.001385 -410.259129) (xy 74.96569 -410.30032) (xy 74.924496 -410.33601)
			(xy 74.878641 -410.365475) (xy 74.82906 -410.388113) (xy 74.776761 -410.403464) (xy 74.722811 -410.411216)
			(xy 74.695558 -410.411676) (xy 73.831958 -410.411676) (xy 73.804706 -410.411251) (xy 73.750759 -410.403489)
			(xy 73.698465 -410.388129) (xy 73.648889 -410.365484) (xy 73.60304 -410.336014) (xy 73.561851 -410.300319)
			(xy 73.526161 -410.259127) (xy 73.496696 -410.213275) (xy 73.474056 -410.163696) (xy 73.458702 -410.1114)
			(xy 73.450946 -410.057452) (xy 72.013289 -410.057452) (xy 72.005534 -410.11139) (xy 71.990182 -410.163679)
			(xy 71.967544 -410.21325) (xy 71.938082 -410.259096) (xy 71.902395 -410.300282) (xy 71.86121 -410.335971)
			(xy 71.815366 -410.365435) (xy 71.765795 -410.388075) (xy 71.713507 -410.403431) (xy 71.659566 -410.411189)
			(xy 71.632318 -410.411676) (xy 70.768718 -410.411676) (xy 70.741462 -410.411278) (xy 70.687505 -410.403523)
			(xy 70.6352 -410.388167) (xy 70.585613 -410.365524) (xy 70.539754 -410.336054) (xy 70.498556 -410.300357)
			(xy 70.462857 -410.25916) (xy 70.433385 -410.213302) (xy 70.410739 -410.163717) (xy 70.395381 -410.111413)
			(xy 70.387623 -410.057456) (xy 68.950112 -410.057456) (xy 68.942356 -410.1114) (xy 68.927 -410.163695)
			(xy 68.904358 -410.213273) (xy 68.87489 -410.259123) (xy 68.839197 -410.300313) (xy 68.798005 -410.336003)
			(xy 68.752153 -410.365468) (xy 68.702574 -410.388108) (xy 68.650278 -410.40346) (xy 68.59633 -410.411214)
			(xy 68.569078 -410.411676) (xy 67.705478 -410.411676) (xy 67.678225 -410.411253) (xy 67.624276 -410.403493)
			(xy 67.571979 -410.388135) (xy 67.522401 -410.36549) (xy 67.476549 -410.336021) (xy 67.435358 -410.300326)
			(xy 67.399666 -410.259133) (xy 67.370199 -410.21328) (xy 67.347558 -410.1637) (xy 67.332202 -410.111403)
			(xy 67.324446 -410.057453) (xy 65.886789 -410.057453) (xy 65.879035 -410.111387) (xy 65.863683 -410.163674)
			(xy 65.841047 -410.213245) (xy 65.811586 -410.259089) (xy 65.775902 -410.300275) (xy 65.73472 -410.335964)
			(xy 65.688878 -410.365428) (xy 65.63931 -410.38807) (xy 65.587024 -410.403427) (xy 65.533085 -410.411187)
			(xy 65.505838 -410.411676) (xy 64.642238 -410.411676) (xy 64.614981 -410.41128) (xy 64.561021 -410.403526)
			(xy 64.508715 -410.388172) (xy 64.459125 -410.36553) (xy 64.413264 -410.336061) (xy 64.372063 -410.300364)
			(xy 64.336362 -410.259167) (xy 64.306888 -410.213308) (xy 64.284241 -410.163721) (xy 64.268882 -410.111416)
			(xy 64.261123 -410.057457) (xy 62.823612 -410.057457) (xy 62.815856 -410.111397) (xy 62.800502 -410.163691)
			(xy 62.777861 -410.213267) (xy 62.748395 -410.259116) (xy 62.712704 -410.300306) (xy 62.671515 -410.335996)
			(xy 62.625665 -410.365462) (xy 62.576089 -410.388102) (xy 62.523795 -410.403457) (xy 62.469849 -410.411213)
			(xy 62.442598 -410.411676) (xy 61.578998 -410.411676) (xy 61.551745 -410.411254) (xy 61.497793 -410.403497)
			(xy 61.445494 -410.38814) (xy 61.395913 -410.365497) (xy 61.350059 -410.336028) (xy 61.308865 -410.300334)
			(xy 61.273171 -410.25914) (xy 61.243702 -410.213286) (xy 61.221059 -410.163705) (xy 61.205703 -410.111406)
			(xy 61.197946 -410.057453) (xy 59.760413 -410.057453) (xy 59.752655 -410.111403) (xy 59.737298 -410.163699)
			(xy 59.714655 -410.213278) (xy 59.685185 -410.259129) (xy 59.64949 -410.30032) (xy 59.608296 -410.33601)
			(xy 59.562441 -410.365475) (xy 59.51286 -410.388113) (xy 59.460561 -410.403464) (xy 59.406611 -410.411216)
			(xy 59.379358 -410.411676) (xy 58.515758 -410.411676) (xy 58.488506 -410.411251) (xy 58.434559 -410.403489)
			(xy 58.382265 -410.388129) (xy 58.332689 -410.365484) (xy 58.28684 -410.336014) (xy 58.245651 -410.300319)
			(xy 58.209961 -410.259127) (xy 58.180496 -410.213275) (xy 58.157856 -410.163696) (xy 58.142502 -410.1114)
			(xy 58.134746 -410.057452) (xy 56.697089 -410.057452) (xy 56.689334 -410.11139) (xy 56.673982 -410.163679)
			(xy 56.651344 -410.21325) (xy 56.621882 -410.259096) (xy 56.586195 -410.300282) (xy 56.54501 -410.335971)
			(xy 56.499166 -410.365435) (xy 56.449595 -410.388075) (xy 56.397307 -410.403431) (xy 56.343366 -410.411189)
			(xy 56.316118 -410.411676) (xy 55.452518 -410.411676) (xy 55.425262 -410.411278) (xy 55.371305 -410.403523)
			(xy 55.319 -410.388167) (xy 55.269413 -410.365524) (xy 55.223554 -410.336054) (xy 55.182356 -410.300357)
			(xy 55.146657 -410.25916) (xy 55.117185 -410.213302) (xy 55.094539 -410.163717) (xy 55.079181 -410.111413)
			(xy 55.071423 -410.057456) (xy 53.633912 -410.057456) (xy 53.626156 -410.1114) (xy 53.6108 -410.163695)
			(xy 53.588158 -410.213273) (xy 53.55869 -410.259123) (xy 53.522997 -410.300313) (xy 53.481805 -410.336003)
			(xy 53.435953 -410.365468) (xy 53.386374 -410.388108) (xy 53.334078 -410.40346) (xy 53.28013 -410.411214)
			(xy 53.252878 -410.411676) (xy 52.389278 -410.411676) (xy 52.362025 -410.411253) (xy 52.308076 -410.403493)
			(xy 52.255779 -410.388135) (xy 52.206201 -410.36549) (xy 52.160349 -410.336021) (xy 52.119158 -410.300326)
			(xy 52.083466 -410.259133) (xy 52.053999 -410.21328) (xy 52.031358 -410.1637) (xy 52.016002 -410.111403)
			(xy 52.008246 -410.057453) (xy 50.570589 -410.057453) (xy 50.562835 -410.111387) (xy 50.547483 -410.163674)
			(xy 50.524847 -410.213245) (xy 50.495386 -410.259089) (xy 50.459702 -410.300275) (xy 50.41852 -410.335964)
			(xy 50.372678 -410.365428) (xy 50.32311 -410.38807) (xy 50.270824 -410.403427) (xy 50.216885 -410.411187)
			(xy 50.189638 -410.411676) (xy 49.326038 -410.411676) (xy 49.298781 -410.41128) (xy 49.244821 -410.403526)
			(xy 49.192515 -410.388172) (xy 49.142925 -410.36553) (xy 49.097064 -410.336061) (xy 49.055863 -410.300364)
			(xy 49.020162 -410.259167) (xy 48.990688 -410.213308) (xy 48.968041 -410.163721) (xy 48.952682 -410.111416)
			(xy 48.944923 -410.057457) (xy 8.024114 -410.057457) (xy 8.024114 -411.241049) (xy 101.876886 -411.241049)
			(xy 101.876886 -411.186551) (xy 101.884641 -411.132608) (xy 101.899994 -411.080318) (xy 101.922631 -411.030744)
			(xy 101.952093 -410.984897) (xy 101.98778 -410.943708) (xy 102.028964 -410.908017) (xy 102.074809 -410.878551)
			(xy 102.12438 -410.855908) (xy 102.176669 -410.840549) (xy 102.230611 -410.832788) (xy 102.25786 -410.8323)
			(xy 103.12146 -410.8323) (xy 103.148715 -410.832745) (xy 103.202672 -410.840497) (xy 103.254975 -410.85585)
			(xy 103.304562 -410.878491) (xy 103.350421 -410.907958) (xy 103.391619 -410.943653) (xy 103.427318 -410.984847)
			(xy 103.45679 -411.030703) (xy 103.479436 -411.080287) (xy 103.494794 -411.132589) (xy 103.502553 -411.186545)
			(xy 103.502553 -411.241055) (xy 103.494794 -411.295011) (xy 103.479436 -411.347313) (xy 103.45679 -411.396897)
			(xy 103.427318 -411.442753) (xy 103.391619 -411.483947) (xy 103.350421 -411.519642) (xy 103.304562 -411.549109)
			(xy 103.254975 -411.57175) (xy 103.202672 -411.587103) (xy 103.148715 -411.594855) (xy 103.12146 -411.595316)
			(xy 102.25786 -411.595316) (xy 102.230611 -411.594812) (xy 102.176669 -411.587051) (xy 102.12438 -411.571692)
			(xy 102.074809 -411.549049) (xy 102.028964 -411.519583) (xy 101.98778 -411.483892) (xy 101.952093 -411.442703)
			(xy 101.922631 -411.396856) (xy 101.899994 -411.347282) (xy 101.884641 -411.294992) (xy 101.876886 -411.241049)
			(xy 8.024114 -411.241049) (xy 8.024114 -424.470068) (xy 39.528496 -424.470068) (xy 39.528496 -417.770056)
			(xy 39.529001 -417.664532) (xy 39.537085 -417.453638) (xy 39.553241 -417.243209) (xy 39.577444 -417.033552)
			(xy 39.609661 -416.824977) (xy 39.649843 -416.617789) (xy 39.697931 -416.412292) (xy 39.753855 -416.208788)
			(xy 39.817532 -416.007575) (xy 39.88887 -415.808948) (xy 39.967764 -415.6132) (xy 40.054097 -415.420618)
			(xy 40.147744 -415.231483) (xy 40.248566 -415.046074) (xy 40.356416 -414.864663) (xy 40.471135 -414.687516)
			(xy 40.592555 -414.514894) (xy 40.720498 -414.347048) (xy 40.854776 -414.184226) (xy 40.995192 -414.026667)
			(xy 41.14154 -413.874602) (xy 41.293605 -413.728254) (xy 41.451164 -413.587838) (xy 41.613986 -413.45356)
			(xy 41.781832 -413.325617) (xy 41.954454 -413.204197) (xy 42.131601 -413.089478) (xy 42.313012 -412.981628)
			(xy 42.498421 -412.880806) (xy 42.687556 -412.787159) (xy 42.880138 -412.700826) (xy 43.075886 -412.621932)
			(xy 43.274513 -412.550594) (xy 43.475726 -412.486917) (xy 43.67923 -412.430993) (xy 43.884727 -412.382905)
			(xy 44.091915 -412.342723) (xy 44.30049 -412.310506) (xy 44.510147 -412.286303) (xy 44.720576 -412.270147)
			(xy 44.93147 -412.262063) (xy 45.142518 -412.262063) (xy 45.353412 -412.270147) (xy 45.563841 -412.286303)
			(xy 45.773498 -412.310506) (xy 45.982073 -412.342723) (xy 46.189261 -412.382905) (xy 46.394758 -412.430993)
			(xy 46.598262 -412.486917) (xy 46.799475 -412.550594) (xy 46.998102 -412.621932) (xy 47.19385 -412.700826)
			(xy 47.386432 -412.787159) (xy 47.575567 -412.880806) (xy 47.760976 -412.981628) (xy 47.942387 -413.089478)
			(xy 48.119534 -413.204197) (xy 48.292156 -413.325617) (xy 48.460002 -413.45356) (xy 48.622824 -413.587838)
			(xy 48.649451 -413.611568) (xy 104.877616 -413.611568) (xy 104.877616 -412.747968) (xy 104.878102 -412.720717)
			(xy 104.885858 -412.666769) (xy 104.901213 -412.614474) (xy 104.923855 -412.564897) (xy 104.953321 -412.519047)
			(xy 104.989012 -412.477856) (xy 105.030203 -412.442165) (xy 105.076053 -412.412699) (xy 105.12563 -412.390057)
			(xy 105.177925 -412.374702) (xy 105.231873 -412.366946) (xy 105.286375 -412.366946) (xy 105.340323 -412.374702)
			(xy 105.392618 -412.390057) (xy 105.442195 -412.412699) (xy 105.488045 -412.442165) (xy 105.529236 -412.477856)
			(xy 105.564927 -412.519047) (xy 105.594393 -412.564897) (xy 105.617035 -412.614474) (xy 105.63239 -412.666769)
			(xy 105.640146 -412.720717) (xy 105.640632 -412.747968) (xy 105.640632 -413.611568) (xy 105.640146 -413.638819)
			(xy 105.63239 -413.692767) (xy 105.617035 -413.745062) (xy 105.594393 -413.794639) (xy 105.584722 -413.809688)
			(xy 116.689632 -413.809688) (xy 116.689632 -412.946088) (xy 116.690118 -412.918837) (xy 116.697874 -412.864889)
			(xy 116.713229 -412.812594) (xy 116.735871 -412.763017) (xy 116.765337 -412.717167) (xy 116.801028 -412.675976)
			(xy 116.842219 -412.640285) (xy 116.888069 -412.610819) (xy 116.937646 -412.588177) (xy 116.989941 -412.572822)
			(xy 117.043889 -412.565066) (xy 117.098391 -412.565066) (xy 117.152339 -412.572822) (xy 117.204634 -412.588177)
			(xy 117.254211 -412.610819) (xy 117.300061 -412.640285) (xy 117.341252 -412.675976) (xy 117.376943 -412.717167)
			(xy 117.406409 -412.763017) (xy 117.429051 -412.812594) (xy 117.444406 -412.864889) (xy 117.452162 -412.918837)
			(xy 117.452648 -412.946088) (xy 117.452648 -413.809688) (xy 117.452162 -413.836939) (xy 117.444406 -413.890887)
			(xy 117.429051 -413.943182) (xy 117.406409 -413.992759) (xy 117.376943 -414.038609) (xy 117.341252 -414.0798)
			(xy 117.300061 -414.115491) (xy 117.254211 -414.144957) (xy 117.204634 -414.167599) (xy 117.152339 -414.182954)
			(xy 117.098391 -414.19071) (xy 117.043889 -414.19071) (xy 116.989941 -414.182954) (xy 116.937646 -414.167599)
			(xy 116.888069 -414.144957) (xy 116.842219 -414.115491) (xy 116.801028 -414.0798) (xy 116.765337 -414.038609)
			(xy 116.735871 -413.992759) (xy 116.713229 -413.943182) (xy 116.697874 -413.890887) (xy 116.690118 -413.836939)
			(xy 116.689632 -413.809688) (xy 105.584722 -413.809688) (xy 105.564927 -413.840489) (xy 105.529236 -413.88168)
			(xy 105.488045 -413.917371) (xy 105.442195 -413.946837) (xy 105.392618 -413.969479) (xy 105.340323 -413.984834)
			(xy 105.286375 -413.99259) (xy 105.231873 -413.99259) (xy 105.177925 -413.984834) (xy 105.12563 -413.969479)
			(xy 105.076053 -413.946837) (xy 105.030203 -413.917371) (xy 104.989012 -413.88168) (xy 104.953321 -413.840489)
			(xy 104.923855 -413.794639) (xy 104.901213 -413.745062) (xy 104.885858 -413.692767) (xy 104.878102 -413.638819)
			(xy 104.877616 -413.611568) (xy 48.649451 -413.611568) (xy 48.780383 -413.728254) (xy 48.932448 -413.874602)
			(xy 49.078796 -414.026667) (xy 49.219212 -414.184226) (xy 49.35349 -414.347048) (xy 49.481433 -414.514894)
			(xy 49.602853 -414.687516) (xy 49.717572 -414.864663) (xy 49.825422 -415.046074) (xy 49.926244 -415.231483)
			(xy 50.019891 -415.420618) (xy 50.106224 -415.6132) (xy 50.133819 -415.681668) (xy 100.559616 -415.681668)
			(xy 100.559616 -414.818068) (xy 100.560102 -414.790817) (xy 100.567858 -414.736869) (xy 100.583213 -414.684574)
			(xy 100.605855 -414.634997) (xy 100.635321 -414.589147) (xy 100.671012 -414.547956) (xy 100.712203 -414.512265)
			(xy 100.758053 -414.482799) (xy 100.80763 -414.460157) (xy 100.859925 -414.444802) (xy 100.913873 -414.437046)
			(xy 100.968375 -414.437046) (xy 101.022323 -414.444802) (xy 101.074618 -414.460157) (xy 101.124195 -414.482799)
			(xy 101.170045 -414.512265) (xy 101.211236 -414.547956) (xy 101.246927 -414.589147) (xy 101.276393 -414.634997)
			(xy 101.299035 -414.684574) (xy 101.31439 -414.736869) (xy 101.322146 -414.790817) (xy 101.322632 -414.818068)
			(xy 101.322632 -415.681668) (xy 101.322146 -415.708919) (xy 101.31439 -415.762867) (xy 101.299035 -415.815162)
			(xy 101.276393 -415.864739) (xy 101.246927 -415.910589) (xy 101.211236 -415.95178) (xy 101.170045 -415.987471)
			(xy 101.124195 -416.016937) (xy 101.074618 -416.039579) (xy 101.022323 -416.054934) (xy 100.968375 -416.06269)
			(xy 100.913873 -416.06269) (xy 100.859925 -416.054934) (xy 100.80763 -416.039579) (xy 100.758053 -416.016937)
			(xy 100.712203 -415.987471) (xy 100.671012 -415.95178) (xy 100.635321 -415.910589) (xy 100.605855 -415.864739)
			(xy 100.583213 -415.815162) (xy 100.567858 -415.762867) (xy 100.560102 -415.708919) (xy 100.559616 -415.681668)
			(xy 50.133819 -415.681668) (xy 50.185118 -415.808948) (xy 50.256456 -416.007575) (xy 50.320133 -416.208788)
			(xy 50.376057 -416.412292) (xy 50.424145 -416.617789) (xy 50.464327 -416.824977) (xy 50.496544 -417.033552)
			(xy 50.520747 -417.243209) (xy 50.536903 -417.453638) (xy 50.544987 -417.664532) (xy 50.545492 -417.770056)
			(xy 50.545492 -420.089838) (xy 58.13806 -420.089838) (xy 58.138171 -420.074752) (xy 58.139951 -420.044634)
			(xy 58.141616 -420.02964) (xy 58.141616 -418.95014) (xy 58.139949 -418.935146) (xy 58.138169 -418.905028)
			(xy 58.13806 -418.889942) (xy 58.138171 -418.874856) (xy 58.139951 -418.844738) (xy 58.141616 -418.829744)
			(xy 58.141616 -418.218874) (xy 58.142085 -418.206785) (xy 58.149546 -418.183788) (xy 58.163733 -418.164211)
			(xy 58.183264 -418.14996) (xy 58.206237 -418.142424) (xy 58.218324 -418.141912) (xy 59.158124 -418.141912)
			(xy 59.170235 -418.142296) (xy 59.193265 -418.149803) (xy 59.212839 -418.164073) (xy 59.227033 -418.183702)
			(xy 59.234451 -418.206761) (xy 59.234832 -418.218874) (xy 59.234832 -420.760398) (xy 59.23439 -420.77249)
			(xy 59.226931 -420.795495) (xy 59.212739 -420.815078) (xy 59.193198 -420.829327) (xy 59.170215 -420.836854)
			(xy 59.158124 -420.83736) (xy 58.218324 -420.83736) (xy 58.206212 -420.836963) (xy 58.183179 -420.829465)
			(xy 58.163602 -420.8152) (xy 58.149408 -420.795571) (xy 58.141994 -420.772511) (xy 58.141616 -420.760398)
			(xy 58.141616 -420.150036) (xy 58.139948 -420.135042) (xy 58.138169 -420.104924) (xy 58.13806 -420.089838)
			(xy 50.545492 -420.089838) (xy 50.545492 -421.089836) (xy 60.138056 -421.089836) (xy 60.138167 -421.07475)
			(xy 60.139947 -421.044632) (xy 60.141612 -421.029638) (xy 60.141612 -419.950138) (xy 60.139945 -419.935144)
			(xy 60.138165 -419.905026) (xy 60.138056 -419.88994) (xy 60.138167 -419.874854) (xy 60.139947 -419.844736)
			(xy 60.141612 -419.829742) (xy 60.141612 -419.218872) (xy 60.14204 -419.206794) (xy 60.149513 -419.183822)
			(xy 60.163718 -419.164284) (xy 60.183265 -419.150091) (xy 60.206242 -419.142633) (xy 60.21832 -419.142164)
			(xy 61.15812 -419.142164) (xy 61.170193 -419.142647) (xy 61.193156 -419.150112) (xy 61.21269 -419.164304)
			(xy 61.226885 -419.183837) (xy 61.234352 -419.206799) (xy 61.234828 -419.218872) (xy 61.234828 -421.089836)
			(xy 68.13804 -421.089836) (xy 68.138151 -421.07475) (xy 68.139931 -421.044632) (xy 68.141596 -421.029638)
			(xy 68.141596 -419.950138) (xy 68.139929 -419.935144) (xy 68.138149 -419.905026) (xy 68.13804 -419.88994)
			(xy 68.138151 -419.874854) (xy 68.139931 -419.844736) (xy 68.141596 -419.829742) (xy 68.141596 -419.218872)
			(xy 68.14204 -419.206796) (xy 68.149511 -419.183827) (xy 68.163712 -419.16429) (xy 68.183255 -419.150096)
			(xy 68.206227 -419.142635) (xy 68.218304 -419.142164) (xy 69.158104 -419.142164) (xy 69.170176 -419.14266)
			(xy 69.193139 -419.150121) (xy 69.212673 -419.16431) (xy 69.226868 -419.18384) (xy 69.234336 -419.2068)
			(xy 69.234812 -419.218872) (xy 69.234812 -420.089838) (xy 70.138036 -420.089838) (xy 70.138149 -420.074753)
			(xy 70.139929 -420.044634) (xy 70.141592 -420.02964) (xy 70.141592 -418.95014) (xy 70.139925 -418.935146)
			(xy 70.138145 -418.905028) (xy 70.138036 -418.889942) (xy 70.13815 -418.874857) (xy 70.139929 -418.844738)
			(xy 70.141592 -418.829744) (xy 70.141592 -418.218874) (xy 70.142084 -418.206788) (xy 70.149542 -418.183794)
			(xy 70.163724 -418.164219) (xy 70.183249 -418.149968) (xy 70.206216 -418.142428) (xy 70.2183 -418.141912)
			(xy 71.1581 -418.141912) (xy 71.17021 -418.142316) (xy 71.193239 -418.149817) (xy 71.212814 -418.164081)
			(xy 71.227008 -418.183706) (xy 71.234426 -418.206762) (xy 71.234808 -418.218874) (xy 71.234808 -420.760398)
			(xy 71.234292 -420.772483) (xy 71.226841 -420.795475) (xy 71.212666 -420.815051) (xy 71.193146 -420.829303)
			(xy 71.170183 -420.836844) (xy 71.1581 -420.83736) (xy 70.2183 -420.83736) (xy 70.206187 -420.836983)
			(xy 70.183153 -420.829479) (xy 70.163576 -420.815209) (xy 70.149383 -420.795576) (xy 70.14197 -420.772512)
			(xy 70.141592 -420.760398) (xy 70.141592 -420.150036) (xy 70.139924 -420.135042) (xy 70.138145 -420.104924)
			(xy 70.138036 -420.089838) (xy 69.234812 -420.089838) (xy 69.234812 -421.089836) (xy 72.138032 -421.089836)
			(xy 72.138145 -421.074751) (xy 72.139925 -421.044632) (xy 72.141588 -421.029638) (xy 72.141588 -419.950138)
			(xy 72.13992 -419.935144) (xy 72.138141 -419.905026) (xy 72.138032 -419.88994) (xy 72.138145 -419.874855)
			(xy 72.139925 -419.844736) (xy 72.141588 -419.829742) (xy 72.141588 -419.218872) (xy 72.14204 -419.206796)
			(xy 72.14951 -419.183829) (xy 72.16371 -419.164293) (xy 72.18325 -419.150099) (xy 72.20622 -419.142636)
			(xy 72.218296 -419.142164) (xy 73.158096 -419.142164) (xy 73.170168 -419.142667) (xy 73.19313 -419.150125)
			(xy 73.212665 -419.164313) (xy 73.22686 -419.183841) (xy 73.234328 -419.206801) (xy 73.234804 -419.218872)
			(xy 73.234804 -419.702852) (xy 110.957342 -419.702852) (xy 110.957342 -419.648348) (xy 110.965098 -419.594399)
			(xy 110.980453 -419.542102) (xy 111.003093 -419.492523) (xy 111.032558 -419.44667) (xy 111.068249 -419.405477)
			(xy 111.109438 -419.369782) (xy 111.155288 -419.340312) (xy 111.204865 -419.317667) (xy 111.25716 -419.302306)
			(xy 111.311108 -419.294545) (xy 111.33836 -419.294056) (xy 112.20196 -419.294056) (xy 112.229212 -419.294589)
			(xy 112.283162 -419.30234) (xy 112.33546 -419.317691) (xy 112.385041 -419.340329) (xy 112.430894 -419.369793)
			(xy 112.472088 -419.405484) (xy 112.507783 -419.446674) (xy 112.537251 -419.492524) (xy 112.559895 -419.542102)
			(xy 112.575251 -419.594399) (xy 112.583009 -419.648348) (xy 112.583009 -419.702852) (xy 112.575251 -419.756801)
			(xy 112.559895 -419.809098) (xy 112.537251 -419.858676) (xy 112.507783 -419.904526) (xy 112.472088 -419.945716)
			(xy 112.430894 -419.981407) (xy 112.385041 -420.010871) (xy 112.33546 -420.033509) (xy 112.283162 -420.04886)
			(xy 112.229212 -420.056611) (xy 112.20196 -420.057072) (xy 111.33836 -420.057072) (xy 111.311108 -420.056655)
			(xy 111.25716 -420.048894) (xy 111.204865 -420.033533) (xy 111.155288 -420.010888) (xy 111.109438 -419.981418)
			(xy 111.068249 -419.945723) (xy 111.032558 -419.90453) (xy 111.003093 -419.858677) (xy 110.980453 -419.809098)
			(xy 110.965098 -419.756801) (xy 110.957342 -419.702852) (xy 73.234804 -419.702852) (xy 73.234804 -421.760396)
			(xy 73.234384 -421.772479) (xy 73.226917 -421.795462) (xy 73.212713 -421.815013) (xy 73.193162 -421.829217)
			(xy 73.170179 -421.836684) (xy 73.158096 -421.837104) (xy 72.218296 -421.837104) (xy 72.206221 -421.836639)
			(xy 72.183253 -421.829175) (xy 72.163716 -421.814979) (xy 72.149521 -421.79544) (xy 72.14206 -421.772471)
			(xy 72.141588 -421.760396) (xy 72.141588 -421.150034) (xy 72.13992 -421.13504) (xy 72.138141 -421.104922)
			(xy 72.138032 -421.089836) (xy 69.234812 -421.089836) (xy 69.234812 -421.760396) (xy 69.234332 -421.77247)
			(xy 69.226871 -421.795436) (xy 69.212679 -421.814973) (xy 69.193143 -421.829168) (xy 69.170178 -421.836631)
			(xy 69.158104 -421.837104) (xy 68.218304 -421.837104) (xy 68.206221 -421.836684) (xy 68.183238 -421.829217)
			(xy 68.163687 -421.815013) (xy 68.149483 -421.795462) (xy 68.142016 -421.772479) (xy 68.141596 -421.760396)
			(xy 68.141596 -421.150034) (xy 68.139928 -421.13504) (xy 68.138149 -421.104922) (xy 68.13804 -421.089836)
			(xy 61.234828 -421.089836) (xy 61.234828 -421.760396) (xy 61.234333 -421.772468) (xy 61.226874 -421.795432)
			(xy 61.212684 -421.814967) (xy 61.193154 -421.829163) (xy 61.170192 -421.836629) (xy 61.15812 -421.837104)
			(xy 60.21832 -421.837104) (xy 60.206238 -421.83667) (xy 60.183255 -421.829208) (xy 60.163704 -421.815007)
			(xy 60.1495 -421.795459) (xy 60.142032 -421.772478) (xy 60.141612 -421.760396) (xy 60.141612 -421.150034)
			(xy 60.139944 -421.13504) (xy 60.138165 -421.104922) (xy 60.138056 -421.089836) (xy 50.545492 -421.089836)
			(xy 50.545492 -423.68978) (xy 58.13806 -423.68978) (xy 58.138175 -423.674695) (xy 58.139953 -423.644576)
			(xy 58.141616 -423.629582) (xy 58.141616 -422.550082) (xy 58.139952 -422.535088) (xy 58.138171 -422.50497)
			(xy 58.13806 -422.489884) (xy 58.138175 -422.474799) (xy 58.139953 -422.44468) (xy 58.141616 -422.429686)
			(xy 58.141616 -421.81907) (xy 58.142081 -421.806981) (xy 58.149543 -421.783984) (xy 58.163731 -421.764406)
			(xy 58.183263 -421.750156) (xy 58.206237 -421.74262) (xy 58.218324 -421.742108) (xy 59.158124 -421.742108)
			(xy 59.170235 -421.742496) (xy 59.193264 -421.750003) (xy 59.212838 -421.764272) (xy 59.227031 -421.783899)
			(xy 59.23445 -421.806958) (xy 59.234832 -421.81907) (xy 59.234832 -423.68978) (xy 62.138052 -423.68978)
			(xy 62.138167 -423.674695) (xy 62.139945 -423.644576) (xy 62.141608 -423.629582) (xy 62.141608 -422.550082)
			(xy 62.139944 -422.535088) (xy 62.138163 -422.50497) (xy 62.138052 -422.489884) (xy 62.138167 -422.474799)
			(xy 62.139945 -422.44468) (xy 62.141608 -422.429686) (xy 62.141608 -421.81907) (xy 62.142081 -421.806982)
			(xy 62.149542 -421.783986) (xy 62.163728 -421.764409) (xy 62.183258 -421.750158) (xy 62.20623 -421.742621)
			(xy 62.218316 -421.742108) (xy 63.158116 -421.742108) (xy 63.170227 -421.742503) (xy 63.193256 -421.750008)
			(xy 63.212829 -421.764274) (xy 63.227023 -421.783901) (xy 63.234442 -421.806958) (xy 63.234824 -421.81907)
			(xy 63.234824 -424.360594) (xy 63.234387 -424.372687) (xy 63.226927 -424.395693) (xy 63.212734 -424.415276)
			(xy 63.193192 -424.429526) (xy 63.170207 -424.437051) (xy 63.158116 -424.437556) (xy 62.218316 -424.437556)
			(xy 62.206214 -424.437071) (xy 62.183196 -424.429582) (xy 62.163628 -424.415337) (xy 62.149431 -424.395733)
			(xy 62.142 -424.372697) (xy 62.141608 -424.360594) (xy 62.141608 -423.749978) (xy 62.139944 -423.734984)
			(xy 62.138162 -423.704866) (xy 62.138052 -423.68978) (xy 59.234832 -423.68978) (xy 59.234832 -424.360594)
			(xy 59.234387 -424.372686) (xy 59.226928 -424.395691) (xy 59.212737 -424.415274) (xy 59.193197 -424.429523)
			(xy 59.170215 -424.43705) (xy 59.158124 -424.437556) (xy 58.218324 -424.437556) (xy 58.206222 -424.437064)
			(xy 58.183205 -424.429578) (xy 58.163637 -424.415334) (xy 58.149439 -424.395732) (xy 58.142008 -424.372697)
			(xy 58.141616 -424.360594) (xy 58.141616 -423.749978) (xy 58.139952 -423.734984) (xy 58.13817 -423.704866)
			(xy 58.13806 -423.68978) (xy 50.545492 -423.68978) (xy 50.545492 -424.470068) (xy 50.544987 -424.575592)
			(xy 50.54061 -424.689778) (xy 64.138048 -424.689778) (xy 64.138163 -424.674693) (xy 64.139941 -424.644574)
			(xy 64.141604 -424.62958) (xy 64.141604 -423.55008) (xy 64.13994 -423.535086) (xy 64.138158 -423.504968)
			(xy 64.138048 -423.489882) (xy 64.138163 -423.474797) (xy 64.139941 -423.444678) (xy 64.141604 -423.429684)
			(xy 64.141604 -422.819068) (xy 64.142037 -422.806991) (xy 64.14951 -422.78402) (xy 64.163714 -422.764483)
			(xy 64.18326 -422.75029) (xy 64.206234 -422.74283) (xy 64.218312 -422.74236) (xy 65.158112 -422.74236)
			(xy 65.170184 -422.742854) (xy 65.193146 -422.750316) (xy 65.21268 -422.764506) (xy 65.226875 -422.784036)
			(xy 65.234343 -422.806996) (xy 65.23482 -422.819068) (xy 65.23482 -424.689778) (xy 68.13804 -424.689778)
			(xy 68.138155 -424.674693) (xy 68.139933 -424.644574) (xy 68.141596 -424.62958) (xy 68.141596 -423.55008)
			(xy 68.139932 -423.535086) (xy 68.13815 -423.504968) (xy 68.13804 -423.489882) (xy 68.138155 -423.474797)
			(xy 68.139933 -423.444678) (xy 68.141596 -423.429684) (xy 68.141596 -422.819068) (xy 68.142037 -422.806991)
			(xy 68.149509 -422.784022) (xy 68.163711 -422.764485) (xy 68.183255 -422.750292) (xy 68.206227 -422.742831)
			(xy 68.218304 -422.74236) (xy 69.158104 -422.74236) (xy 69.170176 -422.74286) (xy 69.193137 -422.75032)
			(xy 69.212672 -422.764508) (xy 69.226867 -422.784037) (xy 69.234335 -422.806997) (xy 69.234812 -422.819068)
			(xy 69.234812 -423.68978) (xy 70.138036 -423.68978) (xy 70.138153 -423.674695) (xy 70.139931 -423.644576)
			(xy 70.141592 -423.629582) (xy 70.141592 -422.550082) (xy 70.139928 -422.535088) (xy 70.138147 -422.50497)
			(xy 70.138036 -422.489884) (xy 70.138153 -422.474799) (xy 70.139931 -422.44468) (xy 70.141592 -422.429686)
			(xy 70.141592 -421.81907) (xy 70.142081 -421.806984) (xy 70.14954 -421.78399) (xy 70.163723 -421.764415)
			(xy 70.183248 -421.750163) (xy 70.206215 -421.742624) (xy 70.2183 -421.742108) (xy 71.1581 -421.742108)
			(xy 71.17021 -421.742516) (xy 71.193238 -421.750017) (xy 71.212812 -421.76428) (xy 71.227007 -421.783904)
			(xy 71.234426 -421.806959) (xy 71.234808 -421.81907) (xy 71.234808 -424.360594) (xy 71.234288 -424.372678)
			(xy 71.226839 -424.395671) (xy 71.212664 -424.415247) (xy 71.193145 -424.429499) (xy 71.170183 -424.43704)
			(xy 71.1581 -424.437556) (xy 70.2183 -424.437556) (xy 70.206197 -424.437085) (xy 70.183179 -424.429592)
			(xy 70.163611 -424.415343) (xy 70.149414 -424.395736) (xy 70.141983 -424.372698) (xy 70.141592 -424.360594)
			(xy 70.141592 -423.749978) (xy 70.139928 -423.734984) (xy 70.138146 -423.704866) (xy 70.138036 -423.68978)
			(xy 69.234812 -423.68978) (xy 69.234812 -424.689778) (xy 72.138032 -424.689778) (xy 72.138149 -424.674693)
			(xy 72.139927 -424.644574) (xy 72.141588 -424.62958) (xy 72.141588 -423.55008) (xy 72.139924 -423.535086)
			(xy 72.138142 -423.504968) (xy 72.138032 -423.489882) (xy 72.138149 -423.474797) (xy 72.139927 -423.444678)
			(xy 72.141588 -423.429684) (xy 72.141588 -422.819068) (xy 72.142037 -422.806992) (xy 72.149508 -422.784025)
			(xy 72.163708 -422.764488) (xy 72.18325 -422.750295) (xy 72.20622 -422.742832) (xy 72.218296 -422.74236)
			(xy 73.158096 -422.74236) (xy 73.170167 -422.742867) (xy 73.193129 -422.750325) (xy 73.212663 -422.764511)
			(xy 73.226859 -422.784039) (xy 73.234327 -422.806997) (xy 73.234804 -422.819068) (xy 73.234804 -425.360592)
			(xy 73.234381 -425.372675) (xy 73.226915 -425.395658) (xy 73.212712 -425.415209) (xy 73.193162 -425.429413)
			(xy 73.170179 -425.43688) (xy 73.158096 -425.4373) (xy 72.218296 -425.4373) (xy 72.206212 -425.436891)
			(xy 72.183228 -425.429421) (xy 72.163677 -425.415214) (xy 72.149473 -425.395661) (xy 72.142007 -425.372676)
			(xy 72.141588 -425.360592) (xy 72.141588 -424.749976) (xy 72.139924 -424.734982) (xy 72.138142 -424.704864)
			(xy 72.138032 -424.689778) (xy 69.234812 -424.689778) (xy 69.234812 -425.360592) (xy 69.234381 -425.372674)
			(xy 69.226916 -425.395656) (xy 69.212714 -425.415206) (xy 69.193167 -425.429411) (xy 69.170186 -425.436879)
			(xy 69.158104 -425.4373) (xy 68.218304 -425.4373) (xy 68.206221 -425.436884) (xy 68.183237 -425.429417)
			(xy 68.163686 -425.415212) (xy 68.149482 -425.39566) (xy 68.142015 -425.372675) (xy 68.141596 -425.360592)
			(xy 68.141596 -424.749976) (xy 68.139932 -424.734982) (xy 68.13815 -424.704864) (xy 68.13804 -424.689778)
			(xy 65.23482 -424.689778) (xy 65.23482 -425.360592) (xy 65.234329 -425.372665) (xy 65.22687 -425.39563)
			(xy 65.21268 -425.415166) (xy 65.193148 -425.429361) (xy 65.170185 -425.436826) (xy 65.158112 -425.4373)
			(xy 64.218312 -425.4373) (xy 64.206229 -425.436877) (xy 64.183246 -425.429412) (xy 64.163694 -425.415208)
			(xy 64.14949 -425.395658) (xy 64.142024 -425.372675) (xy 64.141604 -425.360592) (xy 64.141604 -424.749976)
			(xy 64.13994 -424.734982) (xy 64.138158 -424.704864) (xy 64.138048 -424.689778) (xy 50.54061 -424.689778)
			(xy 50.536903 -424.786486) (xy 50.520747 -424.996915) (xy 50.496544 -425.206572) (xy 50.464327 -425.415147)
			(xy 50.424145 -425.622335) (xy 50.376057 -425.827832) (xy 50.320133 -426.031336) (xy 50.256456 -426.232549)
			(xy 50.185118 -426.431176) (xy 50.106224 -426.626924) (xy 50.019891 -426.819506) (xy 49.926244 -427.008641)
			(xy 49.825422 -427.19405) (xy 49.768393 -427.289976) (xy 58.13806 -427.289976) (xy 58.138174 -427.274891)
			(xy 58.139952 -427.244772) (xy 58.141616 -427.229778) (xy 58.141616 -426.150024) (xy 58.139947 -426.135031)
			(xy 58.138169 -426.104912) (xy 58.13806 -426.089826) (xy 58.13817 -426.07474) (xy 58.139951 -426.044622)
			(xy 58.141616 -426.029628) (xy 58.141616 -425.419012) (xy 58.142023 -425.406928) (xy 58.149491 -425.383941)
			(xy 58.163697 -425.364389) (xy 58.183252 -425.350185) (xy 58.206239 -425.342722) (xy 58.218324 -425.342304)
			(xy 59.158124 -425.342304) (xy 59.170201 -425.342744) (xy 59.193171 -425.350215) (xy 59.212709 -425.364417)
			(xy 59.226902 -425.383961) (xy 59.234361 -425.406935) (xy 59.234832 -425.419012) (xy 59.234832 -427.960536)
			(xy 59.234367 -427.97261) (xy 59.226898 -427.995574) (xy 59.2127 -428.015109) (xy 59.193164 -428.029303)
			(xy 59.170198 -428.036769) (xy 59.158124 -428.037244) (xy 58.218324 -428.037244) (xy 58.206254 -428.036716)
			(xy 58.183294 -428.029264) (xy 58.16376 -428.015083) (xy 58.149563 -427.99556) (xy 58.142093 -427.972605)
			(xy 58.141616 -427.960536) (xy 58.141616 -427.350174) (xy 58.139952 -427.33518) (xy 58.13817 -427.305062)
			(xy 58.13806 -427.289976) (xy 49.768393 -427.289976) (xy 49.717572 -427.375461) (xy 49.602853 -427.552608)
			(xy 49.481433 -427.72523) (xy 49.35349 -427.893076) (xy 49.219212 -428.055898) (xy 49.078796 -428.213457)
			(xy 49.0054 -428.28972) (xy 60.138056 -428.28972) (xy 60.138166 -428.274634) (xy 60.139947 -428.244516)
			(xy 60.141612 -428.229522) (xy 60.141612 -427.150022) (xy 60.139943 -427.135029) (xy 60.138165 -427.10491)
			(xy 60.138056 -427.089824) (xy 60.138166 -427.074738) (xy 60.139947 -427.04462) (xy 60.141612 -427.029626)
			(xy 60.141612 -426.41901) (xy 60.142115 -426.406924) (xy 60.149566 -426.383928) (xy 60.163744 -426.364351)
			(xy 60.183268 -426.350099) (xy 60.206236 -426.342562) (xy 60.21832 -426.342048) (xy 61.15812 -426.342048)
			(xy 61.170225 -426.342499) (xy 61.193244 -426.349997) (xy 61.212812 -426.364252) (xy 61.227008 -426.383863)
			(xy 61.234437 -426.406904) (xy 61.234828 -426.41901) (xy 61.234828 -427.289976) (xy 62.138052 -427.289976)
			(xy 62.138166 -427.274891) (xy 62.139944 -427.244772) (xy 62.141608 -427.229778) (xy 62.141608 -426.150024)
			(xy 62.139939 -426.135031) (xy 62.138161 -426.104912) (xy 62.138052 -426.089826) (xy 62.138162 -426.07474)
			(xy 62.139943 -426.044622) (xy 62.141608 -426.029628) (xy 62.141608 -425.419012) (xy 62.142023 -425.406928)
			(xy 62.149489 -425.383943) (xy 62.163694 -425.364392) (xy 62.183247 -425.350188) (xy 62.206232 -425.342723)
			(xy 62.218316 -425.342304) (xy 63.158116 -425.342304) (xy 63.170193 -425.342751) (xy 63.193162 -425.350219)
			(xy 63.2127 -425.36442) (xy 63.226894 -425.383963) (xy 63.234353 -425.406935) (xy 63.234824 -425.419012)
			(xy 63.234824 -427.960536) (xy 63.234367 -427.972611) (xy 63.226896 -427.995577) (xy 63.212697 -428.015112)
			(xy 63.193159 -428.029306) (xy 63.170191 -428.03677) (xy 63.158116 -428.037244) (xy 62.218316 -428.037244)
			(xy 62.206246 -428.036723) (xy 62.183285 -428.029269) (xy 62.163751 -428.015086) (xy 62.149555 -427.995561)
			(xy 62.142085 -427.972606) (xy 62.141608 -427.960536) (xy 62.141608 -427.350174) (xy 62.139944 -427.33518)
			(xy 62.138162 -427.305062) (xy 62.138052 -427.289976) (xy 61.234828 -427.289976) (xy 61.234828 -428.28972)
			(xy 64.138048 -428.28972) (xy 64.138158 -428.274634) (xy 64.139939 -428.244516) (xy 64.141604 -428.229522)
			(xy 64.141604 -427.150022) (xy 64.139935 -427.135029) (xy 64.138157 -427.10491) (xy 64.138048 -427.089824)
			(xy 64.138158 -427.074738) (xy 64.139939 -427.04462) (xy 64.141604 -427.029626) (xy 64.141604 -426.41901)
			(xy 64.142115 -426.406925) (xy 64.149565 -426.38393) (xy 64.163741 -426.364353) (xy 64.183263 -426.350101)
			(xy 64.206228 -426.342563) (xy 64.218312 -426.342048) (xy 65.158112 -426.342048) (xy 65.170216 -426.342505)
			(xy 65.193235 -426.350002) (xy 65.212804 -426.364255) (xy 65.227 -426.383864) (xy 65.234429 -426.406905)
			(xy 65.23482 -426.41901) (xy 65.23482 -427.289976) (xy 66.138044 -427.289976) (xy 66.138159 -427.274891)
			(xy 66.139936 -427.244772) (xy 66.1416 -427.229778) (xy 66.1416 -426.150024) (xy 66.139931 -426.135031)
			(xy 66.138153 -426.104912) (xy 66.138044 -426.089826) (xy 66.138154 -426.07474) (xy 66.139935 -426.044622)
			(xy 66.1416 -426.029628) (xy 66.1416 -425.419012) (xy 66.142023 -425.406929) (xy 66.149488 -425.383946)
			(xy 66.163692 -425.364394) (xy 66.183242 -425.35019) (xy 66.206225 -425.342724) (xy 66.218308 -425.342304)
			(xy 67.158108 -425.342304) (xy 67.170192 -425.342706) (xy 67.193177 -425.350177) (xy 67.212729 -425.364386)
			(xy 67.226932 -425.383941) (xy 67.234397 -425.406928) (xy 67.234816 -425.419012) (xy 67.234816 -427.960536)
			(xy 67.234367 -427.972612) (xy 67.226895 -427.995579) (xy 67.212695 -428.015115) (xy 67.193154 -428.029308)
			(xy 67.170184 -428.036771) (xy 67.158108 -428.037244) (xy 66.218308 -428.037244) (xy 66.206237 -428.03673)
			(xy 66.183277 -428.029274) (xy 66.163743 -428.015089) (xy 66.149547 -427.995563) (xy 66.142077 -427.972606)
			(xy 66.1416 -427.960536) (xy 66.1416 -427.350174) (xy 66.139936 -427.33518) (xy 66.138154 -427.305062)
			(xy 66.138044 -427.289976) (xy 65.23482 -427.289976) (xy 65.23482 -428.28972) (xy 68.13804 -428.28972)
			(xy 68.138152 -428.274634) (xy 68.139933 -428.244516) (xy 68.141596 -428.229522) (xy 68.141596 -427.150022)
			(xy 68.139927 -427.135029) (xy 68.138149 -427.10491) (xy 68.13804 -427.089824) (xy 68.13815 -427.074738)
			(xy 68.139931 -427.04462) (xy 68.141596 -427.029626) (xy 68.141596 -426.41901) (xy 68.142115 -426.406925)
			(xy 68.149564 -426.383932) (xy 68.163739 -426.364356) (xy 68.183258 -426.350104) (xy 68.206221 -426.342564)
			(xy 68.218304 -426.342048) (xy 69.158104 -426.342048) (xy 69.170208 -426.342512) (xy 69.193227 -426.350006)
			(xy 69.212795 -426.364257) (xy 69.226991 -426.383866) (xy 69.234421 -426.406905) (xy 69.234812 -426.41901)
			(xy 69.234812 -427.289976) (xy 70.138036 -427.289976) (xy 70.138153 -427.274891) (xy 70.13993 -427.244772)
			(xy 70.141592 -427.229778) (xy 70.141592 -426.150024) (xy 70.139923 -426.135031) (xy 70.138145 -426.104912)
			(xy 70.138036 -426.089826) (xy 70.138148 -426.07474) (xy 70.139929 -426.044622) (xy 70.141592 -426.029628)
			(xy 70.141592 -425.419012) (xy 70.142023 -425.40693) (xy 70.149487 -425.383948) (xy 70.163689 -425.364397)
			(xy 70.183237 -425.350193) (xy 70.206218 -425.342725) (xy 70.2183 -425.342304) (xy 71.1581 -425.342304)
			(xy 71.170184 -425.342713) (xy 71.193169 -425.350182) (xy 71.21272 -425.364388) (xy 71.226924 -425.383942)
			(xy 71.234389 -425.406928) (xy 71.234808 -425.419012) (xy 71.234808 -427.960536) (xy 71.234367 -427.972612)
			(xy 71.226894 -427.995581) (xy 71.212692 -428.015117) (xy 71.193149 -428.029311) (xy 71.170177 -428.036772)
			(xy 71.1581 -428.037244) (xy 70.2183 -428.037244) (xy 70.206229 -428.036736) (xy 70.183268 -428.029278)
			(xy 70.163734 -428.015092) (xy 70.149538 -427.995564) (xy 70.142069 -427.972607) (xy 70.141592 -427.960536)
			(xy 70.141592 -427.350174) (xy 70.139928 -427.33518) (xy 70.138146 -427.305062) (xy 70.138036 -427.289976)
			(xy 69.234812 -427.289976) (xy 69.234812 -428.28972) (xy 72.138032 -428.28972) (xy 72.138144 -428.274634)
			(xy 72.139925 -428.244516) (xy 72.141588 -428.229522) (xy 72.141588 -427.150022) (xy 72.139919 -427.135029)
			(xy 72.138141 -427.10491) (xy 72.138032 -427.089824) (xy 72.138144 -427.074738) (xy 72.139925 -427.04462)
			(xy 72.141588 -427.029626) (xy 72.141588 -426.41901) (xy 72.142017 -426.406916) (xy 72.149477 -426.383908)
			(xy 72.163671 -426.364324) (xy 72.183216 -426.350075) (xy 72.206204 -426.342551) (xy 72.218296 -426.342048)
			(xy 73.158096 -426.342048) (xy 73.170199 -426.342519) (xy 73.193218 -426.350011) (xy 73.212787 -426.36426)
			(xy 73.226983 -426.383867) (xy 73.234413 -426.406905) (xy 73.234804 -426.41901) (xy 73.234804 -427.289976)
			(xy 75.138026 -427.289976) (xy 75.138117 -427.275402) (xy 75.139771 -427.246301) (xy 75.141328 -427.23181)
			(xy 75.141328 -426.147992) (xy 75.139785 -426.1335) (xy 75.138132 -426.1044) (xy 75.138026 -426.089826)
			(xy 75.138121 -426.075252) (xy 75.139773 -426.046151) (xy 75.141328 -426.03166) (xy 75.141328 -425.419012)
			(xy 75.141727 -425.406901) (xy 75.149227 -425.383869) (xy 75.163492 -425.364294) (xy 75.183119 -425.3501)
			(xy 75.206178 -425.342684) (xy 75.21829 -425.342304) (xy 76.15809 -425.342304) (xy 76.170175 -425.342815)
			(xy 76.19317 -425.350265) (xy 76.212747 -425.364441) (xy 76.226999 -425.383963) (xy 76.234537 -425.406928)
			(xy 76.235052 -425.419012) (xy 76.235052 -427.960536) (xy 76.234615 -427.972642) (xy 76.227112 -427.995661)
			(xy 76.212854 -428.015229) (xy 76.19324 -428.029424) (xy 76.170197 -428.036854) (xy 76.15809 -428.037244)
			(xy 75.21829 -428.037244) (xy 75.206198 -428.036801) (xy 75.183195 -428.029339) (xy 75.163614 -428.015147)
			(xy 75.149364 -427.995608) (xy 75.141835 -427.972626) (xy 75.141328 -427.960536) (xy 75.141328 -427.348142)
			(xy 75.139781 -427.33365) (xy 75.138131 -427.30455) (xy 75.138026 -427.289976) (xy 73.234804 -427.289976)
			(xy 73.234804 -428.28972) (xy 77.138022 -428.28972) (xy 77.138117 -428.275146) (xy 77.139768 -428.246045)
			(xy 77.141324 -428.231554) (xy 77.141324 -427.14799) (xy 77.139781 -427.133498) (xy 77.138128 -427.104398)
			(xy 77.138022 -427.089824) (xy 77.138117 -427.07525) (xy 77.139769 -427.046149) (xy 77.141324 -427.031658)
			(xy 77.141324 -426.41901) (xy 77.14182 -426.406897) (xy 77.149303 -426.383857) (xy 77.163539 -426.364256)
			(xy 77.183135 -426.350014) (xy 77.206174 -426.342524) (xy 77.218286 -426.342048) (xy 78.158086 -426.342048)
			(xy 78.170209 -426.342472) (xy 78.193269 -426.349962) (xy 78.212885 -426.364212) (xy 78.227136 -426.383827)
			(xy 78.234627 -426.406887) (xy 78.235048 -426.41901) (xy 78.235048 -427.289976) (xy 79.138018 -427.289976)
			(xy 79.138109 -427.275402) (xy 79.139763 -427.246301) (xy 79.14132 -427.23181) (xy 79.14132 -426.147992)
			(xy 79.139777 -426.1335) (xy 79.138124 -426.1044) (xy 79.138018 -426.089826) (xy 79.138113 -426.075252)
			(xy 79.139765 -426.046151) (xy 79.14132 -426.03166) (xy 79.14132 -425.419012) (xy 79.141727 -425.406902)
			(xy 79.149226 -425.383872) (xy 79.163489 -425.364297) (xy 79.183114 -425.350102) (xy 79.20617 -425.342685)
			(xy 79.218282 -425.342304) (xy 80.158082 -425.342304) (xy 80.170167 -425.342822) (xy 80.193161 -425.35027)
			(xy 80.212738 -425.364444) (xy 80.226991 -425.383965) (xy 80.234529 -425.406929) (xy 80.235044 -425.419012)
			(xy 80.235044 -427.960536) (xy 80.234615 -427.972642) (xy 80.227111 -427.995663) (xy 80.212851 -428.015232)
			(xy 80.193235 -428.029427) (xy 80.17019 -428.036855) (xy 80.158082 -428.037244) (xy 79.218282 -428.037244)
			(xy 79.20619 -428.036808) (xy 79.183186 -428.029344) (xy 79.163605 -428.01515) (xy 79.149355 -427.995609)
			(xy 79.141827 -427.972627) (xy 79.14132 -427.960536) (xy 79.14132 -427.348142) (xy 79.139773 -427.33365)
			(xy 79.138123 -427.30455) (xy 79.138018 -427.289976) (xy 78.235048 -427.289976) (xy 78.235048 -428.28972)
			(xy 81.138014 -428.28972) (xy 81.138108 -428.275146) (xy 81.13976 -428.246045) (xy 81.141316 -428.231554)
			(xy 81.141316 -427.14799) (xy 81.139773 -427.133498) (xy 81.13812 -427.104398) (xy 81.138014 -427.089824)
			(xy 81.138108 -427.07525) (xy 81.13976 -427.046149) (xy 81.141316 -427.031658) (xy 81.141316 -426.41901)
			(xy 81.14182 -426.406898) (xy 81.149302 -426.383859) (xy 81.163536 -426.364259) (xy 81.18313 -426.350016)
			(xy 81.206166 -426.342525) (xy 81.218278 -426.342048) (xy 82.158078 -426.342048) (xy 82.170201 -426.342479)
			(xy 82.19326 -426.349966) (xy 82.212877 -426.364215) (xy 82.227128 -426.383829) (xy 82.234619 -426.406887)
			(xy 82.23504 -426.41901) (xy 82.23504 -427.289976) (xy 83.13801 -427.289976) (xy 83.1381 -427.275402)
			(xy 83.139755 -427.246301) (xy 83.141312 -427.23181) (xy 83.141312 -426.147992) (xy 83.139769 -426.1335)
			(xy 83.138116 -426.1044) (xy 83.13801 -426.089826) (xy 83.138105 -426.075252) (xy 83.139756 -426.046151)
			(xy 83.141312 -426.03166) (xy 83.141312 -425.419012) (xy 83.141727 -425.406903) (xy 83.149224 -425.383874)
			(xy 83.163486 -425.364299) (xy 83.183109 -425.350105) (xy 83.206163 -425.342686) (xy 83.218274 -425.342304)
			(xy 84.158074 -425.342304) (xy 84.170159 -425.342829) (xy 84.193152 -425.350274) (xy 84.21273 -425.364447)
			(xy 84.226982 -425.383966) (xy 84.234521 -425.406929) (xy 84.235036 -425.419012) (xy 84.235036 -427.960536)
			(xy 84.234615 -427.972643) (xy 84.22711 -427.995665) (xy 84.212848 -428.015235) (xy 84.19323 -428.029429)
			(xy 84.170183 -428.036856) (xy 84.158074 -428.037244) (xy 83.218274 -428.037244) (xy 83.206181 -428.036815)
			(xy 83.183177 -428.029349) (xy 83.163596 -428.015153) (xy 83.149347 -427.995611) (xy 83.141819 -427.972627)
			(xy 83.141312 -427.960536) (xy 83.141312 -427.348142) (xy 83.139765 -427.33365) (xy 83.138115 -427.30455)
			(xy 83.13801 -427.289976) (xy 82.23504 -427.289976) (xy 82.23504 -428.28972) (xy 85.138006 -428.28972)
			(xy 85.1381 -428.275146) (xy 85.139752 -428.246045) (xy 85.141308 -428.231554) (xy 85.141308 -427.14799)
			(xy 85.139765 -427.133498) (xy 85.138112 -427.104398) (xy 85.138006 -427.089824) (xy 85.1381 -427.07525)
			(xy 85.139752 -427.046149) (xy 85.141308 -427.031658) (xy 85.141308 -426.41901) (xy 85.14182 -426.406899)
			(xy 85.149301 -426.383861) (xy 85.163533 -426.364262) (xy 85.183125 -426.350019) (xy 85.206159 -426.342526)
			(xy 85.21827 -426.342048) (xy 86.15807 -426.342048) (xy 86.170192 -426.342486) (xy 86.193252 -426.349971)
			(xy 86.212868 -426.364218) (xy 86.22712 -426.38383) (xy 86.234611 -426.406888) (xy 86.235032 -426.41901)
			(xy 86.235032 -427.289976) (xy 87.138002 -427.289976) (xy 87.138092 -427.275402) (xy 87.139747 -427.246301)
			(xy 87.141304 -427.23181) (xy 87.141304 -426.147992) (xy 87.139761 -426.1335) (xy 87.138108 -426.1044)
			(xy 87.138002 -426.089826) (xy 87.138097 -426.075252) (xy 87.139748 -426.046151) (xy 87.141304 -426.03166)
			(xy 87.141304 -425.419012) (xy 87.141727 -425.406903) (xy 87.149223 -425.383876) (xy 87.163483 -425.364302)
			(xy 87.183104 -425.350107) (xy 87.206156 -425.342687) (xy 87.218266 -425.342304) (xy 88.158066 -425.342304)
			(xy 88.17015 -425.342836) (xy 88.193144 -425.350279) (xy 88.212721 -425.36445) (xy 88.226974 -425.383968)
			(xy 88.234513 -425.40693) (xy 88.235028 -425.419012) (xy 88.235028 -427.960536) (xy 88.234615 -427.972644)
			(xy 88.227109 -427.995668) (xy 88.212845 -428.015238) (xy 88.193225 -428.029432) (xy 88.170175 -428.036857)
			(xy 88.158066 -428.037244) (xy 87.218266 -428.037244) (xy 87.206173 -428.036821) (xy 87.183169 -428.029353)
			(xy 87.163588 -428.015156) (xy 87.149339 -427.995612) (xy 87.141811 -427.972628) (xy 87.141304 -427.960536)
			(xy 87.141304 -427.348142) (xy 87.139757 -427.33365) (xy 87.138107 -427.30455) (xy 87.138002 -427.289976)
			(xy 86.235032 -427.289976) (xy 86.235032 -428.28972) (xy 89.137998 -428.28972) (xy 89.138092 -428.275146)
			(xy 89.139744 -428.246045) (xy 89.1413 -428.231554) (xy 89.1413 -427.14799) (xy 89.139757 -427.133498)
			(xy 89.138104 -427.104398) (xy 89.137998 -427.089824) (xy 89.138092 -427.07525) (xy 89.139744 -427.046149)
			(xy 89.1413 -427.031658) (xy 89.1413 -426.41901) (xy 89.14182 -426.4069) (xy 89.1493 -426.383863)
			(xy 89.163531 -426.364265) (xy 89.18312 -426.350022) (xy 89.206152 -426.342527) (xy 89.218262 -426.342048)
			(xy 90.158062 -426.342048) (xy 90.170184 -426.342492) (xy 90.193243 -426.349975) (xy 90.21286 -426.36422)
			(xy 90.227112 -426.383832) (xy 90.234603 -426.406888) (xy 90.235024 -426.41901) (xy 90.235024 -428.960534)
			(xy 90.234669 -428.972662) (xy 90.227162 -428.995729) (xy 90.212895 -429.015347) (xy 90.193264 -429.029595)
			(xy 90.170191 -429.03708) (xy 90.158062 -429.037496) (xy 89.218262 -429.037496) (xy 89.206149 -429.037021)
			(xy 89.18311 -429.029528) (xy 89.163512 -429.015285) (xy 89.14927 -428.995686) (xy 89.141778 -428.972647)
			(xy 89.1413 -428.960534) (xy 89.1413 -428.347886) (xy 89.139757 -428.333394) (xy 89.138104 -428.304294)
			(xy 89.137998 -428.28972) (xy 86.235032 -428.28972) (xy 86.235032 -428.960534) (xy 86.234617 -428.972653)
			(xy 86.227117 -428.995703) (xy 86.212861 -429.015307) (xy 86.193245 -429.029546) (xy 86.17019 -429.037027)
			(xy 86.15807 -429.037496) (xy 85.21827 -429.037496) (xy 85.206157 -429.037014) (xy 85.183119 -429.029523)
			(xy 85.16352 -429.015282) (xy 85.149279 -428.995685) (xy 85.141786 -428.972647) (xy 85.141308 -428.960534)
			(xy 85.141308 -428.347886) (xy 85.139765 -428.333394) (xy 85.138112 -428.304294) (xy 85.138006 -428.28972)
			(xy 82.23504 -428.28972) (xy 82.23504 -428.960534) (xy 82.234617 -428.972653) (xy 82.227118 -428.995701)
			(xy 82.212864 -429.015304) (xy 82.19325 -429.029543) (xy 82.170197 -429.037026) (xy 82.158078 -429.037496)
			(xy 81.218278 -429.037496) (xy 81.206166 -429.037008) (xy 81.183127 -429.029519) (xy 81.163529 -429.01528)
			(xy 81.149287 -428.995683) (xy 81.141794 -428.972646) (xy 81.141316 -428.960534) (xy 81.141316 -428.347886)
			(xy 81.139773 -428.333394) (xy 81.13812 -428.304294) (xy 81.138014 -428.28972) (xy 78.235048 -428.28972)
			(xy 78.235048 -428.960534) (xy 78.234617 -428.972652) (xy 78.227119 -428.995698) (xy 78.212867 -429.015301)
			(xy 78.193255 -429.029541) (xy 78.170204 -429.037025) (xy 78.158086 -429.037496) (xy 77.218286 -429.037496)
			(xy 77.206174 -429.037001) (xy 77.183136 -429.029514) (xy 77.163537 -429.015277) (xy 77.149295 -428.995682)
			(xy 77.141802 -428.972646) (xy 77.141324 -428.960534) (xy 77.141324 -428.347886) (xy 77.139781 -428.333394)
			(xy 77.138128 -428.304294) (xy 77.138022 -428.28972) (xy 73.234804 -428.28972) (xy 73.234804 -428.960534)
			(xy 73.234323 -428.972621) (xy 73.226862 -428.995615) (xy 73.212677 -429.015191) (xy 73.19315 -429.029442)
			(xy 73.170181 -429.036981) (xy 73.158096 -429.037496) (xy 72.218296 -429.037496) (xy 72.206187 -429.037087)
			(xy 72.183158 -429.029586) (xy 72.163585 -429.015323) (xy 72.149391 -428.995699) (xy 72.141971 -428.972645)
			(xy 72.141588 -428.960534) (xy 72.141588 -428.349918) (xy 72.139919 -428.334925) (xy 72.138141 -428.304806)
			(xy 72.138032 -428.28972) (xy 69.234812 -428.28972) (xy 69.234812 -428.960534) (xy 69.234421 -428.97263)
			(xy 69.226949 -428.99564) (xy 69.212744 -429.015223) (xy 69.193192 -429.029471) (xy 69.170199 -429.036994)
			(xy 69.158104 -429.037496) (xy 68.218304 -429.037496) (xy 68.206195 -429.03708) (xy 68.183167 -429.029582)
			(xy 68.163593 -429.01532) (xy 68.149399 -428.995698) (xy 68.141979 -428.972644) (xy 68.141596 -428.960534)
			(xy 68.141596 -428.349918) (xy 68.139927 -428.334925) (xy 68.138149 -428.304806) (xy 68.13804 -428.28972)
			(xy 65.23482 -428.28972) (xy 65.23482 -428.960534) (xy 65.234421 -428.972629) (xy 65.22695 -428.995638)
			(xy 65.212747 -429.015221) (xy 65.193197 -429.029469) (xy 65.170206 -429.036993) (xy 65.158112 -429.037496)
			(xy 64.218312 -429.037496) (xy 64.206203 -429.037073) (xy 64.183176 -429.029577) (xy 64.163602 -429.015317)
			(xy 64.149407 -428.995696) (xy 64.141987 -428.972644) (xy 64.141604 -428.960534) (xy 64.141604 -428.349918)
			(xy 64.139935 -428.334925) (xy 64.138157 -428.304806) (xy 64.138048 -428.28972) (xy 61.234828 -428.28972)
			(xy 61.234828 -428.960534) (xy 61.234421 -428.972629) (xy 61.226951 -428.995636) (xy 61.21275 -429.015218)
			(xy 61.193202 -429.029466) (xy 61.170213 -429.036992) (xy 61.15812 -429.037496) (xy 60.21832 -429.037496)
			(xy 60.206212 -429.037066) (xy 60.183185 -429.029572) (xy 60.163611 -429.015314) (xy 60.149416 -428.995695)
			(xy 60.141995 -428.972643) (xy 60.141612 -428.960534) (xy 60.141612 -428.349918) (xy 60.139943 -428.334925)
			(xy 60.138165 -428.304806) (xy 60.138056 -428.28972) (xy 49.0054 -428.28972) (xy 48.932448 -428.365522)
			(xy 48.780383 -428.51187) (xy 48.622824 -428.652286) (xy 48.460002 -428.786564) (xy 48.292156 -428.914507)
			(xy 48.119534 -429.035927) (xy 47.942387 -429.150646) (xy 47.760976 -429.258496) (xy 47.575567 -429.359318)
			(xy 47.386432 -429.452965) (xy 47.19385 -429.539298) (xy 46.998102 -429.618192) (xy 46.799475 -429.68953)
			(xy 46.598262 -429.753207) (xy 46.394758 -429.809131) (xy 46.189261 -429.857219) (xy 45.982073 -429.897401)
			(xy 45.773498 -429.929618) (xy 45.563841 -429.953821) (xy 45.353412 -429.969977) (xy 45.142518 -429.978061)
			(xy 44.93147 -429.978061) (xy 44.720576 -429.969977) (xy 44.510147 -429.953821) (xy 44.30049 -429.929618)
			(xy 44.091915 -429.897401) (xy 43.884727 -429.857219) (xy 43.67923 -429.809131) (xy 43.475726 -429.753207)
			(xy 43.274513 -429.68953) (xy 43.075886 -429.618192) (xy 42.880138 -429.539298) (xy 42.687556 -429.452965)
			(xy 42.498421 -429.359318) (xy 42.313012 -429.258496) (xy 42.131601 -429.150646) (xy 41.954454 -429.035927)
			(xy 41.781832 -428.914507) (xy 41.613986 -428.786564) (xy 41.451164 -428.652286) (xy 41.293605 -428.51187)
			(xy 41.14154 -428.365522) (xy 40.995192 -428.213457) (xy 40.854776 -428.055898) (xy 40.720498 -427.893076)
			(xy 40.592555 -427.72523) (xy 40.471135 -427.552608) (xy 40.356416 -427.375461) (xy 40.248566 -427.19405)
			(xy 40.147744 -427.008641) (xy 40.054097 -426.819506) (xy 39.967764 -426.626924) (xy 39.88887 -426.431176)
			(xy 39.817532 -426.232549) (xy 39.753855 -426.031336) (xy 39.697931 -425.827832) (xy 39.649843 -425.622335)
			(xy 39.609661 -425.415147) (xy 39.577444 -425.206572) (xy 39.553241 -424.996915) (xy 39.537085 -424.786486)
			(xy 39.529001 -424.575592) (xy 39.528496 -424.470068) (xy 8.024114 -424.470068) (xy 8.024114 -433.340256)
			(xy 8.024565 -433.354039) (xy 8.03193 -433.380601) (xy 8.046135 -433.404224) (xy 8.066143 -433.423185)
			(xy 8.090495 -433.4361) (xy 8.117415 -433.442027) (xy 8.144939 -433.440534) (xy 8.17106 -433.43173)
			(xy 8.193872 -433.416257) (xy 8.211712 -433.395244) (xy 8.217916 -433.382928) (xy 8.261825 -433.289418)
			(xy 8.356005 -433.105523) (xy 8.457319 -432.925459) (xy 8.56561 -432.749504) (xy 8.680713 -432.577927)
			(xy 8.802451 -432.410992) (xy 8.930637 -432.248956) (xy 9.065073 -432.092066) (xy 9.205554 -431.940565)
			(xy 9.351863 -431.794686) (xy 9.503776 -431.654651) (xy 9.66106 -431.520676) (xy 9.823472 -431.392967)
			(xy 9.990764 -431.27172) (xy 10.162678 -431.157122) (xy 10.338951 -431.049348) (xy 10.519312 -430.948564)
			(xy 10.703483 -430.854925) (xy 10.891182 -430.768574) (xy 11.08212 -430.689644) (xy 11.276005 -430.618257)
			(xy 11.472537 -430.554521) (xy 11.671417 -430.498536) (xy 11.872337 -430.450387) (xy 12.07499 -430.410147)
			(xy 12.279064 -430.377879) (xy 12.484245 -430.353633) (xy 12.690219 -430.337445) (xy 12.896669 -430.32934)
			(xy 12.999974 -430.328832) (xy 13.103478 -430.32934) (xy 13.310327 -430.337468) (xy 13.516697 -430.353709)
			(xy 13.722271 -430.378041) (xy 13.926731 -430.410424) (xy 14.129762 -430.45081) (xy 14.33105 -430.499135)
			(xy 14.530287 -430.555326) (xy 14.727163 -430.619295) (xy 14.921377 -430.690944) (xy 15.112628 -430.770163)
			(xy 15.300621 -430.856829) (xy 15.365562 -430.889918) (xy 58.13806 -430.889918) (xy 58.138169 -430.874832)
			(xy 58.139951 -430.844714) (xy 58.141616 -430.82972) (xy 58.141616 -429.749966) (xy 58.139951 -429.734972)
			(xy 58.13817 -429.704854) (xy 58.13806 -429.689768) (xy 58.138174 -429.674682) (xy 58.139952 -429.644564)
			(xy 58.141616 -429.62957) (xy 58.141616 -429.018954) (xy 58.142068 -429.006864) (xy 58.149534 -428.983866)
			(xy 58.163726 -428.964289) (xy 58.18326 -428.950039) (xy 58.206236 -428.942504) (xy 58.218324 -428.941992)
			(xy 59.158124 -428.941992) (xy 59.170233 -428.942396) (xy 59.19326 -428.949901) (xy 59.212832 -428.964166)
			(xy 59.227026 -428.983789) (xy 59.234448 -429.006843) (xy 59.234832 -429.018954) (xy 59.234832 -431.560478)
			(xy 59.234373 -431.572569) (xy 59.226919 -431.595574) (xy 59.212732 -431.615156) (xy 59.193194 -431.629407)
			(xy 59.170214 -431.636934) (xy 59.158124 -431.63744) (xy 58.218324 -431.63744) (xy 58.20622 -431.636964)
			(xy 58.183201 -431.629476) (xy 58.163631 -431.615228) (xy 58.149434 -431.595622) (xy 58.142005 -431.572583)
			(xy 58.141616 -431.560478) (xy 58.141616 -430.950116) (xy 58.139947 -430.935123) (xy 58.138169 -430.905004)
			(xy 58.13806 -430.889918) (xy 15.365562 -430.889918) (xy 15.485067 -430.950809) (xy 15.665681 -431.051958)
			(xy 15.842184 -431.16012) (xy 16.014306 -431.275128) (xy 16.181779 -431.396805) (xy 16.344346 -431.524962)
			(xy 16.501756 -431.659404) (xy 16.653767 -431.799921) (xy 16.743762 -431.889916) (xy 60.138056 -431.889916)
			(xy 60.138165 -431.87483) (xy 60.139947 -431.844712) (xy 60.141612 -431.829718) (xy 60.141612 -430.749964)
			(xy 60.139947 -430.73497) (xy 60.138166 -430.704852) (xy 60.138056 -430.689766) (xy 60.13817 -430.67468)
			(xy 60.139948 -430.644562) (xy 60.141612 -430.629568) (xy 60.141612 -430.018952) (xy 60.142024 -430.006873)
			(xy 60.149502 -429.983901) (xy 60.163711 -429.964363) (xy 60.183262 -429.950171) (xy 60.206241 -429.942713)
			(xy 60.21832 -429.942244) (xy 61.15812 -429.942244) (xy 61.170191 -429.942747) (xy 61.19315 -429.950209)
			(xy 61.212683 -429.964397) (xy 61.226878 -429.983924) (xy 61.234349 -430.006881) (xy 61.234828 -430.018952)
			(xy 61.234828 -430.889918) (xy 62.138052 -430.889918) (xy 62.138161 -430.874832) (xy 62.139943 -430.844714)
			(xy 62.141608 -430.82972) (xy 62.141608 -429.749966) (xy 62.139943 -429.734972) (xy 62.138162 -429.704854)
			(xy 62.138052 -429.689768) (xy 62.138166 -429.674682) (xy 62.139944 -429.644564) (xy 62.141608 -429.62957)
			(xy 62.141608 -429.018954) (xy 62.142068 -429.006865) (xy 62.149533 -428.983868) (xy 62.163723 -428.964292)
			(xy 62.183255 -428.950042) (xy 62.206229 -428.942505) (xy 62.218316 -428.941992) (xy 63.158116 -428.941992)
			(xy 63.170225 -428.942402) (xy 63.193251 -428.949905) (xy 63.212824 -428.964169) (xy 63.227018 -428.983791)
			(xy 63.23444 -429.006844) (xy 63.234824 -429.018954) (xy 63.234824 -431.560478) (xy 63.234373 -431.57257)
			(xy 63.226918 -431.595576) (xy 63.212729 -431.615159) (xy 63.193189 -431.629409) (xy 63.170206 -431.636935)
			(xy 63.158116 -431.63744) (xy 62.218316 -431.63744) (xy 62.206212 -431.63697) (xy 62.183192 -431.62948)
			(xy 62.163622 -431.615231) (xy 62.149426 -431.595623) (xy 62.141997 -431.572583) (xy 62.141608 -431.560478)
			(xy 62.141608 -430.950116) (xy 62.139939 -430.935123) (xy 62.138161 -430.905004) (xy 62.138052 -430.889918)
			(xy 61.234828 -430.889918) (xy 61.234828 -431.889916) (xy 64.138048 -431.889916) (xy 64.138157 -431.87483)
			(xy 64.139939 -431.844712) (xy 64.141604 -431.829718) (xy 64.141604 -430.749964) (xy 64.139939 -430.73497)
			(xy 64.138158 -430.704852) (xy 64.138048 -430.689766) (xy 64.138162 -430.67468) (xy 64.13994 -430.644562)
			(xy 64.141604 -430.629568) (xy 64.141604 -430.018952) (xy 64.142023 -430.006874) (xy 64.149501 -429.983903)
			(xy 64.163708 -429.964366) (xy 64.183257 -429.950173) (xy 64.206233 -429.942714) (xy 64.218312 -429.942244)
			(xy 65.158112 -429.942244) (xy 65.170182 -429.942753) (xy 65.193142 -429.950213) (xy 65.212674 -429.9644)
			(xy 65.22687 -429.983926) (xy 65.234341 -430.006882) (xy 65.23482 -430.018952) (xy 65.23482 -430.889918)
			(xy 66.138044 -430.889918) (xy 66.138153 -430.874832) (xy 66.139935 -430.844714) (xy 66.1416 -430.82972)
			(xy 66.1416 -429.749966) (xy 66.139935 -429.734972) (xy 66.138154 -429.704854) (xy 66.138044 -429.689768)
			(xy 66.138158 -429.674682) (xy 66.139936 -429.644564) (xy 66.1416 -429.62957) (xy 66.1416 -429.018954)
			(xy 66.142067 -429.006866) (xy 66.149532 -428.983871) (xy 66.16372 -428.964295) (xy 66.18325 -428.950044)
			(xy 66.206222 -428.942507) (xy 66.218308 -428.941992) (xy 67.158108 -428.941992) (xy 67.170217 -428.942409)
			(xy 67.193243 -428.94991) (xy 67.212815 -428.964172) (xy 67.22701 -428.983792) (xy 67.234432 -429.006844)
			(xy 67.234816 -429.018954) (xy 67.234816 -431.560478) (xy 67.234373 -431.572571) (xy 67.226917 -431.595578)
			(xy 67.212726 -431.615162) (xy 67.193184 -431.629412) (xy 67.170199 -431.636937) (xy 67.158108 -431.63744)
			(xy 66.218308 -431.63744) (xy 66.206204 -431.636978) (xy 66.183183 -431.629485) (xy 66.163613 -431.615234)
			(xy 66.149417 -431.595625) (xy 66.141989 -431.572584) (xy 66.1416 -431.560478) (xy 66.1416 -430.950116)
			(xy 66.139931 -430.935123) (xy 66.138153 -430.905004) (xy 66.138044 -430.889918) (xy 65.23482 -430.889918)
			(xy 65.23482 -431.889916) (xy 68.13804 -431.889916) (xy 68.138151 -431.87483) (xy 68.139933 -431.844712)
			(xy 68.141596 -431.829718) (xy 68.141596 -430.749964) (xy 68.139931 -430.73497) (xy 68.13815 -430.704852)
			(xy 68.13804 -430.689766) (xy 68.138154 -430.67468) (xy 68.139932 -430.644562) (xy 68.141596 -430.629568)
			(xy 68.141596 -430.018952) (xy 68.142023 -430.006875) (xy 68.149499 -429.983905) (xy 68.163705 -429.964368)
			(xy 68.183252 -429.950176) (xy 68.206226 -429.942715) (xy 68.218304 -429.942244) (xy 69.158104 -429.942244)
			(xy 69.170174 -429.94276) (xy 69.193133 -429.950218) (xy 69.212666 -429.964403) (xy 69.226862 -429.983927)
			(xy 69.234333 -430.006882) (xy 69.234812 -430.018952) (xy 69.234812 -430.889918) (xy 70.138036 -430.889918)
			(xy 70.138147 -430.874832) (xy 70.139929 -430.844714) (xy 70.141592 -430.82972) (xy 70.141592 -429.749966)
			(xy 70.139927 -429.734972) (xy 70.138146 -429.704854) (xy 70.138036 -429.689768) (xy 70.138152 -429.674683)
			(xy 70.13993 -429.644564) (xy 70.141592 -429.62957) (xy 70.141592 -429.018954) (xy 70.142067 -429.006867)
			(xy 70.149531 -428.983873) (xy 70.163717 -428.964298) (xy 70.183245 -428.950047) (xy 70.206214 -428.942508)
			(xy 70.2183 -428.941992) (xy 71.1581 -428.941992) (xy 71.170208 -428.942416) (xy 71.193234 -428.949914)
			(xy 71.212807 -428.964174) (xy 71.227001 -428.983794) (xy 71.234424 -429.006845) (xy 71.234808 -429.018954)
			(xy 71.234808 -431.560478) (xy 71.234275 -431.572562) (xy 71.22683 -431.595553) (xy 71.212659 -431.61513)
			(xy 71.193142 -431.629383) (xy 71.170182 -431.636924) (xy 71.1581 -431.63744) (xy 70.2183 -431.63744)
			(xy 70.206195 -431.636984) (xy 70.183175 -431.62949) (xy 70.163605 -431.615237) (xy 70.149409 -431.595626)
			(xy 70.141981 -431.572584) (xy 70.141592 -431.560478) (xy 70.141592 -430.950116) (xy 70.139923 -430.935123)
			(xy 70.138145 -430.905004) (xy 70.138036 -430.889918) (xy 69.234812 -430.889918) (xy 69.234812 -431.889916)
			(xy 72.138032 -431.889916) (xy 72.138143 -431.87483) (xy 72.139925 -431.844712) (xy 72.141588 -431.829718)
			(xy 72.141588 -430.749964) (xy 72.139923 -430.73497) (xy 72.138142 -430.704852) (xy 72.138032 -430.689766)
			(xy 72.138148 -430.674681) (xy 72.139926 -430.644562) (xy 72.141588 -430.629568) (xy 72.141588 -430.018952)
			(xy 72.142023 -430.006875) (xy 72.149498 -429.983907) (xy 72.163703 -429.964371) (xy 72.183247 -429.950178)
			(xy 72.206219 -429.942716) (xy 72.218296 -429.942244) (xy 73.158096 -429.942244) (xy 73.170166 -429.942767)
			(xy 73.193124 -429.950222) (xy 73.212657 -429.964406) (xy 73.226854 -429.983929) (xy 73.234325 -430.006883)
			(xy 73.234804 -430.018952) (xy 73.234804 -430.889918) (xy 75.138026 -430.889918) (xy 75.13812 -430.875344)
			(xy 75.139772 -430.846243) (xy 75.141328 -430.831752) (xy 75.141328 -429.747934) (xy 75.13978 -429.733442)
			(xy 75.13813 -429.704342) (xy 75.138026 -429.689768) (xy 75.138125 -429.675194) (xy 75.139774 -429.646093)
			(xy 75.141328 -429.631602) (xy 75.141328 -429.018954) (xy 75.141772 -429.006838) (xy 75.149271 -428.983795)
			(xy 75.163521 -428.964195) (xy 75.183127 -428.949955) (xy 75.206174 -428.942467) (xy 75.21829 -428.941992)
			(xy 76.15809 -428.941992) (xy 76.170199 -428.94252) (xy 76.193235 -428.949999) (xy 76.212832 -428.964228)
			(xy 76.227076 -428.983815) (xy 76.234572 -429.006845) (xy 76.235052 -429.018954) (xy 76.235052 -431.560478)
			(xy 76.234621 -431.572601) (xy 76.227134 -431.59566) (xy 76.212885 -431.615277) (xy 76.193271 -431.629528)
			(xy 76.170213 -431.637019) (xy 76.15809 -431.63744) (xy 75.21829 -431.63744) (xy 75.206165 -431.637048)
			(xy 75.183102 -431.62955) (xy 75.163485 -431.615292) (xy 75.149235 -431.59567) (xy 75.141747 -431.572604)
			(xy 75.141328 -431.560478) (xy 75.141328 -430.948084) (xy 75.139785 -430.933592) (xy 75.138132 -430.904492)
			(xy 75.138026 -430.889918) (xy 73.234804 -430.889918) (xy 73.234804 -431.889916) (xy 77.138022 -431.889916)
			(xy 77.138116 -431.875342) (xy 77.139768 -431.846241) (xy 77.141324 -431.83175) (xy 77.141324 -430.747932)
			(xy 77.139776 -430.73344) (xy 77.138126 -430.70434) (xy 77.138022 -430.689766) (xy 77.138121 -430.675192)
			(xy 77.13977 -430.646091) (xy 77.141324 -430.6316) (xy 77.141324 -430.018952) (xy 77.141676 -430.006838)
			(xy 77.149191 -429.983805) (xy 77.163469 -429.964231) (xy 77.183105 -429.950039) (xy 77.20617 -429.942624)
			(xy 77.218286 -429.942244) (xy 78.158086 -429.942244) (xy 78.170175 -429.942719) (xy 78.193176 -429.950173)
			(xy 78.212757 -429.964357) (xy 78.227007 -429.983889) (xy 78.234539 -430.006864) (xy 78.235048 -430.018952)
			(xy 78.235048 -430.889918) (xy 79.138018 -430.889918) (xy 79.138112 -430.875344) (xy 79.139764 -430.846243)
			(xy 79.14132 -430.831752) (xy 79.14132 -429.747934) (xy 79.139772 -429.733442) (xy 79.138122 -429.704342)
			(xy 79.138018 -429.689768) (xy 79.138117 -429.675194) (xy 79.139766 -429.646093) (xy 79.14132 -429.631602)
			(xy 79.14132 -429.018954) (xy 79.141772 -429.006839) (xy 79.14927 -428.983797) (xy 79.163518 -428.964198)
			(xy 79.183122 -428.949957) (xy 79.206167 -428.942468) (xy 79.218282 -428.941992) (xy 80.158082 -428.941992)
			(xy 80.170191 -428.942526) (xy 80.193226 -428.950003) (xy 80.212824 -428.964231) (xy 80.227068 -428.983817)
			(xy 80.234563 -429.006845) (xy 80.235044 -429.018954) (xy 80.235044 -431.560478) (xy 80.234621 -431.572601)
			(xy 80.227133 -431.595663) (xy 80.212882 -431.61528) (xy 80.193266 -431.629531) (xy 80.170205 -431.63702)
			(xy 80.158082 -431.63744) (xy 79.218282 -431.63744) (xy 79.206156 -431.637055) (xy 79.183093 -431.629555)
			(xy 79.163476 -431.615295) (xy 79.149227 -431.595671) (xy 79.141739 -431.572604) (xy 79.14132 -431.560478)
			(xy 79.14132 -430.948084) (xy 79.139777 -430.933592) (xy 79.138124 -430.904492) (xy 79.138018 -430.889918)
			(xy 78.235048 -430.889918) (xy 78.235048 -431.889916) (xy 81.138014 -431.889916) (xy 81.138108 -431.875342)
			(xy 81.13976 -431.846241) (xy 81.141316 -431.83175) (xy 81.141316 -430.747932) (xy 81.139768 -430.73344)
			(xy 81.138118 -430.70434) (xy 81.138014 -430.689766) (xy 81.138112 -430.675192) (xy 81.139761 -430.646091)
			(xy 81.141316 -430.6316) (xy 81.141316 -430.018952) (xy 81.141676 -430.006839) (xy 81.14919 -429.983807)
			(xy 81.163466 -429.964234) (xy 81.1831 -429.950041) (xy 81.206163 -429.942625) (xy 81.218278 -429.942244)
			(xy 82.158078 -429.942244) (xy 82.170167 -429.942726) (xy 82.193167 -429.950177) (xy 82.212748 -429.96436)
			(xy 82.226999 -429.983891) (xy 82.234531 -430.006865) (xy 82.23504 -430.018952) (xy 82.23504 -430.889918)
			(xy 83.13801 -430.889918) (xy 83.138104 -430.875344) (xy 83.139756 -430.846243) (xy 83.141312 -430.831752)
			(xy 83.141312 -429.747934) (xy 83.139764 -429.733442) (xy 83.138114 -429.704342) (xy 83.13801 -429.689768)
			(xy 83.138108 -429.675194) (xy 83.139758 -429.646093) (xy 83.141312 -429.631602) (xy 83.141312 -429.018954)
			(xy 83.141772 -429.00684) (xy 83.149269 -428.983799) (xy 83.163515 -428.964201) (xy 83.183117 -428.94996)
			(xy 83.20616 -428.942469) (xy 83.218274 -428.941992) (xy 84.158074 -428.941992) (xy 84.170183 -428.942533)
			(xy 84.193217 -428.950008) (xy 84.212815 -428.964233) (xy 84.227059 -428.983818) (xy 84.234555 -429.006846)
			(xy 84.235036 -429.018954) (xy 84.235036 -431.560478) (xy 84.234621 -431.572602) (xy 84.227132 -431.595665)
			(xy 84.21288 -431.615282) (xy 84.193261 -431.629533) (xy 84.170198 -431.637022) (xy 84.158074 -431.63744)
			(xy 83.218274 -431.63744) (xy 83.206156 -431.63701) (xy 83.183108 -431.629513) (xy 83.163505 -431.615261)
			(xy 83.149265 -431.595649) (xy 83.141782 -431.572596) (xy 83.141312 -431.560478) (xy 83.141312 -430.948084)
			(xy 83.139769 -430.933592) (xy 83.138116 -430.904492) (xy 83.13801 -430.889918) (xy 82.23504 -430.889918)
			(xy 82.23504 -431.889916) (xy 85.138006 -431.889916) (xy 85.1381 -431.875342) (xy 85.139752 -431.846241)
			(xy 85.141308 -431.83175) (xy 85.141308 -430.747932) (xy 85.13976 -430.73344) (xy 85.13811 -430.70434)
			(xy 85.138006 -430.689766) (xy 85.138104 -430.675192) (xy 85.139753 -430.646091) (xy 85.141308 -430.6316)
			(xy 85.141308 -430.018952) (xy 85.141676 -430.00684) (xy 85.149189 -429.98381) (xy 85.163463 -429.964237)
			(xy 85.183095 -429.950044) (xy 85.206156 -429.942626) (xy 85.21827 -429.942244) (xy 86.15807 -429.942244)
			(xy 86.170158 -429.942733) (xy 86.193159 -429.950182) (xy 86.212739 -429.964363) (xy 86.226991 -429.983892)
			(xy 86.234523 -430.006865) (xy 86.235032 -430.018952) (xy 86.235032 -430.889918) (xy 87.138002 -430.889918)
			(xy 87.138096 -430.875344) (xy 87.139748 -430.846243) (xy 87.141304 -430.831752) (xy 87.141304 -429.747934)
			(xy 87.139756 -429.733442) (xy 87.138106 -429.704342) (xy 87.138002 -429.689768) (xy 87.1381 -429.675194)
			(xy 87.13975 -429.646093) (xy 87.141304 -429.631602) (xy 87.141304 -429.018954) (xy 87.141772 -429.00684)
			(xy 87.149268 -428.983801) (xy 87.163512 -428.964203) (xy 87.183112 -428.949962) (xy 87.206152 -428.94247)
			(xy 87.218266 -428.941992) (xy 88.158066 -428.941992) (xy 88.170174 -428.94254) (xy 88.193209 -428.950012)
			(xy 88.212807 -428.964236) (xy 88.227051 -428.98382) (xy 88.234547 -429.006846) (xy 88.235028 -429.018954)
			(xy 88.235028 -431.560478) (xy 88.234621 -431.572603) (xy 88.22713 -431.595667) (xy 88.212877 -431.615285)
			(xy 88.193256 -431.629536) (xy 88.170191 -431.637023) (xy 88.158066 -431.63744) (xy 87.218266 -431.63744)
			(xy 87.206147 -431.637017) (xy 87.183099 -431.629518) (xy 87.163496 -431.615264) (xy 87.149257 -431.59565)
			(xy 87.141774 -431.572597) (xy 87.141304 -431.560478) (xy 87.141304 -430.948084) (xy 87.13976 -430.933592)
			(xy 87.138108 -430.904492) (xy 87.138002 -430.889918) (xy 86.235032 -430.889918) (xy 86.235032 -431.889916)
			(xy 89.137998 -431.889916) (xy 89.138092 -431.875342) (xy 89.139744 -431.846241) (xy 89.1413 -431.83175)
			(xy 89.1413 -430.747932) (xy 89.139752 -430.73344) (xy 89.138102 -430.70434) (xy 89.137998 -430.689766)
			(xy 89.138096 -430.675192) (xy 89.139746 -430.646091) (xy 89.1413 -430.6316) (xy 89.1413 -430.018952)
			(xy 89.141676 -430.006841) (xy 89.149188 -429.983812) (xy 89.16346 -429.96424) (xy 89.18309 -429.950047)
			(xy 89.206149 -429.942627) (xy 89.218262 -429.942244) (xy 90.158062 -429.942244) (xy 90.17015 -429.94274)
			(xy 90.19315 -429.950187) (xy 90.212731 -429.964366) (xy 90.226983 -429.983894) (xy 90.234515 -430.006866)
			(xy 90.235024 -430.018952) (xy 90.235024 -432.560476) (xy 90.234563 -432.572581) (xy 90.227074 -432.595604)
			(xy 90.212823 -432.615175) (xy 90.193212 -432.629371) (xy 90.170168 -432.636797) (xy 90.158062 -432.637184)
			(xy 89.218262 -432.637184) (xy 89.206173 -432.636726) (xy 89.183175 -432.629261) (xy 89.163598 -432.615072)
			(xy 89.149348 -432.595538) (xy 89.141812 -432.572564) (xy 89.1413 -432.560476) (xy 89.1413 -431.948082)
			(xy 89.139756 -431.93359) (xy 89.138104 -431.90449) (xy 89.137998 -431.889916) (xy 86.235032 -431.889916)
			(xy 86.235032 -432.560476) (xy 86.234563 -432.57258) (xy 86.227075 -432.595601) (xy 86.212825 -432.615172)
			(xy 86.193217 -432.629369) (xy 86.170175 -432.636796) (xy 86.15807 -432.637184) (xy 85.21827 -432.637184)
			(xy 85.206181 -432.636719) (xy 85.183184 -432.629257) (xy 85.163606 -432.615069) (xy 85.149356 -432.595537)
			(xy 85.14182 -432.572563) (xy 85.141308 -432.560476) (xy 85.141308 -431.948082) (xy 85.139764 -431.93359)
			(xy 85.138112 -431.90449) (xy 85.138006 -431.889916) (xy 82.23504 -431.889916) (xy 82.23504 -432.560476)
			(xy 82.234564 -432.57258) (xy 82.227076 -432.595599) (xy 82.212828 -432.615169) (xy 82.193222 -432.629366)
			(xy 82.170183 -432.636795) (xy 82.158078 -432.637184) (xy 81.218278 -432.637184) (xy 81.20619 -432.636712)
			(xy 81.183192 -432.629252) (xy 81.163615 -432.615066) (xy 81.149364 -432.595535) (xy 81.141828 -432.572563)
			(xy 81.141316 -432.560476) (xy 81.141316 -431.948082) (xy 81.139772 -431.93359) (xy 81.13812 -431.90449)
			(xy 81.138014 -431.889916) (xy 78.235048 -431.889916) (xy 78.235048 -432.560476) (xy 78.234564 -432.572579)
			(xy 78.227077 -432.595597) (xy 78.212831 -432.615166) (xy 78.193227 -432.629364) (xy 78.17019 -432.636793)
			(xy 78.158086 -432.637184) (xy 77.218286 -432.637184) (xy 77.206198 -432.636705) (xy 77.183201 -432.629248)
			(xy 77.163623 -432.615063) (xy 77.149372 -432.595534) (xy 77.141836 -432.572562) (xy 77.141324 -432.560476)
			(xy 77.141324 -431.948082) (xy 77.13978 -431.93359) (xy 77.138128 -431.90449) (xy 77.138022 -431.889916)
			(xy 73.234804 -431.889916) (xy 73.234804 -432.560476) (xy 73.234367 -432.572558) (xy 73.226905 -432.59554)
			(xy 73.212706 -432.615091) (xy 73.193158 -432.629296) (xy 73.170178 -432.636764) (xy 73.158096 -432.637184)
			(xy 72.218296 -432.637184) (xy 72.206211 -432.636791) (xy 72.183224 -432.629319) (xy 72.163671 -432.615109)
			(xy 72.149468 -432.595551) (xy 72.142005 -432.572562) (xy 72.141588 -432.560476) (xy 72.141588 -431.950114)
			(xy 72.139918 -431.935121) (xy 72.138141 -431.905002) (xy 72.138032 -431.889916) (xy 69.234812 -431.889916)
			(xy 69.234812 -432.560476) (xy 69.234367 -432.572557) (xy 69.226906 -432.595538) (xy 69.212709 -432.615089)
			(xy 69.193163 -432.629294) (xy 69.170185 -432.636762) (xy 69.158104 -432.637184) (xy 68.218304 -432.637184)
			(xy 68.206219 -432.636784) (xy 68.183232 -432.629314) (xy 68.16368 -432.615106) (xy 68.149476 -432.59555)
			(xy 68.142013 -432.572561) (xy 68.141596 -432.560476) (xy 68.141596 -431.950114) (xy 68.139926 -431.935121)
			(xy 68.138149 -431.905002) (xy 68.13804 -431.889916) (xy 65.23482 -431.889916) (xy 65.23482 -432.560476)
			(xy 65.234367 -432.572556) (xy 65.226907 -432.595536) (xy 65.212711 -432.615086) (xy 65.193168 -432.629291)
			(xy 65.170192 -432.636761) (xy 65.158112 -432.637184) (xy 64.218312 -432.637184) (xy 64.206228 -432.636777)
			(xy 64.183241 -432.629309) (xy 64.163689 -432.615103) (xy 64.149485 -432.595548) (xy 64.142022 -432.572561)
			(xy 64.141604 -432.560476) (xy 64.141604 -431.950114) (xy 64.139934 -431.935121) (xy 64.138157 -431.905002)
			(xy 64.138048 -431.889916) (xy 61.234828 -431.889916) (xy 61.234828 -432.560476) (xy 61.234367 -432.572555)
			(xy 61.226909 -432.595534) (xy 61.212714 -432.615083) (xy 61.193173 -432.629288) (xy 61.170199 -432.63676)
			(xy 61.15812 -432.637184) (xy 60.21832 -432.637184) (xy 60.206236 -432.63677) (xy 60.18325 -432.629305)
			(xy 60.163697 -432.6151) (xy 60.149493 -432.595547) (xy 60.14203 -432.57256) (xy 60.141612 -432.560476)
			(xy 60.141612 -431.950114) (xy 60.139942 -431.935121) (xy 60.138165 -431.905002) (xy 60.138056 -431.889916)
			(xy 16.743762 -431.889916) (xy 16.800144 -431.946298) (xy 16.940662 -432.09831) (xy 17.075103 -432.25572)
			(xy 17.20326 -432.418287) (xy 17.324937 -432.585761) (xy 17.439944 -432.757882) (xy 17.548106 -432.934386)
			(xy 17.649254 -433.115) (xy 17.743234 -433.299446) (xy 17.8299 -433.48744) (xy 17.909119 -433.678691)
			(xy 17.980768 -433.872904) (xy 18.044737 -434.069781) (xy 18.100927 -434.269017) (xy 18.149252 -434.470306)
			(xy 18.153141 -434.48986) (xy 58.13806 -434.48986) (xy 58.138173 -434.474774) (xy 58.139952 -434.444656)
			(xy 58.141616 -434.429662) (xy 58.141616 -433.350162) (xy 58.139951 -433.335168) (xy 58.13817 -433.30505)
			(xy 58.13806 -433.289964) (xy 58.138173 -433.274878) (xy 58.139952 -433.24476) (xy 58.141616 -433.229766)
			(xy 58.141616 -432.618896) (xy 58.142009 -432.606811) (xy 58.149481 -432.583824) (xy 58.163691 -432.564271)
			(xy 58.183249 -432.550068) (xy 58.206238 -432.542605) (xy 58.218324 -432.542188) (xy 59.158124 -432.542188)
			(xy 59.170199 -432.542644) (xy 59.193167 -432.550113) (xy 59.212703 -432.564311) (xy 59.226897 -432.583851)
			(xy 59.234359 -432.606821) (xy 59.234832 -432.618896) (xy 59.234832 -435.16042) (xy 59.234353 -435.172493)
			(xy 59.226888 -435.195457) (xy 59.212694 -435.214991) (xy 59.19316 -435.229186) (xy 59.170197 -435.236652)
			(xy 59.158124 -435.237128) (xy 58.218324 -435.237128) (xy 58.206245 -435.236667) (xy 58.183266 -435.229209)
			(xy 58.163717 -435.215014) (xy 58.149512 -435.195473) (xy 58.14204 -435.172499) (xy 58.141616 -435.16042)
			(xy 58.141616 -434.550058) (xy 58.13995 -434.535064) (xy 58.13817 -434.504946) (xy 58.13806 -434.48986)
			(xy 18.153141 -434.48986) (xy 18.189637 -434.673337) (xy 18.22202 -434.877797) (xy 18.246351 -435.083371)
			(xy 18.262593 -435.289741) (xy 18.270456 -435.489858) (xy 60.138056 -435.489858) (xy 60.138169 -435.474772)
			(xy 60.139948 -435.444654) (xy 60.141612 -435.42966) (xy 60.141612 -434.35016) (xy 60.139947 -434.335166)
			(xy 60.138166 -434.305048) (xy 60.138056 -434.289962) (xy 60.138169 -434.274876) (xy 60.139948 -434.244758)
			(xy 60.141612 -434.229764) (xy 60.141612 -433.618894) (xy 60.142102 -433.606807) (xy 60.149557 -433.583811)
			(xy 60.163739 -433.564234) (xy 60.183265 -433.549982) (xy 60.206235 -433.542445) (xy 60.21832 -433.541932)
			(xy 61.15812 -433.541932) (xy 61.170233 -433.5423) (xy 61.193267 -433.549808) (xy 61.212842 -433.564081)
			(xy 61.227035 -433.583715) (xy 61.234449 -433.606779) (xy 61.234828 -433.618894) (xy 61.234828 -434.48986)
			(xy 62.138052 -434.48986) (xy 62.138165 -434.474774) (xy 62.139944 -434.444656) (xy 62.141608 -434.429662)
			(xy 62.141608 -433.350162) (xy 62.139943 -433.335168) (xy 62.138162 -433.30505) (xy 62.138052 -433.289964)
			(xy 62.138165 -433.274878) (xy 62.139944 -433.24476) (xy 62.141608 -433.229766) (xy 62.141608 -432.618896)
			(xy 62.142009 -432.606811) (xy 62.14948 -432.583826) (xy 62.163688 -432.564274) (xy 62.183244 -432.550071)
			(xy 62.206231 -432.542606) (xy 62.218316 -432.542188) (xy 63.158116 -432.542188) (xy 63.170191 -432.542651)
			(xy 63.193158 -432.550117) (xy 63.212694 -432.564314) (xy 63.226888 -432.583853) (xy 63.234351 -432.606821)
			(xy 63.234824 -432.618896) (xy 63.234824 -435.16042) (xy 63.234353 -435.172494) (xy 63.226887 -435.195459)
			(xy 63.212691 -435.214994) (xy 63.193155 -435.229189) (xy 63.17019 -435.236654) (xy 63.158116 -435.237128)
			(xy 62.218316 -435.237128) (xy 62.206244 -435.236622) (xy 62.183281 -435.229167) (xy 62.163745 -435.21498)
			(xy 62.14955 -435.195451) (xy 62.142083 -435.172492) (xy 62.141608 -435.16042) (xy 62.141608 -434.550058)
			(xy 62.139942 -434.535064) (xy 62.138162 -434.504946) (xy 62.138052 -434.48986) (xy 61.234828 -434.48986)
			(xy 61.234828 -435.489858) (xy 64.138048 -435.489858) (xy 64.138161 -435.474772) (xy 64.13994 -435.444654)
			(xy 64.141604 -435.42966) (xy 64.141604 -434.35016) (xy 64.139938 -434.335166) (xy 64.138158 -434.305048)
			(xy 64.138048 -434.289962) (xy 64.138161 -434.274876) (xy 64.13994 -434.244758) (xy 64.141604 -434.229764)
			(xy 64.141604 -433.618894) (xy 64.142102 -433.606808) (xy 64.149556 -433.583813) (xy 64.163736 -433.564236)
			(xy 64.18326 -433.549985) (xy 64.206228 -433.542447) (xy 64.218312 -433.541932) (xy 65.158112 -433.541932)
			(xy 65.170225 -433.542306) (xy 65.193258 -433.549813) (xy 65.212834 -433.564084) (xy 65.227027 -433.583717)
			(xy 65.234441 -433.60678) (xy 65.23482 -433.618894) (xy 65.23482 -434.48986) (xy 66.138044 -434.48986)
			(xy 66.138157 -434.474774) (xy 66.139936 -434.444656) (xy 66.1416 -434.429662) (xy 66.1416 -433.350162)
			(xy 66.139935 -433.335168) (xy 66.138154 -433.30505) (xy 66.138044 -433.289964) (xy 66.138157 -433.274878)
			(xy 66.139936 -433.24476) (xy 66.1416 -433.229766) (xy 66.1416 -432.618896) (xy 66.142009 -432.606812)
			(xy 66.149479 -432.583828) (xy 66.163686 -432.564277) (xy 66.183239 -432.550073) (xy 66.206224 -432.542607)
			(xy 66.218308 -432.542188) (xy 67.158108 -432.542188) (xy 67.170183 -432.542657) (xy 67.193149 -432.550122)
			(xy 67.212686 -432.564317) (xy 67.22688 -432.583854) (xy 67.234343 -432.606821) (xy 67.234816 -432.618896)
			(xy 67.234816 -435.16042) (xy 67.234353 -435.172495) (xy 67.226886 -435.195461) (xy 67.212689 -435.214997)
			(xy 67.19315 -435.229191) (xy 67.170183 -435.236655) (xy 67.158108 -435.237128) (xy 66.218308 -435.237128)
			(xy 66.206236 -435.236629) (xy 66.183272 -435.229171) (xy 66.163737 -435.214983) (xy 66.149541 -435.195453)
			(xy 66.142075 -435.172492) (xy 66.1416 -435.16042) (xy 66.1416 -434.550058) (xy 66.139934 -434.535064)
			(xy 66.138154 -434.504946) (xy 66.138044 -434.48986) (xy 65.23482 -434.48986) (xy 65.23482 -435.489858)
			(xy 68.13804 -435.489858) (xy 68.138153 -435.474772) (xy 68.139932 -435.444654) (xy 68.141596 -435.42966)
			(xy 68.141596 -434.35016) (xy 68.13993 -434.335166) (xy 68.13815 -434.305048) (xy 68.13804 -434.289962)
			(xy 68.138153 -434.274876) (xy 68.139932 -434.244758) (xy 68.141596 -434.229764) (xy 68.141596 -433.618894)
			(xy 68.142102 -433.606809) (xy 68.149555 -433.583815) (xy 68.163733 -433.564239) (xy 68.183255 -433.549987)
			(xy 68.20622 -433.542448) (xy 68.218304 -433.541932) (xy 69.158104 -433.541932) (xy 69.170216 -433.542313)
			(xy 69.193249 -433.549818) (xy 69.212825 -433.564087) (xy 69.227018 -433.583718) (xy 69.234433 -433.60678)
			(xy 69.234812 -433.618894) (xy 69.234812 -434.48986) (xy 70.138036 -434.48986) (xy 70.138151 -434.474775)
			(xy 70.13993 -434.444656) (xy 70.141592 -434.429662) (xy 70.141592 -433.350162) (xy 70.139927 -433.335168)
			(xy 70.138146 -433.30505) (xy 70.138036 -433.289964) (xy 70.138152 -433.274879) (xy 70.13993 -433.24476)
			(xy 70.141592 -433.229766) (xy 70.141592 -432.618896) (xy 70.142061 -432.606821) (xy 70.149524 -432.583854)
			(xy 70.16372 -432.564317) (xy 70.183258 -432.550123) (xy 70.206225 -432.54266) (xy 70.2183 -432.542188)
			(xy 71.1581 -432.542188) (xy 71.170174 -432.542664) (xy 71.193141 -432.550126) (xy 71.212677 -432.56432)
			(xy 71.226872 -432.583856) (xy 71.234335 -432.606822) (xy 71.234808 -432.618896) (xy 71.234808 -435.16042)
			(xy 71.234353 -435.172496) (xy 71.226885 -435.195463) (xy 71.212686 -435.215) (xy 71.193145 -435.229194)
			(xy 71.170176 -435.236656) (xy 71.1581 -435.237128) (xy 70.2183 -435.237128) (xy 70.206227 -435.236636)
			(xy 70.183264 -435.229176) (xy 70.163728 -435.214986) (xy 70.149533 -435.195454) (xy 70.142067 -435.172492)
			(xy 70.141592 -435.16042) (xy 70.141592 -434.550058) (xy 70.139926 -434.535064) (xy 70.138146 -434.504946)
			(xy 70.138036 -434.48986) (xy 69.234812 -434.48986) (xy 69.234812 -435.489858) (xy 72.138032 -435.489858)
			(xy 72.138147 -435.474773) (xy 72.139926 -435.444654) (xy 72.141588 -435.42966) (xy 72.141588 -434.35016)
			(xy 72.139922 -434.335166) (xy 72.138142 -434.305048) (xy 72.138032 -434.289962) (xy 72.138147 -434.274877)
			(xy 72.139926 -434.244758) (xy 72.141588 -434.229764) (xy 72.141588 -433.618894) (xy 72.142003 -433.606799)
			(xy 72.149468 -433.583791) (xy 72.163666 -433.564207) (xy 72.183213 -433.549958) (xy 72.206203 -433.542435)
			(xy 72.218296 -433.541932) (xy 73.158096 -433.541932) (xy 73.170208 -433.54232) (xy 73.193241 -433.549822)
			(xy 73.212817 -433.56409) (xy 73.22701 -433.58372) (xy 73.234425 -433.606781) (xy 73.234804 -433.618894)
			(xy 73.234804 -434.48986) (xy 75.138026 -434.48986) (xy 75.138124 -434.475286) (xy 75.139774 -434.446185)
			(xy 75.141328 -434.431694) (xy 75.141328 -433.34813) (xy 75.13978 -433.333638) (xy 75.13813 -433.304538)
			(xy 75.138026 -433.289964) (xy 75.138124 -433.27539) (xy 75.139774 -433.246289) (xy 75.141328 -433.231798)
			(xy 75.141328 -432.618896) (xy 75.141713 -432.606784) (xy 75.149217 -432.583752) (xy 75.163486 -432.564176)
			(xy 75.183116 -432.549983) (xy 75.206177 -432.542567) (xy 75.21829 -432.542188) (xy 76.15809 -432.542188)
			(xy 76.170184 -432.542617) (xy 76.193192 -432.550077) (xy 76.212776 -432.564271) (xy 76.227025 -432.583816)
			(xy 76.234549 -432.606804) (xy 76.235052 -432.618896) (xy 76.235052 -435.16042) (xy 76.234601 -435.172525)
			(xy 76.227103 -435.195544) (xy 76.212848 -435.215112) (xy 76.193237 -435.229308) (xy 76.170196 -435.236737)
			(xy 76.15809 -435.237128) (xy 75.21829 -435.237128) (xy 75.206197 -435.2367) (xy 75.183191 -435.229237)
			(xy 75.163608 -435.215041) (xy 75.149359 -435.195498) (xy 75.141833 -435.172512) (xy 75.141328 -435.16042)
			(xy 75.141328 -434.548026) (xy 75.13978 -434.533534) (xy 75.13813 -434.504434) (xy 75.138026 -434.48986)
			(xy 73.234804 -434.48986) (xy 73.234804 -435.489858) (xy 77.138022 -435.489858) (xy 77.13812 -435.475284)
			(xy 77.13977 -435.446183) (xy 77.141324 -435.431692) (xy 77.141324 -434.348128) (xy 77.139776 -434.333636)
			(xy 77.138126 -434.304536) (xy 77.138022 -434.289962) (xy 77.13812 -434.275388) (xy 77.13977 -434.246287)
			(xy 77.141324 -434.231796) (xy 77.141324 -433.618894) (xy 77.141807 -433.606781) (xy 77.149294 -433.58374)
			(xy 77.163534 -433.564139) (xy 77.183132 -433.549897) (xy 77.206173 -433.542408) (xy 77.218286 -433.541932)
			(xy 78.158086 -433.541932) (xy 78.170207 -433.542372) (xy 78.193265 -433.54986) (xy 78.21288 -433.564106)
			(xy 78.227131 -433.583717) (xy 78.234625 -433.606773) (xy 78.235048 -433.618894) (xy 78.235048 -434.48986)
			(xy 79.138018 -434.48986) (xy 79.138116 -434.475286) (xy 79.139766 -434.446185) (xy 79.14132 -434.431694)
			(xy 79.14132 -433.34813) (xy 79.139772 -433.333638) (xy 79.138122 -433.304538) (xy 79.138018 -433.289964)
			(xy 79.138116 -433.27539) (xy 79.139766 -433.246289) (xy 79.14132 -433.231798) (xy 79.14132 -432.618896)
			(xy 79.141713 -432.606785) (xy 79.149216 -432.583754) (xy 79.163483 -432.564179) (xy 79.183111 -432.549985)
			(xy 79.206169 -432.542568) (xy 79.218282 -432.542188) (xy 80.158082 -432.542188) (xy 80.170175 -432.542624)
			(xy 80.193183 -432.550081) (xy 80.212768 -432.564274) (xy 80.227017 -432.583818) (xy 80.234541 -432.606804)
			(xy 80.235044 -432.618896) (xy 80.235044 -435.16042) (xy 80.234601 -435.172526) (xy 80.227102 -435.195546)
			(xy 80.212845 -435.215115) (xy 80.193232 -435.22931) (xy 80.170189 -435.236739) (xy 80.158082 -435.237128)
			(xy 79.218282 -435.237128) (xy 79.206188 -435.236708) (xy 79.183182 -435.229242) (xy 79.163599 -435.215045)
			(xy 79.14935 -435.195499) (xy 79.141824 -435.172512) (xy 79.14132 -435.16042) (xy 79.14132 -434.548026)
			(xy 79.139772 -434.533534) (xy 79.138122 -434.504434) (xy 79.138018 -434.48986) (xy 78.235048 -434.48986)
			(xy 78.235048 -435.489858) (xy 81.138014 -435.489858) (xy 81.138111 -435.475284) (xy 81.139761 -435.446183)
			(xy 81.141316 -435.431692) (xy 81.141316 -434.348128) (xy 81.139768 -434.333636) (xy 81.138118 -434.304536)
			(xy 81.138014 -434.289962) (xy 81.138112 -434.275388) (xy 81.139761 -434.246287) (xy 81.141316 -434.231796)
			(xy 81.141316 -433.618894) (xy 81.141807 -433.606781) (xy 81.149293 -433.583742) (xy 81.163531 -433.564142)
			(xy 81.183127 -433.5499) (xy 81.206165 -433.542409) (xy 81.218278 -433.541932) (xy 82.158078 -433.541932)
			(xy 82.170199 -433.542379) (xy 82.193256 -433.549864) (xy 82.212871 -433.564109) (xy 82.227123 -433.583719)
			(xy 82.234617 -433.606773) (xy 82.23504 -433.618894) (xy 82.23504 -434.48986) (xy 83.13801 -434.48986)
			(xy 83.138107 -434.475286) (xy 83.139757 -434.446185) (xy 83.141312 -434.431694) (xy 83.141312 -433.34813)
			(xy 83.139764 -433.333638) (xy 83.138114 -433.304538) (xy 83.13801 -433.289964) (xy 83.138108 -433.27539)
			(xy 83.139757 -433.246289) (xy 83.141312 -433.231798) (xy 83.141312 -432.618896) (xy 83.141713 -432.606786)
			(xy 83.149215 -432.583756) (xy 83.16348 -432.564182) (xy 83.183106 -432.549988) (xy 83.206162 -432.542569)
			(xy 83.218274 -432.542188) (xy 84.158074 -432.542188) (xy 84.170167 -432.54263) (xy 84.193175 -432.550086)
			(xy 84.212759 -432.564277) (xy 84.227009 -432.583819) (xy 84.234533 -432.606804) (xy 84.235036 -432.618896)
			(xy 84.235036 -435.16042) (xy 84.234601 -435.172526) (xy 84.227101 -435.195548) (xy 84.212843 -435.215118)
			(xy 84.193227 -435.229313) (xy 84.170182 -435.23674) (xy 84.158074 -435.237128) (xy 83.218274 -435.237128)
			(xy 83.20618 -435.236714) (xy 83.183173 -435.229247) (xy 83.163591 -435.215047) (xy 83.149342 -435.195501)
			(xy 83.141816 -435.172513) (xy 83.141312 -435.16042) (xy 83.141312 -434.548026) (xy 83.139764 -434.533534)
			(xy 83.138114 -434.504434) (xy 83.13801 -434.48986) (xy 82.23504 -434.48986) (xy 82.23504 -435.489858)
			(xy 85.138006 -435.489858) (xy 85.138103 -435.475284) (xy 85.139753 -435.446183) (xy 85.141308 -435.431692)
			(xy 85.141308 -434.348128) (xy 85.13976 -434.333636) (xy 85.13811 -434.304536) (xy 85.138006 -434.289962)
			(xy 85.138104 -434.275388) (xy 85.139753 -434.246287) (xy 85.141308 -434.231796) (xy 85.141308 -433.618894)
			(xy 85.141806 -433.606782) (xy 85.149292 -433.583744) (xy 85.163528 -433.564145) (xy 85.183122 -433.549903)
			(xy 85.206158 -433.54241) (xy 85.21827 -433.541932) (xy 86.15807 -433.541932) (xy 86.170191 -433.542385)
			(xy 86.193247 -433.549869) (xy 86.212863 -433.564112) (xy 86.227115 -433.58372) (xy 86.234609 -433.606774)
			(xy 86.235032 -433.618894) (xy 86.235032 -434.48986) (xy 87.138002 -434.48986) (xy 87.1381 -434.475286)
			(xy 87.139749 -434.446185) (xy 87.141304 -434.431694) (xy 87.141304 -433.34813) (xy 87.139756 -433.333638)
			(xy 87.138106 -433.304538) (xy 87.138002 -433.289964) (xy 87.1381 -433.27539) (xy 87.139749 -433.246289)
			(xy 87.141304 -433.231798) (xy 87.141304 -432.618896) (xy 87.141713 -432.606787) (xy 87.149214 -432.583758)
			(xy 87.163477 -432.564185) (xy 87.183101 -432.549991) (xy 87.206155 -432.542571) (xy 87.218266 -432.542188)
			(xy 88.158066 -432.542188) (xy 88.170159 -432.542637) (xy 88.193166 -432.55009) (xy 88.212751 -432.56428)
			(xy 88.227001 -432.583821) (xy 88.234525 -432.606805) (xy 88.235028 -432.618896) (xy 88.235028 -435.16042)
			(xy 88.234601 -435.172527) (xy 88.2271 -435.19555) (xy 88.21284 -435.215121) (xy 88.193222 -435.229316)
			(xy 88.170174 -435.236741) (xy 88.158066 -435.237128) (xy 87.218266 -435.237128) (xy 87.206171 -435.236721)
			(xy 87.183164 -435.229251) (xy 87.163582 -435.21505) (xy 87.149334 -435.195502) (xy 87.141808 -435.172513)
			(xy 87.141304 -435.16042) (xy 87.141304 -434.548026) (xy 87.139756 -434.533534) (xy 87.138106 -434.504434)
			(xy 87.138002 -434.48986) (xy 86.235032 -434.48986) (xy 86.235032 -435.489858) (xy 89.137998 -435.489858)
			(xy 89.138095 -435.475284) (xy 89.139745 -435.446183) (xy 89.1413 -435.431692) (xy 89.1413 -434.348128)
			(xy 89.139752 -434.333636) (xy 89.138102 -434.304536) (xy 89.137998 -434.289962) (xy 89.138096 -434.275388)
			(xy 89.139745 -434.246287) (xy 89.1413 -434.231796) (xy 89.1413 -433.618894) (xy 89.141806 -433.606783)
			(xy 89.14929 -433.583746) (xy 89.163525 -433.564148) (xy 89.183117 -433.549905) (xy 89.206151 -433.542411)
			(xy 89.218262 -433.541932) (xy 90.158062 -433.541932) (xy 90.170182 -433.542392) (xy 90.193239 -433.549873)
			(xy 90.212854 -433.564115) (xy 90.227107 -433.583722) (xy 90.234601 -433.606774) (xy 90.235024 -433.618894)
			(xy 90.235024 -436.160418) (xy 90.234655 -436.172545) (xy 90.227153 -436.195611) (xy 90.212889 -436.215229)
			(xy 90.193261 -436.229478) (xy 90.17019 -436.236963) (xy 90.158062 -436.23738) (xy 89.218262 -436.23738)
			(xy 89.206147 -436.236921) (xy 89.183106 -436.229425) (xy 89.163506 -436.21518) (xy 89.149265 -436.195576)
			(xy 89.141776 -436.172533) (xy 89.1413 -436.160418) (xy 89.1413 -435.548024) (xy 89.139751 -435.533532)
			(xy 89.138102 -435.504432) (xy 89.137998 -435.489858) (xy 86.235032 -435.489858) (xy 86.235032 -436.160418)
			(xy 86.234655 -436.172545) (xy 86.227154 -436.195609) (xy 86.212892 -436.215226) (xy 86.193266 -436.229476)
			(xy 86.170197 -436.236962) (xy 86.15807 -436.23738) (xy 85.21827 -436.23738) (xy 85.206156 -436.236914)
			(xy 85.183114 -436.229421) (xy 85.163515 -436.215177) (xy 85.149274 -436.195575) (xy 85.141784 -436.172532)
			(xy 85.141308 -436.160418) (xy 85.141308 -435.548024) (xy 85.139759 -435.533532) (xy 85.13811 -435.504432)
			(xy 85.138006 -435.489858) (xy 82.23504 -435.489858) (xy 82.23504 -436.160418) (xy 82.234655 -436.172544)
			(xy 82.227155 -436.195607) (xy 82.212895 -436.215224) (xy 82.193271 -436.229473) (xy 82.170204 -436.236961)
			(xy 82.158078 -436.23738) (xy 81.218278 -436.23738) (xy 81.206164 -436.236907) (xy 81.183123 -436.229416)
			(xy 81.163523 -436.215174) (xy 81.149282 -436.195573) (xy 81.141792 -436.172532) (xy 81.141316 -436.160418)
			(xy 81.141316 -435.548024) (xy 81.139767 -435.533532) (xy 81.138118 -435.504432) (xy 81.138014 -435.489858)
			(xy 78.235048 -435.489858) (xy 78.235048 -436.160418) (xy 78.234604 -436.172535) (xy 78.22711 -436.195581)
			(xy 78.212861 -436.215184) (xy 78.193252 -436.229424) (xy 78.170203 -436.236909) (xy 78.158086 -436.23738)
			(xy 77.218286 -436.23738) (xy 77.206172 -436.236901) (xy 77.183132 -436.229412) (xy 77.163532 -436.215171)
			(xy 77.14929 -436.195572) (xy 77.1418 -436.172531) (xy 77.141324 -436.160418) (xy 77.141324 -435.548024)
			(xy 77.139775 -435.533532) (xy 77.138126 -435.504432) (xy 77.138022 -435.489858) (xy 73.234804 -435.489858)
			(xy 73.234804 -436.160418) (xy 73.234309 -436.172504) (xy 73.226853 -436.195498) (xy 73.212672 -436.215074)
			(xy 73.193147 -436.229325) (xy 73.17018 -436.236865) (xy 73.158096 -436.23738) (xy 72.218296 -436.23738)
			(xy 72.206185 -436.236987) (xy 72.183154 -436.229484) (xy 72.163579 -436.215217) (xy 72.149385 -436.195589)
			(xy 72.141968 -436.172531) (xy 72.141588 -436.160418) (xy 72.141588 -435.550056) (xy 72.139922 -435.535062)
			(xy 72.138142 -435.504944) (xy 72.138032 -435.489858) (xy 69.234812 -435.489858) (xy 69.234812 -436.160418)
			(xy 69.234407 -436.172513) (xy 69.22694 -436.195523) (xy 69.212739 -436.215106) (xy 69.193189 -436.229355)
			(xy 69.170198 -436.236878) (xy 69.158104 -436.23738) (xy 68.218304 -436.23738) (xy 68.206193 -436.23698)
			(xy 68.183163 -436.229479) (xy 68.163588 -436.215214) (xy 68.149394 -436.195588) (xy 68.141976 -436.17253)
			(xy 68.141596 -436.160418) (xy 68.141596 -435.550056) (xy 68.13993 -435.535062) (xy 68.13815 -435.504944)
			(xy 68.13804 -435.489858) (xy 65.23482 -435.489858) (xy 65.23482 -436.160418) (xy 65.234407 -436.172513)
			(xy 65.226941 -436.195521) (xy 65.212742 -436.215104) (xy 65.193194 -436.229352) (xy 65.170205 -436.236877)
			(xy 65.158112 -436.23738) (xy 64.218312 -436.23738) (xy 64.206202 -436.236973) (xy 64.183172 -436.229474)
			(xy 64.163597 -436.215211) (xy 64.149402 -436.195586) (xy 64.141985 -436.17253) (xy 64.141604 -436.160418)
			(xy 64.141604 -435.550056) (xy 64.139938 -435.535062) (xy 64.138158 -435.504944) (xy 64.138048 -435.489858)
			(xy 61.234828 -435.489858) (xy 61.234828 -436.160418) (xy 61.234408 -436.172512) (xy 61.226942 -436.195518)
			(xy 61.212745 -436.215101) (xy 61.193199 -436.22935) (xy 61.170212 -436.236876) (xy 61.15812 -436.23738)
			(xy 60.21832 -436.23738) (xy 60.20621 -436.236966) (xy 60.18318 -436.22947) (xy 60.163605 -436.215208)
			(xy 60.149411 -436.195585) (xy 60.141993 -436.172529) (xy 60.141612 -436.160418) (xy 60.141612 -435.550056)
			(xy 60.139946 -435.535062) (xy 60.138166 -435.504944) (xy 60.138056 -435.489858) (xy 18.270456 -435.489858)
			(xy 18.27072 -435.49659) (xy 18.271236 -435.600094) (xy 18.27074 -435.702721) (xy 18.26275 -435.907821)
			(xy 18.246783 -436.112454) (xy 18.222861 -436.31631) (xy 18.191021 -436.51908) (xy 18.151311 -436.720457)
			(xy 18.103792 -436.920135) (xy 18.048535 -437.117813) (xy 17.985625 -437.313189) (xy 17.915156 -437.505968)
			(xy 17.837236 -437.695857) (xy 17.751983 -437.882569) (xy 17.659525 -438.065821) (xy 17.64623 -438.089802)
			(xy 58.13806 -438.089802) (xy 58.138177 -438.074717) (xy 58.139953 -438.044598) (xy 58.141616 -438.029604)
			(xy 58.141616 -436.950104) (xy 58.139946 -436.935111) (xy 58.138168 -436.904992) (xy 58.13806 -436.889906)
			(xy 58.138168 -436.87482) (xy 58.13995 -436.844702) (xy 58.141616 -436.829708) (xy 58.141616 -436.219092)
			(xy 58.142006 -436.207006) (xy 58.149479 -436.184019) (xy 58.16369 -436.164467) (xy 58.183248 -436.150264)
			(xy 58.206238 -436.142801) (xy 58.218324 -436.142384) (xy 59.158124 -436.142384) (xy 59.170199 -436.142844)
			(xy 59.193166 -436.150312) (xy 59.212701 -436.16451) (xy 59.226895 -436.184049) (xy 59.234359 -436.207017)
			(xy 59.234832 -436.219092) (xy 59.234832 -438.760616) (xy 59.23435 -438.772689) (xy 59.226886 -438.795653)
			(xy 59.212693 -438.815187) (xy 59.19316 -438.829382) (xy 59.170197 -438.836848) (xy 59.158124 -438.837324)
			(xy 58.218324 -438.837324) (xy 58.206244 -438.836867) (xy 58.183265 -438.829408) (xy 58.163716 -438.815213)
			(xy 58.14951 -438.795671) (xy 58.142039 -438.772696) (xy 58.141616 -438.760616) (xy 58.141616 -438.15)
			(xy 58.139945 -438.135007) (xy 58.138168 -438.104888) (xy 58.13806 -438.089802) (xy 17.64623 -438.089802)
			(xy 17.560003 -438.245334) (xy 17.453569 -438.420837) (xy 17.340383 -438.592063) (xy 17.220616 -438.758754)
			(xy 17.094452 -438.920655) (xy 16.96208 -439.077522) (xy 16.950872 -439.0898) (xy 60.138056 -439.0898)
			(xy 60.138173 -439.074715) (xy 60.139949 -439.044596) (xy 60.141612 -439.029602) (xy 60.141612 -437.950102)
			(xy 60.139941 -437.935109) (xy 60.138164 -437.90499) (xy 60.138056 -437.889904) (xy 60.138173 -437.874819)
			(xy 60.139949 -437.8447) (xy 60.141612 -437.829706) (xy 60.141612 -437.21909) (xy 60.142099 -437.207003)
			(xy 60.149555 -437.184007) (xy 60.163737 -437.164429) (xy 60.183265 -437.150178) (xy 60.206234 -437.142641)
			(xy 60.21832 -437.142128) (xy 61.15812 -437.142128) (xy 61.170233 -437.1425) (xy 61.193265 -437.150008)
			(xy 61.212841 -437.16428) (xy 61.227034 -437.183913) (xy 61.234449 -437.206976) (xy 61.234828 -437.21909)
			(xy 61.234828 -438.089802) (xy 62.138052 -438.089802) (xy 62.138169 -438.074717) (xy 62.139945 -438.044598)
			(xy 62.141608 -438.029604) (xy 62.141608 -436.950104) (xy 62.139938 -436.935111) (xy 62.13816 -436.904992)
			(xy 62.138052 -436.889906) (xy 62.13816 -436.87482) (xy 62.139942 -436.844702) (xy 62.141608 -436.829708)
			(xy 62.141608 -436.219092) (xy 62.142006 -436.207007) (xy 62.149478 -436.184021) (xy 62.163687 -436.16447)
			(xy 62.183243 -436.150267) (xy 62.206231 -436.142802) (xy 62.218316 -436.142384) (xy 63.158116 -436.142384)
			(xy 63.170191 -436.142851) (xy 63.193157 -436.150317) (xy 63.212693 -436.164513) (xy 63.226887 -436.18405)
			(xy 63.234351 -436.207017) (xy 63.234824 -436.219092) (xy 63.234824 -438.760616) (xy 63.23435 -438.77269)
			(xy 63.226885 -438.795655) (xy 63.21269 -438.81519) (xy 63.193155 -438.829385) (xy 63.17019 -438.83685)
			(xy 63.158116 -438.837324) (xy 62.218316 -438.837324) (xy 62.206244 -438.836822) (xy 62.18328 -438.829366)
			(xy 62.163744 -438.815179) (xy 62.149548 -438.795649) (xy 62.142083 -438.772688) (xy 62.141608 -438.760616)
			(xy 62.141608 -438.15) (xy 62.139937 -438.135007) (xy 62.13816 -438.104888) (xy 62.138052 -438.089802)
			(xy 61.234828 -438.089802) (xy 61.234828 -439.0898) (xy 64.138048 -439.0898) (xy 64.138165 -439.074715)
			(xy 64.139941 -439.044596) (xy 64.141604 -439.029602) (xy 64.141604 -437.950102) (xy 64.139933 -437.935109)
			(xy 64.138156 -437.90499) (xy 64.138048 -437.889904) (xy 64.138165 -437.874819) (xy 64.139941 -437.8447)
			(xy 64.141604 -437.829706) (xy 64.141604 -437.21909) (xy 64.142098 -437.207004) (xy 64.149553 -437.184009)
			(xy 64.163734 -437.164432) (xy 64.18326 -437.150181) (xy 64.206227 -437.142643) (xy 64.218312 -437.142128)
			(xy 65.158112 -437.142128) (xy 65.170224 -437.142506) (xy 65.193257 -437.150012) (xy 65.212832 -437.164283)
			(xy 65.227025 -437.183914) (xy 65.234441 -437.206976) (xy 65.23482 -437.21909) (xy 65.23482 -438.089802)
			(xy 66.138044 -438.089802) (xy 66.138161 -438.074717) (xy 66.139937 -438.044598) (xy 66.1416 -438.029604)
			(xy 66.1416 -436.950104) (xy 66.13993 -436.935111) (xy 66.138152 -436.904992) (xy 66.138044 -436.889906)
			(xy 66.138152 -436.87482) (xy 66.139934 -436.844702) (xy 66.1416 -436.829708) (xy 66.1416 -436.219092)
			(xy 66.142058 -436.207016) (xy 66.149523 -436.184047) (xy 66.163721 -436.16451) (xy 66.183262 -436.150316)
			(xy 66.206232 -436.142855) (xy 66.218308 -436.142384) (xy 67.158108 -436.142384) (xy 67.170182 -436.142857)
			(xy 67.193148 -436.150321) (xy 67.212684 -436.164516) (xy 67.226879 -436.184052) (xy 67.234343 -436.207018)
			(xy 67.234816 -436.219092) (xy 67.234816 -438.760616) (xy 67.234349 -438.772691) (xy 67.226883 -438.795657)
			(xy 67.212687 -438.815193) (xy 67.19315 -438.829387) (xy 67.170183 -438.836851) (xy 67.158108 -438.837324)
			(xy 66.218308 -438.837324) (xy 66.206235 -438.836829) (xy 66.183271 -438.829371) (xy 66.163735 -438.815182)
			(xy 66.14954 -438.79565) (xy 66.142075 -438.772688) (xy 66.1416 -438.760616) (xy 66.1416 -438.15)
			(xy 66.139929 -438.135007) (xy 66.138152 -438.104888) (xy 66.138044 -438.089802) (xy 65.23482 -438.089802)
			(xy 65.23482 -439.0898) (xy 68.13804 -439.0898) (xy 68.138157 -439.074715) (xy 68.139933 -439.044596)
			(xy 68.141596 -439.029602) (xy 68.141596 -437.950102) (xy 68.139925 -437.935109) (xy 68.138148 -437.90499)
			(xy 68.13804 -437.889904) (xy 68.138157 -437.874819) (xy 68.139933 -437.8447) (xy 68.141596 -437.829706)
			(xy 68.141596 -437.21909) (xy 68.142098 -437.207004) (xy 68.149552 -437.184011) (xy 68.163731 -437.164435)
			(xy 68.183255 -437.150183) (xy 68.20622 -437.142644) (xy 68.218304 -437.142128) (xy 69.158104 -437.142128)
			(xy 69.170216 -437.142513) (xy 69.193248 -437.150017) (xy 69.212824 -437.164286) (xy 69.227017 -437.183916)
			(xy 69.234433 -437.206977) (xy 69.234812 -437.21909) (xy 69.234812 -438.089802) (xy 70.138036 -438.089802)
			(xy 70.138153 -438.074717) (xy 70.139929 -438.044598) (xy 70.141592 -438.029604) (xy 70.141592 -436.950104)
			(xy 70.139922 -436.935111) (xy 70.138144 -436.904992) (xy 70.138036 -436.889906) (xy 70.138146 -436.87482)
			(xy 70.139928 -436.844702) (xy 70.141592 -436.829708) (xy 70.141592 -436.219092) (xy 70.142058 -436.207017)
			(xy 70.149522 -436.18405) (xy 70.163718 -436.164513) (xy 70.183257 -436.150319) (xy 70.206225 -436.142856)
			(xy 70.2183 -436.142384) (xy 71.1581 -436.142384) (xy 71.170174 -436.142864) (xy 71.19314 -436.150326)
			(xy 71.212676 -436.164518) (xy 71.226871 -436.184053) (xy 71.234335 -436.207018) (xy 71.234808 -436.219092)
			(xy 71.234808 -438.760616) (xy 71.234349 -438.772691) (xy 71.226882 -438.795659) (xy 71.212684 -438.815196)
			(xy 71.193145 -438.82939) (xy 71.170175 -438.836852) (xy 71.1581 -438.837324) (xy 70.2183 -438.837324)
			(xy 70.206227 -438.836836) (xy 70.183263 -438.829375) (xy 70.163727 -438.815184) (xy 70.149532 -438.795652)
			(xy 70.142067 -438.772689) (xy 70.141592 -438.760616) (xy 70.141592 -438.15) (xy 70.139921 -438.135007)
			(xy 70.138144 -438.104888) (xy 70.138036 -438.089802) (xy 69.234812 -438.089802) (xy 69.234812 -439.0898)
			(xy 72.138032 -439.0898) (xy 72.138151 -439.074715) (xy 72.139927 -439.044596) (xy 72.141588 -439.029602)
			(xy 72.141588 -437.950102) (xy 72.139917 -437.935109) (xy 72.13814 -437.90499) (xy 72.138032 -437.889904)
			(xy 72.138151 -437.874819) (xy 72.139927 -437.8447) (xy 72.141588 -437.829706) (xy 72.141588 -437.21909)
			(xy 72.142 -437.206995) (xy 72.149465 -437.183986) (xy 72.163664 -437.164402) (xy 72.183212 -437.150154)
			(xy 72.206202 -437.142631) (xy 72.218296 -437.142128) (xy 73.158096 -437.142128) (xy 73.170207 -437.14252)
			(xy 73.193239 -437.150022) (xy 73.212815 -437.164288) (xy 73.227009 -437.183917) (xy 73.234425 -437.206977)
			(xy 73.234804 -437.21909) (xy 73.234804 -438.089802) (xy 75.138026 -438.089802) (xy 75.138119 -438.075228)
			(xy 75.139772 -438.046127) (xy 75.141328 -438.031636) (xy 75.141328 -436.948072) (xy 75.139784 -436.93358)
			(xy 75.138131 -436.90448) (xy 75.138026 -436.889906) (xy 75.138119 -436.875332) (xy 75.139772 -436.846231)
			(xy 75.141328 -436.83174) (xy 75.141328 -436.219092) (xy 75.14171 -436.20698) (xy 75.149215 -436.183948)
			(xy 75.163484 -436.164372) (xy 75.183115 -436.150179) (xy 75.206176 -436.142763) (xy 75.21829 -436.142384)
			(xy 76.15809 -436.142384) (xy 76.170183 -436.142817) (xy 76.193191 -436.150276) (xy 76.212775 -436.16447)
			(xy 76.227024 -436.184014) (xy 76.234549 -436.207) (xy 76.235052 -436.219092) (xy 76.235052 -438.760616)
			(xy 76.234598 -438.772721) (xy 76.227101 -438.795739) (xy 76.212847 -438.815308) (xy 76.193237 -438.829504)
			(xy 76.170196 -438.836933) (xy 76.15809 -438.837324) (xy 75.21829 -438.837324) (xy 75.206196 -438.8369)
			(xy 75.183189 -438.829436) (xy 75.163607 -438.81524) (xy 75.149358 -438.795695) (xy 75.141832 -438.772708)
			(xy 75.141328 -438.760616) (xy 75.141328 -438.147968) (xy 75.139783 -438.133476) (xy 75.138131 -438.104376)
			(xy 75.138026 -438.089802) (xy 73.234804 -438.089802) (xy 73.234804 -439.0898) (xy 77.138022 -439.0898)
			(xy 77.138115 -439.075226) (xy 77.139768 -439.046125) (xy 77.141324 -439.031634) (xy 77.141324 -437.94807)
			(xy 77.139779 -437.933578) (xy 77.138127 -437.904478) (xy 77.138022 -437.889904) (xy 77.138115 -437.87533)
			(xy 77.139768 -437.846229) (xy 77.141324 -437.831738) (xy 77.141324 -437.21909) (xy 77.141803 -437.206976)
			(xy 77.149291 -437.183935) (xy 77.163532 -437.164335) (xy 77.183132 -437.150093) (xy 77.206172 -437.142604)
			(xy 77.218286 -437.142128) (xy 78.158086 -437.142128) (xy 78.170207 -437.142572) (xy 78.193264 -437.150059)
			(xy 78.212878 -437.164305) (xy 78.22713 -437.183915) (xy 78.234624 -437.206969) (xy 78.235048 -437.21909)
			(xy 78.235048 -438.089802) (xy 79.138018 -438.089802) (xy 79.138111 -438.075228) (xy 79.139764 -438.046127)
			(xy 79.14132 -438.031636) (xy 79.14132 -436.948072) (xy 79.139776 -436.93358) (xy 79.138123 -436.90448)
			(xy 79.138018 -436.889906) (xy 79.138111 -436.875332) (xy 79.139764 -436.846231) (xy 79.14132 -436.83174)
			(xy 79.14132 -436.219092) (xy 79.14171 -436.206981) (xy 79.149214 -436.18395) (xy 79.163481 -436.164375)
			(xy 79.18311 -436.150181) (xy 79.206169 -436.142764) (xy 79.218282 -436.142384) (xy 80.158082 -436.142384)
			(xy 80.170175 -436.142824) (xy 80.193182 -436.150281) (xy 80.212766 -436.164473) (xy 80.227016 -436.184015)
			(xy 80.234541 -436.207) (xy 80.235044 -436.219092) (xy 80.235044 -438.760616) (xy 80.234598 -438.772721)
			(xy 80.227099 -438.795742) (xy 80.212844 -438.815311) (xy 80.193232 -438.829506) (xy 80.170189 -438.836935)
			(xy 80.158082 -438.837324) (xy 79.218282 -438.837324) (xy 79.206188 -438.836907) (xy 79.183181 -438.829441)
			(xy 79.163598 -438.815243) (xy 79.149349 -438.795697) (xy 79.141824 -438.772709) (xy 79.14132 -438.760616)
			(xy 79.14132 -438.147968) (xy 79.139775 -438.133476) (xy 79.138123 -438.104376) (xy 79.138018 -438.089802)
			(xy 78.235048 -438.089802) (xy 78.235048 -439.0898) (xy 81.138014 -439.0898) (xy 81.138106 -439.075226)
			(xy 81.13976 -439.046125) (xy 81.141316 -439.031634) (xy 81.141316 -437.94807) (xy 81.139771 -437.933578)
			(xy 81.138119 -437.904478) (xy 81.138014 -437.889904) (xy 81.138107 -437.87533) (xy 81.13976 -437.846229)
			(xy 81.141316 -437.831738) (xy 81.141316 -437.21909) (xy 81.141803 -437.206977) (xy 81.14929 -437.183937)
			(xy 81.163529 -437.164338) (xy 81.183127 -437.150096) (xy 81.206165 -437.142605) (xy 81.218278 -437.142128)
			(xy 82.158078 -437.142128) (xy 82.170199 -437.142579) (xy 82.193255 -437.150064) (xy 82.21287 -437.164308)
			(xy 82.227122 -437.183916) (xy 82.234616 -437.20697) (xy 82.23504 -437.21909) (xy 82.23504 -438.089802)
			(xy 83.13801 -438.089802) (xy 83.138103 -438.075228) (xy 83.139756 -438.046127) (xy 83.141312 -438.031636)
			(xy 83.141312 -436.948072) (xy 83.139767 -436.93358) (xy 83.138115 -436.90448) (xy 83.13801 -436.889906)
			(xy 83.138103 -436.875332) (xy 83.139756 -436.846231) (xy 83.141312 -436.83174) (xy 83.141312 -436.219092)
			(xy 83.14171 -436.206981) (xy 83.149213 -436.183952) (xy 83.163479 -436.164378) (xy 83.183105 -436.150184)
			(xy 83.206162 -436.142765) (xy 83.218274 -436.142384) (xy 84.158074 -436.142384) (xy 84.170167 -436.14283)
			(xy 84.193174 -436.150285) (xy 84.212758 -436.164476) (xy 84.227008 -436.184017) (xy 84.234533 -436.207001)
			(xy 84.235036 -436.219092) (xy 84.235036 -438.760616) (xy 84.234598 -438.772722) (xy 84.227098 -438.795744)
			(xy 84.212841 -438.815313) (xy 84.193227 -438.829509) (xy 84.170181 -438.836936) (xy 84.158074 -438.837324)
			(xy 83.218274 -438.837324) (xy 83.206179 -438.836914) (xy 83.183172 -438.829446) (xy 83.163589 -438.815246)
			(xy 83.149341 -438.795698) (xy 83.141816 -438.772709) (xy 83.141312 -438.760616) (xy 83.141312 -438.147968)
			(xy 83.139767 -438.133476) (xy 83.138115 -438.104376) (xy 83.13801 -438.089802) (xy 82.23504 -438.089802)
			(xy 82.23504 -439.0898) (xy 85.138006 -439.0898) (xy 85.138098 -439.075226) (xy 85.139752 -439.046125)
			(xy 85.141308 -439.031634) (xy 85.141308 -437.94807) (xy 85.139763 -437.933578) (xy 85.138111 -437.904478)
			(xy 85.138006 -437.889904) (xy 85.138099 -437.87533) (xy 85.139752 -437.846229) (xy 85.141308 -437.831738)
			(xy 85.141308 -437.21909) (xy 85.141803 -437.206978) (xy 85.149289 -437.18394) (xy 85.163526 -437.164341)
			(xy 85.183122 -437.150098) (xy 85.206158 -437.142606) (xy 85.21827 -437.142128) (xy 86.15807 -437.142128)
			(xy 86.17019 -437.142585) (xy 86.193246 -437.150068) (xy 86.212861 -437.16431) (xy 86.227114 -437.183918)
			(xy 86.234608 -437.20697) (xy 86.235032 -437.21909) (xy 86.235032 -438.089802) (xy 87.138002 -438.089802)
			(xy 87.138095 -438.075228) (xy 87.139748 -438.046127) (xy 87.141304 -438.031636) (xy 87.141304 -436.948072)
			(xy 87.139759 -436.93358) (xy 87.138107 -436.90448) (xy 87.138002 -436.889906) (xy 87.138095 -436.875332)
			(xy 87.139748 -436.846231) (xy 87.141304 -436.83174) (xy 87.141304 -436.219092) (xy 87.141709 -436.206982)
			(xy 87.149212 -436.183954) (xy 87.163476 -436.164381) (xy 87.1831 -436.150186) (xy 87.206155 -436.142767)
			(xy 87.218266 -436.142384) (xy 88.158066 -436.142384) (xy 88.170158 -436.142837) (xy 88.193165 -436.15029)
			(xy 88.212749 -436.164478) (xy 88.227 -436.184018) (xy 88.234525 -436.207001) (xy 88.235028 -436.219092)
			(xy 88.235028 -438.760616) (xy 88.234598 -438.772723) (xy 88.227097 -438.795746) (xy 88.212838 -438.815316)
			(xy 88.193222 -438.829511) (xy 88.170174 -438.836937) (xy 88.158066 -438.837324) (xy 87.218266 -438.837324)
			(xy 87.206171 -438.836921) (xy 87.183163 -438.829451) (xy 87.163581 -438.815249) (xy 87.149333 -438.7957)
			(xy 87.141808 -438.77271) (xy 87.141304 -438.760616) (xy 87.141304 -438.147968) (xy 87.139759 -438.133476)
			(xy 87.138107 -438.104376) (xy 87.138002 -438.089802) (xy 86.235032 -438.089802) (xy 86.235032 -439.0898)
			(xy 89.137998 -439.0898) (xy 89.13809 -439.075226) (xy 89.139744 -439.046125) (xy 89.1413 -439.031634)
			(xy 89.1413 -437.94807) (xy 89.139755 -437.933578) (xy 89.138103 -437.904478) (xy 89.137998 -437.889904)
			(xy 89.138091 -437.87533) (xy 89.139744 -437.846229) (xy 89.1413 -437.831738) (xy 89.1413 -437.21909)
			(xy 89.141803 -437.206979) (xy 89.149288 -437.183942) (xy 89.163524 -437.164343) (xy 89.183117 -437.150101)
			(xy 89.206151 -437.142607) (xy 89.218262 -437.142128) (xy 90.158062 -437.142128) (xy 90.170182 -437.142592)
			(xy 90.193238 -437.150073) (xy 90.212853 -437.164313) (xy 90.227105 -437.183919) (xy 90.2346 -437.20697)
			(xy 90.235024 -437.21909) (xy 90.235024 -439.760614) (xy 90.234651 -439.772741) (xy 90.22715 -439.795807)
			(xy 90.212888 -439.815425) (xy 90.19326 -439.829674) (xy 90.17019 -439.837159) (xy 90.158062 -439.837576)
			(xy 89.218262 -439.837576) (xy 89.206147 -439.837121) (xy 89.183105 -439.829625) (xy 89.163505 -439.815378)
			(xy 89.149264 -439.795774) (xy 89.141775 -439.772729) (xy 89.1413 -439.760614) (xy 89.1413 -439.147966)
			(xy 89.139755 -439.133474) (xy 89.138103 -439.104374) (xy 89.137998 -439.0898) (xy 86.235032 -439.0898)
			(xy 86.235032 -439.760614) (xy 86.234651 -439.77274) (xy 86.227152 -439.795805) (xy 86.212891 -439.815422)
			(xy 86.193265 -439.829672) (xy 86.170197 -439.837158) (xy 86.15807 -439.837576) (xy 85.21827 -439.837576)
			(xy 85.206155 -439.837114) (xy 85.183113 -439.82962) (xy 85.163513 -439.815375) (xy 85.149272 -439.795772)
			(xy 85.141783 -439.772729) (xy 85.141308 -439.760614) (xy 85.141308 -439.147966) (xy 85.139763 -439.133474)
			(xy 85.138111 -439.104374) (xy 85.138006 -439.0898) (xy 82.23504 -439.0898) (xy 82.23504 -439.760614)
			(xy 82.234651 -439.77274) (xy 82.227153 -439.795803) (xy 82.212894 -439.815419) (xy 82.19327 -439.829669)
			(xy 82.170204 -439.837157) (xy 82.158078 -439.837576) (xy 81.218278 -439.837576) (xy 81.206164 -439.837107)
			(xy 81.183122 -439.829616) (xy 81.163522 -439.815372) (xy 81.149281 -439.795771) (xy 81.141791 -439.772728)
			(xy 81.141316 -439.760614) (xy 81.141316 -439.147966) (xy 81.139771 -439.133474) (xy 81.138119 -439.104374)
			(xy 81.138014 -439.0898) (xy 78.235048 -439.0898) (xy 78.235048 -439.760614) (xy 78.2346 -439.772731)
			(xy 78.227107 -439.795777) (xy 78.21286 -439.81538) (xy 78.193252 -439.82962) (xy 78.170203 -439.837105)
			(xy 78.158086 -439.837576) (xy 77.218286 -439.837576) (xy 77.206172 -439.837101) (xy 77.183131 -439.829611)
			(xy 77.16353 -439.81537) (xy 77.149289 -439.795769) (xy 77.141799 -439.772728) (xy 77.141324 -439.760614)
			(xy 77.141324 -439.147966) (xy 77.139779 -439.133474) (xy 77.138127 -439.104374) (xy 77.138022 -439.0898)
			(xy 73.234804 -439.0898) (xy 73.234804 -439.760614) (xy 73.234306 -439.7727) (xy 73.22685 -439.795694)
			(xy 73.21267 -439.81527) (xy 73.193146 -439.829521) (xy 73.17018 -439.837061) (xy 73.158096 -439.837576)
			(xy 72.218296 -439.837576) (xy 72.206185 -439.837187) (xy 72.183153 -439.829683) (xy 72.163578 -439.815416)
			(xy 72.149384 -439.795787) (xy 72.141968 -439.772727) (xy 72.141588 -439.760614) (xy 72.141588 -439.149998)
			(xy 72.139917 -439.135005) (xy 72.13814 -439.104886) (xy 72.138032 -439.0898) (xy 69.234812 -439.0898)
			(xy 69.234812 -439.760614) (xy 69.234404 -439.772709) (xy 69.226938 -439.795718) (xy 69.212737 -439.815302)
			(xy 69.193189 -439.829551) (xy 69.170198 -439.837074) (xy 69.158104 -439.837576) (xy 68.218304 -439.837576)
			(xy 68.206193 -439.83718) (xy 68.183162 -439.829679) (xy 68.163586 -439.815413) (xy 68.149392 -439.795785)
			(xy 68.141976 -439.772727) (xy 68.141596 -439.760614) (xy 68.141596 -439.149998) (xy 68.139925 -439.135005)
			(xy 68.138148 -439.104886) (xy 68.13804 -439.0898) (xy 65.23482 -439.0898) (xy 65.23482 -439.760614)
			(xy 65.234404 -439.772708) (xy 65.226939 -439.795716) (xy 65.21274 -439.815299) (xy 65.193194 -439.829548)
			(xy 65.170205 -439.837073) (xy 65.158112 -439.837576) (xy 64.218312 -439.837576) (xy 64.206201 -439.837173)
			(xy 64.18317 -439.829674) (xy 64.163595 -439.81541) (xy 64.149401 -439.795784) (xy 64.141984 -439.772726)
			(xy 64.141604 -439.760614) (xy 64.141604 -439.149998) (xy 64.139933 -439.135005) (xy 64.138156 -439.104886)
			(xy 64.138048 -439.0898) (xy 61.234828 -439.0898) (xy 61.234828 -439.760614) (xy 61.234404 -439.772708)
			(xy 61.22694 -439.795714) (xy 61.212743 -439.815297) (xy 61.193199 -439.829546) (xy 61.170212 -439.837072)
			(xy 61.15812 -439.837576) (xy 60.21832 -439.837576) (xy 60.20621 -439.837166) (xy 60.183179 -439.829669)
			(xy 60.163604 -439.815407) (xy 60.149409 -439.795782) (xy 60.141992 -439.772726) (xy 60.141612 -439.760614)
			(xy 60.141612 -439.149998) (xy 60.139941 -439.135005) (xy 60.138164 -439.104886) (xy 60.138056 -439.0898)
			(xy 16.950872 -439.0898) (xy 16.823701 -439.229117) (xy 16.679526 -439.375209) (xy 16.529773 -439.515579)
			(xy 16.374669 -439.650012) (xy 16.214449 -439.778305) (xy 16.049355 -439.900263) (xy 15.87964 -440.015701)
			(xy 15.705558 -440.124446) (xy 15.527376 -440.22633) (xy 15.436596 -440.274202) (xy 15.423478 -440.281619)
			(xy 15.401949 -440.302682) (xy 15.387495 -440.329107) (xy 15.381373 -440.358597) (xy 15.384112 -440.388591)
			(xy 15.395477 -440.416484) (xy 15.414479 -440.439853) (xy 15.439468 -440.456667) (xy 15.468273 -440.465467)
			(xy 15.483332 -440.465972) (xy 58.138314 -440.465972)
		)
		(stroke
			(width 0)
			(type solid)
		)
		(fill yes)
		(layer "In9.Cu")
		(net "P12V_AUX")
	)
	(gr_line
		(start 0.585724 -79.085694)
		(end 1.414272 -79.914242)
		(stroke
			(width 3.048)
			(type default)
		)
		(layer "In9.Cu")
	)
	(gr_arc
		(start 1.999996 -403.371812)
		(mid 2.152217 -404.13708)
		(end 2.58572 -404.78583)
		(stroke
			(width 3.048)
			(type default)
		)
		(layer "In9.Cu")
	)
	(gr_arc
		(start 1.999996 -81.32826)
		(mid 1.847757 -80.563001)
		(end 1.414272 -79.914242)
		(stroke
			(width 3.048)
			(type default)
		)
		(layer "In9.Cu")
	)
	(gr_line
		(start 1.999996 -81.32826)
		(end 1.999996 -403.371812)
		(stroke
			(width 3.048)
			(type default)
		)
		(layer "In9.Cu")
	)
	(gr_arc
		(start 1.999996 -11.780012)
		(mid 0.585785 -12.365797)
		(end 0 -13.780008)
		(stroke
			(width 3.048)
			(type default)
		)
		(layer "In9.Cu")
	)
	(gr_line
		(start 2.58572 -404.78583)
		(end 5.914644 -408.114754)
		(stroke
			(width 3.048)
			(type default)
		)
		(layer "In9.Cu")
	)
	(gr_line
		(start 6.355842 -189.490604)
		(end 12.935458 -176.65065)
		(stroke
			(width 0.508)
			(type default)
		)
		(layer "In9.Cu")
	)
	(gr_line
		(start 6.36143 -334.993742)
		(end 8.797798 -337.43011)
		(stroke
			(width 0.508)
			(type default)
		)
		(layer "In9.Cu")
	)
	(gr_line
		(start 6.36143 -327.654158)
		(end 6.36143 -334.993742)
		(stroke
			(width 0.508)
			(type default)
		)
		(layer "In9.Cu")
	)
	(gr_line
		(start 6.361938 -327.65365)
		(end 6.36143 -327.654158)
		(stroke
			(width 0.508)
			(type default)
		)
		(layer "In9.Cu")
	)
	(gr_line
		(start 6.361938 -189.46749)
		(end 6.361938 -327.65365)
		(stroke
			(width 0.508)
			(type default)
		)
		(layer "In9.Cu")
	)
	(gr_line
		(start 6.39445 -319.186306)
		(end 7.05612 -318.524636)
		(stroke
			(width 0.508)
			(type default)
		)
		(layer "In9.Cu")
	)
	(gr_line
		(start 6.436106 -318.533272)
		(end 6.448552 -318.520826)
		(stroke
			(width 0.508)
			(type default)
		)
		(layer "In9.Cu")
	)
	(gr_arc
		(start 6.500114 -439.989976)
		(mid 7.085899 -441.404187)
		(end 8.50011 -441.989972)
		(stroke
			(width 3.048)
			(type default)
		)
		(layer "In9.Cu")
	)
	(gr_arc
		(start 6.500114 -409.528264)
		(mid 6.347973 -408.763275)
		(end 5.914644 -408.114754)
		(stroke
			(width 3.048)
			(type default)
		)
		(layer "In9.Cu")
	)
	(gr_line
		(start 6.500114 -409.528264)
		(end 6.500114 -439.989976)
		(stroke
			(width 3.048)
			(type default)
		)
		(layer "In9.Cu")
	)
	(gr_line
		(start 7.05612 -318.524636)
		(end 6.401816 -317.870332)
		(stroke
			(width 0.508)
			(type default)
		)
		(layer "In9.Cu")
	)
	(gr_line
		(start 8.50011 -441.989972)
		(end 194.505072 -441.989972)
		(stroke
			(width 3.048)
			(type default)
		)
		(layer "In9.Cu")
	)
	(gr_line
		(start 8.797798 -337.43011)
		(end 9.115298 -337.43011)
		(stroke
			(width 0.508)
			(type default)
		)
		(layer "In9.Cu")
	)
	(gr_line
		(start 9.115298 -337.43011)
		(end 22.328378 -337.43011)
		(stroke
			(width 0.508)
			(type default)
		)
		(layer "In9.Cu")
	)
	(gr_line
		(start 11.102086 -11.780012)
		(end 1.999996 -11.780012)
		(stroke
			(width 3.048)
			(type default)
		)
		(layer "In9.Cu")
	)
	(gr_arc
		(start 11.102086 -11.780012)
		(mid 12.516298 -11.194228)
		(end 13.102082 -9.780016)
		(stroke
			(width 3.048)
			(type default)
		)
		(layer "In9.Cu")
	)
	(gr_line
		(start 11.492738 -318.520826)
		(end 6.448552 -318.520826)
		(stroke
			(width 0.508)
			(type default)
		)
		(layer "In9.Cu")
	)
	(gr_line
		(start 12.935458 -176.65065)
		(end 12.935458 -163.93033)
		(stroke
			(width 0.508)
			(type default)
		)
		(layer "In9.Cu")
	)
	(gr_line
		(start 13.102082 -0.999998)
		(end 13.102082 -9.780016)
		(stroke
			(width 3.048)
			(type default)
		)
		(layer "In9.Cu")
	)
	(gr_arc
		(start 14.10208 0)
		(mid 13.394975 -0.292893)
		(end 13.102082 -0.999998)
		(stroke
			(width 3.048)
			(type default)
		)
		(layer "In9.Cu")
	)
	(gr_line
		(start 17.78 -159.085788)
		(end 12.935458 -163.93033)
		(stroke
			(width 0.508)
			(type default)
		)
		(layer "In9.Cu")
	)
	(gr_line
		(start 22.328378 -337.43011)
		(end 25.069038 -340.17077)
		(stroke
			(width 0.508)
			(type default)
		)
		(layer "In9.Cu")
	)
	(gr_line
		(start 25.069038 -347.920056)
		(end 25.069038 -340.17077)
		(stroke
			(width 0.508)
			(type default)
		)
		(layer "In9.Cu")
	)
	(gr_line
		(start 25.069038 -347.920056)
		(end 36.981892 -359.83291)
		(stroke
			(width 0.508)
			(type default)
		)
		(layer "In9.Cu")
	)
	(gr_line
		(start 25.20696 -126.774448)
		(end 30.14218 -131.709668)
		(stroke
			(width 0.508)
			(type default)
		)
		(layer "In9.Cu")
	)
	(gr_line
		(start 25.20696 -44.882308)
		(end 25.20696 -126.774448)
		(stroke
			(width 0.508)
			(type default)
		)
		(layer "In9.Cu")
	)
	(gr_line
		(start 30.14218 -131.709668)
		(end 38.847776 -131.709668)
		(stroke
			(width 0.508)
			(type default)
		)
		(layer "In9.Cu")
	)
	(gr_line
		(start 31.41218 -317.861188)
		(end 30.826964 -318.446404)
		(stroke
			(width 0.508)
			(type default)
		)
		(layer "In9.Cu")
	)
	(gr_line
		(start 31.416498 -317.861188)
		(end 31.41218 -317.861188)
		(stroke
			(width 0.508)
			(type default)
		)
		(layer "In9.Cu")
	)
	(gr_line
		(start 31.489142 -318.520826)
		(end 11.492738 -318.520826)
		(stroke
			(width 0.508)
			(type default)
		)
		(layer "In9.Cu")
	)
	(gr_line
		(start 31.489142 -318.51219)
		(end 31.489142 -219.006166)
		(stroke
			(width 0.508)
			(type default)
		)
		(layer "In9.Cu")
	)
	(gr_line
		(start 31.489142 -219.006166)
		(end 32.171386 -218.323922)
		(stroke
			(width 0.508)
			(type default)
		)
		(layer "In9.Cu")
	)
	(gr_line
		(start 32.171386 -218.323922)
		(end 74.415142 -218.323922)
		(stroke
			(width 0.508)
			(type default)
		)
		(layer "In9.Cu")
	)
	(gr_line
		(start 32.60344 -37.485828)
		(end 25.20696 -44.882308)
		(stroke
			(width 0.508)
			(type default)
		)
		(layer "In9.Cu")
	)
	(gr_line
		(start 36.30041 -341.547958)
		(end 36.30041 -323.332094)
		(stroke
			(width 0.508)
			(type default)
		)
		(layer "In9.Cu")
	)
	(gr_line
		(start 36.30041 -323.332094)
		(end 31.489142 -318.520826)
		(stroke
			(width 0.508)
			(type default)
		)
		(layer "In9.Cu")
	)
	(gr_line
		(start 36.981892 -359.83291)
		(end 85.917278 -359.83291)
		(stroke
			(width 0.508)
			(type default)
		)
		(layer "In9.Cu")
	)
	(gr_line
		(start 38.225476 -343.473024)
		(end 36.30041 -341.547958)
		(stroke
			(width 0.508)
			(type default)
		)
		(layer "In9.Cu")
	)
	(gr_line
		(start 38.847776 -131.709668)
		(end 40.442642 -130.114802)
		(stroke
			(width 0.508)
			(type default)
		)
		(layer "In9.Cu")
	)
	(gr_line
		(start 40.442642 -130.114802)
		(end 109.360716 -130.114802)
		(stroke
			(width 0.508)
			(type default)
		)
		(layer "In9.Cu")
	)
	(gr_line
		(start 47.939452 -159.085788)
		(end 17.78 -159.085788)
		(stroke
			(width 0.508)
			(type default)
		)
		(layer "In9.Cu")
	)
	(gr_line
		(start 49.138078 -157.887162)
		(end 47.939452 -159.085788)
		(stroke
			(width 0.508)
			(type default)
		)
		(layer "In9.Cu")
	)
	(gr_line
		(start 49.138078 -139.22883)
		(end 49.138078 -157.887162)
		(stroke
			(width 0.508)
			(type default)
		)
		(layer "In9.Cu")
	)
	(gr_line
		(start 49.920398 -138.44651)
		(end 49.138078 -139.22883)
		(stroke
			(width 0.508)
			(type default)
		)
		(layer "In9.Cu")
	)
	(gr_line
		(start 49.920398 -138.44651)
		(end 98.095562 -138.44651)
		(stroke
			(width 0.508)
			(type default)
		)
		(layer "In9.Cu")
	)
	(gr_line
		(start 58.922158 -343.473024)
		(end 38.225476 -343.473024)
		(stroke
			(width 0.508)
			(type default)
		)
		(layer "In9.Cu")
	)
	(gr_line
		(start 60.502038 -138.448796)
		(end 61.163708 -139.110466)
		(stroke
			(width 0.508)
			(type default)
		)
		(layer "In9.Cu")
	)
	(gr_line
		(start 61.106304 -217.656664)
		(end 60.452 -218.310968)
		(stroke
			(width 0.508)
			(type default)
		)
		(layer "In9.Cu")
	)
	(gr_line
		(start 61.14034 -218.20378)
		(end 61.14034 -138.605768)
		(stroke
			(width 0.508)
			(type default)
		)
		(layer "In9.Cu")
	)
	(gr_line
		(start 61.142372 -168.862248)
		(end 61.142372 -168.8338)
		(stroke
			(width 0.508)
			(type default)
		)
		(layer "In9.Cu")
	)
	(gr_line
		(start 61.149738 -167.517826)
		(end 61.14669 -167.517826)
		(stroke
			(width 0.508)
			(type default)
		)
		(layer "In9.Cu")
	)
	(gr_line
		(start 61.163708 -139.110466)
		(end 61.818012 -138.456162)
		(stroke
			(width 0.508)
			(type default)
		)
		(layer "In9.Cu")
	)
	(gr_line
		(start 61.20765 -162.098482)
		(end 61.86932 -161.436812)
		(stroke
			(width 0.508)
			(type default)
		)
		(layer "In9.Cu")
	)
	(gr_line
		(start 61.214 -171.084748)
		(end 61.7474 -170.551348)
		(stroke
			(width 0.508)
			(type default)
		)
		(layer "In9.Cu")
	)
	(gr_line
		(start 61.260228 -161.468308)
		(end 71.738998 -161.468308)
		(stroke
			(width 0.508)
			(type default)
		)
		(layer "In9.Cu")
	)
	(gr_line
		(start 61.6966 -170.551348)
		(end 61.1886 -170.043348)
		(stroke
			(width 0.508)
			(type default)
		)
		(layer "In9.Cu")
	)
	(gr_line
		(start 61.7474 -170.551348)
		(end 61.6966 -170.551348)
		(stroke
			(width 0.508)
			(type default)
		)
		(layer "In9.Cu")
	)
	(gr_line
		(start 61.7474 -170.551348)
		(end 65.6844 -170.551348)
		(stroke
			(width 0.508)
			(type default)
		)
		(layer "In9.Cu")
	)
	(gr_line
		(start 61.767974 -218.318334)
		(end 61.106304 -217.656664)
		(stroke
			(width 0.508)
			(type default)
		)
		(layer "In9.Cu")
	)
	(gr_line
		(start 61.86932 -161.436812)
		(end 61.215016 -160.782508)
		(stroke
			(width 0.508)
			(type default)
		)
		(layer "In9.Cu")
	)
	(gr_line
		(start 65.6844 -170.551348)
		(end 68.072 -172.938948)
		(stroke
			(width 0.508)
			(type default)
		)
		(layer "In9.Cu")
	)
	(gr_line
		(start 67.93103 -334.464152)
		(end 58.922158 -343.473024)
		(stroke
			(width 0.508)
			(type default)
		)
		(layer "In9.Cu")
	)
	(gr_line
		(start 68.072 -172.938948)
		(end 74.980038 -172.938948)
		(stroke
			(width 0.508)
			(type default)
		)
		(layer "In9.Cu")
	)
	(gr_line
		(start 71.738998 -161.468308)
		(end 72.968358 -160.238948)
		(stroke
			(width 0.508)
			(type default)
		)
		(layer "In9.Cu")
	)
	(gr_line
		(start 72.711818 -333.98587)
		(end 72.291448 -334.40624)
		(stroke
			(width 0.508)
			(type default)
		)
		(layer "In9.Cu")
	)
	(gr_line
		(start 72.714358 -334.44815)
		(end 72.714358 -296.49039)
		(stroke
			(width 0.508)
			(type default)
		)
		(layer "In9.Cu")
	)
	(gr_line
		(start 72.714358 -296.49039)
		(end 80.158336 -289.046412)
		(stroke
			(width 0.508)
			(type default)
		)
		(layer "In9.Cu")
	)
	(gr_line
		(start 72.968358 -160.238948)
		(end 80.003904 -160.238948)
		(stroke
			(width 0.508)
			(type default)
		)
		(layer "In9.Cu")
	)
	(gr_line
		(start 73.176638 -334.45069)
		(end 72.711818 -333.98587)
		(stroke
			(width 0.508)
			(type default)
		)
		(layer "In9.Cu")
	)
	(gr_line
		(start 74.424794 -218.31427)
		(end 74.415142 -218.323922)
		(stroke
			(width 0.508)
			(type default)
		)
		(layer "In9.Cu")
	)
	(gr_line
		(start 74.980038 -172.938948)
		(end 77.069442 -175.028352)
		(stroke
			(width 0.508)
			(type default)
		)
		(layer "In9.Cu")
	)
	(gr_line
		(start 76.061316 -334.464152)
		(end 67.93103 -334.464152)
		(stroke
			(width 0.508)
			(type default)
		)
		(layer "In9.Cu")
	)
	(gr_line
		(start 76.26604 -347.58757)
		(end 77.935328 -349.256858)
		(stroke
			(width 0.508)
			(type default)
		)
		(layer "In9.Cu")
	)
	(gr_line
		(start 76.26604 -341.25154)
		(end 76.26604 -347.58757)
		(stroke
			(width 0.508)
			(type default)
		)
		(layer "In9.Cu")
	)
	(gr_line
		(start 77.069442 -175.028352)
		(end 85.940646 -194.906392)
		(stroke
			(width 0.508)
			(type default)
		)
		(layer "In9.Cu")
	)
	(gr_line
		(start 77.213968 -340.303612)
		(end 76.26604 -341.25154)
		(stroke
			(width 0.508)
			(type default)
		)
		(layer "In9.Cu")
	)
	(gr_line
		(start 77.935328 -349.256858)
		(end 85.83295 -349.256858)
		(stroke
			(width 0.508)
			(type default)
		)
		(layer "In9.Cu")
	)
	(gr_line
		(start 79.973678 -330.55179)
		(end 76.061316 -334.464152)
		(stroke
			(width 0.508)
			(type default)
		)
		(layer "In9.Cu")
	)
	(gr_line
		(start 80.003904 -160.238948)
		(end 83.08594 -163.320984)
		(stroke
			(width 0.508)
			(type default)
		)
		(layer "In9.Cu")
	)
	(gr_line
		(start 80.158336 -289.046412)
		(end 103.48849 -289.046412)
		(stroke
			(width 0.508)
			(type default)
		)
		(layer "In9.Cu")
	)
	(gr_line
		(start 80.701896 0)
		(end 14.10208 0)
		(stroke
			(width 3.048)
			(type default)
		)
		(layer "In9.Cu")
	)
	(gr_line
		(start 80.841088 -345.232482)
		(end 83.009486 -347.40088)
		(stroke
			(width 0.254)
			(type default)
		)
		(layer "In9.Cu")
	)
	(gr_line
		(start 80.841088 -343.195148)
		(end 80.841088 -345.232482)
		(stroke
			(width 0.254)
			(type default)
		)
		(layer "In9.Cu")
	)
	(gr_line
		(start 81.011776 -343.02446)
		(end 80.841088 -343.195148)
		(stroke
			(width 0.254)
			(type default)
		)
		(layer "In9.Cu")
	)
	(gr_line
		(start 81.701894 -9.780016)
		(end 81.701894 -0.999998)
		(stroke
			(width 3.048)
			(type default)
		)
		(layer "In9.Cu")
	)
	(gr_arc
		(start 81.701894 -9.780016)
		(mid 82.287684 -11.19422)
		(end 83.70189 -11.780012)
		(stroke
			(width 3.048)
			(type default)
		)
		(layer "In9.Cu")
	)
	(gr_arc
		(start 81.701894 -0.999998)
		(mid 81.409001 -0.292893)
		(end 80.701896 0)
		(stroke
			(width 3.048)
			(type default)
		)
		(layer "In9.Cu")
	)
	(gr_line
		(start 82.092292 -162.32759)
		(end 115.359942 -195.59524)
		(stroke
			(width 0.508)
			(type default)
		)
		(layer "In9.Cu")
	)
	(gr_line
		(start 82.996024 -348.857316)
		(end 82.750406 -349.102934)
		(stroke
			(width 0.254)
			(type default)
		)
		(layer "In9.Cu")
	)
	(gr_line
		(start 82.996024 -348.83598)
		(end 83.250024 -349.08998)
		(stroke
			(width 0.254)
			(type default)
		)
		(layer "In9.Cu")
	)
	(gr_line
		(start 83.009486 -347.40088)
		(end 83.009486 -348.96298)
		(stroke
			(width 0.254)
			(type default)
		)
		(layer "In9.Cu")
	)
	(gr_line
		(start 83.123532 -340.303612)
		(end 77.213968 -340.303612)
		(stroke
			(width 0.508)
			(type default)
		)
		(layer "In9.Cu")
	)
	(gr_line
		(start 83.503008 -339.924136)
		(end 83.123532 -340.303612)
		(stroke
			(width 0.508)
			(type default)
		)
		(layer "In9.Cu")
	)
	(gr_line
		(start 83.503008 -336.813144)
		(end 83.503008 -339.924136)
		(stroke
			(width 0.508)
			(type default)
		)
		(layer "In9.Cu")
	)
	(gr_line
		(start 83.593178 -330.55179)
		(end 79.973678 -330.55179)
		(stroke
			(width 0.508)
			(type default)
		)
		(layer "In9.Cu")
	)
	(gr_line
		(start 84.66836 -343.02446)
		(end 81.011776 -343.02446)
		(stroke
			(width 0.254)
			(type default)
		)
		(layer "In9.Cu")
	)
	(gr_line
		(start 84.854542 -329.290426)
		(end 83.593178 -330.55179)
		(stroke
			(width 0.508)
			(type default)
		)
		(layer "In9.Cu")
	)
	(gr_line
		(start 84.854542 -327.37171)
		(end 84.854542 -329.290426)
		(stroke
			(width 0.508)
			(type default)
		)
		(layer "In9.Cu")
	)
	(gr_line
		(start 85.143848 -343.499948)
		(end 84.66836 -343.02446)
		(stroke
			(width 0.254)
			(type default)
		)
		(layer "In9.Cu")
	)
	(gr_line
		(start 85.751162 -334.56499)
		(end 83.503008 -336.813144)
		(stroke
			(width 0.508)
			(type default)
		)
		(layer "In9.Cu")
	)
	(gr_line
		(start 85.768942 -326.45731)
		(end 84.854542 -327.37171)
		(stroke
			(width 0.508)
			(type default)
		)
		(layer "In9.Cu")
	)
	(gr_line
		(start 85.83295 -349.256858)
		(end 87.483442 -350.90735)
		(stroke
			(width 0.508)
			(type default)
		)
		(layer "In9.Cu")
	)
	(gr_line
		(start 85.917278 -359.83291)
		(end 87.334598 -358.41559)
		(stroke
			(width 0.508)
			(type default)
		)
		(layer "In9.Cu")
	)
	(gr_line
		(start 87.334598 -358.41559)
		(end 87.334598 -355.68763)
		(stroke
			(width 0.508)
			(type default)
		)
		(layer "In9.Cu")
	)
	(gr_line
		(start 87.334598 -355.68763)
		(end 88.221058 -354.80117)
		(stroke
			(width 0.508)
			(type default)
		)
		(layer "In9.Cu")
	)
	(gr_line
		(start 87.483442 -350.90735)
		(end 88.251792 -351.6757)
		(stroke
			(width 0.508)
			(type default)
		)
		(layer "In9.Cu")
	)
	(gr_line
		(start 88.221058 -354.80117)
		(end 101.689662 -354.80117)
		(stroke
			(width 0.508)
			(type default)
		)
		(layer "In9.Cu")
	)
	(gr_line
		(start 88.251792 -351.6757)
		(end 95.84817 -351.6757)
		(stroke
			(width 0.508)
			(type default)
		)
		(layer "In9.Cu")
	)
	(gr_line
		(start 88.595962 -343.499948)
		(end 85.143848 -343.499948)
		(stroke
			(width 0.254)
			(type default)
		)
		(layer "In9.Cu")
	)
	(gr_line
		(start 88.925146 -206.024734)
		(end 85.940646 -194.906392)
		(stroke
			(width 0.508)
			(type default)
		)
		(layer "In9.Cu")
	)
	(gr_line
		(start 89.051638 -339.654134)
		(end 89.715086 -340.317582)
		(stroke
			(width 0.254)
			(type default)
		)
		(layer "In9.Cu")
	)
	(gr_line
		(start 89.051638 -337.30692)
		(end 89.051638 -339.654134)
		(stroke
			(width 0.254)
			(type default)
		)
		(layer "In9.Cu")
	)
	(gr_line
		(start 89.104978 -218.31427)
		(end 74.424794 -218.31427)
		(stroke
			(width 0.508)
			(type default)
		)
		(layer "In9.Cu")
	)
	(gr_line
		(start 89.12733 -337.231228)
		(end 89.051638 -337.30692)
		(stroke
			(width 0.254)
			(type default)
		)
		(layer "In9.Cu")
	)
	(gr_line
		(start 89.12733 -337.231228)
		(end 92.801694 -337.231228)
		(stroke
			(width 0.254)
			(type default)
		)
		(layer "In9.Cu")
	)
	(gr_line
		(start 89.528142 -260.92531)
		(end 89.528142 -233.665522)
		(stroke
			(width 0.508)
			(type default)
		)
		(layer "In9.Cu")
	)
	(gr_line
		(start 89.528142 -233.665522)
		(end 97.108518 -226.085146)
		(stroke
			(width 0.508)
			(type default)
		)
		(layer "In9.Cu")
	)
	(gr_line
		(start 89.564718 -217.85453)
		(end 89.104978 -218.31427)
		(stroke
			(width 0.508)
			(type default)
		)
		(layer "In9.Cu")
	)
	(gr_line
		(start 89.715086 -342.380824)
		(end 88.595962 -343.499948)
		(stroke
			(width 0.254)
			(type default)
		)
		(layer "In9.Cu")
	)
	(gr_line
		(start 89.715086 -340.317582)
		(end 89.715086 -342.380824)
		(stroke
			(width 0.254)
			(type default)
		)
		(layer "In9.Cu")
	)
	(gr_line
		(start 91.116658 -334.56499)
		(end 85.751162 -334.56499)
		(stroke
			(width 0.508)
			(type default)
		)
		(layer "In9.Cu")
	)
	(gr_line
		(start 91.458542 -326.45731)
		(end 85.768942 -326.45731)
		(stroke
			(width 0.508)
			(type default)
		)
		(layer "In9.Cu")
	)
	(gr_line
		(start 91.463368 -334.21828)
		(end 91.116658 -334.56499)
		(stroke
			(width 0.508)
			(type default)
		)
		(layer "In9.Cu")
	)
	(gr_line
		(start 91.463368 -332.966314)
		(end 91.463368 -334.21828)
		(stroke
			(width 0.508)
			(type default)
		)
		(layer "In9.Cu")
	)
	(gr_line
		(start 91.51366 -37.485828)
		(end 32.60344 -37.485828)
		(stroke
			(width 0.508)
			(type default)
		)
		(layer "In9.Cu")
	)
	(gr_line
		(start 92.779342 -325.13651)
		(end 91.458542 -326.45731)
		(stroke
			(width 0.508)
			(type default)
		)
		(layer "In9.Cu")
	)
	(gr_line
		(start 92.779342 -323.46011)
		(end 92.779342 -325.13651)
		(stroke
			(width 0.508)
			(type default)
		)
		(layer "In9.Cu")
	)
	(gr_line
		(start 92.801694 -337.231228)
		(end 92.920058 -337.349592)
		(stroke
			(width 0.254)
			(type default)
		)
		(layer "In9.Cu")
	)
	(gr_line
		(start 92.920058 -337.349592)
		(end 92.920058 -339.383624)
		(stroke
			(width 0.254)
			(type default)
		)
		(layer "In9.Cu")
	)
	(gr_line
		(start 93.171518 -339.635084)
		(end 92.920058 -339.383624)
		(stroke
			(width 0.254)
			(type default)
		)
		(layer "In9.Cu")
	)
	(gr_line
		(start 93.247464 -331.182218)
		(end 91.463368 -332.966314)
		(stroke
			(width 0.508)
			(type default)
		)
		(layer "In9.Cu")
	)
	(gr_line
		(start 93.261942 -322.97751)
		(end 92.779342 -323.46011)
		(stroke
			(width 0.508)
			(type default)
		)
		(layer "In9.Cu")
	)
	(gr_line
		(start 94.812358 -217.85453)
		(end 89.564718 -217.85453)
		(stroke
			(width 0.508)
			(type default)
		)
		(layer "In9.Cu")
	)
	(gr_line
		(start 95.167958 -219.61729)
		(end 95.167958 -218.76639)
		(stroke
			(width 0.508)
			(type default)
		)
		(layer "In9.Cu")
	)
	(gr_line
		(start 95.167958 -218.76639)
		(end 95.180658 -218.75369)
		(stroke
			(width 0.508)
			(type default)
		)
		(layer "In9.Cu")
	)
	(gr_line
		(start 95.180658 -218.75369)
		(end 95.180658 -218.22283)
		(stroke
			(width 0.508)
			(type default)
		)
		(layer "In9.Cu")
	)
	(gr_line
		(start 95.180658 -218.22283)
		(end 94.812358 -217.85453)
		(stroke
			(width 0.508)
			(type default)
		)
		(layer "In9.Cu")
	)
	(gr_line
		(start 95.84817 -351.6757)
		(end 97.721928 -349.801942)
		(stroke
			(width 0.508)
			(type default)
		)
		(layer "In9.Cu")
	)
	(gr_line
		(start 96.640142 -268.03731)
		(end 89.528142 -260.92531)
		(stroke
			(width 0.508)
			(type default)
		)
		(layer "In9.Cu")
	)
	(gr_line
		(start 96.732598 -260.52399)
		(end 97.286318 -261.07771)
		(stroke
			(width 0.508)
			(type default)
		)
		(layer "In9.Cu")
	)
	(gr_line
		(start 96.732598 -234.93857)
		(end 96.732598 -260.52399)
		(stroke
			(width 0.508)
			(type default)
		)
		(layer "In9.Cu")
	)
	(gr_line
		(start 97.108518 -226.085146)
		(end 97.108518 -221.55785)
		(stroke
			(width 0.508)
			(type default)
		)
		(layer "In9.Cu")
	)
	(gr_line
		(start 97.108518 -221.55785)
		(end 95.167958 -219.61729)
		(stroke
			(width 0.508)
			(type default)
		)
		(layer "In9.Cu")
	)
	(gr_line
		(start 97.189544 -335.993486)
		(end 98.115374 -336.919316)
		(stroke
			(width 0.254)
			(type default)
		)
		(layer "In9.Cu")
	)
	(gr_line
		(start 97.189544 -333.929736)
		(end 97.189544 -335.993486)
		(stroke
			(width 0.254)
			(type default)
		)
		(layer "In9.Cu")
	)
	(gr_line
		(start 97.286318 -261.07771)
		(end 102.532942 -261.07771)
		(stroke
			(width 0.508)
			(type default)
		)
		(layer "In9.Cu")
	)
	(gr_line
		(start 97.316798 -333.802482)
		(end 97.189544 -333.929736)
		(stroke
			(width 0.254)
			(type default)
		)
		(layer "In9.Cu")
	)
	(gr_line
		(start 97.429574 -339.635084)
		(end 93.171518 -339.635084)
		(stroke
			(width 0.254)
			(type default)
		)
		(layer "In9.Cu")
	)
	(gr_line
		(start 97.61474 -31.384748)
		(end 91.51366 -37.485828)
		(stroke
			(width 0.508)
			(type default)
		)
		(layer "In9.Cu")
	)
	(gr_line
		(start 97.721928 -349.801942)
		(end 113.672874 -349.801942)
		(stroke
			(width 0.508)
			(type default)
		)
		(layer "In9.Cu")
	)
	(gr_line
		(start 98.095562 -138.44651)
		(end 152.596342 -192.94729)
		(stroke
			(width 0.508)
			(type default)
		)
		(layer "In9.Cu")
	)
	(gr_line
		(start 98.115374 -338.949284)
		(end 97.429574 -339.635084)
		(stroke
			(width 0.254)
			(type default)
		)
		(layer "In9.Cu")
	)
	(gr_line
		(start 98.115374 -336.919316)
		(end 98.115374 -338.949284)
		(stroke
			(width 0.254)
			(type default)
		)
		(layer "In9.Cu")
	)
	(gr_line
		(start 98.570542 -233.100626)
		(end 96.732598 -234.93857)
		(stroke
			(width 0.508)
			(type default)
		)
		(layer "In9.Cu")
	)
	(gr_line
		(start 98.570542 -233.100626)
		(end 100.894134 -230.777034)
		(stroke
			(width 0.508)
			(type default)
		)
		(layer "In9.Cu")
	)
	(gr_line
		(start 100.864162 -333.802482)
		(end 97.316798 -333.802482)
		(stroke
			(width 0.254)
			(type default)
		)
		(layer "In9.Cu")
	)
	(gr_line
		(start 100.894134 -219.286836)
		(end 100.894134 -213.23935)
		(stroke
			(width 0.508)
			(type default)
		)
		(layer "In9.Cu")
	)
	(gr_line
		(start 100.894134 -219.286836)
		(end 102.683818 -221.07652)
		(stroke
			(width 0.508)
			(type default)
		)
		(layer "In9.Cu")
	)
	(gr_line
		(start 100.894134 -213.23935)
		(end 88.925146 -206.024734)
		(stroke
			(width 0.508)
			(type default)
		)
		(layer "In9.Cu")
	)
	(gr_line
		(start 100.99294 -338.73694)
		(end 100.99294 -333.93126)
		(stroke
			(width 0.254)
			(type default)
		)
		(layer "In9.Cu")
	)
	(gr_line
		(start 100.99294 -333.93126)
		(end 100.864162 -333.802482)
		(stroke
			(width 0.254)
			(type default)
		)
		(layer "In9.Cu")
	)
	(gr_line
		(start 101.689662 -354.80117)
		(end 104.641142 -357.75265)
		(stroke
			(width 0.508)
			(type default)
		)
		(layer "In9.Cu")
	)
	(gr_line
		(start 101.923596 -339.667596)
		(end 100.99294 -338.73694)
		(stroke
			(width 0.254)
			(type default)
		)
		(layer "In9.Cu")
	)
	(gr_line
		(start 102.683818 -228.98735)
		(end 100.894134 -230.777034)
		(stroke
			(width 0.508)
			(type default)
		)
		(layer "In9.Cu")
	)
	(gr_line
		(start 102.683818 -221.07652)
		(end 102.683818 -228.98735)
		(stroke
			(width 0.508)
			(type default)
		)
		(layer "In9.Cu")
	)
	(gr_line
		(start 102.710742 -268.03731)
		(end 96.640142 -268.03731)
		(stroke
			(width 0.508)
			(type default)
		)
		(layer "In9.Cu")
	)
	(gr_line
		(start 102.79888 -258.166108)
		(end 102.79888 -257.42773)
		(stroke
			(width 0.508)
			(type default)
		)
		(layer "In9.Cu")
	)
	(gr_line
		(start 102.79888 -257.42773)
		(end 103.091742 -257.134868)
		(stroke
			(width 0.508)
			(type default)
		)
		(layer "In9.Cu")
	)
	(gr_line
		(start 103.040942 -245.32971)
		(end 103.574342 -245.86311)
		(stroke
			(width 0.508)
			(type default)
		)
		(layer "In9.Cu")
	)
	(gr_line
		(start 103.040942 -239.43691)
		(end 103.040942 -245.32971)
		(stroke
			(width 0.508)
			(type default)
		)
		(layer "In9.Cu")
	)
	(gr_line
		(start 103.091742 -260.51891)
		(end 102.532942 -261.07771)
		(stroke
			(width 0.508)
			(type default)
		)
		(layer "In9.Cu")
	)
	(gr_line
		(start 103.091742 -260.51891)
		(end 103.091742 -258.45897)
		(stroke
			(width 0.508)
			(type default)
		)
		(layer "In9.Cu")
	)
	(gr_line
		(start 103.091742 -258.45897)
		(end 102.79888 -258.166108)
		(stroke
			(width 0.508)
			(type default)
		)
		(layer "In9.Cu")
	)
	(gr_line
		(start 103.091742 -257.134868)
		(end 103.091742 -256.27711)
		(stroke
			(width 0.508)
			(type default)
		)
		(layer "In9.Cu")
	)
	(gr_line
		(start 103.091742 -248.50471)
		(end 103.091742 -256.27711)
		(stroke
			(width 0.508)
			(type default)
		)
		(layer "In9.Cu")
	)
	(gr_line
		(start 103.156766 -256.890774)
		(end 103.485696 -256.561844)
		(stroke
			(width 0.508)
			(type default)
		)
		(layer "In9.Cu")
	)
	(gr_line
		(start 103.480362 -256.402332)
		(end 103.151432 -256.073402)
		(stroke
			(width 0.508)
			(type default)
		)
		(layer "In9.Cu")
	)
	(gr_line
		(start 103.548942 -256.48031)
		(end 103.294942 -256.48031)
		(stroke
			(width 0.508)
			(type default)
		)
		(layer "In9.Cu")
	)
	(gr_line
		(start 103.548942 -256.48031)
		(end 104.742742 -256.48031)
		(stroke
			(width 0.508)
			(type default)
		)
		(layer "In9.Cu")
	)
	(gr_line
		(start 103.574342 -248.02211)
		(end 103.091742 -248.50471)
		(stroke
			(width 0.508)
			(type default)
		)
		(layer "In9.Cu")
	)
	(gr_line
		(start 103.574342 -245.86311)
		(end 104.793542 -245.86311)
		(stroke
			(width 0.508)
			(type default)
		)
		(layer "In9.Cu")
	)
	(gr_line
		(start 104.20096 -261.592568)
		(end 104.20096 -261.163308)
		(stroke
			(width 0.254)
			(type default)
		)
		(layer "In9.Cu")
	)
	(gr_line
		(start 104.20096 -261.163308)
		(end 104.591358 -260.77291)
		(stroke
			(width 0.254)
			(type default)
		)
		(layer "In9.Cu")
	)
	(gr_line
		(start 104.366314 -288.168588)
		(end 103.48849 -289.046412)
		(stroke
			(width 0.508)
			(type default)
		)
		(layer "In9.Cu")
	)
	(gr_line
		(start 104.366314 -283.765752)
		(end 104.366314 -288.168588)
		(stroke
			(width 0.508)
			(type default)
		)
		(layer "In9.Cu")
	)
	(gr_line
		(start 104.387142 -238.09071)
		(end 103.040942 -239.43691)
		(stroke
			(width 0.508)
			(type default)
		)
		(layer "In9.Cu")
	)
	(gr_line
		(start 104.412542 -266.33551)
		(end 102.710742 -268.03731)
		(stroke
			(width 0.508)
			(type default)
		)
		(layer "In9.Cu")
	)
	(gr_line
		(start 104.412542 -266.33551)
		(end 104.412542 -262.01751)
		(stroke
			(width 0.508)
			(type default)
		)
		(layer "In9.Cu")
	)
	(gr_line
		(start 104.412542 -262.01751)
		(end 104.412542 -261.80415)
		(stroke
			(width 0.254)
			(type default)
		)
		(layer "In9.Cu")
	)
	(gr_line
		(start 104.412542 -261.80415)
		(end 104.20096 -261.592568)
		(stroke
			(width 0.254)
			(type default)
		)
		(layer "In9.Cu")
	)
	(gr_line
		(start 104.488742 -248.02211)
		(end 103.574342 -248.02211)
		(stroke
			(width 0.508)
			(type default)
		)
		(layer "In9.Cu")
	)
	(gr_line
		(start 104.591358 -260.77291)
		(end 105.530142 -260.77291)
		(stroke
			(width 0.254)
			(type default)
		)
		(layer "In9.Cu")
	)
	(gr_line
		(start 104.641142 -357.75265)
		(end 128.981962 -357.75265)
		(stroke
			(width 0.508)
			(type default)
		)
		(layer "In9.Cu")
	)
	(gr_line
		(start 104.742742 -256.48031)
		(end 105.250742 -256.98831)
		(stroke
			(width 0.508)
			(type default)
		)
		(layer "In9.Cu")
	)
	(gr_line
		(start 104.793542 -245.86311)
		(end 105.123742 -246.19331)
		(stroke
			(width 0.508)
			(type default)
		)
		(layer "In9.Cu")
	)
	(gr_line
		(start 105.123742 -247.38711)
		(end 104.488742 -248.02211)
		(stroke
			(width 0.508)
			(type default)
		)
		(layer "In9.Cu")
	)
	(gr_line
		(start 105.123742 -246.19331)
		(end 105.123742 -247.38711)
		(stroke
			(width 0.508)
			(type default)
		)
		(layer "In9.Cu")
	)
	(gr_line
		(start 105.250742 -260.49351)
		(end 105.571544 -260.814312)
		(stroke
			(width 0.508)
			(type default)
		)
		(layer "In9.Cu")
	)
	(gr_line
		(start 105.250742 -256.98831)
		(end 105.250742 -260.49351)
		(stroke
			(width 0.508)
			(type default)
		)
		(layer "In9.Cu")
	)
	(gr_line
		(start 105.348786 -336.030824)
		(end 106.154474 -336.836512)
		(stroke
			(width 0.254)
			(type default)
		)
		(layer "In9.Cu")
	)
	(gr_line
		(start 105.348786 -333.936594)
		(end 105.348786 -336.030824)
		(stroke
			(width 0.254)
			(type default)
		)
		(layer "In9.Cu")
	)
	(gr_line
		(start 105.484676 -333.800704)
		(end 105.348786 -333.936594)
		(stroke
			(width 0.254)
			(type default)
		)
		(layer "In9.Cu")
	)
	(gr_line
		(start 105.571544 -260.814312)
		(end 107.629198 -260.814312)
		(stroke
			(width 0.508)
			(type default)
		)
		(layer "In9.Cu")
	)
	(gr_line
		(start 105.722928 -339.667596)
		(end 101.923596 -339.667596)
		(stroke
			(width 0.254)
			(type default)
		)
		(layer "In9.Cu")
	)
	(gr_line
		(start 106.154474 -339.23605)
		(end 105.722928 -339.667596)
		(stroke
			(width 0.254)
			(type default)
		)
		(layer "In9.Cu")
	)
	(gr_line
		(start 106.154474 -336.836512)
		(end 106.154474 -339.23605)
		(stroke
			(width 0.254)
			(type default)
		)
		(layer "In9.Cu")
	)
	(gr_line
		(start 106.91495 -263.604756)
		(end 108.127038 -264.816844)
		(stroke
			(width 0.508)
			(type default)
		)
		(layer "In9.Cu")
	)
	(gr_line
		(start 106.91495 -262.118094)
		(end 106.91495 -263.604756)
		(stroke
			(width 0.508)
			(type default)
		)
		(layer "In9.Cu")
	)
	(gr_line
		(start 107.249214 -261.78383)
		(end 106.91495 -262.118094)
		(stroke
			(width 0.508)
			(type default)
		)
		(layer "In9.Cu")
	)
	(gr_line
		(start 107.557316 -261.78383)
		(end 107.249214 -261.78383)
		(stroke
			(width 0.508)
			(type default)
		)
		(layer "In9.Cu")
	)
	(gr_line
		(start 107.629198 -260.814312)
		(end 107.89793 -261.083044)
		(stroke
			(width 0.508)
			(type default)
		)
		(layer "In9.Cu")
	)
	(gr_line
		(start 107.89793 -261.443216)
		(end 107.557316 -261.78383)
		(stroke
			(width 0.508)
			(type default)
		)
		(layer "In9.Cu")
	)
	(gr_line
		(start 107.89793 -261.083044)
		(end 107.89793 -261.443216)
		(stroke
			(width 0.508)
			(type default)
		)
		(layer "In9.Cu")
	)
	(gr_line
		(start 108.127038 -280.005028)
		(end 104.366314 -283.765752)
		(stroke
			(width 0.508)
			(type default)
		)
		(layer "In9.Cu")
	)
	(gr_line
		(start 108.127038 -264.816844)
		(end 108.127038 -280.005028)
		(stroke
			(width 0.508)
			(type default)
		)
		(layer "In9.Cu")
	)
	(gr_line
		(start 109.00537 -338.589366)
		(end 109.00537 -337.58124)
		(stroke
			(width 0.254)
			(type default)
		)
		(layer "In9.Cu")
	)
	(gr_line
		(start 109.00537 -337.58124)
		(end 109.2581 -337.32851)
		(stroke
			(width 0.254)
			(type default)
		)
		(layer "In9.Cu")
	)
	(gr_line
		(start 109.073442 -333.800704)
		(end 105.484676 -333.800704)
		(stroke
			(width 0.254)
			(type default)
		)
		(layer "In9.Cu")
	)
	(gr_line
		(start 109.2581 -337.32851)
		(end 109.2581 -333.985362)
		(stroke
			(width 0.254)
			(type default)
		)
		(layer "In9.Cu")
	)
	(gr_line
		(start 109.2581 -333.985362)
		(end 109.073442 -333.800704)
		(stroke
			(width 0.254)
			(type default)
		)
		(layer "In9.Cu")
	)
	(gr_line
		(start 109.360716 -130.114802)
		(end 211.767166 -130.114802)
		(stroke
			(width 0.508)
			(type default)
		)
		(layer "In9.Cu")
	)
	(gr_line
		(start 110.059978 -339.643974)
		(end 109.00537 -338.589366)
		(stroke
			(width 0.254)
			(type default)
		)
		(layer "In9.Cu")
	)
	(gr_line
		(start 113.530634 -336.00898)
		(end 114.17554 -336.653886)
		(stroke
			(width 0.254)
			(type default)
		)
		(layer "In9.Cu")
	)
	(gr_line
		(start 113.530634 -333.912972)
		(end 113.530634 -336.00898)
		(stroke
			(width 0.254)
			(type default)
		)
		(layer "In9.Cu")
	)
	(gr_line
		(start 113.64214 -333.801466)
		(end 113.530634 -333.912972)
		(stroke
			(width 0.254)
			(type default)
		)
		(layer "In9.Cu")
	)
	(gr_line
		(start 113.672874 -349.801942)
		(end 115.75542 -351.884488)
		(stroke
			(width 0.508)
			(type default)
		)
		(layer "In9.Cu")
	)
	(gr_line
		(start 113.720118 -339.643974)
		(end 110.059978 -339.643974)
		(stroke
			(width 0.254)
			(type default)
		)
		(layer "In9.Cu")
	)
	(gr_line
		(start 114.17554 -339.188552)
		(end 113.720118 -339.643974)
		(stroke
			(width 0.254)
			(type default)
		)
		(layer "In9.Cu")
	)
	(gr_line
		(start 114.17554 -336.653886)
		(end 114.17554 -339.188552)
		(stroke
			(width 0.254)
			(type default)
		)
		(layer "In9.Cu")
	)
	(gr_line
		(start 115.334542 -238.09071)
		(end 104.387142 -238.09071)
		(stroke
			(width 0.508)
			(type default)
		)
		(layer "In9.Cu")
	)
	(gr_line
		(start 115.359942 -227.72751)
		(end 115.359942 -218.46413)
		(stroke
			(width 0.508)
			(type default)
		)
		(layer "In9.Cu")
	)
	(gr_line
		(start 115.359942 -227.72751)
		(end 127.243078 -239.610646)
		(stroke
			(width 0.508)
			(type default)
		)
		(layer "In9.Cu")
	)
	(gr_line
		(start 115.359942 -211.048854)
		(end 115.359942 -218.46413)
		(stroke
			(width 0.508)
			(type default)
		)
		(layer "In9.Cu")
	)
	(gr_line
		(start 115.359942 -195.59524)
		(end 115.359942 -211.048854)
		(stroke
			(width 0.508)
			(type default)
		)
		(layer "In9.Cu")
	)
	(gr_line
		(start 115.75542 -351.884488)
		(end 120.08358 -351.884488)
		(stroke
			(width 0.508)
			(type default)
		)
		(layer "In9.Cu")
	)
	(gr_line
		(start 115.842542 -240.02111)
		(end 115.842542 -238.59871)
		(stroke
			(width 0.508)
			(type default)
		)
		(layer "In9.Cu")
	)
	(gr_line
		(start 115.842542 -238.59871)
		(end 115.334542 -238.09071)
		(stroke
			(width 0.508)
			(type default)
		)
		(layer "In9.Cu")
	)
	(gr_line
		(start 116.020342 -279.08631)
		(end 116.020342 -261.17931)
		(stroke
			(width 0.508)
			(type default)
		)
		(layer "In9.Cu")
	)
	(gr_line
		(start 116.020342 -261.17931)
		(end 116.680742 -260.51891)
		(stroke
			(width 0.508)
			(type default)
		)
		(layer "In9.Cu")
	)
	(gr_line
		(start 116.680742 -260.51891)
		(end 120.668542 -260.51891)
		(stroke
			(width 0.508)
			(type default)
		)
		(layer "In9.Cu")
	)
	(gr_line
		(start 117.22608 -333.801466)
		(end 113.64214 -333.801466)
		(stroke
			(width 0.254)
			(type default)
		)
		(layer "In9.Cu")
	)
	(gr_line
		(start 117.375686 -338.88045)
		(end 117.375686 -333.951072)
		(stroke
			(width 0.254)
			(type default)
		)
		(layer "In9.Cu")
	)
	(gr_line
		(start 117.375686 -333.951072)
		(end 117.22608 -333.801466)
		(stroke
			(width 0.254)
			(type default)
		)
		(layer "In9.Cu")
	)
	(gr_line
		(start 117.747542 -241.92611)
		(end 115.842542 -240.02111)
		(stroke
			(width 0.508)
			(type default)
		)
		(layer "In9.Cu")
	)
	(gr_line
		(start 118.3005 -339.805264)
		(end 117.375686 -338.88045)
		(stroke
			(width 0.254)
			(type default)
		)
		(layer "In9.Cu")
	)
	(gr_line
		(start 118.618 -246.835168)
		(end 121.100342 -249.31751)
		(stroke
			(width 0.508)
			(type default)
		)
		(layer "In9.Cu")
	)
	(gr_line
		(start 118.618 -245.068852)
		(end 118.618 -246.835168)
		(stroke
			(width 0.508)
			(type default)
		)
		(layer "In9.Cu")
	)
	(gr_line
		(start 118.661942 -270.06931)
		(end 118.661942 -260.84911)
		(stroke
			(width 0.254)
			(type default)
		)
		(layer "In9.Cu")
	)
	(gr_line
		(start 118.661942 -260.84911)
		(end 118.407942 -260.59511)
		(stroke
			(width 0.254)
			(type default)
		)
		(layer "In9.Cu")
	)
	(gr_line
		(start 118.92788 -260.632448)
		(end 118.67388 -260.886448)
		(stroke
			(width 0.254)
			(type default)
		)
		(layer "In9.Cu")
	)
	(gr_line
		(start 119.423942 -270.83131)
		(end 118.661942 -270.06931)
		(stroke
			(width 0.254)
			(type default)
		)
		(layer "In9.Cu")
	)
	(gr_line
		(start 120.08358 -351.884488)
		(end 121.790968 -350.1771)
		(stroke
			(width 0.508)
			(type default)
		)
		(layer "In9.Cu")
	)
	(gr_line
		(start 120.084342 -243.60251)
		(end 118.618 -245.068852)
		(stroke
			(width 0.508)
			(type default)
		)
		(layer "In9.Cu")
	)
	(gr_line
		(start 120.084342 -243.60251)
		(end 120.744742 -243.60251)
		(stroke
			(width 0.508)
			(type default)
		)
		(layer "In9.Cu")
	)
	(gr_line
		(start 120.338342 -270.83131)
		(end 119.423942 -270.83131)
		(stroke
			(width 0.254)
			(type default)
		)
		(layer "In9.Cu")
	)
	(gr_line
		(start 120.465342 -241.92611)
		(end 117.747542 -241.92611)
		(stroke
			(width 0.508)
			(type default)
		)
		(layer "In9.Cu")
	)
	(gr_line
		(start 120.668542 -260.51891)
		(end 121.100342 -260.08711)
		(stroke
			(width 0.508)
			(type default)
		)
		(layer "In9.Cu")
	)
	(gr_line
		(start 120.744742 -243.60251)
		(end 121.024142 -243.32311)
		(stroke
			(width 0.508)
			(type default)
		)
		(layer "In9.Cu")
	)
	(gr_line
		(start 121.024142 -243.32311)
		(end 121.024142 -242.48491)
		(stroke
			(width 0.508)
			(type default)
		)
		(layer "In9.Cu")
	)
	(gr_line
		(start 121.024142 -242.48491)
		(end 120.465342 -241.92611)
		(stroke
			(width 0.508)
			(type default)
		)
		(layer "In9.Cu")
	)
	(gr_line
		(start 121.100342 -260.08711)
		(end 121.481342 -260.46811)
		(stroke
			(width 0.254)
			(type default)
		)
		(layer "In9.Cu")
	)
	(gr_line
		(start 121.100342 -249.31751)
		(end 121.100342 -260.08711)
		(stroke
			(width 0.508)
			(type default)
		)
		(layer "In9.Cu")
	)
	(gr_line
		(start 121.481342 -261.73811)
		(end 121.786142 -262.04291)
		(stroke
			(width 0.254)
			(type default)
		)
		(layer "In9.Cu")
	)
	(gr_line
		(start 121.481342 -260.46811)
		(end 121.481342 -261.73811)
		(stroke
			(width 0.254)
			(type default)
		)
		(layer "In9.Cu")
	)
	(gr_line
		(start 121.672604 -336.047334)
		(end 122.38101 -336.75574)
		(stroke
			(width 0.254)
			(type default)
		)
		(layer "In9.Cu")
	)
	(gr_line
		(start 121.672604 -333.912972)
		(end 121.672604 -336.047334)
		(stroke
			(width 0.254)
			(type default)
		)
		(layer "In9.Cu")
	)
	(gr_line
		(start 121.722896 -289.031172)
		(end 116.020342 -279.08631)
		(stroke
			(width 0.508)
			(type default)
		)
		(layer "In9.Cu")
	)
	(gr_line
		(start 121.76252 -289.070796)
		(end 121.722896 -289.031172)
		(stroke
			(width 0.508)
			(type default)
		)
		(layer "In9.Cu")
	)
	(gr_line
		(start 121.785126 -333.80045)
		(end 121.672604 -333.912972)
		(stroke
			(width 0.254)
			(type default)
		)
		(layer "In9.Cu")
	)
	(gr_line
		(start 121.786142 -262.04291)
		(end 122.040142 -262.04291)
		(stroke
			(width 0.254)
			(type default)
		)
		(layer "In9.Cu")
	)
	(gr_line
		(start 121.790968 -350.1771)
		(end 139.713716 -350.1771)
		(stroke
			(width 0.508)
			(type default)
		)
		(layer "In9.Cu")
	)
	(gr_line
		(start 121.859802 -339.805264)
		(end 118.3005 -339.805264)
		(stroke
			(width 0.254)
			(type default)
		)
		(layer "In9.Cu")
	)
	(gr_line
		(start 122.38101 -339.284056)
		(end 121.859802 -339.805264)
		(stroke
			(width 0.254)
			(type default)
		)
		(layer "In9.Cu")
	)
	(gr_line
		(start 122.38101 -336.75574)
		(end 122.38101 -339.284056)
		(stroke
			(width 0.254)
			(type default)
		)
		(layer "In9.Cu")
	)
	(gr_line
		(start 124.102114 -11.780012)
		(end 83.70189 -11.780012)
		(stroke
			(width 3.048)
			(type default)
		)
		(layer "In9.Cu")
	)
	(gr_arc
		(start 124.102114 -11.780012)
		(mid 125.516321 -11.194223)
		(end 126.10211 -9.780016)
		(stroke
			(width 3.048)
			(type default)
		)
		(layer "In9.Cu")
	)
	(gr_line
		(start 125.062742 -322.97751)
		(end 93.261942 -322.97751)
		(stroke
			(width 0.508)
			(type default)
		)
		(layer "In9.Cu")
	)
	(gr_line
		(start 125.392688 -333.80045)
		(end 121.785126 -333.80045)
		(stroke
			(width 0.254)
			(type default)
		)
		(layer "In9.Cu")
	)
	(gr_line
		(start 125.551692 -342.469724)
		(end 125.551692 -333.959454)
		(stroke
			(width 0.254)
			(type default)
		)
		(layer "In9.Cu")
	)
	(gr_line
		(start 125.551692 -333.959454)
		(end 125.392688 -333.80045)
		(stroke
			(width 0.254)
			(type default)
		)
		(layer "In9.Cu")
	)
	(gr_line
		(start 125.723142 -324.98411)
		(end 125.723142 -323.63791)
		(stroke
			(width 0.508)
			(type default)
		)
		(layer "In9.Cu")
	)
	(gr_line
		(start 125.723142 -323.63791)
		(end 125.062742 -322.97751)
		(stroke
			(width 0.508)
			(type default)
		)
		(layer "In9.Cu")
	)
	(gr_line
		(start 126.10211 -6.279896)
		(end 126.10211 -9.780016)
		(stroke
			(width 3.048)
			(type default)
		)
		(layer "In9.Cu")
	)
	(gr_line
		(start 126.209298 -262.04291)
		(end 122.040142 -262.04291)
		(stroke
			(width 0.508)
			(type default)
		)
		(layer "In9.Cu")
	)
	(gr_line
		(start 126.297182 -343.215214)
		(end 125.551692 -342.469724)
		(stroke
			(width 0.254)
			(type default)
		)
		(layer "In9.Cu")
	)
	(gr_line
		(start 126.794768 -331.182218)
		(end 93.247464 -331.182218)
		(stroke
			(width 0.508)
			(type default)
		)
		(layer "In9.Cu")
	)
	(gr_arc
		(start 127.102108 -5.279898)
		(mid 126.395003 -5.572791)
		(end 126.10211 -6.279896)
		(stroke
			(width 3.048)
			(type default)
		)
		(layer "In9.Cu")
	)
	(gr_line
		(start 127.243078 -261.00913)
		(end 126.209298 -262.04291)
		(stroke
			(width 0.508)
			(type default)
		)
		(layer "In9.Cu")
	)
	(gr_line
		(start 127.243078 -239.610646)
		(end 127.243078 -261.00913)
		(stroke
			(width 0.508)
			(type default)
		)
		(layer "In9.Cu")
	)
	(gr_line
		(start 127.247142 -326.50811)
		(end 125.723142 -324.98411)
		(stroke
			(width 0.508)
			(type default)
		)
		(layer "In9.Cu")
	)
	(gr_line
		(start 127.260858 -333.971646)
		(end 127.260858 -331.648308)
		(stroke
			(width 0.508)
			(type default)
		)
		(layer "In9.Cu")
	)
	(gr_line
		(start 127.260858 -331.648308)
		(end 126.794768 -331.182218)
		(stroke
			(width 0.508)
			(type default)
		)
		(layer "In9.Cu")
	)
	(gr_line
		(start 127.628142 -225.44151)
		(end 129.228342 -227.04171)
		(stroke
			(width 0.508)
			(type default)
		)
		(layer "In9.Cu")
	)
	(gr_line
		(start 127.628142 -215.28151)
		(end 127.628142 -225.44151)
		(stroke
			(width 0.508)
			(type default)
		)
		(layer "In9.Cu")
	)
	(gr_line
		(start 127.83947 -334.550258)
		(end 127.260858 -333.971646)
		(stroke
			(width 0.508)
			(type default)
		)
		(layer "In9.Cu")
	)
	(gr_line
		(start 128.110742 -214.79891)
		(end 127.628142 -215.28151)
		(stroke
			(width 0.508)
			(type default)
		)
		(layer "In9.Cu")
	)
	(gr_line
		(start 128.981962 -357.75265)
		(end 132.81914 -361.589828)
		(stroke
			(width 0.508)
			(type default)
		)
		(layer "In9.Cu")
	)
	(gr_line
		(start 129.228342 -227.04171)
		(end 132.606542 -227.04171)
		(stroke
			(width 0.508)
			(type default)
		)
		(layer "In9.Cu")
	)
	(gr_line
		(start 129.803398 -343.215214)
		(end 126.297182 -343.215214)
		(stroke
			(width 0.254)
			(type default)
		)
		(layer "In9.Cu")
	)
	(gr_line
		(start 129.843784 -340.065868)
		(end 130.572256 -340.79434)
		(stroke
			(width 0.254)
			(type default)
		)
		(layer "In9.Cu")
	)
	(gr_line
		(start 129.843784 -337.277202)
		(end 129.843784 -340.065868)
		(stroke
			(width 0.254)
			(type default)
		)
		(layer "In9.Cu")
	)
	(gr_line
		(start 129.912872 -337.208114)
		(end 129.843784 -337.277202)
		(stroke
			(width 0.254)
			(type default)
		)
		(layer "In9.Cu")
	)
	(gr_line
		(start 130.572256 -342.446356)
		(end 129.803398 -343.215214)
		(stroke
			(width 0.254)
			(type default)
		)
		(layer "In9.Cu")
	)
	(gr_line
		(start 130.572256 -340.79434)
		(end 130.572256 -342.446356)
		(stroke
			(width 0.254)
			(type default)
		)
		(layer "In9.Cu")
	)
	(gr_line
		(start 131.438142 -326.50811)
		(end 127.247142 -326.50811)
		(stroke
			(width 0.508)
			(type default)
		)
		(layer "In9.Cu")
	)
	(gr_line
		(start 132.047742 -270.83131)
		(end 120.338342 -270.83131)
		(stroke
			(width 0.508)
			(type default)
		)
		(layer "In9.Cu")
	)
	(gr_line
		(start 132.606542 -227.04171)
		(end 135.88238 -230.317548)
		(stroke
			(width 0.508)
			(type default)
		)
		(layer "In9.Cu")
	)
	(gr_line
		(start 132.81914 -361.589828)
		(end 212.53196 -361.589828)
		(stroke
			(width 0.508)
			(type default)
		)
		(layer "In9.Cu")
	)
	(gr_line
		(start 133.551676 -337.208114)
		(end 129.912872 -337.208114)
		(stroke
			(width 0.254)
			(type default)
		)
		(layer "In9.Cu")
	)
	(gr_line
		(start 133.825742 -331.23251)
		(end 133.825742 -328.89571)
		(stroke
			(width 0.508)
			(type default)
		)
		(layer "In9.Cu")
	)
	(gr_line
		(start 133.825742 -328.89571)
		(end 131.438142 -326.50811)
		(stroke
			(width 0.508)
			(type default)
		)
		(layer "In9.Cu")
	)
	(gr_line
		(start 133.826758 -348.063058)
		(end 133.826758 -337.483196)
		(stroke
			(width 0.254)
			(type default)
		)
		(layer "In9.Cu")
	)
	(gr_line
		(start 133.826758 -337.483196)
		(end 133.551676 -337.208114)
		(stroke
			(width 0.254)
			(type default)
		)
		(layer "In9.Cu")
	)
	(gr_line
		(start 134.257542 -331.66431)
		(end 133.825742 -331.23251)
		(stroke
			(width 0.508)
			(type default)
		)
		(layer "In9.Cu")
	)
	(gr_line
		(start 134.257542 -331.66431)
		(end 148.007578 -331.66431)
		(stroke
			(width 0.508)
			(type default)
		)
		(layer "In9.Cu")
	)
	(gr_line
		(start 134.325106 -348.561406)
		(end 133.826758 -348.063058)
		(stroke
			(width 0.254)
			(type default)
		)
		(layer "In9.Cu")
	)
	(gr_line
		(start 134.34568 -334.550258)
		(end 127.83947 -334.550258)
		(stroke
			(width 0.508)
			(type default)
		)
		(layer "In9.Cu")
	)
	(gr_line
		(start 135.711438 -341.987378)
		(end 135.711438 -335.916016)
		(stroke
			(width 0.508)
			(type default)
		)
		(layer "In9.Cu")
	)
	(gr_line
		(start 135.711438 -335.916016)
		(end 134.34568 -334.550258)
		(stroke
			(width 0.508)
			(type default)
		)
		(layer "In9.Cu")
	)
	(gr_line
		(start 135.773922 -267.10513)
		(end 132.047742 -270.83131)
		(stroke
			(width 0.508)
			(type default)
		)
		(layer "In9.Cu")
	)
	(gr_line
		(start 135.88238 -230.317548)
		(end 138.733276 -230.317548)
		(stroke
			(width 0.508)
			(type default)
		)
		(layer "In9.Cu")
	)
	(gr_line
		(start 136.400794 -342.676734)
		(end 135.711438 -341.987378)
		(stroke
			(width 0.508)
			(type default)
		)
		(layer "In9.Cu")
	)
	(gr_line
		(start 137.448544 -289.070796)
		(end 121.76252 -289.070796)
		(stroke
			(width 0.508)
			(type default)
		)
		(layer "In9.Cu")
	)
	(gr_line
		(start 138.00455 -345.41714)
		(end 138.573764 -345.986354)
		(stroke
			(width 0.254)
			(type default)
		)
		(layer "In9.Cu")
	)
	(gr_line
		(start 138.00455 -342.86571)
		(end 138.00455 -345.41714)
		(stroke
			(width 0.254)
			(type default)
		)
		(layer "In9.Cu")
	)
	(gr_line
		(start 138.00963 -342.997536)
		(end 137.75563 -342.743536)
		(stroke
			(width 0.254)
			(type default)
		)
		(layer "In9.Cu")
	)
	(gr_line
		(start 138.00963 -342.9762)
		(end 138.255248 -342.730582)
		(stroke
			(width 0.254)
			(type default)
		)
		(layer "In9.Cu")
	)
	(gr_line
		(start 138.298682 -348.561406)
		(end 134.325106 -348.561406)
		(stroke
			(width 0.254)
			(type default)
		)
		(layer "In9.Cu")
	)
	(gr_line
		(start 138.380978 -267.10513)
		(end 135.773922 -267.10513)
		(stroke
			(width 0.508)
			(type default)
		)
		(layer "In9.Cu")
	)
	(gr_line
		(start 138.573764 -348.286324)
		(end 138.298682 -348.561406)
		(stroke
			(width 0.254)
			(type default)
		)
		(layer "In9.Cu")
	)
	(gr_line
		(start 138.573764 -345.986354)
		(end 138.573764 -348.286324)
		(stroke
			(width 0.254)
			(type default)
		)
		(layer "In9.Cu")
	)
	(gr_line
		(start 138.733276 -230.317548)
		(end 140.813536 -230.317548)
		(stroke
			(width 0.508)
			(type default)
		)
		(layer "In9.Cu")
	)
	(gr_line
		(start 139.713716 -350.1771)
		(end 143.200374 -346.690442)
		(stroke
			(width 0.508)
			(type default)
		)
		(layer "In9.Cu")
	)
	(gr_line
		(start 140.504418 -267.10513)
		(end 138.380978 -267.10513)
		(stroke
			(width 0.508)
			(type default)
		)
		(layer "In9.Cu")
	)
	(gr_line
		(start 140.813536 -230.317548)
		(end 141.637258 -231.14127)
		(stroke
			(width 0.508)
			(type default)
		)
		(layer "In9.Cu")
	)
	(gr_line
		(start 141.637258 -265.97229)
		(end 140.504418 -267.10513)
		(stroke
			(width 0.508)
			(type default)
		)
		(layer "In9.Cu")
	)
	(gr_line
		(start 141.637258 -231.14127)
		(end 141.637258 -265.97229)
		(stroke
			(width 0.508)
			(type default)
		)
		(layer "In9.Cu")
	)
	(gr_line
		(start 142.897352 -342.676734)
		(end 136.400794 -342.676734)
		(stroke
			(width 0.508)
			(type default)
		)
		(layer "In9.Cu")
	)
	(gr_line
		(start 143.200374 -346.690442)
		(end 143.200374 -342.979756)
		(stroke
			(width 0.508)
			(type default)
		)
		(layer "In9.Cu")
	)
	(gr_line
		(start 143.200374 -342.979756)
		(end 142.897352 -342.676734)
		(stroke
			(width 0.508)
			(type default)
		)
		(layer "In9.Cu")
	)
	(gr_line
		(start 144.875758 -331.14361)
		(end 144.455388 -331.56398)
		(stroke
			(width 0.508)
			(type default)
		)
		(layer "In9.Cu")
	)
	(gr_line
		(start 144.880838 -331.64145)
		(end 144.880838 -296.50309)
		(stroke
			(width 0.508)
			(type default)
		)
		(layer "In9.Cu")
	)
	(gr_line
		(start 144.880838 -296.50309)
		(end 137.448544 -289.070796)
		(stroke
			(width 0.508)
			(type default)
		)
		(layer "In9.Cu")
	)
	(gr_line
		(start 145.340578 -331.60843)
		(end 144.875758 -331.14361)
		(stroke
			(width 0.508)
			(type default)
		)
		(layer "In9.Cu")
	)
	(gr_line
		(start 148.007578 -331.66431)
		(end 148.624798 -332.28153)
		(stroke
			(width 0.508)
			(type default)
		)
		(layer "In9.Cu")
	)
	(gr_line
		(start 148.624798 -340.809326)
		(end 148.624798 -332.28153)
		(stroke
			(width 0.508)
			(type default)
		)
		(layer "In9.Cu")
	)
	(gr_line
		(start 149.83714 -342.021668)
		(end 148.624798 -340.809326)
		(stroke
			(width 0.508)
			(type default)
		)
		(layer "In9.Cu")
	)
	(gr_line
		(start 151.246078 -214.79383)
		(end 150.992078 -214.79383)
		(stroke
			(width 0.508)
			(type default)
		)
		(layer "In9.Cu")
	)
	(gr_line
		(start 152.596342 -192.94729)
		(end 216.315798 -192.94729)
		(stroke
			(width 0.508)
			(type default)
		)
		(layer "In9.Cu")
	)
	(gr_line
		(start 152.617678 -214.79891)
		(end 128.110742 -214.79891)
		(stroke
			(width 0.508)
			(type default)
		)
		(layer "In9.Cu")
	)
	(gr_line
		(start 152.6794 -194.528948)
		(end 152.6794 -193.030348)
		(stroke
			(width 0.508)
			(type default)
		)
		(layer "In9.Cu")
	)
	(gr_line
		(start 152.6794 -193.030348)
		(end 152.596342 -192.94729)
		(stroke
			(width 0.508)
			(type default)
		)
		(layer "In9.Cu")
	)
	(gr_line
		(start 153.847038 -214.79383)
		(end 151.500078 -214.79383)
		(stroke
			(width 0.508)
			(type default)
		)
		(layer "In9.Cu")
	)
	(gr_line
		(start 154.398218 -214.24265)
		(end 153.847038 -214.79383)
		(stroke
			(width 0.508)
			(type default)
		)
		(layer "In9.Cu")
	)
	(gr_line
		(start 154.398218 -214.24265)
		(end 154.398218 -196.247766)
		(stroke
			(width 0.508)
			(type default)
		)
		(layer "In9.Cu")
	)
	(gr_line
		(start 154.398218 -214.24265)
		(end 154.906218 -214.75065)
		(stroke
			(width 0.508)
			(type default)
		)
		(layer "In9.Cu")
	)
	(gr_line
		(start 154.398218 -196.247766)
		(end 152.6794 -194.528948)
		(stroke
			(width 0.508)
			(type default)
		)
		(layer "In9.Cu")
	)
	(gr_line
		(start 160.5788 -31.384748)
		(end 97.61474 -31.384748)
		(stroke
			(width 0.508)
			(type default)
		)
		(layer "In9.Cu")
	)
	(gr_line
		(start 161.671 -57.064148)
		(end 161.671 -32.476948)
		(stroke
			(width 0.508)
			(type default)
		)
		(layer "In9.Cu")
	)
	(gr_line
		(start 161.671 -32.476948)
		(end 160.5788 -31.384748)
		(stroke
			(width 0.508)
			(type default)
		)
		(layer "In9.Cu")
	)
	(gr_line
		(start 164.7444 -60.137548)
		(end 161.671 -57.064148)
		(stroke
			(width 0.508)
			(type default)
		)
		(layer "In9.Cu")
	)
	(gr_line
		(start 166.78148 -440.8678)
		(end 166.64686 -440.8678)
		(stroke
			(width 0.635)
			(type default)
		)
		(layer "In9.Cu")
	)
	(gr_line
		(start 167.59174 -440.05754)
		(end 166.78148 -440.8678)
		(stroke
			(width 0.635)
			(type default)
		)
		(layer "In9.Cu")
	)
	(gr_line
		(start 167.59174 -440.05754)
		(end 168.43248 -440.89828)
		(stroke
			(width 0.635)
			(type default)
		)
		(layer "In9.Cu")
	)
	(gr_line
		(start 167.59174 -416.88258)
		(end 167.59174 -440.05754)
		(stroke
			(width 0.635)
			(type default)
		)
		(layer "In9.Cu")
	)
	(gr_line
		(start 170.464988 -414.009332)
		(end 167.59174 -416.88258)
		(stroke
			(width 0.635)
			(type default)
		)
		(layer "In9.Cu")
	)
	(gr_line
		(start 180.581808 -214.79383)
		(end 153.847038 -214.79383)
		(stroke
			(width 0.508)
			(type default)
		)
		(layer "In9.Cu")
	)
	(gr_line
		(start 180.581808 -214.79383)
		(end 181.171342 -215.383364)
		(stroke
			(width 0.508)
			(type default)
		)
		(layer "In9.Cu")
	)
	(gr_line
		(start 180.847746 -215.059768)
		(end 180.581808 -214.79383)
		(stroke
			(width 0.508)
			(type default)
		)
		(layer "In9.Cu")
	)
	(gr_line
		(start 181.171342 -327.49871)
		(end 182.02148 -328.348848)
		(stroke
			(width 0.508)
			(type default)
		)
		(layer "In9.Cu")
	)
	(gr_line
		(start 181.171342 -267.58011)
		(end 181.171342 -327.49871)
		(stroke
			(width 0.508)
			(type default)
		)
		(layer "In9.Cu")
	)
	(gr_line
		(start 181.171342 -215.383364)
		(end 181.171342 -267.58011)
		(stroke
			(width 0.508)
			(type default)
		)
		(layer "In9.Cu")
	)
	(gr_line
		(start 181.26202 -320.21145)
		(end 181.664356 -319.809114)
		(stroke
			(width 0.508)
			(type default)
		)
		(layer "In9.Cu")
	)
	(gr_line
		(start 181.635908 -319.809114)
		(end 181.26202 -319.435226)
		(stroke
			(width 0.508)
			(type default)
		)
		(layer "In9.Cu")
	)
	(gr_line
		(start 181.664356 -319.809114)
		(end 181.635908 -319.809114)
		(stroke
			(width 0.508)
			(type default)
		)
		(layer "In9.Cu")
	)
	(gr_line
		(start 181.664356 -319.809114)
		(end 197.5866 -319.809114)
		(stroke
			(width 0.508)
			(type default)
		)
		(layer "In9.Cu")
	)
	(gr_line
		(start 182.02148 -328.348848)
		(end 185.60034 -328.348848)
		(stroke
			(width 0.508)
			(type default)
		)
		(layer "In9.Cu")
	)
	(gr_line
		(start 184.879488 -406.620726)
		(end 185.209688 -406.950926)
		(stroke
			(width 0.635)
			(type default)
		)
		(layer "In9.Cu")
	)
	(gr_line
		(start 184.879488 -400.685254)
		(end 184.879488 -406.620726)
		(stroke
			(width 0.635)
			(type default)
		)
		(layer "In9.Cu")
	)
	(gr_line
		(start 185.006488 -414.009332)
		(end 170.464988 -414.009332)
		(stroke
			(width 0.635)
			(type default)
		)
		(layer "In9.Cu")
	)
	(gr_line
		(start 185.006488 -414.009332)
		(end 185.830972 -414.009332)
		(stroke
			(width 0.635)
			(type default)
		)
		(layer "In9.Cu")
	)
	(gr_line
		(start 185.006488 -413.184848)
		(end 185.006488 -412.970726)
		(stroke
			(width 0.635)
			(type default)
		)
		(layer "In9.Cu")
	)
	(gr_line
		(start 185.006488 -408.491182)
		(end 185.006488 -414.009332)
		(stroke
			(width 0.635)
			(type default)
		)
		(layer "In9.Cu")
	)
	(gr_line
		(start 185.166 -342.021668)
		(end 149.83714 -342.021668)
		(stroke
			(width 0.508)
			(type default)
		)
		(layer "In9.Cu")
	)
	(gr_line
		(start 185.209688 -408.287982)
		(end 185.006488 -408.491182)
		(stroke
			(width 0.635)
			(type default)
		)
		(layer "In9.Cu")
	)
	(gr_line
		(start 185.209688 -406.950926)
		(end 185.209688 -408.287982)
		(stroke
			(width 0.635)
			(type default)
		)
		(layer "In9.Cu")
	)
	(gr_line
		(start 185.60034 -328.348848)
		(end 186.3344 -329.082908)
		(stroke
			(width 0.508)
			(type default)
		)
		(layer "In9.Cu")
	)
	(gr_line
		(start 185.830972 -414.009332)
		(end 185.904124 -414.082484)
		(stroke
			(width 0.635)
			(type default)
		)
		(layer "In9.Cu")
	)
	(gr_line
		(start 186.3344 -340.853268)
		(end 185.166 -342.021668)
		(stroke
			(width 0.508)
			(type default)
		)
		(layer "In9.Cu")
	)
	(gr_line
		(start 186.3344 -329.082908)
		(end 186.3344 -340.853268)
		(stroke
			(width 0.508)
			(type default)
		)
		(layer "In9.Cu")
	)
	(gr_line
		(start 188.73343 -400.685254)
		(end 184.879488 -400.685254)
		(stroke
			(width 0.635)
			(type default)
		)
		(layer "In9.Cu")
	)
	(gr_line
		(start 188.93536 -403.657054)
		(end 188.93536 -400.890232)
		(stroke
			(width 0.635)
			(type default)
		)
		(layer "In9.Cu")
	)
	(gr_line
		(start 188.93536 -400.890232)
		(end 188.73343 -400.685254)
		(stroke
			(width 0.635)
			(type default)
		)
		(layer "In9.Cu")
	)
	(gr_line
		(start 189.11316 -403.834854)
		(end 188.93536 -403.657054)
		(stroke
			(width 0.635)
			(type default)
		)
		(layer "In9.Cu")
	)
	(gr_line
		(start 189.46876 -403.834854)
		(end 189.11316 -403.834854)
		(stroke
			(width 0.635)
			(type default)
		)
		(layer "In9.Cu")
	)
	(gr_line
		(start 189.680088 -404.477982)
		(end 189.680088 -404.046182)
		(stroke
			(width 0.635)
			(type default)
		)
		(layer "In9.Cu")
	)
	(gr_line
		(start 189.680088 -404.046182)
		(end 189.46876 -403.834854)
		(stroke
			(width 0.635)
			(type default)
		)
		(layer "In9.Cu")
	)
	(gr_line
		(start 190.870332 -405.66848)
		(end 189.680088 -404.477982)
		(stroke
			(width 0.635)
			(type default)
		)
		(layer "In9.Cu")
	)
	(gr_line
		(start 192.7479 -420.92626)
		(end 185.006488 -413.184848)
		(stroke
			(width 0.635)
			(type default)
		)
		(layer "In9.Cu")
	)
	(gr_line
		(start 193.701924 -5.279898)
		(end 127.102108 -5.279898)
		(stroke
			(width 3.048)
			(type default)
		)
		(layer "In9.Cu")
	)
	(gr_arc
		(start 194.505072 -441.989972)
		(mid 194.858535 -441.843563)
		(end 195.004944 -441.4901)
		(stroke
			(width 3.048)
			(type default)
		)
		(layer "In9.Cu")
	)
	(gr_line
		(start 194.701922 -9.780016)
		(end 194.701922 -6.279896)
		(stroke
			(width 3.048)
			(type default)
		)
		(layer "In9.Cu")
	)
	(gr_arc
		(start 194.701922 -9.780016)
		(mid 195.287714 -11.19421)
		(end 196.701918 -11.780012)
		(stroke
			(width 3.048)
			(type default)
		)
		(layer "In9.Cu")
	)
	(gr_arc
		(start 194.701922 -6.279896)
		(mid 194.409029 -5.572791)
		(end 193.701924 -5.279898)
		(stroke
			(width 3.048)
			(type default)
		)
		(layer "In9.Cu")
	)
	(gr_line
		(start 195.004944 -441.4901)
		(end 195.004944 -441.17006)
		(stroke
			(width 3.048)
			(type default)
		)
		(layer "In9.Cu")
	)
	(gr_arc
		(start 195.50507 -440.669934)
		(mid 195.151433 -440.816426)
		(end 195.004944 -441.17006)
		(stroke
			(width 3.048)
			(type default)
		)
		(layer "In9.Cu")
	)
	(gr_line
		(start 195.50507 -440.669934)
		(end 276.314916 -440.669934)
		(stroke
			(width 3.048)
			(type default)
		)
		(layer "In9.Cu")
	)
	(gr_line
		(start 196.969888 -405.66848)
		(end 190.870332 -405.66848)
		(stroke
			(width 0.635)
			(type default)
		)
		(layer "In9.Cu")
	)
	(gr_line
		(start 197.414388 -420.92626)
		(end 192.7479 -420.92626)
		(stroke
			(width 0.635)
			(type default)
		)
		(layer "In9.Cu")
	)
	(gr_line
		(start 198.15048 -404.487888)
		(end 196.969888 -405.66848)
		(stroke
			(width 0.635)
			(type default)
		)
		(layer "In9.Cu")
	)
	(gr_line
		(start 198.15048 -400.893788)
		(end 198.15048 -404.487888)
		(stroke
			(width 0.635)
			(type default)
		)
		(layer "In9.Cu")
	)
	(gr_line
		(start 198.341488 -400.70278)
		(end 198.15048 -400.893788)
		(stroke
			(width 0.635)
			(type default)
		)
		(layer "In9.Cu")
	)
	(gr_line
		(start 201.995532 -400.70278)
		(end 198.341488 -400.70278)
		(stroke
			(width 0.635)
			(type default)
		)
		(layer "In9.Cu")
	)
	(gr_line
		(start 202.19416 -404.462488)
		(end 202.19416 -400.901408)
		(stroke
			(width 0.635)
			(type default)
		)
		(layer "In9.Cu")
	)
	(gr_line
		(start 202.19416 -400.901408)
		(end 201.995532 -400.70278)
		(stroke
			(width 0.635)
			(type default)
		)
		(layer "In9.Cu")
	)
	(gr_line
		(start 202.380088 -407.607008)
		(end 202.380088 -404.648416)
		(stroke
			(width 0.635)
			(type default)
		)
		(layer "In9.Cu")
	)
	(gr_line
		(start 202.380088 -404.648416)
		(end 202.19416 -404.462488)
		(stroke
			(width 0.635)
			(type default)
		)
		(layer "In9.Cu")
	)
	(gr_line
		(start 204.16012 -409.38704)
		(end 202.380088 -407.607008)
		(stroke
			(width 0.635)
			(type default)
		)
		(layer "In9.Cu")
	)
	(gr_line
		(start 206.17434 -435.523132)
		(end 207.503268 -436.85206)
		(stroke
			(width 0.635)
			(type default)
		)
		(layer "In9.Cu")
	)
	(gr_line
		(start 206.17434 -429.686212)
		(end 197.414388 -420.92626)
		(stroke
			(width 0.635)
			(type default)
		)
		(layer "In9.Cu")
	)
	(gr_line
		(start 206.17434 -429.686212)
		(end 206.17434 -435.523132)
		(stroke
			(width 0.635)
			(type default)
		)
		(layer "In9.Cu")
	)
	(gr_line
		(start 206.545688 -409.38704)
		(end 204.16012 -409.38704)
		(stroke
			(width 0.635)
			(type default)
		)
		(layer "In9.Cu")
	)
	(gr_line
		(start 207.503268 -436.85206)
		(end 228.909372 -436.85206)
		(stroke
			(width 0.635)
			(type default)
		)
		(layer "In9.Cu")
	)
	(gr_line
		(start 208.628488 -407.30424)
		(end 206.545688 -409.38704)
		(stroke
			(width 0.635)
			(type default)
		)
		(layer "In9.Cu")
	)
	(gr_line
		(start 208.628488 -404.642828)
		(end 208.628488 -407.30424)
		(stroke
			(width 0.635)
			(type default)
		)
		(layer "In9.Cu")
	)
	(gr_line
		(start 208.81848 -404.452836)
		(end 208.628488 -404.642828)
		(stroke
			(width 0.635)
			(type default)
		)
		(layer "In9.Cu")
	)
	(gr_line
		(start 208.81848 -400.893788)
		(end 208.81848 -404.452836)
		(stroke
			(width 0.635)
			(type default)
		)
		(layer "In9.Cu")
	)
	(gr_line
		(start 209.009488 -400.70278)
		(end 208.81848 -400.893788)
		(stroke
			(width 0.635)
			(type default)
		)
		(layer "In9.Cu")
	)
	(gr_line
		(start 209.33664 -60.137548)
		(end 164.7444 -60.137548)
		(stroke
			(width 0.508)
			(type default)
		)
		(layer "In9.Cu")
	)
	(gr_line
		(start 210.62696 -74.336148)
		(end 210.62696 -61.427868)
		(stroke
			(width 0.508)
			(type default)
		)
		(layer "In9.Cu")
	)
	(gr_line
		(start 210.62696 -61.427868)
		(end 209.33664 -60.137548)
		(stroke
			(width 0.508)
			(type default)
		)
		(layer "In9.Cu")
	)
	(gr_line
		(start 211.767166 -130.114802)
		(end 223.09836 -118.783608)
		(stroke
			(width 0.508)
			(type default)
		)
		(layer "In9.Cu")
	)
	(gr_line
		(start 212.53196 -361.589828)
		(end 217.794078 -356.32771)
		(stroke
			(width 0.508)
			(type default)
		)
		(layer "In9.Cu")
	)
	(gr_line
		(start 212.668612 -400.70278)
		(end 209.009488 -400.70278)
		(stroke
			(width 0.635)
			(type default)
		)
		(layer "In9.Cu")
	)
	(gr_line
		(start 212.85962 -404.485348)
		(end 212.85962 -400.893788)
		(stroke
			(width 0.635)
			(type default)
		)
		(layer "In9.Cu")
	)
	(gr_line
		(start 212.85962 -400.893788)
		(end 212.668612 -400.70278)
		(stroke
			(width 0.635)
			(type default)
		)
		(layer "In9.Cu")
	)
	(gr_line
		(start 213.03742 -407.525728)
		(end 213.03742 -404.663148)
		(stroke
			(width 0.635)
			(type default)
		)
		(layer "In9.Cu")
	)
	(gr_line
		(start 213.03742 -404.663148)
		(end 212.85962 -404.485348)
		(stroke
			(width 0.635)
			(type default)
		)
		(layer "In9.Cu")
	)
	(gr_line
		(start 213.09076 -76.799948)
		(end 210.62696 -74.336148)
		(stroke
			(width 0.508)
			(type default)
		)
		(layer "In9.Cu")
	)
	(gr_line
		(start 214.794592 -409.2829)
		(end 213.03742 -407.525728)
		(stroke
			(width 0.635)
			(type default)
		)
		(layer "In9.Cu")
	)
	(gr_line
		(start 216.315798 -192.94729)
		(end 217.794078 -194.42557)
		(stroke
			(width 0.508)
			(type default)
		)
		(layer "In9.Cu")
	)
	(gr_line
		(start 217.272616 -409.2829)
		(end 214.794592 -409.2829)
		(stroke
			(width 0.635)
			(type default)
		)
		(layer "In9.Cu")
	)
	(gr_line
		(start 217.672158 -319.45453)
		(end 217.394028 -319.73266)
		(stroke
			(width 0.508)
			(type default)
		)
		(layer "In9.Cu")
	)
	(gr_line
		(start 217.678254 -319.809114)
		(end 197.5866 -319.809114)
		(stroke
			(width 0.508)
			(type default)
		)
		(layer "In9.Cu")
	)
	(gr_line
		(start 217.794078 -356.32771)
		(end 217.794078 -215.42883)
		(stroke
			(width 0.508)
			(type default)
		)
		(layer "In9.Cu")
	)
	(gr_line
		(start 217.794078 -319.69329)
		(end 217.678254 -319.809114)
		(stroke
			(width 0.508)
			(type default)
		)
		(layer "In9.Cu")
	)
	(gr_line
		(start 217.794078 -194.42557)
		(end 217.794078 -215.42883)
		(stroke
			(width 0.508)
			(type default)
		)
		(layer "In9.Cu")
	)
	(gr_line
		(start 219.296488 -407.259028)
		(end 217.272616 -409.2829)
		(stroke
			(width 0.635)
			(type default)
		)
		(layer "In9.Cu")
	)
	(gr_line
		(start 219.296488 -404.673308)
		(end 219.296488 -407.259028)
		(stroke
			(width 0.635)
			(type default)
		)
		(layer "In9.Cu")
	)
	(gr_line
		(start 219.47886 -404.490936)
		(end 219.296488 -404.673308)
		(stroke
			(width 0.635)
			(type default)
		)
		(layer "In9.Cu")
	)
	(gr_line
		(start 219.47886 -400.906488)
		(end 219.47886 -404.490936)
		(stroke
			(width 0.635)
			(type default)
		)
		(layer "In9.Cu")
	)
	(gr_line
		(start 219.682568 -400.70278)
		(end 219.47886 -400.906488)
		(stroke
			(width 0.635)
			(type default)
		)
		(layer "In9.Cu")
	)
	(gr_line
		(start 221.30004 -11.780012)
		(end 196.701918 -11.780012)
		(stroke
			(width 3.048)
			(type default)
		)
		(layer "In9.Cu")
	)
	(gr_line
		(start 223.09836 -118.783608)
		(end 240.219738 -118.783608)
		(stroke
			(width 0.508)
			(type default)
		)
		(layer "In9.Cu")
	)
	(gr_line
		(start 223.300036 -33.275016)
		(end 223.300036 -13.780008)
		(stroke
			(width 3.048)
			(type default)
		)
		(layer "In9.Cu")
	)
	(gr_arc
		(start 223.300036 -33.275016)
		(mid 223.885829 -34.689205)
		(end 225.300032 -35.275012)
		(stroke
			(width 3.048)
			(type default)
		)
		(layer "In9.Cu")
	)
	(gr_arc
		(start 223.300036 -13.780008)
		(mid 222.714251 -12.365797)
		(end 221.30004 -11.780012)
		(stroke
			(width 3.048)
			(type default)
		)
		(layer "In9.Cu")
	)
	(gr_line
		(start 223.323912 -400.70278)
		(end 219.682568 -400.70278)
		(stroke
			(width 0.635)
			(type default)
		)
		(layer "In9.Cu")
	)
	(gr_line
		(start 223.53524 -404.47976)
		(end 223.53524 -400.914108)
		(stroke
			(width 0.635)
			(type default)
		)
		(layer "In9.Cu")
	)
	(gr_line
		(start 223.53524 -400.914108)
		(end 223.323912 -400.70278)
		(stroke
			(width 0.635)
			(type default)
		)
		(layer "In9.Cu")
	)
	(gr_line
		(start 223.716088 -407.403808)
		(end 223.716088 -404.660608)
		(stroke
			(width 0.635)
			(type default)
		)
		(layer "In9.Cu")
	)
	(gr_line
		(start 223.716088 -404.660608)
		(end 223.53524 -404.47976)
		(stroke
			(width 0.635)
			(type default)
		)
		(layer "In9.Cu")
	)
	(gr_line
		(start 225.70694 -409.39466)
		(end 223.716088 -407.403808)
		(stroke
			(width 0.635)
			(type default)
		)
		(layer "In9.Cu")
	)
	(gr_line
		(start 227.935028 -409.39466)
		(end 225.70694 -409.39466)
		(stroke
			(width 0.635)
			(type default)
		)
		(layer "In9.Cu")
	)
	(gr_line
		(start 228.909372 -436.85206)
		(end 230.69804 -435.063392)
		(stroke
			(width 0.635)
			(type default)
		)
		(layer "In9.Cu")
	)
	(gr_line
		(start 229.939088 -407.3906)
		(end 227.935028 -409.39466)
		(stroke
			(width 0.635)
			(type default)
		)
		(layer "In9.Cu")
	)
	(gr_line
		(start 229.939088 -404.678388)
		(end 229.939088 -407.3906)
		(stroke
			(width 0.635)
			(type default)
		)
		(layer "In9.Cu")
	)
	(gr_line
		(start 230.14432 -404.473156)
		(end 229.939088 -404.678388)
		(stroke
			(width 0.635)
			(type default)
		)
		(layer "In9.Cu")
	)
	(gr_line
		(start 230.14432 -400.901408)
		(end 230.14432 -404.473156)
		(stroke
			(width 0.635)
			(type default)
		)
		(layer "In9.Cu")
	)
	(gr_line
		(start 230.345488 -400.70024)
		(end 230.14432 -400.901408)
		(stroke
			(width 0.635)
			(type default)
		)
		(layer "In9.Cu")
	)
	(gr_line
		(start 230.69804 -423.43324)
		(end 230.69804 -435.063392)
		(stroke
			(width 0.635)
			(type default)
		)
		(layer "In9.Cu")
	)
	(gr_line
		(start 233.172 -420.95928)
		(end 230.69804 -423.43324)
		(stroke
			(width 0.635)
			(type default)
		)
		(layer "In9.Cu")
	)
	(gr_line
		(start 233.996992 -400.70024)
		(end 230.345488 -400.70024)
		(stroke
			(width 0.635)
			(type default)
		)
		(layer "In9.Cu")
	)
	(gr_line
		(start 234.19816 -404.477728)
		(end 234.19816 -400.901408)
		(stroke
			(width 0.635)
			(type default)
		)
		(layer "In9.Cu")
	)
	(gr_line
		(start 234.19816 -400.901408)
		(end 233.996992 -400.70024)
		(stroke
			(width 0.635)
			(type default)
		)
		(layer "In9.Cu")
	)
	(gr_line
		(start 235.520992 -405.80056)
		(end 234.19816 -404.477728)
		(stroke
			(width 0.635)
			(type default)
		)
		(layer "In9.Cu")
	)
	(gr_line
		(start 237.746032 -405.80056)
		(end 235.520992 -405.80056)
		(stroke
			(width 0.635)
			(type default)
		)
		(layer "In9.Cu")
	)
	(gr_line
		(start 239.10036 -406.737312)
		(end 238.682784 -406.737312)
		(stroke
			(width 0.635)
			(type default)
		)
		(layer "In9.Cu")
	)
	(gr_line
		(start 239.3315 -406.506172)
		(end 239.10036 -406.737312)
		(stroke
			(width 0.635)
			(type default)
		)
		(layer "In9.Cu")
	)
	(gr_arc
		(start 239.3315 -406.506172)
		(mid 239.359619 -406.647264)
		(end 239.439704 -406.766776)
		(stroke
			(width 0.635)
			(type default)
		)
		(layer "In9.Cu")
	)
	(gr_line
		(start 239.3315 -397.839946)
		(end 239.3315 -406.506172)
		(stroke
			(width 0.635)
			(type default)
		)
		(layer "In9.Cu")
	)
	(gr_line
		(start 239.387634 -397.701516)
		(end 239.3315 -397.839946)
		(stroke
			(width 0.635)
			(type default)
		)
		(layer "In9.Cu")
	)
	(gr_line
		(start 239.439704 -406.766776)
		(end 239.663224 -406.990296)
		(stroke
			(width 0.635)
			(type default)
		)
		(layer "In9.Cu")
	)
	(gr_line
		(start 239.441482 -397.649446)
		(end 239.387634 -397.701516)
		(stroke
			(width 0.635)
			(type default)
		)
		(layer "In9.Cu")
	)
	(gr_arc
		(start 239.663224 -406.990296)
		(mid 239.782747 -407.070378)
		(end 239.923828 -407.0985)
		(stroke
			(width 0.635)
			(type default)
		)
		(layer "In9.Cu")
	)
	(gr_line
		(start 239.699292 -407.75382)
		(end 237.746032 -405.80056)
		(stroke
			(width 0.635)
			(type default)
		)
		(layer "In9.Cu")
	)
	(gr_line
		(start 239.699292 -407.75382)
		(end 240.057432 -407.39568)
		(stroke
			(width 0.635)
			(type default)
		)
		(layer "In9.Cu")
	)
	(gr_line
		(start 239.917224 -397.173704)
		(end 239.441482 -397.649446)
		(stroke
			(width 0.635)
			(type default)
		)
		(layer "In9.Cu")
	)
	(gr_line
		(start 239.923828 -407.0985)
		(end 273.791172 -407.0985)
		(stroke
			(width 0.635)
			(type default)
		)
		(layer "In9.Cu")
	)
	(gr_line
		(start 240.057432 -407.39568)
		(end 273.646392 -407.39568)
		(stroke
			(width 0.635)
			(type default)
		)
		(layer "In9.Cu")
	)
	(gr_arc
		(start 240.177828 -397.0655)
		(mid 240.036774 -397.093687)
		(end 239.917224 -397.173704)
		(stroke
			(width 0.635)
			(type default)
		)
		(layer "In9.Cu")
	)
	(gr_line
		(start 240.219738 -118.783608)
		(end 255.447038 -134.010908)
		(stroke
			(width 0.508)
			(type default)
		)
		(layer "In9.Cu")
	)
	(gr_line
		(start 253.798578 -354.563426)
		(end 261.680198 -362.445046)
		(stroke
			(width 0.508)
			(type default)
		)
		(layer "In9.Cu")
	)
	(gr_line
		(start 253.798578 -319.688718)
		(end 253.798578 -354.563426)
		(stroke
			(width 0.508)
			(type default)
		)
		(layer "In9.Cu")
	)
	(gr_line
		(start 253.798578 -318.891666)
		(end 253.798578 -319.688718)
		(stroke
			(width 0.508)
			(type default)
		)
		(layer "In9.Cu")
	)
	(gr_line
		(start 253.798578 -318.891666)
		(end 253.798578 -219.17533)
		(stroke
			(width 0.508)
			(type default)
		)
		(layer "In9.Cu")
	)
	(gr_line
		(start 253.798578 -308.98465)
		(end 253.798578 -308.99481)
		(stroke
			(width 0.508)
			(type default)
		)
		(layer "In9.Cu")
	)
	(gr_line
		(start 253.798578 -219.17533)
		(end 253.798578 -194.91071)
		(stroke
			(width 0.508)
			(type default)
		)
		(layer "In9.Cu")
	)
	(gr_line
		(start 253.798578 -194.91071)
		(end 254.575818 -194.13347)
		(stroke
			(width 0.508)
			(type default)
		)
		(layer "In9.Cu")
	)
	(gr_line
		(start 254.177546 -319.30975)
		(end 253.798578 -319.688718)
		(stroke
			(width 0.508)
			(type default)
		)
		(layer "In9.Cu")
	)
	(gr_line
		(start 254.216662 -319.30975)
		(end 253.798578 -318.891666)
		(stroke
			(width 0.508)
			(type default)
		)
		(layer "In9.Cu")
	)
	(gr_line
		(start 254.216662 -319.30975)
		(end 254.177546 -319.30975)
		(stroke
			(width 0.508)
			(type default)
		)
		(layer "In9.Cu")
	)
	(gr_line
		(start 254.575818 -194.13347)
		(end 318.817498 -194.13347)
		(stroke
			(width 0.508)
			(type default)
		)
		(layer "In9.Cu")
	)
	(gr_line
		(start 255.447038 -134.010908)
		(end 333.9084 -134.010908)
		(stroke
			(width 0.508)
			(type default)
		)
		(layer "In9.Cu")
	)
	(gr_line
		(start 256.800096 -35.275012)
		(end 225.300032 -35.275012)
		(stroke
			(width 3.048)
			(type default)
		)
		(layer "In9.Cu")
	)
	(gr_arc
		(start 256.800096 -35.275012)
		(mid 258.214315 -34.689229)
		(end 258.800092 -33.275016)
		(stroke
			(width 3.048)
			(type default)
		)
		(layer "In9.Cu")
	)
	(gr_line
		(start 258.800092 -13.780008)
		(end 258.800092 -33.275016)
		(stroke
			(width 3.048)
			(type default)
		)
		(layer "In9.Cu")
	)
	(gr_arc
		(start 260.800088 -11.780012)
		(mid 259.385877 -12.365797)
		(end 258.800092 -13.780008)
		(stroke
			(width 3.048)
			(type default)
		)
		(layer "In9.Cu")
	)
	(gr_line
		(start 261.680198 -362.445046)
		(end 300.560486 -362.445046)
		(stroke
			(width 0.508)
			(type default)
		)
		(layer "In9.Cu")
	)
	(gr_line
		(start 269.3035 -76.799948)
		(end 213.09076 -76.799948)
		(stroke
			(width 0.508)
			(type default)
		)
		(layer "In9.Cu")
	)
	(gr_line
		(start 269.3035 -76.799948)
		(end 271.8308 -76.799948)
		(stroke
			(width 0.508)
			(type default)
		)
		(layer "In9.Cu")
	)
	(gr_line
		(start 270.481552 -420.95928)
		(end 233.172 -420.95928)
		(stroke
			(width 0.635)
			(type default)
		)
		(layer "In9.Cu")
	)
	(gr_line
		(start 271.8308 -76.799948)
		(end 271.8562 -76.825348)
		(stroke
			(width 0.508)
			(type default)
		)
		(layer "In9.Cu")
	)
	(gr_line
		(start 271.8562 -76.825348)
		(end 272.19402 -77.163168)
		(stroke
			(width 0.508)
			(type default)
		)
		(layer "In9.Cu")
	)
	(gr_line
		(start 271.8562 -76.749148)
		(end 271.8562 -76.825348)
		(stroke
			(width 0.508)
			(type default)
		)
		(layer "In9.Cu")
	)
	(gr_line
		(start 272.2372 -82.172048)
		(end 272.2372 -76.368148)
		(stroke
			(width 0.508)
			(type default)
		)
		(layer "In9.Cu")
	)
	(gr_line
		(start 272.2372 -76.368148)
		(end 271.8562 -76.749148)
		(stroke
			(width 0.508)
			(type default)
		)
		(layer "In9.Cu")
	)
	(gr_line
		(start 272.2372 -76.342748)
		(end 272.2372 -76.368148)
		(stroke
			(width 0.508)
			(type default)
		)
		(layer "In9.Cu")
	)
	(gr_line
		(start 272.2372 -57.671208)
		(end 272.2372 -76.342748)
		(stroke
			(width 0.508)
			(type default)
		)
		(layer "In9.Cu")
	)
	(gr_line
		(start 273.646392 -407.39568)
		(end 274.051776 -406.990296)
		(stroke
			(width 0.635)
			(type default)
		)
		(layer "In9.Cu")
	)
	(gr_arc
		(start 273.791172 -407.0985)
		(mid 273.932264 -407.070381)
		(end 274.051776 -406.990296)
		(stroke
			(width 0.635)
			(type default)
		)
		(layer "In9.Cu")
	)
	(gr_line
		(start 273.99996 -55.908448)
		(end 272.2372 -57.671208)
		(stroke
			(width 0.508)
			(type default)
		)
		(layer "In9.Cu")
	)
	(gr_line
		(start 273.99996 -37.132768)
		(end 273.99996 -55.908448)
		(stroke
			(width 0.508)
			(type default)
		)
		(layer "In9.Cu")
	)
	(gr_line
		(start 274.03552 -83.970368)
		(end 272.2372 -82.172048)
		(stroke
			(width 0.508)
			(type default)
		)
		(layer "In9.Cu")
	)
	(gr_line
		(start 274.051776 -407.33472)
		(end 274.470876 -407.75382)
		(stroke
			(width 0.635)
			(type default)
		)
		(layer "In9.Cu")
	)
	(gr_line
		(start 274.051776 -406.990296)
		(end 274.051776 -407.33472)
		(stroke
			(width 0.635)
			(type default)
		)
		(layer "In9.Cu")
	)
	(gr_line
		(start 274.051776 -406.990296)
		(end 274.529296 -406.512776)
		(stroke
			(width 0.635)
			(type default)
		)
		(layer "In9.Cu")
	)
	(gr_line
		(start 274.117054 -397.0655)
		(end 240.177828 -397.0655)
		(stroke
			(width 0.635)
			(type default)
		)
		(layer "In9.Cu")
	)
	(gr_line
		(start 274.255484 -397.121634)
		(end 274.117054 -397.0655)
		(stroke
			(width 0.635)
			(type default)
		)
		(layer "In9.Cu")
	)
	(gr_line
		(start 274.307554 -397.175482)
		(end 274.255484 -397.121634)
		(stroke
			(width 0.635)
			(type default)
		)
		(layer "In9.Cu")
	)
	(gr_line
		(start 274.4216 -42.255948)
		(end 274.066 -42.611548)
		(stroke
			(width 0.508)
			(type default)
		)
		(layer "In9.Cu")
	)
	(gr_arc
		(start 274.529296 -406.512776)
		(mid 274.609378 -406.393253)
		(end 274.6375 -406.252172)
		(stroke
			(width 0.635)
			(type default)
		)
		(layer "In9.Cu")
	)
	(gr_line
		(start 274.529296 -397.397224)
		(end 274.307554 -397.175482)
		(stroke
			(width 0.635)
			(type default)
		)
		(layer "In9.Cu")
	)
	(gr_line
		(start 274.574 -42.255948)
		(end 274.0914 -41.773348)
		(stroke
			(width 0.508)
			(type default)
		)
		(layer "In9.Cu")
	)
	(gr_line
		(start 274.574 -42.255948)
		(end 274.4216 -42.255948)
		(stroke
			(width 0.508)
			(type default)
		)
		(layer "In9.Cu")
	)
	(gr_line
		(start 274.6375 -406.252172)
		(end 274.6375 -397.657828)
		(stroke
			(width 0.635)
			(type default)
		)
		(layer "In9.Cu")
	)
	(gr_arc
		(start 274.6375 -397.657828)
		(mid 274.609313 -397.516774)
		(end 274.529296 -397.397224)
		(stroke
			(width 0.635)
			(type default)
		)
		(layer "In9.Cu")
	)
	(gr_line
		(start 275.0693 -405.960072)
		(end 275.351748 -406.24252)
		(stroke
			(width 0.635)
			(type default)
		)
		(layer "In9.Cu")
	)
	(gr_line
		(start 275.0693 -397.505428)
		(end 275.0693 -405.960072)
		(stroke
			(width 0.635)
			(type default)
		)
		(layer "In9.Cu")
	)
	(gr_line
		(start 275.351748 -406.24252)
		(end 278.143208 -406.24252)
		(stroke
			(width 0.635)
			(type default)
		)
		(layer "In9.Cu")
	)
	(gr_line
		(start 275.509228 -397.0655)
		(end 275.0693 -397.505428)
		(stroke
			(width 0.635)
			(type default)
		)
		(layer "In9.Cu")
	)
	(gr_line
		(start 275.547074 -319.30975)
		(end 254.216662 -319.30975)
		(stroke
			(width 0.508)
			(type default)
		)
		(layer "In9.Cu")
	)
	(gr_line
		(start 275.547074 -319.30975)
		(end 284.336998 -319.30975)
		(stroke
			(width 0.508)
			(type default)
		)
		(layer "In9.Cu")
	)
	(gr_line
		(start 275.680932 -415.7599)
		(end 270.481552 -420.95928)
		(stroke
			(width 0.635)
			(type default)
		)
		(layer "In9.Cu")
	)
	(gr_arc
		(start 276.815042 -441.4901)
		(mid 276.961451 -441.843563)
		(end 277.314914 -441.989972)
		(stroke
			(width 3.048)
			(type default)
		)
		(layer "In9.Cu")
	)
	(gr_arc
		(start 276.815042 -441.17006)
		(mid 276.668545 -440.816438)
		(end 276.314916 -440.669934)
		(stroke
			(width 3.048)
			(type default)
		)
		(layer "In9.Cu")
	)
	(gr_line
		(start 276.815042 -441.17006)
		(end 276.815042 -441.4901)
		(stroke
			(width 3.048)
			(type default)
		)
		(layer "In9.Cu")
	)
	(gr_line
		(start 277.314914 -441.989972)
		(end 463.300064 -441.989972)
		(stroke
			(width 3.048)
			(type default)
		)
		(layer "In9.Cu")
	)
	(gr_line
		(start 278.143208 -406.24252)
		(end 278.145748 -406.23998)
		(stroke
			(width 0.635)
			(type default)
		)
		(layer "In9.Cu")
	)
	(gr_line
		(start 278.145748 -406.23998)
		(end 281.037792 -406.23998)
		(stroke
			(width 0.635)
			(type default)
		)
		(layer "In9.Cu")
	)
	(gr_line
		(start 279.927812 -415.7599)
		(end 275.680932 -415.7599)
		(stroke
			(width 0.635)
			(type default)
		)
		(layer "In9.Cu")
	)
	(gr_line
		(start 279.927812 -415.7599)
		(end 280.51506 -415.172652)
		(stroke
			(width 0.635)
			(type default)
		)
		(layer "In9.Cu")
	)
	(gr_line
		(start 280.100532 -407.75382)
		(end 239.699292 -407.75382)
		(stroke
			(width 0.635)
			(type default)
		)
		(layer "In9.Cu")
	)
	(gr_line
		(start 280.51506 -415.172652)
		(end 280.51506 -408.168348)
		(stroke
			(width 0.635)
			(type default)
		)
		(layer "In9.Cu")
	)
	(gr_line
		(start 280.51506 -415.172652)
		(end 309.099712 -415.172652)
		(stroke
			(width 0.635)
			(type default)
		)
		(layer "In9.Cu")
	)
	(gr_line
		(start 280.51506 -408.168348)
		(end 280.100532 -407.75382)
		(stroke
			(width 0.635)
			(type default)
		)
		(layer "In9.Cu")
	)
	(gr_line
		(start 280.83764 -397.0655)
		(end 275.509228 -397.0655)
		(stroke
			(width 0.635)
			(type default)
		)
		(layer "In9.Cu")
	)
	(gr_line
		(start 281.037792 -406.23998)
		(end 281.369008 -405.908764)
		(stroke
			(width 0.635)
			(type default)
		)
		(layer "In9.Cu")
	)
	(gr_line
		(start 281.369008 -405.908764)
		(end 281.369008 -397.596868)
		(stroke
			(width 0.635)
			(type default)
		)
		(layer "In9.Cu")
	)
	(gr_line
		(start 281.369008 -397.596868)
		(end 280.83764 -397.0655)
		(stroke
			(width 0.635)
			(type default)
		)
		(layer "In9.Cu")
	)
	(gr_line
		(start 284.1498 -351.173288)
		(end 284.1498 -319.41262)
		(stroke
			(width 0.508)
			(type default)
		)
		(layer "In9.Cu")
	)
	(gr_line
		(start 284.1498 -319.41262)
		(end 284.04693 -319.30975)
		(stroke
			(width 0.508)
			(type default)
		)
		(layer "In9.Cu")
	)
	(gr_line
		(start 284.336998 -319.30975)
		(end 284.5816 -319.065148)
		(stroke
			(width 0.508)
			(type default)
		)
		(layer "In9.Cu")
	)
	(gr_line
		(start 284.5816 -319.065148)
		(end 284.5816 -218.785948)
		(stroke
			(width 0.508)
			(type default)
		)
		(layer "In9.Cu")
	)
	(gr_line
		(start 284.5816 -218.785948)
		(end 285.18231 -218.185238)
		(stroke
			(width 0.508)
			(type default)
		)
		(layer "In9.Cu")
	)
	(gr_line
		(start 284.973776 -351.997264)
		(end 284.1498 -351.173288)
		(stroke
			(width 0.508)
			(type default)
		)
		(layer "In9.Cu")
	)
	(gr_line
		(start 285.18231 -218.185238)
		(end 342.552274 -218.185238)
		(stroke
			(width 0.508)
			(type default)
		)
		(layer "In9.Cu")
	)
	(gr_line
		(start 287.3756 -23.757128)
		(end 273.99996 -37.132768)
		(stroke
			(width 0.508)
			(type default)
		)
		(layer "In9.Cu")
	)
	(gr_line
		(start 309.099712 -415.172652)
		(end 310.28386 -416.3568)
		(stroke
			(width 0.635)
			(type default)
		)
		(layer "In9.Cu")
	)
	(gr_line
		(start 310.28386 -440.17692)
		(end 309.3085 -441.15228)
		(stroke
			(width 0.635)
			(type default)
		)
		(layer "In9.Cu")
	)
	(gr_line
		(start 310.28386 -440.17692)
		(end 311.19826 -441.09132)
		(stroke
			(width 0.635)
			(type default)
		)
		(layer "In9.Cu")
	)
	(gr_line
		(start 310.28386 -416.3568)
		(end 310.28386 -440.17692)
		(stroke
			(width 0.635)
			(type default)
		)
		(layer "In9.Cu")
	)
	(gr_line
		(start 311.19826 -441.09132)
		(end 311.34812 -441.09132)
		(stroke
			(width 0.635)
			(type default)
		)
		(layer "In9.Cu")
	)
	(gr_line
		(start 317.060072 -351.997264)
		(end 284.973776 -351.997264)
		(stroke
			(width 0.508)
			(type default)
		)
		(layer "In9.Cu")
	)
	(gr_line
		(start 317.060072 -351.997264)
		(end 318.396874 -350.660462)
		(stroke
			(width 0.508)
			(type default)
		)
		(layer "In9.Cu")
	)
	(gr_line
		(start 318.290702 -217.515186)
		(end 317.636398 -218.16949)
		(stroke
			(width 0.508)
			(type default)
		)
		(layer "In9.Cu")
	)
	(gr_line
		(start 318.31788 -218.125548)
		(end 318.31788 -194.723512)
		(stroke
			(width 0.508)
			(type default)
		)
		(layer "In9.Cu")
	)
	(gr_line
		(start 318.31788 -194.718432)
		(end 317.7794 -194.179952)
		(stroke
			(width 0.508)
			(type default)
		)
		(layer "In9.Cu")
	)
	(gr_line
		(start 318.31788 -185.969148)
		(end 318.31788 -194.718432)
		(stroke
			(width 0.508)
			(type default)
		)
		(layer "In9.Cu")
	)
	(gr_line
		(start 318.396874 -332.950058)
		(end 318.396874 -350.660462)
		(stroke
			(width 0.508)
			(type default)
		)
		(layer "In9.Cu")
	)
	(gr_line
		(start 318.84874 -332.498192)
		(end 318.396874 -332.950058)
		(stroke
			(width 0.508)
			(type default)
		)
		(layer "In9.Cu")
	)
	(gr_line
		(start 318.951102 -218.163394)
		(end 318.296798 -217.50909)
		(stroke
			(width 0.508)
			(type default)
		)
		(layer "In9.Cu")
	)
	(gr_line
		(start 322.475098 -332.47203)
		(end 322.475098 -296.86885)
		(stroke
			(width 0.508)
			(type default)
		)
		(layer "In9.Cu")
	)
	(gr_line
		(start 322.475098 -296.86885)
		(end 330.29779 -289.046158)
		(stroke
			(width 0.508)
			(type default)
		)
		(layer "In9.Cu")
	)
	(gr_line
		(start 322.492878 -331.99197)
		(end 322.038218 -332.44663)
		(stroke
			(width 0.508)
			(type default)
		)
		(layer "In9.Cu")
	)
	(gr_line
		(start 322.978018 -332.47711)
		(end 322.492878 -331.99197)
		(stroke
			(width 0.508)
			(type default)
		)
		(layer "In9.Cu")
	)
	(gr_line
		(start 324.205854 -347.587316)
		(end 325.875142 -349.256604)
		(stroke
			(width 0.508)
			(type default)
		)
		(layer "In9.Cu")
	)
	(gr_line
		(start 324.205854 -341.251286)
		(end 324.205854 -347.587316)
		(stroke
			(width 0.508)
			(type default)
		)
		(layer "In9.Cu")
	)
	(gr_line
		(start 325.153782 -340.303358)
		(end 324.205854 -341.251286)
		(stroke
			(width 0.508)
			(type default)
		)
		(layer "In9.Cu")
	)
	(gr_line
		(start 325.875142 -349.256604)
		(end 333.772764 -349.256604)
		(stroke
			(width 0.508)
			(type default)
		)
		(layer "In9.Cu")
	)
	(gr_line
		(start 327.54824 -83.970368)
		(end 274.03552 -83.970368)
		(stroke
			(width 0.508)
			(type default)
		)
		(layer "In9.Cu")
	)
	(gr_line
		(start 328.780902 -345.232228)
		(end 330.9493 -347.400626)
		(stroke
			(width 0.254)
			(type default)
		)
		(layer "In9.Cu")
	)
	(gr_line
		(start 328.780902 -343.194894)
		(end 328.780902 -345.232228)
		(stroke
			(width 0.254)
			(type default)
		)
		(layer "In9.Cu")
	)
	(gr_line
		(start 328.95159 -343.024206)
		(end 328.780902 -343.194894)
		(stroke
			(width 0.254)
			(type default)
		)
		(layer "In9.Cu")
	)
	(gr_line
		(start 329.2602 -82.258408)
		(end 327.54824 -83.970368)
		(stroke
			(width 0.508)
			(type default)
		)
		(layer "In9.Cu")
	)
	(gr_line
		(start 329.2602 -57.648348)
		(end 329.2602 -82.258408)
		(stroke
			(width 0.508)
			(type default)
		)
		(layer "In9.Cu")
	)
	(gr_line
		(start 329.2602 -57.648348)
		(end 329.9714 -56.937148)
		(stroke
			(width 0.508)
			(type default)
		)
		(layer "In9.Cu")
	)
	(gr_line
		(start 329.845416 -332.498192)
		(end 318.84874 -332.498192)
		(stroke
			(width 0.508)
			(type default)
		)
		(layer "In9.Cu")
	)
	(gr_line
		(start 329.9714 -56.937148)
		(end 338.2264 -56.937148)
		(stroke
			(width 0.508)
			(type default)
		)
		(layer "In9.Cu")
	)
	(gr_line
		(start 330.29779 -289.046158)
		(end 351.428304 -289.046158)
		(stroke
			(width 0.508)
			(type default)
		)
		(layer "In9.Cu")
	)
	(gr_line
		(start 330.935838 -348.857062)
		(end 330.69022 -349.10268)
		(stroke
			(width 0.254)
			(type default)
		)
		(layer "In9.Cu")
	)
	(gr_line
		(start 330.935838 -348.835726)
		(end 331.189838 -349.089726)
		(stroke
			(width 0.254)
			(type default)
		)
		(layer "In9.Cu")
	)
	(gr_line
		(start 330.9493 -347.400626)
		(end 330.9493 -348.962726)
		(stroke
			(width 0.254)
			(type default)
		)
		(layer "In9.Cu")
	)
	(gr_line
		(start 331.063346 -340.303358)
		(end 325.153782 -340.303358)
		(stroke
			(width 0.508)
			(type default)
		)
		(layer "In9.Cu")
	)
	(gr_line
		(start 331.226922 -362.445046)
		(end 299.506894 -362.445046)
		(stroke
			(width 0.508)
			(type default)
		)
		(layer "In9.Cu")
	)
	(gr_line
		(start 331.442822 -339.923882)
		(end 331.063346 -340.303358)
		(stroke
			(width 0.508)
			(type default)
		)
		(layer "In9.Cu")
	)
	(gr_line
		(start 331.442822 -336.81289)
		(end 331.442822 -339.923882)
		(stroke
			(width 0.508)
			(type default)
		)
		(layer "In9.Cu")
	)
	(gr_line
		(start 332.608174 -343.024206)
		(end 328.95159 -343.024206)
		(stroke
			(width 0.254)
			(type default)
		)
		(layer "In9.Cu")
	)
	(gr_line
		(start 333.083662 -343.499694)
		(end 332.608174 -343.024206)
		(stroke
			(width 0.254)
			(type default)
		)
		(layer "In9.Cu")
	)
	(gr_line
		(start 333.690976 -334.564736)
		(end 331.442822 -336.81289)
		(stroke
			(width 0.508)
			(type default)
		)
		(layer "In9.Cu")
	)
	(gr_line
		(start 333.772764 -349.256604)
		(end 335.423256 -350.907096)
		(stroke
			(width 0.508)
			(type default)
		)
		(layer "In9.Cu")
	)
	(gr_line
		(start 333.9084 -134.010908)
		(end 364.47984 -103.439468)
		(stroke
			(width 0.508)
			(type default)
		)
		(layer "In9.Cu")
	)
	(gr_line
		(start 335.423256 -350.907096)
		(end 336.191606 -351.675446)
		(stroke
			(width 0.508)
			(type default)
		)
		(layer "In9.Cu")
	)
	(gr_line
		(start 336.191606 -351.675446)
		(end 343.787984 -351.675446)
		(stroke
			(width 0.508)
			(type default)
		)
		(layer "In9.Cu")
	)
	(gr_line
		(start 336.535776 -343.499694)
		(end 333.083662 -343.499694)
		(stroke
			(width 0.254)
			(type default)
		)
		(layer "In9.Cu")
	)
	(gr_line
		(start 336.600038 -325.74357)
		(end 329.845416 -332.498192)
		(stroke
			(width 0.508)
			(type default)
		)
		(layer "In9.Cu")
	)
	(gr_line
		(start 336.991452 -339.65388)
		(end 337.6549 -340.317328)
		(stroke
			(width 0.254)
			(type default)
		)
		(layer "In9.Cu")
	)
	(gr_line
		(start 336.991452 -337.306666)
		(end 336.991452 -339.65388)
		(stroke
			(width 0.254)
			(type default)
		)
		(layer "In9.Cu")
	)
	(gr_line
		(start 337.067144 -337.230974)
		(end 336.991452 -337.306666)
		(stroke
			(width 0.254)
			(type default)
		)
		(layer "In9.Cu")
	)
	(gr_line
		(start 337.467956 -260.925056)
		(end 337.467956 -232.578656)
		(stroke
			(width 0.508)
			(type default)
		)
		(layer "In9.Cu")
	)
	(gr_line
		(start 337.467956 -232.578656)
		(end 344.859356 -225.187256)
		(stroke
			(width 0.508)
			(type default)
		)
		(layer "In9.Cu")
	)
	(gr_line
		(start 337.6549 -342.38057)
		(end 336.535776 -343.499694)
		(stroke
			(width 0.254)
			(type default)
		)
		(layer "In9.Cu")
	)
	(gr_line
		(start 337.6549 -340.317328)
		(end 337.6549 -342.38057)
		(stroke
			(width 0.254)
			(type default)
		)
		(layer "In9.Cu")
	)
	(gr_line
		(start 337.880198 -355.79177)
		(end 331.226922 -362.445046)
		(stroke
			(width 0.508)
			(type default)
		)
		(layer "In9.Cu")
	)
	(gr_line
		(start 338.2264 -56.937148)
		(end 338.963 -56.200548)
		(stroke
			(width 0.508)
			(type default)
		)
		(layer "In9.Cu")
	)
	(gr_line
		(start 338.4804 -42.255948)
		(end 274.574 -42.255948)
		(stroke
			(width 0.508)
			(type default)
		)
		(layer "In9.Cu")
	)
	(gr_line
		(start 338.963 -56.200548)
		(end 338.963 -42.738548)
		(stroke
			(width 0.508)
			(type default)
		)
		(layer "In9.Cu")
	)
	(gr_line
		(start 338.963 -42.738548)
		(end 338.4804 -42.255948)
		(stroke
			(width 0.508)
			(type default)
		)
		(layer "In9.Cu")
	)
	(gr_line
		(start 339.056472 -334.564736)
		(end 333.690976 -334.564736)
		(stroke
			(width 0.508)
			(type default)
		)
		(layer "In9.Cu")
	)
	(gr_line
		(start 339.206078 -325.74357)
		(end 336.600038 -325.74357)
		(stroke
			(width 0.508)
			(type default)
		)
		(layer "In9.Cu")
	)
	(gr_line
		(start 339.403182 -334.218026)
		(end 339.056472 -334.564736)
		(stroke
			(width 0.508)
			(type default)
		)
		(layer "In9.Cu")
	)
	(gr_line
		(start 339.403182 -332.96606)
		(end 339.403182 -334.218026)
		(stroke
			(width 0.508)
			(type default)
		)
		(layer "In9.Cu")
	)
	(gr_line
		(start 340.614508 -337.230974)
		(end 337.067144 -337.230974)
		(stroke
			(width 0.254)
			(type default)
		)
		(layer "In9.Cu")
	)
	(gr_line
		(start 340.732872 -339.38337)
		(end 340.732872 -337.349338)
		(stroke
			(width 0.254)
			(type default)
		)
		(layer "In9.Cu")
	)
	(gr_line
		(start 340.732872 -337.349338)
		(end 340.614508 -337.230974)
		(stroke
			(width 0.254)
			(type default)
		)
		(layer "In9.Cu")
	)
	(gr_line
		(start 340.984332 -339.63483)
		(end 340.732872 -339.38337)
		(stroke
			(width 0.254)
			(type default)
		)
		(layer "In9.Cu")
	)
	(gr_line
		(start 341.187278 -331.181964)
		(end 339.403182 -332.96606)
		(stroke
			(width 0.508)
			(type default)
		)
		(layer "In9.Cu")
	)
	(gr_line
		(start 341.972392 -322.977256)
		(end 339.206078 -325.74357)
		(stroke
			(width 0.508)
			(type default)
		)
		(layer "In9.Cu")
	)
	(gr_line
		(start 342.552274 -218.185238)
		(end 344.859356 -220.49232)
		(stroke
			(width 0.508)
			(type default)
		)
		(layer "In9.Cu")
	)
	(gr_line
		(start 343.787984 -351.675446)
		(end 345.661742 -349.801688)
		(stroke
			(width 0.508)
			(type default)
		)
		(layer "In9.Cu")
	)
	(gr_line
		(start 344.579956 -268.037056)
		(end 337.467956 -260.925056)
		(stroke
			(width 0.508)
			(type default)
		)
		(layer "In9.Cu")
	)
	(gr_line
		(start 344.672412 -260.523736)
		(end 345.226132 -261.077456)
		(stroke
			(width 0.508)
			(type default)
		)
		(layer "In9.Cu")
	)
	(gr_line
		(start 344.672412 -234.938316)
		(end 344.672412 -260.523736)
		(stroke
			(width 0.508)
			(type default)
		)
		(layer "In9.Cu")
	)
	(gr_line
		(start 344.859356 -225.187256)
		(end 344.859356 -220.49232)
		(stroke
			(width 0.508)
			(type default)
		)
		(layer "In9.Cu")
	)
	(gr_line
		(start 345.129358 -335.993232)
		(end 346.055188 -336.919062)
		(stroke
			(width 0.254)
			(type default)
		)
		(layer "In9.Cu")
	)
	(gr_line
		(start 345.129358 -333.929482)
		(end 345.129358 -335.993232)
		(stroke
			(width 0.254)
			(type default)
		)
		(layer "In9.Cu")
	)
	(gr_line
		(start 345.256612 -333.802228)
		(end 345.129358 -333.929482)
		(stroke
			(width 0.254)
			(type default)
		)
		(layer "In9.Cu")
	)
	(gr_line
		(start 345.369388 -339.63483)
		(end 340.984332 -339.63483)
		(stroke
			(width 0.254)
			(type default)
		)
		(layer "In9.Cu")
	)
	(gr_line
		(start 345.661742 -349.801688)
		(end 361.442 -349.801688)
		(stroke
			(width 0.508)
			(type default)
		)
		(layer "In9.Cu")
	)
	(gr_line
		(start 346.055188 -338.94903)
		(end 345.369388 -339.63483)
		(stroke
			(width 0.254)
			(type default)
		)
		(layer "In9.Cu")
	)
	(gr_line
		(start 346.055188 -336.919062)
		(end 346.055188 -338.94903)
		(stroke
			(width 0.254)
			(type default)
		)
		(layer "In9.Cu")
	)
	(gr_line
		(start 347.547692 -355.79177)
		(end 337.880198 -355.79177)
		(stroke
			(width 0.508)
			(type default)
		)
		(layer "In9.Cu")
	)
	(gr_line
		(start 348.803976 -333.802228)
		(end 345.256612 -333.802228)
		(stroke
			(width 0.254)
			(type default)
		)
		(layer "In9.Cu")
	)
	(gr_line
		(start 348.932754 -338.736686)
		(end 348.932754 -333.931006)
		(stroke
			(width 0.254)
			(type default)
		)
		(layer "In9.Cu")
	)
	(gr_line
		(start 348.932754 -333.931006)
		(end 348.803976 -333.802228)
		(stroke
			(width 0.254)
			(type default)
		)
		(layer "In9.Cu")
	)
	(gr_line
		(start 349.133668 -189.34938)
		(end 349.133668 -219.08008)
		(stroke
			(width 0.508)
			(type default)
		)
		(layer "In9.Cu")
	)
	(gr_line
		(start 349.70212 -188.780928)
		(end 349.133668 -189.34938)
		(stroke
			(width 0.508)
			(type default)
		)
		(layer "In9.Cu")
	)
	(gr_line
		(start 349.86341 -339.667342)
		(end 348.932754 -338.736686)
		(stroke
			(width 0.254)
			(type default)
		)
		(layer "In9.Cu")
	)
	(gr_line
		(start 350.472756 -261.077456)
		(end 345.226132 -261.077456)
		(stroke
			(width 0.508)
			(type default)
		)
		(layer "In9.Cu")
	)
	(gr_line
		(start 350.650556 -268.037056)
		(end 344.579956 -268.037056)
		(stroke
			(width 0.508)
			(type default)
		)
		(layer "In9.Cu")
	)
	(gr_line
		(start 350.980756 -245.329456)
		(end 350.980756 -239.436656)
		(stroke
			(width 0.508)
			(type default)
		)
		(layer "In9.Cu")
	)
	(gr_line
		(start 350.980756 -239.436656)
		(end 352.326956 -238.090456)
		(stroke
			(width 0.508)
			(type default)
		)
		(layer "In9.Cu")
	)
	(gr_line
		(start 351.031556 -260.518656)
		(end 350.472756 -261.077456)
		(stroke
			(width 0.508)
			(type default)
		)
		(layer "In9.Cu")
	)
	(gr_line
		(start 351.031556 -256.276856)
		(end 351.031556 -260.518656)
		(stroke
			(width 0.508)
			(type default)
		)
		(layer "In9.Cu")
	)
	(gr_line
		(start 351.031556 -256.276856)
		(end 351.031556 -248.504456)
		(stroke
			(width 0.508)
			(type default)
		)
		(layer "In9.Cu")
	)
	(gr_line
		(start 351.031556 -248.504456)
		(end 351.514156 -248.021856)
		(stroke
			(width 0.508)
			(type default)
		)
		(layer "In9.Cu")
	)
	(gr_line
		(start 351.09658 -256.89052)
		(end 351.42551 -256.56159)
		(stroke
			(width 0.508)
			(type default)
		)
		(layer "In9.Cu")
	)
	(gr_line
		(start 351.420176 -256.402078)
		(end 351.091246 -256.073148)
		(stroke
			(width 0.508)
			(type default)
		)
		(layer "In9.Cu")
	)
	(gr_line
		(start 351.428304 -289.046158)
		(end 352.306128 -288.168334)
		(stroke
			(width 0.508)
			(type default)
		)
		(layer "In9.Cu")
	)
	(gr_line
		(start 351.488756 -256.480056)
		(end 351.234756 -256.480056)
		(stroke
			(width 0.508)
			(type default)
		)
		(layer "In9.Cu")
	)
	(gr_line
		(start 351.514156 -248.021856)
		(end 352.428556 -248.021856)
		(stroke
			(width 0.508)
			(type default)
		)
		(layer "In9.Cu")
	)
	(gr_line
		(start 351.514156 -245.862856)
		(end 350.980756 -245.329456)
		(stroke
			(width 0.508)
			(type default)
		)
		(layer "In9.Cu")
	)
	(gr_line
		(start 352.036634 -227.574094)
		(end 344.672412 -234.938316)
		(stroke
			(width 0.508)
			(type default)
		)
		(layer "In9.Cu")
	)
	(gr_line
		(start 352.036634 -226.91217)
		(end 352.036634 -227.574094)
		(stroke
			(width 0.508)
			(type default)
		)
		(layer "In9.Cu")
	)
	(gr_line
		(start 352.036634 -226.91217)
		(end 352.036634 -221.983046)
		(stroke
			(width 0.508)
			(type default)
		)
		(layer "In9.Cu")
	)
	(gr_line
		(start 352.036634 -221.983046)
		(end 349.133668 -219.08008)
		(stroke
			(width 0.508)
			(type default)
		)
		(layer "In9.Cu")
	)
	(gr_line
		(start 352.306128 -288.168334)
		(end 352.306128 -283.765498)
		(stroke
			(width 0.508)
			(type default)
		)
		(layer "In9.Cu")
	)
	(gr_line
		(start 352.306128 -283.765498)
		(end 356.066852 -280.004774)
		(stroke
			(width 0.508)
			(type default)
		)
		(layer "In9.Cu")
	)
	(gr_line
		(start 352.326956 -238.090456)
		(end 363.274356 -238.090456)
		(stroke
			(width 0.508)
			(type default)
		)
		(layer "In9.Cu")
	)
	(gr_line
		(start 352.352356 -266.335256)
		(end 350.650556 -268.037056)
		(stroke
			(width 0.508)
			(type default)
		)
		(layer "In9.Cu")
	)
	(gr_line
		(start 352.352356 -262.017256)
		(end 352.352356 -266.335256)
		(stroke
			(width 0.508)
			(type default)
		)
		(layer "In9.Cu")
	)
	(gr_line
		(start 352.352356 -261.306056)
		(end 352.352356 -262.017256)
		(stroke
			(width 0.254)
			(type default)
		)
		(layer "In9.Cu")
	)
	(gr_line
		(start 352.428556 -248.021856)
		(end 353.063556 -247.386856)
		(stroke
			(width 0.508)
			(type default)
		)
		(layer "In9.Cu")
	)
	(gr_line
		(start 352.682556 -256.480056)
		(end 351.488756 -256.480056)
		(stroke
			(width 0.508)
			(type default)
		)
		(layer "In9.Cu")
	)
	(gr_line
		(start 352.733356 -245.862856)
		(end 351.514156 -245.862856)
		(stroke
			(width 0.508)
			(type default)
		)
		(layer "In9.Cu")
	)
	(gr_line
		(start 352.817938 -260.84149)
		(end 353.122738 -260.53669)
		(stroke
			(width 0.254)
			(type default)
		)
		(layer "In9.Cu")
	)
	(gr_line
		(start 352.885756 -260.772656)
		(end 352.352356 -261.306056)
		(stroke
			(width 0.254)
			(type default)
		)
		(layer "In9.Cu")
	)
	(gr_line
		(start 353.063556 -247.386856)
		(end 353.063556 -246.193056)
		(stroke
			(width 0.508)
			(type default)
		)
		(layer "In9.Cu")
	)
	(gr_line
		(start 353.063556 -246.193056)
		(end 352.733356 -245.862856)
		(stroke
			(width 0.508)
			(type default)
		)
		(layer "In9.Cu")
	)
	(gr_line
		(start 353.190556 -260.493256)
		(end 353.190556 -256.988056)
		(stroke
			(width 0.508)
			(type default)
		)
		(layer "In9.Cu")
	)
	(gr_line
		(start 353.190556 -256.988056)
		(end 352.682556 -256.480056)
		(stroke
			(width 0.508)
			(type default)
		)
		(layer "In9.Cu")
	)
	(gr_line
		(start 353.2886 -336.03057)
		(end 354.094288 -336.836258)
		(stroke
			(width 0.254)
			(type default)
		)
		(layer "In9.Cu")
	)
	(gr_line
		(start 353.2886 -333.93634)
		(end 353.2886 -336.03057)
		(stroke
			(width 0.254)
			(type default)
		)
		(layer "In9.Cu")
	)
	(gr_line
		(start 353.42449 -333.80045)
		(end 353.2886 -333.93634)
		(stroke
			(width 0.254)
			(type default)
		)
		(layer "In9.Cu")
	)
	(gr_line
		(start 353.469956 -260.772656)
		(end 352.885756 -260.772656)
		(stroke
			(width 0.254)
			(type default)
		)
		(layer "In9.Cu")
	)
	(gr_line
		(start 353.511358 -260.814058)
		(end 353.190556 -260.493256)
		(stroke
			(width 0.508)
			(type default)
		)
		(layer "In9.Cu")
	)
	(gr_line
		(start 353.662742 -339.667342)
		(end 349.86341 -339.667342)
		(stroke
			(width 0.254)
			(type default)
		)
		(layer "In9.Cu")
	)
	(gr_line
		(start 354.094288 -339.235796)
		(end 353.662742 -339.667342)
		(stroke
			(width 0.254)
			(type default)
		)
		(layer "In9.Cu")
	)
	(gr_line
		(start 354.094288 -336.836258)
		(end 354.094288 -339.235796)
		(stroke
			(width 0.254)
			(type default)
		)
		(layer "In9.Cu")
	)
	(gr_line
		(start 354.349812 -362.59389)
		(end 347.547692 -355.79177)
		(stroke
			(width 0.508)
			(type default)
		)
		(layer "In9.Cu")
	)
	(gr_line
		(start 354.349812 -362.59389)
		(end 440.747658 -362.59389)
		(stroke
			(width 0.508)
			(type default)
		)
		(layer "In9.Cu")
	)
	(gr_line
		(start 354.854764 -263.604502)
		(end 354.854764 -262.11784)
		(stroke
			(width 0.508)
			(type default)
		)
		(layer "In9.Cu")
	)
	(gr_line
		(start 354.854764 -263.604502)
		(end 356.066852 -264.81659)
		(stroke
			(width 0.508)
			(type default)
		)
		(layer "In9.Cu")
	)
	(gr_line
		(start 354.854764 -262.11784)
		(end 355.189028 -261.783576)
		(stroke
			(width 0.508)
			(type default)
		)
		(layer "In9.Cu")
	)
	(gr_line
		(start 355.189028 -261.783576)
		(end 355.49713 -261.783576)
		(stroke
			(width 0.508)
			(type default)
		)
		(layer "In9.Cu")
	)
	(gr_line
		(start 355.19868 -188.780928)
		(end 349.70212 -188.780928)
		(stroke
			(width 0.508)
			(type default)
		)
		(layer "In9.Cu")
	)
	(gr_line
		(start 355.19868 -188.780928)
		(end 355.83876 -188.140848)
		(stroke
			(width 0.508)
			(type default)
		)
		(layer "In9.Cu")
	)
	(gr_line
		(start 355.49713 -261.783576)
		(end 355.837744 -261.442962)
		(stroke
			(width 0.508)
			(type default)
		)
		(layer "In9.Cu")
	)
	(gr_line
		(start 355.569012 -260.814058)
		(end 353.511358 -260.814058)
		(stroke
			(width 0.508)
			(type default)
		)
		(layer "In9.Cu")
	)
	(gr_line
		(start 355.837744 -261.442962)
		(end 355.837744 -261.08279)
		(stroke
			(width 0.508)
			(type default)
		)
		(layer "In9.Cu")
	)
	(gr_line
		(start 355.837744 -261.08279)
		(end 355.569012 -260.814058)
		(stroke
			(width 0.508)
			(type default)
		)
		(layer "In9.Cu")
	)
	(gr_line
		(start 355.83876 -188.140848)
		(end 355.83876 -174.508668)
		(stroke
			(width 0.508)
			(type default)
		)
		(layer "In9.Cu")
	)
	(gr_line
		(start 355.83876 -174.508668)
		(end 373.070882 -157.276546)
		(stroke
			(width 0.508)
			(type default)
		)
		(layer "In9.Cu")
	)
	(gr_line
		(start 355.925882 -148.361146)
		(end 318.31788 -185.969148)
		(stroke
			(width 0.508)
			(type default)
		)
		(layer "In9.Cu")
	)
	(gr_line
		(start 356.066852 -264.81659)
		(end 356.066852 -280.004774)
		(stroke
			(width 0.508)
			(type default)
		)
		(layer "In9.Cu")
	)
	(gr_line
		(start 356.945184 -338.589112)
		(end 356.945184 -337.580986)
		(stroke
			(width 0.254)
			(type default)
		)
		(layer "In9.Cu")
	)
	(gr_line
		(start 356.945184 -337.580986)
		(end 357.197914 -337.328256)
		(stroke
			(width 0.254)
			(type default)
		)
		(layer "In9.Cu")
	)
	(gr_line
		(start 357.013256 -333.80045)
		(end 353.42449 -333.80045)
		(stroke
			(width 0.254)
			(type default)
		)
		(layer "In9.Cu")
	)
	(gr_line
		(start 357.197914 -337.328256)
		(end 357.197914 -333.985108)
		(stroke
			(width 0.254)
			(type default)
		)
		(layer "In9.Cu")
	)
	(gr_line
		(start 357.197914 -333.985108)
		(end 357.013256 -333.80045)
		(stroke
			(width 0.254)
			(type default)
		)
		(layer "In9.Cu")
	)
	(gr_line
		(start 357.999792 -339.64372)
		(end 356.945184 -338.589112)
		(stroke
			(width 0.254)
			(type default)
		)
		(layer "In9.Cu")
	)
	(gr_line
		(start 361.442 -349.801688)
		(end 363.59084 -351.950528)
		(stroke
			(width 0.508)
			(type default)
		)
		(layer "In9.Cu")
	)
	(gr_line
		(start 361.470448 -336.008726)
		(end 362.115354 -336.653632)
		(stroke
			(width 0.254)
			(type default)
		)
		(layer "In9.Cu")
	)
	(gr_line
		(start 361.470448 -333.912718)
		(end 361.470448 -336.008726)
		(stroke
			(width 0.254)
			(type default)
		)
		(layer "In9.Cu")
	)
	(gr_line
		(start 361.581954 -333.801212)
		(end 361.470448 -333.912718)
		(stroke
			(width 0.254)
			(type default)
		)
		(layer "In9.Cu")
	)
	(gr_line
		(start 361.659932 -339.64372)
		(end 357.999792 -339.64372)
		(stroke
			(width 0.254)
			(type default)
		)
		(layer "In9.Cu")
	)
	(gr_line
		(start 362.115354 -339.188298)
		(end 361.659932 -339.64372)
		(stroke
			(width 0.254)
			(type default)
		)
		(layer "In9.Cu")
	)
	(gr_line
		(start 362.115354 -336.653632)
		(end 362.115354 -339.188298)
		(stroke
			(width 0.254)
			(type default)
		)
		(layer "In9.Cu")
	)
	(gr_line
		(start 363.274356 -238.090456)
		(end 363.782356 -238.598456)
		(stroke
			(width 0.508)
			(type default)
		)
		(layer "In9.Cu")
	)
	(gr_line
		(start 363.299756 -227.727256)
		(end 363.299756 -201.196194)
		(stroke
			(width 0.508)
			(type default)
		)
		(layer "In9.Cu")
	)
	(gr_line
		(start 363.299756 -227.727256)
		(end 375.182892 -239.610392)
		(stroke
			(width 0.508)
			(type default)
		)
		(layer "In9.Cu")
	)
	(gr_line
		(start 363.299756 -201.196194)
		(end 397.96593 -166.53002)
		(stroke
			(width 0.508)
			(type default)
		)
		(layer "In9.Cu")
	)
	(gr_line
		(start 363.59084 -351.950528)
		(end 367.95202 -351.950528)
		(stroke
			(width 0.508)
			(type default)
		)
		(layer "In9.Cu")
	)
	(gr_line
		(start 363.782356 -240.020856)
		(end 365.687356 -241.925856)
		(stroke
			(width 0.508)
			(type default)
		)
		(layer "In9.Cu")
	)
	(gr_line
		(start 363.782356 -238.598456)
		(end 363.782356 -240.020856)
		(stroke
			(width 0.508)
			(type default)
		)
		(layer "In9.Cu")
	)
	(gr_line
		(start 363.960156 -279.086056)
		(end 369.66271 -289.030918)
		(stroke
			(width 0.508)
			(type default)
		)
		(layer "In9.Cu")
	)
	(gr_line
		(start 363.960156 -261.179056)
		(end 363.960156 -279.086056)
		(stroke
			(width 0.508)
			(type default)
		)
		(layer "In9.Cu")
	)
	(gr_line
		(start 364.47984 -103.439468)
		(end 381.84836 -103.439468)
		(stroke
			(width 0.508)
			(type default)
		)
		(layer "In9.Cu")
	)
	(gr_line
		(start 364.620556 -260.518656)
		(end 363.960156 -261.179056)
		(stroke
			(width 0.508)
			(type default)
		)
		(layer "In9.Cu")
	)
	(gr_line
		(start 364.680246 -148.361146)
		(end 355.925882 -148.361146)
		(stroke
			(width 0.508)
			(type default)
		)
		(layer "In9.Cu")
	)
	(gr_line
		(start 364.680246 -148.361146)
		(end 418.927534 -148.361146)
		(stroke
			(width 0.508)
			(type default)
		)
		(layer "In9.Cu")
	)
	(gr_line
		(start 365.165894 -333.801212)
		(end 361.581954 -333.801212)
		(stroke
			(width 0.254)
			(type default)
		)
		(layer "In9.Cu")
	)
	(gr_line
		(start 365.3155 -338.880196)
		(end 365.3155 -333.950818)
		(stroke
			(width 0.254)
			(type default)
		)
		(layer "In9.Cu")
	)
	(gr_line
		(start 365.3155 -333.950818)
		(end 365.165894 -333.801212)
		(stroke
			(width 0.254)
			(type default)
		)
		(layer "In9.Cu")
	)
	(gr_line
		(start 365.687356 -241.925856)
		(end 368.405156 -241.925856)
		(stroke
			(width 0.508)
			(type default)
		)
		(layer "In9.Cu")
	)
	(gr_line
		(start 366.240314 -339.80501)
		(end 365.3155 -338.880196)
		(stroke
			(width 0.254)
			(type default)
		)
		(layer "In9.Cu")
	)
	(gr_line
		(start 366.347756 -260.594856)
		(end 366.601756 -260.848856)
		(stroke
			(width 0.254)
			(type default)
		)
		(layer "In9.Cu")
	)
	(gr_line
		(start 366.601756 -270.069056)
		(end 367.363756 -270.831056)
		(stroke
			(width 0.254)
			(type default)
		)
		(layer "In9.Cu")
	)
	(gr_line
		(start 366.601756 -260.848856)
		(end 366.601756 -270.069056)
		(stroke
			(width 0.254)
			(type default)
		)
		(layer "In9.Cu")
	)
	(gr_line
		(start 366.728756 -246.878856)
		(end 369.040156 -249.190256)
		(stroke
			(width 0.508)
			(type default)
		)
		(layer "In9.Cu")
	)
	(gr_line
		(start 366.728756 -244.897656)
		(end 366.728756 -246.878856)
		(stroke
			(width 0.508)
			(type default)
		)
		(layer "In9.Cu")
	)
	(gr_line
		(start 366.852454 -260.614668)
		(end 366.598454 -260.868668)
		(stroke
			(width 0.254)
			(type default)
		)
		(layer "In9.Cu")
	)
	(gr_line
		(start 367.363756 -270.831056)
		(end 368.278156 -270.831056)
		(stroke
			(width 0.254)
			(type default)
		)
		(layer "In9.Cu")
	)
	(gr_line
		(start 367.95202 -351.950528)
		(end 369.717828 -350.18472)
		(stroke
			(width 0.508)
			(type default)
		)
		(layer "In9.Cu")
	)
	(gr_line
		(start 368.024156 -243.602256)
		(end 366.728756 -244.897656)
		(stroke
			(width 0.508)
			(type default)
		)
		(layer "In9.Cu")
	)
	(gr_line
		(start 368.278156 -270.831056)
		(end 379.987556 -270.831056)
		(stroke
			(width 0.508)
			(type default)
		)
		(layer "In9.Cu")
	)
	(gr_line
		(start 368.405156 -241.925856)
		(end 368.963956 -242.484656)
		(stroke
			(width 0.508)
			(type default)
		)
		(layer "In9.Cu")
	)
	(gr_line
		(start 368.608356 -260.518656)
		(end 364.620556 -260.518656)
		(stroke
			(width 0.508)
			(type default)
		)
		(layer "In9.Cu")
	)
	(gr_line
		(start 368.684556 -243.602256)
		(end 368.024156 -243.602256)
		(stroke
			(width 0.508)
			(type default)
		)
		(layer "In9.Cu")
	)
	(gr_line
		(start 368.80292 -260.30555)
		(end 369.233958 -260.30555)
		(stroke
			(width 0.254)
			(type default)
		)
		(layer "In9.Cu")
	)
	(gr_line
		(start 368.963956 -243.322856)
		(end 368.684556 -243.602256)
		(stroke
			(width 0.508)
			(type default)
		)
		(layer "In9.Cu")
	)
	(gr_line
		(start 368.963956 -242.484656)
		(end 368.963956 -243.322856)
		(stroke
			(width 0.508)
			(type default)
		)
		(layer "In9.Cu")
	)
	(gr_line
		(start 369.040156 -260.086856)
		(end 368.608356 -260.518656)
		(stroke
			(width 0.508)
			(type default)
		)
		(layer "In9.Cu")
	)
	(gr_line
		(start 369.040156 -260.086856)
		(end 369.421156 -260.467856)
		(stroke
			(width 0.254)
			(type default)
		)
		(layer "In9.Cu")
	)
	(gr_line
		(start 369.040156 -249.190256)
		(end 369.040156 -260.086856)
		(stroke
			(width 0.508)
			(type default)
		)
		(layer "In9.Cu")
	)
	(gr_line
		(start 369.421156 -261.737856)
		(end 369.725956 -262.042656)
		(stroke
			(width 0.254)
			(type default)
		)
		(layer "In9.Cu")
	)
	(gr_line
		(start 369.421156 -260.467856)
		(end 369.421156 -261.737856)
		(stroke
			(width 0.254)
			(type default)
		)
		(layer "In9.Cu")
	)
	(gr_line
		(start 369.612418 -336.04708)
		(end 370.320824 -336.755486)
		(stroke
			(width 0.254)
			(type default)
		)
		(layer "In9.Cu")
	)
	(gr_line
		(start 369.612418 -333.912718)
		(end 369.612418 -336.04708)
		(stroke
			(width 0.254)
			(type default)
		)
		(layer "In9.Cu")
	)
	(gr_line
		(start 369.66271 -289.030918)
		(end 369.702334 -289.070542)
		(stroke
			(width 0.508)
			(type default)
		)
		(layer "In9.Cu")
	)
	(gr_line
		(start 369.717828 -350.18472)
		(end 387.645656 -350.18472)
		(stroke
			(width 0.508)
			(type default)
		)
		(layer "In9.Cu")
	)
	(gr_line
		(start 369.72494 -333.800196)
		(end 369.612418 -333.912718)
		(stroke
			(width 0.254)
			(type default)
		)
		(layer "In9.Cu")
	)
	(gr_line
		(start 369.725956 -262.042656)
		(end 369.979956 -262.042656)
		(stroke
			(width 0.254)
			(type default)
		)
		(layer "In9.Cu")
	)
	(gr_line
		(start 369.799616 -339.80501)
		(end 366.240314 -339.80501)
		(stroke
			(width 0.254)
			(type default)
		)
		(layer "In9.Cu")
	)
	(gr_line
		(start 369.979956 -262.042656)
		(end 372.138956 -262.042656)
		(stroke
			(width 0.508)
			(type default)
		)
		(layer "In9.Cu")
	)
	(gr_line
		(start 370.320824 -339.283802)
		(end 369.799616 -339.80501)
		(stroke
			(width 0.254)
			(type default)
		)
		(layer "In9.Cu")
	)
	(gr_line
		(start 370.320824 -336.755486)
		(end 370.320824 -339.283802)
		(stroke
			(width 0.254)
			(type default)
		)
		(layer "In9.Cu")
	)
	(gr_line
		(start 371.681756 -236.109256)
		(end 363.299756 -227.727256)
		(stroke
			(width 0.508)
			(type default)
		)
		(layer "In9.Cu")
	)
	(gr_line
		(start 373.002556 -322.977256)
		(end 341.972392 -322.977256)
		(stroke
			(width 0.508)
			(type default)
		)
		(layer "In9.Cu")
	)
	(gr_line
		(start 373.04472 -23.757128)
		(end 287.3756 -23.757128)
		(stroke
			(width 0.508)
			(type default)
		)
		(layer "In9.Cu")
	)
	(gr_line
		(start 373.070882 -157.276546)
		(end 377.993402 -157.276546)
		(stroke
			(width 0.508)
			(type default)
		)
		(layer "In9.Cu")
	)
	(gr_line
		(start 373.332502 -333.800196)
		(end 369.72494 -333.800196)
		(stroke
			(width 0.254)
			(type default)
		)
		(layer "In9.Cu")
	)
	(gr_line
		(start 373.491506 -342.46947)
		(end 373.491506 -333.9592)
		(stroke
			(width 0.254)
			(type default)
		)
		(layer "In9.Cu")
	)
	(gr_line
		(start 373.491506 -333.9592)
		(end 373.332502 -333.800196)
		(stroke
			(width 0.254)
			(type default)
		)
		(layer "In9.Cu")
	)
	(gr_line
		(start 373.662956 -324.983856)
		(end 373.662956 -323.637656)
		(stroke
			(width 0.508)
			(type default)
		)
		(layer "In9.Cu")
	)
	(gr_line
		(start 373.662956 -323.637656)
		(end 373.002556 -322.977256)
		(stroke
			(width 0.508)
			(type default)
		)
		(layer "In9.Cu")
	)
	(gr_line
		(start 374.149112 -262.042656)
		(end 369.979956 -262.042656)
		(stroke
			(width 0.508)
			(type default)
		)
		(layer "In9.Cu")
	)
	(gr_line
		(start 374.236996 -343.21496)
		(end 373.491506 -342.46947)
		(stroke
			(width 0.254)
			(type default)
		)
		(layer "In9.Cu")
	)
	(gr_line
		(start 374.734582 -331.181964)
		(end 341.187278 -331.181964)
		(stroke
			(width 0.508)
			(type default)
		)
		(layer "In9.Cu")
	)
	(gr_line
		(start 375.182892 -261.008876)
		(end 374.149112 -262.042656)
		(stroke
			(width 0.508)
			(type default)
		)
		(layer "In9.Cu")
	)
	(gr_line
		(start 375.182892 -239.610392)
		(end 375.182892 -261.008876)
		(stroke
			(width 0.508)
			(type default)
		)
		(layer "In9.Cu")
	)
	(gr_line
		(start 375.186956 -326.507856)
		(end 373.662956 -324.983856)
		(stroke
			(width 0.508)
			(type default)
		)
		(layer "In9.Cu")
	)
	(gr_line
		(start 375.186956 -326.507856)
		(end 379.035564 -326.507856)
		(stroke
			(width 0.508)
			(type default)
		)
		(layer "In9.Cu")
	)
	(gr_line
		(start 375.200672 -333.971392)
		(end 375.200672 -331.648054)
		(stroke
			(width 0.508)
			(type default)
		)
		(layer "In9.Cu")
	)
	(gr_line
		(start 375.200672 -331.648054)
		(end 374.734582 -331.181964)
		(stroke
			(width 0.508)
			(type default)
		)
		(layer "In9.Cu")
	)
	(gr_line
		(start 375.567956 -225.441256)
		(end 375.567956 -215.281256)
		(stroke
			(width 0.508)
			(type default)
		)
		(layer "In9.Cu")
	)
	(gr_line
		(start 375.567956 -215.281256)
		(end 376.050556 -214.798656)
		(stroke
			(width 0.508)
			(type default)
		)
		(layer "In9.Cu")
	)
	(gr_line
		(start 375.779284 -334.550004)
		(end 375.200672 -333.971392)
		(stroke
			(width 0.508)
			(type default)
		)
		(layer "In9.Cu")
	)
	(gr_line
		(start 376.050556 -214.798656)
		(end 428.490634 -214.798656)
		(stroke
			(width 0.508)
			(type default)
		)
		(layer "In9.Cu")
	)
	(gr_line
		(start 377.168156 -227.041456)
		(end 375.567956 -225.441256)
		(stroke
			(width 0.508)
			(type default)
		)
		(layer "In9.Cu")
	)
	(gr_line
		(start 377.743212 -343.21496)
		(end 374.236996 -343.21496)
		(stroke
			(width 0.254)
			(type default)
		)
		(layer "In9.Cu")
	)
	(gr_line
		(start 377.783598 -340.065614)
		(end 378.51207 -340.794086)
		(stroke
			(width 0.254)
			(type default)
		)
		(layer "In9.Cu")
	)
	(gr_line
		(start 377.783598 -337.276948)
		(end 377.783598 -340.065614)
		(stroke
			(width 0.254)
			(type default)
		)
		(layer "In9.Cu")
	)
	(gr_line
		(start 377.852686 -337.20786)
		(end 377.783598 -337.276948)
		(stroke
			(width 0.254)
			(type default)
		)
		(layer "In9.Cu")
	)
	(gr_line
		(start 377.993402 -157.276546)
		(end 379.561852 -157.276546)
		(stroke
			(width 0.508)
			(type default)
		)
		(layer "In9.Cu")
	)
	(gr_line
		(start 378.51207 -342.446102)
		(end 377.743212 -343.21496)
		(stroke
			(width 0.254)
			(type default)
		)
		(layer "In9.Cu")
	)
	(gr_line
		(start 378.51207 -340.794086)
		(end 378.51207 -342.446102)
		(stroke
			(width 0.254)
			(type default)
		)
		(layer "In9.Cu")
	)
	(gr_line
		(start 379.035564 -326.507856)
		(end 382.934718 -330.40701)
		(stroke
			(width 0.508)
			(type default)
		)
		(layer "In9.Cu")
	)
	(gr_line
		(start 380.546356 -227.041456)
		(end 377.168156 -227.041456)
		(stroke
			(width 0.508)
			(type default)
		)
		(layer "In9.Cu")
	)
	(gr_line
		(start 380.546356 -227.041456)
		(end 387.633718 -234.128818)
		(stroke
			(width 0.508)
			(type default)
		)
		(layer "In9.Cu")
	)
	(gr_line
		(start 381.49149 -337.20786)
		(end 377.852686 -337.20786)
		(stroke
			(width 0.254)
			(type default)
		)
		(layer "In9.Cu")
	)
	(gr_line
		(start 381.766572 -348.062804)
		(end 381.766572 -337.482942)
		(stroke
			(width 0.254)
			(type default)
		)
		(layer "In9.Cu")
	)
	(gr_line
		(start 381.766572 -337.482942)
		(end 381.49149 -337.20786)
		(stroke
			(width 0.254)
			(type default)
		)
		(layer "In9.Cu")
	)
	(gr_line
		(start 381.786384 -214.798656)
		(end 381.715772 -214.798656)
		(stroke
			(width 0.508)
			(type default)
		)
		(layer "In9.Cu")
	)
	(gr_line
		(start 381.84836 -103.439468)
		(end 390.88314 -94.404688)
		(stroke
			(width 0.508)
			(type default)
		)
		(layer "In9.Cu")
	)
	(gr_line
		(start 382.26492 -348.561152)
		(end 381.766572 -348.062804)
		(stroke
			(width 0.254)
			(type default)
		)
		(layer "In9.Cu")
	)
	(gr_line
		(start 382.285494 -334.550004)
		(end 375.779284 -334.550004)
		(stroke
			(width 0.508)
			(type default)
		)
		(layer "In9.Cu")
	)
	(gr_line
		(start 382.934718 -330.40701)
		(end 396.150338 -330.40701)
		(stroke
			(width 0.508)
			(type default)
		)
		(layer "In9.Cu")
	)
	(gr_line
		(start 383.651252 -341.987124)
		(end 383.651252 -335.915762)
		(stroke
			(width 0.508)
			(type default)
		)
		(layer "In9.Cu")
	)
	(gr_line
		(start 383.651252 -335.915762)
		(end 382.285494 -334.550004)
		(stroke
			(width 0.508)
			(type default)
		)
		(layer "In9.Cu")
	)
	(gr_line
		(start 384.340608 -342.67648)
		(end 383.651252 -341.987124)
		(stroke
			(width 0.508)
			(type default)
		)
		(layer "In9.Cu")
	)
	(gr_line
		(start 385.601972 -11.780012)
		(end 260.800088 -11.780012)
		(stroke
			(width 3.048)
			(type default)
		)
		(layer "In9.Cu")
	)
	(gr_arc
		(start 385.601972 -11.780012)
		(mid 387.016206 -11.194238)
		(end 387.601968 -9.780016)
		(stroke
			(width 3.048)
			(type default)
		)
		(layer "In9.Cu")
	)
	(gr_line
		(start 385.71805 -289.070542)
		(end 369.702334 -289.070542)
		(stroke
			(width 0.508)
			(type default)
		)
		(layer "In9.Cu")
	)
	(gr_line
		(start 385.944364 -345.416886)
		(end 386.513578 -345.9861)
		(stroke
			(width 0.254)
			(type default)
		)
		(layer "In9.Cu")
	)
	(gr_line
		(start 385.944364 -342.865456)
		(end 385.944364 -345.416886)
		(stroke
			(width 0.254)
			(type default)
		)
		(layer "In9.Cu")
	)
	(gr_line
		(start 385.949444 -342.997282)
		(end 385.695444 -342.743282)
		(stroke
			(width 0.254)
			(type default)
		)
		(layer "In9.Cu")
	)
	(gr_line
		(start 385.949444 -342.975946)
		(end 386.195062 -342.730328)
		(stroke
			(width 0.254)
			(type default)
		)
		(layer "In9.Cu")
	)
	(gr_line
		(start 386.18668 -36.899088)
		(end 373.04472 -23.757128)
		(stroke
			(width 0.508)
			(type default)
		)
		(layer "In9.Cu")
	)
	(gr_line
		(start 386.238496 -348.561152)
		(end 382.26492 -348.561152)
		(stroke
			(width 0.254)
			(type default)
		)
		(layer "In9.Cu")
	)
	(gr_line
		(start 386.513578 -348.28607)
		(end 386.238496 -348.561152)
		(stroke
			(width 0.254)
			(type default)
		)
		(layer "In9.Cu")
	)
	(gr_line
		(start 386.513578 -345.9861)
		(end 386.513578 -348.28607)
		(stroke
			(width 0.254)
			(type default)
		)
		(layer "In9.Cu")
	)
	(gr_line
		(start 387.601968 -0.999998)
		(end 387.601968 -9.780016)
		(stroke
			(width 3.048)
			(type default)
		)
		(layer "In9.Cu")
	)
	(gr_line
		(start 387.633718 -263.184894)
		(end 379.987556 -270.831056)
		(stroke
			(width 0.508)
			(type default)
		)
		(layer "In9.Cu")
	)
	(gr_line
		(start 387.633718 -234.128818)
		(end 387.633718 -263.184894)
		(stroke
			(width 0.508)
			(type default)
		)
		(layer "In9.Cu")
	)
	(gr_line
		(start 387.645656 -350.18472)
		(end 391.140188 -346.690188)
		(stroke
			(width 0.508)
			(type default)
		)
		(layer "In9.Cu")
	)
	(gr_arc
		(start 388.601966 0)
		(mid 387.894861 -0.292893)
		(end 387.601968 -0.999998)
		(stroke
			(width 3.048)
			(type default)
		)
		(layer "In9.Cu")
	)
	(gr_line
		(start 390.837166 -342.67648)
		(end 384.340608 -342.67648)
		(stroke
			(width 0.508)
			(type default)
		)
		(layer "In9.Cu")
	)
	(gr_line
		(start 390.88314 -94.404688)
		(end 390.88314 -78.151228)
		(stroke
			(width 0.508)
			(type default)
		)
		(layer "In9.Cu")
	)
	(gr_line
		(start 390.88314 -78.151228)
		(end 396.69212 -72.342248)
		(stroke
			(width 0.508)
			(type default)
		)
		(layer "In9.Cu")
	)
	(gr_line
		(start 391.140188 -346.690188)
		(end 391.140188 -342.979502)
		(stroke
			(width 0.508)
			(type default)
		)
		(layer "In9.Cu")
	)
	(gr_line
		(start 391.140188 -342.979502)
		(end 390.837166 -342.67648)
		(stroke
			(width 0.508)
			(type default)
		)
		(layer "In9.Cu")
	)
	(gr_line
		(start 392.863578 -330.36637)
		(end 392.863578 -296.21607)
		(stroke
			(width 0.508)
			(type default)
		)
		(layer "In9.Cu")
	)
	(gr_line
		(start 392.863578 -296.21607)
		(end 385.71805 -289.070542)
		(stroke
			(width 0.508)
			(type default)
		)
		(layer "In9.Cu")
	)
	(gr_line
		(start 392.871198 -329.91679)
		(end 392.416538 -330.37145)
		(stroke
			(width 0.508)
			(type default)
		)
		(layer "In9.Cu")
	)
	(gr_line
		(start 393.356338 -330.40193)
		(end 392.871198 -329.91679)
		(stroke
			(width 0.508)
			(type default)
		)
		(layer "In9.Cu")
	)
	(gr_line
		(start 396.150338 -330.40701)
		(end 396.564612 -330.821284)
		(stroke
			(width 0.508)
			(type default)
		)
		(layer "In9.Cu")
	)
	(gr_line
		(start 396.564612 -330.821284)
		(end 396.564612 -340.024466)
		(stroke
			(width 0.508)
			(type default)
		)
		(layer "In9.Cu")
	)
	(gr_line
		(start 396.69212 -72.342248)
		(end 450.96684 -72.342248)
		(stroke
			(width 0.508)
			(type default)
		)
		(layer "In9.Cu")
	)
	(gr_line
		(start 397.96593 -166.53002)
		(end 410.218382 -166.53002)
		(stroke
			(width 0.508)
			(type default)
		)
		(layer "In9.Cu")
	)
	(gr_line
		(start 408.285696 -351.74555)
		(end 396.564612 -340.024466)
		(stroke
			(width 0.508)
			(type default)
		)
		(layer "In9.Cu")
	)
	(gr_line
		(start 409.61945 -157.284928)
		(end 410.220668 -157.886146)
		(stroke
			(width 0.508)
			(type default)
		)
		(layer "In9.Cu")
	)
	(gr_line
		(start 409.712668 -148.488146)
		(end 410.220668 -148.996146)
		(stroke
			(width 0.508)
			(type default)
		)
		(layer "In9.Cu")
	)
	(gr_line
		(start 409.75153 -166.529766)
		(end 410.20873 -166.072566)
		(stroke
			(width 0.508)
			(type default)
		)
		(layer "In9.Cu")
	)
	(gr_line
		(start 410.195268 -148.970746)
		(end 410.195268 -148.488146)
		(stroke
			(width 0.508)
			(type default)
		)
		(layer "In9.Cu")
	)
	(gr_line
		(start 410.201872 -166.988998)
		(end 409.744672 -166.531798)
		(stroke
			(width 0.508)
			(type default)
		)
		(layer "In9.Cu")
	)
	(gr_line
		(start 410.20619 -157.276546)
		(end 378.570236 -157.276546)
		(stroke
			(width 0.508)
			(type default)
		)
		(layer "In9.Cu")
	)
	(gr_line
		(start 410.20619 -157.149546)
		(end 410.220668 -157.164024)
		(stroke
			(width 0.508)
			(type default)
		)
		(layer "In9.Cu")
	)
	(gr_line
		(start 410.212286 -156.675328)
		(end 409.611068 -157.276546)
		(stroke
			(width 0.508)
			(type default)
		)
		(layer "In9.Cu")
	)
	(gr_line
		(start 410.214318 -214.09279)
		(end 409.560014 -214.747094)
		(stroke
			(width 0.508)
			(type default)
		)
		(layer "In9.Cu")
	)
	(gr_line
		(start 410.218382 -168.05402)
		(end 410.220668 -168.056306)
		(stroke
			(width 0.508)
			(type default)
		)
		(layer "In9.Cu")
	)
	(gr_line
		(start 410.220668 -148.996146)
		(end 410.195268 -148.970746)
		(stroke
			(width 0.508)
			(type default)
		)
		(layer "In9.Cu")
	)
	(gr_line
		(start 410.220668 -148.996146)
		(end 410.220668 -214.72652)
		(stroke
			(width 0.508)
			(type default)
		)
		(layer "In9.Cu")
	)
	(gr_line
		(start 410.754068 -148.462746)
		(end 410.220668 -148.996146)
		(stroke
			(width 0.508)
			(type default)
		)
		(layer "In9.Cu")
	)
	(gr_line
		(start 410.875988 -214.75446)
		(end 410.214318 -214.09279)
		(stroke
			(width 0.508)
			(type default)
		)
		(layer "In9.Cu")
	)
	(gr_line
		(start 418.927534 -148.361146)
		(end 421.056308 -150.48992)
		(stroke
			(width 0.508)
			(type default)
		)
		(layer "In9.Cu")
	)
	(gr_line
		(start 421.056308 -169.458386)
		(end 421.489632 -169.89171)
		(stroke
			(width 0.508)
			(type default)
		)
		(layer "In9.Cu")
	)
	(gr_line
		(start 421.056308 -150.48992)
		(end 421.056308 -169.458386)
		(stroke
			(width 0.508)
			(type default)
		)
		(layer "In9.Cu")
	)
	(gr_line
		(start 421.489632 -169.89171)
		(end 428.621698 -169.89171)
		(stroke
			(width 0.508)
			(type default)
		)
		(layer "In9.Cu")
	)
	(gr_line
		(start 428.490634 -214.798656)
		(end 429.111156 -215.419178)
		(stroke
			(width 0.508)
			(type default)
		)
		(layer "In9.Cu")
	)
	(gr_line
		(start 429.111156 -215.419178)
		(end 429.111156 -328.997056)
		(stroke
			(width 0.508)
			(type default)
		)
		(layer "In9.Cu")
	)
	(gr_line
		(start 429.122078 -321.85483)
		(end 452.871078 -321.85483)
		(stroke
			(width 0.508)
			(type default)
		)
		(layer "In9.Cu")
	)
	(gr_line
		(start 429.170338 -312.84291)
		(end 441.943998 -312.84291)
		(stroke
			(width 0.508)
			(type default)
		)
		(layer "In9.Cu")
	)
	(gr_line
		(start 429.201834 -322.243196)
		(end 429.60417 -321.84086)
		(stroke
			(width 0.508)
			(type default)
		)
		(layer "In9.Cu")
	)
	(gr_line
		(start 429.250094 -313.231276)
		(end 429.65243 -312.82894)
		(stroke
			(width 0.508)
			(type default)
		)
		(layer "In9.Cu")
	)
	(gr_line
		(start 429.353218 -351.74555)
		(end 408.285696 -351.74555)
		(stroke
			(width 0.508)
			(type default)
		)
		(layer "In9.Cu")
	)
	(gr_line
		(start 429.575722 -321.84086)
		(end 429.201834 -321.466972)
		(stroke
			(width 0.508)
			(type default)
		)
		(layer "In9.Cu")
	)
	(gr_line
		(start 429.60417 -321.84086)
		(end 429.575722 -321.84086)
		(stroke
			(width 0.508)
			(type default)
		)
		(layer "In9.Cu")
	)
	(gr_line
		(start 429.623982 -312.82894)
		(end 429.250094 -312.455052)
		(stroke
			(width 0.508)
			(type default)
		)
		(layer "In9.Cu")
	)
	(gr_line
		(start 429.65243 -312.82894)
		(end 429.623982 -312.82894)
		(stroke
			(width 0.508)
			(type default)
		)
		(layer "In9.Cu")
	)
	(gr_line
		(start 429.820578 -351.27819)
		(end 429.353218 -351.74555)
		(stroke
			(width 0.508)
			(type default)
		)
		(layer "In9.Cu")
	)
	(gr_line
		(start 429.820578 -329.706478)
		(end 429.111156 -328.997056)
		(stroke
			(width 0.508)
			(type default)
		)
		(layer "In9.Cu")
	)
	(gr_line
		(start 429.820578 -329.706478)
		(end 429.820578 -351.27819)
		(stroke
			(width 0.508)
			(type default)
		)
		(layer "In9.Cu")
	)
	(gr_line
		(start 440.747658 -362.59389)
		(end 445.385698 -357.95585)
		(stroke
			(width 0.508)
			(type default)
		)
		(layer "In9.Cu")
	)
	(gr_line
		(start 442.581538 -312.84291)
		(end 441.943998 -312.84291)
		(stroke
			(width 0.508)
			(type default)
		)
		(layer "In9.Cu")
	)
	(gr_line
		(start 442.700918 -169.89171)
		(end 428.621698 -169.89171)
		(stroke
			(width 0.508)
			(type default)
		)
		(layer "In9.Cu")
	)
	(gr_line
		(start 443.346078 -312.07837)
		(end 442.581538 -312.84291)
		(stroke
			(width 0.508)
			(type default)
		)
		(layer "In9.Cu")
	)
	(gr_line
		(start 443.346078 -312.07837)
		(end 443.346078 -170.53687)
		(stroke
			(width 0.508)
			(type default)
		)
		(layer "In9.Cu")
	)
	(gr_line
		(start 443.346078 -170.53687)
		(end 442.700918 -169.89171)
		(stroke
			(width 0.508)
			(type default)
		)
		(layer "In9.Cu")
	)
	(gr_line
		(start 445.385698 -357.95585)
		(end 445.385698 -335.80959)
		(stroke
			(width 0.508)
			(type default)
		)
		(layer "In9.Cu")
	)
	(gr_line
		(start 445.385698 -335.80959)
		(end 445.982598 -335.21269)
		(stroke
			(width 0.508)
			(type default)
		)
		(layer "In9.Cu")
	)
	(gr_line
		(start 445.982598 -335.21269)
		(end 453.523604 -335.21269)
		(stroke
			(width 0.508)
			(type default)
		)
		(layer "In9.Cu")
	)
	(gr_line
		(start 448.15252 -36.899088)
		(end 386.18668 -36.899088)
		(stroke
			(width 0.508)
			(type default)
		)
		(layer "In9.Cu")
	)
	(gr_line
		(start 450.96684 -72.342248)
		(end 452.37654 -70.932548)
		(stroke
			(width 0.508)
			(type default)
		)
		(layer "In9.Cu")
	)
	(gr_line
		(start 452.37654 -70.932548)
		(end 452.37654 -41.123108)
		(stroke
			(width 0.508)
			(type default)
		)
		(layer "In9.Cu")
	)
	(gr_line
		(start 452.37654 -41.123108)
		(end 448.15252 -36.899088)
		(stroke
			(width 0.508)
			(type default)
		)
		(layer "In9.Cu")
	)
	(gr_line
		(start 452.753476 -335.21269)
		(end 453.6059 -335.21269)
		(stroke
			(width 0.508)
			(type default)
		)
		(layer "In9.Cu")
	)
	(gr_line
		(start 452.871078 -321.85483)
		(end 453.203818 -322.18757)
		(stroke
			(width 0.508)
			(type default)
		)
		(layer "In9.Cu")
	)
	(gr_line
		(start 453.203818 -328.05497)
		(end 454.214738 -329.06589)
		(stroke
			(width 0.508)
			(type default)
		)
		(layer "In9.Cu")
	)
	(gr_line
		(start 453.203818 -322.18757)
		(end 453.203818 -328.05497)
		(stroke
			(width 0.508)
			(type default)
		)
		(layer "In9.Cu")
	)
	(gr_line
		(start 453.6059 -335.21269)
		(end 453.607424 -335.214214)
		(stroke
			(width 0.508)
			(type default)
		)
		(layer "In9.Cu")
	)
	(gr_line
		(start 453.607424 -335.214214)
		(end 454.214738 -334.6069)
		(stroke
			(width 0.508)
			(type default)
		)
		(layer "In9.Cu")
	)
	(gr_line
		(start 454.214738 -334.6069)
		(end 454.214738 -333.944976)
		(stroke
			(width 0.508)
			(type default)
		)
		(layer "In9.Cu")
	)
	(gr_line
		(start 454.214738 -329.06589)
		(end 454.214738 -334.568292)
		(stroke
			(width 0.508)
			(type default)
		)
		(layer "In9.Cu")
	)
	(gr_line
		(start 455.202036 0)
		(end 388.601966 0)
		(stroke
			(width 3.048)
			(type default)
		)
		(layer "In9.Cu")
	)
	(gr_line
		(start 456.202034 -9.780016)
		(end 456.202034 -0.999998)
		(stroke
			(width 3.048)
			(type default)
		)
		(layer "In9.Cu")
	)
	(gr_arc
		(start 456.202034 -9.780016)
		(mid 456.787827 -11.194206)
		(end 458.20203 -11.780012)
		(stroke
			(width 3.048)
			(type default)
		)
		(layer "In9.Cu")
	)
	(gr_arc
		(start 456.202034 -0.999998)
		(mid 455.909141 -0.292893)
		(end 455.202036 0)
		(stroke
			(width 3.048)
			(type default)
		)
		(layer "In9.Cu")
	)
	(gr_arc
		(start 463.300064 -441.989972)
		(mid 464.714275 -441.404187)
		(end 465.30006 -439.989976)
		(stroke
			(width 3.048)
			(type default)
		)
		(layer "In9.Cu")
	)
	(gr_line
		(start 465.30006 -439.989976)
		(end 465.30006 -409.528264)
		(stroke
			(width 3.048)
			(type default)
		)
		(layer "In9.Cu")
	)
	(gr_arc
		(start 465.885784 -408.114246)
		(mid 465.452298 -408.763001)
		(end 465.30006 -409.528264)
		(stroke
			(width 3.048)
			(type default)
		)
		(layer "In9.Cu")
	)
	(gr_line
		(start 465.885784 -408.114246)
		(end 467.71433 -406.2857)
		(stroke
			(width 3.048)
			(type default)
		)
		(layer "In9.Cu")
	)
	(gr_arc
		(start 467.71433 -406.2857)
		(mid 468.147816 -405.636943)
		(end 468.300054 -404.871682)
		(stroke
			(width 3.048)
			(type default)
		)
		(layer "In9.Cu")
	)
	(gr_line
		(start 468.300054 -404.871682)
		(end 468.300054 -82.82813)
		(stroke
			(width 3.048)
			(type default)
		)
		(layer "In9.Cu")
	)
	(gr_arc
		(start 468.885778 -81.414112)
		(mid 468.452282 -82.062865)
		(end 468.300054 -82.82813)
		(stroke
			(width 3.048)
			(type default)
		)
		(layer "In9.Cu")
	)
	(gr_line
		(start 468.885778 -81.414112)
		(end 471.214196 -79.085694)
		(stroke
			(width 3.048)
			(type default)
		)
		(layer "In9.Cu")
	)
	(gr_line
		(start 469.799924 -11.780012)
		(end 458.20203 -11.780012)
		(stroke
			(width 3.048)
			(type default)
		)
		(layer "In9.Cu")
	)
	(gr_arc
		(start 471.214196 -79.085694)
		(mid 471.647682 -78.436937)
		(end 471.79992 -77.671676)
		(stroke
			(width 3.048)
			(type default)
		)
		(layer "In9.Cu")
	)
	(gr_line
		(start 471.79992 -77.671676)
		(end 471.79992 -13.780008)
		(stroke
			(width 3.048)
			(type default)
		)
		(layer "In9.Cu")
	)
	(gr_arc
		(start 471.79992 -13.780008)
		(mid 471.214135 -12.365797)
		(end 469.799924 -11.780012)
		(stroke
			(width 3.048)
			(type default)
		)
		(layer "In9.Cu")
	)
	(gr_poly
		(pts
			(arc
				(start 278.10841 -405.924766)
				(mid 278.127045 -405.923069)
				(end 278.145748 -405.92248)
			)
			(xy 280.90622 -405.92248) (xy 281.051508 -405.777192) (xy 281.051508 -397.72844) (xy 280.706068 -397.383)
			(xy 275.6408 -397.383) (xy 275.3868 -397.637) (xy 275.3868 -405.8285) (xy 275.48332 -405.92502) (xy 278.105616 -405.92502)
		)
		(stroke
			(width 0)
			(type solid)
		)
		(fill yes)
		(layer "In10.Cu")
		(net "P12V_MAIN_R_0")
	)
	(gr_poly
		(pts
			(arc
				(start 273.791172 -406.781)
				(mid 273.810393 -406.777119)
				(end 273.826732 -406.766268)
			)
			(xy 274.30476 -406.28824) (xy 274.32 -406.274016) (xy 274.32 -397.635984) (xy 274.30476 -397.62176)
			(xy 274.083018 -397.400018) (xy 274.067016 -397.383) (xy 240.155984 -397.383) (xy 240.14176 -397.39824)
			(xy 239.666018 -397.873982) (xy 239.665764 -397.874236) (xy 239.649 -397.889984) (xy 239.649 -406.528016)
			(xy 239.66424 -406.54224) (xy 239.88776 -406.76576) (xy 239.901984 -406.781)
		)
		(stroke
			(width 0)
			(type solid)
		)
		(fill yes)
		(layer "In10.Cu")
		(net "P12V_MAIN_R")
	)
	(gr_poly
		(pts
			(xy 230.38054 -434.93182)
			(arc
				(start 230.38054 -423.45102)
				(mid 230.404693 -423.329504)
				(end 230.473504 -423.226484)
			)
			(arc
				(start 232.947464 -420.752524)
				(mid 233.050496 -420.683743)
				(end 233.172 -420.65956)
			)
			(xy 270.3322 -420.65956)
			(arc
				(start 275.456396 -415.535364)
				(mid 275.559428 -415.466583)
				(end 275.680932 -415.4424)
			)
			(xy 279.79624 -415.4424) (xy 280.19756 -415.04108) (xy 280.19756 -408.29992) (xy 279.96896 -408.07132)
			(arc
				(start 239.699292 -408.07132)
				(mid 239.577776 -408.047167)
				(end 239.474756 -407.978356)
			)
			(xy 237.61446 -406.11806)
			(arc
				(start 235.520992 -406.11806)
				(mid 235.399476 -406.093907)
				(end 235.296456 -406.025096)
			)
			(arc
				(start 233.973624 -404.702264)
				(mid 233.904843 -404.599232)
				(end 233.88066 -404.477728)
			)
			(xy 233.88066 -401.03298) (xy 233.86542 -401.01774) (xy 230.47706 -401.01774) (xy 230.46182 -401.03298)
			(arc
				(start 230.46182 -404.473156)
				(mid 230.437667 -404.594672)
				(end 230.368856 -404.697692)
			)
			(xy 230.256588 -404.80996)
			(arc
				(start 230.256588 -407.3906)
				(mid 230.232435 -407.512116)
				(end 230.163624 -407.615136)
			)
			(arc
				(start 228.159564 -409.619196)
				(mid 228.056532 -409.687977)
				(end 227.935028 -409.71216)
			)
			(arc
				(start 225.70694 -409.71216)
				(mid 225.585424 -409.688007)
				(end 225.482404 -409.619196)
			)
			(arc
				(start 223.491552 -407.628344)
				(mid 223.422771 -407.525312)
				(end 223.398588 -407.403808)
			)
			(xy 223.398588 -404.79218)
			(arc
				(start 223.310704 -404.704296)
				(mid 223.241923 -404.601264)
				(end 223.21774 -404.47976)
			)
			(xy 223.21774 -401.04568) (xy 223.19234 -401.02028) (xy 219.81414 -401.02028) (xy 219.79636 -401.03806)
			(arc
				(start 219.79636 -404.490936)
				(mid 219.772207 -404.612452)
				(end 219.703396 -404.715472)
			)
			(xy 219.613988 -404.80488)
			(arc
				(start 219.613988 -407.259028)
				(mid 219.589835 -407.380544)
				(end 219.521024 -407.483564)
			)
			(arc
				(start 217.497152 -409.507436)
				(mid 217.39412 -409.576217)
				(end 217.272616 -409.6004)
			)
			(arc
				(start 214.794592 -409.6004)
				(mid 214.673076 -409.576247)
				(end 214.570056 -409.507436)
			)
			(arc
				(start 212.812884 -407.750264)
				(mid 212.744103 -407.647232)
				(end 212.71992 -407.525728)
			)
			(xy 212.71992 -404.79472)
			(arc
				(start 212.635084 -404.709884)
				(mid 212.566303 -404.606852)
				(end 212.54212 -404.485348)
			)
			(xy 212.54212 -401.02536) (xy 212.53704 -401.02028) (xy 209.14106 -401.02028) (xy 209.13598 -401.02536)
			(arc
				(start 209.13598 -404.452836)
				(mid 209.111827 -404.574352)
				(end 209.043016 -404.677372)
			)
			(xy 208.945988 -404.7744)
			(arc
				(start 208.945988 -407.30424)
				(mid 208.921835 -407.425756)
				(end 208.853024 -407.528776)
			)
			(arc
				(start 206.770224 -409.611576)
				(mid 206.667192 -409.680357)
				(end 206.545688 -409.70454)
			)
			(arc
				(start 204.16012 -409.70454)
				(mid 204.038604 -409.680387)
				(end 203.935584 -409.611576)
			)
			(arc
				(start 202.155552 -407.831544)
				(mid 202.086771 -407.728512)
				(end 202.062588 -407.607008)
			)
			(xy 202.062588 -404.779988)
			(arc
				(start 201.969624 -404.687024)
				(mid 201.900843 -404.583992)
				(end 201.87666 -404.462488)
			)
			(xy 201.87666 -401.03298) (xy 201.86396 -401.02028) (xy 198.47306 -401.02028) (xy 198.46798 -401.02536)
			(arc
				(start 198.46798 -404.487888)
				(mid 198.443827 -404.609404)
				(end 198.375016 -404.712424)
			)
			(arc
				(start 197.194424 -405.893016)
				(mid 197.091392 -405.961797)
				(end 196.969888 -405.98598)
			)
			(arc
				(start 190.870332 -405.98598)
				(mid 190.748816 -405.961827)
				(end 190.645796 -405.893016)
			)
			(arc
				(start 189.455552 -404.702518)
				(mid 189.386771 -404.599486)
				(end 189.362588 -404.477982)
			)
			(xy 189.362588 -404.177754) (xy 189.337188 -404.152354)
			(arc
				(start 189.11316 -404.152354)
				(mid 188.991644 -404.128201)
				(end 188.888624 -404.05939)
			)
			(arc
				(start 188.710824 -403.88159)
				(mid 188.642043 -403.778558)
				(end 188.61786 -403.657054)
			)
			(xy 188.61786 -401.02028) (xy 188.600588 -401.002754) (xy 185.196988 -401.002754) (xy 185.196988 -406.489154)
			(arc
				(start 185.434224 -406.72639)
				(mid 185.480227 -406.78458)
				(end 185.51144 -406.851866)
			)
			(arc
				(start 185.51144 -406.851866)
				(mid 185.548193 -406.942536)
				(end 185.560716 -407.039572)
			)
			(arc
				(start 185.560716 -407.039572)
				(mid 185.553298 -407.114694)
				(end 185.531252 -407.186892)
			)
			(xy 185.527188 -407.19629)
			(arc
				(start 185.527188 -408.287982)
				(mid 185.503035 -408.409498)
				(end 185.434224 -408.512518)
			)
			(xy 185.323988 -408.622754) (xy 185.323988 -413.053276) (xy 192.882012 -420.6113)
			(arc
				(start 197.416928 -420.6113)
				(mid 197.538444 -420.635453)
				(end 197.641464 -420.704264)
			)
			(arc
				(start 206.398876 -429.461676)
				(mid 206.467657 -429.564708)
				(end 206.49184 -429.686212)
			)
			(xy 206.49184 -435.39156) (xy 207.63484 -436.53456) (xy 228.7778 -436.53456)
		)
		(stroke
			(width 0)
			(type solid)
		)
		(fill yes)
		(layer "In10.Cu")
		(net "P12V_PSU")
	)
	(gr_poly
		(pts
			(xy 531.7998 -462.520284) (xy 531.855607 -462.519775) (xy 531.96691 -462.511434) (xy 532.077278 -462.494798)
			(xy 532.186094 -462.469962) (xy 532.29275 -462.437062) (xy 532.396649 -462.396285) (xy 532.49721 -462.347857)
			(xy 532.593871 -462.292049) (xy 532.686092 -462.229174) (xy 532.773355 -462.159583) (xy 532.855174 -462.083666)
			(xy 532.931091 -462.001846) (xy 533.000681 -461.914582) (xy 533.063556 -461.822361) (xy 533.119362 -461.7257)
			(xy 533.16779 -461.625138) (xy 533.208566 -461.521239) (xy 533.241465 -461.414583) (xy 533.266301 -461.305766)
			(xy 533.282935 -461.195398) (xy 533.291275 -461.084095) (xy 533.291796 -461.028288) (xy 533.291796 -455.0283)
			(xy 533.291274 -454.972493) (xy 533.282933 -454.861191) (xy 533.266298 -454.750824) (xy 533.241462 -454.642008)
			(xy 533.208563 -454.535353) (xy 533.167786 -454.431454) (xy 533.119358 -454.330893) (xy 533.063551 -454.234233)
			(xy 533.000677 -454.142013) (xy 532.931086 -454.054749) (xy 532.85517 -453.97293) (xy 532.773351 -453.897014)
			(xy 532.686087 -453.827423) (xy 532.593867 -453.764549) (xy 532.497207 -453.708742) (xy 532.396646 -453.660314)
			(xy 532.292747 -453.619537) (xy 532.186092 -453.586638) (xy 532.077276 -453.561802) (xy 531.966909 -453.545167)
			(xy 531.855607 -453.536826) (xy 531.7998 -453.536304) (xy 516.019796 -453.536304) (xy 515.949442 -453.535811)
			(xy 515.808956 -453.527921) (xy 515.669133 -453.512166) (xy 515.530414 -453.488597) (xy 515.393234 -453.457286)
			(xy 515.258026 -453.418334) (xy 515.125215 -453.371861) (xy 514.995218 -453.318014) (xy 514.868445 -453.256963)
			(xy 514.745294 -453.188901) (xy 514.626154 -453.11404) (xy 514.511398 -453.032616) (xy 514.401389 -452.944887)
			(xy 514.296471 -452.851127) (xy 514.196976 -452.751632) (xy 514.103216 -452.646714) (xy 514.015486 -452.536705)
			(xy 513.934063 -452.421949) (xy 513.859201 -452.302809) (xy 513.791138 -452.179659) (xy 513.730087 -452.052886)
			(xy 513.676241 -451.922889) (xy 513.629768 -451.790078) (xy 513.590815 -451.65487) (xy 513.559504 -451.51769)
			(xy 513.535934 -451.378971) (xy 513.520179 -451.239148) (xy 513.512289 -451.098662) (xy 513.5118 -451.028308)
			(xy 513.5118 -312.408316) (xy 513.512284 -312.337962) (xy 513.520173 -312.197474) (xy 513.535926 -312.05765)
			(xy 513.559495 -311.91893) (xy 513.590805 -311.781749) (xy 513.629757 -311.646539) (xy 513.676229 -311.513726)
			(xy 513.730076 -311.383728) (xy 513.791126 -311.256954) (xy 513.859189 -311.133802) (xy 513.93405 -311.01466)
			(xy 514.015474 -310.899903) (xy 514.103203 -310.789893) (xy 514.196964 -310.684974) (xy 514.296459 -310.585477)
			(xy 514.401377 -310.491716) (xy 514.511387 -310.403986) (xy 514.626144 -310.322561) (xy 514.745285 -310.247699)
			(xy 514.868436 -310.179635) (xy 514.99521 -310.118584) (xy 515.125208 -310.064737) (xy 515.25802 -310.018263)
			(xy 515.393229 -309.97931) (xy 515.53041 -309.947999) (xy 515.669131 -309.924429) (xy 515.808954 -309.908674)
			(xy 515.949442 -309.900784) (xy 516.019796 -309.90032) (xy 531.7998 -309.90032) (xy 531.855607 -309.899798)
			(xy 531.96691 -309.891457) (xy 532.077278 -309.874822) (xy 532.186094 -309.849986) (xy 532.292751 -309.817087)
			(xy 532.39665 -309.77631) (xy 532.497211 -309.727883) (xy 532.593873 -309.672076) (xy 532.686094 -309.609202)
			(xy 532.773358 -309.539612) (xy 532.855178 -309.463695) (xy 532.931096 -309.381876) (xy 533.000687 -309.294613)
			(xy 533.063563 -309.202393) (xy 533.119372 -309.105733) (xy 533.167801 -309.005172) (xy 533.208579 -308.901273)
			(xy 533.24148 -308.794618) (xy 533.266318 -308.685802) (xy 533.282955 -308.575434) (xy 533.291297 -308.464131)
			(xy 533.291796 -308.408324) (xy 533.291796 10.40003) (xy 533.291273 10.455836) (xy 533.28293 10.567137)
			(xy 533.266293 10.677502) (xy 533.241455 10.786316) (xy 533.208555 10.89297) (xy 533.167777 10.996866)
			(xy 533.119348 11.097425) (xy 533.063541 11.194084) (xy 533.000666 11.286302) (xy 532.931076 11.373563)
			(xy 532.855159 11.45538) (xy 532.77334 11.531295) (xy 532.686078 11.600884) (xy 532.593858 11.663757)
			(xy 532.497199 11.719562) (xy 532.396639 11.767989) (xy 532.292741 11.808765) (xy 532.186087 11.841663)
			(xy 532.077273 11.866499) (xy 531.966907 11.883134) (xy 531.855606 11.891474) (xy 531.7998 11.892026)
			(xy 475.799912 11.892026) (xy 475.744104 11.891505) (xy 475.632801 11.883165) (xy 475.522432 11.86653)
			(xy 475.413615 11.841695) (xy 475.306958 11.808796) (xy 475.203057 11.76802) (xy 475.102495 11.719593)
			(xy 475.005832 11.663786) (xy 474.91361 11.600912) (xy 474.826345 11.531322) (xy 474.744524 11.455406)
			(xy 474.668605 11.373587) (xy 474.599013 11.286323) (xy 474.536136 11.194103) (xy 474.480327 11.097442)
			(xy 474.431897 10.996881) (xy 474.391117 10.892982) (xy 474.358216 10.786326) (xy 474.333378 10.677509)
			(xy 474.31674 10.567141) (xy 474.308397 10.455838) (xy 474.307916 10.40003) (xy 474.307916 7.335466)
			(xy 526.704041 7.335466) (xy 526.704041 7.464606) (xy 526.711991 7.593501) (xy 526.727861 7.721661)
			(xy 526.75159 7.848602) (xy 526.783089 7.973841) (xy 526.822238 8.096904) (xy 526.868889 8.217323)
			(xy 526.922864 8.334642) (xy 526.983959 8.448416) (xy 527.051942 8.558213) (xy 527.126556 8.663616)
			(xy 527.207517 8.764226) (xy 527.294517 8.859661) (xy 527.387228 8.94956) (xy 527.485298 9.033581)
			(xy 527.588353 9.111405) (xy 527.696004 9.182737) (xy 527.807843 9.247307) (xy 527.923444 9.304869)
			(xy 528.042369 9.355206) (xy 528.164168 9.398126) (xy 528.288378 9.433467) (xy 528.414527 9.461094)
			(xy 528.542139 9.480903) (xy 528.670728 9.492819) (xy 528.799806 9.496796) (xy 528.928884 9.492819)
			(xy 529.057473 9.480903) (xy 529.185085 9.461094) (xy 529.311234 9.433467) (xy 529.435444 9.398126)
			(xy 529.557243 9.355206) (xy 529.676168 9.304869) (xy 529.791769 9.247307) (xy 529.903608 9.182737)
			(xy 530.011259 9.111405) (xy 530.114314 9.033581) (xy 530.212384 8.94956) (xy 530.305095 8.859661)
			(xy 530.392095 8.764226) (xy 530.473056 8.663616) (xy 530.54767 8.558213) (xy 530.615653 8.448416)
			(xy 530.676748 8.334642) (xy 530.730723 8.217323) (xy 530.777374 8.096904) (xy 530.816523 7.973841)
			(xy 530.848022 7.848602) (xy 530.871751 7.721661) (xy 530.887621 7.593501) (xy 530.895571 7.464606)
			(xy 530.896068 7.400036) (xy 530.895571 7.335466) (xy 530.887621 7.206571) (xy 530.871751 7.078411)
			(xy 530.848022 6.95147) (xy 530.816523 6.826231) (xy 530.777374 6.703168) (xy 530.730723 6.582749)
			(xy 530.676748 6.46543) (xy 530.615653 6.351656) (xy 530.54767 6.241859) (xy 530.473056 6.136456)
			(xy 530.392095 6.035846) (xy 530.305095 5.940411) (xy 530.212384 5.850512) (xy 530.114314 5.766491)
			(xy 530.011259 5.688667) (xy 529.903608 5.617335) (xy 529.791769 5.552765) (xy 529.676168 5.495203)
			(xy 529.557243 5.444866) (xy 529.435444 5.401946) (xy 529.311234 5.366605) (xy 529.185085 5.338978)
			(xy 529.057473 5.319169) (xy 528.928884 5.307253) (xy 528.799806 5.303277) (xy 528.670728 5.307253)
			(xy 528.542139 5.319169) (xy 528.414527 5.338978) (xy 528.288378 5.366605) (xy 528.164168 5.401946)
			(xy 528.042369 5.444866) (xy 527.923444 5.495203) (xy 527.807843 5.552765) (xy 527.696004 5.617335)
			(xy 527.588353 5.688667) (xy 527.485298 5.766491) (xy 527.387228 5.850512) (xy 527.294517 5.940411)
			(xy 527.207517 6.035846) (xy 527.126556 6.136456) (xy 527.051942 6.241859) (xy 526.983959 6.351656)
			(xy 526.922864 6.46543) (xy 526.868889 6.582749) (xy 526.822238 6.703168) (xy 526.783089 6.826231)
			(xy 526.75159 6.95147) (xy 526.727861 7.078411) (xy 526.711991 7.206571) (xy 526.704041 7.335466)
			(xy 474.307916 7.335466) (xy 474.307916 -77.67193) (xy 474.307428 -77.765094) (xy 474.299715 -77.951262)
			(xy 474.284317 -78.136953) (xy 474.261258 -78.321849) (xy 474.23058 -78.505634) (xy 474.192333 -78.687994)
			(xy 474.146584 -78.868619) (xy 474.093411 -79.047199) (xy 474.032904 -79.223429) (xy 473.965167 -79.397008)
			(xy 473.890315 -79.56764) (xy 473.808477 -79.735034) (xy 473.719792 -79.898903) (xy 473.624411 -80.058968)
			(xy 473.522498 -80.214955) (xy 473.414227 -80.366597) (xy 473.299782 -80.513637) (xy 473.17936 -80.655821)
			(xy 473.053165 -80.792909) (xy 472.987624 -80.859122) (xy 471.245184 -82.601562) (xy 471.207836 -82.63956)
			(xy 471.138049 -82.720082) (xy 471.074185 -82.805378) (xy 471.01657 -82.895014) (xy 470.965496 -82.988531)
			(xy 470.921226 -83.085455) (xy 470.883983 -83.18529) (xy 470.853958 -83.287527) (xy 470.831304 -83.391646)
			(xy 470.816136 -83.497117) (xy 470.808532 -83.6034) (xy 470.80805 -83.656678) (xy 470.80805 -404.871936)
			(xy 470.807562 -404.9651) (xy 470.799849 -405.151268) (xy 470.78445 -405.336959) (xy 470.761392 -405.521855)
			(xy 470.730713 -405.70564) (xy 470.692467 -405.888001) (xy 470.646718 -406.068625) (xy 470.593544 -406.247205)
			(xy 470.533038 -406.423435) (xy 470.465301 -406.597015) (xy 470.39045 -406.767647) (xy 470.308612 -406.935041)
			(xy 470.219927 -407.098911) (xy 470.124547 -407.258976) (xy 470.022634 -407.414963) (xy 469.914363 -407.566606)
			(xy 469.799919 -407.713645) (xy 469.679497 -407.855831) (xy 469.553302 -407.992919) (xy 469.487758 -408.059128)
			(xy 468.244936 -409.30195) (xy 468.207612 -409.339964) (xy 468.137859 -409.4205) (xy 468.074028 -409.505805)
			(xy 468.016443 -409.595446) (xy 467.965398 -409.688966) (xy 467.921153 -409.785888) (xy 467.883933 -409.885719)
			(xy 467.853928 -409.98795) (xy 467.831291 -410.092061) (xy 467.816137 -410.197522) (xy 467.808543 -410.303794)
			(xy 467.808056 -410.357066) (xy 467.808056 -439.989976) (xy 467.808577 -440.045784) (xy 467.816916 -440.157089)
			(xy 467.83355 -440.267459) (xy 467.858385 -440.376277) (xy 467.891282 -440.482936) (xy 467.932058 -440.586837)
			(xy 467.980485 -440.687401) (xy 468.036291 -440.784065) (xy 468.099165 -440.876289) (xy 468.168754 -440.963556)
			(xy 468.244671 -441.045378) (xy 468.32649 -441.121299) (xy 468.413753 -441.190893) (xy 468.505974 -441.253771)
			(xy 468.602635 -441.309582) (xy 468.703197 -441.358013) (xy 468.807096 -441.398794) (xy 468.913753 -441.431697)
			(xy 469.02257 -441.456537) (xy 469.13294 -441.473176) (xy 469.244244 -441.48152) (xy 469.300052 -441.481972)
			(xy 471.79992 -441.481972) (xy 471.870274 -441.482466) (xy 472.01076 -441.490356) (xy 472.150582 -441.506112)
			(xy 472.289302 -441.529682) (xy 472.426481 -441.560993) (xy 472.561689 -441.599946) (xy 472.6945 -441.646419)
			(xy 472.824497 -441.700266) (xy 472.95127 -441.761317) (xy 473.07442 -441.82938) (xy 473.19356 -441.904241)
			(xy 473.308316 -441.985664) (xy 473.418325 -442.073394) (xy 473.523243 -442.167153) (xy 473.622738 -442.266648)
			(xy 473.716499 -442.371565) (xy 473.804229 -442.481575) (xy 473.885652 -442.59633) (xy 473.960514 -442.71547)
			(xy 474.028578 -442.83862) (xy 474.089629 -442.965392) (xy 474.143476 -443.095389) (xy 474.18995 -443.2282)
			(xy 474.228904 -443.363407) (xy 474.260216 -443.500587) (xy 474.283787 -443.639306) (xy 474.299543 -443.779128)
			(xy 474.307434 -443.919614) (xy 474.307916 -443.989968) (xy 474.307916 -458.092864) (xy 526.704041 -458.092864)
			(xy 526.704041 -457.963724) (xy 526.711991 -457.834829) (xy 526.727861 -457.706669) (xy 526.75159 -457.579728)
			(xy 526.783089 -457.454489) (xy 526.822238 -457.331426) (xy 526.868889 -457.211007) (xy 526.922864 -457.093688)
			(xy 526.983959 -456.979914) (xy 527.051942 -456.870117) (xy 527.126556 -456.764714) (xy 527.207517 -456.664104)
			(xy 527.294517 -456.568669) (xy 527.387228 -456.47877) (xy 527.485298 -456.394749) (xy 527.588353 -456.316925)
			(xy 527.696004 -456.245593) (xy 527.807843 -456.181023) (xy 527.923444 -456.123461) (xy 528.042369 -456.073124)
			(xy 528.164168 -456.030204) (xy 528.288378 -455.994863) (xy 528.414527 -455.967236) (xy 528.542139 -455.947427)
			(xy 528.670728 -455.935511) (xy 528.799806 -455.931535) (xy 528.928884 -455.935511) (xy 529.057473 -455.947427)
			(xy 529.185085 -455.967236) (xy 529.311234 -455.994863) (xy 529.435444 -456.030204) (xy 529.557243 -456.073124)
			(xy 529.676168 -456.123461) (xy 529.791769 -456.181023) (xy 529.903608 -456.245593) (xy 530.011259 -456.316925)
			(xy 530.114314 -456.394749) (xy 530.212384 -456.47877) (xy 530.305095 -456.568669) (xy 530.392095 -456.664104)
			(xy 530.473056 -456.764714) (xy 530.54767 -456.870117) (xy 530.615653 -456.979914) (xy 530.676748 -457.093688)
			(xy 530.730723 -457.211007) (xy 530.777374 -457.331426) (xy 530.816523 -457.454489) (xy 530.848022 -457.579728)
			(xy 530.871751 -457.706669) (xy 530.887621 -457.834829) (xy 530.895571 -457.963724) (xy 530.896068 -458.028294)
			(xy 530.895571 -458.092864) (xy 530.887621 -458.221759) (xy 530.871751 -458.349919) (xy 530.848022 -458.47686)
			(xy 530.816523 -458.602099) (xy 530.777374 -458.725162) (xy 530.730723 -458.845581) (xy 530.676748 -458.9629)
			(xy 530.615653 -459.076674) (xy 530.54767 -459.186471) (xy 530.473056 -459.291874) (xy 530.392095 -459.392484)
			(xy 530.305095 -459.487919) (xy 530.212384 -459.577818) (xy 530.114314 -459.661839) (xy 530.011259 -459.739663)
			(xy 529.903608 -459.810995) (xy 529.791769 -459.875565) (xy 529.676168 -459.933127) (xy 529.557243 -459.983464)
			(xy 529.435444 -460.026384) (xy 529.311234 -460.061725) (xy 529.185085 -460.089352) (xy 529.057473 -460.109161)
			(xy 528.928884 -460.121077) (xy 528.799806 -460.125054) (xy 528.670728 -460.121077) (xy 528.542139 -460.109161)
			(xy 528.414527 -460.089352) (xy 528.288378 -460.061725) (xy 528.164168 -460.026384) (xy 528.042369 -459.983464)
			(xy 527.923444 -459.933127) (xy 527.807843 -459.875565) (xy 527.696004 -459.810995) (xy 527.588353 -459.739663)
			(xy 527.485298 -459.661839) (xy 527.387228 -459.577818) (xy 527.294517 -459.487919) (xy 527.207517 -459.392484)
			(xy 527.126556 -459.291874) (xy 527.051942 -459.186471) (xy 526.983959 -459.076674) (xy 526.922864 -458.9629)
			(xy 526.868889 -458.845581) (xy 526.822238 -458.725162) (xy 526.783089 -458.602099) (xy 526.75159 -458.47686)
			(xy 526.727861 -458.349919) (xy 526.711991 -458.221759) (xy 526.704041 -458.092864) (xy 474.307916 -458.092864)
			(xy 474.307916 -461.028288) (xy 474.308425 -461.084096) (xy 474.316765 -461.195399) (xy 474.3334 -461.305768)
			(xy 474.358236 -461.414584) (xy 474.391134 -461.521241) (xy 474.431912 -461.625141) (xy 474.480339 -461.725703)
			(xy 474.536147 -461.822365) (xy 474.599022 -461.914586) (xy 474.668612 -462.00185) (xy 474.74453 -462.08367)
			(xy 474.82635 -462.159588) (xy 474.913614 -462.229178) (xy 475.005835 -462.292053) (xy 475.102497 -462.347861)
			(xy 475.203059 -462.396288) (xy 475.306959 -462.437066) (xy 475.413616 -462.469964) (xy 475.522432 -462.4948)
			(xy 475.632801 -462.511435) (xy 475.744104 -462.519775) (xy 475.799912 -462.520284)
		)
		(stroke
			(width 0)
			(type solid)
		)
		(fill yes)
		(layer "In10.Cu")
		(net "T1_GND")
	)
	(gr_poly
		(pts
			(xy 256.292096 -31.120588) (xy 256.292096 -11.780012) (xy 256.29258 -11.709658) (xy 256.300469 -11.56917)
			(xy 256.316223 -11.429347) (xy 256.339792 -11.290626) (xy 256.371101 -11.153445) (xy 256.410054 -11.018236)
			(xy 256.456527 -10.885423) (xy 256.510373 -10.755425) (xy 256.571423 -10.628651) (xy 256.639486 -10.505499)
			(xy 256.714347 -10.386357) (xy 256.795771 -10.2716) (xy 256.883501 -10.16159) (xy 256.977261 -10.056671)
			(xy 257.076757 -9.957175) (xy 257.181674 -9.863414) (xy 257.291684 -9.775683) (xy 257.406441 -9.694258)
			(xy 257.525582 -9.619396) (xy 257.648733 -9.551333) (xy 257.775507 -9.490281) (xy 257.905504 -9.436434)
			(xy 258.038317 -9.38996) (xy 258.173526 -9.351006) (xy 258.310706 -9.319695) (xy 258.449427 -9.296125)
			(xy 258.589251 -9.280371) (xy 258.729738 -9.272481) (xy 258.800092 -9.272016) (xy 383.601976 -9.272016)
			(xy 383.657784 -9.271508) (xy 383.769089 -9.263168) (xy 383.879459 -9.246534) (xy 383.988278 -9.221699)
			(xy 384.094936 -9.188801) (xy 384.198838 -9.148025) (xy 384.299402 -9.099598) (xy 384.396066 -9.043791)
			(xy 384.488289 -8.980916) (xy 384.575555 -8.911326) (xy 384.657377 -8.835408) (xy 384.733297 -8.753588)
			(xy 384.80289 -8.666324) (xy 384.865767 -8.574103) (xy 384.921577 -8.477441) (xy 384.970007 -8.376878)
			(xy 385.010787 -8.272978) (xy 385.043688 -8.16632) (xy 385.068526 -8.057503) (xy 385.085163 -7.947133)
			(xy 385.093506 -7.835828) (xy 385.093972 -7.78002) (xy 385.093972 0.999998) (xy 385.094465 1.070352)
			(xy 385.102355 1.210839) (xy 385.118109 1.350662) (xy 385.141678 1.489383) (xy 385.172988 1.626563)
			(xy 385.211941 1.761772) (xy 385.258413 1.894584) (xy 385.312259 2.024582) (xy 385.37331 2.151356)
			(xy 385.441373 2.274507) (xy 385.516233 2.393649) (xy 385.597656 2.508405) (xy 385.685386 2.618416)
			(xy 385.779146 2.723335) (xy 385.878641 2.822831) (xy 385.983558 2.916592) (xy 386.093567 3.004323)
			(xy 386.208323 3.085748) (xy 386.327463 3.16061) (xy 386.450614 3.228674) (xy 386.577387 3.289727)
			(xy 386.707384 3.343575) (xy 386.840195 3.390049) (xy 386.975404 3.429003) (xy 387.112584 3.460315)
			(xy 387.251304 3.483887) (xy 387.391127 3.499643) (xy 387.531614 3.507534) (xy 387.601968 3.507994)
			(xy 456.202034 3.507994) (xy 456.272387 3.5075) (xy 456.412872 3.499608) (xy 456.552693 3.483853)
			(xy 456.691411 3.460282) (xy 456.828589 3.42897) (xy 456.963796 3.390016) (xy 457.096605 3.343542)
			(xy 457.226601 3.289695) (xy 457.353372 3.228644) (xy 457.476521 3.16058) (xy 457.595659 3.085719)
			(xy 457.710413 3.004295) (xy 457.820421 2.916565) (xy 457.925337 2.822806) (xy 458.02483 2.723311)
			(xy 458.118589 2.618393) (xy 458.206317 2.508384) (xy 458.287739 2.393629) (xy 458.362598 2.27449)
			(xy 458.43066 2.15134) (xy 458.49171 2.024568) (xy 458.545555 1.894572) (xy 458.592027 1.761761)
			(xy 458.630979 1.626554) (xy 458.662289 1.489376) (xy 458.685858 1.350658) (xy 458.701612 1.210836)
			(xy 458.709501 1.070351) (xy 458.71003 0.999998) (xy 458.71003 -7.78002) (xy 458.71054 -7.835827)
			(xy 458.718882 -7.947128) (xy 458.735519 -8.057494) (xy 458.760357 -8.166309) (xy 458.793257 -8.272963)
			(xy 458.834035 -8.37686) (xy 458.882464 -8.47742) (xy 458.938272 -8.574079) (xy 459.001148 -8.666297)
			(xy 459.070739 -8.753559) (xy 459.146656 -8.835376) (xy 459.228476 -8.911291) (xy 459.31574 -8.98088)
			(xy 459.40796 -9.043752) (xy 459.504621 -9.099557) (xy 459.605182 -9.147983) (xy 459.70908 -9.188758)
			(xy 459.815736 -9.221655) (xy 459.924551 -9.24649) (xy 460.034918 -9.263123) (xy 460.146219 -9.271462)
			(xy 460.202026 -9.272016) (xy 464.327748 -9.272016) (xy 464.332574 -9.271) (xy 464.357024 -9.266474)
			(xy 464.406516 -9.261643) (xy 464.43138 -9.261348) (xy 464.456244 -9.26164) (xy 464.505735 -9.266479)
			(xy 464.530186 -9.271) (xy 464.535012 -9.272016) (xy 469.799924 -9.272016) (xy 469.855731 -9.271493)
			(xy 469.967032 -9.263151) (xy 470.077399 -9.246514) (xy 470.186213 -9.221677) (xy 470.292868 -9.188777)
			(xy 470.396765 -9.147999) (xy 470.497325 -9.099571) (xy 470.593985 -9.043764) (xy 470.686204 -8.980889)
			(xy 470.773467 -8.911299) (xy 470.855285 -8.835382) (xy 470.931202 -8.753564) (xy 471.000791 -8.666301)
			(xy 471.063666 -8.574082) (xy 471.119473 -8.477422) (xy 471.167901 -8.376862) (xy 471.208678 -8.272964)
			(xy 471.241578 -8.166309) (xy 471.266415 -8.057495) (xy 471.283051 -7.947128) (xy 471.291394 -7.835827)
			(xy 471.29192 -7.78002) (xy 471.29192 10.40003) (xy 471.291397 10.455837) (xy 471.283054 10.567138)
			(xy 471.266417 10.677504) (xy 471.241579 10.786319) (xy 471.208679 10.892973) (xy 471.167901 10.99687)
			(xy 471.119473 11.09743) (xy 471.063666 11.194089) (xy 471.000791 11.286308) (xy 470.931201 11.373571)
			(xy 470.855284 11.455389) (xy 470.773466 11.531305) (xy 470.686203 11.600895) (xy 470.593984 11.663769)
			(xy 470.497324 11.719576) (xy 470.396765 11.768004) (xy 470.292867 11.808781) (xy 470.186213 11.841681)
			(xy 470.077398 11.866518) (xy 469.967032 11.883155) (xy 469.855731 11.891497) (xy 469.799924 11.892026)
			(xy 1.999996 11.892026) (xy 1.944189 11.891504) (xy 1.832887 11.883163) (xy 1.72252 11.866527) (xy 1.613705 11.841691)
			(xy 1.50705 11.808792) (xy 1.403151 11.768014) (xy 1.302591 11.719587) (xy 1.20593 11.66378) (xy 1.113711 11.600905)
			(xy 1.026448 11.531315) (xy 0.944629 11.455398) (xy 0.868712 11.373579) (xy 0.799122 11.286316) (xy 0.736248 11.194096)
			(xy 0.680441 11.097436) (xy 0.632014 10.996875) (xy 0.591237 10.892977) (xy 0.558338 10.786321) (xy 0.533502 10.677506)
			(xy 0.516867 10.567139) (xy 0.508526 10.455837) (xy 0.508 10.40003) (xy 0.508 7.335466) (xy 2.904225 7.335466)
			(xy 2.904225 7.464606) (xy 2.912175 7.593501) (xy 2.928045 7.721661) (xy 2.951774 7.848602) (xy 2.983273 7.973841)
			(xy 3.022422 8.096904) (xy 3.069073 8.217323) (xy 3.123048 8.334642) (xy 3.184143 8.448416) (xy 3.252126 8.558213)
			(xy 3.32674 8.663616) (xy 3.407701 8.764226) (xy 3.494701 8.859661) (xy 3.587412 8.94956) (xy 3.685482 9.033581)
			(xy 3.788537 9.111405) (xy 3.896188 9.182737) (xy 4.008027 9.247307) (xy 4.123628 9.304869) (xy 4.242553 9.355206)
			(xy 4.364352 9.398126) (xy 4.488562 9.433467) (xy 4.614711 9.461094) (xy 4.742323 9.480903) (xy 4.870912 9.492819)
			(xy 4.99999 9.496796) (xy 5.129068 9.492819) (xy 5.257657 9.480903) (xy 5.385269 9.461094) (xy 5.511418 9.433467)
			(xy 5.635628 9.398126) (xy 5.757427 9.355206) (xy 5.876352 9.304869) (xy 5.991953 9.247307) (xy 6.020338 9.230919)
			(xy 256.921241 9.230919) (xy 256.921241 9.316669) (xy 256.929153 9.402052) (xy 256.944909 9.486342)
			(xy 256.968376 9.568818) (xy 256.999352 9.648777) (xy 257.037574 9.725537) (xy 257.082715 9.798443)
			(xy 257.134391 9.866872) (xy 257.19216 9.930242) (xy 257.25553 9.988011) (xy 257.323959 10.039687)
			(xy 257.396865 10.084828) (xy 257.473625 10.12305) (xy 257.553584 10.154026) (xy 257.63606 10.177493)
			(xy 257.72035 10.193249) (xy 257.805733 10.201161) (xy 257.891483 10.201161) (xy 257.976866 10.193249)
			(xy 258.061156 10.177493) (xy 258.143632 10.154026) (xy 258.223591 10.12305) (xy 258.300351 10.084828)
			(xy 258.373257 10.039687) (xy 258.441686 9.988011) (xy 258.505056 9.930242) (xy 258.562825 9.866872)
			(xy 258.614501 9.798443) (xy 258.659642 9.725537) (xy 258.697864 9.648777) (xy 258.72884 9.568818)
			(xy 258.752307 9.486342) (xy 258.768063 9.402052) (xy 258.775975 9.316669) (xy 258.77647 9.273794)
			(xy 258.775975 9.230919) (xy 263.271241 9.230919) (xy 263.271241 9.316669) (xy 263.279153 9.402052)
			(xy 263.294909 9.486342) (xy 263.318376 9.568818) (xy 263.349352 9.648777) (xy 263.387574 9.725537)
			(xy 263.432715 9.798443) (xy 263.484391 9.866872) (xy 263.54216 9.930242) (xy 263.60553 9.988011)
			(xy 263.673959 10.039687) (xy 263.746865 10.084828) (xy 263.823625 10.12305) (xy 263.903584 10.154026)
			(xy 263.98606 10.177493) (xy 264.07035 10.193249) (xy 264.155733 10.201161) (xy 264.241483 10.201161)
			(xy 264.326866 10.193249) (xy 264.411156 10.177493) (xy 264.493632 10.154026) (xy 264.573591 10.12305)
			(xy 264.650351 10.084828) (xy 264.723257 10.039687) (xy 264.791686 9.988011) (xy 264.855056 9.930242)
			(xy 264.912825 9.866872) (xy 264.964501 9.798443) (xy 265.009642 9.725537) (xy 265.047864 9.648777)
			(xy 265.07884 9.568818) (xy 265.102307 9.486342) (xy 265.118063 9.402052) (xy 265.125975 9.316669)
			(xy 265.12647 9.273794) (xy 265.125975 9.230919) (xy 324.845921 9.230919) (xy 324.845921 9.316669)
			(xy 324.853833 9.402052) (xy 324.869589 9.486342) (xy 324.893056 9.568818) (xy 324.924032 9.648777)
			(xy 324.962254 9.725537) (xy 325.007395 9.798443) (xy 325.059071 9.866872) (xy 325.11684 9.930242)
			(xy 325.18021 9.988011) (xy 325.248639 10.039687) (xy 325.321545 10.084828) (xy 325.398305 10.12305)
			(xy 325.478264 10.154026) (xy 325.56074 10.177493) (xy 325.64503 10.193249) (xy 325.730413 10.201161)
			(xy 325.816163 10.201161) (xy 325.901546 10.193249) (xy 325.985836 10.177493) (xy 326.068312 10.154026)
			(xy 326.148271 10.12305) (xy 326.225031 10.084828) (xy 326.297937 10.039687) (xy 326.366366 9.988011)
			(xy 326.429736 9.930242) (xy 326.487505 9.866872) (xy 326.539181 9.798443) (xy 326.584322 9.725537)
			(xy 326.622544 9.648777) (xy 326.65352 9.568818) (xy 326.676987 9.486342) (xy 326.692743 9.402052)
			(xy 326.700655 9.316669) (xy 326.70115 9.273794) (xy 326.700655 9.230919) (xy 331.195921 9.230919)
			(xy 331.195921 9.316669) (xy 331.203833 9.402052) (xy 331.219589 9.486342) (xy 331.243056 9.568818)
			(xy 331.274032 9.648777) (xy 331.312254 9.725537) (xy 331.357395 9.798443) (xy 331.409071 9.866872)
			(xy 331.46684 9.930242) (xy 331.53021 9.988011) (xy 331.598639 10.039687) (xy 331.671545 10.084828)
			(xy 331.748305 10.12305) (xy 331.828264 10.154026) (xy 331.91074 10.177493) (xy 331.99503 10.193249)
			(xy 332.080413 10.201161) (xy 332.166163 10.201161) (xy 332.251546 10.193249) (xy 332.335836 10.177493)
			(xy 332.418312 10.154026) (xy 332.498271 10.12305) (xy 332.575031 10.084828) (xy 332.647937 10.039687)
			(xy 332.716366 9.988011) (xy 332.779736 9.930242) (xy 332.837505 9.866872) (xy 332.889181 9.798443)
			(xy 332.934322 9.725537) (xy 332.972544 9.648777) (xy 333.00352 9.568818) (xy 333.026987 9.486342)
			(xy 333.042743 9.402052) (xy 333.050655 9.316669) (xy 333.05115 9.273794) (xy 333.050655 9.230919)
			(xy 335.488267 9.230919) (xy 335.488267 9.316669) (xy 335.496179 9.402052) (xy 335.511935 9.486342)
			(xy 335.535402 9.568818) (xy 335.566378 9.648777) (xy 335.6046 9.725537) (xy 335.649741 9.798443)
			(xy 335.701417 9.866872) (xy 335.759186 9.930242) (xy 335.822556 9.988011) (xy 335.890985 10.039687)
			(xy 335.963891 10.084828) (xy 336.040651 10.12305) (xy 336.12061 10.154026) (xy 336.203086 10.177493)
			(xy 336.287376 10.193249) (xy 336.372759 10.201161) (xy 336.458509 10.201161) (xy 336.543892 10.193249)
			(xy 336.628182 10.177493) (xy 336.710658 10.154026) (xy 336.790617 10.12305) (xy 336.867377 10.084828)
			(xy 336.940283 10.039687) (xy 337.008712 9.988011) (xy 337.072082 9.930242) (xy 337.129851 9.866872)
			(xy 337.181527 9.798443) (xy 337.226668 9.725537) (xy 337.26489 9.648777) (xy 337.295866 9.568818)
			(xy 337.319333 9.486342) (xy 337.335089 9.402052) (xy 337.343001 9.316669) (xy 337.343496 9.273794)
			(xy 337.343001 9.230919) (xy 341.838267 9.230919) (xy 341.838267 9.316669) (xy 341.846179 9.402052)
			(xy 341.861935 9.486342) (xy 341.885402 9.568818) (xy 341.916378 9.648777) (xy 341.9546 9.725537)
			(xy 341.999741 9.798443) (xy 342.051417 9.866872) (xy 342.109186 9.930242) (xy 342.172556 9.988011)
			(xy 342.240985 10.039687) (xy 342.313891 10.084828) (xy 342.390651 10.12305) (xy 342.47061 10.154026)
			(xy 342.553086 10.177493) (xy 342.637376 10.193249) (xy 342.722759 10.201161) (xy 342.808509 10.201161)
			(xy 342.893892 10.193249) (xy 342.978182 10.177493) (xy 343.060658 10.154026) (xy 343.140617 10.12305)
			(xy 343.217377 10.084828) (xy 343.290283 10.039687) (xy 343.358712 9.988011) (xy 343.422082 9.930242)
			(xy 343.479851 9.866872) (xy 343.531527 9.798443) (xy 343.576668 9.725537) (xy 343.61489 9.648777)
			(xy 343.645866 9.568818) (xy 343.669333 9.486342) (xy 343.685089 9.402052) (xy 343.693001 9.316669)
			(xy 343.693496 9.273794) (xy 343.693001 9.230919) (xy 373.705107 9.230919) (xy 373.705107 9.316669)
			(xy 373.713019 9.402052) (xy 373.728775 9.486342) (xy 373.752242 9.568818) (xy 373.783218 9.648777)
			(xy 373.82144 9.725537) (xy 373.866581 9.798443) (xy 373.918257 9.866872) (xy 373.976026 9.930242)
			(xy 374.039396 9.988011) (xy 374.107825 10.039687) (xy 374.180731 10.084828) (xy 374.257491 10.12305)
			(xy 374.33745 10.154026) (xy 374.419926 10.177493) (xy 374.504216 10.193249) (xy 374.589599 10.201161)
			(xy 374.675349 10.201161) (xy 374.760732 10.193249) (xy 374.845022 10.177493) (xy 374.927498 10.154026)
			(xy 375.007457 10.12305) (xy 375.084217 10.084828) (xy 375.157123 10.039687) (xy 375.225552 9.988011)
			(xy 375.288922 9.930242) (xy 375.346691 9.866872) (xy 375.398367 9.798443) (xy 375.443508 9.725537)
			(xy 375.48173 9.648777) (xy 375.512706 9.568818) (xy 375.536173 9.486342) (xy 375.551929 9.402052)
			(xy 375.559841 9.316669) (xy 375.560336 9.273794) (xy 375.559841 9.230919) (xy 380.055107 9.230919)
			(xy 380.055107 9.316669) (xy 380.063019 9.402052) (xy 380.078775 9.486342) (xy 380.102242 9.568818)
			(xy 380.133218 9.648777) (xy 380.17144 9.725537) (xy 380.216581 9.798443) (xy 380.268257 9.866872)
			(xy 380.326026 9.930242) (xy 380.389396 9.988011) (xy 380.457825 10.039687) (xy 380.530731 10.084828)
			(xy 380.607491 10.12305) (xy 380.68745 10.154026) (xy 380.769926 10.177493) (xy 380.854216 10.193249)
			(xy 380.939599 10.201161) (xy 381.025349 10.201161) (xy 381.110732 10.193249) (xy 381.195022 10.177493)
			(xy 381.277498 10.154026) (xy 381.357457 10.12305) (xy 381.434217 10.084828) (xy 381.507123 10.039687)
			(xy 381.575552 9.988011) (xy 381.638922 9.930242) (xy 381.696691 9.866872) (xy 381.748367 9.798443)
			(xy 381.793508 9.725537) (xy 381.83173 9.648777) (xy 381.862706 9.568818) (xy 381.886173 9.486342)
			(xy 381.901929 9.402052) (xy 381.909841 9.316669) (xy 381.910336 9.273794) (xy 381.909841 9.230919)
			(xy 381.901929 9.145536) (xy 381.886173 9.061246) (xy 381.862706 8.97877) (xy 381.83173 8.898811)
			(xy 381.793508 8.822051) (xy 381.748367 8.749145) (xy 381.696691 8.680716) (xy 381.638922 8.617346)
			(xy 381.575552 8.559577) (xy 381.507123 8.507901) (xy 381.434217 8.46276) (xy 381.357457 8.424538)
			(xy 381.277498 8.393562) (xy 381.195022 8.370095) (xy 381.110732 8.354339) (xy 381.025349 8.346427)
			(xy 380.939599 8.346427) (xy 380.854216 8.354339) (xy 380.769926 8.370095) (xy 380.68745 8.393562)
			(xy 380.607491 8.424538) (xy 380.530731 8.46276) (xy 380.457825 8.507901) (xy 380.389396 8.559577)
			(xy 380.326026 8.617346) (xy 380.268257 8.680716) (xy 380.216581 8.749145) (xy 380.17144 8.822051)
			(xy 380.133218 8.898811) (xy 380.102242 8.97877) (xy 380.078775 9.061246) (xy 380.063019 9.145536)
			(xy 380.055107 9.230919) (xy 375.559841 9.230919) (xy 375.551929 9.145536) (xy 375.536173 9.061246)
			(xy 375.512706 8.97877) (xy 375.48173 8.898811) (xy 375.443508 8.822051) (xy 375.398367 8.749145)
			(xy 375.346691 8.680716) (xy 375.288922 8.617346) (xy 375.225552 8.559577) (xy 375.157123 8.507901)
			(xy 375.084217 8.46276) (xy 375.007457 8.424538) (xy 374.927498 8.393562) (xy 374.845022 8.370095)
			(xy 374.760732 8.354339) (xy 374.675349 8.346427) (xy 374.589599 8.346427) (xy 374.504216 8.354339)
			(xy 374.419926 8.370095) (xy 374.33745 8.393562) (xy 374.257491 8.424538) (xy 374.180731 8.46276)
			(xy 374.107825 8.507901) (xy 374.039396 8.559577) (xy 373.976026 8.617346) (xy 373.918257 8.680716)
			(xy 373.866581 8.749145) (xy 373.82144 8.822051) (xy 373.783218 8.898811) (xy 373.752242 8.97877)
			(xy 373.728775 9.061246) (xy 373.713019 9.145536) (xy 373.705107 9.230919) (xy 343.693001 9.230919)
			(xy 343.685089 9.145536) (xy 343.669333 9.061246) (xy 343.645866 8.97877) (xy 343.61489 8.898811)
			(xy 343.576668 8.822051) (xy 343.531527 8.749145) (xy 343.479851 8.680716) (xy 343.422082 8.617346)
			(xy 343.358712 8.559577) (xy 343.290283 8.507901) (xy 343.217377 8.46276) (xy 343.140617 8.424538)
			(xy 343.060658 8.393562) (xy 342.978182 8.370095) (xy 342.893892 8.354339) (xy 342.808509 8.346427)
			(xy 342.722759 8.346427) (xy 342.637376 8.354339) (xy 342.553086 8.370095) (xy 342.47061 8.393562)
			(xy 342.390651 8.424538) (xy 342.313891 8.46276) (xy 342.240985 8.507901) (xy 342.172556 8.559577)
			(xy 342.109186 8.617346) (xy 342.051417 8.680716) (xy 341.999741 8.749145) (xy 341.9546 8.822051)
			(xy 341.916378 8.898811) (xy 341.885402 8.97877) (xy 341.861935 9.061246) (xy 341.846179 9.145536)
			(xy 341.838267 9.230919) (xy 337.343001 9.230919) (xy 337.335089 9.145536) (xy 337.319333 9.061246)
			(xy 337.295866 8.97877) (xy 337.26489 8.898811) (xy 337.226668 8.822051) (xy 337.181527 8.749145)
			(xy 337.129851 8.680716) (xy 337.072082 8.617346) (xy 337.008712 8.559577) (xy 336.940283 8.507901)
			(xy 336.867377 8.46276) (xy 336.790617 8.424538) (xy 336.710658 8.393562) (xy 336.628182 8.370095)
			(xy 336.543892 8.354339) (xy 336.458509 8.346427) (xy 336.372759 8.346427) (xy 336.287376 8.354339)
			(xy 336.203086 8.370095) (xy 336.12061 8.393562) (xy 336.040651 8.424538) (xy 335.963891 8.46276)
			(xy 335.890985 8.507901) (xy 335.822556 8.559577) (xy 335.759186 8.617346) (xy 335.701417 8.680716)
			(xy 335.649741 8.749145) (xy 335.6046 8.822051) (xy 335.566378 8.898811) (xy 335.535402 8.97877)
			(xy 335.511935 9.061246) (xy 335.496179 9.145536) (xy 335.488267 9.230919) (xy 333.050655 9.230919)
			(xy 333.042743 9.145536) (xy 333.026987 9.061246) (xy 333.00352 8.97877) (xy 332.972544 8.898811)
			(xy 332.934322 8.822051) (xy 332.889181 8.749145) (xy 332.837505 8.680716) (xy 332.779736 8.617346)
			(xy 332.716366 8.559577) (xy 332.647937 8.507901) (xy 332.575031 8.46276) (xy 332.498271 8.424538)
			(xy 332.418312 8.393562) (xy 332.335836 8.370095) (xy 332.251546 8.354339) (xy 332.166163 8.346427)
			(xy 332.080413 8.346427) (xy 331.99503 8.354339) (xy 331.91074 8.370095) (xy 331.828264 8.393562)
			(xy 331.748305 8.424538) (xy 331.671545 8.46276) (xy 331.598639 8.507901) (xy 331.53021 8.559577)
			(xy 331.46684 8.617346) (xy 331.409071 8.680716) (xy 331.357395 8.749145) (xy 331.312254 8.822051)
			(xy 331.274032 8.898811) (xy 331.243056 8.97877) (xy 331.219589 9.061246) (xy 331.203833 9.145536)
			(xy 331.195921 9.230919) (xy 326.700655 9.230919) (xy 326.692743 9.145536) (xy 326.676987 9.061246)
			(xy 326.65352 8.97877) (xy 326.622544 8.898811) (xy 326.584322 8.822051) (xy 326.539181 8.749145)
			(xy 326.487505 8.680716) (xy 326.429736 8.617346) (xy 326.366366 8.559577) (xy 326.297937 8.507901)
			(xy 326.225031 8.46276) (xy 326.148271 8.424538) (xy 326.068312 8.393562) (xy 325.985836 8.370095)
			(xy 325.901546 8.354339) (xy 325.816163 8.346427) (xy 325.730413 8.346427) (xy 325.64503 8.354339)
			(xy 325.56074 8.370095) (xy 325.478264 8.393562) (xy 325.398305 8.424538) (xy 325.321545 8.46276)
			(xy 325.248639 8.507901) (xy 325.18021 8.559577) (xy 325.11684 8.617346) (xy 325.059071 8.680716)
			(xy 325.007395 8.749145) (xy 324.962254 8.822051) (xy 324.924032 8.898811) (xy 324.893056 8.97877)
			(xy 324.869589 9.061246) (xy 324.853833 9.145536) (xy 324.845921 9.230919) (xy 265.125975 9.230919)
			(xy 265.118063 9.145536) (xy 265.102307 9.061246) (xy 265.07884 8.97877) (xy 265.047864 8.898811)
			(xy 265.009642 8.822051) (xy 264.964501 8.749145) (xy 264.912825 8.680716) (xy 264.855056 8.617346)
			(xy 264.791686 8.559577) (xy 264.723257 8.507901) (xy 264.650351 8.46276) (xy 264.573591 8.424538)
			(xy 264.493632 8.393562) (xy 264.411156 8.370095) (xy 264.326866 8.354339) (xy 264.241483 8.346427)
			(xy 264.155733 8.346427) (xy 264.07035 8.354339) (xy 263.98606 8.370095) (xy 263.903584 8.393562)
			(xy 263.823625 8.424538) (xy 263.746865 8.46276) (xy 263.673959 8.507901) (xy 263.60553 8.559577)
			(xy 263.54216 8.617346) (xy 263.484391 8.680716) (xy 263.432715 8.749145) (xy 263.387574 8.822051)
			(xy 263.349352 8.898811) (xy 263.318376 8.97877) (xy 263.294909 9.061246) (xy 263.279153 9.145536)
			(xy 263.271241 9.230919) (xy 258.775975 9.230919) (xy 258.768063 9.145536) (xy 258.752307 9.061246)
			(xy 258.72884 8.97877) (xy 258.697864 8.898811) (xy 258.659642 8.822051) (xy 258.614501 8.749145)
			(xy 258.562825 8.680716) (xy 258.505056 8.617346) (xy 258.441686 8.559577) (xy 258.373257 8.507901)
			(xy 258.300351 8.46276) (xy 258.223591 8.424538) (xy 258.143632 8.393562) (xy 258.061156 8.370095)
			(xy 257.976866 8.354339) (xy 257.891483 8.346427) (xy 257.805733 8.346427) (xy 257.72035 8.354339)
			(xy 257.63606 8.370095) (xy 257.553584 8.393562) (xy 257.473625 8.424538) (xy 257.396865 8.46276)
			(xy 257.323959 8.507901) (xy 257.25553 8.559577) (xy 257.19216 8.617346) (xy 257.134391 8.680716)
			(xy 257.082715 8.749145) (xy 257.037574 8.822051) (xy 256.999352 8.898811) (xy 256.968376 8.97877)
			(xy 256.944909 9.061246) (xy 256.929153 9.145536) (xy 256.921241 9.230919) (xy 6.020338 9.230919)
			(xy 6.103792 9.182737) (xy 6.211443 9.111405) (xy 6.314498 9.033581) (xy 6.412568 8.94956) (xy 6.505279 8.859661)
			(xy 6.592279 8.764226) (xy 6.67324 8.663616) (xy 6.747854 8.558213) (xy 6.815837 8.448416) (xy 6.876932 8.334642)
			(xy 6.930907 8.217323) (xy 6.977558 8.096904) (xy 7.016707 7.973841) (xy 7.048206 7.848602) (xy 7.071935 7.721661)
			(xy 7.087805 7.593501) (xy 7.095755 7.464606) (xy 7.096252 7.400036) (xy 7.095755 7.335466) (xy 7.087805 7.206571)
			(xy 7.071935 7.078411) (xy 7.048206 6.95147) (xy 7.016707 6.826231) (xy 6.977558 6.703168) (xy 6.97173 6.688125)
			(xy 178.335673 6.688125) (xy 178.335673 6.773875) (xy 178.343585 6.859258) (xy 178.359341 6.943548)
			(xy 178.382808 7.026024) (xy 178.413784 7.105983) (xy 178.452006 7.182743) (xy 178.497147 7.255649)
			(xy 178.548823 7.324078) (xy 178.606592 7.387448) (xy 178.669962 7.445217) (xy 178.738391 7.496893)
			(xy 178.811297 7.542034) (xy 178.888057 7.580256) (xy 178.968016 7.611232) (xy 179.050492 7.634699)
			(xy 179.134782 7.650455) (xy 179.220165 7.658367) (xy 179.305915 7.658367) (xy 179.391298 7.650455)
			(xy 179.475588 7.634699) (xy 179.558064 7.611232) (xy 179.638023 7.580256) (xy 179.714783 7.542034)
			(xy 179.787689 7.496893) (xy 179.856118 7.445217) (xy 179.919488 7.387448) (xy 179.977257 7.324078)
			(xy 180.028933 7.255649) (xy 180.074074 7.182743) (xy 180.112296 7.105983) (xy 180.143272 7.026024)
			(xy 180.166739 6.943548) (xy 180.182495 6.859258) (xy 180.190407 6.773875) (xy 180.190902 6.731)
			(xy 180.190407 6.688125) (xy 184.685673 6.688125) (xy 184.685673 6.773875) (xy 184.693585 6.859258)
			(xy 184.709341 6.943548) (xy 184.732808 7.026024) (xy 184.763784 7.105983) (xy 184.802006 7.182743)
			(xy 184.847147 7.255649) (xy 184.898823 7.324078) (xy 184.956592 7.387448) (xy 185.019962 7.445217)
			(xy 185.088391 7.496893) (xy 185.161297 7.542034) (xy 185.238057 7.580256) (xy 185.318016 7.611232)
			(xy 185.400492 7.634699) (xy 185.484782 7.650455) (xy 185.570165 7.658367) (xy 185.655915 7.658367)
			(xy 185.741298 7.650455) (xy 185.825588 7.634699) (xy 185.908064 7.611232) (xy 185.988023 7.580256)
			(xy 186.064783 7.542034) (xy 186.137689 7.496893) (xy 186.206118 7.445217) (xy 186.269488 7.387448)
			(xy 186.327257 7.324078) (xy 186.378933 7.255649) (xy 186.424074 7.182743) (xy 186.462296 7.105983)
			(xy 186.493272 7.026024) (xy 186.516739 6.943548) (xy 186.532495 6.859258) (xy 186.540407 6.773875)
			(xy 186.540902 6.731) (xy 186.540407 6.688125) (xy 246.260353 6.688125) (xy 246.260353 6.773875)
			(xy 246.268265 6.859258) (xy 246.284021 6.943548) (xy 246.307488 7.026024) (xy 246.338464 7.105983)
			(xy 246.376686 7.182743) (xy 246.421827 7.255649) (xy 246.473503 7.324078) (xy 246.531272 7.387448)
			(xy 246.594642 7.445217) (xy 246.663071 7.496893) (xy 246.735977 7.542034) (xy 246.812737 7.580256)
			(xy 246.892696 7.611232) (xy 246.975172 7.634699) (xy 247.059462 7.650455) (xy 247.144845 7.658367)
			(xy 247.230595 7.658367) (xy 247.315978 7.650455) (xy 247.400268 7.634699) (xy 247.482744 7.611232)
			(xy 247.562703 7.580256) (xy 247.639463 7.542034) (xy 247.712369 7.496893) (xy 247.780798 7.445217)
			(xy 247.844168 7.387448) (xy 247.901937 7.324078) (xy 247.953613 7.255649) (xy 247.998754 7.182743)
			(xy 248.036976 7.105983) (xy 248.067952 7.026024) (xy 248.091419 6.943548) (xy 248.107175 6.859258)
			(xy 248.115087 6.773875) (xy 248.115582 6.731) (xy 248.115087 6.688125) (xy 252.610353 6.688125)
			(xy 252.610353 6.773875) (xy 252.618265 6.859258) (xy 252.634021 6.943548) (xy 252.657488 7.026024)
			(xy 252.688464 7.105983) (xy 252.726686 7.182743) (xy 252.771827 7.255649) (xy 252.823503 7.324078)
			(xy 252.881272 7.387448) (xy 252.944642 7.445217) (xy 253.013071 7.496893) (xy 253.085977 7.542034)
			(xy 253.162737 7.580256) (xy 253.242696 7.611232) (xy 253.325172 7.634699) (xy 253.409462 7.650455)
			(xy 253.494845 7.658367) (xy 253.580595 7.658367) (xy 253.665978 7.650455) (xy 253.750268 7.634699)
			(xy 253.832744 7.611232) (xy 253.912703 7.580256) (xy 253.989463 7.542034) (xy 254.062369 7.496893)
			(xy 254.130798 7.445217) (xy 254.194168 7.387448) (xy 254.251937 7.324078) (xy 254.303613 7.255649)
			(xy 254.348754 7.182743) (xy 254.386976 7.105983) (xy 254.417952 7.026024) (xy 254.441419 6.943548)
			(xy 254.457175 6.859258) (xy 254.465087 6.773875) (xy 254.465582 6.731) (xy 254.465119 6.690919)
			(xy 256.921241 6.690919) (xy 256.921241 6.776669) (xy 256.929153 6.862052) (xy 256.944909 6.946342)
			(xy 256.968376 7.028818) (xy 256.999352 7.108777) (xy 257.037574 7.185537) (xy 257.082715 7.258443)
			(xy 257.134391 7.326872) (xy 257.19216 7.390242) (xy 257.25553 7.448011) (xy 257.323959 7.499687)
			(xy 257.396865 7.544828) (xy 257.473625 7.58305) (xy 257.553584 7.614026) (xy 257.63606 7.637493)
			(xy 257.72035 7.653249) (xy 257.805733 7.661161) (xy 257.891483 7.661161) (xy 257.976866 7.653249)
			(xy 258.061156 7.637493) (xy 258.143632 7.614026) (xy 258.223591 7.58305) (xy 258.245794 7.571994)
			(xy 261.85622 7.571994) (xy 261.85622 8.435594) (xy 261.856706 8.462863) (xy 261.864468 8.516847)
			(xy 261.879833 8.569177) (xy 261.90249 8.618787) (xy 261.931976 8.664668) (xy 261.967691 8.705885)
			(xy 262.008908 8.7416) (xy 262.054789 8.771086) (xy 262.104399 8.793743) (xy 262.156729 8.809108)
			(xy 262.210713 8.81687) (xy 262.265251 8.81687) (xy 262.319235 8.809108) (xy 262.371565 8.793743)
			(xy 262.421175 8.771086) (xy 262.467056 8.7416) (xy 262.508273 8.705885) (xy 262.543988 8.664668)
			(xy 262.573474 8.618787) (xy 262.596131 8.569177) (xy 262.611496 8.516847) (xy 262.619258 8.462863)
			(xy 262.619744 8.435594) (xy 262.619744 7.571994) (xy 262.619258 7.544725) (xy 262.611496 7.490741)
			(xy 262.596131 7.438411) (xy 262.573474 7.388801) (xy 262.543988 7.34292) (xy 262.508273 7.301703)
			(xy 262.467056 7.265988) (xy 262.421175 7.236502) (xy 262.371565 7.213845) (xy 262.319235 7.19848)
			(xy 262.265251 7.190718) (xy 262.210713 7.190718) (xy 262.156729 7.19848) (xy 262.104399 7.213845)
			(xy 262.054789 7.236502) (xy 262.008908 7.265988) (xy 261.967691 7.301703) (xy 261.931976 7.34292)
			(xy 261.90249 7.388801) (xy 261.879833 7.438411) (xy 261.864468 7.490741) (xy 261.856706 7.544725)
			(xy 261.85622 7.571994) (xy 258.245794 7.571994) (xy 258.300351 7.544828) (xy 258.373257 7.499687)
			(xy 258.441686 7.448011) (xy 258.505056 7.390242) (xy 258.562825 7.326872) (xy 258.614501 7.258443)
			(xy 258.659642 7.185537) (xy 258.697864 7.108777) (xy 258.72884 7.028818) (xy 258.752307 6.946342)
			(xy 258.768063 6.862052) (xy 258.775975 6.776669) (xy 258.77647 6.733794) (xy 258.775975 6.690919)
			(xy 263.271241 6.690919) (xy 263.271241 6.776669) (xy 263.279153 6.862052) (xy 263.294909 6.946342)
			(xy 263.318376 7.028818) (xy 263.349352 7.108777) (xy 263.387574 7.185537) (xy 263.432715 7.258443)
			(xy 263.484391 7.326872) (xy 263.54216 7.390242) (xy 263.60553 7.448011) (xy 263.673959 7.499687)
			(xy 263.746865 7.544828) (xy 263.823625 7.58305) (xy 263.903584 7.614026) (xy 263.98606 7.637493)
			(xy 264.07035 7.653249) (xy 264.155733 7.661161) (xy 264.241483 7.661161) (xy 264.326866 7.653249)
			(xy 264.411156 7.637493) (xy 264.493632 7.614026) (xy 264.573591 7.58305) (xy 264.650351 7.544828)
			(xy 264.723257 7.499687) (xy 264.791686 7.448011) (xy 264.855056 7.390242) (xy 264.912825 7.326872)
			(xy 264.964501 7.258443) (xy 265.009642 7.185537) (xy 265.047864 7.108777) (xy 265.07884 7.028818)
			(xy 265.102307 6.946342) (xy 265.118063 6.862052) (xy 265.125975 6.776669) (xy 265.12647 6.733794)
			(xy 265.125975 6.690919) (xy 324.845921 6.690919) (xy 324.845921 6.776669) (xy 324.853833 6.862052)
			(xy 324.869589 6.946342) (xy 324.893056 7.028818) (xy 324.924032 7.108777) (xy 324.962254 7.185537)
			(xy 325.007395 7.258443) (xy 325.059071 7.326872) (xy 325.11684 7.390242) (xy 325.18021 7.448011)
			(xy 325.248639 7.499687) (xy 325.321545 7.544828) (xy 325.398305 7.58305) (xy 325.478264 7.614026)
			(xy 325.56074 7.637493) (xy 325.64503 7.653249) (xy 325.730413 7.661161) (xy 325.816163 7.661161)
			(xy 325.901546 7.653249) (xy 325.985836 7.637493) (xy 326.068312 7.614026) (xy 326.148271 7.58305)
			(xy 326.170474 7.571994) (xy 327.352152 7.571994) (xy 327.352152 8.435594) (xy 327.352638 8.462863)
			(xy 327.3604 8.516847) (xy 327.375765 8.569177) (xy 327.398422 8.618787) (xy 327.427908 8.664668)
			(xy 327.463623 8.705885) (xy 327.50484 8.7416) (xy 327.550721 8.771086) (xy 327.600331 8.793743)
			(xy 327.652661 8.809108) (xy 327.706645 8.81687) (xy 327.761183 8.81687) (xy 327.815167 8.809108)
			(xy 327.867497 8.793743) (xy 327.917107 8.771086) (xy 327.962988 8.7416) (xy 328.004205 8.705885)
			(xy 328.03992 8.664668) (xy 328.069406 8.618787) (xy 328.092063 8.569177) (xy 328.107428 8.516847)
			(xy 328.11519 8.462863) (xy 328.115676 8.435594) (xy 328.115676 7.571994) (xy 328.11519 7.544725)
			(xy 328.107428 7.490741) (xy 328.092063 7.438411) (xy 328.069406 7.388801) (xy 328.03992 7.34292)
			(xy 328.004205 7.301703) (xy 327.962988 7.265988) (xy 327.917107 7.236502) (xy 327.867497 7.213845)
			(xy 327.815167 7.19848) (xy 327.761183 7.190718) (xy 327.706645 7.190718) (xy 327.652661 7.19848)
			(xy 327.600331 7.213845) (xy 327.550721 7.236502) (xy 327.50484 7.265988) (xy 327.463623 7.301703)
			(xy 327.427908 7.34292) (xy 327.398422 7.388801) (xy 327.375765 7.438411) (xy 327.3604 7.490741)
			(xy 327.352638 7.544725) (xy 327.352152 7.571994) (xy 326.170474 7.571994) (xy 326.225031 7.544828)
			(xy 326.297937 7.499687) (xy 326.366366 7.448011) (xy 326.429736 7.390242) (xy 326.487505 7.326872)
			(xy 326.539181 7.258443) (xy 326.584322 7.185537) (xy 326.622544 7.108777) (xy 326.65352 7.028818)
			(xy 326.676987 6.946342) (xy 326.692743 6.862052) (xy 326.700655 6.776669) (xy 326.70115 6.733794)
			(xy 326.700655 6.690919) (xy 331.195921 6.690919) (xy 331.195921 6.776669) (xy 331.203833 6.862052)
			(xy 331.219589 6.946342) (xy 331.243056 7.028818) (xy 331.274032 7.108777) (xy 331.312254 7.185537)
			(xy 331.357395 7.258443) (xy 331.409071 7.326872) (xy 331.46684 7.390242) (xy 331.53021 7.448011)
			(xy 331.598639 7.499687) (xy 331.671545 7.544828) (xy 331.748305 7.58305) (xy 331.828264 7.614026)
			(xy 331.91074 7.637493) (xy 331.99503 7.653249) (xy 332.080413 7.661161) (xy 332.166163 7.661161)
			(xy 332.251546 7.653249) (xy 332.335836 7.637493) (xy 332.418312 7.614026) (xy 332.498271 7.58305)
			(xy 332.575031 7.544828) (xy 332.647937 7.499687) (xy 332.716366 7.448011) (xy 332.779736 7.390242)
			(xy 332.837505 7.326872) (xy 332.889181 7.258443) (xy 332.934322 7.185537) (xy 332.972544 7.108777)
			(xy 333.00352 7.028818) (xy 333.026987 6.946342) (xy 333.042743 6.862052) (xy 333.050655 6.776669)
			(xy 333.05115 6.733794) (xy 333.050655 6.690919) (xy 335.488267 6.690919) (xy 335.488267 6.776669)
			(xy 335.496179 6.862052) (xy 335.511935 6.946342) (xy 335.535402 7.028818) (xy 335.566378 7.108777)
			(xy 335.6046 7.185537) (xy 335.649741 7.258443) (xy 335.701417 7.326872) (xy 335.759186 7.390242)
			(xy 335.822556 7.448011) (xy 335.890985 7.499687) (xy 335.963891 7.544828) (xy 336.040651 7.58305)
			(xy 336.12061 7.614026) (xy 336.203086 7.637493) (xy 336.287376 7.653249) (xy 336.372759 7.661161)
			(xy 336.458509 7.661161) (xy 336.543892 7.653249) (xy 336.628182 7.637493) (xy 336.710658 7.614026)
			(xy 336.790617 7.58305) (xy 336.81282 7.571994) (xy 340.4235 7.571994) (xy 340.4235 8.435594) (xy 340.423986 8.462845)
			(xy 340.431742 8.516793) (xy 340.447097 8.569088) (xy 340.469739 8.618665) (xy 340.499205 8.664515)
			(xy 340.534896 8.705706) (xy 340.576087 8.741397) (xy 340.621937 8.770863) (xy 340.671514 8.793505)
			(xy 340.723809 8.80886) (xy 340.777757 8.816616) (xy 340.832259 8.816616) (xy 340.886207 8.80886)
			(xy 340.938502 8.793505) (xy 340.988079 8.770863) (xy 341.033929 8.741397) (xy 341.07512 8.705706)
			(xy 341.110811 8.664515) (xy 341.140277 8.618665) (xy 341.162919 8.569088) (xy 341.178274 8.516793)
			(xy 341.18603 8.462845) (xy 341.186516 8.435594) (xy 341.186516 7.571994) (xy 341.18603 7.544743)
			(xy 341.178274 7.490795) (xy 341.162919 7.4385) (xy 341.140277 7.388923) (xy 341.110811 7.343073)
			(xy 341.07512 7.301882) (xy 341.033929 7.266191) (xy 340.988079 7.236725) (xy 340.938502 7.214083)
			(xy 340.886207 7.198728) (xy 340.832259 7.190972) (xy 340.777757 7.190972) (xy 340.723809 7.198728)
			(xy 340.671514 7.214083) (xy 340.621937 7.236725) (xy 340.576087 7.266191) (xy 340.534896 7.301882)
			(xy 340.499205 7.343073) (xy 340.469739 7.388923) (xy 340.447097 7.4385) (xy 340.431742 7.490795)
			(xy 340.423986 7.544743) (xy 340.4235 7.571994) (xy 336.81282 7.571994) (xy 336.867377 7.544828)
			(xy 336.940283 7.499687) (xy 337.008712 7.448011) (xy 337.072082 7.390242) (xy 337.129851 7.326872)
			(xy 337.181527 7.258443) (xy 337.226668 7.185537) (xy 337.26489 7.108777) (xy 337.295866 7.028818)
			(xy 337.319333 6.946342) (xy 337.335089 6.862052) (xy 337.343001 6.776669) (xy 337.343496 6.733794)
			(xy 337.343001 6.690919) (xy 341.838267 6.690919) (xy 341.838267 6.776669) (xy 341.846179 6.862052)
			(xy 341.861935 6.946342) (xy 341.885402 7.028818) (xy 341.916378 7.108777) (xy 341.9546 7.185537)
			(xy 341.999741 7.258443) (xy 342.051417 7.326872) (xy 342.109186 7.390242) (xy 342.172556 7.448011)
			(xy 342.240985 7.499687) (xy 342.313891 7.544828) (xy 342.390651 7.58305) (xy 342.47061 7.614026)
			(xy 342.553086 7.637493) (xy 342.637376 7.653249) (xy 342.722759 7.661161) (xy 342.808509 7.661161)
			(xy 342.893892 7.653249) (xy 342.978182 7.637493) (xy 343.060658 7.614026) (xy 343.140617 7.58305)
			(xy 343.217377 7.544828) (xy 343.290283 7.499687) (xy 343.358712 7.448011) (xy 343.422082 7.390242)
			(xy 343.479851 7.326872) (xy 343.531527 7.258443) (xy 343.576668 7.185537) (xy 343.61489 7.108777)
			(xy 343.645866 7.028818) (xy 343.669333 6.946342) (xy 343.685089 6.862052) (xy 343.693001 6.776669)
			(xy 343.693496 6.733794) (xy 343.693001 6.690919) (xy 373.705107 6.690919) (xy 373.705107 6.776669)
			(xy 373.713019 6.862052) (xy 373.728775 6.946342) (xy 373.752242 7.028818) (xy 373.783218 7.108777)
			(xy 373.82144 7.185537) (xy 373.866581 7.258443) (xy 373.918257 7.326872) (xy 373.976026 7.390242)
			(xy 374.039396 7.448011) (xy 374.107825 7.499687) (xy 374.180731 7.544828) (xy 374.257491 7.58305)
			(xy 374.33745 7.614026) (xy 374.419926 7.637493) (xy 374.504216 7.653249) (xy 374.589599 7.661161)
			(xy 374.675349 7.661161) (xy 374.760732 7.653249) (xy 374.845022 7.637493) (xy 374.927498 7.614026)
			(xy 375.007457 7.58305) (xy 375.02966 7.571994) (xy 376.211592 7.571994) (xy 376.211592 8.435594)
			(xy 376.212078 8.462845) (xy 376.219834 8.516793) (xy 376.235189 8.569088) (xy 376.257831 8.618665)
			(xy 376.287297 8.664515) (xy 376.322988 8.705706) (xy 376.364179 8.741397) (xy 376.410029 8.770863)
			(xy 376.459606 8.793505) (xy 376.511901 8.80886) (xy 376.565849 8.816616) (xy 376.620351 8.816616)
			(xy 376.674299 8.80886) (xy 376.726594 8.793505) (xy 376.776171 8.770863) (xy 376.822021 8.741397)
			(xy 376.863212 8.705706) (xy 376.898903 8.664515) (xy 376.928369 8.618665) (xy 376.951011 8.569088)
			(xy 376.966366 8.516793) (xy 376.974122 8.462845) (xy 376.974608 8.435594) (xy 376.974608 7.571994)
			(xy 376.974122 7.544743) (xy 376.966366 7.490795) (xy 376.951011 7.4385) (xy 376.928369 7.388923)
			(xy 376.898903 7.343073) (xy 376.863212 7.301882) (xy 376.822021 7.266191) (xy 376.776171 7.236725)
			(xy 376.726594 7.214083) (xy 376.674299 7.198728) (xy 376.620351 7.190972) (xy 376.565849 7.190972)
			(xy 376.511901 7.198728) (xy 376.459606 7.214083) (xy 376.410029 7.236725) (xy 376.364179 7.266191)
			(xy 376.322988 7.301882) (xy 376.287297 7.343073) (xy 376.257831 7.388923) (xy 376.235189 7.4385)
			(xy 376.219834 7.490795) (xy 376.212078 7.544743) (xy 376.211592 7.571994) (xy 375.02966 7.571994)
			(xy 375.084217 7.544828) (xy 375.157123 7.499687) (xy 375.225552 7.448011) (xy 375.288922 7.390242)
			(xy 375.346691 7.326872) (xy 375.398367 7.258443) (xy 375.443508 7.185537) (xy 375.48173 7.108777)
			(xy 375.512706 7.028818) (xy 375.536173 6.946342) (xy 375.551929 6.862052) (xy 375.559841 6.776669)
			(xy 375.560336 6.733794) (xy 375.559841 6.690919) (xy 380.055107 6.690919) (xy 380.055107 6.776669)
			(xy 380.063019 6.862052) (xy 380.078775 6.946342) (xy 380.102242 7.028818) (xy 380.133218 7.108777)
			(xy 380.17144 7.185537) (xy 380.216581 7.258443) (xy 380.268257 7.326872) (xy 380.326026 7.390242)
			(xy 380.389396 7.448011) (xy 380.457825 7.499687) (xy 380.530731 7.544828) (xy 380.607491 7.58305)
			(xy 380.68745 7.614026) (xy 380.769926 7.637493) (xy 380.854216 7.653249) (xy 380.939599 7.661161)
			(xy 381.025349 7.661161) (xy 381.110732 7.653249) (xy 381.195022 7.637493) (xy 381.277498 7.614026)
			(xy 381.357457 7.58305) (xy 381.434217 7.544828) (xy 381.507123 7.499687) (xy 381.575552 7.448011)
			(xy 381.638922 7.390242) (xy 381.688857 7.335466) (xy 464.704165 7.335466) (xy 464.704165 7.464606)
			(xy 464.712115 7.593501) (xy 464.727985 7.721661) (xy 464.751714 7.848602) (xy 464.783213 7.973841)
			(xy 464.822362 8.096904) (xy 464.869013 8.217323) (xy 464.922988 8.334642) (xy 464.984083 8.448416)
			(xy 465.052066 8.558213) (xy 465.12668 8.663616) (xy 465.207641 8.764226) (xy 465.294641 8.859661)
			(xy 465.387352 8.94956) (xy 465.485422 9.033581) (xy 465.588477 9.111405) (xy 465.696128 9.182737)
			(xy 465.807967 9.247307) (xy 465.923568 9.304869) (xy 466.042493 9.355206) (xy 466.164292 9.398126)
			(xy 466.288502 9.433467) (xy 466.414651 9.461094) (xy 466.542263 9.480903) (xy 466.670852 9.492819)
			(xy 466.79993 9.496796) (xy 466.929008 9.492819) (xy 467.057597 9.480903) (xy 467.185209 9.461094)
			(xy 467.311358 9.433467) (xy 467.435568 9.398126) (xy 467.557367 9.355206) (xy 467.676292 9.304869)
			(xy 467.791893 9.247307) (xy 467.903732 9.182737) (xy 468.011383 9.111405) (xy 468.114438 9.033581)
			(xy 468.212508 8.94956) (xy 468.305219 8.859661) (xy 468.392219 8.764226) (xy 468.47318 8.663616)
			(xy 468.547794 8.558213) (xy 468.615777 8.448416) (xy 468.676872 8.334642) (xy 468.730847 8.217323)
			(xy 468.777498 8.096904) (xy 468.816647 7.973841) (xy 468.848146 7.848602) (xy 468.871875 7.721661)
			(xy 468.887745 7.593501) (xy 468.895695 7.464606) (xy 468.896192 7.400036) (xy 468.895695 7.335466)
			(xy 468.887745 7.206571) (xy 468.871875 7.078411) (xy 468.848146 6.95147) (xy 468.816647 6.826231)
			(xy 468.777498 6.703168) (xy 468.730847 6.582749) (xy 468.676872 6.46543) (xy 468.615777 6.351656)
			(xy 468.547794 6.241859) (xy 468.47318 6.136456) (xy 468.392219 6.035846) (xy 468.305219 5.940411)
			(xy 468.212508 5.850512) (xy 468.114438 5.766491) (xy 468.011383 5.688667) (xy 467.903732 5.617335)
			(xy 467.791893 5.552765) (xy 467.676292 5.495203) (xy 467.557367 5.444866) (xy 467.435568 5.401946)
			(xy 467.311358 5.366605) (xy 467.185209 5.338978) (xy 467.057597 5.319169) (xy 466.929008 5.307253)
			(xy 466.79993 5.303277) (xy 466.670852 5.307253) (xy 466.542263 5.319169) (xy 466.414651 5.338978)
			(xy 466.288502 5.366605) (xy 466.164292 5.401946) (xy 466.042493 5.444866) (xy 465.923568 5.495203)
			(xy 465.807967 5.552765) (xy 465.696128 5.617335) (xy 465.588477 5.688667) (xy 465.485422 5.766491)
			(xy 465.387352 5.850512) (xy 465.294641 5.940411) (xy 465.207641 6.035846) (xy 465.12668 6.136456)
			(xy 465.052066 6.241859) (xy 464.984083 6.351656) (xy 464.922988 6.46543) (xy 464.869013 6.582749)
			(xy 464.822362 6.703168) (xy 464.783213 6.826231) (xy 464.751714 6.95147) (xy 464.727985 7.078411)
			(xy 464.712115 7.206571) (xy 464.704165 7.335466) (xy 381.688857 7.335466) (xy 381.696691 7.326872)
			(xy 381.748367 7.258443) (xy 381.793508 7.185537) (xy 381.83173 7.108777) (xy 381.862706 7.028818)
			(xy 381.886173 6.946342) (xy 381.901929 6.862052) (xy 381.909841 6.776669) (xy 381.910336 6.733794)
			(xy 381.909841 6.690919) (xy 381.901929 6.605536) (xy 381.886173 6.521246) (xy 381.862706 6.43877)
			(xy 381.83173 6.358811) (xy 381.793508 6.282051) (xy 381.748367 6.209145) (xy 381.696691 6.140716)
			(xy 381.638922 6.077346) (xy 381.575552 6.019577) (xy 381.507123 5.967901) (xy 381.434217 5.92276)
			(xy 381.357457 5.884538) (xy 381.277498 5.853562) (xy 381.195022 5.830095) (xy 381.110732 5.814339)
			(xy 381.025349 5.806427) (xy 380.939599 5.806427) (xy 380.854216 5.814339) (xy 380.769926 5.830095)
			(xy 380.68745 5.853562) (xy 380.607491 5.884538) (xy 380.530731 5.92276) (xy 380.457825 5.967901)
			(xy 380.389396 6.019577) (xy 380.326026 6.077346) (xy 380.268257 6.140716) (xy 380.216581 6.209145)
			(xy 380.17144 6.282051) (xy 380.133218 6.358811) (xy 380.102242 6.43877) (xy 380.078775 6.521246)
			(xy 380.063019 6.605536) (xy 380.055107 6.690919) (xy 375.559841 6.690919) (xy 375.551929 6.605536)
			(xy 375.536173 6.521246) (xy 375.512706 6.43877) (xy 375.48173 6.358811) (xy 375.443508 6.282051)
			(xy 375.398367 6.209145) (xy 375.346691 6.140716) (xy 375.288922 6.077346) (xy 375.225552 6.019577)
			(xy 375.157123 5.967901) (xy 375.084217 5.92276) (xy 375.007457 5.884538) (xy 374.927498 5.853562)
			(xy 374.845022 5.830095) (xy 374.760732 5.814339) (xy 374.675349 5.806427) (xy 374.589599 5.806427)
			(xy 374.504216 5.814339) (xy 374.419926 5.830095) (xy 374.33745 5.853562) (xy 374.257491 5.884538)
			(xy 374.180731 5.92276) (xy 374.107825 5.967901) (xy 374.039396 6.019577) (xy 373.976026 6.077346)
			(xy 373.918257 6.140716) (xy 373.866581 6.209145) (xy 373.82144 6.282051) (xy 373.783218 6.358811)
			(xy 373.752242 6.43877) (xy 373.728775 6.521246) (xy 373.713019 6.605536) (xy 373.705107 6.690919)
			(xy 343.693001 6.690919) (xy 343.685089 6.605536) (xy 343.669333 6.521246) (xy 343.645866 6.43877)
			(xy 343.61489 6.358811) (xy 343.576668 6.282051) (xy 343.531527 6.209145) (xy 343.479851 6.140716)
			(xy 343.422082 6.077346) (xy 343.358712 6.019577) (xy 343.290283 5.967901) (xy 343.217377 5.92276)
			(xy 343.140617 5.884538) (xy 343.060658 5.853562) (xy 342.978182 5.830095) (xy 342.893892 5.814339)
			(xy 342.808509 5.806427) (xy 342.722759 5.806427) (xy 342.637376 5.814339) (xy 342.553086 5.830095)
			(xy 342.47061 5.853562) (xy 342.390651 5.884538) (xy 342.313891 5.92276) (xy 342.240985 5.967901)
			(xy 342.172556 6.019577) (xy 342.109186 6.077346) (xy 342.051417 6.140716) (xy 341.999741 6.209145)
			(xy 341.9546 6.282051) (xy 341.916378 6.358811) (xy 341.885402 6.43877) (xy 341.861935 6.521246)
			(xy 341.846179 6.605536) (xy 341.838267 6.690919) (xy 337.343001 6.690919) (xy 337.335089 6.605536)
			(xy 337.319333 6.521246) (xy 337.295866 6.43877) (xy 337.26489 6.358811) (xy 337.226668 6.282051)
			(xy 337.181527 6.209145) (xy 337.129851 6.140716) (xy 337.072082 6.077346) (xy 337.008712 6.019577)
			(xy 336.940283 5.967901) (xy 336.867377 5.92276) (xy 336.790617 5.884538) (xy 336.710658 5.853562)
			(xy 336.628182 5.830095) (xy 336.543892 5.814339) (xy 336.458509 5.806427) (xy 336.372759 5.806427)
			(xy 336.287376 5.814339) (xy 336.203086 5.830095) (xy 336.12061 5.853562) (xy 336.040651 5.884538)
			(xy 335.963891 5.92276) (xy 335.890985 5.967901) (xy 335.822556 6.019577) (xy 335.759186 6.077346)
			(xy 335.701417 6.140716) (xy 335.649741 6.209145) (xy 335.6046 6.282051) (xy 335.566378 6.358811)
			(xy 335.535402 6.43877) (xy 335.511935 6.521246) (xy 335.496179 6.605536) (xy 335.488267 6.690919)
			(xy 333.050655 6.690919) (xy 333.042743 6.605536) (xy 333.026987 6.521246) (xy 333.00352 6.43877)
			(xy 332.972544 6.358811) (xy 332.934322 6.282051) (xy 332.889181 6.209145) (xy 332.837505 6.140716)
			(xy 332.779736 6.077346) (xy 332.716366 6.019577) (xy 332.647937 5.967901) (xy 332.575031 5.92276)
			(xy 332.498271 5.884538) (xy 332.418312 5.853562) (xy 332.335836 5.830095) (xy 332.251546 5.814339)
			(xy 332.166163 5.806427) (xy 332.080413 5.806427) (xy 331.99503 5.814339) (xy 331.91074 5.830095)
			(xy 331.828264 5.853562) (xy 331.748305 5.884538) (xy 331.671545 5.92276) (xy 331.598639 5.967901)
			(xy 331.53021 6.019577) (xy 331.46684 6.077346) (xy 331.409071 6.140716) (xy 331.357395 6.209145)
			(xy 331.312254 6.282051) (xy 331.274032 6.358811) (xy 331.243056 6.43877) (xy 331.219589 6.521246)
			(xy 331.203833 6.605536) (xy 331.195921 6.690919) (xy 326.700655 6.690919) (xy 326.692743 6.605536)
			(xy 326.676987 6.521246) (xy 326.65352 6.43877) (xy 326.622544 6.358811) (xy 326.584322 6.282051)
			(xy 326.539181 6.209145) (xy 326.487505 6.140716) (xy 326.429736 6.077346) (xy 326.366366 6.019577)
			(xy 326.297937 5.967901) (xy 326.225031 5.92276) (xy 326.148271 5.884538) (xy 326.068312 5.853562)
			(xy 325.985836 5.830095) (xy 325.901546 5.814339) (xy 325.816163 5.806427) (xy 325.730413 5.806427)
			(xy 325.64503 5.814339) (xy 325.56074 5.830095) (xy 325.478264 5.853562) (xy 325.398305 5.884538)
			(xy 325.321545 5.92276) (xy 325.248639 5.967901) (xy 325.18021 6.019577) (xy 325.11684 6.077346)
			(xy 325.059071 6.140716) (xy 325.007395 6.209145) (xy 324.962254 6.282051) (xy 324.924032 6.358811)
			(xy 324.893056 6.43877) (xy 324.869589 6.521246) (xy 324.853833 6.605536) (xy 324.845921 6.690919)
			(xy 265.125975 6.690919) (xy 265.118063 6.605536) (xy 265.102307 6.521246) (xy 265.07884 6.43877)
			(xy 265.047864 6.358811) (xy 265.009642 6.282051) (xy 264.964501 6.209145) (xy 264.912825 6.140716)
			(xy 264.855056 6.077346) (xy 264.791686 6.019577) (xy 264.723257 5.967901) (xy 264.650351 5.92276)
			(xy 264.573591 5.884538) (xy 264.493632 5.853562) (xy 264.411156 5.830095) (xy 264.326866 5.814339)
			(xy 264.241483 5.806427) (xy 264.155733 5.806427) (xy 264.07035 5.814339) (xy 263.98606 5.830095)
			(xy 263.903584 5.853562) (xy 263.823625 5.884538) (xy 263.746865 5.92276) (xy 263.673959 5.967901)
			(xy 263.60553 6.019577) (xy 263.54216 6.077346) (xy 263.484391 6.140716) (xy 263.432715 6.209145)
			(xy 263.387574 6.282051) (xy 263.349352 6.358811) (xy 263.318376 6.43877) (xy 263.294909 6.521246)
			(xy 263.279153 6.605536) (xy 263.271241 6.690919) (xy 258.775975 6.690919) (xy 258.768063 6.605536)
			(xy 258.752307 6.521246) (xy 258.72884 6.43877) (xy 258.697864 6.358811) (xy 258.659642 6.282051)
			(xy 258.614501 6.209145) (xy 258.562825 6.140716) (xy 258.505056 6.077346) (xy 258.441686 6.019577)
			(xy 258.373257 5.967901) (xy 258.300351 5.92276) (xy 258.223591 5.884538) (xy 258.143632 5.853562)
			(xy 258.061156 5.830095) (xy 257.976866 5.814339) (xy 257.891483 5.806427) (xy 257.805733 5.806427)
			(xy 257.72035 5.814339) (xy 257.63606 5.830095) (xy 257.553584 5.853562) (xy 257.473625 5.884538)
			(xy 257.396865 5.92276) (xy 257.323959 5.967901) (xy 257.25553 6.019577) (xy 257.19216 6.077346)
			(xy 257.134391 6.140716) (xy 257.082715 6.209145) (xy 257.037574 6.282051) (xy 256.999352 6.358811)
			(xy 256.968376 6.43877) (xy 256.944909 6.521246) (xy 256.929153 6.605536) (xy 256.921241 6.690919)
			(xy 254.465119 6.690919) (xy 254.465087 6.688125) (xy 254.457175 6.602742) (xy 254.441419 6.518452)
			(xy 254.417952 6.435976) (xy 254.386976 6.356017) (xy 254.348754 6.279257) (xy 254.303613 6.206351)
			(xy 254.251937 6.137922) (xy 254.194168 6.074552) (xy 254.130798 6.016783) (xy 254.062369 5.965107)
			(xy 253.989463 5.919966) (xy 253.912703 5.881744) (xy 253.832744 5.850768) (xy 253.750268 5.827301)
			(xy 253.665978 5.811545) (xy 253.580595 5.803633) (xy 253.494845 5.803633) (xy 253.409462 5.811545)
			(xy 253.325172 5.827301) (xy 253.242696 5.850768) (xy 253.162737 5.881744) (xy 253.085977 5.919966)
			(xy 253.013071 5.965107) (xy 252.944642 6.016783) (xy 252.881272 6.074552) (xy 252.823503 6.137922)
			(xy 252.771827 6.206351) (xy 252.726686 6.279257) (xy 252.688464 6.356017) (xy 252.657488 6.435976)
			(xy 252.634021 6.518452) (xy 252.618265 6.602742) (xy 252.610353 6.688125) (xy 248.115087 6.688125)
			(xy 248.107175 6.602742) (xy 248.091419 6.518452) (xy 248.067952 6.435976) (xy 248.036976 6.356017)
			(xy 247.998754 6.279257) (xy 247.953613 6.206351) (xy 247.901937 6.137922) (xy 247.844168 6.074552)
			(xy 247.780798 6.016783) (xy 247.712369 5.965107) (xy 247.639463 5.919966) (xy 247.562703 5.881744)
			(xy 247.482744 5.850768) (xy 247.400268 5.827301) (xy 247.315978 5.811545) (xy 247.230595 5.803633)
			(xy 247.144845 5.803633) (xy 247.059462 5.811545) (xy 246.975172 5.827301) (xy 246.892696 5.850768)
			(xy 246.812737 5.881744) (xy 246.735977 5.919966) (xy 246.663071 5.965107) (xy 246.594642 6.016783)
			(xy 246.531272 6.074552) (xy 246.473503 6.137922) (xy 246.421827 6.206351) (xy 246.376686 6.279257)
			(xy 246.338464 6.356017) (xy 246.307488 6.435976) (xy 246.284021 6.518452) (xy 246.268265 6.602742)
			(xy 246.260353 6.688125) (xy 186.540407 6.688125) (xy 186.532495 6.602742) (xy 186.516739 6.518452)
			(xy 186.493272 6.435976) (xy 186.462296 6.356017) (xy 186.424074 6.279257) (xy 186.378933 6.206351)
			(xy 186.327257 6.137922) (xy 186.269488 6.074552) (xy 186.206118 6.016783) (xy 186.137689 5.965107)
			(xy 186.064783 5.919966) (xy 185.988023 5.881744) (xy 185.908064 5.850768) (xy 185.825588 5.827301)
			(xy 185.741298 5.811545) (xy 185.655915 5.803633) (xy 185.570165 5.803633) (xy 185.484782 5.811545)
			(xy 185.400492 5.827301) (xy 185.318016 5.850768) (xy 185.238057 5.881744) (xy 185.161297 5.919966)
			(xy 185.088391 5.965107) (xy 185.019962 6.016783) (xy 184.956592 6.074552) (xy 184.898823 6.137922)
			(xy 184.847147 6.206351) (xy 184.802006 6.279257) (xy 184.763784 6.356017) (xy 184.732808 6.435976)
			(xy 184.709341 6.518452) (xy 184.693585 6.602742) (xy 184.685673 6.688125) (xy 180.190407 6.688125)
			(xy 180.182495 6.602742) (xy 180.166739 6.518452) (xy 180.143272 6.435976) (xy 180.112296 6.356017)
			(xy 180.074074 6.279257) (xy 180.028933 6.206351) (xy 179.977257 6.137922) (xy 179.919488 6.074552)
			(xy 179.856118 6.016783) (xy 179.787689 5.965107) (xy 179.714783 5.919966) (xy 179.638023 5.881744)
			(xy 179.558064 5.850768) (xy 179.475588 5.827301) (xy 179.391298 5.811545) (xy 179.305915 5.803633)
			(xy 179.220165 5.803633) (xy 179.134782 5.811545) (xy 179.050492 5.827301) (xy 178.968016 5.850768)
			(xy 178.888057 5.881744) (xy 178.811297 5.919966) (xy 178.738391 5.965107) (xy 178.669962 6.016783)
			(xy 178.606592 6.074552) (xy 178.548823 6.137922) (xy 178.497147 6.206351) (xy 178.452006 6.279257)
			(xy 178.413784 6.356017) (xy 178.382808 6.435976) (xy 178.359341 6.518452) (xy 178.343585 6.602742)
			(xy 178.335673 6.688125) (xy 6.97173 6.688125) (xy 6.930907 6.582749) (xy 6.876932 6.46543) (xy 6.815837 6.351656)
			(xy 6.747854 6.241859) (xy 6.67324 6.136456) (xy 6.592279 6.035846) (xy 6.505279 5.940411) (xy 6.412568 5.850512)
			(xy 6.314498 5.766491) (xy 6.211443 5.688667) (xy 6.103792 5.617335) (xy 5.991953 5.552765) (xy 5.876352 5.495203)
			(xy 5.757427 5.444866) (xy 5.635628 5.401946) (xy 5.511418 5.366605) (xy 5.385269 5.338978) (xy 5.257657 5.319169)
			(xy 5.129068 5.307253) (xy 4.99999 5.303277) (xy 4.870912 5.307253) (xy 4.742323 5.319169) (xy 4.614711 5.338978)
			(xy 4.488562 5.366605) (xy 4.364352 5.401946) (xy 4.242553 5.444866) (xy 4.123628 5.495203) (xy 4.008027 5.552765)
			(xy 3.896188 5.617335) (xy 3.788537 5.688667) (xy 3.685482 5.766491) (xy 3.587412 5.850512) (xy 3.494701 5.940411)
			(xy 3.407701 6.035846) (xy 3.32674 6.136456) (xy 3.252126 6.241859) (xy 3.184143 6.351656) (xy 3.123048 6.46543)
			(xy 3.069073 6.582749) (xy 3.022422 6.703168) (xy 2.983273 6.826231) (xy 2.951774 6.95147) (xy 2.928045 7.078411)
			(xy 2.912175 7.206571) (xy 2.904225 7.335466) (xy 0.508 7.335466) (xy 0.508 4.148125) (xy 178.335673 4.148125)
			(xy 178.335673 4.233875) (xy 178.343585 4.319258) (xy 178.359341 4.403548) (xy 178.382808 4.486024)
			(xy 178.413784 4.565983) (xy 178.452006 4.642743) (xy 178.497147 4.715649) (xy 178.548823 4.784078)
			(xy 178.606592 4.847448) (xy 178.669962 4.905217) (xy 178.738391 4.956893) (xy 178.811297 5.002034)
			(xy 178.888057 5.040256) (xy 178.968016 5.071232) (xy 179.050492 5.094699) (xy 179.134782 5.110455)
			(xy 179.220165 5.118367) (xy 179.305915 5.118367) (xy 179.391298 5.110455) (xy 179.475588 5.094699)
			(xy 179.558064 5.071232) (xy 179.638023 5.040256) (xy 179.660226 5.0292) (xy 183.270652 5.0292) (xy 183.270652 5.8928)
			(xy 183.271138 5.920069) (xy 183.2789 5.974053) (xy 183.294265 6.026383) (xy 183.316922 6.075993)
			(xy 183.346408 6.121874) (xy 183.382123 6.163091) (xy 183.42334 6.198806) (xy 183.469221 6.228292)
			(xy 183.518831 6.250949) (xy 183.571161 6.266314) (xy 183.625145 6.274076) (xy 183.679683 6.274076)
			(xy 183.733667 6.266314) (xy 183.785997 6.250949) (xy 183.835607 6.228292) (xy 183.881488 6.198806)
			(xy 183.922705 6.163091) (xy 183.95842 6.121874) (xy 183.987906 6.075993) (xy 184.010563 6.026383)
			(xy 184.025928 5.974053) (xy 184.03369 5.920069) (xy 184.034176 5.8928) (xy 184.034176 5.0292) (xy 184.03369 5.001931)
			(xy 184.025928 4.947947) (xy 184.010563 4.895617) (xy 183.987906 4.846007) (xy 183.95842 4.800126)
			(xy 183.922705 4.758909) (xy 183.881488 4.723194) (xy 183.835607 4.693708) (xy 183.785997 4.671051)
			(xy 183.733667 4.655686) (xy 183.679683 4.647924) (xy 183.625145 4.647924) (xy 183.571161 4.655686)
			(xy 183.518831 4.671051) (xy 183.469221 4.693708) (xy 183.42334 4.723194) (xy 183.382123 4.758909)
			(xy 183.346408 4.800126) (xy 183.316922 4.846007) (xy 183.294265 4.895617) (xy 183.2789 4.947947)
			(xy 183.271138 5.001931) (xy 183.270652 5.0292) (xy 179.660226 5.0292) (xy 179.714783 5.002034) (xy 179.787689 4.956893)
			(xy 179.856118 4.905217) (xy 179.919488 4.847448) (xy 179.977257 4.784078) (xy 180.028933 4.715649)
			(xy 180.074074 4.642743) (xy 180.112296 4.565983) (xy 180.143272 4.486024) (xy 180.166739 4.403548)
			(xy 180.182495 4.319258) (xy 180.190407 4.233875) (xy 180.190902 4.191) (xy 180.190407 4.148125)
			(xy 184.685673 4.148125) (xy 184.685673 4.233875) (xy 184.693585 4.319258) (xy 184.709341 4.403548)
			(xy 184.732808 4.486024) (xy 184.763784 4.565983) (xy 184.802006 4.642743) (xy 184.847147 4.715649)
			(xy 184.898823 4.784078) (xy 184.956592 4.847448) (xy 185.019962 4.905217) (xy 185.088391 4.956893)
			(xy 185.161297 5.002034) (xy 185.238057 5.040256) (xy 185.318016 5.071232) (xy 185.400492 5.094699)
			(xy 185.484782 5.110455) (xy 185.570165 5.118367) (xy 185.655915 5.118367) (xy 185.741298 5.110455)
			(xy 185.825588 5.094699) (xy 185.908064 5.071232) (xy 185.988023 5.040256) (xy 186.064783 5.002034)
			(xy 186.137689 4.956893) (xy 186.206118 4.905217) (xy 186.269488 4.847448) (xy 186.327257 4.784078)
			(xy 186.378933 4.715649) (xy 186.424074 4.642743) (xy 186.462296 4.565983) (xy 186.493272 4.486024)
			(xy 186.516739 4.403548) (xy 186.532495 4.319258) (xy 186.540407 4.233875) (xy 186.540902 4.191)
			(xy 186.540407 4.148125) (xy 246.260353 4.148125) (xy 246.260353 4.233875) (xy 246.268265 4.319258)
			(xy 246.284021 4.403548) (xy 246.307488 4.486024) (xy 246.338464 4.565983) (xy 246.376686 4.642743)
			(xy 246.421827 4.715649) (xy 246.473503 4.784078) (xy 246.531272 4.847448) (xy 246.594642 4.905217)
			(xy 246.663071 4.956893) (xy 246.735977 5.002034) (xy 246.812737 5.040256) (xy 246.892696 5.071232)
			(xy 246.975172 5.094699) (xy 247.059462 5.110455) (xy 247.144845 5.118367) (xy 247.230595 5.118367)
			(xy 247.315978 5.110455) (xy 247.400268 5.094699) (xy 247.482744 5.071232) (xy 247.562703 5.040256)
			(xy 247.584906 5.0292) (xy 248.766584 5.0292) (xy 248.766584 5.8928) (xy 248.76707 5.920069) (xy 248.774832 5.974053)
			(xy 248.790197 6.026383) (xy 248.812854 6.075993) (xy 248.84234 6.121874) (xy 248.878055 6.163091)
			(xy 248.919272 6.198806) (xy 248.965153 6.228292) (xy 249.014763 6.250949) (xy 249.067093 6.266314)
			(xy 249.121077 6.274076) (xy 249.175615 6.274076) (xy 249.229599 6.266314) (xy 249.281929 6.250949)
			(xy 249.331539 6.228292) (xy 249.37742 6.198806) (xy 249.418637 6.163091) (xy 249.454352 6.121874)
			(xy 249.483838 6.075993) (xy 249.506495 6.026383) (xy 249.52186 5.974053) (xy 249.529622 5.920069)
			(xy 249.530108 5.8928) (xy 249.530108 5.0292) (xy 249.529622 5.001931) (xy 249.52186 4.947947) (xy 249.506495 4.895617)
			(xy 249.483838 4.846007) (xy 249.454352 4.800126) (xy 249.418637 4.758909) (xy 249.37742 4.723194)
			(xy 249.331539 4.693708) (xy 249.281929 4.671051) (xy 249.229599 4.655686) (xy 249.175615 4.647924)
			(xy 249.121077 4.647924) (xy 249.067093 4.655686) (xy 249.014763 4.671051) (xy 248.965153 4.693708)
			(xy 248.919272 4.723194) (xy 248.878055 4.758909) (xy 248.84234 4.800126) (xy 248.812854 4.846007)
			(xy 248.790197 4.895617) (xy 248.774832 4.947947) (xy 248.76707 5.001931) (xy 248.766584 5.0292)
			(xy 247.584906 5.0292) (xy 247.639463 5.002034) (xy 247.712369 4.956893) (xy 247.780798 4.905217)
			(xy 247.844168 4.847448) (xy 247.901937 4.784078) (xy 247.953613 4.715649) (xy 247.998754 4.642743)
			(xy 248.036976 4.565983) (xy 248.067952 4.486024) (xy 248.091419 4.403548) (xy 248.107175 4.319258)
			(xy 248.115087 4.233875) (xy 248.115582 4.191) (xy 248.115087 4.148125) (xy 252.610353 4.148125)
			(xy 252.610353 4.233875) (xy 252.618265 4.319258) (xy 252.634021 4.403548) (xy 252.657488 4.486024)
			(xy 252.688464 4.565983) (xy 252.726686 4.642743) (xy 252.771827 4.715649) (xy 252.823503 4.784078)
			(xy 252.881272 4.847448) (xy 252.944642 4.905217) (xy 253.013071 4.956893) (xy 253.085977 5.002034)
			(xy 253.162737 5.040256) (xy 253.242696 5.071232) (xy 253.325172 5.094699) (xy 253.409462 5.110455)
			(xy 253.494845 5.118367) (xy 253.580595 5.118367) (xy 253.665978 5.110455) (xy 253.750268 5.094699)
			(xy 253.832744 5.071232) (xy 253.912703 5.040256) (xy 253.989463 5.002034) (xy 254.062369 4.956893)
			(xy 254.130798 4.905217) (xy 254.194168 4.847448) (xy 254.251937 4.784078) (xy 254.303613 4.715649)
			(xy 254.348754 4.642743) (xy 254.386976 4.565983) (xy 254.417952 4.486024) (xy 254.441419 4.403548)
			(xy 254.457175 4.319258) (xy 254.465087 4.233875) (xy 254.465582 4.191) (xy 254.465119 4.150919)
			(xy 256.921241 4.150919) (xy 256.921241 4.236669) (xy 256.929153 4.322052) (xy 256.944909 4.406342)
			(xy 256.968376 4.488818) (xy 256.999352 4.568777) (xy 257.037574 4.645537) (xy 257.082715 4.718443)
			(xy 257.134391 4.786872) (xy 257.19216 4.850242) (xy 257.25553 4.908011) (xy 257.323959 4.959687)
			(xy 257.396865 5.004828) (xy 257.473625 5.04305) (xy 257.553584 5.074026) (xy 257.63606 5.097493)
			(xy 257.72035 5.113249) (xy 257.805733 5.121161) (xy 257.891483 5.121161) (xy 257.976866 5.113249)
			(xy 258.061156 5.097493) (xy 258.143632 5.074026) (xy 258.223591 5.04305) (xy 258.245794 5.031994)
			(xy 261.85622 5.031994) (xy 261.85622 5.895594) (xy 261.856706 5.922863) (xy 261.864468 5.976847)
			(xy 261.879833 6.029177) (xy 261.90249 6.078787) (xy 261.931976 6.124668) (xy 261.967691 6.165885)
			(xy 262.008908 6.2016) (xy 262.054789 6.231086) (xy 262.104399 6.253743) (xy 262.156729 6.269108)
			(xy 262.210713 6.27687) (xy 262.265251 6.27687) (xy 262.319235 6.269108) (xy 262.371565 6.253743)
			(xy 262.421175 6.231086) (xy 262.467056 6.2016) (xy 262.508273 6.165885) (xy 262.543988 6.124668)
			(xy 262.573474 6.078787) (xy 262.596131 6.029177) (xy 262.611496 5.976847) (xy 262.619258 5.922863)
			(xy 262.619744 5.895594) (xy 262.619744 5.031994) (xy 262.619258 5.004725) (xy 262.611496 4.950741)
			(xy 262.596131 4.898411) (xy 262.573474 4.848801) (xy 262.543988 4.80292) (xy 262.508273 4.761703)
			(xy 262.467056 4.725988) (xy 262.421175 4.696502) (xy 262.371565 4.673845) (xy 262.319235 4.65848)
			(xy 262.265251 4.650718) (xy 262.210713 4.650718) (xy 262.156729 4.65848) (xy 262.104399 4.673845)
			(xy 262.054789 4.696502) (xy 262.008908 4.725988) (xy 261.967691 4.761703) (xy 261.931976 4.80292)
			(xy 261.90249 4.848801) (xy 261.879833 4.898411) (xy 261.864468 4.950741) (xy 261.856706 5.004725)
			(xy 261.85622 5.031994) (xy 258.245794 5.031994) (xy 258.300351 5.004828) (xy 258.373257 4.959687)
			(xy 258.441686 4.908011) (xy 258.505056 4.850242) (xy 258.562825 4.786872) (xy 258.614501 4.718443)
			(xy 258.659642 4.645537) (xy 258.697864 4.568777) (xy 258.72884 4.488818) (xy 258.752307 4.406342)
			(xy 258.768063 4.322052) (xy 258.775975 4.236669) (xy 258.77647 4.193794) (xy 258.775975 4.150919)
			(xy 263.271241 4.150919) (xy 263.271241 4.236669) (xy 263.279153 4.322052) (xy 263.294909 4.406342)
			(xy 263.318376 4.488818) (xy 263.349352 4.568777) (xy 263.387574 4.645537) (xy 263.432715 4.718443)
			(xy 263.484391 4.786872) (xy 263.54216 4.850242) (xy 263.60553 4.908011) (xy 263.673959 4.959687)
			(xy 263.746865 5.004828) (xy 263.823625 5.04305) (xy 263.903584 5.074026) (xy 263.98606 5.097493)
			(xy 264.07035 5.113249) (xy 264.155733 5.121161) (xy 264.241483 5.121161) (xy 264.326866 5.113249)
			(xy 264.411156 5.097493) (xy 264.493632 5.074026) (xy 264.573591 5.04305) (xy 264.650351 5.004828)
			(xy 264.723257 4.959687) (xy 264.791686 4.908011) (xy 264.855056 4.850242) (xy 264.912825 4.786872)
			(xy 264.964501 4.718443) (xy 265.009642 4.645537) (xy 265.047864 4.568777) (xy 265.07884 4.488818)
			(xy 265.102307 4.406342) (xy 265.118063 4.322052) (xy 265.125975 4.236669) (xy 265.12647 4.193794)
			(xy 265.125975 4.150919) (xy 324.845921 4.150919) (xy 324.845921 4.236669) (xy 324.853833 4.322052)
			(xy 324.869589 4.406342) (xy 324.893056 4.488818) (xy 324.924032 4.568777) (xy 324.962254 4.645537)
			(xy 325.007395 4.718443) (xy 325.059071 4.786872) (xy 325.11684 4.850242) (xy 325.18021 4.908011)
			(xy 325.248639 4.959687) (xy 325.321545 5.004828) (xy 325.398305 5.04305) (xy 325.478264 5.074026)
			(xy 325.56074 5.097493) (xy 325.64503 5.113249) (xy 325.730413 5.121161) (xy 325.816163 5.121161)
			(xy 325.901546 5.113249) (xy 325.985836 5.097493) (xy 326.068312 5.074026) (xy 326.148271 5.04305)
			(xy 326.170474 5.031994) (xy 327.352152 5.031994) (xy 327.352152 5.895594) (xy 327.352638 5.922863)
			(xy 327.3604 5.976847) (xy 327.375765 6.029177) (xy 327.398422 6.078787) (xy 327.427908 6.124668)
			(xy 327.463623 6.165885) (xy 327.50484 6.2016) (xy 327.550721 6.231086) (xy 327.600331 6.253743)
			(xy 327.652661 6.269108) (xy 327.706645 6.27687) (xy 327.761183 6.27687) (xy 327.815167 6.269108)
			(xy 327.867497 6.253743) (xy 327.917107 6.231086) (xy 327.962988 6.2016) (xy 328.004205 6.165885)
			(xy 328.03992 6.124668) (xy 328.069406 6.078787) (xy 328.092063 6.029177) (xy 328.107428 5.976847)
			(xy 328.11519 5.922863) (xy 328.115676 5.895594) (xy 328.115676 5.031994) (xy 328.11519 5.004725)
			(xy 328.107428 4.950741) (xy 328.092063 4.898411) (xy 328.069406 4.848801) (xy 328.03992 4.80292)
			(xy 328.004205 4.761703) (xy 327.962988 4.725988) (xy 327.917107 4.696502) (xy 327.867497 4.673845)
			(xy 327.815167 4.65848) (xy 327.761183 4.650718) (xy 327.706645 4.650718) (xy 327.652661 4.65848)
			(xy 327.600331 4.673845) (xy 327.550721 4.696502) (xy 327.50484 4.725988) (xy 327.463623 4.761703)
			(xy 327.427908 4.80292) (xy 327.398422 4.848801) (xy 327.375765 4.898411) (xy 327.3604 4.950741)
			(xy 327.352638 5.004725) (xy 327.352152 5.031994) (xy 326.170474 5.031994) (xy 326.225031 5.004828)
			(xy 326.297937 4.959687) (xy 326.366366 4.908011) (xy 326.429736 4.850242) (xy 326.487505 4.786872)
			(xy 326.539181 4.718443) (xy 326.584322 4.645537) (xy 326.622544 4.568777) (xy 326.65352 4.488818)
			(xy 326.676987 4.406342) (xy 326.692743 4.322052) (xy 326.700655 4.236669) (xy 326.70115 4.193794)
			(xy 326.700655 4.150919) (xy 331.195921 4.150919) (xy 331.195921 4.236669) (xy 331.203833 4.322052)
			(xy 331.219589 4.406342) (xy 331.243056 4.488818) (xy 331.274032 4.568777) (xy 331.312254 4.645537)
			(xy 331.357395 4.718443) (xy 331.409071 4.786872) (xy 331.46684 4.850242) (xy 331.53021 4.908011)
			(xy 331.598639 4.959687) (xy 331.671545 5.004828) (xy 331.748305 5.04305) (xy 331.828264 5.074026)
			(xy 331.91074 5.097493) (xy 331.99503 5.113249) (xy 332.080413 5.121161) (xy 332.166163 5.121161)
			(xy 332.251546 5.113249) (xy 332.335836 5.097493) (xy 332.418312 5.074026) (xy 332.498271 5.04305)
			(xy 332.575031 5.004828) (xy 332.647937 4.959687) (xy 332.716366 4.908011) (xy 332.779736 4.850242)
			(xy 332.837505 4.786872) (xy 332.889181 4.718443) (xy 332.934322 4.645537) (xy 332.972544 4.568777)
			(xy 333.00352 4.488818) (xy 333.026987 4.406342) (xy 333.042743 4.322052) (xy 333.050655 4.236669)
			(xy 333.05115 4.193794) (xy 333.050655 4.150919) (xy 335.488267 4.150919) (xy 335.488267 4.236669)
			(xy 335.496179 4.322052) (xy 335.511935 4.406342) (xy 335.535402 4.488818) (xy 335.566378 4.568777)
			(xy 335.6046 4.645537) (xy 335.649741 4.718443) (xy 335.701417 4.786872) (xy 335.759186 4.850242)
			(xy 335.822556 4.908011) (xy 335.890985 4.959687) (xy 335.963891 5.004828) (xy 336.040651 5.04305)
			(xy 336.12061 5.074026) (xy 336.203086 5.097493) (xy 336.287376 5.113249) (xy 336.372759 5.121161)
			(xy 336.458509 5.121161) (xy 336.543892 5.113249) (xy 336.628182 5.097493) (xy 336.710658 5.074026)
			(xy 336.790617 5.04305) (xy 336.81282 5.031994) (xy 340.4235 5.031994) (xy 340.4235 5.895594) (xy 340.423986 5.922845)
			(xy 340.431742 5.976793) (xy 340.447097 6.029088) (xy 340.469739 6.078665) (xy 340.499205 6.124515)
			(xy 340.534896 6.165706) (xy 340.576087 6.201397) (xy 340.621937 6.230863) (xy 340.671514 6.253505)
			(xy 340.723809 6.26886) (xy 340.777757 6.276616) (xy 340.832259 6.276616) (xy 340.886207 6.26886)
			(xy 340.938502 6.253505) (xy 340.988079 6.230863) (xy 341.033929 6.201397) (xy 341.07512 6.165706)
			(xy 341.110811 6.124515) (xy 341.140277 6.078665) (xy 341.162919 6.029088) (xy 341.178274 5.976793)
			(xy 341.18603 5.922845) (xy 341.186516 5.895594) (xy 341.186516 5.031994) (xy 341.18603 5.004743)
			(xy 341.178274 4.950795) (xy 341.162919 4.8985) (xy 341.140277 4.848923) (xy 341.110811 4.803073)
			(xy 341.07512 4.761882) (xy 341.033929 4.726191) (xy 340.988079 4.696725) (xy 340.938502 4.674083)
			(xy 340.886207 4.658728) (xy 340.832259 4.650972) (xy 340.777757 4.650972) (xy 340.723809 4.658728)
			(xy 340.671514 4.674083) (xy 340.621937 4.696725) (xy 340.576087 4.726191) (xy 340.534896 4.761882)
			(xy 340.499205 4.803073) (xy 340.469739 4.848923) (xy 340.447097 4.8985) (xy 340.431742 4.950795)
			(xy 340.423986 5.004743) (xy 340.4235 5.031994) (xy 336.81282 5.031994) (xy 336.867377 5.004828)
			(xy 336.940283 4.959687) (xy 337.008712 4.908011) (xy 337.072082 4.850242) (xy 337.129851 4.786872)
			(xy 337.181527 4.718443) (xy 337.226668 4.645537) (xy 337.26489 4.568777) (xy 337.295866 4.488818)
			(xy 337.319333 4.406342) (xy 337.335089 4.322052) (xy 337.343001 4.236669) (xy 337.343496 4.193794)
			(xy 337.343001 4.150919) (xy 341.838267 4.150919) (xy 341.838267 4.236669) (xy 341.846179 4.322052)
			(xy 341.861935 4.406342) (xy 341.885402 4.488818) (xy 341.916378 4.568777) (xy 341.9546 4.645537)
			(xy 341.999741 4.718443) (xy 342.051417 4.786872) (xy 342.109186 4.850242) (xy 342.172556 4.908011)
			(xy 342.240985 4.959687) (xy 342.313891 5.004828) (xy 342.390651 5.04305) (xy 342.47061 5.074026)
			(xy 342.553086 5.097493) (xy 342.637376 5.113249) (xy 342.722759 5.121161) (xy 342.808509 5.121161)
			(xy 342.893892 5.113249) (xy 342.978182 5.097493) (xy 343.060658 5.074026) (xy 343.140617 5.04305)
			(xy 343.217377 5.004828) (xy 343.290283 4.959687) (xy 343.358712 4.908011) (xy 343.422082 4.850242)
			(xy 343.479851 4.786872) (xy 343.531527 4.718443) (xy 343.576668 4.645537) (xy 343.61489 4.568777)
			(xy 343.645866 4.488818) (xy 343.669333 4.406342) (xy 343.685089 4.322052) (xy 343.693001 4.236669)
			(xy 343.693496 4.193794) (xy 343.693001 4.150919) (xy 373.705107 4.150919) (xy 373.705107 4.236669)
			(xy 373.713019 4.322052) (xy 373.728775 4.406342) (xy 373.752242 4.488818) (xy 373.783218 4.568777)
			(xy 373.82144 4.645537) (xy 373.866581 4.718443) (xy 373.918257 4.786872) (xy 373.976026 4.850242)
			(xy 374.039396 4.908011) (xy 374.107825 4.959687) (xy 374.180731 5.004828) (xy 374.257491 5.04305)
			(xy 374.33745 5.074026) (xy 374.419926 5.097493) (xy 374.504216 5.113249) (xy 374.589599 5.121161)
			(xy 374.675349 5.121161) (xy 374.760732 5.113249) (xy 374.845022 5.097493) (xy 374.927498 5.074026)
			(xy 375.007457 5.04305) (xy 375.02966 5.031994) (xy 376.211592 5.031994) (xy 376.211592 5.895594)
			(xy 376.212078 5.922845) (xy 376.219834 5.976793) (xy 376.235189 6.029088) (xy 376.257831 6.078665)
			(xy 376.287297 6.124515) (xy 376.322988 6.165706) (xy 376.364179 6.201397) (xy 376.410029 6.230863)
			(xy 376.459606 6.253505) (xy 376.511901 6.26886) (xy 376.565849 6.276616) (xy 376.620351 6.276616)
			(xy 376.674299 6.26886) (xy 376.726594 6.253505) (xy 376.776171 6.230863) (xy 376.822021 6.201397)
			(xy 376.863212 6.165706) (xy 376.898903 6.124515) (xy 376.928369 6.078665) (xy 376.951011 6.029088)
			(xy 376.966366 5.976793) (xy 376.974122 5.922845) (xy 376.974608 5.895594) (xy 376.974608 5.031994)
			(xy 376.974122 5.004743) (xy 376.966366 4.950795) (xy 376.951011 4.8985) (xy 376.928369 4.848923)
			(xy 376.898903 4.803073) (xy 376.863212 4.761882) (xy 376.822021 4.726191) (xy 376.776171 4.696725)
			(xy 376.726594 4.674083) (xy 376.674299 4.658728) (xy 376.620351 4.650972) (xy 376.565849 4.650972)
			(xy 376.511901 4.658728) (xy 376.459606 4.674083) (xy 376.410029 4.696725) (xy 376.364179 4.726191)
			(xy 376.322988 4.761882) (xy 376.287297 4.803073) (xy 376.257831 4.848923) (xy 376.235189 4.8985)
			(xy 376.219834 4.950795) (xy 376.212078 5.004743) (xy 376.211592 5.031994) (xy 375.02966 5.031994)
			(xy 375.084217 5.004828) (xy 375.157123 4.959687) (xy 375.225552 4.908011) (xy 375.288922 4.850242)
			(xy 375.346691 4.786872) (xy 375.398367 4.718443) (xy 375.443508 4.645537) (xy 375.48173 4.568777)
			(xy 375.512706 4.488818) (xy 375.536173 4.406342) (xy 375.551929 4.322052) (xy 375.559841 4.236669)
			(xy 375.560336 4.193794) (xy 375.559841 4.150919) (xy 380.055107 4.150919) (xy 380.055107 4.236669)
			(xy 380.063019 4.322052) (xy 380.078775 4.406342) (xy 380.102242 4.488818) (xy 380.133218 4.568777)
			(xy 380.17144 4.645537) (xy 380.216581 4.718443) (xy 380.268257 4.786872) (xy 380.326026 4.850242)
			(xy 380.389396 4.908011) (xy 380.457825 4.959687) (xy 380.530731 5.004828) (xy 380.607491 5.04305)
			(xy 380.68745 5.074026) (xy 380.769926 5.097493) (xy 380.854216 5.113249) (xy 380.939599 5.121161)
			(xy 381.025349 5.121161) (xy 381.110732 5.113249) (xy 381.195022 5.097493) (xy 381.277498 5.074026)
			(xy 381.357457 5.04305) (xy 381.434217 5.004828) (xy 381.507123 4.959687) (xy 381.575552 4.908011)
			(xy 381.638922 4.850242) (xy 381.696691 4.786872) (xy 381.748367 4.718443) (xy 381.793508 4.645537)
			(xy 381.83173 4.568777) (xy 381.862706 4.488818) (xy 381.886173 4.406342) (xy 381.901929 4.322052)
			(xy 381.909841 4.236669) (xy 381.910336 4.193794) (xy 381.909841 4.150919) (xy 381.901929 4.065536)
			(xy 381.886173 3.981246) (xy 381.862706 3.89877) (xy 381.83173 3.818811) (xy 381.793508 3.742051)
			(xy 381.748367 3.669145) (xy 381.696691 3.600716) (xy 381.638922 3.537346) (xy 381.575552 3.479577)
			(xy 381.507123 3.427901) (xy 381.434217 3.38276) (xy 381.357457 3.344538) (xy 381.277498 3.313562)
			(xy 381.195022 3.290095) (xy 381.110732 3.274339) (xy 381.025349 3.266427) (xy 380.939599 3.266427)
			(xy 380.854216 3.274339) (xy 380.769926 3.290095) (xy 380.68745 3.313562) (xy 380.607491 3.344538)
			(xy 380.530731 3.38276) (xy 380.457825 3.427901) (xy 380.389396 3.479577) (xy 380.326026 3.537346)
			(xy 380.268257 3.600716) (xy 380.216581 3.669145) (xy 380.17144 3.742051) (xy 380.133218 3.818811)
			(xy 380.102242 3.89877) (xy 380.078775 3.981246) (xy 380.063019 4.065536) (xy 380.055107 4.150919)
			(xy 375.559841 4.150919) (xy 375.551929 4.065536) (xy 375.536173 3.981246) (xy 375.512706 3.89877)
			(xy 375.48173 3.818811) (xy 375.443508 3.742051) (xy 375.398367 3.669145) (xy 375.346691 3.600716)
			(xy 375.288922 3.537346) (xy 375.225552 3.479577) (xy 375.157123 3.427901) (xy 375.084217 3.38276)
			(xy 375.007457 3.344538) (xy 374.927498 3.313562) (xy 374.845022 3.290095) (xy 374.760732 3.274339)
			(xy 374.675349 3.266427) (xy 374.589599 3.266427) (xy 374.504216 3.274339) (xy 374.419926 3.290095)
			(xy 374.33745 3.313562) (xy 374.257491 3.344538) (xy 374.180731 3.38276) (xy 374.107825 3.427901)
			(xy 374.039396 3.479577) (xy 373.976026 3.537346) (xy 373.918257 3.600716) (xy 373.866581 3.669145)
			(xy 373.82144 3.742051) (xy 373.783218 3.818811) (xy 373.752242 3.89877) (xy 373.728775 3.981246)
			(xy 373.713019 4.065536) (xy 373.705107 4.150919) (xy 343.693001 4.150919) (xy 343.685089 4.065536)
			(xy 343.669333 3.981246) (xy 343.645866 3.89877) (xy 343.61489 3.818811) (xy 343.576668 3.742051)
			(xy 343.531527 3.669145) (xy 343.479851 3.600716) (xy 343.422082 3.537346) (xy 343.358712 3.479577)
			(xy 343.290283 3.427901) (xy 343.217377 3.38276) (xy 343.140617 3.344538) (xy 343.060658 3.313562)
			(xy 342.978182 3.290095) (xy 342.893892 3.274339) (xy 342.808509 3.266427) (xy 342.722759 3.266427)
			(xy 342.637376 3.274339) (xy 342.553086 3.290095) (xy 342.47061 3.313562) (xy 342.390651 3.344538)
			(xy 342.313891 3.38276) (xy 342.240985 3.427901) (xy 342.172556 3.479577) (xy 342.109186 3.537346)
			(xy 342.051417 3.600716) (xy 341.999741 3.669145) (xy 341.9546 3.742051) (xy 341.916378 3.818811)
			(xy 341.885402 3.89877) (xy 341.861935 3.981246) (xy 341.846179 4.065536) (xy 341.838267 4.150919)
			(xy 337.343001 4.150919) (xy 337.335089 4.065536) (xy 337.319333 3.981246) (xy 337.295866 3.89877)
			(xy 337.26489 3.818811) (xy 337.226668 3.742051) (xy 337.181527 3.669145) (xy 337.129851 3.600716)
			(xy 337.072082 3.537346) (xy 337.008712 3.479577) (xy 336.940283 3.427901) (xy 336.867377 3.38276)
			(xy 336.790617 3.344538) (xy 336.710658 3.313562) (xy 336.628182 3.290095) (xy 336.543892 3.274339)
			(xy 336.458509 3.266427) (xy 336.372759 3.266427) (xy 336.287376 3.274339) (xy 336.203086 3.290095)
			(xy 336.12061 3.313562) (xy 336.040651 3.344538) (xy 335.963891 3.38276) (xy 335.890985 3.427901)
			(xy 335.822556 3.479577) (xy 335.759186 3.537346) (xy 335.701417 3.600716) (xy 335.649741 3.669145)
			(xy 335.6046 3.742051) (xy 335.566378 3.818811) (xy 335.535402 3.89877) (xy 335.511935 3.981246)
			(xy 335.496179 4.065536) (xy 335.488267 4.150919) (xy 333.050655 4.150919) (xy 333.042743 4.065536)
			(xy 333.026987 3.981246) (xy 333.00352 3.89877) (xy 332.972544 3.818811) (xy 332.934322 3.742051)
			(xy 332.889181 3.669145) (xy 332.837505 3.600716) (xy 332.779736 3.537346) (xy 332.716366 3.479577)
			(xy 332.647937 3.427901) (xy 332.575031 3.38276) (xy 332.498271 3.344538) (xy 332.418312 3.313562)
			(xy 332.335836 3.290095) (xy 332.251546 3.274339) (xy 332.166163 3.266427) (xy 332.080413 3.266427)
			(xy 331.99503 3.274339) (xy 331.91074 3.290095) (xy 331.828264 3.313562) (xy 331.748305 3.344538)
			(xy 331.671545 3.38276) (xy 331.598639 3.427901) (xy 331.53021 3.479577) (xy 331.46684 3.537346)
			(xy 331.409071 3.600716) (xy 331.357395 3.669145) (xy 331.312254 3.742051) (xy 331.274032 3.818811)
			(xy 331.243056 3.89877) (xy 331.219589 3.981246) (xy 331.203833 4.065536) (xy 331.195921 4.150919)
			(xy 326.700655 4.150919) (xy 326.692743 4.065536) (xy 326.676987 3.981246) (xy 326.65352 3.89877)
			(xy 326.622544 3.818811) (xy 326.584322 3.742051) (xy 326.539181 3.669145) (xy 326.487505 3.600716)
			(xy 326.429736 3.537346) (xy 326.366366 3.479577) (xy 326.297937 3.427901) (xy 326.225031 3.38276)
			(xy 326.148271 3.344538) (xy 326.068312 3.313562) (xy 325.985836 3.290095) (xy 325.901546 3.274339)
			(xy 325.816163 3.266427) (xy 325.730413 3.266427) (xy 325.64503 3.274339) (xy 325.56074 3.290095)
			(xy 325.478264 3.313562) (xy 325.398305 3.344538) (xy 325.321545 3.38276) (xy 325.248639 3.427901)
			(xy 325.18021 3.479577) (xy 325.11684 3.537346) (xy 325.059071 3.600716) (xy 325.007395 3.669145)
			(xy 324.962254 3.742051) (xy 324.924032 3.818811) (xy 324.893056 3.89877) (xy 324.869589 3.981246)
			(xy 324.853833 4.065536) (xy 324.845921 4.150919) (xy 265.125975 4.150919) (xy 265.118063 4.065536)
			(xy 265.102307 3.981246) (xy 265.07884 3.89877) (xy 265.047864 3.818811) (xy 265.009642 3.742051)
			(xy 264.964501 3.669145) (xy 264.912825 3.600716) (xy 264.855056 3.537346) (xy 264.791686 3.479577)
			(xy 264.723257 3.427901) (xy 264.650351 3.38276) (xy 264.573591 3.344538) (xy 264.493632 3.313562)
			(xy 264.411156 3.290095) (xy 264.326866 3.274339) (xy 264.241483 3.266427) (xy 264.155733 3.266427)
			(xy 264.07035 3.274339) (xy 263.98606 3.290095) (xy 263.903584 3.313562) (xy 263.823625 3.344538)
			(xy 263.746865 3.38276) (xy 263.673959 3.427901) (xy 263.60553 3.479577) (xy 263.54216 3.537346)
			(xy 263.484391 3.600716) (xy 263.432715 3.669145) (xy 263.387574 3.742051) (xy 263.349352 3.818811)
			(xy 263.318376 3.89877) (xy 263.294909 3.981246) (xy 263.279153 4.065536) (xy 263.271241 4.150919)
			(xy 258.775975 4.150919) (xy 258.768063 4.065536) (xy 258.752307 3.981246) (xy 258.72884 3.89877)
			(xy 258.697864 3.818811) (xy 258.659642 3.742051) (xy 258.614501 3.669145) (xy 258.562825 3.600716)
			(xy 258.505056 3.537346) (xy 258.441686 3.479577) (xy 258.373257 3.427901) (xy 258.300351 3.38276)
			(xy 258.223591 3.344538) (xy 258.143632 3.313562) (xy 258.061156 3.290095) (xy 257.976866 3.274339)
			(xy 257.891483 3.266427) (xy 257.805733 3.266427) (xy 257.72035 3.274339) (xy 257.63606 3.290095)
			(xy 257.553584 3.313562) (xy 257.473625 3.344538) (xy 257.396865 3.38276) (xy 257.323959 3.427901)
			(xy 257.25553 3.479577) (xy 257.19216 3.537346) (xy 257.134391 3.600716) (xy 257.082715 3.669145)
			(xy 257.037574 3.742051) (xy 256.999352 3.818811) (xy 256.968376 3.89877) (xy 256.944909 3.981246)
			(xy 256.929153 4.065536) (xy 256.921241 4.150919) (xy 254.465119 4.150919) (xy 254.465087 4.148125)
			(xy 254.457175 4.062742) (xy 254.441419 3.978452) (xy 254.417952 3.895976) (xy 254.386976 3.816017)
			(xy 254.348754 3.739257) (xy 254.303613 3.666351) (xy 254.251937 3.597922) (xy 254.194168 3.534552)
			(xy 254.130798 3.476783) (xy 254.062369 3.425107) (xy 253.989463 3.379966) (xy 253.912703 3.341744)
			(xy 253.832744 3.310768) (xy 253.750268 3.287301) (xy 253.665978 3.271545) (xy 253.580595 3.263633)
			(xy 253.494845 3.263633) (xy 253.409462 3.271545) (xy 253.325172 3.287301) (xy 253.242696 3.310768)
			(xy 253.162737 3.341744) (xy 253.085977 3.379966) (xy 253.013071 3.425107) (xy 252.944642 3.476783)
			(xy 252.881272 3.534552) (xy 252.823503 3.597922) (xy 252.771827 3.666351) (xy 252.726686 3.739257)
			(xy 252.688464 3.816017) (xy 252.657488 3.895976) (xy 252.634021 3.978452) (xy 252.618265 4.062742)
			(xy 252.610353 4.148125) (xy 248.115087 4.148125) (xy 248.107175 4.062742) (xy 248.091419 3.978452)
			(xy 248.067952 3.895976) (xy 248.036976 3.816017) (xy 247.998754 3.739257) (xy 247.953613 3.666351)
			(xy 247.901937 3.597922) (xy 247.844168 3.534552) (xy 247.780798 3.476783) (xy 247.712369 3.425107)
			(xy 247.639463 3.379966) (xy 247.562703 3.341744) (xy 247.482744 3.310768) (xy 247.400268 3.287301)
			(xy 247.315978 3.271545) (xy 247.230595 3.263633) (xy 247.144845 3.263633) (xy 247.059462 3.271545)
			(xy 246.975172 3.287301) (xy 246.892696 3.310768) (xy 246.812737 3.341744) (xy 246.735977 3.379966)
			(xy 246.663071 3.425107) (xy 246.594642 3.476783) (xy 246.531272 3.534552) (xy 246.473503 3.597922)
			(xy 246.421827 3.666351) (xy 246.376686 3.739257) (xy 246.338464 3.816017) (xy 246.307488 3.895976)
			(xy 246.284021 3.978452) (xy 246.268265 4.062742) (xy 246.260353 4.148125) (xy 186.540407 4.148125)
			(xy 186.532495 4.062742) (xy 186.516739 3.978452) (xy 186.493272 3.895976) (xy 186.462296 3.816017)
			(xy 186.424074 3.739257) (xy 186.378933 3.666351) (xy 186.327257 3.597922) (xy 186.269488 3.534552)
			(xy 186.206118 3.476783) (xy 186.137689 3.425107) (xy 186.064783 3.379966) (xy 185.988023 3.341744)
			(xy 185.908064 3.310768) (xy 185.825588 3.287301) (xy 185.741298 3.271545) (xy 185.655915 3.263633)
			(xy 185.570165 3.263633) (xy 185.484782 3.271545) (xy 185.400492 3.287301) (xy 185.318016 3.310768)
			(xy 185.238057 3.341744) (xy 185.161297 3.379966) (xy 185.088391 3.425107) (xy 185.019962 3.476783)
			(xy 184.956592 3.534552) (xy 184.898823 3.597922) (xy 184.847147 3.666351) (xy 184.802006 3.739257)
			(xy 184.763784 3.816017) (xy 184.732808 3.895976) (xy 184.709341 3.978452) (xy 184.693585 4.062742)
			(xy 184.685673 4.148125) (xy 180.190407 4.148125) (xy 180.182495 4.062742) (xy 180.166739 3.978452)
			(xy 180.143272 3.895976) (xy 180.112296 3.816017) (xy 180.074074 3.739257) (xy 180.028933 3.666351)
			(xy 179.977257 3.597922) (xy 179.919488 3.534552) (xy 179.856118 3.476783) (xy 179.787689 3.425107)
			(xy 179.714783 3.379966) (xy 179.638023 3.341744) (xy 179.558064 3.310768) (xy 179.475588 3.287301)
			(xy 179.391298 3.271545) (xy 179.305915 3.263633) (xy 179.220165 3.263633) (xy 179.134782 3.271545)
			(xy 179.050492 3.287301) (xy 178.968016 3.310768) (xy 178.888057 3.341744) (xy 178.811297 3.379966)
			(xy 178.738391 3.425107) (xy 178.669962 3.476783) (xy 178.606592 3.534552) (xy 178.548823 3.597922)
			(xy 178.497147 3.666351) (xy 178.452006 3.739257) (xy 178.413784 3.816017) (xy 178.382808 3.895976)
			(xy 178.359341 3.978452) (xy 178.343585 4.062742) (xy 178.335673 4.148125) (xy 0.508 4.148125) (xy 0.508 -7.78002)
			(xy 0.508522 -7.835827) (xy 0.516863 -7.947129) (xy 0.533498 -8.057497) (xy 0.558334 -8.166312) (xy 0.591233 -8.272968)
			(xy 0.63201 -8.376867) (xy 0.680438 -8.477428) (xy 0.736245 -8.574088) (xy 0.799119 -8.666308) (xy 0.868709 -8.753572)
			(xy 0.944626 -8.835391) (xy 1.026445 -8.911308) (xy 1.113708 -8.980898) (xy 1.205928 -9.043773) (xy 1.302589 -9.09958)
			(xy 1.40315 -9.148008) (xy 1.507048 -9.188786) (xy 1.613704 -9.221685) (xy 1.722519 -9.246521) (xy 1.832887 -9.263157)
			(xy 1.944189 -9.271498) (xy 1.999996 -9.272016) (xy 9.10209 -9.272016) (xy 9.157898 -9.271495) (xy 9.269201 -9.263154)
			(xy 9.379569 -9.24652) (xy 9.488386 -9.221684) (xy 9.595043 -9.188786) (xy 9.698942 -9.148009) (xy 9.799505 -9.099582)
			(xy 9.896167 -9.043775) (xy 9.988388 -8.980901) (xy 10.075653 -8.911311) (xy 10.157473 -8.835394)
			(xy 10.233392 -8.753575) (xy 10.302983 -8.666312) (xy 10.365859 -8.574092) (xy 10.421668 -8.477431)
			(xy 10.470097 -8.37687) (xy 10.510876 -8.272971) (xy 10.543776 -8.166315) (xy 10.568614 -8.057499)
			(xy 10.585251 -7.94713) (xy 10.593594 -7.835828) (xy 10.594086 -7.78002) (xy 10.594086 0.999998)
			(xy 10.59457 1.070352) (xy 10.60246 1.210839) (xy 10.618214 1.350662) (xy 10.641783 1.489382) (xy 10.673094 1.626562)
			(xy 10.712047 1.761771) (xy 10.758519 1.894583) (xy 10.812366 2.02458) (xy 10.873417 2.151354) (xy 10.94148 2.274505)
			(xy 11.016341 2.393646) (xy 11.097765 2.508402) (xy 11.185495 2.618411) (xy 11.279255 2.723329) (xy 11.378751 2.822825)
			(xy 11.483669 2.916585) (xy 11.593678 3.004315) (xy 11.708434 3.085739) (xy 11.827575 3.1606) (xy 11.950726 3.228663)
			(xy 12.0775 3.289714) (xy 12.207497 3.343561) (xy 12.340309 3.390033) (xy 12.475518 3.428986) (xy 12.612698 3.460297)
			(xy 12.751418 3.483866) (xy 12.891241 3.49962) (xy 13.031728 3.50751) (xy 13.102082 3.507994) (xy 81.701894 3.507994)
			(xy 81.772248 3.50751) (xy 81.912735 3.499621) (xy 82.052558 3.483867) (xy 82.191278 3.460297) (xy 82.328459 3.428987)
			(xy 82.463668 3.390034) (xy 82.59648 3.343562) (xy 82.726477 3.289715) (xy 82.853251 3.228664) (xy 82.976402 3.160601)
			(xy 83.095543 3.08574) (xy 83.2103 3.004317) (xy 83.32031 2.916587) (xy 83.425228 2.822826) (xy 83.524724 2.723331)
			(xy 83.618484 2.618413) (xy 83.706214 2.508403) (xy 83.787638 2.393647) (xy 83.862499 2.274506) (xy 83.930563 2.151355)
			(xy 83.991614 2.024581) (xy 84.04546 1.894584) (xy 84.091933 1.761772) (xy 84.130886 1.626563) (xy 84.135094 1.608125)
			(xy 178.335673 1.608125) (xy 178.335673 1.693875) (xy 178.343585 1.779258) (xy 178.359341 1.863548)
			(xy 178.382808 1.946024) (xy 178.413784 2.025983) (xy 178.452006 2.102743) (xy 178.497147 2.175649)
			(xy 178.548823 2.244078) (xy 178.606592 2.307448) (xy 178.669962 2.365217) (xy 178.738391 2.416893)
			(xy 178.811297 2.462034) (xy 178.888057 2.500256) (xy 178.968016 2.531232) (xy 179.050492 2.554699)
			(xy 179.134782 2.570455) (xy 179.220165 2.578367) (xy 179.305915 2.578367) (xy 179.391298 2.570455)
			(xy 179.475588 2.554699) (xy 179.558064 2.531232) (xy 179.638023 2.500256) (xy 179.660226 2.4892)
			(xy 183.270652 2.4892) (xy 183.270652 3.3528) (xy 183.271138 3.380069) (xy 183.2789 3.434053) (xy 183.294265 3.486383)
			(xy 183.316922 3.535993) (xy 183.346408 3.581874) (xy 183.382123 3.623091) (xy 183.42334 3.658806)
			(xy 183.469221 3.688292) (xy 183.518831 3.710949) (xy 183.571161 3.726314) (xy 183.625145 3.734076)
			(xy 183.679683 3.734076) (xy 183.733667 3.726314) (xy 183.785997 3.710949) (xy 183.835607 3.688292)
			(xy 183.881488 3.658806) (xy 183.922705 3.623091) (xy 183.95842 3.581874) (xy 183.987906 3.535993)
			(xy 184.010563 3.486383) (xy 184.025928 3.434053) (xy 184.03369 3.380069) (xy 184.034176 3.3528)
			(xy 184.034176 2.4892) (xy 184.03369 2.461931) (xy 184.025928 2.407947) (xy 184.010563 2.355617)
			(xy 183.987906 2.306007) (xy 183.95842 2.260126) (xy 183.922705 2.218909) (xy 183.881488 2.183194)
			(xy 183.835607 2.153708) (xy 183.785997 2.131051) (xy 183.733667 2.115686) (xy 183.679683 2.107924)
			(xy 183.625145 2.107924) (xy 183.571161 2.115686) (xy 183.518831 2.131051) (xy 183.469221 2.153708)
			(xy 183.42334 2.183194) (xy 183.382123 2.218909) (xy 183.346408 2.260126) (xy 183.316922 2.306007)
			(xy 183.294265 2.355617) (xy 183.2789 2.407947) (xy 183.271138 2.461931) (xy 183.270652 2.4892) (xy 179.660226 2.4892)
			(xy 179.714783 2.462034) (xy 179.787689 2.416893) (xy 179.856118 2.365217) (xy 179.919488 2.307448)
			(xy 179.977257 2.244078) (xy 180.028933 2.175649) (xy 180.074074 2.102743) (xy 180.112296 2.025983)
			(xy 180.143272 1.946024) (xy 180.166739 1.863548) (xy 180.182495 1.779258) (xy 180.190407 1.693875)
			(xy 180.190902 1.651) (xy 180.190407 1.608125) (xy 184.685673 1.608125) (xy 184.685673 1.693875)
			(xy 184.693585 1.779258) (xy 184.709341 1.863548) (xy 184.732808 1.946024) (xy 184.763784 2.025983)
			(xy 184.802006 2.102743) (xy 184.847147 2.175649) (xy 184.898823 2.244078) (xy 184.956592 2.307448)
			(xy 185.019962 2.365217) (xy 185.088391 2.416893) (xy 185.161297 2.462034) (xy 185.238057 2.500256)
			(xy 185.318016 2.531232) (xy 185.400492 2.554699) (xy 185.484782 2.570455) (xy 185.570165 2.578367)
			(xy 185.655915 2.578367) (xy 185.741298 2.570455) (xy 185.825588 2.554699) (xy 185.908064 2.531232)
			(xy 185.988023 2.500256) (xy 186.064783 2.462034) (xy 186.137689 2.416893) (xy 186.206118 2.365217)
			(xy 186.269488 2.307448) (xy 186.327257 2.244078) (xy 186.378933 2.175649) (xy 186.424074 2.102743)
			(xy 186.462296 2.025983) (xy 186.493272 1.946024) (xy 186.516739 1.863548) (xy 186.532495 1.779258)
			(xy 186.540407 1.693875) (xy 186.540902 1.651) (xy 186.540407 1.608125) (xy 246.260353 1.608125)
			(xy 246.260353 1.693875) (xy 246.268265 1.779258) (xy 246.284021 1.863548) (xy 246.307488 1.946024)
			(xy 246.338464 2.025983) (xy 246.376686 2.102743) (xy 246.421827 2.175649) (xy 246.473503 2.244078)
			(xy 246.531272 2.307448) (xy 246.594642 2.365217) (xy 246.663071 2.416893) (xy 246.735977 2.462034)
			(xy 246.812737 2.500256) (xy 246.892696 2.531232) (xy 246.975172 2.554699) (xy 247.059462 2.570455)
			(xy 247.144845 2.578367) (xy 247.230595 2.578367) (xy 247.315978 2.570455) (xy 247.400268 2.554699)
			(xy 247.482744 2.531232) (xy 247.562703 2.500256) (xy 247.584906 2.4892) (xy 248.766584 2.4892) (xy 248.766584 3.3528)
			(xy 248.76707 3.380069) (xy 248.774832 3.434053) (xy 248.790197 3.486383) (xy 248.812854 3.535993)
			(xy 248.84234 3.581874) (xy 248.878055 3.623091) (xy 248.919272 3.658806) (xy 248.965153 3.688292)
			(xy 249.014763 3.710949) (xy 249.067093 3.726314) (xy 249.121077 3.734076) (xy 249.175615 3.734076)
			(xy 249.229599 3.726314) (xy 249.281929 3.710949) (xy 249.331539 3.688292) (xy 249.37742 3.658806)
			(xy 249.418637 3.623091) (xy 249.454352 3.581874) (xy 249.483838 3.535993) (xy 249.506495 3.486383)
			(xy 249.52186 3.434053) (xy 249.529622 3.380069) (xy 249.530108 3.3528) (xy 249.530108 2.4892) (xy 249.529622 2.461931)
			(xy 249.52186 2.407947) (xy 249.506495 2.355617) (xy 249.483838 2.306007) (xy 249.454352 2.260126)
			(xy 249.418637 2.218909) (xy 249.37742 2.183194) (xy 249.331539 2.153708) (xy 249.281929 2.131051)
			(xy 249.229599 2.115686) (xy 249.175615 2.107924) (xy 249.121077 2.107924) (xy 249.067093 2.115686)
			(xy 249.014763 2.131051) (xy 248.965153 2.153708) (xy 248.919272 2.183194) (xy 248.878055 2.218909)
			(xy 248.84234 2.260126) (xy 248.812854 2.306007) (xy 248.790197 2.355617) (xy 248.774832 2.407947)
			(xy 248.76707 2.461931) (xy 248.766584 2.4892) (xy 247.584906 2.4892) (xy 247.639463 2.462034) (xy 247.712369 2.416893)
			(xy 247.780798 2.365217) (xy 247.844168 2.307448) (xy 247.901937 2.244078) (xy 247.953613 2.175649)
			(xy 247.998754 2.102743) (xy 248.036976 2.025983) (xy 248.067952 1.946024) (xy 248.091419 1.863548)
			(xy 248.107175 1.779258) (xy 248.115087 1.693875) (xy 248.115582 1.651) (xy 248.115087 1.608125)
			(xy 252.610353 1.608125) (xy 252.610353 1.693875) (xy 252.618265 1.779258) (xy 252.634021 1.863548)
			(xy 252.657488 1.946024) (xy 252.688464 2.025983) (xy 252.726686 2.102743) (xy 252.771827 2.175649)
			(xy 252.823503 2.244078) (xy 252.881272 2.307448) (xy 252.944642 2.365217) (xy 253.013071 2.416893)
			(xy 253.085977 2.462034) (xy 253.162737 2.500256) (xy 253.242696 2.531232) (xy 253.325172 2.554699)
			(xy 253.409462 2.570455) (xy 253.494845 2.578367) (xy 253.580595 2.578367) (xy 253.665978 2.570455)
			(xy 253.750268 2.554699) (xy 253.832744 2.531232) (xy 253.912703 2.500256) (xy 253.989463 2.462034)
			(xy 254.062369 2.416893) (xy 254.130798 2.365217) (xy 254.194168 2.307448) (xy 254.251937 2.244078)
			(xy 254.303613 2.175649) (xy 254.348754 2.102743) (xy 254.386976 2.025983) (xy 254.417952 1.946024)
			(xy 254.441419 1.863548) (xy 254.457175 1.779258) (xy 254.465087 1.693875) (xy 254.465582 1.651)
			(xy 254.465119 1.610919) (xy 256.921241 1.610919) (xy 256.921241 1.696669) (xy 256.929153 1.782052)
			(xy 256.944909 1.866342) (xy 256.968376 1.948818) (xy 256.999352 2.028777) (xy 257.037574 2.105537)
			(xy 257.082715 2.178443) (xy 257.134391 2.246872) (xy 257.19216 2.310242) (xy 257.25553 2.368011)
			(xy 257.323959 2.419687) (xy 257.396865 2.464828) (xy 257.473625 2.50305) (xy 257.553584 2.534026)
			(xy 257.63606 2.557493) (xy 257.72035 2.573249) (xy 257.805733 2.581161) (xy 257.891483 2.581161)
			(xy 257.976866 2.573249) (xy 258.061156 2.557493) (xy 258.143632 2.534026) (xy 258.223591 2.50305)
			(xy 258.245794 2.491994) (xy 261.85622 2.491994) (xy 261.85622 3.355594) (xy 261.856706 3.382863)
			(xy 261.864468 3.436847) (xy 261.879833 3.489177) (xy 261.90249 3.538787) (xy 261.931976 3.584668)
			(xy 261.967691 3.625885) (xy 262.008908 3.6616) (xy 262.054789 3.691086) (xy 262.104399 3.713743)
			(xy 262.156729 3.729108) (xy 262.210713 3.73687) (xy 262.265251 3.73687) (xy 262.319235 3.729108)
			(xy 262.371565 3.713743) (xy 262.421175 3.691086) (xy 262.467056 3.6616) (xy 262.508273 3.625885)
			(xy 262.543988 3.584668) (xy 262.573474 3.538787) (xy 262.596131 3.489177) (xy 262.611496 3.436847)
			(xy 262.619258 3.382863) (xy 262.619744 3.355594) (xy 262.619744 2.491994) (xy 262.619258 2.464725)
			(xy 262.611496 2.410741) (xy 262.596131 2.358411) (xy 262.573474 2.308801) (xy 262.543988 2.26292)
			(xy 262.508273 2.221703) (xy 262.467056 2.185988) (xy 262.421175 2.156502) (xy 262.371565 2.133845)
			(xy 262.319235 2.11848) (xy 262.265251 2.110718) (xy 262.210713 2.110718) (xy 262.156729 2.11848)
			(xy 262.104399 2.133845) (xy 262.054789 2.156502) (xy 262.008908 2.185988) (xy 261.967691 2.221703)
			(xy 261.931976 2.26292) (xy 261.90249 2.308801) (xy 261.879833 2.358411) (xy 261.864468 2.410741)
			(xy 261.856706 2.464725) (xy 261.85622 2.491994) (xy 258.245794 2.491994) (xy 258.300351 2.464828)
			(xy 258.373257 2.419687) (xy 258.441686 2.368011) (xy 258.505056 2.310242) (xy 258.562825 2.246872)
			(xy 258.614501 2.178443) (xy 258.659642 2.105537) (xy 258.697864 2.028777) (xy 258.72884 1.948818)
			(xy 258.752307 1.866342) (xy 258.768063 1.782052) (xy 258.775975 1.696669) (xy 258.77647 1.653794)
			(xy 258.775975 1.610919) (xy 263.271241 1.610919) (xy 263.271241 1.696669) (xy 263.279153 1.782052)
			(xy 263.294909 1.866342) (xy 263.318376 1.948818) (xy 263.349352 2.028777) (xy 263.387574 2.105537)
			(xy 263.432715 2.178443) (xy 263.484391 2.246872) (xy 263.54216 2.310242) (xy 263.60553 2.368011)
			(xy 263.673959 2.419687) (xy 263.746865 2.464828) (xy 263.823625 2.50305) (xy 263.903584 2.534026)
			(xy 263.98606 2.557493) (xy 264.07035 2.573249) (xy 264.155733 2.581161) (xy 264.241483 2.581161)
			(xy 264.326866 2.573249) (xy 264.411156 2.557493) (xy 264.493632 2.534026) (xy 264.573591 2.50305)
			(xy 264.650351 2.464828) (xy 264.723257 2.419687) (xy 264.791686 2.368011) (xy 264.855056 2.310242)
			(xy 264.912825 2.246872) (xy 264.964501 2.178443) (xy 265.009642 2.105537) (xy 265.047864 2.028777)
			(xy 265.07884 1.948818) (xy 265.102307 1.866342) (xy 265.118063 1.782052) (xy 265.125975 1.696669)
			(xy 265.12647 1.653794) (xy 265.125975 1.610919) (xy 324.845921 1.610919) (xy 324.845921 1.696669)
			(xy 324.853833 1.782052) (xy 324.869589 1.866342) (xy 324.893056 1.948818) (xy 324.924032 2.028777)
			(xy 324.962254 2.105537) (xy 325.007395 2.178443) (xy 325.059071 2.246872) (xy 325.11684 2.310242)
			(xy 325.18021 2.368011) (xy 325.248639 2.419687) (xy 325.321545 2.464828) (xy 325.398305 2.50305)
			(xy 325.478264 2.534026) (xy 325.56074 2.557493) (xy 325.64503 2.573249) (xy 325.730413 2.581161)
			(xy 325.816163 2.581161) (xy 325.901546 2.573249) (xy 325.985836 2.557493) (xy 326.068312 2.534026)
			(xy 326.148271 2.50305) (xy 326.170474 2.491994) (xy 327.352152 2.491994) (xy 327.352152 3.355594)
			(xy 327.352638 3.382863) (xy 327.3604 3.436847) (xy 327.375765 3.489177) (xy 327.398422 3.538787)
			(xy 327.427908 3.584668) (xy 327.463623 3.625885) (xy 327.50484 3.6616) (xy 327.550721 3.691086)
			(xy 327.600331 3.713743) (xy 327.652661 3.729108) (xy 327.706645 3.73687) (xy 327.761183 3.73687)
			(xy 327.815167 3.729108) (xy 327.867497 3.713743) (xy 327.917107 3.691086) (xy 327.962988 3.6616)
			(xy 328.004205 3.625885) (xy 328.03992 3.584668) (xy 328.069406 3.538787) (xy 328.092063 3.489177)
			(xy 328.107428 3.436847) (xy 328.11519 3.382863) (xy 328.115676 3.355594) (xy 328.115676 2.491994)
			(xy 328.11519 2.464725) (xy 328.107428 2.410741) (xy 328.092063 2.358411) (xy 328.069406 2.308801)
			(xy 328.03992 2.26292) (xy 328.004205 2.221703) (xy 327.962988 2.185988) (xy 327.917107 2.156502)
			(xy 327.867497 2.133845) (xy 327.815167 2.11848) (xy 327.761183 2.110718) (xy 327.706645 2.110718)
			(xy 327.652661 2.11848) (xy 327.600331 2.133845) (xy 327.550721 2.156502) (xy 327.50484 2.185988)
			(xy 327.463623 2.221703) (xy 327.427908 2.26292) (xy 327.398422 2.308801) (xy 327.375765 2.358411)
			(xy 327.3604 2.410741) (xy 327.352638 2.464725) (xy 327.352152 2.491994) (xy 326.170474 2.491994)
			(xy 326.225031 2.464828) (xy 326.297937 2.419687) (xy 326.366366 2.368011) (xy 326.429736 2.310242)
			(xy 326.487505 2.246872) (xy 326.539181 2.178443) (xy 326.584322 2.105537) (xy 326.622544 2.028777)
			(xy 326.65352 1.948818) (xy 326.676987 1.866342) (xy 326.692743 1.782052) (xy 326.700655 1.696669)
			(xy 326.70115 1.653794) (xy 326.700655 1.610919) (xy 331.195921 1.610919) (xy 331.195921 1.696669)
			(xy 331.203833 1.782052) (xy 331.219589 1.866342) (xy 331.243056 1.948818) (xy 331.274032 2.028777)
			(xy 331.312254 2.105537) (xy 331.357395 2.178443) (xy 331.409071 2.246872) (xy 331.46684 2.310242)
			(xy 331.53021 2.368011) (xy 331.598639 2.419687) (xy 331.671545 2.464828) (xy 331.748305 2.50305)
			(xy 331.828264 2.534026) (xy 331.91074 2.557493) (xy 331.99503 2.573249) (xy 332.080413 2.581161)
			(xy 332.166163 2.581161) (xy 332.251546 2.573249) (xy 332.335836 2.557493) (xy 332.418312 2.534026)
			(xy 332.498271 2.50305) (xy 332.575031 2.464828) (xy 332.647937 2.419687) (xy 332.716366 2.368011)
			(xy 332.779736 2.310242) (xy 332.837505 2.246872) (xy 332.889181 2.178443) (xy 332.934322 2.105537)
			(xy 332.972544 2.028777) (xy 333.00352 1.948818) (xy 333.026987 1.866342) (xy 333.042743 1.782052)
			(xy 333.050655 1.696669) (xy 333.05115 1.653794) (xy 333.050655 1.610919) (xy 335.488267 1.610919)
			(xy 335.488267 1.696669) (xy 335.496179 1.782052) (xy 335.511935 1.866342) (xy 335.535402 1.948818)
			(xy 335.566378 2.028777) (xy 335.6046 2.105537) (xy 335.649741 2.178443) (xy 335.701417 2.246872)
			(xy 335.759186 2.310242) (xy 335.822556 2.368011) (xy 335.890985 2.419687) (xy 335.963891 2.464828)
			(xy 336.040651 2.50305) (xy 336.12061 2.534026) (xy 336.203086 2.557493) (xy 336.287376 2.573249)
			(xy 336.372759 2.581161) (xy 336.458509 2.581161) (xy 336.543892 2.573249) (xy 336.628182 2.557493)
			(xy 336.710658 2.534026) (xy 336.790617 2.50305) (xy 336.81282 2.491994) (xy 340.4235 2.491994) (xy 340.4235 3.355594)
			(xy 340.423986 3.382845) (xy 340.431742 3.436793) (xy 340.447097 3.489088) (xy 340.469739 3.538665)
			(xy 340.499205 3.584515) (xy 340.534896 3.625706) (xy 340.576087 3.661397) (xy 340.621937 3.690863)
			(xy 340.671514 3.713505) (xy 340.723809 3.72886) (xy 340.777757 3.736616) (xy 340.832259 3.736616)
			(xy 340.886207 3.72886) (xy 340.938502 3.713505) (xy 340.988079 3.690863) (xy 341.033929 3.661397)
			(xy 341.07512 3.625706) (xy 341.110811 3.584515) (xy 341.140277 3.538665) (xy 341.162919 3.489088)
			(xy 341.178274 3.436793) (xy 341.18603 3.382845) (xy 341.186516 3.355594) (xy 341.186516 2.491994)
			(xy 341.18603 2.464743) (xy 341.178274 2.410795) (xy 341.162919 2.3585) (xy 341.140277 2.308923)
			(xy 341.110811 2.263073) (xy 341.07512 2.221882) (xy 341.033929 2.186191) (xy 340.988079 2.156725)
			(xy 340.938502 2.134083) (xy 340.886207 2.118728) (xy 340.832259 2.110972) (xy 340.777757 2.110972)
			(xy 340.723809 2.118728) (xy 340.671514 2.134083) (xy 340.621937 2.156725) (xy 340.576087 2.186191)
			(xy 340.534896 2.221882) (xy 340.499205 2.263073) (xy 340.469739 2.308923) (xy 340.447097 2.3585)
			(xy 340.431742 2.410795) (xy 340.423986 2.464743) (xy 340.4235 2.491994) (xy 336.81282 2.491994)
			(xy 336.867377 2.464828) (xy 336.940283 2.419687) (xy 337.008712 2.368011) (xy 337.072082 2.310242)
			(xy 337.129851 2.246872) (xy 337.181527 2.178443) (xy 337.226668 2.105537) (xy 337.26489 2.028777)
			(xy 337.295866 1.948818) (xy 337.319333 1.866342) (xy 337.335089 1.782052) (xy 337.343001 1.696669)
			(xy 337.343496 1.653794) (xy 337.343001 1.610919) (xy 341.838267 1.610919) (xy 341.838267 1.696669)
			(xy 341.846179 1.782052) (xy 341.861935 1.866342) (xy 341.885402 1.948818) (xy 341.916378 2.028777)
			(xy 341.9546 2.105537) (xy 341.999741 2.178443) (xy 342.051417 2.246872) (xy 342.109186 2.310242)
			(xy 342.172556 2.368011) (xy 342.240985 2.419687) (xy 342.313891 2.464828) (xy 342.390651 2.50305)
			(xy 342.47061 2.534026) (xy 342.553086 2.557493) (xy 342.637376 2.573249) (xy 342.722759 2.581161)
			(xy 342.808509 2.581161) (xy 342.893892 2.573249) (xy 342.978182 2.557493) (xy 343.060658 2.534026)
			(xy 343.140617 2.50305) (xy 343.217377 2.464828) (xy 343.290283 2.419687) (xy 343.358712 2.368011)
			(xy 343.422082 2.310242) (xy 343.479851 2.246872) (xy 343.531527 2.178443) (xy 343.576668 2.105537)
			(xy 343.61489 2.028777) (xy 343.645866 1.948818) (xy 343.669333 1.866342) (xy 343.685089 1.782052)
			(xy 343.693001 1.696669) (xy 343.693496 1.653794) (xy 343.693001 1.610919) (xy 373.705107 1.610919)
			(xy 373.705107 1.696669) (xy 373.713019 1.782052) (xy 373.728775 1.866342) (xy 373.752242 1.948818)
			(xy 373.783218 2.028777) (xy 373.82144 2.105537) (xy 373.866581 2.178443) (xy 373.918257 2.246872)
			(xy 373.976026 2.310242) (xy 374.039396 2.368011) (xy 374.107825 2.419687) (xy 374.180731 2.464828)
			(xy 374.257491 2.50305) (xy 374.33745 2.534026) (xy 374.419926 2.557493) (xy 374.504216 2.573249)
			(xy 374.589599 2.581161) (xy 374.675349 2.581161) (xy 374.760732 2.573249) (xy 374.845022 2.557493)
			(xy 374.927498 2.534026) (xy 375.007457 2.50305) (xy 375.02966 2.491994) (xy 376.211592 2.491994)
			(xy 376.211592 3.355594) (xy 376.212078 3.382845) (xy 376.219834 3.436793) (xy 376.235189 3.489088)
			(xy 376.257831 3.538665) (xy 376.287297 3.584515) (xy 376.322988 3.625706) (xy 376.364179 3.661397)
			(xy 376.410029 3.690863) (xy 376.459606 3.713505) (xy 376.511901 3.72886) (xy 376.565849 3.736616)
			(xy 376.620351 3.736616) (xy 376.674299 3.72886) (xy 376.726594 3.713505) (xy 376.776171 3.690863)
			(xy 376.822021 3.661397) (xy 376.863212 3.625706) (xy 376.898903 3.584515) (xy 376.928369 3.538665)
			(xy 376.951011 3.489088) (xy 376.966366 3.436793) (xy 376.974122 3.382845) (xy 376.974608 3.355594)
			(xy 376.974608 2.491994) (xy 376.974122 2.464743) (xy 376.966366 2.410795) (xy 376.951011 2.3585)
			(xy 376.928369 2.308923) (xy 376.898903 2.263073) (xy 376.863212 2.221882) (xy 376.822021 2.186191)
			(xy 376.776171 2.156725) (xy 376.726594 2.134083) (xy 376.674299 2.118728) (xy 376.620351 2.110972)
			(xy 376.565849 2.110972) (xy 376.511901 2.118728) (xy 376.459606 2.134083) (xy 376.410029 2.156725)
			(xy 376.364179 2.186191) (xy 376.322988 2.221882) (xy 376.287297 2.263073) (xy 376.257831 2.308923)
			(xy 376.235189 2.3585) (xy 376.219834 2.410795) (xy 376.212078 2.464743) (xy 376.211592 2.491994)
			(xy 375.02966 2.491994) (xy 375.084217 2.464828) (xy 375.157123 2.419687) (xy 375.225552 2.368011)
			(xy 375.288922 2.310242) (xy 375.346691 2.246872) (xy 375.398367 2.178443) (xy 375.443508 2.105537)
			(xy 375.48173 2.028777) (xy 375.512706 1.948818) (xy 375.536173 1.866342) (xy 375.551929 1.782052)
			(xy 375.559841 1.696669) (xy 375.560336 1.653794) (xy 375.559841 1.610919) (xy 380.055107 1.610919)
			(xy 380.055107 1.696669) (xy 380.063019 1.782052) (xy 380.078775 1.866342) (xy 380.102242 1.948818)
			(xy 380.133218 2.028777) (xy 380.17144 2.105537) (xy 380.216581 2.178443) (xy 380.268257 2.246872)
			(xy 380.326026 2.310242) (xy 380.389396 2.368011) (xy 380.457825 2.419687) (xy 380.530731 2.464828)
			(xy 380.607491 2.50305) (xy 380.68745 2.534026) (xy 380.769926 2.557493) (xy 380.854216 2.573249)
			(xy 380.939599 2.581161) (xy 381.025349 2.581161) (xy 381.110732 2.573249) (xy 381.195022 2.557493)
			(xy 381.277498 2.534026) (xy 381.357457 2.50305) (xy 381.434217 2.464828) (xy 381.507123 2.419687)
			(xy 381.575552 2.368011) (xy 381.638922 2.310242) (xy 381.696691 2.246872) (xy 381.748367 2.178443)
			(xy 381.793508 2.105537) (xy 381.83173 2.028777) (xy 381.862706 1.948818) (xy 381.886173 1.866342)
			(xy 381.901929 1.782052) (xy 381.909841 1.696669) (xy 381.910336 1.653794) (xy 381.909841 1.610919)
			(xy 381.901929 1.525536) (xy 381.886173 1.441246) (xy 381.862706 1.35877) (xy 381.83173 1.278811)
			(xy 381.793508 1.202051) (xy 381.748367 1.129145) (xy 381.696691 1.060716) (xy 381.638922 0.997346)
			(xy 381.575552 0.939577) (xy 381.507123 0.887901) (xy 381.434217 0.84276) (xy 381.357457 0.804538)
			(xy 381.277498 0.773562) (xy 381.195022 0.750095) (xy 381.110732 0.734339) (xy 381.025349 0.726427)
			(xy 380.939599 0.726427) (xy 380.854216 0.734339) (xy 380.769926 0.750095) (xy 380.68745 0.773562)
			(xy 380.607491 0.804538) (xy 380.530731 0.84276) (xy 380.457825 0.887901) (xy 380.389396 0.939577)
			(xy 380.326026 0.997346) (xy 380.268257 1.060716) (xy 380.216581 1.129145) (xy 380.17144 1.202051)
			(xy 380.133218 1.278811) (xy 380.102242 1.35877) (xy 380.078775 1.441246) (xy 380.063019 1.525536)
			(xy 380.055107 1.610919) (xy 375.559841 1.610919) (xy 375.551929 1.525536) (xy 375.536173 1.441246)
			(xy 375.512706 1.35877) (xy 375.48173 1.278811) (xy 375.443508 1.202051) (xy 375.398367 1.129145)
			(xy 375.346691 1.060716) (xy 375.288922 0.997346) (xy 375.225552 0.939577) (xy 375.157123 0.887901)
			(xy 375.084217 0.84276) (xy 375.007457 0.804538) (xy 374.927498 0.773562) (xy 374.845022 0.750095)
			(xy 374.760732 0.734339) (xy 374.675349 0.726427) (xy 374.589599 0.726427) (xy 374.504216 0.734339)
			(xy 374.419926 0.750095) (xy 374.33745 0.773562) (xy 374.257491 0.804538) (xy 374.180731 0.84276)
			(xy 374.107825 0.887901) (xy 374.039396 0.939577) (xy 373.976026 0.997346) (xy 373.918257 1.060716)
			(xy 373.866581 1.129145) (xy 373.82144 1.202051) (xy 373.783218 1.278811) (xy 373.752242 1.35877)
			(xy 373.728775 1.441246) (xy 373.713019 1.525536) (xy 373.705107 1.610919) (xy 343.693001 1.610919)
			(xy 343.685089 1.525536) (xy 343.669333 1.441246) (xy 343.645866 1.35877) (xy 343.61489 1.278811)
			(xy 343.576668 1.202051) (xy 343.531527 1.129145) (xy 343.479851 1.060716) (xy 343.422082 0.997346)
			(xy 343.358712 0.939577) (xy 343.290283 0.887901) (xy 343.217377 0.84276) (xy 343.140617 0.804538)
			(xy 343.060658 0.773562) (xy 342.978182 0.750095) (xy 342.893892 0.734339) (xy 342.808509 0.726427)
			(xy 342.722759 0.726427) (xy 342.637376 0.734339) (xy 342.553086 0.750095) (xy 342.47061 0.773562)
			(xy 342.390651 0.804538) (xy 342.313891 0.84276) (xy 342.240985 0.887901) (xy 342.172556 0.939577)
			(xy 342.109186 0.997346) (xy 342.051417 1.060716) (xy 341.999741 1.129145) (xy 341.9546 1.202051)
			(xy 341.916378 1.278811) (xy 341.885402 1.35877) (xy 341.861935 1.441246) (xy 341.846179 1.525536)
			(xy 341.838267 1.610919) (xy 337.343001 1.610919) (xy 337.335089 1.525536) (xy 337.319333 1.441246)
			(xy 337.295866 1.35877) (xy 337.26489 1.278811) (xy 337.226668 1.202051) (xy 337.181527 1.129145)
			(xy 337.129851 1.060716) (xy 337.072082 0.997346) (xy 337.008712 0.939577) (xy 336.940283 0.887901)
			(xy 336.867377 0.84276) (xy 336.790617 0.804538) (xy 336.710658 0.773562) (xy 336.628182 0.750095)
			(xy 336.543892 0.734339) (xy 336.458509 0.726427) (xy 336.372759 0.726427) (xy 336.287376 0.734339)
			(xy 336.203086 0.750095) (xy 336.12061 0.773562) (xy 336.040651 0.804538) (xy 335.963891 0.84276)
			(xy 335.890985 0.887901) (xy 335.822556 0.939577) (xy 335.759186 0.997346) (xy 335.701417 1.060716)
			(xy 335.649741 1.129145) (xy 335.6046 1.202051) (xy 335.566378 1.278811) (xy 335.535402 1.35877)
			(xy 335.511935 1.441246) (xy 335.496179 1.525536) (xy 335.488267 1.610919) (xy 333.050655 1.610919)
			(xy 333.042743 1.525536) (xy 333.026987 1.441246) (xy 333.00352 1.35877) (xy 332.972544 1.278811)
			(xy 332.934322 1.202051) (xy 332.889181 1.129145) (xy 332.837505 1.060716) (xy 332.779736 0.997346)
			(xy 332.716366 0.939577) (xy 332.647937 0.887901) (xy 332.575031 0.84276) (xy 332.498271 0.804538)
			(xy 332.418312 0.773562) (xy 332.335836 0.750095) (xy 332.251546 0.734339) (xy 332.166163 0.726427)
			(xy 332.080413 0.726427) (xy 331.99503 0.734339) (xy 331.91074 0.750095) (xy 331.828264 0.773562)
			(xy 331.748305 0.804538) (xy 331.671545 0.84276) (xy 331.598639 0.887901) (xy 331.53021 0.939577)
			(xy 331.46684 0.997346) (xy 331.409071 1.060716) (xy 331.357395 1.129145) (xy 331.312254 1.202051)
			(xy 331.274032 1.278811) (xy 331.243056 1.35877) (xy 331.219589 1.441246) (xy 331.203833 1.525536)
			(xy 331.195921 1.610919) (xy 326.700655 1.610919) (xy 326.692743 1.525536) (xy 326.676987 1.441246)
			(xy 326.65352 1.35877) (xy 326.622544 1.278811) (xy 326.584322 1.202051) (xy 326.539181 1.129145)
			(xy 326.487505 1.060716) (xy 326.429736 0.997346) (xy 326.366366 0.939577) (xy 326.297937 0.887901)
			(xy 326.225031 0.84276) (xy 326.148271 0.804538) (xy 326.068312 0.773562) (xy 325.985836 0.750095)
			(xy 325.901546 0.734339) (xy 325.816163 0.726427) (xy 325.730413 0.726427) (xy 325.64503 0.734339)
			(xy 325.56074 0.750095) (xy 325.478264 0.773562) (xy 325.398305 0.804538) (xy 325.321545 0.84276)
			(xy 325.248639 0.887901) (xy 325.18021 0.939577) (xy 325.11684 0.997346) (xy 325.059071 1.060716)
			(xy 325.007395 1.129145) (xy 324.962254 1.202051) (xy 324.924032 1.278811) (xy 324.893056 1.35877)
			(xy 324.869589 1.441246) (xy 324.853833 1.525536) (xy 324.845921 1.610919) (xy 265.125975 1.610919)
			(xy 265.118063 1.525536) (xy 265.102307 1.441246) (xy 265.07884 1.35877) (xy 265.047864 1.278811)
			(xy 265.009642 1.202051) (xy 264.964501 1.129145) (xy 264.912825 1.060716) (xy 264.855056 0.997346)
			(xy 264.791686 0.939577) (xy 264.723257 0.887901) (xy 264.650351 0.84276) (xy 264.573591 0.804538)
			(xy 264.493632 0.773562) (xy 264.411156 0.750095) (xy 264.326866 0.734339) (xy 264.241483 0.726427)
			(xy 264.155733 0.726427) (xy 264.07035 0.734339) (xy 263.98606 0.750095) (xy 263.903584 0.773562)
			(xy 263.823625 0.804538) (xy 263.746865 0.84276) (xy 263.673959 0.887901) (xy 263.60553 0.939577)
			(xy 263.54216 0.997346) (xy 263.484391 1.060716) (xy 263.432715 1.129145) (xy 263.387574 1.202051)
			(xy 263.349352 1.278811) (xy 263.318376 1.35877) (xy 263.294909 1.441246) (xy 263.279153 1.525536)
			(xy 263.271241 1.610919) (xy 258.775975 1.610919) (xy 258.768063 1.525536) (xy 258.752307 1.441246)
			(xy 258.72884 1.35877) (xy 258.697864 1.278811) (xy 258.659642 1.202051) (xy 258.614501 1.129145)
			(xy 258.562825 1.060716) (xy 258.505056 0.997346) (xy 258.441686 0.939577) (xy 258.373257 0.887901)
			(xy 258.300351 0.84276) (xy 258.223591 0.804538) (xy 258.143632 0.773562) (xy 258.061156 0.750095)
			(xy 257.976866 0.734339) (xy 257.891483 0.726427) (xy 257.805733 0.726427) (xy 257.72035 0.734339)
			(xy 257.63606 0.750095) (xy 257.553584 0.773562) (xy 257.473625 0.804538) (xy 257.396865 0.84276)
			(xy 257.323959 0.887901) (xy 257.25553 0.939577) (xy 257.19216 0.997346) (xy 257.134391 1.060716)
			(xy 257.082715 1.129145) (xy 257.037574 1.202051) (xy 256.999352 1.278811) (xy 256.968376 1.35877)
			(xy 256.944909 1.441246) (xy 256.929153 1.525536) (xy 256.921241 1.610919) (xy 254.465119 1.610919)
			(xy 254.465087 1.608125) (xy 254.457175 1.522742) (xy 254.441419 1.438452) (xy 254.417952 1.355976)
			(xy 254.386976 1.276017) (xy 254.348754 1.199257) (xy 254.303613 1.126351) (xy 254.251937 1.057922)
			(xy 254.194168 0.994552) (xy 254.130798 0.936783) (xy 254.062369 0.885107) (xy 253.989463 0.839966)
			(xy 253.912703 0.801744) (xy 253.832744 0.770768) (xy 253.750268 0.747301) (xy 253.665978 0.731545)
			(xy 253.580595 0.723633) (xy 253.494845 0.723633) (xy 253.409462 0.731545) (xy 253.325172 0.747301)
			(xy 253.242696 0.770768) (xy 253.162737 0.801744) (xy 253.085977 0.839966) (xy 253.013071 0.885107)
			(xy 252.944642 0.936783) (xy 252.881272 0.994552) (xy 252.823503 1.057922) (xy 252.771827 1.126351)
			(xy 252.726686 1.199257) (xy 252.688464 1.276017) (xy 252.657488 1.355976) (xy 252.634021 1.438452)
			(xy 252.618265 1.522742) (xy 252.610353 1.608125) (xy 248.115087 1.608125) (xy 248.107175 1.522742)
			(xy 248.091419 1.438452) (xy 248.067952 1.355976) (xy 248.036976 1.276017) (xy 247.998754 1.199257)
			(xy 247.953613 1.126351) (xy 247.901937 1.057922) (xy 247.844168 0.994552) (xy 247.780798 0.936783)
			(xy 247.712369 0.885107) (xy 247.639463 0.839966) (xy 247.562703 0.801744) (xy 247.482744 0.770768)
			(xy 247.400268 0.747301) (xy 247.315978 0.731545) (xy 247.230595 0.723633) (xy 247.144845 0.723633)
			(xy 247.059462 0.731545) (xy 246.975172 0.747301) (xy 246.892696 0.770768) (xy 246.812737 0.801744)
			(xy 246.735977 0.839966) (xy 246.663071 0.885107) (xy 246.594642 0.936783) (xy 246.531272 0.994552)
			(xy 246.473503 1.057922) (xy 246.421827 1.126351) (xy 246.376686 1.199257) (xy 246.338464 1.276017)
			(xy 246.307488 1.355976) (xy 246.284021 1.438452) (xy 246.268265 1.522742) (xy 246.260353 1.608125)
			(xy 186.540407 1.608125) (xy 186.532495 1.522742) (xy 186.516739 1.438452) (xy 186.493272 1.355976)
			(xy 186.462296 1.276017) (xy 186.424074 1.199257) (xy 186.378933 1.126351) (xy 186.327257 1.057922)
			(xy 186.269488 0.994552) (xy 186.206118 0.936783) (xy 186.137689 0.885107) (xy 186.064783 0.839966)
			(xy 185.988023 0.801744) (xy 185.908064 0.770768) (xy 185.825588 0.747301) (xy 185.741298 0.731545)
			(xy 185.655915 0.723633) (xy 185.570165 0.723633) (xy 185.484782 0.731545) (xy 185.400492 0.747301)
			(xy 185.318016 0.770768) (xy 185.238057 0.801744) (xy 185.161297 0.839966) (xy 185.088391 0.885107)
			(xy 185.019962 0.936783) (xy 184.956592 0.994552) (xy 184.898823 1.057922) (xy 184.847147 1.126351)
			(xy 184.802006 1.199257) (xy 184.763784 1.276017) (xy 184.732808 1.355976) (xy 184.709341 1.438452)
			(xy 184.693585 1.522742) (xy 184.685673 1.608125) (xy 180.190407 1.608125) (xy 180.182495 1.522742)
			(xy 180.166739 1.438452) (xy 180.143272 1.355976) (xy 180.112296 1.276017) (xy 180.074074 1.199257)
			(xy 180.028933 1.126351) (xy 179.977257 1.057922) (xy 179.919488 0.994552) (xy 179.856118 0.936783)
			(xy 179.787689 0.885107) (xy 179.714783 0.839966) (xy 179.638023 0.801744) (xy 179.558064 0.770768)
			(xy 179.475588 0.747301) (xy 179.391298 0.731545) (xy 179.305915 0.723633) (xy 179.220165 0.723633)
			(xy 179.134782 0.731545) (xy 179.050492 0.747301) (xy 178.968016 0.770768) (xy 178.888057 0.801744)
			(xy 178.811297 0.839966) (xy 178.738391 0.885107) (xy 178.669962 0.936783) (xy 178.606592 0.994552)
			(xy 178.548823 1.057922) (xy 178.497147 1.126351) (xy 178.452006 1.199257) (xy 178.413784 1.276017)
			(xy 178.382808 1.355976) (xy 178.359341 1.438452) (xy 178.343585 1.522742) (xy 178.335673 1.608125)
			(xy 84.135094 1.608125) (xy 84.162197 1.489382) (xy 84.185766 1.350662) (xy 84.20152 1.210839) (xy 84.20941 1.070352)
			(xy 84.20989 0.999998) (xy 84.20989 -0.931875) (xy 208.043513 -0.931875) (xy 208.043513 -0.846125)
			(xy 208.051425 -0.760742) (xy 208.067181 -0.676452) (xy 208.090648 -0.593976) (xy 208.121624 -0.514017)
			(xy 208.159846 -0.437257) (xy 208.204987 -0.364351) (xy 208.256663 -0.295922) (xy 208.314432 -0.232552)
			(xy 208.377802 -0.174783) (xy 208.446231 -0.123107) (xy 208.519137 -0.077966) (xy 208.595897 -0.039744)
			(xy 208.675856 -0.008768) (xy 208.758332 0.014699) (xy 208.842622 0.030455) (xy 208.928005 0.038367)
			(xy 209.013755 0.038367) (xy 209.099138 0.030455) (xy 209.183428 0.014699) (xy 209.265904 -0.008768)
			(xy 209.345863 -0.039744) (xy 209.422623 -0.077966) (xy 209.495529 -0.123107) (xy 209.563958 -0.174783)
			(xy 209.627328 -0.232552) (xy 209.685097 -0.295922) (xy 209.736773 -0.364351) (xy 209.781914 -0.437257)
			(xy 209.820136 -0.514017) (xy 209.851112 -0.593976) (xy 209.874579 -0.676452) (xy 209.890335 -0.760742)
			(xy 209.898247 -0.846125) (xy 209.898742 -0.889) (xy 209.898247 -0.931875) (xy 214.393513 -0.931875)
			(xy 214.393513 -0.846125) (xy 214.401425 -0.760742) (xy 214.417181 -0.676452) (xy 214.440648 -0.593976)
			(xy 214.471624 -0.514017) (xy 214.509846 -0.437257) (xy 214.554987 -0.364351) (xy 214.606663 -0.295922)
			(xy 214.664432 -0.232552) (xy 214.727802 -0.174783) (xy 214.796231 -0.123107) (xy 214.869137 -0.077966)
			(xy 214.945897 -0.039744) (xy 215.025856 -0.008768) (xy 215.108332 0.014699) (xy 215.192622 0.030455)
			(xy 215.278005 0.038367) (xy 215.363755 0.038367) (xy 215.449138 0.030455) (xy 215.533428 0.014699)
			(xy 215.615904 -0.008768) (xy 215.695863 -0.039744) (xy 215.772623 -0.077966) (xy 215.845529 -0.123107)
			(xy 215.913958 -0.174783) (xy 215.977328 -0.232552) (xy 216.035097 -0.295922) (xy 216.086773 -0.364351)
			(xy 216.131914 -0.437257) (xy 216.170136 -0.514017) (xy 216.201112 -0.593976) (xy 216.224579 -0.676452)
			(xy 216.240335 -0.760742) (xy 216.248247 -0.846125) (xy 216.248742 -0.889) (xy 216.248247 -0.931875)
			(xy 246.260353 -0.931875) (xy 246.260353 -0.846125) (xy 246.268265 -0.760742) (xy 246.284021 -0.676452)
			(xy 246.307488 -0.593976) (xy 246.338464 -0.514017) (xy 246.376686 -0.437257) (xy 246.421827 -0.364351)
			(xy 246.473503 -0.295922) (xy 246.531272 -0.232552) (xy 246.594642 -0.174783) (xy 246.663071 -0.123107)
			(xy 246.735977 -0.077966) (xy 246.812737 -0.039744) (xy 246.892696 -0.008768) (xy 246.975172 0.014699)
			(xy 247.059462 0.030455) (xy 247.144845 0.038367) (xy 247.230595 0.038367) (xy 247.315978 0.030455)
			(xy 247.400268 0.014699) (xy 247.482744 -0.008768) (xy 247.562703 -0.039744) (xy 247.639463 -0.077966)
			(xy 247.712369 -0.123107) (xy 247.780798 -0.174783) (xy 247.844168 -0.232552) (xy 247.901937 -0.295922)
			(xy 247.953613 -0.364351) (xy 247.998754 -0.437257) (xy 248.036976 -0.514017) (xy 248.067952 -0.593976)
			(xy 248.091419 -0.676452) (xy 248.107175 -0.760742) (xy 248.115087 -0.846125) (xy 248.115582 -0.889)
			(xy 248.115087 -0.931875) (xy 252.610353 -0.931875) (xy 252.610353 -0.846125) (xy 252.618265 -0.760742)
			(xy 252.634021 -0.676452) (xy 252.657488 -0.593976) (xy 252.688464 -0.514017) (xy 252.726686 -0.437257)
			(xy 252.771827 -0.364351) (xy 252.823503 -0.295922) (xy 252.881272 -0.232552) (xy 252.944642 -0.174783)
			(xy 253.013071 -0.123107) (xy 253.085977 -0.077966) (xy 253.162737 -0.039744) (xy 253.242696 -0.008768)
			(xy 253.325172 0.014699) (xy 253.409462 0.030455) (xy 253.494845 0.038367) (xy 253.580595 0.038367)
			(xy 253.665978 0.030455) (xy 253.750268 0.014699) (xy 253.832744 -0.008768) (xy 253.912703 -0.039744)
			(xy 253.989463 -0.077966) (xy 254.062369 -0.123107) (xy 254.130798 -0.174783) (xy 254.194168 -0.232552)
			(xy 254.251937 -0.295922) (xy 254.303613 -0.364351) (xy 254.348754 -0.437257) (xy 254.386976 -0.514017)
			(xy 254.417952 -0.593976) (xy 254.441419 -0.676452) (xy 254.457175 -0.760742) (xy 254.465087 -0.846125)
			(xy 254.465582 -0.889) (xy 254.465119 -0.929081) (xy 256.921241 -0.929081) (xy 256.921241 -0.843331)
			(xy 256.929153 -0.757948) (xy 256.944909 -0.673658) (xy 256.968376 -0.591182) (xy 256.999352 -0.511223)
			(xy 257.037574 -0.434463) (xy 257.082715 -0.361557) (xy 257.134391 -0.293128) (xy 257.19216 -0.229758)
			(xy 257.25553 -0.171989) (xy 257.323959 -0.120313) (xy 257.396865 -0.075172) (xy 257.473625 -0.03695)
			(xy 257.553584 -0.005974) (xy 257.63606 0.017493) (xy 257.72035 0.033249) (xy 257.805733 0.041161)
			(xy 257.891483 0.041161) (xy 257.976866 0.033249) (xy 258.061156 0.017493) (xy 258.143632 -0.005974)
			(xy 258.223591 -0.03695) (xy 258.245794 -0.048006) (xy 261.85622 -0.048006) (xy 261.85622 0.815594)
			(xy 261.856706 0.842863) (xy 261.864468 0.896847) (xy 261.879833 0.949177) (xy 261.90249 0.998787)
			(xy 261.931976 1.044668) (xy 261.967691 1.085885) (xy 262.008908 1.1216) (xy 262.054789 1.151086)
			(xy 262.104399 1.173743) (xy 262.156729 1.189108) (xy 262.210713 1.19687) (xy 262.265251 1.19687)
			(xy 262.319235 1.189108) (xy 262.371565 1.173743) (xy 262.421175 1.151086) (xy 262.467056 1.1216)
			(xy 262.508273 1.085885) (xy 262.543988 1.044668) (xy 262.573474 0.998787) (xy 262.596131 0.949177)
			(xy 262.611496 0.896847) (xy 262.619258 0.842863) (xy 262.619744 0.815594) (xy 262.619744 -0.048006)
			(xy 262.619258 -0.075275) (xy 262.611496 -0.129259) (xy 262.596131 -0.181589) (xy 262.573474 -0.231199)
			(xy 262.543988 -0.27708) (xy 262.508273 -0.318297) (xy 262.467056 -0.354012) (xy 262.421175 -0.383498)
			(xy 262.371565 -0.406155) (xy 262.319235 -0.42152) (xy 262.265251 -0.429282) (xy 262.210713 -0.429282)
			(xy 262.156729 -0.42152) (xy 262.104399 -0.406155) (xy 262.054789 -0.383498) (xy 262.008908 -0.354012)
			(xy 261.967691 -0.318297) (xy 261.931976 -0.27708) (xy 261.90249 -0.231199) (xy 261.879833 -0.181589)
			(xy 261.864468 -0.129259) (xy 261.856706 -0.075275) (xy 261.85622 -0.048006) (xy 258.245794 -0.048006)
			(xy 258.300351 -0.075172) (xy 258.373257 -0.120313) (xy 258.441686 -0.171989) (xy 258.505056 -0.229758)
			(xy 258.562825 -0.293128) (xy 258.614501 -0.361557) (xy 258.659642 -0.434463) (xy 258.697864 -0.511223)
			(xy 258.72884 -0.591182) (xy 258.752307 -0.673658) (xy 258.768063 -0.757948) (xy 258.775975 -0.843331)
			(xy 258.77647 -0.886206) (xy 258.775975 -0.929081) (xy 263.271241 -0.929081) (xy 263.271241 -0.843331)
			(xy 263.279153 -0.757948) (xy 263.294909 -0.673658) (xy 263.318376 -0.591182) (xy 263.349352 -0.511223)
			(xy 263.387574 -0.434463) (xy 263.432715 -0.361557) (xy 263.484391 -0.293128) (xy 263.54216 -0.229758)
			(xy 263.60553 -0.171989) (xy 263.673959 -0.120313) (xy 263.746865 -0.075172) (xy 263.823625 -0.03695)
			(xy 263.903584 -0.005974) (xy 263.98606 0.017493) (xy 264.07035 0.033249) (xy 264.155733 0.041161)
			(xy 264.241483 0.041161) (xy 264.326866 0.033249) (xy 264.411156 0.017493) (xy 264.493632 -0.005974)
			(xy 264.573591 -0.03695) (xy 264.650351 -0.075172) (xy 264.723257 -0.120313) (xy 264.791686 -0.171989)
			(xy 264.855056 -0.229758) (xy 264.912825 -0.293128) (xy 264.964501 -0.361557) (xy 265.009642 -0.434463)
			(xy 265.047864 -0.511223) (xy 265.07884 -0.591182) (xy 265.102307 -0.673658) (xy 265.118063 -0.757948)
			(xy 265.125975 -0.843331) (xy 265.12647 -0.886206) (xy 265.125975 -0.929081) (xy 324.845921 -0.929081)
			(xy 324.845921 -0.843331) (xy 324.853833 -0.757948) (xy 324.869589 -0.673658) (xy 324.893056 -0.591182)
			(xy 324.924032 -0.511223) (xy 324.962254 -0.434463) (xy 325.007395 -0.361557) (xy 325.059071 -0.293128)
			(xy 325.11684 -0.229758) (xy 325.18021 -0.171989) (xy 325.248639 -0.120313) (xy 325.321545 -0.075172)
			(xy 325.398305 -0.03695) (xy 325.478264 -0.005974) (xy 325.56074 0.017493) (xy 325.64503 0.033249)
			(xy 325.730413 0.041161) (xy 325.816163 0.041161) (xy 325.901546 0.033249) (xy 325.985836 0.017493)
			(xy 326.068312 -0.005974) (xy 326.148271 -0.03695) (xy 326.170474 -0.048006) (xy 327.352152 -0.048006)
			(xy 327.352152 0.815594) (xy 327.352638 0.842863) (xy 327.3604 0.896847) (xy 327.375765 0.949177)
			(xy 327.398422 0.998787) (xy 327.427908 1.044668) (xy 327.463623 1.085885) (xy 327.50484 1.1216)
			(xy 327.550721 1.151086) (xy 327.600331 1.173743) (xy 327.652661 1.189108) (xy 327.706645 1.19687)
			(xy 327.761183 1.19687) (xy 327.815167 1.189108) (xy 327.867497 1.173743) (xy 327.917107 1.151086)
			(xy 327.962988 1.1216) (xy 328.004205 1.085885) (xy 328.03992 1.044668) (xy 328.069406 0.998787)
			(xy 328.092063 0.949177) (xy 328.107428 0.896847) (xy 328.11519 0.842863) (xy 328.115676 0.815594)
			(xy 328.115676 -0.048006) (xy 328.11519 -0.075275) (xy 328.107428 -0.129259) (xy 328.092063 -0.181589)
			(xy 328.069406 -0.231199) (xy 328.03992 -0.27708) (xy 328.004205 -0.318297) (xy 327.962988 -0.354012)
			(xy 327.917107 -0.383498) (xy 327.867497 -0.406155) (xy 327.815167 -0.42152) (xy 327.761183 -0.429282)
			(xy 327.706645 -0.429282) (xy 327.652661 -0.42152) (xy 327.600331 -0.406155) (xy 327.550721 -0.383498)
			(xy 327.50484 -0.354012) (xy 327.463623 -0.318297) (xy 327.427908 -0.27708) (xy 327.398422 -0.231199)
			(xy 327.375765 -0.181589) (xy 327.3604 -0.129259) (xy 327.352638 -0.075275) (xy 327.352152 -0.048006)
			(xy 326.170474 -0.048006) (xy 326.225031 -0.075172) (xy 326.297937 -0.120313) (xy 326.366366 -0.171989)
			(xy 326.429736 -0.229758) (xy 326.487505 -0.293128) (xy 326.539181 -0.361557) (xy 326.584322 -0.434463)
			(xy 326.622544 -0.511223) (xy 326.65352 -0.591182) (xy 326.676987 -0.673658) (xy 326.692743 -0.757948)
			(xy 326.700655 -0.843331) (xy 326.70115 -0.886206) (xy 326.700655 -0.929081) (xy 331.195921 -0.929081)
			(xy 331.195921 -0.843331) (xy 331.203833 -0.757948) (xy 331.219589 -0.673658) (xy 331.243056 -0.591182)
			(xy 331.274032 -0.511223) (xy 331.312254 -0.434463) (xy 331.357395 -0.361557) (xy 331.409071 -0.293128)
			(xy 331.46684 -0.229758) (xy 331.53021 -0.171989) (xy 331.598639 -0.120313) (xy 331.671545 -0.075172)
			(xy 331.748305 -0.03695) (xy 331.828264 -0.005974) (xy 331.91074 0.017493) (xy 331.99503 0.033249)
			(xy 332.080413 0.041161) (xy 332.166163 0.041161) (xy 332.251546 0.033249) (xy 332.335836 0.017493)
			(xy 332.418312 -0.005974) (xy 332.498271 -0.03695) (xy 332.575031 -0.075172) (xy 332.647937 -0.120313)
			(xy 332.716366 -0.171989) (xy 332.779736 -0.229758) (xy 332.837505 -0.293128) (xy 332.889181 -0.361557)
			(xy 332.934322 -0.434463) (xy 332.972544 -0.511223) (xy 333.00352 -0.591182) (xy 333.026987 -0.673658)
			(xy 333.042743 -0.757948) (xy 333.050655 -0.843331) (xy 333.05115 -0.886206) (xy 333.050655 -0.929081)
			(xy 335.488267 -0.929081) (xy 335.488267 -0.843331) (xy 335.496179 -0.757948) (xy 335.511935 -0.673658)
			(xy 335.535402 -0.591182) (xy 335.566378 -0.511223) (xy 335.6046 -0.434463) (xy 335.649741 -0.361557)
			(xy 335.701417 -0.293128) (xy 335.759186 -0.229758) (xy 335.822556 -0.171989) (xy 335.890985 -0.120313)
			(xy 335.963891 -0.075172) (xy 336.040651 -0.03695) (xy 336.12061 -0.005974) (xy 336.203086 0.017493)
			(xy 336.287376 0.033249) (xy 336.372759 0.041161) (xy 336.458509 0.041161) (xy 336.543892 0.033249)
			(xy 336.628182 0.017493) (xy 336.710658 -0.005974) (xy 336.790617 -0.03695) (xy 336.81282 -0.048006)
			(xy 340.4235 -0.048006) (xy 340.4235 0.815594) (xy 340.423986 0.842845) (xy 340.431742 0.896793)
			(xy 340.447097 0.949088) (xy 340.469739 0.998665) (xy 340.499205 1.044515) (xy 340.534896 1.085706)
			(xy 340.576087 1.121397) (xy 340.621937 1.150863) (xy 340.671514 1.173505) (xy 340.723809 1.18886)
			(xy 340.777757 1.196616) (xy 340.832259 1.196616) (xy 340.886207 1.18886) (xy 340.938502 1.173505)
			(xy 340.988079 1.150863) (xy 341.033929 1.121397) (xy 341.07512 1.085706) (xy 341.110811 1.044515)
			(xy 341.140277 0.998665) (xy 341.162919 0.949088) (xy 341.178274 0.896793) (xy 341.18603 0.842845)
			(xy 341.186516 0.815594) (xy 341.186516 -0.048006) (xy 341.18603 -0.075257) (xy 341.178274 -0.129205)
			(xy 341.162919 -0.1815) (xy 341.140277 -0.231077) (xy 341.110811 -0.276927) (xy 341.07512 -0.318118)
			(xy 341.033929 -0.353809) (xy 340.988079 -0.383275) (xy 340.938502 -0.405917) (xy 340.886207 -0.421272)
			(xy 340.832259 -0.429028) (xy 340.777757 -0.429028) (xy 340.723809 -0.421272) (xy 340.671514 -0.405917)
			(xy 340.621937 -0.383275) (xy 340.576087 -0.353809) (xy 340.534896 -0.318118) (xy 340.499205 -0.276927)
			(xy 340.469739 -0.231077) (xy 340.447097 -0.1815) (xy 340.431742 -0.129205) (xy 340.423986 -0.075257)
			(xy 340.4235 -0.048006) (xy 336.81282 -0.048006) (xy 336.867377 -0.075172) (xy 336.940283 -0.120313)
			(xy 337.008712 -0.171989) (xy 337.072082 -0.229758) (xy 337.129851 -0.293128) (xy 337.181527 -0.361557)
			(xy 337.226668 -0.434463) (xy 337.26489 -0.511223) (xy 337.295866 -0.591182) (xy 337.319333 -0.673658)
			(xy 337.335089 -0.757948) (xy 337.343001 -0.843331) (xy 337.343496 -0.886206) (xy 337.343001 -0.929081)
			(xy 341.838267 -0.929081) (xy 341.838267 -0.843331) (xy 341.846179 -0.757948) (xy 341.861935 -0.673658)
			(xy 341.885402 -0.591182) (xy 341.916378 -0.511223) (xy 341.9546 -0.434463) (xy 341.999741 -0.361557)
			(xy 342.051417 -0.293128) (xy 342.109186 -0.229758) (xy 342.172556 -0.171989) (xy 342.240985 -0.120313)
			(xy 342.313891 -0.075172) (xy 342.390651 -0.03695) (xy 342.47061 -0.005974) (xy 342.553086 0.017493)
			(xy 342.637376 0.033249) (xy 342.722759 0.041161) (xy 342.808509 0.041161) (xy 342.893892 0.033249)
			(xy 342.978182 0.017493) (xy 343.060658 -0.005974) (xy 343.140617 -0.03695) (xy 343.217377 -0.075172)
			(xy 343.290283 -0.120313) (xy 343.358712 -0.171989) (xy 343.422082 -0.229758) (xy 343.479851 -0.293128)
			(xy 343.531527 -0.361557) (xy 343.576668 -0.434463) (xy 343.61489 -0.511223) (xy 343.645866 -0.591182)
			(xy 343.669333 -0.673658) (xy 343.685089 -0.757948) (xy 343.693001 -0.843331) (xy 343.693496 -0.886206)
			(xy 343.693001 -0.929081) (xy 373.705107 -0.929081) (xy 373.705107 -0.843331) (xy 373.713019 -0.757948)
			(xy 373.728775 -0.673658) (xy 373.752242 -0.591182) (xy 373.783218 -0.511223) (xy 373.82144 -0.434463)
			(xy 373.866581 -0.361557) (xy 373.918257 -0.293128) (xy 373.976026 -0.229758) (xy 374.039396 -0.171989)
			(xy 374.107825 -0.120313) (xy 374.180731 -0.075172) (xy 374.257491 -0.03695) (xy 374.33745 -0.005974)
			(xy 374.419926 0.017493) (xy 374.504216 0.033249) (xy 374.589599 0.041161) (xy 374.675349 0.041161)
			(xy 374.760732 0.033249) (xy 374.845022 0.017493) (xy 374.927498 -0.005974) (xy 375.007457 -0.03695)
			(xy 375.02966 -0.048006) (xy 376.211592 -0.048006) (xy 376.211592 0.815594) (xy 376.212078 0.842845)
			(xy 376.219834 0.896793) (xy 376.235189 0.949088) (xy 376.257831 0.998665) (xy 376.287297 1.044515)
			(xy 376.322988 1.085706) (xy 376.364179 1.121397) (xy 376.410029 1.150863) (xy 376.459606 1.173505)
			(xy 376.511901 1.18886) (xy 376.565849 1.196616) (xy 376.620351 1.196616) (xy 376.674299 1.18886)
			(xy 376.726594 1.173505) (xy 376.776171 1.150863) (xy 376.822021 1.121397) (xy 376.863212 1.085706)
			(xy 376.898903 1.044515) (xy 376.928369 0.998665) (xy 376.951011 0.949088) (xy 376.966366 0.896793)
			(xy 376.974122 0.842845) (xy 376.974608 0.815594) (xy 376.974608 -0.048006) (xy 376.974122 -0.075257)
			(xy 376.966366 -0.129205) (xy 376.951011 -0.1815) (xy 376.928369 -0.231077) (xy 376.898903 -0.276927)
			(xy 376.863212 -0.318118) (xy 376.822021 -0.353809) (xy 376.776171 -0.383275) (xy 376.726594 -0.405917)
			(xy 376.674299 -0.421272) (xy 376.620351 -0.429028) (xy 376.565849 -0.429028) (xy 376.511901 -0.421272)
			(xy 376.459606 -0.405917) (xy 376.410029 -0.383275) (xy 376.364179 -0.353809) (xy 376.322988 -0.318118)
			(xy 376.287297 -0.276927) (xy 376.257831 -0.231077) (xy 376.235189 -0.1815) (xy 376.219834 -0.129205)
			(xy 376.212078 -0.075257) (xy 376.211592 -0.048006) (xy 375.02966 -0.048006) (xy 375.084217 -0.075172)
			(xy 375.157123 -0.120313) (xy 375.225552 -0.171989) (xy 375.288922 -0.229758) (xy 375.346691 -0.293128)
			(xy 375.398367 -0.361557) (xy 375.443508 -0.434463) (xy 375.48173 -0.511223) (xy 375.512706 -0.591182)
			(xy 375.536173 -0.673658) (xy 375.551929 -0.757948) (xy 375.559841 -0.843331) (xy 375.560336 -0.886206)
			(xy 375.559841 -0.929081) (xy 380.055107 -0.929081) (xy 380.055107 -0.843331) (xy 380.063019 -0.757948)
			(xy 380.078775 -0.673658) (xy 380.102242 -0.591182) (xy 380.133218 -0.511223) (xy 380.17144 -0.434463)
			(xy 380.216581 -0.361557) (xy 380.268257 -0.293128) (xy 380.326026 -0.229758) (xy 380.389396 -0.171989)
			(xy 380.457825 -0.120313) (xy 380.530731 -0.075172) (xy 380.607491 -0.03695) (xy 380.68745 -0.005974)
			(xy 380.769926 0.017493) (xy 380.854216 0.033249) (xy 380.939599 0.041161) (xy 381.025349 0.041161)
			(xy 381.110732 0.033249) (xy 381.195022 0.017493) (xy 381.277498 -0.005974) (xy 381.357457 -0.03695)
			(xy 381.434217 -0.075172) (xy 381.507123 -0.120313) (xy 381.575552 -0.171989) (xy 381.638922 -0.229758)
			(xy 381.696691 -0.293128) (xy 381.748367 -0.361557) (xy 381.793508 -0.434463) (xy 381.83173 -0.511223)
			(xy 381.862706 -0.591182) (xy 381.886173 -0.673658) (xy 381.901929 -0.757948) (xy 381.909841 -0.843331)
			(xy 381.910336 -0.886206) (xy 381.909841 -0.929081) (xy 381.901929 -1.014464) (xy 381.886173 -1.098754)
			(xy 381.862706 -1.18123) (xy 381.83173 -1.261189) (xy 381.793508 -1.337949) (xy 381.748367 -1.410855)
			(xy 381.696691 -1.479284) (xy 381.638922 -1.542654) (xy 381.575552 -1.600423) (xy 381.507123 -1.652099)
			(xy 381.434217 -1.69724) (xy 381.357457 -1.735462) (xy 381.277498 -1.766438) (xy 381.195022 -1.789905)
			(xy 381.110732 -1.805661) (xy 381.025349 -1.813573) (xy 380.939599 -1.813573) (xy 380.854216 -1.805661)
			(xy 380.769926 -1.789905) (xy 380.68745 -1.766438) (xy 380.607491 -1.735462) (xy 380.530731 -1.69724)
			(xy 380.457825 -1.652099) (xy 380.389396 -1.600423) (xy 380.326026 -1.542654) (xy 380.268257 -1.479284)
			(xy 380.216581 -1.410855) (xy 380.17144 -1.337949) (xy 380.133218 -1.261189) (xy 380.102242 -1.18123)
			(xy 380.078775 -1.098754) (xy 380.063019 -1.014464) (xy 380.055107 -0.929081) (xy 375.559841 -0.929081)
			(xy 375.551929 -1.014464) (xy 375.536173 -1.098754) (xy 375.512706 -1.18123) (xy 375.48173 -1.261189)
			(xy 375.443508 -1.337949) (xy 375.398367 -1.410855) (xy 375.346691 -1.479284) (xy 375.288922 -1.542654)
			(xy 375.225552 -1.600423) (xy 375.157123 -1.652099) (xy 375.084217 -1.69724) (xy 375.007457 -1.735462)
			(xy 374.927498 -1.766438) (xy 374.845022 -1.789905) (xy 374.760732 -1.805661) (xy 374.675349 -1.813573)
			(xy 374.589599 -1.813573) (xy 374.504216 -1.805661) (xy 374.419926 -1.789905) (xy 374.33745 -1.766438)
			(xy 374.257491 -1.735462) (xy 374.180731 -1.69724) (xy 374.107825 -1.652099) (xy 374.039396 -1.600423)
			(xy 373.976026 -1.542654) (xy 373.918257 -1.479284) (xy 373.866581 -1.410855) (xy 373.82144 -1.337949)
			(xy 373.783218 -1.261189) (xy 373.752242 -1.18123) (xy 373.728775 -1.098754) (xy 373.713019 -1.014464)
			(xy 373.705107 -0.929081) (xy 343.693001 -0.929081) (xy 343.685089 -1.014464) (xy 343.669333 -1.098754)
			(xy 343.645866 -1.18123) (xy 343.61489 -1.261189) (xy 343.576668 -1.337949) (xy 343.531527 -1.410855)
			(xy 343.479851 -1.479284) (xy 343.422082 -1.542654) (xy 343.358712 -1.600423) (xy 343.290283 -1.652099)
			(xy 343.217377 -1.69724) (xy 343.140617 -1.735462) (xy 343.060658 -1.766438) (xy 342.978182 -1.789905)
			(xy 342.893892 -1.805661) (xy 342.808509 -1.813573) (xy 342.722759 -1.813573) (xy 342.637376 -1.805661)
			(xy 342.553086 -1.789905) (xy 342.47061 -1.766438) (xy 342.390651 -1.735462) (xy 342.313891 -1.69724)
			(xy 342.240985 -1.652099) (xy 342.172556 -1.600423) (xy 342.109186 -1.542654) (xy 342.051417 -1.479284)
			(xy 341.999741 -1.410855) (xy 341.9546 -1.337949) (xy 341.916378 -1.261189) (xy 341.885402 -1.18123)
			(xy 341.861935 -1.098754) (xy 341.846179 -1.014464) (xy 341.838267 -0.929081) (xy 337.343001 -0.929081)
			(xy 337.335089 -1.014464) (xy 337.319333 -1.098754) (xy 337.295866 -1.18123) (xy 337.26489 -1.261189)
			(xy 337.226668 -1.337949) (xy 337.181527 -1.410855) (xy 337.129851 -1.479284) (xy 337.072082 -1.542654)
			(xy 337.008712 -1.600423) (xy 336.940283 -1.652099) (xy 336.867377 -1.69724) (xy 336.790617 -1.735462)
			(xy 336.710658 -1.766438) (xy 336.628182 -1.789905) (xy 336.543892 -1.805661) (xy 336.458509 -1.813573)
			(xy 336.372759 -1.813573) (xy 336.287376 -1.805661) (xy 336.203086 -1.789905) (xy 336.12061 -1.766438)
			(xy 336.040651 -1.735462) (xy 335.963891 -1.69724) (xy 335.890985 -1.652099) (xy 335.822556 -1.600423)
			(xy 335.759186 -1.542654) (xy 335.701417 -1.479284) (xy 335.649741 -1.410855) (xy 335.6046 -1.337949)
			(xy 335.566378 -1.261189) (xy 335.535402 -1.18123) (xy 335.511935 -1.098754) (xy 335.496179 -1.014464)
			(xy 335.488267 -0.929081) (xy 333.050655 -0.929081) (xy 333.042743 -1.014464) (xy 333.026987 -1.098754)
			(xy 333.00352 -1.18123) (xy 332.972544 -1.261189) (xy 332.934322 -1.337949) (xy 332.889181 -1.410855)
			(xy 332.837505 -1.479284) (xy 332.779736 -1.542654) (xy 332.716366 -1.600423) (xy 332.647937 -1.652099)
			(xy 332.575031 -1.69724) (xy 332.498271 -1.735462) (xy 332.418312 -1.766438) (xy 332.335836 -1.789905)
			(xy 332.251546 -1.805661) (xy 332.166163 -1.813573) (xy 332.080413 -1.813573) (xy 331.99503 -1.805661)
			(xy 331.91074 -1.789905) (xy 331.828264 -1.766438) (xy 331.748305 -1.735462) (xy 331.671545 -1.69724)
			(xy 331.598639 -1.652099) (xy 331.53021 -1.600423) (xy 331.46684 -1.542654) (xy 331.409071 -1.479284)
			(xy 331.357395 -1.410855) (xy 331.312254 -1.337949) (xy 331.274032 -1.261189) (xy 331.243056 -1.18123)
			(xy 331.219589 -1.098754) (xy 331.203833 -1.014464) (xy 331.195921 -0.929081) (xy 326.700655 -0.929081)
			(xy 326.692743 -1.014464) (xy 326.676987 -1.098754) (xy 326.65352 -1.18123) (xy 326.622544 -1.261189)
			(xy 326.584322 -1.337949) (xy 326.539181 -1.410855) (xy 326.487505 -1.479284) (xy 326.429736 -1.542654)
			(xy 326.366366 -1.600423) (xy 326.297937 -1.652099) (xy 326.225031 -1.69724) (xy 326.148271 -1.735462)
			(xy 326.068312 -1.766438) (xy 325.985836 -1.789905) (xy 325.901546 -1.805661) (xy 325.816163 -1.813573)
			(xy 325.730413 -1.813573) (xy 325.64503 -1.805661) (xy 325.56074 -1.789905) (xy 325.478264 -1.766438)
			(xy 325.398305 -1.735462) (xy 325.321545 -1.69724) (xy 325.248639 -1.652099) (xy 325.18021 -1.600423)
			(xy 325.11684 -1.542654) (xy 325.059071 -1.479284) (xy 325.007395 -1.410855) (xy 324.962254 -1.337949)
			(xy 324.924032 -1.261189) (xy 324.893056 -1.18123) (xy 324.869589 -1.098754) (xy 324.853833 -1.014464)
			(xy 324.845921 -0.929081) (xy 265.125975 -0.929081) (xy 265.118063 -1.014464) (xy 265.102307 -1.098754)
			(xy 265.07884 -1.18123) (xy 265.047864 -1.261189) (xy 265.009642 -1.337949) (xy 264.964501 -1.410855)
			(xy 264.912825 -1.479284) (xy 264.855056 -1.542654) (xy 264.791686 -1.600423) (xy 264.723257 -1.652099)
			(xy 264.650351 -1.69724) (xy 264.573591 -1.735462) (xy 264.493632 -1.766438) (xy 264.411156 -1.789905)
			(xy 264.326866 -1.805661) (xy 264.241483 -1.813573) (xy 264.155733 -1.813573) (xy 264.07035 -1.805661)
			(xy 263.98606 -1.789905) (xy 263.903584 -1.766438) (xy 263.823625 -1.735462) (xy 263.746865 -1.69724)
			(xy 263.673959 -1.652099) (xy 263.60553 -1.600423) (xy 263.54216 -1.542654) (xy 263.484391 -1.479284)
			(xy 263.432715 -1.410855) (xy 263.387574 -1.337949) (xy 263.349352 -1.261189) (xy 263.318376 -1.18123)
			(xy 263.294909 -1.098754) (xy 263.279153 -1.014464) (xy 263.271241 -0.929081) (xy 258.775975 -0.929081)
			(xy 258.768063 -1.014464) (xy 258.752307 -1.098754) (xy 258.72884 -1.18123) (xy 258.697864 -1.261189)
			(xy 258.659642 -1.337949) (xy 258.614501 -1.410855) (xy 258.562825 -1.479284) (xy 258.505056 -1.542654)
			(xy 258.441686 -1.600423) (xy 258.373257 -1.652099) (xy 258.300351 -1.69724) (xy 258.223591 -1.735462)
			(xy 258.143632 -1.766438) (xy 258.061156 -1.789905) (xy 257.976866 -1.805661) (xy 257.891483 -1.813573)
			(xy 257.805733 -1.813573) (xy 257.72035 -1.805661) (xy 257.63606 -1.789905) (xy 257.553584 -1.766438)
			(xy 257.473625 -1.735462) (xy 257.396865 -1.69724) (xy 257.323959 -1.652099) (xy 257.25553 -1.600423)
			(xy 257.19216 -1.542654) (xy 257.134391 -1.479284) (xy 257.082715 -1.410855) (xy 257.037574 -1.337949)
			(xy 256.999352 -1.261189) (xy 256.968376 -1.18123) (xy 256.944909 -1.098754) (xy 256.929153 -1.014464)
			(xy 256.921241 -0.929081) (xy 254.465119 -0.929081) (xy 254.465087 -0.931875) (xy 254.457175 -1.017258)
			(xy 254.441419 -1.101548) (xy 254.417952 -1.184024) (xy 254.386976 -1.263983) (xy 254.348754 -1.340743)
			(xy 254.303613 -1.413649) (xy 254.251937 -1.482078) (xy 254.194168 -1.545448) (xy 254.130798 -1.603217)
			(xy 254.062369 -1.654893) (xy 253.989463 -1.700034) (xy 253.912703 -1.738256) (xy 253.832744 -1.769232)
			(xy 253.750268 -1.792699) (xy 253.665978 -1.808455) (xy 253.580595 -1.816367) (xy 253.494845 -1.816367)
			(xy 253.409462 -1.808455) (xy 253.325172 -1.792699) (xy 253.242696 -1.769232) (xy 253.162737 -1.738256)
			(xy 253.085977 -1.700034) (xy 253.013071 -1.654893) (xy 252.944642 -1.603217) (xy 252.881272 -1.545448)
			(xy 252.823503 -1.482078) (xy 252.771827 -1.413649) (xy 252.726686 -1.340743) (xy 252.688464 -1.263983)
			(xy 252.657488 -1.184024) (xy 252.634021 -1.101548) (xy 252.618265 -1.017258) (xy 252.610353 -0.931875)
			(xy 248.115087 -0.931875) (xy 248.107175 -1.017258) (xy 248.091419 -1.101548) (xy 248.067952 -1.184024)
			(xy 248.036976 -1.263983) (xy 247.998754 -1.340743) (xy 247.953613 -1.413649) (xy 247.901937 -1.482078)
			(xy 247.844168 -1.545448) (xy 247.780798 -1.603217) (xy 247.712369 -1.654893) (xy 247.639463 -1.700034)
			(xy 247.562703 -1.738256) (xy 247.482744 -1.769232) (xy 247.400268 -1.792699) (xy 247.315978 -1.808455)
			(xy 247.230595 -1.816367) (xy 247.144845 -1.816367) (xy 247.059462 -1.808455) (xy 246.975172 -1.792699)
			(xy 246.892696 -1.769232) (xy 246.812737 -1.738256) (xy 246.735977 -1.700034) (xy 246.663071 -1.654893)
			(xy 246.594642 -1.603217) (xy 246.531272 -1.545448) (xy 246.473503 -1.482078) (xy 246.421827 -1.413649)
			(xy 246.376686 -1.340743) (xy 246.338464 -1.263983) (xy 246.307488 -1.184024) (xy 246.284021 -1.101548)
			(xy 246.268265 -1.017258) (xy 246.260353 -0.931875) (xy 216.248247 -0.931875) (xy 216.240335 -1.017258)
			(xy 216.224579 -1.101548) (xy 216.201112 -1.184024) (xy 216.170136 -1.263983) (xy 216.131914 -1.340743)
			(xy 216.086773 -1.413649) (xy 216.035097 -1.482078) (xy 215.977328 -1.545448) (xy 215.913958 -1.603217)
			(xy 215.845529 -1.654893) (xy 215.772623 -1.700034) (xy 215.695863 -1.738256) (xy 215.615904 -1.769232)
			(xy 215.533428 -1.792699) (xy 215.449138 -1.808455) (xy 215.363755 -1.816367) (xy 215.278005 -1.816367)
			(xy 215.192622 -1.808455) (xy 215.108332 -1.792699) (xy 215.025856 -1.769232) (xy 214.945897 -1.738256)
			(xy 214.869137 -1.700034) (xy 214.796231 -1.654893) (xy 214.727802 -1.603217) (xy 214.664432 -1.545448)
			(xy 214.606663 -1.482078) (xy 214.554987 -1.413649) (xy 214.509846 -1.340743) (xy 214.471624 -1.263983)
			(xy 214.440648 -1.184024) (xy 214.417181 -1.101548) (xy 214.401425 -1.017258) (xy 214.393513 -0.931875)
			(xy 209.898247 -0.931875) (xy 209.890335 -1.017258) (xy 209.874579 -1.101548) (xy 209.851112 -1.184024)
			(xy 209.820136 -1.263983) (xy 209.781914 -1.340743) (xy 209.736773 -1.413649) (xy 209.685097 -1.482078)
			(xy 209.627328 -1.545448) (xy 209.563958 -1.603217) (xy 209.495529 -1.654893) (xy 209.422623 -1.700034)
			(xy 209.345863 -1.738256) (xy 209.265904 -1.769232) (xy 209.183428 -1.792699) (xy 209.099138 -1.808455)
			(xy 209.013755 -1.816367) (xy 208.928005 -1.816367) (xy 208.842622 -1.808455) (xy 208.758332 -1.792699)
			(xy 208.675856 -1.769232) (xy 208.595897 -1.738256) (xy 208.519137 -1.700034) (xy 208.446231 -1.654893)
			(xy 208.377802 -1.603217) (xy 208.314432 -1.545448) (xy 208.256663 -1.482078) (xy 208.204987 -1.413649)
			(xy 208.159846 -1.340743) (xy 208.121624 -1.263983) (xy 208.090648 -1.184024) (xy 208.067181 -1.101548)
			(xy 208.051425 -1.017258) (xy 208.043513 -0.931875) (xy 84.20989 -0.931875) (xy 84.20989 -7.78002)
			(xy 84.210412 -7.835827) (xy 84.218755 -7.947128) (xy 84.235391 -8.057495) (xy 84.260229 -8.16631)
			(xy 84.293128 -8.272964) (xy 84.333906 -8.376862) (xy 84.382334 -8.477422) (xy 84.438141 -8.574082)
			(xy 84.501016 -8.666301) (xy 84.570606 -8.753563) (xy 84.646523 -8.835382) (xy 84.728341 -8.911298)
			(xy 84.815604 -8.980888) (xy 84.907824 -9.043762) (xy 85.004484 -9.099569) (xy 85.105044 -9.147996)
			(xy 85.208942 -9.188774) (xy 85.315596 -9.221673) (xy 85.424411 -9.24651) (xy 85.534778 -9.263146)
			(xy 85.646079 -9.271488) (xy 85.701886 -9.272016) (xy 122.102118 -9.272016) (xy 122.157925 -9.271494)
			(xy 122.269226 -9.263152) (xy 122.379593 -9.246515) (xy 122.488409 -9.221678) (xy 122.595063 -9.188778)
			(xy 122.698961 -9.148001) (xy 122.799522 -9.099573) (xy 122.896182 -9.043766) (xy 122.988401 -8.980891)
			(xy 123.075664 -8.911301) (xy 123.157483 -8.835384) (xy 123.2334 -8.753566) (xy 123.30299 -8.666303)
			(xy 123.365865 -8.574084) (xy 123.421672 -8.477423) (xy 123.4701 -8.376863) (xy 123.510878 -8.272965)
			(xy 123.543777 -8.16631) (xy 123.568615 -8.057495) (xy 123.585251 -7.947128) (xy 123.593594 -7.835827)
			(xy 123.594114 -7.78002) (xy 123.594114 -4.2799) (xy 123.594598 -4.209546) (xy 123.602488 -4.06906)
			(xy 123.618242 -3.929237) (xy 123.641812 -3.790517) (xy 123.673122 -3.653337) (xy 123.712075 -3.518129)
			(xy 123.758548 -3.385317) (xy 123.812395 -3.25532) (xy 123.873446 -3.128547) (xy 123.941509 -3.005396)
			(xy 124.01637 -2.886255) (xy 124.097794 -2.7715) (xy 124.185524 -2.66149) (xy 124.279284 -2.556573)
			(xy 124.37878 -2.457077) (xy 124.483698 -2.363317) (xy 124.593708 -2.275588) (xy 124.708464 -2.194165)
			(xy 124.827605 -2.119304) (xy 124.950755 -2.051241) (xy 125.077529 -1.990191) (xy 125.207526 -1.936345)
			(xy 125.340338 -1.889872) (xy 125.475547 -1.85092) (xy 125.612727 -1.81961) (xy 125.751447 -1.796041)
			(xy 125.89127 -1.780287) (xy 126.031756 -1.772398) (xy 126.10211 -1.771904) (xy 194.701922 -1.771904)
			(xy 194.772275 -1.772398) (xy 194.912761 -1.780289) (xy 195.052582 -1.796044) (xy 195.191301 -1.819614)
			(xy 195.32848 -1.850925) (xy 195.463687 -1.889879) (xy 195.596497 -1.936352) (xy 195.726493 -1.990199)
			(xy 195.853265 -2.05125) (xy 195.976414 -2.119314) (xy 196.095554 -2.194175) (xy 196.210308 -2.275598)
			(xy 196.320316 -2.363328) (xy 196.425233 -2.457088) (xy 196.524727 -2.556583) (xy 196.618486 -2.6615)
			(xy 196.706215 -2.77151) (xy 196.787637 -2.886265) (xy 196.862497 -3.005405) (xy 196.93056 -3.128555)
			(xy 196.99161 -3.255327) (xy 197.045455 -3.385323) (xy 197.075741 -3.471875) (xy 208.043513 -3.471875)
			(xy 208.043513 -3.386125) (xy 208.051425 -3.300742) (xy 208.067181 -3.216452) (xy 208.090648 -3.133976)
			(xy 208.121624 -3.054017) (xy 208.159846 -2.977257) (xy 208.204987 -2.904351) (xy 208.256663 -2.835922)
			(xy 208.314432 -2.772552) (xy 208.377802 -2.714783) (xy 208.446231 -2.663107) (xy 208.519137 -2.617966)
			(xy 208.595897 -2.579744) (xy 208.675856 -2.548768) (xy 208.758332 -2.525301) (xy 208.842622 -2.509545)
			(xy 208.928005 -2.501633) (xy 209.013755 -2.501633) (xy 209.099138 -2.509545) (xy 209.183428 -2.525301)
			(xy 209.265904 -2.548768) (xy 209.345863 -2.579744) (xy 209.368066 -2.5908) (xy 212.978492 -2.5908)
			(xy 212.978492 -1.7272) (xy 212.978978 -1.699931) (xy 212.98674 -1.645947) (xy 213.002105 -1.593617)
			(xy 213.024762 -1.544007) (xy 213.054248 -1.498126) (xy 213.089963 -1.456909) (xy 213.13118 -1.421194)
			(xy 213.177061 -1.391708) (xy 213.226671 -1.369051) (xy 213.279001 -1.353686) (xy 213.332985 -1.345924)
			(xy 213.387523 -1.345924) (xy 213.441507 -1.353686) (xy 213.493837 -1.369051) (xy 213.543447 -1.391708)
			(xy 213.589328 -1.421194) (xy 213.630545 -1.456909) (xy 213.66626 -1.498126) (xy 213.695746 -1.544007)
			(xy 213.718403 -1.593617) (xy 213.733768 -1.645947) (xy 213.74153 -1.699931) (xy 213.742016 -1.7272)
			(xy 213.742016 -2.5908) (xy 213.74153 -2.618069) (xy 213.733768 -2.672053) (xy 213.718403 -2.724383)
			(xy 213.695746 -2.773993) (xy 213.66626 -2.819874) (xy 213.630545 -2.861091) (xy 213.589328 -2.896806)
			(xy 213.543447 -2.926292) (xy 213.493837 -2.948949) (xy 213.441507 -2.964314) (xy 213.387523 -2.972076)
			(xy 213.332985 -2.972076) (xy 213.279001 -2.964314) (xy 213.226671 -2.948949) (xy 213.177061 -2.926292)
			(xy 213.13118 -2.896806) (xy 213.089963 -2.861091) (xy 213.054248 -2.819874) (xy 213.024762 -2.773993)
			(xy 213.002105 -2.724383) (xy 212.98674 -2.672053) (xy 212.978978 -2.618069) (xy 212.978492 -2.5908)
			(xy 209.368066 -2.5908) (xy 209.422623 -2.617966) (xy 209.495529 -2.663107) (xy 209.563958 -2.714783)
			(xy 209.627328 -2.772552) (xy 209.685097 -2.835922) (xy 209.736773 -2.904351) (xy 209.781914 -2.977257)
			(xy 209.820136 -3.054017) (xy 209.851112 -3.133976) (xy 209.874579 -3.216452) (xy 209.890335 -3.300742)
			(xy 209.898247 -3.386125) (xy 209.898742 -3.429) (xy 209.898247 -3.471875) (xy 214.393513 -3.471875)
			(xy 214.393513 -3.386125) (xy 214.401425 -3.300742) (xy 214.417181 -3.216452) (xy 214.440648 -3.133976)
			(xy 214.471624 -3.054017) (xy 214.509846 -2.977257) (xy 214.554987 -2.904351) (xy 214.606663 -2.835922)
			(xy 214.664432 -2.772552) (xy 214.727802 -2.714783) (xy 214.796231 -2.663107) (xy 214.869137 -2.617966)
			(xy 214.945897 -2.579744) (xy 215.025856 -2.548768) (xy 215.108332 -2.525301) (xy 215.192622 -2.509545)
			(xy 215.278005 -2.501633) (xy 215.363755 -2.501633) (xy 215.449138 -2.509545) (xy 215.533428 -2.525301)
			(xy 215.615904 -2.548768) (xy 215.695863 -2.579744) (xy 215.772623 -2.617966) (xy 215.845529 -2.663107)
			(xy 215.913958 -2.714783) (xy 215.977328 -2.772552) (xy 216.035097 -2.835922) (xy 216.086773 -2.904351)
			(xy 216.131914 -2.977257) (xy 216.170136 -3.054017) (xy 216.201112 -3.133976) (xy 216.224579 -3.216452)
			(xy 216.240335 -3.300742) (xy 216.248247 -3.386125) (xy 216.248742 -3.429) (xy 216.248247 -3.471875)
			(xy 246.260353 -3.471875) (xy 246.260353 -3.386125) (xy 246.268265 -3.300742) (xy 246.284021 -3.216452)
			(xy 246.307488 -3.133976) (xy 246.338464 -3.054017) (xy 246.376686 -2.977257) (xy 246.421827 -2.904351)
			(xy 246.473503 -2.835922) (xy 246.531272 -2.772552) (xy 246.594642 -2.714783) (xy 246.663071 -2.663107)
			(xy 246.735977 -2.617966) (xy 246.812737 -2.579744) (xy 246.892696 -2.548768) (xy 246.975172 -2.525301)
			(xy 247.059462 -2.509545) (xy 247.144845 -2.501633) (xy 247.230595 -2.501633) (xy 247.315978 -2.509545)
			(xy 247.400268 -2.525301) (xy 247.482744 -2.548768) (xy 247.562703 -2.579744) (xy 247.584906 -2.5908)
			(xy 248.766584 -2.5908) (xy 248.766584 -1.7272) (xy 248.76707 -1.699931) (xy 248.774832 -1.645947)
			(xy 248.790197 -1.593617) (xy 248.812854 -1.544007) (xy 248.84234 -1.498126) (xy 248.878055 -1.456909)
			(xy 248.919272 -1.421194) (xy 248.965153 -1.391708) (xy 249.014763 -1.369051) (xy 249.067093 -1.353686)
			(xy 249.121077 -1.345924) (xy 249.175615 -1.345924) (xy 249.229599 -1.353686) (xy 249.281929 -1.369051)
			(xy 249.331539 -1.391708) (xy 249.37742 -1.421194) (xy 249.418637 -1.456909) (xy 249.454352 -1.498126)
			(xy 249.483838 -1.544007) (xy 249.506495 -1.593617) (xy 249.52186 -1.645947) (xy 249.529622 -1.699931)
			(xy 249.530108 -1.7272) (xy 249.530108 -2.5908) (xy 249.529622 -2.618069) (xy 249.52186 -2.672053)
			(xy 249.506495 -2.724383) (xy 249.483838 -2.773993) (xy 249.454352 -2.819874) (xy 249.418637 -2.861091)
			(xy 249.37742 -2.896806) (xy 249.331539 -2.926292) (xy 249.281929 -2.948949) (xy 249.229599 -2.964314)
			(xy 249.175615 -2.972076) (xy 249.121077 -2.972076) (xy 249.067093 -2.964314) (xy 249.014763 -2.948949)
			(xy 248.965153 -2.926292) (xy 248.919272 -2.896806) (xy 248.878055 -2.861091) (xy 248.84234 -2.819874)
			(xy 248.812854 -2.773993) (xy 248.790197 -2.724383) (xy 248.774832 -2.672053) (xy 248.76707 -2.618069)
			(xy 248.766584 -2.5908) (xy 247.584906 -2.5908) (xy 247.639463 -2.617966) (xy 247.712369 -2.663107)
			(xy 247.780798 -2.714783) (xy 247.844168 -2.772552) (xy 247.901937 -2.835922) (xy 247.953613 -2.904351)
			(xy 247.998754 -2.977257) (xy 248.036976 -3.054017) (xy 248.067952 -3.133976) (xy 248.091419 -3.216452)
			(xy 248.107175 -3.300742) (xy 248.115087 -3.386125) (xy 248.115582 -3.429) (xy 248.115087 -3.471875)
			(xy 252.610353 -3.471875) (xy 252.610353 -3.386125) (xy 252.618265 -3.300742) (xy 252.634021 -3.216452)
			(xy 252.657488 -3.133976) (xy 252.688464 -3.054017) (xy 252.726686 -2.977257) (xy 252.771827 -2.904351)
			(xy 252.823503 -2.835922) (xy 252.881272 -2.772552) (xy 252.944642 -2.714783) (xy 253.013071 -2.663107)
			(xy 253.085977 -2.617966) (xy 253.162737 -2.579744) (xy 253.242696 -2.548768) (xy 253.325172 -2.525301)
			(xy 253.409462 -2.509545) (xy 253.494845 -2.501633) (xy 253.580595 -2.501633) (xy 253.665978 -2.509545)
			(xy 253.750268 -2.525301) (xy 253.832744 -2.548768) (xy 253.912703 -2.579744) (xy 253.989463 -2.617966)
			(xy 254.062369 -2.663107) (xy 254.130798 -2.714783) (xy 254.194168 -2.772552) (xy 254.251937 -2.835922)
			(xy 254.303613 -2.904351) (xy 254.348754 -2.977257) (xy 254.386976 -3.054017) (xy 254.417952 -3.133976)
			(xy 254.441419 -3.216452) (xy 254.457175 -3.300742) (xy 254.465087 -3.386125) (xy 254.465582 -3.429)
			(xy 254.465119 -3.469081) (xy 256.921241 -3.469081) (xy 256.921241 -3.383331) (xy 256.929153 -3.297948)
			(xy 256.944909 -3.213658) (xy 256.968376 -3.131182) (xy 256.999352 -3.051223) (xy 257.037574 -2.974463)
			(xy 257.082715 -2.901557) (xy 257.134391 -2.833128) (xy 257.19216 -2.769758) (xy 257.25553 -2.711989)
			(xy 257.323959 -2.660313) (xy 257.396865 -2.615172) (xy 257.473625 -2.57695) (xy 257.553584 -2.545974)
			(xy 257.63606 -2.522507) (xy 257.72035 -2.506751) (xy 257.805733 -2.498839) (xy 257.891483 -2.498839)
			(xy 257.976866 -2.506751) (xy 258.061156 -2.522507) (xy 258.143632 -2.545974) (xy 258.223591 -2.57695)
			(xy 258.300351 -2.615172) (xy 258.373257 -2.660313) (xy 258.441686 -2.711989) (xy 258.505056 -2.769758)
			(xy 258.562825 -2.833128) (xy 258.614501 -2.901557) (xy 258.659642 -2.974463) (xy 258.697864 -3.051223)
			(xy 258.72884 -3.131182) (xy 258.752307 -3.213658) (xy 258.768063 -3.297948) (xy 258.775975 -3.383331)
			(xy 258.77647 -3.426206) (xy 258.775975 -3.469081) (xy 263.271241 -3.469081) (xy 263.271241 -3.383331)
			(xy 263.279153 -3.297948) (xy 263.294909 -3.213658) (xy 263.318376 -3.131182) (xy 263.349352 -3.051223)
			(xy 263.387574 -2.974463) (xy 263.432715 -2.901557) (xy 263.484391 -2.833128) (xy 263.54216 -2.769758)
			(xy 263.60553 -2.711989) (xy 263.673959 -2.660313) (xy 263.746865 -2.615172) (xy 263.823625 -2.57695)
			(xy 263.903584 -2.545974) (xy 263.98606 -2.522507) (xy 264.07035 -2.506751) (xy 264.155733 -2.498839)
			(xy 264.241483 -2.498839) (xy 264.326866 -2.506751) (xy 264.411156 -2.522507) (xy 264.493632 -2.545974)
			(xy 264.573591 -2.57695) (xy 264.650351 -2.615172) (xy 264.723257 -2.660313) (xy 264.791686 -2.711989)
			(xy 264.855056 -2.769758) (xy 264.912825 -2.833128) (xy 264.964501 -2.901557) (xy 265.009642 -2.974463)
			(xy 265.047864 -3.051223) (xy 265.07884 -3.131182) (xy 265.102307 -3.213658) (xy 265.118063 -3.297948)
			(xy 265.125975 -3.383331) (xy 265.12647 -3.426206) (xy 265.125975 -3.469081) (xy 324.845921 -3.469081)
			(xy 324.845921 -3.383331) (xy 324.853833 -3.297948) (xy 324.869589 -3.213658) (xy 324.893056 -3.131182)
			(xy 324.924032 -3.051223) (xy 324.962254 -2.974463) (xy 325.007395 -2.901557) (xy 325.059071 -2.833128)
			(xy 325.11684 -2.769758) (xy 325.18021 -2.711989) (xy 325.248639 -2.660313) (xy 325.321545 -2.615172)
			(xy 325.398305 -2.57695) (xy 325.478264 -2.545974) (xy 325.56074 -2.522507) (xy 325.64503 -2.506751)
			(xy 325.730413 -2.498839) (xy 325.816163 -2.498839) (xy 325.901546 -2.506751) (xy 325.985836 -2.522507)
			(xy 326.068312 -2.545974) (xy 326.148271 -2.57695) (xy 326.225031 -2.615172) (xy 326.297937 -2.660313)
			(xy 326.366366 -2.711989) (xy 326.429736 -2.769758) (xy 326.487505 -2.833128) (xy 326.539181 -2.901557)
			(xy 326.584322 -2.974463) (xy 326.622544 -3.051223) (xy 326.65352 -3.131182) (xy 326.676987 -3.213658)
			(xy 326.692743 -3.297948) (xy 326.700655 -3.383331) (xy 326.70115 -3.426206) (xy 326.700655 -3.469081)
			(xy 331.195921 -3.469081) (xy 331.195921 -3.383331) (xy 331.203833 -3.297948) (xy 331.219589 -3.213658)
			(xy 331.243056 -3.131182) (xy 331.274032 -3.051223) (xy 331.312254 -2.974463) (xy 331.357395 -2.901557)
			(xy 331.409071 -2.833128) (xy 331.46684 -2.769758) (xy 331.53021 -2.711989) (xy 331.598639 -2.660313)
			(xy 331.671545 -2.615172) (xy 331.748305 -2.57695) (xy 331.828264 -2.545974) (xy 331.91074 -2.522507)
			(xy 331.99503 -2.506751) (xy 332.080413 -2.498839) (xy 332.166163 -2.498839) (xy 332.251546 -2.506751)
			(xy 332.335836 -2.522507) (xy 332.418312 -2.545974) (xy 332.498271 -2.57695) (xy 332.575031 -2.615172)
			(xy 332.647937 -2.660313) (xy 332.716366 -2.711989) (xy 332.779736 -2.769758) (xy 332.837505 -2.833128)
			(xy 332.889181 -2.901557) (xy 332.934322 -2.974463) (xy 332.972544 -3.051223) (xy 333.00352 -3.131182)
			(xy 333.026987 -3.213658) (xy 333.042743 -3.297948) (xy 333.050655 -3.383331) (xy 333.05115 -3.426206)
			(xy 333.050655 -3.469081) (xy 335.488267 -3.469081) (xy 335.488267 -3.383331) (xy 335.496179 -3.297948)
			(xy 335.511935 -3.213658) (xy 335.535402 -3.131182) (xy 335.566378 -3.051223) (xy 335.6046 -2.974463)
			(xy 335.649741 -2.901557) (xy 335.701417 -2.833128) (xy 335.759186 -2.769758) (xy 335.822556 -2.711989)
			(xy 335.890985 -2.660313) (xy 335.963891 -2.615172) (xy 336.040651 -2.57695) (xy 336.12061 -2.545974)
			(xy 336.203086 -2.522507) (xy 336.287376 -2.506751) (xy 336.372759 -2.498839) (xy 336.458509 -2.498839)
			(xy 336.543892 -2.506751) (xy 336.628182 -2.522507) (xy 336.710658 -2.545974) (xy 336.790617 -2.57695)
			(xy 336.867377 -2.615172) (xy 336.940283 -2.660313) (xy 337.008712 -2.711989) (xy 337.072082 -2.769758)
			(xy 337.129851 -2.833128) (xy 337.181527 -2.901557) (xy 337.226668 -2.974463) (xy 337.26489 -3.051223)
			(xy 337.295866 -3.131182) (xy 337.319333 -3.213658) (xy 337.335089 -3.297948) (xy 337.343001 -3.383331)
			(xy 337.343496 -3.426206) (xy 337.343001 -3.469081) (xy 341.838267 -3.469081) (xy 341.838267 -3.383331)
			(xy 341.846179 -3.297948) (xy 341.861935 -3.213658) (xy 341.885402 -3.131182) (xy 341.916378 -3.051223)
			(xy 341.9546 -2.974463) (xy 341.999741 -2.901557) (xy 342.051417 -2.833128) (xy 342.109186 -2.769758)
			(xy 342.172556 -2.711989) (xy 342.240985 -2.660313) (xy 342.313891 -2.615172) (xy 342.390651 -2.57695)
			(xy 342.47061 -2.545974) (xy 342.553086 -2.522507) (xy 342.637376 -2.506751) (xy 342.722759 -2.498839)
			(xy 342.808509 -2.498839) (xy 342.893892 -2.506751) (xy 342.978182 -2.522507) (xy 343.060658 -2.545974)
			(xy 343.140617 -2.57695) (xy 343.217377 -2.615172) (xy 343.290283 -2.660313) (xy 343.358712 -2.711989)
			(xy 343.422082 -2.769758) (xy 343.479851 -2.833128) (xy 343.531527 -2.901557) (xy 343.576668 -2.974463)
			(xy 343.61489 -3.051223) (xy 343.645866 -3.131182) (xy 343.669333 -3.213658) (xy 343.685089 -3.297948)
			(xy 343.693001 -3.383331) (xy 343.693496 -3.426206) (xy 343.693001 -3.469081) (xy 373.705107 -3.469081)
			(xy 373.705107 -3.383331) (xy 373.713019 -3.297948) (xy 373.728775 -3.213658) (xy 373.752242 -3.131182)
			(xy 373.783218 -3.051223) (xy 373.82144 -2.974463) (xy 373.866581 -2.901557) (xy 373.918257 -2.833128)
			(xy 373.976026 -2.769758) (xy 374.039396 -2.711989) (xy 374.107825 -2.660313) (xy 374.180731 -2.615172)
			(xy 374.257491 -2.57695) (xy 374.33745 -2.545974) (xy 374.419926 -2.522507) (xy 374.504216 -2.506751)
			(xy 374.589599 -2.498839) (xy 374.675349 -2.498839) (xy 374.760732 -2.506751) (xy 374.845022 -2.522507)
			(xy 374.927498 -2.545974) (xy 375.007457 -2.57695) (xy 375.084217 -2.615172) (xy 375.157123 -2.660313)
			(xy 375.225552 -2.711989) (xy 375.288922 -2.769758) (xy 375.346691 -2.833128) (xy 375.398367 -2.901557)
			(xy 375.443508 -2.974463) (xy 375.48173 -3.051223) (xy 375.512706 -3.131182) (xy 375.536173 -3.213658)
			(xy 375.551929 -3.297948) (xy 375.559841 -3.383331) (xy 375.560336 -3.426206) (xy 375.559841 -3.469081)
			(xy 380.055107 -3.469081) (xy 380.055107 -3.383331) (xy 380.063019 -3.297948) (xy 380.078775 -3.213658)
			(xy 380.102242 -3.131182) (xy 380.133218 -3.051223) (xy 380.17144 -2.974463) (xy 380.216581 -2.901557)
			(xy 380.268257 -2.833128) (xy 380.326026 -2.769758) (xy 380.389396 -2.711989) (xy 380.457825 -2.660313)
			(xy 380.530731 -2.615172) (xy 380.607491 -2.57695) (xy 380.68745 -2.545974) (xy 380.769926 -2.522507)
			(xy 380.854216 -2.506751) (xy 380.939599 -2.498839) (xy 381.025349 -2.498839) (xy 381.110732 -2.506751)
			(xy 381.195022 -2.522507) (xy 381.277498 -2.545974) (xy 381.357457 -2.57695) (xy 381.434217 -2.615172)
			(xy 381.507123 -2.660313) (xy 381.575552 -2.711989) (xy 381.638922 -2.769758) (xy 381.696691 -2.833128)
			(xy 381.748367 -2.901557) (xy 381.793508 -2.974463) (xy 381.83173 -3.051223) (xy 381.862706 -3.131182)
			(xy 381.886173 -3.213658) (xy 381.901929 -3.297948) (xy 381.909841 -3.383331) (xy 381.910336 -3.426206)
			(xy 381.909841 -3.469081) (xy 381.901929 -3.554464) (xy 381.886173 -3.638754) (xy 381.862706 -3.72123)
			(xy 381.83173 -3.801189) (xy 381.793508 -3.877949) (xy 381.748367 -3.950855) (xy 381.696691 -4.019284)
			(xy 381.638922 -4.082654) (xy 381.575552 -4.140423) (xy 381.507123 -4.192099) (xy 381.434217 -4.23724)
			(xy 381.357457 -4.275462) (xy 381.277498 -4.306438) (xy 381.195022 -4.329905) (xy 381.110732 -4.345661)
			(xy 381.025349 -4.353573) (xy 380.939599 -4.353573) (xy 380.854216 -4.345661) (xy 380.769926 -4.329905)
			(xy 380.68745 -4.306438) (xy 380.607491 -4.275462) (xy 380.530731 -4.23724) (xy 380.457825 -4.192099)
			(xy 380.389396 -4.140423) (xy 380.326026 -4.082654) (xy 380.268257 -4.019284) (xy 380.216581 -3.950855)
			(xy 380.17144 -3.877949) (xy 380.133218 -3.801189) (xy 380.102242 -3.72123) (xy 380.078775 -3.638754)
			(xy 380.063019 -3.554464) (xy 380.055107 -3.469081) (xy 375.559841 -3.469081) (xy 375.551929 -3.554464)
			(xy 375.536173 -3.638754) (xy 375.512706 -3.72123) (xy 375.48173 -3.801189) (xy 375.443508 -3.877949)
			(xy 375.398367 -3.950855) (xy 375.346691 -4.019284) (xy 375.288922 -4.082654) (xy 375.225552 -4.140423)
			(xy 375.157123 -4.192099) (xy 375.084217 -4.23724) (xy 375.007457 -4.275462) (xy 374.927498 -4.306438)
			(xy 374.845022 -4.329905) (xy 374.760732 -4.345661) (xy 374.675349 -4.353573) (xy 374.589599 -4.353573)
			(xy 374.504216 -4.345661) (xy 374.419926 -4.329905) (xy 374.33745 -4.306438) (xy 374.257491 -4.275462)
			(xy 374.180731 -4.23724) (xy 374.107825 -4.192099) (xy 374.039396 -4.140423) (xy 373.976026 -4.082654)
			(xy 373.918257 -4.019284) (xy 373.866581 -3.950855) (xy 373.82144 -3.877949) (xy 373.783218 -3.801189)
			(xy 373.752242 -3.72123) (xy 373.728775 -3.638754) (xy 373.713019 -3.554464) (xy 373.705107 -3.469081)
			(xy 343.693001 -3.469081) (xy 343.685089 -3.554464) (xy 343.669333 -3.638754) (xy 343.645866 -3.72123)
			(xy 343.61489 -3.801189) (xy 343.576668 -3.877949) (xy 343.531527 -3.950855) (xy 343.479851 -4.019284)
			(xy 343.422082 -4.082654) (xy 343.358712 -4.140423) (xy 343.290283 -4.192099) (xy 343.217377 -4.23724)
			(xy 343.140617 -4.275462) (xy 343.060658 -4.306438) (xy 342.978182 -4.329905) (xy 342.893892 -4.345661)
			(xy 342.808509 -4.353573) (xy 342.722759 -4.353573) (xy 342.637376 -4.345661) (xy 342.553086 -4.329905)
			(xy 342.47061 -4.306438) (xy 342.390651 -4.275462) (xy 342.313891 -4.23724) (xy 342.240985 -4.192099)
			(xy 342.172556 -4.140423) (xy 342.109186 -4.082654) (xy 342.051417 -4.019284) (xy 341.999741 -3.950855)
			(xy 341.9546 -3.877949) (xy 341.916378 -3.801189) (xy 341.885402 -3.72123) (xy 341.861935 -3.638754)
			(xy 341.846179 -3.554464) (xy 341.838267 -3.469081) (xy 337.343001 -3.469081) (xy 337.335089 -3.554464)
			(xy 337.319333 -3.638754) (xy 337.295866 -3.72123) (xy 337.26489 -3.801189) (xy 337.226668 -3.877949)
			(xy 337.181527 -3.950855) (xy 337.129851 -4.019284) (xy 337.072082 -4.082654) (xy 337.008712 -4.140423)
			(xy 336.940283 -4.192099) (xy 336.867377 -4.23724) (xy 336.790617 -4.275462) (xy 336.710658 -4.306438)
			(xy 336.628182 -4.329905) (xy 336.543892 -4.345661) (xy 336.458509 -4.353573) (xy 336.372759 -4.353573)
			(xy 336.287376 -4.345661) (xy 336.203086 -4.329905) (xy 336.12061 -4.306438) (xy 336.040651 -4.275462)
			(xy 335.963891 -4.23724) (xy 335.890985 -4.192099) (xy 335.822556 -4.140423) (xy 335.759186 -4.082654)
			(xy 335.701417 -4.019284) (xy 335.649741 -3.950855) (xy 335.6046 -3.877949) (xy 335.566378 -3.801189)
			(xy 335.535402 -3.72123) (xy 335.511935 -3.638754) (xy 335.496179 -3.554464) (xy 335.488267 -3.469081)
			(xy 333.050655 -3.469081) (xy 333.042743 -3.554464) (xy 333.026987 -3.638754) (xy 333.00352 -3.72123)
			(xy 332.972544 -3.801189) (xy 332.934322 -3.877949) (xy 332.889181 -3.950855) (xy 332.837505 -4.019284)
			(xy 332.779736 -4.082654) (xy 332.716366 -4.140423) (xy 332.647937 -4.192099) (xy 332.575031 -4.23724)
			(xy 332.498271 -4.275462) (xy 332.418312 -4.306438) (xy 332.335836 -4.329905) (xy 332.251546 -4.345661)
			(xy 332.166163 -4.353573) (xy 332.080413 -4.353573) (xy 331.99503 -4.345661) (xy 331.91074 -4.329905)
			(xy 331.828264 -4.306438) (xy 331.748305 -4.275462) (xy 331.671545 -4.23724) (xy 331.598639 -4.192099)
			(xy 331.53021 -4.140423) (xy 331.46684 -4.082654) (xy 331.409071 -4.019284) (xy 331.357395 -3.950855)
			(xy 331.312254 -3.877949) (xy 331.274032 -3.801189) (xy 331.243056 -3.72123) (xy 331.219589 -3.638754)
			(xy 331.203833 -3.554464) (xy 331.195921 -3.469081) (xy 326.700655 -3.469081) (xy 326.692743 -3.554464)
			(xy 326.676987 -3.638754) (xy 326.65352 -3.72123) (xy 326.622544 -3.801189) (xy 326.584322 -3.877949)
			(xy 326.539181 -3.950855) (xy 326.487505 -4.019284) (xy 326.429736 -4.082654) (xy 326.366366 -4.140423)
			(xy 326.297937 -4.192099) (xy 326.225031 -4.23724) (xy 326.148271 -4.275462) (xy 326.068312 -4.306438)
			(xy 325.985836 -4.329905) (xy 325.901546 -4.345661) (xy 325.816163 -4.353573) (xy 325.730413 -4.353573)
			(xy 325.64503 -4.345661) (xy 325.56074 -4.329905) (xy 325.478264 -4.306438) (xy 325.398305 -4.275462)
			(xy 325.321545 -4.23724) (xy 325.248639 -4.192099) (xy 325.18021 -4.140423) (xy 325.11684 -4.082654)
			(xy 325.059071 -4.019284) (xy 325.007395 -3.950855) (xy 324.962254 -3.877949) (xy 324.924032 -3.801189)
			(xy 324.893056 -3.72123) (xy 324.869589 -3.638754) (xy 324.853833 -3.554464) (xy 324.845921 -3.469081)
			(xy 265.125975 -3.469081) (xy 265.118063 -3.554464) (xy 265.102307 -3.638754) (xy 265.07884 -3.72123)
			(xy 265.047864 -3.801189) (xy 265.009642 -3.877949) (xy 264.964501 -3.950855) (xy 264.912825 -4.019284)
			(xy 264.855056 -4.082654) (xy 264.791686 -4.140423) (xy 264.723257 -4.192099) (xy 264.650351 -4.23724)
			(xy 264.573591 -4.275462) (xy 264.493632 -4.306438) (xy 264.411156 -4.329905) (xy 264.326866 -4.345661)
			(xy 264.241483 -4.353573) (xy 264.155733 -4.353573) (xy 264.07035 -4.345661) (xy 263.98606 -4.329905)
			(xy 263.903584 -4.306438) (xy 263.823625 -4.275462) (xy 263.746865 -4.23724) (xy 263.673959 -4.192099)
			(xy 263.60553 -4.140423) (xy 263.54216 -4.082654) (xy 263.484391 -4.019284) (xy 263.432715 -3.950855)
			(xy 263.387574 -3.877949) (xy 263.349352 -3.801189) (xy 263.318376 -3.72123) (xy 263.294909 -3.638754)
			(xy 263.279153 -3.554464) (xy 263.271241 -3.469081) (xy 258.775975 -3.469081) (xy 258.768063 -3.554464)
			(xy 258.752307 -3.638754) (xy 258.72884 -3.72123) (xy 258.697864 -3.801189) (xy 258.659642 -3.877949)
			(xy 258.614501 -3.950855) (xy 258.562825 -4.019284) (xy 258.505056 -4.082654) (xy 258.441686 -4.140423)
			(xy 258.373257 -4.192099) (xy 258.300351 -4.23724) (xy 258.223591 -4.275462) (xy 258.143632 -4.306438)
			(xy 258.061156 -4.329905) (xy 257.976866 -4.345661) (xy 257.891483 -4.353573) (xy 257.805733 -4.353573)
			(xy 257.72035 -4.345661) (xy 257.63606 -4.329905) (xy 257.553584 -4.306438) (xy 257.473625 -4.275462)
			(xy 257.396865 -4.23724) (xy 257.323959 -4.192099) (xy 257.25553 -4.140423) (xy 257.19216 -4.082654)
			(xy 257.134391 -4.019284) (xy 257.082715 -3.950855) (xy 257.037574 -3.877949) (xy 256.999352 -3.801189)
			(xy 256.968376 -3.72123) (xy 256.944909 -3.638754) (xy 256.929153 -3.554464) (xy 256.921241 -3.469081)
			(xy 254.465119 -3.469081) (xy 254.465087 -3.471875) (xy 254.457175 -3.557258) (xy 254.441419 -3.641548)
			(xy 254.417952 -3.724024) (xy 254.386976 -3.803983) (xy 254.348754 -3.880743) (xy 254.303613 -3.953649)
			(xy 254.251937 -4.022078) (xy 254.194168 -4.085448) (xy 254.130798 -4.143217) (xy 254.062369 -4.194893)
			(xy 253.989463 -4.240034) (xy 253.912703 -4.278256) (xy 253.832744 -4.309232) (xy 253.750268 -4.332699)
			(xy 253.665978 -4.348455) (xy 253.580595 -4.356367) (xy 253.494845 -4.356367) (xy 253.409462 -4.348455)
			(xy 253.325172 -4.332699) (xy 253.242696 -4.309232) (xy 253.162737 -4.278256) (xy 253.085977 -4.240034)
			(xy 253.013071 -4.194893) (xy 252.944642 -4.143217) (xy 252.881272 -4.085448) (xy 252.823503 -4.022078)
			(xy 252.771827 -3.953649) (xy 252.726686 -3.880743) (xy 252.688464 -3.803983) (xy 252.657488 -3.724024)
			(xy 252.634021 -3.641548) (xy 252.618265 -3.557258) (xy 252.610353 -3.471875) (xy 248.115087 -3.471875)
			(xy 248.107175 -3.557258) (xy 248.091419 -3.641548) (xy 248.067952 -3.724024) (xy 248.036976 -3.803983)
			(xy 247.998754 -3.880743) (xy 247.953613 -3.953649) (xy 247.901937 -4.022078) (xy 247.844168 -4.085448)
			(xy 247.780798 -4.143217) (xy 247.712369 -4.194893) (xy 247.639463 -4.240034) (xy 247.562703 -4.278256)
			(xy 247.482744 -4.309232) (xy 247.400268 -4.332699) (xy 247.315978 -4.348455) (xy 247.230595 -4.356367)
			(xy 247.144845 -4.356367) (xy 247.059462 -4.348455) (xy 246.975172 -4.332699) (xy 246.892696 -4.309232)
			(xy 246.812737 -4.278256) (xy 246.735977 -4.240034) (xy 246.663071 -4.194893) (xy 246.594642 -4.143217)
			(xy 246.531272 -4.085448) (xy 246.473503 -4.022078) (xy 246.421827 -3.953649) (xy 246.376686 -3.880743)
			(xy 246.338464 -3.803983) (xy 246.307488 -3.724024) (xy 246.284021 -3.641548) (xy 246.268265 -3.557258)
			(xy 246.260353 -3.471875) (xy 216.248247 -3.471875) (xy 216.240335 -3.557258) (xy 216.224579 -3.641548)
			(xy 216.201112 -3.724024) (xy 216.170136 -3.803983) (xy 216.131914 -3.880743) (xy 216.086773 -3.953649)
			(xy 216.035097 -4.022078) (xy 215.977328 -4.085448) (xy 215.913958 -4.143217) (xy 215.845529 -4.194893)
			(xy 215.772623 -4.240034) (xy 215.695863 -4.278256) (xy 215.615904 -4.309232) (xy 215.533428 -4.332699)
			(xy 215.449138 -4.348455) (xy 215.363755 -4.356367) (xy 215.278005 -4.356367) (xy 215.192622 -4.348455)
			(xy 215.108332 -4.332699) (xy 215.025856 -4.309232) (xy 214.945897 -4.278256) (xy 214.869137 -4.240034)
			(xy 214.796231 -4.194893) (xy 214.727802 -4.143217) (xy 214.664432 -4.085448) (xy 214.606663 -4.022078)
			(xy 214.554987 -3.953649) (xy 214.509846 -3.880743) (xy 214.471624 -3.803983) (xy 214.440648 -3.724024)
			(xy 214.417181 -3.641548) (xy 214.401425 -3.557258) (xy 214.393513 -3.471875) (xy 209.898247 -3.471875)
			(xy 209.890335 -3.557258) (xy 209.874579 -3.641548) (xy 209.851112 -3.724024) (xy 209.820136 -3.803983)
			(xy 209.781914 -3.880743) (xy 209.736773 -3.953649) (xy 209.685097 -4.022078) (xy 209.627328 -4.085448)
			(xy 209.563958 -4.143217) (xy 209.495529 -4.194893) (xy 209.422623 -4.240034) (xy 209.345863 -4.278256)
			(xy 209.265904 -4.309232) (xy 209.183428 -4.332699) (xy 209.099138 -4.348455) (xy 209.013755 -4.356367)
			(xy 208.928005 -4.356367) (xy 208.842622 -4.348455) (xy 208.758332 -4.332699) (xy 208.675856 -4.309232)
			(xy 208.595897 -4.278256) (xy 208.519137 -4.240034) (xy 208.446231 -4.194893) (xy 208.377802 -4.143217)
			(xy 208.314432 -4.085448) (xy 208.256663 -4.022078) (xy 208.204987 -3.953649) (xy 208.159846 -3.880743)
			(xy 208.121624 -3.803983) (xy 208.090648 -3.724024) (xy 208.067181 -3.641548) (xy 208.051425 -3.557258)
			(xy 208.043513 -3.471875) (xy 197.075741 -3.471875) (xy 197.091928 -3.518134) (xy 197.13088 -3.653342)
			(xy 197.16219 -3.790521) (xy 197.185759 -3.929239) (xy 197.201513 -4.069061) (xy 197.209403 -4.209547)
			(xy 197.209918 -4.2799) (xy 197.209918 -6.011875) (xy 208.043513 -6.011875) (xy 208.043513 -5.926125)
			(xy 208.051425 -5.840742) (xy 208.067181 -5.756452) (xy 208.090648 -5.673976) (xy 208.121624 -5.594017)
			(xy 208.159846 -5.517257) (xy 208.204987 -5.444351) (xy 208.256663 -5.375922) (xy 208.314432 -5.312552)
			(xy 208.377802 -5.254783) (xy 208.446231 -5.203107) (xy 208.519137 -5.157966) (xy 208.595897 -5.119744)
			(xy 208.675856 -5.088768) (xy 208.758332 -5.065301) (xy 208.842622 -5.049545) (xy 208.928005 -5.041633)
			(xy 209.013755 -5.041633) (xy 209.099138 -5.049545) (xy 209.183428 -5.065301) (xy 209.265904 -5.088768)
			(xy 209.345863 -5.119744) (xy 209.368066 -5.1308) (xy 212.978492 -5.1308) (xy 212.978492 -4.2672)
			(xy 212.978978 -4.239931) (xy 212.98674 -4.185947) (xy 213.002105 -4.133617) (xy 213.024762 -4.084007)
			(xy 213.054248 -4.038126) (xy 213.089963 -3.996909) (xy 213.13118 -3.961194) (xy 213.177061 -3.931708)
			(xy 213.226671 -3.909051) (xy 213.279001 -3.893686) (xy 213.332985 -3.885924) (xy 213.387523 -3.885924)
			(xy 213.441507 -3.893686) (xy 213.493837 -3.909051) (xy 213.543447 -3.931708) (xy 213.589328 -3.961194)
			(xy 213.630545 -3.996909) (xy 213.66626 -4.038126) (xy 213.695746 -4.084007) (xy 213.718403 -4.133617)
			(xy 213.733768 -4.185947) (xy 213.74153 -4.239931) (xy 213.742016 -4.2672) (xy 213.742016 -5.1308)
			(xy 213.74153 -5.158069) (xy 213.733768 -5.212053) (xy 213.718403 -5.264383) (xy 213.695746 -5.313993)
			(xy 213.66626 -5.359874) (xy 213.630545 -5.401091) (xy 213.589328 -5.436806) (xy 213.543447 -5.466292)
			(xy 213.493837 -5.488949) (xy 213.441507 -5.504314) (xy 213.387523 -5.512076) (xy 213.332985 -5.512076)
			(xy 213.279001 -5.504314) (xy 213.226671 -5.488949) (xy 213.177061 -5.466292) (xy 213.13118 -5.436806)
			(xy 213.089963 -5.401091) (xy 213.054248 -5.359874) (xy 213.024762 -5.313993) (xy 213.002105 -5.264383)
			(xy 212.98674 -5.212053) (xy 212.978978 -5.158069) (xy 212.978492 -5.1308) (xy 209.368066 -5.1308)
			(xy 209.422623 -5.157966) (xy 209.495529 -5.203107) (xy 209.563958 -5.254783) (xy 209.627328 -5.312552)
			(xy 209.685097 -5.375922) (xy 209.736773 -5.444351) (xy 209.781914 -5.517257) (xy 209.820136 -5.594017)
			(xy 209.851112 -5.673976) (xy 209.874579 -5.756452) (xy 209.890335 -5.840742) (xy 209.898247 -5.926125)
			(xy 209.898742 -5.969) (xy 209.898247 -6.011875) (xy 214.393513 -6.011875) (xy 214.393513 -5.926125)
			(xy 214.401425 -5.840742) (xy 214.417181 -5.756452) (xy 214.440648 -5.673976) (xy 214.471624 -5.594017)
			(xy 214.509846 -5.517257) (xy 214.554987 -5.444351) (xy 214.606663 -5.375922) (xy 214.664432 -5.312552)
			(xy 214.727802 -5.254783) (xy 214.796231 -5.203107) (xy 214.869137 -5.157966) (xy 214.945897 -5.119744)
			(xy 215.025856 -5.088768) (xy 215.108332 -5.065301) (xy 215.192622 -5.049545) (xy 215.278005 -5.041633)
			(xy 215.363755 -5.041633) (xy 215.449138 -5.049545) (xy 215.533428 -5.065301) (xy 215.615904 -5.088768)
			(xy 215.695863 -5.119744) (xy 215.772623 -5.157966) (xy 215.845529 -5.203107) (xy 215.913958 -5.254783)
			(xy 215.977328 -5.312552) (xy 216.035097 -5.375922) (xy 216.086773 -5.444351) (xy 216.131914 -5.517257)
			(xy 216.170136 -5.594017) (xy 216.201112 -5.673976) (xy 216.224579 -5.756452) (xy 216.240335 -5.840742)
			(xy 216.248247 -5.926125) (xy 216.248742 -5.969) (xy 216.248247 -6.011875) (xy 246.260353 -6.011875)
			(xy 246.260353 -5.926125) (xy 246.268265 -5.840742) (xy 246.284021 -5.756452) (xy 246.307488 -5.673976)
			(xy 246.338464 -5.594017) (xy 246.376686 -5.517257) (xy 246.421827 -5.444351) (xy 246.473503 -5.375922)
			(xy 246.531272 -5.312552) (xy 246.594642 -5.254783) (xy 246.663071 -5.203107) (xy 246.735977 -5.157966)
			(xy 246.812737 -5.119744) (xy 246.892696 -5.088768) (xy 246.975172 -5.065301) (xy 247.059462 -5.049545)
			(xy 247.144845 -5.041633) (xy 247.230595 -5.041633) (xy 247.315978 -5.049545) (xy 247.400268 -5.065301)
			(xy 247.482744 -5.088768) (xy 247.562703 -5.119744) (xy 247.584906 -5.1308) (xy 248.766584 -5.1308)
			(xy 248.766584 -4.2672) (xy 248.76707 -4.239931) (xy 248.774832 -4.185947) (xy 248.790197 -4.133617)
			(xy 248.812854 -4.084007) (xy 248.84234 -4.038126) (xy 248.878055 -3.996909) (xy 248.919272 -3.961194)
			(xy 248.965153 -3.931708) (xy 249.014763 -3.909051) (xy 249.067093 -3.893686) (xy 249.121077 -3.885924)
			(xy 249.175615 -3.885924) (xy 249.229599 -3.893686) (xy 249.281929 -3.909051) (xy 249.331539 -3.931708)
			(xy 249.37742 -3.961194) (xy 249.418637 -3.996909) (xy 249.454352 -4.038126) (xy 249.483838 -4.084007)
			(xy 249.506495 -4.133617) (xy 249.52186 -4.185947) (xy 249.529622 -4.239931) (xy 249.530108 -4.2672)
			(xy 249.530108 -5.1308) (xy 249.529622 -5.158069) (xy 249.52186 -5.212053) (xy 249.506495 -5.264383)
			(xy 249.483838 -5.313993) (xy 249.454352 -5.359874) (xy 249.418637 -5.401091) (xy 249.37742 -5.436806)
			(xy 249.331539 -5.466292) (xy 249.281929 -5.488949) (xy 249.229599 -5.504314) (xy 249.175615 -5.512076)
			(xy 249.121077 -5.512076) (xy 249.067093 -5.504314) (xy 249.014763 -5.488949) (xy 248.965153 -5.466292)
			(xy 248.919272 -5.436806) (xy 248.878055 -5.401091) (xy 248.84234 -5.359874) (xy 248.812854 -5.313993)
			(xy 248.790197 -5.264383) (xy 248.774832 -5.212053) (xy 248.76707 -5.158069) (xy 248.766584 -5.1308)
			(xy 247.584906 -5.1308) (xy 247.639463 -5.157966) (xy 247.712369 -5.203107) (xy 247.780798 -5.254783)
			(xy 247.844168 -5.312552) (xy 247.901937 -5.375922) (xy 247.953613 -5.444351) (xy 247.998754 -5.517257)
			(xy 248.036976 -5.594017) (xy 248.067952 -5.673976) (xy 248.091419 -5.756452) (xy 248.107175 -5.840742)
			(xy 248.115087 -5.926125) (xy 248.115582 -5.969) (xy 248.115087 -6.011875) (xy 252.610353 -6.011875)
			(xy 252.610353 -5.926125) (xy 252.618265 -5.840742) (xy 252.634021 -5.756452) (xy 252.657488 -5.673976)
			(xy 252.688464 -5.594017) (xy 252.726686 -5.517257) (xy 252.771827 -5.444351) (xy 252.823503 -5.375922)
			(xy 252.881272 -5.312552) (xy 252.944642 -5.254783) (xy 253.013071 -5.203107) (xy 253.085977 -5.157966)
			(xy 253.162737 -5.119744) (xy 253.242696 -5.088768) (xy 253.325172 -5.065301) (xy 253.409462 -5.049545)
			(xy 253.494845 -5.041633) (xy 253.580595 -5.041633) (xy 253.665978 -5.049545) (xy 253.750268 -5.065301)
			(xy 253.832744 -5.088768) (xy 253.912703 -5.119744) (xy 253.989463 -5.157966) (xy 254.062369 -5.203107)
			(xy 254.130798 -5.254783) (xy 254.194168 -5.312552) (xy 254.251937 -5.375922) (xy 254.303613 -5.444351)
			(xy 254.348754 -5.517257) (xy 254.386976 -5.594017) (xy 254.417952 -5.673976) (xy 254.441419 -5.756452)
			(xy 254.457175 -5.840742) (xy 254.465087 -5.926125) (xy 254.465582 -5.969) (xy 254.465119 -6.009081)
			(xy 256.921241 -6.009081) (xy 256.921241 -5.923331) (xy 256.929153 -5.837948) (xy 256.944909 -5.753658)
			(xy 256.968376 -5.671182) (xy 256.999352 -5.591223) (xy 257.037574 -5.514463) (xy 257.082715 -5.441557)
			(xy 257.134391 -5.373128) (xy 257.19216 -5.309758) (xy 257.25553 -5.251989) (xy 257.323959 -5.200313)
			(xy 257.396865 -5.155172) (xy 257.473625 -5.11695) (xy 257.553584 -5.085974) (xy 257.63606 -5.062507)
			(xy 257.72035 -5.046751) (xy 257.805733 -5.038839) (xy 257.891483 -5.038839) (xy 257.976866 -5.046751)
			(xy 258.061156 -5.062507) (xy 258.143632 -5.085974) (xy 258.223591 -5.11695) (xy 258.300351 -5.155172)
			(xy 258.373257 -5.200313) (xy 258.441686 -5.251989) (xy 258.505056 -5.309758) (xy 258.562825 -5.373128)
			(xy 258.614501 -5.441557) (xy 258.659642 -5.514463) (xy 258.697864 -5.591223) (xy 258.72884 -5.671182)
			(xy 258.752307 -5.753658) (xy 258.768063 -5.837948) (xy 258.775975 -5.923331) (xy 258.77647 -5.966206)
			(xy 258.775975 -6.009081) (xy 263.271241 -6.009081) (xy 263.271241 -5.923331) (xy 263.279153 -5.837948)
			(xy 263.294909 -5.753658) (xy 263.318376 -5.671182) (xy 263.349352 -5.591223) (xy 263.387574 -5.514463)
			(xy 263.432715 -5.441557) (xy 263.484391 -5.373128) (xy 263.54216 -5.309758) (xy 263.60553 -5.251989)
			(xy 263.673959 -5.200313) (xy 263.746865 -5.155172) (xy 263.823625 -5.11695) (xy 263.903584 -5.085974)
			(xy 263.98606 -5.062507) (xy 264.07035 -5.046751) (xy 264.155733 -5.038839) (xy 264.241483 -5.038839)
			(xy 264.326866 -5.046751) (xy 264.411156 -5.062507) (xy 264.493632 -5.085974) (xy 264.573591 -5.11695)
			(xy 264.650351 -5.155172) (xy 264.723257 -5.200313) (xy 264.791686 -5.251989) (xy 264.855056 -5.309758)
			(xy 264.912825 -5.373128) (xy 264.964501 -5.441557) (xy 265.009642 -5.514463) (xy 265.047864 -5.591223)
			(xy 265.07884 -5.671182) (xy 265.102307 -5.753658) (xy 265.118063 -5.837948) (xy 265.125975 -5.923331)
			(xy 265.12647 -5.966206) (xy 265.125975 -6.009081) (xy 324.845921 -6.009081) (xy 324.845921 -5.923331)
			(xy 324.853833 -5.837948) (xy 324.869589 -5.753658) (xy 324.893056 -5.671182) (xy 324.924032 -5.591223)
			(xy 324.962254 -5.514463) (xy 325.007395 -5.441557) (xy 325.059071 -5.373128) (xy 325.11684 -5.309758)
			(xy 325.18021 -5.251989) (xy 325.248639 -5.200313) (xy 325.321545 -5.155172) (xy 325.398305 -5.11695)
			(xy 325.478264 -5.085974) (xy 325.56074 -5.062507) (xy 325.64503 -5.046751) (xy 325.730413 -5.038839)
			(xy 325.816163 -5.038839) (xy 325.901546 -5.046751) (xy 325.985836 -5.062507) (xy 326.068312 -5.085974)
			(xy 326.148271 -5.11695) (xy 326.225031 -5.155172) (xy 326.297937 -5.200313) (xy 326.366366 -5.251989)
			(xy 326.429736 -5.309758) (xy 326.487505 -5.373128) (xy 326.539181 -5.441557) (xy 326.584322 -5.514463)
			(xy 326.622544 -5.591223) (xy 326.65352 -5.671182) (xy 326.676987 -5.753658) (xy 326.692743 -5.837948)
			(xy 326.700655 -5.923331) (xy 326.70115 -5.966206) (xy 326.700655 -6.009081) (xy 331.195921 -6.009081)
			(xy 331.195921 -5.923331) (xy 331.203833 -5.837948) (xy 331.219589 -5.753658) (xy 331.243056 -5.671182)
			(xy 331.274032 -5.591223) (xy 331.312254 -5.514463) (xy 331.357395 -5.441557) (xy 331.409071 -5.373128)
			(xy 331.46684 -5.309758) (xy 331.53021 -5.251989) (xy 331.598639 -5.200313) (xy 331.671545 -5.155172)
			(xy 331.748305 -5.11695) (xy 331.828264 -5.085974) (xy 331.91074 -5.062507) (xy 331.99503 -5.046751)
			(xy 332.080413 -5.038839) (xy 332.166163 -5.038839) (xy 332.251546 -5.046751) (xy 332.335836 -5.062507)
			(xy 332.418312 -5.085974) (xy 332.498271 -5.11695) (xy 332.575031 -5.155172) (xy 332.647937 -5.200313)
			(xy 332.716366 -5.251989) (xy 332.779736 -5.309758) (xy 332.837505 -5.373128) (xy 332.889181 -5.441557)
			(xy 332.934322 -5.514463) (xy 332.972544 -5.591223) (xy 333.00352 -5.671182) (xy 333.026987 -5.753658)
			(xy 333.042743 -5.837948) (xy 333.050655 -5.923331) (xy 333.05115 -5.966206) (xy 333.050655 -6.009081)
			(xy 335.488267 -6.009081) (xy 335.488267 -5.923331) (xy 335.496179 -5.837948) (xy 335.511935 -5.753658)
			(xy 335.535402 -5.671182) (xy 335.566378 -5.591223) (xy 335.6046 -5.514463) (xy 335.649741 -5.441557)
			(xy 335.701417 -5.373128) (xy 335.759186 -5.309758) (xy 335.822556 -5.251989) (xy 335.890985 -5.200313)
			(xy 335.963891 -5.155172) (xy 336.040651 -5.11695) (xy 336.12061 -5.085974) (xy 336.203086 -5.062507)
			(xy 336.287376 -5.046751) (xy 336.372759 -5.038839) (xy 336.458509 -5.038839) (xy 336.543892 -5.046751)
			(xy 336.628182 -5.062507) (xy 336.710658 -5.085974) (xy 336.790617 -5.11695) (xy 336.867377 -5.155172)
			(xy 336.940283 -5.200313) (xy 337.008712 -5.251989) (xy 337.072082 -5.309758) (xy 337.129851 -5.373128)
			(xy 337.181527 -5.441557) (xy 337.226668 -5.514463) (xy 337.26489 -5.591223) (xy 337.295866 -5.671182)
			(xy 337.319333 -5.753658) (xy 337.335089 -5.837948) (xy 337.343001 -5.923331) (xy 337.343496 -5.966206)
			(xy 337.343001 -6.009081) (xy 341.838267 -6.009081) (xy 341.838267 -5.923331) (xy 341.846179 -5.837948)
			(xy 341.861935 -5.753658) (xy 341.885402 -5.671182) (xy 341.916378 -5.591223) (xy 341.9546 -5.514463)
			(xy 341.999741 -5.441557) (xy 342.051417 -5.373128) (xy 342.109186 -5.309758) (xy 342.172556 -5.251989)
			(xy 342.240985 -5.200313) (xy 342.313891 -5.155172) (xy 342.390651 -5.11695) (xy 342.47061 -5.085974)
			(xy 342.553086 -5.062507) (xy 342.637376 -5.046751) (xy 342.722759 -5.038839) (xy 342.808509 -5.038839)
			(xy 342.893892 -5.046751) (xy 342.978182 -5.062507) (xy 343.060658 -5.085974) (xy 343.140617 -5.11695)
			(xy 343.217377 -5.155172) (xy 343.290283 -5.200313) (xy 343.358712 -5.251989) (xy 343.422082 -5.309758)
			(xy 343.479851 -5.373128) (xy 343.531527 -5.441557) (xy 343.576668 -5.514463) (xy 343.61489 -5.591223)
			(xy 343.645866 -5.671182) (xy 343.669333 -5.753658) (xy 343.685089 -5.837948) (xy 343.693001 -5.923331)
			(xy 343.693496 -5.966206) (xy 343.693001 -6.009081) (xy 373.705107 -6.009081) (xy 373.705107 -5.923331)
			(xy 373.713019 -5.837948) (xy 373.728775 -5.753658) (xy 373.752242 -5.671182) (xy 373.783218 -5.591223)
			(xy 373.82144 -5.514463) (xy 373.866581 -5.441557) (xy 373.918257 -5.373128) (xy 373.976026 -5.309758)
			(xy 374.039396 -5.251989) (xy 374.107825 -5.200313) (xy 374.180731 -5.155172) (xy 374.257491 -5.11695)
			(xy 374.33745 -5.085974) (xy 374.419926 -5.062507) (xy 374.504216 -5.046751) (xy 374.589599 -5.038839)
			(xy 374.675349 -5.038839) (xy 374.760732 -5.046751) (xy 374.845022 -5.062507) (xy 374.927498 -5.085974)
			(xy 375.007457 -5.11695) (xy 375.084217 -5.155172) (xy 375.157123 -5.200313) (xy 375.225552 -5.251989)
			(xy 375.288922 -5.309758) (xy 375.346691 -5.373128) (xy 375.398367 -5.441557) (xy 375.443508 -5.514463)
			(xy 375.48173 -5.591223) (xy 375.512706 -5.671182) (xy 375.536173 -5.753658) (xy 375.551929 -5.837948)
			(xy 375.559841 -5.923331) (xy 375.560336 -5.966206) (xy 375.559841 -6.009081) (xy 380.055107 -6.009081)
			(xy 380.055107 -5.923331) (xy 380.063019 -5.837948) (xy 380.078775 -5.753658) (xy 380.102242 -5.671182)
			(xy 380.133218 -5.591223) (xy 380.17144 -5.514463) (xy 380.216581 -5.441557) (xy 380.268257 -5.373128)
			(xy 380.326026 -5.309758) (xy 380.389396 -5.251989) (xy 380.457825 -5.200313) (xy 380.530731 -5.155172)
			(xy 380.607491 -5.11695) (xy 380.68745 -5.085974) (xy 380.769926 -5.062507) (xy 380.854216 -5.046751)
			(xy 380.939599 -5.038839) (xy 381.025349 -5.038839) (xy 381.110732 -5.046751) (xy 381.195022 -5.062507)
			(xy 381.277498 -5.085974) (xy 381.357457 -5.11695) (xy 381.434217 -5.155172) (xy 381.507123 -5.200313)
			(xy 381.575552 -5.251989) (xy 381.638922 -5.309758) (xy 381.696691 -5.373128) (xy 381.748367 -5.441557)
			(xy 381.793508 -5.514463) (xy 381.83173 -5.591223) (xy 381.862706 -5.671182) (xy 381.886173 -5.753658)
			(xy 381.901929 -5.837948) (xy 381.909841 -5.923331) (xy 381.910336 -5.966206) (xy 381.909841 -6.009081)
			(xy 381.901929 -6.094464) (xy 381.886173 -6.178754) (xy 381.862706 -6.26123) (xy 381.83173 -6.341189)
			(xy 381.793508 -6.417949) (xy 381.748367 -6.490855) (xy 381.696691 -6.559284) (xy 381.638922 -6.622654)
			(xy 381.575552 -6.680423) (xy 381.507123 -6.732099) (xy 381.434217 -6.77724) (xy 381.357457 -6.815462)
			(xy 381.277498 -6.846438) (xy 381.195022 -6.869905) (xy 381.110732 -6.885661) (xy 381.025349 -6.893573)
			(xy 380.939599 -6.893573) (xy 380.854216 -6.885661) (xy 380.769926 -6.869905) (xy 380.68745 -6.846438)
			(xy 380.607491 -6.815462) (xy 380.530731 -6.77724) (xy 380.457825 -6.732099) (xy 380.389396 -6.680423)
			(xy 380.326026 -6.622654) (xy 380.268257 -6.559284) (xy 380.216581 -6.490855) (xy 380.17144 -6.417949)
			(xy 380.133218 -6.341189) (xy 380.102242 -6.26123) (xy 380.078775 -6.178754) (xy 380.063019 -6.094464)
			(xy 380.055107 -6.009081) (xy 375.559841 -6.009081) (xy 375.551929 -6.094464) (xy 375.536173 -6.178754)
			(xy 375.512706 -6.26123) (xy 375.48173 -6.341189) (xy 375.443508 -6.417949) (xy 375.398367 -6.490855)
			(xy 375.346691 -6.559284) (xy 375.288922 -6.622654) (xy 375.225552 -6.680423) (xy 375.157123 -6.732099)
			(xy 375.084217 -6.77724) (xy 375.007457 -6.815462) (xy 374.927498 -6.846438) (xy 374.845022 -6.869905)
			(xy 374.760732 -6.885661) (xy 374.675349 -6.893573) (xy 374.589599 -6.893573) (xy 374.504216 -6.885661)
			(xy 374.419926 -6.869905) (xy 374.33745 -6.846438) (xy 374.257491 -6.815462) (xy 374.180731 -6.77724)
			(xy 374.107825 -6.732099) (xy 374.039396 -6.680423) (xy 373.976026 -6.622654) (xy 373.918257 -6.559284)
			(xy 373.866581 -6.490855) (xy 373.82144 -6.417949) (xy 373.783218 -6.341189) (xy 373.752242 -6.26123)
			(xy 373.728775 -6.178754) (xy 373.713019 -6.094464) (xy 373.705107 -6.009081) (xy 343.693001 -6.009081)
			(xy 343.685089 -6.094464) (xy 343.669333 -6.178754) (xy 343.645866 -6.26123) (xy 343.61489 -6.341189)
			(xy 343.576668 -6.417949) (xy 343.531527 -6.490855) (xy 343.479851 -6.559284) (xy 343.422082 -6.622654)
			(xy 343.358712 -6.680423) (xy 343.290283 -6.732099) (xy 343.217377 -6.77724) (xy 343.140617 -6.815462)
			(xy 343.060658 -6.846438) (xy 342.978182 -6.869905) (xy 342.893892 -6.885661) (xy 342.808509 -6.893573)
			(xy 342.722759 -6.893573) (xy 342.637376 -6.885661) (xy 342.553086 -6.869905) (xy 342.47061 -6.846438)
			(xy 342.390651 -6.815462) (xy 342.313891 -6.77724) (xy 342.240985 -6.732099) (xy 342.172556 -6.680423)
			(xy 342.109186 -6.622654) (xy 342.051417 -6.559284) (xy 341.999741 -6.490855) (xy 341.9546 -6.417949)
			(xy 341.916378 -6.341189) (xy 341.885402 -6.26123) (xy 341.861935 -6.178754) (xy 341.846179 -6.094464)
			(xy 341.838267 -6.009081) (xy 337.343001 -6.009081) (xy 337.335089 -6.094464) (xy 337.319333 -6.178754)
			(xy 337.295866 -6.26123) (xy 337.26489 -6.341189) (xy 337.226668 -6.417949) (xy 337.181527 -6.490855)
			(xy 337.129851 -6.559284) (xy 337.072082 -6.622654) (xy 337.008712 -6.680423) (xy 336.940283 -6.732099)
			(xy 336.867377 -6.77724) (xy 336.790617 -6.815462) (xy 336.710658 -6.846438) (xy 336.628182 -6.869905)
			(xy 336.543892 -6.885661) (xy 336.458509 -6.893573) (xy 336.372759 -6.893573) (xy 336.287376 -6.885661)
			(xy 336.203086 -6.869905) (xy 336.12061 -6.846438) (xy 336.040651 -6.815462) (xy 335.963891 -6.77724)
			(xy 335.890985 -6.732099) (xy 335.822556 -6.680423) (xy 335.759186 -6.622654) (xy 335.701417 -6.559284)
			(xy 335.649741 -6.490855) (xy 335.6046 -6.417949) (xy 335.566378 -6.341189) (xy 335.535402 -6.26123)
			(xy 335.511935 -6.178754) (xy 335.496179 -6.094464) (xy 335.488267 -6.009081) (xy 333.050655 -6.009081)
			(xy 333.042743 -6.094464) (xy 333.026987 -6.178754) (xy 333.00352 -6.26123) (xy 332.972544 -6.341189)
			(xy 332.934322 -6.417949) (xy 332.889181 -6.490855) (xy 332.837505 -6.559284) (xy 332.779736 -6.622654)
			(xy 332.716366 -6.680423) (xy 332.647937 -6.732099) (xy 332.575031 -6.77724) (xy 332.498271 -6.815462)
			(xy 332.418312 -6.846438) (xy 332.335836 -6.869905) (xy 332.251546 -6.885661) (xy 332.166163 -6.893573)
			(xy 332.080413 -6.893573) (xy 331.99503 -6.885661) (xy 331.91074 -6.869905) (xy 331.828264 -6.846438)
			(xy 331.748305 -6.815462) (xy 331.671545 -6.77724) (xy 331.598639 -6.732099) (xy 331.53021 -6.680423)
			(xy 331.46684 -6.622654) (xy 331.409071 -6.559284) (xy 331.357395 -6.490855) (xy 331.312254 -6.417949)
			(xy 331.274032 -6.341189) (xy 331.243056 -6.26123) (xy 331.219589 -6.178754) (xy 331.203833 -6.094464)
			(xy 331.195921 -6.009081) (xy 326.700655 -6.009081) (xy 326.692743 -6.094464) (xy 326.676987 -6.178754)
			(xy 326.65352 -6.26123) (xy 326.622544 -6.341189) (xy 326.584322 -6.417949) (xy 326.539181 -6.490855)
			(xy 326.487505 -6.559284) (xy 326.429736 -6.622654) (xy 326.366366 -6.680423) (xy 326.297937 -6.732099)
			(xy 326.225031 -6.77724) (xy 326.148271 -6.815462) (xy 326.068312 -6.846438) (xy 325.985836 -6.869905)
			(xy 325.901546 -6.885661) (xy 325.816163 -6.893573) (xy 325.730413 -6.893573) (xy 325.64503 -6.885661)
			(xy 325.56074 -6.869905) (xy 325.478264 -6.846438) (xy 325.398305 -6.815462) (xy 325.321545 -6.77724)
			(xy 325.248639 -6.732099) (xy 325.18021 -6.680423) (xy 325.11684 -6.622654) (xy 325.059071 -6.559284)
			(xy 325.007395 -6.490855) (xy 324.962254 -6.417949) (xy 324.924032 -6.341189) (xy 324.893056 -6.26123)
			(xy 324.869589 -6.178754) (xy 324.853833 -6.094464) (xy 324.845921 -6.009081) (xy 265.125975 -6.009081)
			(xy 265.118063 -6.094464) (xy 265.102307 -6.178754) (xy 265.07884 -6.26123) (xy 265.047864 -6.341189)
			(xy 265.009642 -6.417949) (xy 264.964501 -6.490855) (xy 264.912825 -6.559284) (xy 264.855056 -6.622654)
			(xy 264.791686 -6.680423) (xy 264.723257 -6.732099) (xy 264.650351 -6.77724) (xy 264.573591 -6.815462)
			(xy 264.493632 -6.846438) (xy 264.411156 -6.869905) (xy 264.326866 -6.885661) (xy 264.241483 -6.893573)
			(xy 264.155733 -6.893573) (xy 264.07035 -6.885661) (xy 263.98606 -6.869905) (xy 263.903584 -6.846438)
			(xy 263.823625 -6.815462) (xy 263.746865 -6.77724) (xy 263.673959 -6.732099) (xy 263.60553 -6.680423)
			(xy 263.54216 -6.622654) (xy 263.484391 -6.559284) (xy 263.432715 -6.490855) (xy 263.387574 -6.417949)
			(xy 263.349352 -6.341189) (xy 263.318376 -6.26123) (xy 263.294909 -6.178754) (xy 263.279153 -6.094464)
			(xy 263.271241 -6.009081) (xy 258.775975 -6.009081) (xy 258.768063 -6.094464) (xy 258.752307 -6.178754)
			(xy 258.72884 -6.26123) (xy 258.697864 -6.341189) (xy 258.659642 -6.417949) (xy 258.614501 -6.490855)
			(xy 258.562825 -6.559284) (xy 258.505056 -6.622654) (xy 258.441686 -6.680423) (xy 258.373257 -6.732099)
			(xy 258.300351 -6.77724) (xy 258.223591 -6.815462) (xy 258.143632 -6.846438) (xy 258.061156 -6.869905)
			(xy 257.976866 -6.885661) (xy 257.891483 -6.893573) (xy 257.805733 -6.893573) (xy 257.72035 -6.885661)
			(xy 257.63606 -6.869905) (xy 257.553584 -6.846438) (xy 257.473625 -6.815462) (xy 257.396865 -6.77724)
			(xy 257.323959 -6.732099) (xy 257.25553 -6.680423) (xy 257.19216 -6.622654) (xy 257.134391 -6.559284)
			(xy 257.082715 -6.490855) (xy 257.037574 -6.417949) (xy 256.999352 -6.341189) (xy 256.968376 -6.26123)
			(xy 256.944909 -6.178754) (xy 256.929153 -6.094464) (xy 256.921241 -6.009081) (xy 254.465119 -6.009081)
			(xy 254.465087 -6.011875) (xy 254.457175 -6.097258) (xy 254.441419 -6.181548) (xy 254.417952 -6.264024)
			(xy 254.386976 -6.343983) (xy 254.348754 -6.420743) (xy 254.303613 -6.493649) (xy 254.251937 -6.562078)
			(xy 254.194168 -6.625448) (xy 254.130798 -6.683217) (xy 254.062369 -6.734893) (xy 253.989463 -6.780034)
			(xy 253.912703 -6.818256) (xy 253.832744 -6.849232) (xy 253.750268 -6.872699) (xy 253.665978 -6.888455)
			(xy 253.580595 -6.896367) (xy 253.494845 -6.896367) (xy 253.409462 -6.888455) (xy 253.325172 -6.872699)
			(xy 253.242696 -6.849232) (xy 253.162737 -6.818256) (xy 253.085977 -6.780034) (xy 253.013071 -6.734893)
			(xy 252.944642 -6.683217) (xy 252.881272 -6.625448) (xy 252.823503 -6.562078) (xy 252.771827 -6.493649)
			(xy 252.726686 -6.420743) (xy 252.688464 -6.343983) (xy 252.657488 -6.264024) (xy 252.634021 -6.181548)
			(xy 252.618265 -6.097258) (xy 252.610353 -6.011875) (xy 248.115087 -6.011875) (xy 248.107175 -6.097258)
			(xy 248.091419 -6.181548) (xy 248.067952 -6.264024) (xy 248.036976 -6.343983) (xy 247.998754 -6.420743)
			(xy 247.953613 -6.493649) (xy 247.901937 -6.562078) (xy 247.844168 -6.625448) (xy 247.780798 -6.683217)
			(xy 247.712369 -6.734893) (xy 247.639463 -6.780034) (xy 247.562703 -6.818256) (xy 247.482744 -6.849232)
			(xy 247.400268 -6.872699) (xy 247.315978 -6.888455) (xy 247.230595 -6.896367) (xy 247.144845 -6.896367)
			(xy 247.059462 -6.888455) (xy 246.975172 -6.872699) (xy 246.892696 -6.849232) (xy 246.812737 -6.818256)
			(xy 246.735977 -6.780034) (xy 246.663071 -6.734893) (xy 246.594642 -6.683217) (xy 246.531272 -6.625448)
			(xy 246.473503 -6.562078) (xy 246.421827 -6.493649) (xy 246.376686 -6.420743) (xy 246.338464 -6.343983)
			(xy 246.307488 -6.264024) (xy 246.284021 -6.181548) (xy 246.268265 -6.097258) (xy 246.260353 -6.011875)
			(xy 216.248247 -6.011875) (xy 216.240335 -6.097258) (xy 216.224579 -6.181548) (xy 216.201112 -6.264024)
			(xy 216.170136 -6.343983) (xy 216.131914 -6.420743) (xy 216.086773 -6.493649) (xy 216.035097 -6.562078)
			(xy 215.977328 -6.625448) (xy 215.913958 -6.683217) (xy 215.845529 -6.734893) (xy 215.772623 -6.780034)
			(xy 215.695863 -6.818256) (xy 215.615904 -6.849232) (xy 215.533428 -6.872699) (xy 215.449138 -6.888455)
			(xy 215.363755 -6.896367) (xy 215.278005 -6.896367) (xy 215.192622 -6.888455) (xy 215.108332 -6.872699)
			(xy 215.025856 -6.849232) (xy 214.945897 -6.818256) (xy 214.869137 -6.780034) (xy 214.796231 -6.734893)
			(xy 214.727802 -6.683217) (xy 214.664432 -6.625448) (xy 214.606663 -6.562078) (xy 214.554987 -6.493649)
			(xy 214.509846 -6.420743) (xy 214.471624 -6.343983) (xy 214.440648 -6.264024) (xy 214.417181 -6.181548)
			(xy 214.401425 -6.097258) (xy 214.393513 -6.011875) (xy 209.898247 -6.011875) (xy 209.890335 -6.097258)
			(xy 209.874579 -6.181548) (xy 209.851112 -6.264024) (xy 209.820136 -6.343983) (xy 209.781914 -6.420743)
			(xy 209.736773 -6.493649) (xy 209.685097 -6.562078) (xy 209.627328 -6.625448) (xy 209.563958 -6.683217)
			(xy 209.495529 -6.734893) (xy 209.422623 -6.780034) (xy 209.345863 -6.818256) (xy 209.265904 -6.849232)
			(xy 209.183428 -6.872699) (xy 209.099138 -6.888455) (xy 209.013755 -6.896367) (xy 208.928005 -6.896367)
			(xy 208.842622 -6.888455) (xy 208.758332 -6.872699) (xy 208.675856 -6.849232) (xy 208.595897 -6.818256)
			(xy 208.519137 -6.780034) (xy 208.446231 -6.734893) (xy 208.377802 -6.683217) (xy 208.314432 -6.625448)
			(xy 208.256663 -6.562078) (xy 208.204987 -6.493649) (xy 208.159846 -6.420743) (xy 208.121624 -6.343983)
			(xy 208.090648 -6.264024) (xy 208.067181 -6.181548) (xy 208.051425 -6.097258) (xy 208.043513 -6.011875)
			(xy 197.209918 -6.011875) (xy 197.209918 -7.78002) (xy 197.21044 -7.835826) (xy 197.218783 -7.947127)
			(xy 197.235419 -8.057493) (xy 197.260257 -8.166307) (xy 197.293157 -8.27296) (xy 197.333935 -8.376857)
			(xy 197.382363 -8.477416) (xy 197.43817 -8.574075) (xy 197.501045 -8.666293) (xy 197.570635 -8.753555)
			(xy 197.646552 -8.835372) (xy 197.728371 -8.911287) (xy 197.815634 -8.980875) (xy 197.907854 -9.043748)
			(xy 198.004514 -9.099553) (xy 198.105074 -9.147979) (xy 198.208972 -9.188755) (xy 198.315626 -9.221652)
			(xy 198.424441 -9.246487) (xy 198.534807 -9.263121) (xy 198.646108 -9.271461) (xy 198.701914 -9.272016)
			(xy 223.300036 -9.272016) (xy 223.370389 -9.27251) (xy 223.510873 -9.280402) (xy 223.650694 -9.296158)
			(xy 223.789412 -9.319729) (xy 223.92659 -9.35104) (xy 224.061796 -9.389995) (xy 224.194606 -9.436468)
			(xy 224.3246 -9.490316) (xy 224.451371 -9.551367) (xy 224.57452 -9.619431) (xy 224.693658 -9.694292)
			(xy 224.808411 -9.775716) (xy 224.918419 -9.863446) (xy 225.023334 -9.957206) (xy 225.122827 -10.056701)
			(xy 225.216585 -10.161618) (xy 225.304313 -10.271627) (xy 225.385734 -10.386382) (xy 225.460594 -10.505522)
			(xy 225.528655 -10.628671) (xy 225.589704 -10.755444) (xy 225.643549 -10.885439) (xy 225.69002 -11.01825)
			(xy 225.728972 -11.153457) (xy 225.760281 -11.290635) (xy 225.783849 -11.429353) (xy 225.799602 -11.569174)
			(xy 225.807491 -11.709659) (xy 225.808032 -11.780012) (xy 225.808032 -31.197296) (xy 227.377752 -32.767016)
			(xy 254.645668 -32.767016)
		)
		(stroke
			(width 0)
			(type solid)
		)
		(fill yes)
		(layer "In10.Cu")
		(net "DELTA_L_GND_1")
	)
	(gr_poly
		(pts
			(xy 194.495928 -441.17006) (xy 194.49641 -441.126022) (xy 194.50409 -441.03828) (xy 194.519387 -440.951542)
			(xy 194.542185 -440.866466) (xy 194.572311 -440.783702) (xy 194.609536 -440.703878) (xy 194.653576 -440.627602)
			(xy 194.704095 -440.555454) (xy 194.760711 -440.487984) (xy 194.822991 -440.425704) (xy 194.890462 -440.369089)
			(xy 194.96261 -440.31857) (xy 195.038887 -440.274531) (xy 195.118711 -440.237308) (xy 195.201476 -440.207182)
			(xy 195.286551 -440.184385) (xy 195.37329 -440.169088) (xy 195.461032 -440.16141) (xy 195.50507 -440.160918)
			(xy 276.314916 -440.160918) (xy 276.358955 -440.161399) (xy 276.446699 -440.169077) (xy 276.533439 -440.184372)
			(xy 276.618516 -440.207169) (xy 276.701283 -440.237294) (xy 276.781109 -440.274518) (xy 276.857388 -440.318557)
			(xy 276.929538 -440.369076) (xy 276.99701 -440.425692) (xy 277.059292 -440.487972) (xy 277.115909 -440.555443)
			(xy 277.16643 -440.627592) (xy 277.210471 -440.703869) (xy 277.247697 -440.783695) (xy 277.277823 -440.866461)
			(xy 277.300622 -440.951538) (xy 277.31592 -441.038278) (xy 277.3236 -441.126021) (xy 277.324058 -441.17006)
			(xy 277.324058 -441.480956) (xy 463.300064 -441.480956) (xy 463.355834 -441.480449) (xy 463.467062 -441.472116)
			(xy 463.577357 -441.455494) (xy 463.686101 -441.430676) (xy 463.792686 -441.397801) (xy 463.896517 -441.357052)
			(xy 463.997011 -441.308658) (xy 464.093608 -441.252889) (xy 464.185768 -441.190057) (xy 464.272974 -441.120513)
			(xy 464.354739 -441.044647) (xy 464.430606 -440.962883) (xy 464.50015 -440.875677) (xy 464.562982 -440.783519)
			(xy 464.618752 -440.686922) (xy 464.667147 -440.586428) (xy 464.707897 -440.482598) (xy 464.740773 -440.376013)
			(xy 464.765592 -440.267269) (xy 464.782215 -440.156974) (xy 464.790548 -440.045746) (xy 464.791044 -439.989976)
			(xy 464.791044 -419.236652) (xy 464.79206 -419.236652) (xy 464.79206 -419.160198) (xy 464.791806 -419.158674)
			(xy 464.783625 -419.126333) (xy 464.774834 -419.060203) (xy 464.77428 -419.026848) (xy 464.774826 -418.994155)
			(xy 464.783231 -418.929312) (xy 464.791044 -418.897562) (xy 464.791044 -409.528264) (xy 464.791527 -409.457889)
			(xy 464.799416 -409.317359) (xy 464.815173 -409.177493) (xy 464.838748 -409.03873) (xy 464.870067 -408.901508)
			(xy 464.909031 -408.766258) (xy 464.955519 -408.633405) (xy 465.009383 -408.503369) (xy 465.070454 -408.376557)
			(xy 465.138539 -408.25337) (xy 465.213426 -408.134194) (xy 465.294877 -408.019405) (xy 465.382637 -407.909364)
			(xy 465.47643 -407.804418) (xy 465.525866 -407.754328) (xy 467.354412 -405.925782) (xy 467.391723 -405.887821)
			(xy 467.461438 -405.807375) (xy 467.525236 -405.722161) (xy 467.582791 -405.632611) (xy 467.633809 -405.539182)
			(xy 467.678031 -405.442352) (xy 467.715231 -405.342613) (xy 467.74522 -405.240474) (xy 467.767844 -405.136455)
			(xy 467.782988 -405.031087) (xy 467.790575 -404.924907) (xy 467.791038 -404.871682) (xy 467.791038 -82.82813)
			(xy 467.791541 -82.757757) (xy 467.799451 -82.617233) (xy 467.815226 -82.477373) (xy 467.838815 -82.338618)
			(xy 467.870145 -82.201402) (xy 467.909116 -82.066159) (xy 467.955608 -81.933313) (xy 468.009473 -81.803282)
			(xy 468.070541 -81.676474) (xy 468.138622 -81.553289) (xy 468.213501 -81.434114) (xy 468.294942 -81.319323)
			(xy 468.382689 -81.209278) (xy 468.476467 -81.104324) (xy 468.52586 -81.054194) (xy 470.854278 -78.725776)
			(xy 470.891589 -78.687815) (xy 470.961306 -78.60737) (xy 471.025105 -78.522156) (xy 471.082661 -78.432606)
			(xy 471.13368 -78.339178) (xy 471.177903 -78.242348) (xy 471.215103 -78.142608) (xy 471.245092 -78.040469)
			(xy 471.267716 -77.93645) (xy 471.28286 -77.831082) (xy 471.290447 -77.724901) (xy 471.290904 -77.671676)
			(xy 471.290904 -13.780008) (xy 471.290383 -13.724238) (xy 471.282048 -13.613011) (xy 471.265425 -13.502718)
			(xy 471.240606 -13.393975) (xy 471.20773 -13.287391) (xy 471.166981 -13.183562) (xy 471.118587 -13.083068)
			(xy 471.062818 -12.986472) (xy 470.999987 -12.894314) (xy 470.930444 -12.807108) (xy 470.854579 -12.725344)
			(xy 470.772816 -12.649477) (xy 470.685612 -12.579932) (xy 470.593455 -12.517099) (xy 470.49686 -12.461328)
			(xy 470.396367 -12.412932) (xy 470.292539 -12.372181) (xy 470.185956 -12.339303) (xy 470.077214 -12.314481)
			(xy 469.966921 -12.297855) (xy 469.855694 -12.289518) (xy 469.799924 -12.289028) (xy 464.613244 -12.289028)
			(xy 464.613244 -12.288012) (xy 464.272376 -12.288012) (xy 464.272376 -12.289028) (xy 458.20203 -12.289028)
			(xy 458.131647 -12.288544) (xy 457.991102 -12.280653) (xy 457.85122 -12.264894) (xy 457.712443 -12.241316)
			(xy 457.575205 -12.209994) (xy 457.43994 -12.171027) (xy 457.307072 -12.124536) (xy 457.177021 -12.070668)
			(xy 457.050194 -12.009593) (xy 456.926991 -11.941503) (xy 456.8078 -11.866612) (xy 456.692996 -11.785156)
			(xy 456.582939 -11.69739) (xy 456.477977 -11.603592) (xy 456.378439 -11.504056) (xy 456.284639 -11.399096)
			(xy 456.196872 -11.289041) (xy 456.115413 -11.174238) (xy 456.04052 -11.055048) (xy 455.972428 -10.931847)
			(xy 455.911351 -10.805021) (xy 455.857481 -10.674971) (xy 455.810987 -10.542104) (xy 455.772017 -10.406839)
			(xy 455.740693 -10.269603) (xy 455.717113 -10.130825) (xy 455.701351 -9.990944) (xy 455.693457 -9.850399)
			(xy 455.693018 -9.780016) (xy 455.693018 -0.999998) (xy 455.692493 -0.967851) (xy 455.684101 -0.904107)
			(xy 455.667461 -0.842004) (xy 455.642857 -0.782603) (xy 455.610712 -0.726922) (xy 455.571573 -0.675913)
			(xy 455.526112 -0.630449) (xy 455.475106 -0.591307) (xy 455.419427 -0.559158) (xy 455.360029 -0.53455)
			(xy 455.297926 -0.517906) (xy 455.234183 -0.50951) (xy 455.202036 -0.509016) (xy 388.601966 -0.509016)
			(xy 388.569821 -0.509544) (xy 388.506082 -0.517939) (xy 388.443984 -0.534582) (xy 388.384589 -0.559188)
			(xy 388.328914 -0.591335) (xy 388.277911 -0.630474) (xy 388.232453 -0.675936) (xy 388.193318 -0.726941)
			(xy 388.161174 -0.782618) (xy 388.136572 -0.842014) (xy 388.119933 -0.904114) (xy 388.111542 -0.967853)
			(xy 388.110984 -0.999998) (xy 388.110984 -5.169916) (xy 388.850131 -5.169916) (xy 388.854136 -5.082008)
			(xy 388.866119 -4.994828) (xy 388.885979 -4.909099) (xy 388.913554 -4.825531) (xy 388.948613 -4.744817)
			(xy 388.990866 -4.667625) (xy 389.039964 -4.594596) (xy 389.0955 -4.526334) (xy 389.157012 -4.463404)
			(xy 389.223993 -4.40633) (xy 389.295886 -4.355582) (xy 389.372095 -4.311582) (xy 389.45199 -4.274695)
			(xy 389.534909 -4.245226) (xy 389.620164 -4.223419) (xy 389.707048 -4.209455) (xy 389.794842 -4.203449)
			(xy 389.882819 -4.205453) (xy 389.970249 -4.215448) (xy 390.056408 -4.233352) (xy 390.140582 -4.259016)
			(xy 390.222073 -4.292229) (xy 390.300207 -4.332715) (xy 390.374335 -4.380137) (xy 390.443843 -4.434104)
			(xy 390.508157 -4.494169) (xy 390.566741 -4.559833) (xy 390.619112 -4.630552) (xy 390.664835 -4.70574)
			(xy 390.703532 -4.784775) (xy 390.734881 -4.867001) (xy 390.758623 -4.951737) (xy 390.763638 -4.978969)
			(xy 394.947631 -4.978969) (xy 394.947631 -4.924431) (xy 394.955393 -4.870448) (xy 394.970758 -4.81812)
			(xy 394.993414 -4.76851) (xy 395.0229 -4.72263) (xy 395.058614 -4.681413) (xy 395.099832 -4.645698)
			(xy 395.145712 -4.616213) (xy 395.195321 -4.593557) (xy 395.24765 -4.578193) (xy 395.301633 -4.570431)
			(xy 395.328902 -4.569968) (xy 396.192502 -4.569968) (xy 396.219773 -4.570395) (xy 396.273761 -4.578157)
			(xy 396.326094 -4.593524) (xy 396.375708 -4.616182) (xy 396.421593 -4.64567) (xy 396.462813 -4.681388)
			(xy 396.498531 -4.722609) (xy 396.528019 -4.768493) (xy 396.550677 -4.818107) (xy 396.566043 -4.870441)
			(xy 396.573806 -4.924429) (xy 396.573806 -4.978971) (xy 398.547532 -4.978971) (xy 398.547532 -4.924429)
			(xy 398.555294 -4.870443) (xy 398.570661 -4.818111) (xy 398.593321 -4.768498) (xy 398.62281 -4.722616)
			(xy 398.658529 -4.681398) (xy 398.699751 -4.645684) (xy 398.745637 -4.616199) (xy 398.795252 -4.593546)
			(xy 398.847586 -4.578185) (xy 398.901573 -4.570428) (xy 398.928844 -4.569968) (xy 399.792444 -4.569968)
			(xy 399.819713 -4.570398) (xy 399.873697 -4.578165) (xy 399.926025 -4.593535) (xy 399.975633 -4.616196)
			(xy 400.021512 -4.645685) (xy 400.062728 -4.681403) (xy 400.098441 -4.722623) (xy 400.127925 -4.768505)
			(xy 400.15058 -4.818116) (xy 400.165944 -4.870447) (xy 400.173706 -4.92443) (xy 400.173706 -4.978967)
			(xy 402.147554 -4.978967) (xy 402.147554 -4.924433) (xy 402.155315 -4.870455) (xy 402.170678 -4.818131)
			(xy 402.193332 -4.768526) (xy 402.222814 -4.722649) (xy 402.258525 -4.681435) (xy 402.299738 -4.645722)
			(xy 402.345613 -4.616239) (xy 402.395218 -4.593583) (xy 402.447542 -4.578218) (xy 402.501519 -4.570455)
			(xy 402.528786 -4.569968) (xy 403.392386 -4.569968) (xy 403.41966 -4.570371) (xy 403.473652 -4.578132)
			(xy 403.525991 -4.593498) (xy 403.57561 -4.616157) (xy 403.621499 -4.645646) (xy 403.662724 -4.681366)
			(xy 403.698445 -4.72259) (xy 403.727937 -4.768478) (xy 403.750597 -4.818096) (xy 403.765965 -4.870434)
			(xy 403.773728 -4.924426) (xy 403.773728 -4.978966) (xy 405.747754 -4.978966) (xy 405.747754 -4.924434)
			(xy 405.755515 -4.870456) (xy 405.770878 -4.818132) (xy 405.793531 -4.768527) (xy 405.823013 -4.72265)
			(xy 405.858724 -4.681436) (xy 405.899936 -4.645724) (xy 405.945811 -4.61624) (xy 405.995415 -4.593584)
			(xy 406.047738 -4.578219) (xy 406.101716 -4.570456) (xy 406.128982 -4.569968) (xy 406.992582 -4.569968)
			(xy 407.019856 -4.57037) (xy 407.073849 -4.578131) (xy 407.126188 -4.593497) (xy 407.175807 -4.616155)
			(xy 407.221697 -4.645645) (xy 407.262922 -4.681365) (xy 407.298644 -4.722589) (xy 407.328136 -4.768477)
			(xy 407.350797 -4.818095) (xy 407.366165 -4.870433) (xy 407.373928 -4.924426) (xy 407.373928 -4.978971)
			(xy 414.857632 -4.978971) (xy 414.857632 -4.924429) (xy 414.865394 -4.870442) (xy 414.880762 -4.81811)
			(xy 414.903421 -4.768498) (xy 414.93291 -4.722616) (xy 414.96863 -4.681397) (xy 415.009852 -4.645683)
			(xy 415.055738 -4.616199) (xy 415.105353 -4.593546) (xy 415.157687 -4.578184) (xy 415.211675 -4.570428)
			(xy 415.238946 -4.569968) (xy 416.102546 -4.569968) (xy 416.129815 -4.570398) (xy 416.183798 -4.578165)
			(xy 416.236126 -4.593536) (xy 416.285735 -4.616196) (xy 416.331613 -4.645686) (xy 416.372829 -4.681404)
			(xy 416.408542 -4.722624) (xy 416.438026 -4.768506) (xy 416.46068 -4.818117) (xy 416.476045 -4.870447)
			(xy 416.483806 -4.924431) (xy 416.483806 -4.978967) (xy 418.457654 -4.978967) (xy 418.457654 -4.924433)
			(xy 418.465415 -4.870455) (xy 418.480779 -4.818131) (xy 418.503432 -4.768525) (xy 418.532915 -4.722648)
			(xy 418.568626 -4.681434) (xy 418.609839 -4.645722) (xy 418.655715 -4.616238) (xy 418.705319 -4.593583)
			(xy 418.757643 -4.578218) (xy 418.811621 -4.570455) (xy 418.838888 -4.569968) (xy 419.702488 -4.569968)
			(xy 419.729762 -4.570371) (xy 419.783754 -4.578132) (xy 419.836092 -4.593499) (xy 419.885711 -4.616157)
			(xy 419.9316 -4.645647) (xy 419.972824 -4.681367) (xy 420.008546 -4.722591) (xy 420.038037 -4.768479)
			(xy 420.060697 -4.818096) (xy 420.076065 -4.870434) (xy 420.083828 -4.924426) (xy 420.083828 -4.978966)
			(xy 426.067754 -4.978966) (xy 426.067754 -4.924434) (xy 426.075515 -4.870456) (xy 426.090878 -4.818132)
			(xy 426.113531 -4.768527) (xy 426.143013 -4.72265) (xy 426.178724 -4.681436) (xy 426.219936 -4.645724)
			(xy 426.265811 -4.61624) (xy 426.315415 -4.593584) (xy 426.367738 -4.578219) (xy 426.421716 -4.570456)
			(xy 426.448982 -4.569968) (xy 427.312582 -4.569968) (xy 427.339856 -4.57037) (xy 427.393849 -4.578131)
			(xy 427.446188 -4.593497) (xy 427.495807 -4.616155) (xy 427.541697 -4.645645) (xy 427.582922 -4.681365)
			(xy 427.618644 -4.722589) (xy 427.648136 -4.768477) (xy 427.670797 -4.818095) (xy 427.686165 -4.870433)
			(xy 427.693928 -4.924426) (xy 427.693928 -4.97897) (xy 429.667631 -4.97897) (xy 429.667631 -4.92443)
			(xy 429.675394 -4.870445) (xy 429.69076 -4.818115) (xy 429.713417 -4.768504) (xy 429.742905 -4.722623)
			(xy 429.778622 -4.681405) (xy 429.819842 -4.645691) (xy 429.865725 -4.616206) (xy 429.915337 -4.593552)
			(xy 429.967669 -4.578189) (xy 430.021654 -4.57043) (xy 430.048924 -4.569968) (xy 430.912524 -4.569968)
			(xy 430.939794 -4.570396) (xy 430.99378 -4.578161) (xy 431.04611 -4.59353) (xy 431.095721 -4.616189)
			(xy 431.141603 -4.645678) (xy 431.182821 -4.681396) (xy 431.218536 -4.722616) (xy 431.248022 -4.7685)
			(xy 431.270679 -4.818112) (xy 431.286044 -4.870444) (xy 431.293806 -4.92443) (xy 431.293806 -4.97897)
			(xy 431.286044 -5.032956) (xy 431.270679 -5.085288) (xy 431.248022 -5.1349) (xy 431.218536 -5.180784)
			(xy 431.182821 -5.222004) (xy 431.141603 -5.257722) (xy 431.095721 -5.287211) (xy 431.04611 -5.30987)
			(xy 430.99378 -5.325239) (xy 430.939794 -5.333004) (xy 430.912524 -5.333492) (xy 430.048924 -5.333492)
			(xy 430.021654 -5.33297) (xy 429.967669 -5.325211) (xy 429.915337 -5.309848) (xy 429.865725 -5.287194)
			(xy 429.819842 -5.257709) (xy 429.778622 -5.221995) (xy 429.742905 -5.180777) (xy 429.713417 -5.134896)
			(xy 429.69076 -5.085285) (xy 429.675394 -5.032955) (xy 429.667631 -4.97897) (xy 427.693928 -4.97897)
			(xy 427.693928 -4.978974) (xy 427.686165 -5.032967) (xy 427.670797 -5.085305) (xy 427.648136 -5.134923)
			(xy 427.618644 -5.180811) (xy 427.582922 -5.222035) (xy 427.541697 -5.257755) (xy 427.495807 -5.287245)
			(xy 427.446188 -5.309903) (xy 427.393849 -5.325269) (xy 427.339856 -5.33303) (xy 427.312582 -5.333492)
			(xy 426.448982 -5.333492) (xy 426.421716 -5.332944) (xy 426.367738 -5.325181) (xy 426.315415 -5.309816)
			(xy 426.265811 -5.28716) (xy 426.219936 -5.257676) (xy 426.178724 -5.221964) (xy 426.143013 -5.18075)
			(xy 426.113531 -5.134873) (xy 426.090878 -5.085268) (xy 426.075515 -5.032944) (xy 426.067754 -4.978966)
			(xy 420.083828 -4.978966) (xy 420.083828 -4.978974) (xy 420.076065 -5.032966) (xy 420.060697 -5.085304)
			(xy 420.038037 -5.134921) (xy 420.008546 -5.180809) (xy 419.972824 -5.222033) (xy 419.9316 -5.257753)
			(xy 419.885711 -5.287243) (xy 419.836092 -5.309901) (xy 419.783754 -5.325268) (xy 419.729762 -5.333029)
			(xy 419.702488 -5.333492) (xy 418.838888 -5.333492) (xy 418.811621 -5.332945) (xy 418.757643 -5.325182)
			(xy 418.705319 -5.309817) (xy 418.655715 -5.287162) (xy 418.609839 -5.257678) (xy 418.568626 -5.221966)
			(xy 418.532915 -5.180752) (xy 418.503432 -5.134875) (xy 418.480779 -5.085269) (xy 418.465415 -5.032945)
			(xy 418.457654 -4.978967) (xy 416.483806 -4.978967) (xy 416.483806 -4.978969) (xy 416.476045 -5.032953)
			(xy 416.46068 -5.085283) (xy 416.438026 -5.134894) (xy 416.408542 -5.180776) (xy 416.372829 -5.221996)
			(xy 416.331613 -5.257714) (xy 416.285735 -5.287204) (xy 416.236126 -5.309864) (xy 416.183798 -5.325235)
			(xy 416.129815 -5.333002) (xy 416.102546 -5.333492) (xy 415.238946 -5.333492) (xy 415.211675 -5.332972)
			(xy 415.157687 -5.325216) (xy 415.105353 -5.309854) (xy 415.055738 -5.287201) (xy 415.009852 -5.257717)
			(xy 414.96863 -5.222003) (xy 414.93291 -5.180784) (xy 414.903421 -5.134902) (xy 414.880762 -5.08529)
			(xy 414.865394 -5.032958) (xy 414.857632 -4.978971) (xy 407.373928 -4.978971) (xy 407.373928 -4.978974)
			(xy 407.366165 -5.032967) (xy 407.350797 -5.085305) (xy 407.328136 -5.134923) (xy 407.298644 -5.180811)
			(xy 407.262922 -5.222035) (xy 407.221697 -5.257755) (xy 407.175807 -5.287245) (xy 407.126188 -5.309903)
			(xy 407.073849 -5.325269) (xy 407.019856 -5.33303) (xy 406.992582 -5.333492) (xy 406.128982 -5.333492)
			(xy 406.101716 -5.332944) (xy 406.047738 -5.325181) (xy 405.995415 -5.309816) (xy 405.945811 -5.28716)
			(xy 405.899936 -5.257676) (xy 405.858724 -5.221964) (xy 405.823013 -5.18075) (xy 405.793531 -5.134873)
			(xy 405.770878 -5.085268) (xy 405.755515 -5.032944) (xy 405.747754 -4.978966) (xy 403.773728 -4.978966)
			(xy 403.773728 -4.978974) (xy 403.765965 -5.032966) (xy 403.750597 -5.085304) (xy 403.727937 -5.134922)
			(xy 403.698445 -5.18081) (xy 403.662724 -5.222034) (xy 403.621499 -5.257754) (xy 403.57561 -5.287243)
			(xy 403.525991 -5.309902) (xy 403.473652 -5.325268) (xy 403.41966 -5.333029) (xy 403.392386 -5.333492)
			(xy 402.528786 -5.333492) (xy 402.501519 -5.332945) (xy 402.447542 -5.325182) (xy 402.395218 -5.309817)
			(xy 402.345613 -5.287161) (xy 402.299738 -5.257678) (xy 402.258525 -5.221965) (xy 402.222814 -5.180751)
			(xy 402.193332 -5.134874) (xy 402.170678 -5.085269) (xy 402.155315 -5.032945) (xy 402.147554 -4.978967)
			(xy 400.173706 -4.978967) (xy 400.173706 -4.97897) (xy 400.165944 -5.032953) (xy 400.15058 -5.085284)
			(xy 400.127925 -5.134895) (xy 400.098441 -5.180777) (xy 400.062728 -5.221997) (xy 400.021512 -5.257715)
			(xy 399.975633 -5.287204) (xy 399.926025 -5.309865) (xy 399.873697 -5.325235) (xy 399.819713 -5.333002)
			(xy 399.792444 -5.333492) (xy 398.928844 -5.333492) (xy 398.901573 -5.332972) (xy 398.847586 -5.325215)
			(xy 398.795252 -5.309854) (xy 398.745637 -5.287201) (xy 398.699751 -5.257716) (xy 398.658529 -5.222002)
			(xy 398.62281 -5.180784) (xy 398.593321 -5.134902) (xy 398.570661 -5.085289) (xy 398.555294 -5.032957)
			(xy 398.547532 -4.978971) (xy 396.573806 -4.978971) (xy 396.566043 -5.032959) (xy 396.550677 -5.085293)
			(xy 396.528019 -5.134907) (xy 396.498531 -5.180791) (xy 396.462813 -5.222012) (xy 396.421593 -5.25773)
			(xy 396.375708 -5.287218) (xy 396.326094 -5.309876) (xy 396.273761 -5.325243) (xy 396.219773 -5.333005)
			(xy 396.192502 -5.333492) (xy 395.328902 -5.333492) (xy 395.301633 -5.332969) (xy 395.24765 -5.325207)
			(xy 395.195321 -5.309843) (xy 395.145712 -5.287187) (xy 395.099832 -5.257702) (xy 395.058614 -5.221987)
			(xy 395.0229 -5.18077) (xy 394.993414 -5.13489) (xy 394.970758 -5.08528) (xy 394.955393 -5.032952)
			(xy 394.947631 -4.978969) (xy 390.763638 -4.978969) (xy 390.774561 -5.038281) (xy 390.782563 -5.125916)
			(xy 390.783064 -5.169916) (xy 390.782563 -5.213916) (xy 390.774561 -5.301551) (xy 390.758623 -5.388095)
			(xy 390.734881 -5.472831) (xy 390.703532 -5.555057) (xy 390.664835 -5.634092) (xy 390.619112 -5.70928)
			(xy 390.566741 -5.779999) (xy 390.508157 -5.845663) (xy 390.443843 -5.905728) (xy 390.374335 -5.959695)
			(xy 390.300207 -6.007117) (xy 390.222073 -6.047603) (xy 390.140582 -6.080816) (xy 390.056408 -6.10648)
			(xy 389.970249 -6.124384) (xy 389.882819 -6.134379) (xy 389.794842 -6.136383) (xy 389.707048 -6.130377)
			(xy 389.620164 -6.116413) (xy 389.534909 -6.094606) (xy 389.45199 -6.065137) (xy 389.372095 -6.02825)
			(xy 389.295886 -5.98425) (xy 389.223993 -5.933502) (xy 389.157012 -5.876428) (xy 389.0955 -5.813498)
			(xy 389.039964 -5.745236) (xy 388.990866 -5.672207) (xy 388.948613 -5.595015) (xy 388.913554 -5.514301)
			(xy 388.885979 -5.430733) (xy 388.866119 -5.345004) (xy 388.854136 -5.257824) (xy 388.850131 -5.169916)
			(xy 388.110984 -5.169916) (xy 388.110984 -6.169914) (xy 453.015103 -6.169914) (xy 453.019108 -6.082006)
			(xy 453.031091 -5.994826) (xy 453.050951 -5.909097) (xy 453.078526 -5.825529) (xy 453.113585 -5.744815)
			(xy 453.155838 -5.667623) (xy 453.204936 -5.594594) (xy 453.260472 -5.526332) (xy 453.321984 -5.463402)
			(xy 453.388965 -5.406328) (xy 453.460858 -5.35558) (xy 453.537067 -5.31158) (xy 453.616962 -5.274693)
			(xy 453.699881 -5.245224) (xy 453.785136 -5.223417) (xy 453.87202 -5.209453) (xy 453.959814 -5.203447)
			(xy 454.047791 -5.205451) (xy 454.135221 -5.215446) (xy 454.22138 -5.23335) (xy 454.305554 -5.259014)
			(xy 454.387045 -5.292227) (xy 454.465179 -5.332713) (xy 454.539307 -5.380135) (xy 454.608815 -5.434102)
			(xy 454.673129 -5.494167) (xy 454.731713 -5.559831) (xy 454.784084 -5.63055) (xy 454.829807 -5.705738)
			(xy 454.868504 -5.784773) (xy 454.899853 -5.866999) (xy 454.923595 -5.951735) (xy 454.939533 -6.038279)
			(xy 454.947535 -6.125914) (xy 454.948036 -6.169914) (xy 454.947535 -6.213914) (xy 454.939533 -6.301549)
			(xy 454.923595 -6.388093) (xy 454.899853 -6.472829) (xy 454.868504 -6.555055) (xy 454.829807 -6.63409)
			(xy 454.784084 -6.709278) (xy 454.731713 -6.779997) (xy 454.673129 -6.845661) (xy 454.608815 -6.905726)
			(xy 454.539307 -6.959693) (xy 454.465179 -7.007115) (xy 454.387045 -7.047601) (xy 454.305554 -7.080814)
			(xy 454.22138 -7.106478) (xy 454.135221 -7.124382) (xy 454.047791 -7.134377) (xy 453.959814 -7.136381)
			(xy 453.87202 -7.130375) (xy 453.785136 -7.116411) (xy 453.699881 -7.094604) (xy 453.616962 -7.065135)
			(xy 453.537067 -7.028248) (xy 453.460858 -6.984248) (xy 453.388965 -6.9335) (xy 453.321984 -6.876426)
			(xy 453.260472 -6.813496) (xy 453.204936 -6.745234) (xy 453.155838 -6.672205) (xy 453.113585 -6.595013)
			(xy 453.078526 -6.514299) (xy 453.050951 -6.430731) (xy 453.031091 -6.345002) (xy 453.019108 -6.257822)
			(xy 453.015103 -6.169914) (xy 388.110984 -6.169914) (xy 388.110984 -6.740774) (xy 393.142876 -6.740774)
			(xy 393.142876 -6.686226) (xy 393.150639 -6.632232) (xy 393.166008 -6.579894) (xy 393.18867 -6.530275)
			(xy 393.218162 -6.484387) (xy 393.253885 -6.443163) (xy 393.295112 -6.407443) (xy 393.341003 -6.377954)
			(xy 393.390624 -6.355297) (xy 393.442964 -6.339932) (xy 393.496958 -6.332173) (xy 393.524232 -6.331712)
			(xy 394.387832 -6.331712) (xy 394.415098 -6.332253) (xy 394.469074 -6.340017) (xy 394.521397 -6.355384)
			(xy 394.570999 -6.378041) (xy 394.616873 -6.407526) (xy 394.658084 -6.443238) (xy 394.693794 -6.484452)
			(xy 394.723274 -6.530329) (xy 394.745927 -6.579933) (xy 394.761289 -6.632257) (xy 394.76905 -6.686234)
			(xy 394.76905 -6.740766) (xy 394.769049 -6.74077) (xy 396.742898 -6.74077) (xy 396.742898 -6.68623)
			(xy 396.75066 -6.632245) (xy 396.766025 -6.579914) (xy 396.788681 -6.530302) (xy 396.818166 -6.484419)
			(xy 396.853881 -6.4432) (xy 396.895099 -6.407482) (xy 396.940979 -6.377993) (xy 396.99059 -6.355334)
			(xy 397.04292 -6.339965) (xy 397.096904 -6.3322) (xy 397.124174 -6.331712) (xy 397.987774 -6.331712)
			(xy 398.015044 -6.332226) (xy 398.06903 -6.339984) (xy 398.121363 -6.355347) (xy 398.170976 -6.378002)
			(xy 398.216859 -6.407487) (xy 398.25808 -6.443202) (xy 398.293798 -6.48442) (xy 398.323286 -6.530301)
			(xy 398.345944 -6.579913) (xy 398.36131 -6.632244) (xy 398.369072 -6.68623) (xy 398.369072 -6.74077)
			(xy 398.369071 -6.740774) (xy 400.342776 -6.740774) (xy 400.342776 -6.686226) (xy 400.350539 -6.632234)
			(xy 400.365907 -6.579897) (xy 400.388567 -6.530279) (xy 400.418058 -6.484392) (xy 400.45378 -6.443168)
			(xy 400.495005 -6.407449) (xy 400.540893 -6.377959) (xy 400.590512 -6.355301) (xy 400.64285 -6.339935)
			(xy 400.696842 -6.332174) (xy 400.724116 -6.331712) (xy 401.587716 -6.331712) (xy 401.614983 -6.332251)
			(xy 401.668961 -6.340014) (xy 401.721285 -6.35538) (xy 401.77089 -6.378036) (xy 401.816766 -6.40752)
			(xy 401.857978 -6.443233) (xy 401.89369 -6.484447) (xy 401.923172 -6.530324) (xy 401.945825 -6.57993)
			(xy 401.961189 -6.632255) (xy 401.96895 -6.686233) (xy 401.96895 -6.740767) (xy 401.968949 -6.740773)
			(xy 403.942976 -6.740773) (xy 403.942976 -6.686227) (xy 403.950739 -6.632235) (xy 403.966106 -6.579898)
			(xy 403.988766 -6.53028) (xy 404.018257 -6.484393) (xy 404.053978 -6.44317) (xy 404.095203 -6.40745)
			(xy 404.141091 -6.377961) (xy 404.190709 -6.355302) (xy 404.243047 -6.339936) (xy 404.297039 -6.332175)
			(xy 404.324312 -6.331712) (xy 405.187912 -6.331712) (xy 405.215179 -6.332251) (xy 405.269158 -6.340014)
			(xy 405.321482 -6.355379) (xy 405.371087 -6.378034) (xy 405.416964 -6.407519) (xy 405.458177 -6.443231)
			(xy 405.493889 -6.484446) (xy 405.523371 -6.530323) (xy 405.546025 -6.579929) (xy 405.561389 -6.632254)
			(xy 405.56915 -6.686233) (xy 405.56915 -6.740767) (xy 405.56915 -6.74077) (xy 413.052998 -6.74077)
			(xy 413.052998 -6.68623) (xy 413.06076 -6.632245) (xy 413.076125 -6.579914) (xy 413.098781 -6.530302)
			(xy 413.128267 -6.484419) (xy 413.163982 -6.443199) (xy 413.205199 -6.407481) (xy 413.25108 -6.377993)
			(xy 413.300691 -6.355334) (xy 413.353021 -6.339965) (xy 413.407006 -6.3322) (xy 413.434276 -6.331712)
			(xy 414.297876 -6.331712) (xy 414.325146 -6.332226) (xy 414.379132 -6.339985) (xy 414.431464 -6.355348)
			(xy 414.481077 -6.378002) (xy 414.52696 -6.407487) (xy 414.568181 -6.443202) (xy 414.603898 -6.48442)
			(xy 414.633386 -6.530302) (xy 414.656044 -6.579913) (xy 414.67141 -6.632244) (xy 414.679173 -6.68623)
			(xy 414.679173 -6.74077) (xy 414.679172 -6.740774) (xy 416.652876 -6.740774) (xy 416.652876 -6.686226)
			(xy 416.660639 -6.632234) (xy 416.676007 -6.579897) (xy 416.698667 -6.530279) (xy 416.728159 -6.484391)
			(xy 416.763881 -6.443168) (xy 416.805106 -6.407448) (xy 416.850995 -6.377959) (xy 416.900613 -6.355301)
			(xy 416.952952 -6.339935) (xy 417.006944 -6.332174) (xy 417.034218 -6.331712) (xy 417.897818 -6.331712)
			(xy 417.925085 -6.332252) (xy 417.979063 -6.340015) (xy 418.031386 -6.355381) (xy 418.080991 -6.378036)
			(xy 418.126867 -6.407521) (xy 418.168079 -6.443234) (xy 418.20379 -6.484448) (xy 418.233272 -6.530325)
			(xy 418.255926 -6.57993) (xy 418.271289 -6.632255) (xy 418.27905 -6.686233) (xy 418.27905 -6.740767)
			(xy 418.279049 -6.740773) (xy 424.262976 -6.740773) (xy 424.262976 -6.686227) (xy 424.270739 -6.632235)
			(xy 424.286106 -6.579898) (xy 424.308766 -6.53028) (xy 424.338257 -6.484393) (xy 424.373978 -6.44317)
			(xy 424.415203 -6.40745) (xy 424.461091 -6.377961) (xy 424.510709 -6.355302) (xy 424.563047 -6.339936)
			(xy 424.617039 -6.332175) (xy 424.644312 -6.331712) (xy 425.507912 -6.331712) (xy 425.535179 -6.332251)
			(xy 425.589158 -6.340014) (xy 425.641482 -6.355379) (xy 425.691087 -6.378034) (xy 425.736964 -6.407519)
			(xy 425.778177 -6.443231) (xy 425.813889 -6.484446) (xy 425.843371 -6.530323) (xy 425.866025 -6.579929)
			(xy 425.881389 -6.632254) (xy 425.88915 -6.686233) (xy 425.88915 -6.740767) (xy 425.88915 -6.740769)
			(xy 427.862998 -6.740769) (xy 427.862998 -6.686231) (xy 427.870759 -6.632248) (xy 427.886123 -6.579918)
			(xy 427.908778 -6.530308) (xy 427.938261 -6.484426) (xy 427.973974 -6.443207) (xy 428.015189 -6.407489)
			(xy 428.061067 -6.378) (xy 428.110675 -6.35534) (xy 428.163003 -6.339969) (xy 428.216985 -6.332202)
			(xy 428.244254 -6.331712) (xy 429.107854 -6.331712) (xy 429.135125 -6.332224) (xy 429.189113 -6.339981)
			(xy 429.241448 -6.355342) (xy 429.291064 -6.377995) (xy 429.33695 -6.40748) (xy 429.378173 -6.443195)
			(xy 429.413893 -6.484413) (xy 429.443383 -6.530296) (xy 429.466042 -6.579909) (xy 429.48141 -6.632242)
			(xy 429.489172 -6.686229) (xy 429.489172 -6.740771) (xy 429.488151 -6.747873) (xy 431.473788 -6.747873)
			(xy 431.473788 -6.693327) (xy 431.48155 -6.639337) (xy 431.496918 -6.587001) (xy 431.519578 -6.537385)
			(xy 431.549068 -6.491498) (xy 431.584789 -6.450276) (xy 431.626013 -6.414558) (xy 431.6719 -6.385069)
			(xy 431.721518 -6.362412) (xy 431.773854 -6.347047) (xy 431.827845 -6.339286) (xy 431.855118 -6.338824)
			(xy 432.718718 -6.338824) (xy 432.745986 -6.33934) (xy 432.799965 -6.347103) (xy 432.852291 -6.362469)
			(xy 432.901897 -6.385126) (xy 432.947774 -6.414611) (xy 432.988988 -6.450325) (xy 433.0247 -6.491541)
			(xy 433.054183 -6.537419) (xy 433.076837 -6.587026) (xy 433.092201 -6.639352) (xy 433.099962 -6.693332)
			(xy 433.099962 -6.740771) (xy 445.457798 -6.740771) (xy 445.457798 -6.686229) (xy 445.46556 -6.632243)
			(xy 445.480926 -6.579911) (xy 445.503583 -6.530298) (xy 445.53307 -6.484415) (xy 445.568786 -6.443195)
			(xy 445.610005 -6.407477) (xy 445.655888 -6.377989) (xy 445.7055 -6.35533) (xy 445.757831 -6.339963)
			(xy 445.811817 -6.332199) (xy 445.839088 -6.331712) (xy 446.702688 -6.331712) (xy 446.729958 -6.332227)
			(xy 446.783942 -6.339987) (xy 446.836273 -6.355351) (xy 446.885884 -6.378006) (xy 446.931766 -6.407492)
			(xy 446.972985 -6.443207) (xy 447.008701 -6.484424) (xy 447.038188 -6.530305) (xy 447.060845 -6.579916)
			(xy 447.076211 -6.632246) (xy 447.083973 -6.68623) (xy 447.083973 -6.74077) (xy 447.076211 -6.794754)
			(xy 447.060845 -6.847084) (xy 447.038188 -6.896695) (xy 447.008701 -6.942576) (xy 446.972985 -6.983793)
			(xy 446.931766 -7.019508) (xy 446.885884 -7.048994) (xy 446.836273 -7.071649) (xy 446.783942 -7.087013)
			(xy 446.729958 -7.094773) (xy 446.702688 -7.095236) (xy 445.839088 -7.095236) (xy 445.811817 -7.094801)
			(xy 445.757831 -7.087037) (xy 445.7055 -7.07167) (xy 445.655888 -7.049011) (xy 445.610005 -7.019523)
			(xy 445.568786 -6.983805) (xy 445.53307 -6.942585) (xy 445.503583 -6.896702) (xy 445.480926 -6.847089)
			(xy 445.46556 -6.794757) (xy 445.457798 -6.740771) (xy 433.099962 -6.740771) (xy 433.099962 -6.747868)
			(xy 433.092201 -6.801848) (xy 433.076837 -6.854174) (xy 433.054183 -6.903781) (xy 433.0247 -6.949659)
			(xy 432.988988 -6.990875) (xy 432.947774 -7.026589) (xy 432.901897 -7.056074) (xy 432.852291 -7.078731)
			(xy 432.799965 -7.094097) (xy 432.745986 -7.10186) (xy 432.718718 -7.102348) (xy 431.855118 -7.102348)
			(xy 431.827845 -7.101914) (xy 431.773854 -7.094153) (xy 431.721518 -7.078788) (xy 431.6719 -7.056131)
			(xy 431.626013 -7.026642) (xy 431.584789 -6.990924) (xy 431.549068 -6.949702) (xy 431.519578 -6.903815)
			(xy 431.496918 -6.854199) (xy 431.48155 -6.801863) (xy 431.473788 -6.747873) (xy 429.488151 -6.747873)
			(xy 429.48141 -6.794758) (xy 429.466042 -6.847091) (xy 429.443383 -6.896704) (xy 429.413893 -6.942587)
			(xy 429.378173 -6.983805) (xy 429.33695 -7.01952) (xy 429.291064 -7.049005) (xy 429.241448 -7.071658)
			(xy 429.189113 -7.087019) (xy 429.135125 -7.094776) (xy 429.107854 -7.095236) (xy 428.244254 -7.095236)
			(xy 428.216985 -7.094798) (xy 428.163003 -7.087031) (xy 428.110675 -7.07166) (xy 428.061067 -7.049)
			(xy 428.015189 -7.019511) (xy 427.973974 -6.983793) (xy 427.938261 -6.942574) (xy 427.908778 -6.896692)
			(xy 427.886123 -6.847082) (xy 427.870759 -6.794752) (xy 427.862998 -6.740769) (xy 425.88915 -6.740769)
			(xy 425.881389 -6.794746) (xy 425.866025 -6.847071) (xy 425.843371 -6.896677) (xy 425.813889 -6.942554)
			(xy 425.778177 -6.983769) (xy 425.736964 -7.019481) (xy 425.691087 -7.048966) (xy 425.641482 -7.071621)
			(xy 425.589158 -7.086986) (xy 425.535179 -7.094749) (xy 425.507912 -7.095236) (xy 424.644312 -7.095236)
			(xy 424.617039 -7.094825) (xy 424.563047 -7.087064) (xy 424.510709 -7.071698) (xy 424.461091 -7.049039)
			(xy 424.415203 -7.01955) (xy 424.373978 -6.98383) (xy 424.338257 -6.942607) (xy 424.308766 -6.89672)
			(xy 424.286106 -6.847102) (xy 424.270739 -6.794765) (xy 424.262976 -6.740773) (xy 418.279049 -6.740773)
			(xy 418.271289 -6.794745) (xy 418.255926 -6.84707) (xy 418.233272 -6.896675) (xy 418.20379 -6.942552)
			(xy 418.168079 -6.983766) (xy 418.126867 -7.019479) (xy 418.080991 -7.048964) (xy 418.031386 -7.071619)
			(xy 417.979063 -7.086985) (xy 417.925085 -7.094748) (xy 417.897818 -7.095236) (xy 417.034218 -7.095236)
			(xy 417.006944 -7.094826) (xy 416.952952 -7.087065) (xy 416.900613 -7.071699) (xy 416.850995 -7.049041)
			(xy 416.805106 -7.019552) (xy 416.763881 -6.983832) (xy 416.728159 -6.942609) (xy 416.698667 -6.896721)
			(xy 416.676007 -6.847103) (xy 416.660639 -6.794766) (xy 416.652876 -6.740774) (xy 414.679172 -6.740774)
			(xy 414.67141 -6.794756) (xy 414.656044 -6.847087) (xy 414.633386 -6.896698) (xy 414.603898 -6.94258)
			(xy 414.568181 -6.983798) (xy 414.52696 -7.019513) (xy 414.481077 -7.048998) (xy 414.431464 -7.071652)
			(xy 414.379132 -7.087015) (xy 414.325146 -7.094774) (xy 414.297876 -7.095236) (xy 413.434276 -7.095236)
			(xy 413.407006 -7.0948) (xy 413.353021 -7.087035) (xy 413.300691 -7.071666) (xy 413.25108 -7.049007)
			(xy 413.205199 -7.019519) (xy 413.163982 -6.983801) (xy 413.128267 -6.942581) (xy 413.098781 -6.896698)
			(xy 413.076125 -6.847086) (xy 413.06076 -6.794755) (xy 413.052998 -6.74077) (xy 405.56915 -6.74077)
			(xy 405.561389 -6.794746) (xy 405.546025 -6.847071) (xy 405.523371 -6.896677) (xy 405.493889 -6.942554)
			(xy 405.458177 -6.983769) (xy 405.416964 -7.019481) (xy 405.371087 -7.048966) (xy 405.321482 -7.071621)
			(xy 405.269158 -7.086986) (xy 405.215179 -7.094749) (xy 405.187912 -7.095236) (xy 404.324312 -7.095236)
			(xy 404.297039 -7.094825) (xy 404.243047 -7.087064) (xy 404.190709 -7.071698) (xy 404.141091 -7.049039)
			(xy 404.095203 -7.01955) (xy 404.053978 -6.98383) (xy 404.018257 -6.942607) (xy 403.988766 -6.89672)
			(xy 403.966106 -6.847102) (xy 403.950739 -6.794765) (xy 403.942976 -6.740773) (xy 401.968949 -6.740773)
			(xy 401.961189 -6.794745) (xy 401.945825 -6.84707) (xy 401.923172 -6.896676) (xy 401.89369 -6.942553)
			(xy 401.857978 -6.983767) (xy 401.816766 -7.01948) (xy 401.77089 -7.048964) (xy 401.721285 -7.07162)
			(xy 401.668961 -7.086986) (xy 401.614983 -7.094749) (xy 401.587716 -7.095236) (xy 400.724116 -7.095236)
			(xy 400.696842 -7.094826) (xy 400.64285 -7.087065) (xy 400.590512 -7.071699) (xy 400.540893 -7.049041)
			(xy 400.495005 -7.019551) (xy 400.45378 -6.983832) (xy 400.418058 -6.942608) (xy 400.388567 -6.896721)
			(xy 400.365907 -6.847103) (xy 400.350539 -6.794766) (xy 400.342776 -6.740774) (xy 398.369071 -6.740774)
			(xy 398.36131 -6.794756) (xy 398.345944 -6.847087) (xy 398.323286 -6.896699) (xy 398.293798 -6.94258)
			(xy 398.25808 -6.983798) (xy 398.216859 -7.019513) (xy 398.170976 -7.048998) (xy 398.121363 -7.071653)
			(xy 398.06903 -7.087016) (xy 398.015044 -7.094774) (xy 397.987774 -7.095236) (xy 397.124174 -7.095236)
			(xy 397.096904 -7.0948) (xy 397.04292 -7.087035) (xy 396.99059 -7.071666) (xy 396.940979 -7.049007)
			(xy 396.895099 -7.019518) (xy 396.853881 -6.9838) (xy 396.818166 -6.942581) (xy 396.788681 -6.896698)
			(xy 396.766025 -6.847086) (xy 396.75066 -6.794755) (xy 396.742898 -6.74077) (xy 394.769049 -6.74077)
			(xy 394.761289 -6.794743) (xy 394.745927 -6.847067) (xy 394.723274 -6.896671) (xy 394.693794 -6.942548)
			(xy 394.658084 -6.983762) (xy 394.616873 -7.019474) (xy 394.570999 -7.048959) (xy 394.521397 -7.071616)
			(xy 394.469074 -7.086983) (xy 394.415098 -7.094747) (xy 394.387832 -7.095236) (xy 393.524232 -7.095236)
			(xy 393.496958 -7.094827) (xy 393.442964 -7.087068) (xy 393.390624 -7.071703) (xy 393.341003 -7.049046)
			(xy 393.295112 -7.019557) (xy 393.253885 -6.983837) (xy 393.218162 -6.942613) (xy 393.18867 -6.896725)
			(xy 393.166008 -6.847106) (xy 393.150639 -6.794768) (xy 393.142876 -6.740774) (xy 388.110984 -6.740774)
			(xy 388.110984 -9.780016) (xy 388.110499 -9.850398) (xy 388.102605 -9.99094) (xy 388.086844 -10.130819)
			(xy 388.063264 -10.269594) (xy 388.03194 -10.406828) (xy 387.992971 -10.54209) (xy 387.946478 -10.674954)
			(xy 387.892609 -10.805003) (xy 387.831533 -10.931826) (xy 387.763442 -11.055026) (xy 387.68855 -11.174213)
			(xy 387.607093 -11.289014) (xy 387.519328 -11.399067) (xy 387.425529 -11.504025) (xy 387.325993 -11.60356)
			(xy 387.221033 -11.697356) (xy 387.110979 -11.78512) (xy 386.996176 -11.866575) (xy 386.876988 -11.941465)
			(xy 386.753787 -12.009554) (xy 386.626963 -12.070627) (xy 386.496913 -12.124494) (xy 386.364048 -12.170984)
			(xy 386.228785 -12.209951) (xy 386.091551 -12.241273) (xy 385.952775 -12.26485) (xy 385.812896 -12.280609)
			(xy 385.672354 -12.2885) (xy 385.601972 -12.289028) (xy 260.800088 -12.289028) (xy 260.744319 -12.28955)
			(xy 260.633094 -12.297886) (xy 260.522803 -12.314511) (xy 260.414062 -12.339331) (xy 260.30748 -12.372208)
			(xy 260.203654 -12.412958) (xy 260.103162 -12.461353) (xy 260.006569 -12.517122) (xy 259.914413 -12.579954)
			(xy 259.82721 -12.649497) (xy 259.745448 -12.725362) (xy 259.669584 -12.807125) (xy 259.601847 -12.892065)
			(xy 431.46197 -12.892065) (xy 431.46197 -12.837535) (xy 431.46973 -12.783559) (xy 431.485093 -12.731238)
			(xy 431.507745 -12.681635) (xy 431.537225 -12.635761) (xy 431.572934 -12.594548) (xy 431.614145 -12.558837)
			(xy 431.660017 -12.529355) (xy 431.709619 -12.5067) (xy 431.76194 -12.491335) (xy 431.815915 -12.483572)
			(xy 431.84318 -12.483084) (xy 432.70678 -12.483084) (xy 432.734055 -12.483454) (xy 432.788051 -12.491215)
			(xy 432.840392 -12.506581) (xy 432.890014 -12.529241) (xy 432.935905 -12.558731) (xy 432.977133 -12.594453)
			(xy 433.012857 -12.635678) (xy 433.04235 -12.681569) (xy 433.065012 -12.731189) (xy 433.080381 -12.78353)
			(xy 433.088144 -12.837525) (xy 433.088144 -12.864846) (xy 445.45631 -12.864846) (xy 445.45631 -12.864592)
			(xy 445.456564 -12.850622) (xy 445.45717 -12.823469) (xy 445.46523 -12.769758) (xy 445.48082 -12.717731)
			(xy 445.503625 -12.668439) (xy 445.533186 -12.622876) (xy 445.568905 -12.581962) (xy 445.610062 -12.546522)
			(xy 445.655826 -12.517273) (xy 445.705273 -12.494804) (xy 445.757405 -12.47957) (xy 445.81117 -12.471876)
			(xy 445.838326 -12.4714) (xy 446.701926 -12.4714) (xy 446.72908 -12.471883) (xy 446.782838 -12.479582)
			(xy 446.834964 -12.494821) (xy 446.884404 -12.517293) (xy 446.93016 -12.546543) (xy 446.971311 -12.581982)
			(xy 447.007024 -12.622895) (xy 447.03658 -12.668455) (xy 447.059381 -12.717744) (xy 447.074968 -12.769766)
			(xy 447.083027 -12.823472) (xy 447.083688 -12.850622) (xy 447.083942 -12.864592) (xy 447.083942 -12.864846)
			(xy 447.083472 -12.892133) (xy 447.0757 -12.946152) (xy 447.06032 -12.998515) (xy 447.037645 -13.048157)
			(xy 447.008137 -13.094067) (xy 446.972397 -13.135311) (xy 446.931151 -13.171049) (xy 446.885239 -13.200555)
			(xy 446.835597 -13.223227) (xy 446.783233 -13.238604) (xy 446.729214 -13.246374) (xy 446.701926 -13.246862)
			(xy 446.679426 -13.246581) (xy 446.634732 -13.241355) (xy 446.612772 -13.236448) (xy 446.60693 -13.234924)
			(xy 445.933322 -13.234924) (xy 445.92748 -13.236448) (xy 445.905519 -13.241348) (xy 445.860825 -13.246566)
			(xy 445.838326 -13.246862) (xy 445.811041 -13.246305) (xy 445.757027 -13.238543) (xy 445.704666 -13.223173)
			(xy 445.655026 -13.200508) (xy 445.609117 -13.17101) (xy 445.567873 -13.135278) (xy 445.532133 -13.094041)
			(xy 445.502626 -13.048137) (xy 445.479952 -12.998501) (xy 445.464572 -12.946144) (xy 445.4568 -12.892131)
			(xy 445.45631 -12.864846) (xy 433.088144 -12.864846) (xy 433.088144 -12.892075) (xy 433.080381 -12.94607)
			(xy 433.065012 -12.998411) (xy 433.04235 -13.048031) (xy 433.012857 -13.093921) (xy 432.977133 -13.135147)
			(xy 432.935905 -13.170869) (xy 432.890014 -13.200359) (xy 432.840392 -13.223019) (xy 432.788051 -13.238385)
			(xy 432.734055 -13.246146) (xy 432.70678 -13.246608) (xy 431.84318 -13.246608) (xy 431.815915 -13.246028)
			(xy 431.76194 -13.238265) (xy 431.709619 -13.2229) (xy 431.660017 -13.200245) (xy 431.614145 -13.170763)
			(xy 431.572934 -13.135052) (xy 431.537225 -13.093839) (xy 431.507745 -13.047965) (xy 431.485093 -12.998362)
			(xy 431.46973 -12.946041) (xy 431.46197 -12.892065) (xy 259.601847 -12.892065) (xy 259.600042 -12.894329)
			(xy 259.537211 -12.986486) (xy 259.481443 -13.08308) (xy 259.43305 -13.183572) (xy 259.392301 -13.287399)
			(xy 259.359426 -13.393981) (xy 259.334607 -13.502722) (xy 259.317984 -13.613014) (xy 259.309649 -13.724239)
			(xy 259.309108 -13.780008) (xy 259.309108 -17.628666) (xy 389.660162 -17.628666) (xy 389.660162 -17.574134)
			(xy 389.667923 -17.520157) (xy 389.683286 -17.467834) (xy 389.705939 -17.41823) (xy 389.73542 -17.372354)
			(xy 389.77113 -17.331141) (xy 389.812342 -17.29543) (xy 389.858216 -17.265946) (xy 389.907819 -17.243291)
			(xy 389.960142 -17.227926) (xy 390.014118 -17.220163) (xy 390.041384 -17.219676) (xy 390.904984 -17.219676)
			(xy 390.932258 -17.220062) (xy 390.986252 -17.227824) (xy 391.038592 -17.24319) (xy 391.088212 -17.265849)
			(xy 391.134103 -17.295339) (xy 391.175329 -17.33106) (xy 391.211051 -17.372285) (xy 391.240543 -17.418174)
			(xy 391.263204 -17.467793) (xy 391.278573 -17.520132) (xy 391.286336 -17.574126) (xy 391.286336 -17.628666)
			(xy 395.248162 -17.628666) (xy 395.248162 -17.574134) (xy 395.255923 -17.520157) (xy 395.271286 -17.467834)
			(xy 395.293939 -17.41823) (xy 395.32342 -17.372354) (xy 395.35913 -17.331141) (xy 395.400342 -17.29543)
			(xy 395.446216 -17.265946) (xy 395.495819 -17.243291) (xy 395.548142 -17.227926) (xy 395.602118 -17.220163)
			(xy 395.629384 -17.219676) (xy 396.492984 -17.219676) (xy 396.520258 -17.220062) (xy 396.574252 -17.227824)
			(xy 396.626592 -17.24319) (xy 396.676212 -17.265849) (xy 396.722103 -17.295339) (xy 396.763329 -17.33106)
			(xy 396.799051 -17.372285) (xy 396.828543 -17.418174) (xy 396.851204 -17.467793) (xy 396.866573 -17.520132)
			(xy 396.874336 -17.574126) (xy 396.874336 -17.628666) (xy 400.836162 -17.628666) (xy 400.836162 -17.574134)
			(xy 400.843923 -17.520157) (xy 400.859286 -17.467834) (xy 400.881939 -17.41823) (xy 400.91142 -17.372354)
			(xy 400.94713 -17.331141) (xy 400.988342 -17.29543) (xy 401.034216 -17.265946) (xy 401.083819 -17.243291)
			(xy 401.136142 -17.227926) (xy 401.190118 -17.220163) (xy 401.217384 -17.219676) (xy 402.080984 -17.219676)
			(xy 402.108258 -17.220062) (xy 402.162252 -17.227824) (xy 402.214592 -17.24319) (xy 402.264212 -17.265849)
			(xy 402.310103 -17.295339) (xy 402.351329 -17.33106) (xy 402.387051 -17.372285) (xy 402.416543 -17.418174)
			(xy 402.439204 -17.467793) (xy 402.454573 -17.520132) (xy 402.462336 -17.574126) (xy 402.462336 -17.628666)
			(xy 406.424162 -17.628666) (xy 406.424162 -17.574134) (xy 406.431923 -17.520157) (xy 406.447286 -17.467834)
			(xy 406.469939 -17.41823) (xy 406.49942 -17.372354) (xy 406.53513 -17.331141) (xy 406.576342 -17.29543)
			(xy 406.622216 -17.265946) (xy 406.671819 -17.243291) (xy 406.724142 -17.227926) (xy 406.778118 -17.220163)
			(xy 406.805384 -17.219676) (xy 407.668984 -17.219676) (xy 407.696258 -17.220062) (xy 407.750252 -17.227824)
			(xy 407.802592 -17.24319) (xy 407.852212 -17.265849) (xy 407.898103 -17.295339) (xy 407.939329 -17.33106)
			(xy 407.975051 -17.372285) (xy 408.004543 -17.418174) (xy 408.027204 -17.467793) (xy 408.042573 -17.520132)
			(xy 408.050336 -17.574126) (xy 408.050336 -17.628666) (xy 412.012162 -17.628666) (xy 412.012162 -17.574134)
			(xy 412.019923 -17.520157) (xy 412.035286 -17.467834) (xy 412.057939 -17.41823) (xy 412.08742 -17.372354)
			(xy 412.12313 -17.331141) (xy 412.164342 -17.29543) (xy 412.210216 -17.265946) (xy 412.259819 -17.243291)
			(xy 412.312142 -17.227926) (xy 412.366118 -17.220163) (xy 412.393384 -17.219676) (xy 413.256984 -17.219676)
			(xy 413.284258 -17.220062) (xy 413.338252 -17.227824) (xy 413.390592 -17.24319) (xy 413.440212 -17.265849)
			(xy 413.486103 -17.295339) (xy 413.527329 -17.33106) (xy 413.563051 -17.372285) (xy 413.592543 -17.418174)
			(xy 413.615204 -17.467793) (xy 413.630573 -17.520132) (xy 413.638336 -17.574126) (xy 413.638336 -17.628667)
			(xy 417.905962 -17.628667) (xy 417.905962 -17.574133) (xy 417.913723 -17.520155) (xy 417.929087 -17.467831)
			(xy 417.951741 -17.418226) (xy 417.981224 -17.372349) (xy 418.016936 -17.331136) (xy 418.058149 -17.295424)
			(xy 418.104026 -17.265941) (xy 418.153631 -17.243287) (xy 418.205955 -17.227923) (xy 418.259933 -17.220162)
			(xy 418.2872 -17.219676) (xy 419.1508 -17.219676) (xy 419.178072 -17.220087) (xy 419.232061 -17.227849)
			(xy 419.284396 -17.243216) (xy 419.334011 -17.265874) (xy 419.379896 -17.295363) (xy 419.421118 -17.331082)
			(xy 419.456837 -17.372304) (xy 419.486326 -17.418189) (xy 419.508984 -17.467804) (xy 419.524351 -17.520139)
			(xy 419.532113 -17.574128) (xy 419.532113 -17.628667) (xy 423.493962 -17.628667) (xy 423.493962 -17.574133)
			(xy 423.501723 -17.520155) (xy 423.517087 -17.467831) (xy 423.539741 -17.418226) (xy 423.569224 -17.372349)
			(xy 423.604936 -17.331136) (xy 423.646149 -17.295424) (xy 423.692026 -17.265941) (xy 423.741631 -17.243287)
			(xy 423.793955 -17.227923) (xy 423.847933 -17.220162) (xy 423.8752 -17.219676) (xy 424.7388 -17.219676)
			(xy 424.766072 -17.220087) (xy 424.820061 -17.227849) (xy 424.872396 -17.243216) (xy 424.922011 -17.265874)
			(xy 424.967896 -17.295363) (xy 425.009118 -17.331082) (xy 425.044837 -17.372304) (xy 425.074326 -17.418189)
			(xy 425.096984 -17.467804) (xy 425.112351 -17.520139) (xy 425.120113 -17.574128) (xy 425.120113 -17.62867)
			(xy 429.11594 -17.62867) (xy 429.11594 -17.57413) (xy 429.123702 -17.520145) (xy 429.139068 -17.467815)
			(xy 429.161726 -17.418204) (xy 429.191214 -17.372324) (xy 429.226932 -17.331107) (xy 429.268152 -17.295393)
			(xy 429.314036 -17.265909) (xy 429.363649 -17.243256) (xy 429.415981 -17.227894) (xy 429.469966 -17.220137)
			(xy 429.497236 -17.219676) (xy 430.360836 -17.219676) (xy 430.388106 -17.220089) (xy 430.442091 -17.227856)
			(xy 430.494422 -17.243226) (xy 430.544032 -17.265886) (xy 430.589913 -17.295376) (xy 430.631131 -17.331095)
			(xy 430.666846 -17.372315) (xy 430.696331 -17.418199) (xy 430.718987 -17.467812) (xy 430.734352 -17.520144)
			(xy 430.742114 -17.57413) (xy 430.742114 -17.62867) (xy 430.734352 -17.682656) (xy 430.718987 -17.734988)
			(xy 430.696331 -17.784601) (xy 430.666846 -17.830485) (xy 430.631131 -17.871705) (xy 430.589913 -17.907424)
			(xy 430.544032 -17.936914) (xy 430.494422 -17.959574) (xy 430.442091 -17.974944) (xy 430.388106 -17.982711)
			(xy 430.360836 -17.9832) (xy 429.497236 -17.9832) (xy 429.469966 -17.982663) (xy 429.415981 -17.974906)
			(xy 429.363649 -17.959544) (xy 429.314036 -17.936891) (xy 429.268152 -17.907407) (xy 429.226932 -17.871693)
			(xy 429.191214 -17.830476) (xy 429.161726 -17.784596) (xy 429.139068 -17.734985) (xy 429.123702 -17.682655)
			(xy 429.11594 -17.62867) (xy 425.120113 -17.62867) (xy 425.120113 -17.628672) (xy 425.112351 -17.682661)
			(xy 425.096984 -17.734996) (xy 425.074326 -17.784611) (xy 425.044837 -17.830496) (xy 425.009118 -17.871718)
			(xy 424.967896 -17.907437) (xy 424.922011 -17.936926) (xy 424.872396 -17.959584) (xy 424.820061 -17.974951)
			(xy 424.766072 -17.982713) (xy 424.7388 -17.9832) (xy 423.8752 -17.9832) (xy 423.847933 -17.982638)
			(xy 423.793955 -17.974877) (xy 423.741631 -17.959513) (xy 423.692026 -17.936859) (xy 423.646149 -17.907376)
			(xy 423.604936 -17.871664) (xy 423.569224 -17.830451) (xy 423.539741 -17.784574) (xy 423.517087 -17.734969)
			(xy 423.501723 -17.682645) (xy 423.493962 -17.628667) (xy 419.532113 -17.628667) (xy 419.532113 -17.628672)
			(xy 419.524351 -17.682661) (xy 419.508984 -17.734996) (xy 419.486326 -17.784611) (xy 419.456837 -17.830496)
			(xy 419.421118 -17.871718) (xy 419.379896 -17.907437) (xy 419.334011 -17.936926) (xy 419.284396 -17.959584)
			(xy 419.232061 -17.974951) (xy 419.178072 -17.982713) (xy 419.1508 -17.9832) (xy 418.2872 -17.9832)
			(xy 418.259933 -17.982638) (xy 418.205955 -17.974877) (xy 418.153631 -17.959513) (xy 418.104026 -17.936859)
			(xy 418.058149 -17.907376) (xy 418.016936 -17.871664) (xy 417.981224 -17.830451) (xy 417.951741 -17.784574)
			(xy 417.929087 -17.734969) (xy 417.913723 -17.682645) (xy 417.905962 -17.628667) (xy 413.638336 -17.628667)
			(xy 413.638336 -17.628674) (xy 413.630573 -17.682668) (xy 413.615204 -17.735007) (xy 413.592543 -17.784626)
			(xy 413.563051 -17.830515) (xy 413.527329 -17.87174) (xy 413.486103 -17.907461) (xy 413.440212 -17.936951)
			(xy 413.390592 -17.95961) (xy 413.338252 -17.974976) (xy 413.284258 -17.982738) (xy 413.256984 -17.9832)
			(xy 412.393384 -17.9832) (xy 412.366118 -17.982637) (xy 412.312142 -17.974874) (xy 412.259819 -17.959509)
			(xy 412.210216 -17.936854) (xy 412.164342 -17.90737) (xy 412.12313 -17.871659) (xy 412.08742 -17.830446)
			(xy 412.057939 -17.78457) (xy 412.035286 -17.734966) (xy 412.019923 -17.682643) (xy 412.012162 -17.628666)
			(xy 408.050336 -17.628666) (xy 408.050336 -17.628674) (xy 408.042573 -17.682668) (xy 408.027204 -17.735007)
			(xy 408.004543 -17.784626) (xy 407.975051 -17.830515) (xy 407.939329 -17.87174) (xy 407.898103 -17.907461)
			(xy 407.852212 -17.936951) (xy 407.802592 -17.95961) (xy 407.750252 -17.974976) (xy 407.696258 -17.982738)
			(xy 407.668984 -17.9832) (xy 406.805384 -17.9832) (xy 406.778118 -17.982637) (xy 406.724142 -17.974874)
			(xy 406.671819 -17.959509) (xy 406.622216 -17.936854) (xy 406.576342 -17.90737) (xy 406.53513 -17.871659)
			(xy 406.49942 -17.830446) (xy 406.469939 -17.78457) (xy 406.447286 -17.734966) (xy 406.431923 -17.682643)
			(xy 406.424162 -17.628666) (xy 402.462336 -17.628666) (xy 402.462336 -17.628674) (xy 402.454573 -17.682668)
			(xy 402.439204 -17.735007) (xy 402.416543 -17.784626) (xy 402.387051 -17.830515) (xy 402.351329 -17.87174)
			(xy 402.310103 -17.907461) (xy 402.264212 -17.936951) (xy 402.214592 -17.95961) (xy 402.162252 -17.974976)
			(xy 402.108258 -17.982738) (xy 402.080984 -17.9832) (xy 401.217384 -17.9832) (xy 401.190118 -17.982637)
			(xy 401.136142 -17.974874) (xy 401.083819 -17.959509) (xy 401.034216 -17.936854) (xy 400.988342 -17.90737)
			(xy 400.94713 -17.871659) (xy 400.91142 -17.830446) (xy 400.881939 -17.78457) (xy 400.859286 -17.734966)
			(xy 400.843923 -17.682643) (xy 400.836162 -17.628666) (xy 396.874336 -17.628666) (xy 396.874336 -17.628674)
			(xy 396.866573 -17.682668) (xy 396.851204 -17.735007) (xy 396.828543 -17.784626) (xy 396.799051 -17.830515)
			(xy 396.763329 -17.87174) (xy 396.722103 -17.907461) (xy 396.676212 -17.936951) (xy 396.626592 -17.95961)
			(xy 396.574252 -17.974976) (xy 396.520258 -17.982738) (xy 396.492984 -17.9832) (xy 395.629384 -17.9832)
			(xy 395.602118 -17.982637) (xy 395.548142 -17.974874) (xy 395.495819 -17.959509) (xy 395.446216 -17.936854)
			(xy 395.400342 -17.90737) (xy 395.35913 -17.871659) (xy 395.32342 -17.830446) (xy 395.293939 -17.78457)
			(xy 395.271286 -17.734966) (xy 395.255923 -17.682643) (xy 395.248162 -17.628666) (xy 391.286336 -17.628666)
			(xy 391.286336 -17.628674) (xy 391.278573 -17.682668) (xy 391.263204 -17.735007) (xy 391.240543 -17.784626)
			(xy 391.211051 -17.830515) (xy 391.175329 -17.87174) (xy 391.134103 -17.907461) (xy 391.088212 -17.936951)
			(xy 391.038592 -17.95961) (xy 390.986252 -17.974976) (xy 390.932258 -17.982738) (xy 390.904984 -17.9832)
			(xy 390.041384 -17.9832) (xy 390.014118 -17.982637) (xy 389.960142 -17.974874) (xy 389.907819 -17.959509)
			(xy 389.858216 -17.936854) (xy 389.812342 -17.90737) (xy 389.77113 -17.871659) (xy 389.73542 -17.830446)
			(xy 389.705939 -17.78457) (xy 389.683286 -17.734966) (xy 389.667923 -17.682643) (xy 389.660162 -17.628666)
			(xy 259.309108 -17.628666) (xy 259.309108 -19.152666) (xy 392.454162 -19.152666) (xy 392.454162 -19.098134)
			(xy 392.461923 -19.044157) (xy 392.477286 -18.991834) (xy 392.499939 -18.94223) (xy 392.52942 -18.896354)
			(xy 392.56513 -18.855141) (xy 392.606342 -18.81943) (xy 392.652216 -18.789946) (xy 392.701819 -18.767291)
			(xy 392.754142 -18.751926) (xy 392.808118 -18.744163) (xy 392.835384 -18.743676) (xy 393.698984 -18.743676)
			(xy 393.726258 -18.744062) (xy 393.780252 -18.751824) (xy 393.832592 -18.76719) (xy 393.882212 -18.789849)
			(xy 393.928103 -18.819339) (xy 393.969329 -18.85506) (xy 394.005051 -18.896285) (xy 394.034543 -18.942174)
			(xy 394.057204 -18.991793) (xy 394.072573 -19.044132) (xy 394.080336 -19.098126) (xy 394.080336 -19.152666)
			(xy 398.042162 -19.152666) (xy 398.042162 -19.098134) (xy 398.049923 -19.044157) (xy 398.065286 -18.991834)
			(xy 398.087939 -18.94223) (xy 398.11742 -18.896354) (xy 398.15313 -18.855141) (xy 398.194342 -18.81943)
			(xy 398.240216 -18.789946) (xy 398.289819 -18.767291) (xy 398.342142 -18.751926) (xy 398.396118 -18.744163)
			(xy 398.423384 -18.743676) (xy 399.286984 -18.743676) (xy 399.314258 -18.744062) (xy 399.368252 -18.751824)
			(xy 399.420592 -18.76719) (xy 399.470212 -18.789849) (xy 399.516103 -18.819339) (xy 399.557329 -18.85506)
			(xy 399.593051 -18.896285) (xy 399.622543 -18.942174) (xy 399.645204 -18.991793) (xy 399.660573 -19.044132)
			(xy 399.668336 -19.098126) (xy 399.668336 -19.152666) (xy 403.630162 -19.152666) (xy 403.630162 -19.098134)
			(xy 403.637923 -19.044157) (xy 403.653286 -18.991834) (xy 403.675939 -18.94223) (xy 403.70542 -18.896354)
			(xy 403.74113 -18.855141) (xy 403.782342 -18.81943) (xy 403.828216 -18.789946) (xy 403.877819 -18.767291)
			(xy 403.930142 -18.751926) (xy 403.984118 -18.744163) (xy 404.011384 -18.743676) (xy 404.874984 -18.743676)
			(xy 404.902258 -18.744062) (xy 404.956252 -18.751824) (xy 405.008592 -18.76719) (xy 405.058212 -18.789849)
			(xy 405.104103 -18.819339) (xy 405.145329 -18.85506) (xy 405.181051 -18.896285) (xy 405.210543 -18.942174)
			(xy 405.233204 -18.991793) (xy 405.248573 -19.044132) (xy 405.256336 -19.098126) (xy 405.256336 -19.152666)
			(xy 409.218162 -19.152666) (xy 409.218162 -19.098134) (xy 409.225923 -19.044157) (xy 409.241286 -18.991834)
			(xy 409.263939 -18.94223) (xy 409.29342 -18.896354) (xy 409.32913 -18.855141) (xy 409.370342 -18.81943)
			(xy 409.416216 -18.789946) (xy 409.465819 -18.767291) (xy 409.518142 -18.751926) (xy 409.572118 -18.744163)
			(xy 409.599384 -18.743676) (xy 410.462984 -18.743676) (xy 410.490258 -18.744062) (xy 410.544252 -18.751824)
			(xy 410.596592 -18.76719) (xy 410.646212 -18.789849) (xy 410.692103 -18.819339) (xy 410.733329 -18.85506)
			(xy 410.769051 -18.896285) (xy 410.798543 -18.942174) (xy 410.821204 -18.991793) (xy 410.836573 -19.044132)
			(xy 410.844336 -19.098126) (xy 410.844336 -19.152667) (xy 415.111962 -19.152667) (xy 415.111962 -19.098133)
			(xy 415.119723 -19.044155) (xy 415.135087 -18.991831) (xy 415.157741 -18.942226) (xy 415.187224 -18.896349)
			(xy 415.222936 -18.855136) (xy 415.264149 -18.819424) (xy 415.310026 -18.789941) (xy 415.359631 -18.767287)
			(xy 415.411955 -18.751923) (xy 415.465933 -18.744162) (xy 415.4932 -18.743676) (xy 416.3568 -18.743676)
			(xy 416.384072 -18.744087) (xy 416.438061 -18.751849) (xy 416.490396 -18.767216) (xy 416.540011 -18.789874)
			(xy 416.585896 -18.819363) (xy 416.627118 -18.855082) (xy 416.662837 -18.896304) (xy 416.692326 -18.942189)
			(xy 416.714984 -18.991804) (xy 416.730351 -19.044139) (xy 416.738113 -19.098128) (xy 416.738113 -19.152667)
			(xy 420.699962 -19.152667) (xy 420.699962 -19.098133) (xy 420.707723 -19.044155) (xy 420.723087 -18.991831)
			(xy 420.745741 -18.942226) (xy 420.775224 -18.896349) (xy 420.810936 -18.855136) (xy 420.852149 -18.819424)
			(xy 420.898026 -18.789941) (xy 420.947631 -18.767287) (xy 420.999955 -18.751923) (xy 421.053933 -18.744162)
			(xy 421.0812 -18.743676) (xy 421.9448 -18.743676) (xy 421.972072 -18.744087) (xy 422.026061 -18.751849)
			(xy 422.078396 -18.767216) (xy 422.128011 -18.789874) (xy 422.173896 -18.819363) (xy 422.215118 -18.855082)
			(xy 422.250837 -18.896304) (xy 422.280326 -18.942189) (xy 422.302984 -18.991804) (xy 422.318351 -19.044139)
			(xy 422.326113 -19.098128) (xy 422.326113 -19.15267) (xy 426.32194 -19.15267) (xy 426.32194 -19.09813)
			(xy 426.329702 -19.044145) (xy 426.345068 -18.991815) (xy 426.367726 -18.942204) (xy 426.397214 -18.896324)
			(xy 426.432932 -18.855107) (xy 426.474152 -18.819393) (xy 426.520036 -18.789909) (xy 426.569649 -18.767256)
			(xy 426.621981 -18.751894) (xy 426.675966 -18.744137) (xy 426.703236 -18.743676) (xy 427.566836 -18.743676)
			(xy 427.594106 -18.744089) (xy 427.648091 -18.751856) (xy 427.700422 -18.767226) (xy 427.750032 -18.789886)
			(xy 427.795913 -18.819376) (xy 427.837131 -18.855095) (xy 427.872846 -18.896315) (xy 427.902331 -18.942199)
			(xy 427.924987 -18.991812) (xy 427.940352 -19.044144) (xy 427.948114 -19.09813) (xy 427.948114 -19.15267)
			(xy 431.90994 -19.15267) (xy 431.90994 -19.09813) (xy 431.917702 -19.044145) (xy 431.933068 -18.991815)
			(xy 431.955726 -18.942204) (xy 431.985214 -18.896324) (xy 432.020932 -18.855107) (xy 432.062152 -18.819393)
			(xy 432.108036 -18.789909) (xy 432.157649 -18.767256) (xy 432.209981 -18.751894) (xy 432.263966 -18.744137)
			(xy 432.291236 -18.743676) (xy 433.154836 -18.743676) (xy 433.182106 -18.744089) (xy 433.236091 -18.751856)
			(xy 433.288422 -18.767226) (xy 433.338032 -18.789886) (xy 433.383913 -18.819376) (xy 433.425131 -18.855095)
			(xy 433.460846 -18.896315) (xy 433.490331 -18.942199) (xy 433.512987 -18.991812) (xy 433.528352 -19.044144)
			(xy 433.536114 -19.09813) (xy 433.536114 -19.15267) (xy 433.528352 -19.206656) (xy 433.512987 -19.258988)
			(xy 433.490331 -19.308601) (xy 433.460846 -19.354485) (xy 433.425131 -19.395705) (xy 433.383913 -19.431424)
			(xy 433.338032 -19.460914) (xy 433.288422 -19.483574) (xy 433.236091 -19.498944) (xy 433.182106 -19.506711)
			(xy 433.154836 -19.5072) (xy 432.291236 -19.5072) (xy 432.263966 -19.506663) (xy 432.209981 -19.498906)
			(xy 432.157649 -19.483544) (xy 432.108036 -19.460891) (xy 432.062152 -19.431407) (xy 432.020932 -19.395693)
			(xy 431.985214 -19.354476) (xy 431.955726 -19.308596) (xy 431.933068 -19.258985) (xy 431.917702 -19.206655)
			(xy 431.90994 -19.15267) (xy 427.948114 -19.15267) (xy 427.940352 -19.206656) (xy 427.924987 -19.258988)
			(xy 427.902331 -19.308601) (xy 427.872846 -19.354485) (xy 427.837131 -19.395705) (xy 427.795913 -19.431424)
			(xy 427.750032 -19.460914) (xy 427.700422 -19.483574) (xy 427.648091 -19.498944) (xy 427.594106 -19.506711)
			(xy 427.566836 -19.5072) (xy 426.703236 -19.5072) (xy 426.675966 -19.506663) (xy 426.621981 -19.498906)
			(xy 426.569649 -19.483544) (xy 426.520036 -19.460891) (xy 426.474152 -19.431407) (xy 426.432932 -19.395693)
			(xy 426.397214 -19.354476) (xy 426.367726 -19.308596) (xy 426.345068 -19.258985) (xy 426.329702 -19.206655)
			(xy 426.32194 -19.15267) (xy 422.326113 -19.15267) (xy 422.326113 -19.152672) (xy 422.318351 -19.206661)
			(xy 422.302984 -19.258996) (xy 422.280326 -19.308611) (xy 422.250837 -19.354496) (xy 422.215118 -19.395718)
			(xy 422.173896 -19.431437) (xy 422.128011 -19.460926) (xy 422.078396 -19.483584) (xy 422.026061 -19.498951)
			(xy 421.972072 -19.506713) (xy 421.9448 -19.5072) (xy 421.0812 -19.5072) (xy 421.053933 -19.506638)
			(xy 420.999955 -19.498877) (xy 420.947631 -19.483513) (xy 420.898026 -19.460859) (xy 420.852149 -19.431376)
			(xy 420.810936 -19.395664) (xy 420.775224 -19.354451) (xy 420.745741 -19.308574) (xy 420.723087 -19.258969)
			(xy 420.707723 -19.206645) (xy 420.699962 -19.152667) (xy 416.738113 -19.152667) (xy 416.738113 -19.152672)
			(xy 416.730351 -19.206661) (xy 416.714984 -19.258996) (xy 416.692326 -19.308611) (xy 416.662837 -19.354496)
			(xy 416.627118 -19.395718) (xy 416.585896 -19.431437) (xy 416.540011 -19.460926) (xy 416.490396 -19.483584)
			(xy 416.438061 -19.498951) (xy 416.384072 -19.506713) (xy 416.3568 -19.5072) (xy 415.4932 -19.5072)
			(xy 415.465933 -19.506638) (xy 415.411955 -19.498877) (xy 415.359631 -19.483513) (xy 415.310026 -19.460859)
			(xy 415.264149 -19.431376) (xy 415.222936 -19.395664) (xy 415.187224 -19.354451) (xy 415.157741 -19.308574)
			(xy 415.135087 -19.258969) (xy 415.119723 -19.206645) (xy 415.111962 -19.152667) (xy 410.844336 -19.152667)
			(xy 410.844336 -19.152674) (xy 410.836573 -19.206668) (xy 410.821204 -19.259007) (xy 410.798543 -19.308626)
			(xy 410.769051 -19.354515) (xy 410.733329 -19.39574) (xy 410.692103 -19.431461) (xy 410.646212 -19.460951)
			(xy 410.596592 -19.48361) (xy 410.544252 -19.498976) (xy 410.490258 -19.506738) (xy 410.462984 -19.5072)
			(xy 409.599384 -19.5072) (xy 409.572118 -19.506637) (xy 409.518142 -19.498874) (xy 409.465819 -19.483509)
			(xy 409.416216 -19.460854) (xy 409.370342 -19.43137) (xy 409.32913 -19.395659) (xy 409.29342 -19.354446)
			(xy 409.263939 -19.30857) (xy 409.241286 -19.258966) (xy 409.225923 -19.206643) (xy 409.218162 -19.152666)
			(xy 405.256336 -19.152666) (xy 405.256336 -19.152674) (xy 405.248573 -19.206668) (xy 405.233204 -19.259007)
			(xy 405.210543 -19.308626) (xy 405.181051 -19.354515) (xy 405.145329 -19.39574) (xy 405.104103 -19.431461)
			(xy 405.058212 -19.460951) (xy 405.008592 -19.48361) (xy 404.956252 -19.498976) (xy 404.902258 -19.506738)
			(xy 404.874984 -19.5072) (xy 404.011384 -19.5072) (xy 403.984118 -19.506637) (xy 403.930142 -19.498874)
			(xy 403.877819 -19.483509) (xy 403.828216 -19.460854) (xy 403.782342 -19.43137) (xy 403.74113 -19.395659)
			(xy 403.70542 -19.354446) (xy 403.675939 -19.30857) (xy 403.653286 -19.258966) (xy 403.637923 -19.206643)
			(xy 403.630162 -19.152666) (xy 399.668336 -19.152666) (xy 399.668336 -19.152674) (xy 399.660573 -19.206668)
			(xy 399.645204 -19.259007) (xy 399.622543 -19.308626) (xy 399.593051 -19.354515) (xy 399.557329 -19.39574)
			(xy 399.516103 -19.431461) (xy 399.470212 -19.460951) (xy 399.420592 -19.48361) (xy 399.368252 -19.498976)
			(xy 399.314258 -19.506738) (xy 399.286984 -19.5072) (xy 398.423384 -19.5072) (xy 398.396118 -19.506637)
			(xy 398.342142 -19.498874) (xy 398.289819 -19.483509) (xy 398.240216 -19.460854) (xy 398.194342 -19.43137)
			(xy 398.15313 -19.395659) (xy 398.11742 -19.354446) (xy 398.087939 -19.30857) (xy 398.065286 -19.258966)
			(xy 398.049923 -19.206643) (xy 398.042162 -19.152666) (xy 394.080336 -19.152666) (xy 394.080336 -19.152674)
			(xy 394.072573 -19.206668) (xy 394.057204 -19.259007) (xy 394.034543 -19.308626) (xy 394.005051 -19.354515)
			(xy 393.969329 -19.39574) (xy 393.928103 -19.431461) (xy 393.882212 -19.460951) (xy 393.832592 -19.48361)
			(xy 393.780252 -19.498976) (xy 393.726258 -19.506738) (xy 393.698984 -19.5072) (xy 392.835384 -19.5072)
			(xy 392.808118 -19.506637) (xy 392.754142 -19.498874) (xy 392.701819 -19.483509) (xy 392.652216 -19.460854)
			(xy 392.606342 -19.43137) (xy 392.56513 -19.395659) (xy 392.52942 -19.354446) (xy 392.499939 -19.30857)
			(xy 392.477286 -19.258966) (xy 392.461923 -19.206643) (xy 392.454162 -19.152666) (xy 259.309108 -19.152666)
			(xy 259.309108 -25.468351) (xy 388.406603 -25.468351) (xy 388.406603 -25.413849) (xy 388.41436 -25.359901)
			(xy 388.429716 -25.307607) (xy 388.452359 -25.25803) (xy 388.481827 -25.212181) (xy 388.517521 -25.170992)
			(xy 388.558713 -25.135303) (xy 388.604565 -25.10584) (xy 388.654144 -25.083202) (xy 388.70644 -25.067852)
			(xy 388.760389 -25.0601) (xy 388.78764 -25.05964) (xy 389.65124 -25.05964) (xy 389.678493 -25.060033)
			(xy 389.732443 -25.067795) (xy 389.78474 -25.083155) (xy 389.834318 -25.105802) (xy 389.880169 -25.135273)
			(xy 389.92136 -25.170969) (xy 389.957051 -25.212163) (xy 389.986518 -25.258017) (xy 390.009159 -25.307598)
			(xy 390.024514 -25.359896) (xy 390.03227 -25.413847) (xy 390.03227 -25.468353) (xy 390.024514 -25.522304)
			(xy 390.009159 -25.574602) (xy 389.986518 -25.624183) (xy 389.957051 -25.670037) (xy 389.92136 -25.711231)
			(xy 389.880169 -25.746927) (xy 389.834318 -25.776398) (xy 389.78474 -25.799045) (xy 389.732443 -25.814405)
			(xy 389.678493 -25.822167) (xy 389.65124 -25.822656) (xy 388.78764 -25.822656) (xy 388.760389 -25.8221)
			(xy 388.70644 -25.814348) (xy 388.654144 -25.798998) (xy 388.604565 -25.77636) (xy 388.558713 -25.746897)
			(xy 388.517521 -25.711208) (xy 388.481827 -25.670019) (xy 388.452359 -25.62417) (xy 388.429716 -25.574593)
			(xy 388.41436 -25.522299) (xy 388.406603 -25.468351) (xy 259.309108 -25.468351) (xy 259.309108 -28.450032)
			(xy 354.840804 -28.450032) (xy 354.844787 -28.322014) (xy 354.856722 -28.194492) (xy 354.876561 -28.067958)
			(xy 354.904228 -27.942902) (xy 354.939617 -27.819809) (xy 354.98259 -27.699153) (xy 355.032981 -27.581403)
			(xy 355.090595 -27.467013) (xy 355.155209 -27.356426) (xy 355.226573 -27.25007) (xy 355.304411 -27.148357)
			(xy 355.388422 -27.051679) (xy 355.478281 -26.960412) (xy 355.57364 -26.874907) (xy 355.674131 -26.795497)
			(xy 355.779364 -26.722487) (xy 355.888933 -26.656161) (xy 356.002413 -26.596775) (xy 356.119365 -26.544559)
			(xy 356.239338 -26.499715) (xy 356.361866 -26.462417) (xy 356.486477 -26.432808) (xy 356.612686 -26.411003)
			(xy 356.740008 -26.397087) (xy 356.867948 -26.391113) (xy 356.996012 -26.393105) (xy 357.123705 -26.403055)
			(xy 357.250532 -26.420924) (xy 357.376003 -26.446643) (xy 357.499632 -26.480113) (xy 357.620941 -26.521204)
			(xy 357.739461 -26.569758) (xy 357.854733 -26.625586) (xy 357.966311 -26.688472) (xy 358.073764 -26.758174)
			(xy 358.176676 -26.834421) (xy 358.274648 -26.916918) (xy 358.367302 -27.005347) (xy 358.454279 -27.099365)
			(xy 358.535243 -27.198608) (xy 358.60988 -27.302693) (xy 358.677902 -27.411217) (xy 358.739046 -27.52376)
			(xy 358.793074 -27.639886) (xy 358.839779 -27.759147) (xy 358.878979 -27.88108) (xy 358.910522 -28.005215)
			(xy 358.934287 -28.131071) (xy 358.950181 -28.25816) (xy 358.958144 -28.385992) (xy 358.958642 -28.450032)
			(xy 358.958144 -28.514072) (xy 358.950181 -28.641904) (xy 358.934287 -28.768993) (xy 358.910522 -28.894849)
			(xy 358.878979 -29.018984) (xy 358.839779 -29.140917) (xy 358.793074 -29.260178) (xy 358.739046 -29.376304)
			(xy 358.677902 -29.488847) (xy 358.60988 -29.597371) (xy 358.535243 -29.701456) (xy 358.454279 -29.800699)
			(xy 358.367302 -29.894717) (xy 358.274648 -29.983146) (xy 358.176676 -30.065643) (xy 358.073764 -30.14189)
			(xy 357.966311 -30.211592) (xy 357.854733 -30.274478) (xy 357.739461 -30.330306) (xy 357.620941 -30.37886)
			(xy 357.499632 -30.419951) (xy 357.376003 -30.453421) (xy 357.250532 -30.47914) (xy 357.123705 -30.497009)
			(xy 356.996012 -30.506959) (xy 356.867948 -30.508951) (xy 356.740008 -30.502977) (xy 356.612686 -30.489061)
			(xy 356.486477 -30.467256) (xy 356.361866 -30.437647) (xy 356.239338 -30.400349) (xy 356.119365 -30.355505)
			(xy 356.002413 -30.303289) (xy 355.888933 -30.243903) (xy 355.779364 -30.177577) (xy 355.674131 -30.104567)
			(xy 355.57364 -30.025157) (xy 355.478281 -29.939652) (xy 355.388422 -29.848385) (xy 355.304411 -29.751707)
			(xy 355.226573 -29.649994) (xy 355.155209 -29.543638) (xy 355.090595 -29.433051) (xy 355.032981 -29.318661)
			(xy 354.98259 -29.200911) (xy 354.939617 -29.080255) (xy 354.904228 -28.957162) (xy 354.876561 -28.832106)
			(xy 354.856722 -28.705572) (xy 354.844787 -28.57805) (xy 354.840804 -28.450032) (xy 259.309108 -28.450032)
			(xy 259.309108 -33.275016) (xy 259.308614 -33.345398) (xy 259.30072 -33.48594) (xy 259.284959 -33.625819)
			(xy 259.261379 -33.764594) (xy 259.230448 -33.90011) (xy 462.69148 -33.90011) (xy 462.69148 -32.29991)
			(xy 462.691988 -32.23523) (xy 462.700111 -32.106124) (xy 462.716324 -31.977784) (xy 462.740564 -31.850714)
			(xy 462.772734 -31.725418) (xy 462.812709 -31.602388) (xy 462.86033 -31.482112) (xy 462.915409 -31.365063)
			(xy 462.977729 -31.251703) (xy 463.047044 -31.14248) (xy 463.12308 -31.037825) (xy 463.205538 -30.938151)
			(xy 463.294091 -30.843851) (xy 463.388391 -30.755298) (xy 463.488065 -30.67284) (xy 463.59272 -30.596804)
			(xy 463.701943 -30.527489) (xy 463.815303 -30.465169) (xy 463.932352 -30.41009) (xy 464.052628 -30.362469)
			(xy 464.175658 -30.322494) (xy 464.300954 -30.290324) (xy 464.428024 -30.266084) (xy 464.556364 -30.249871)
			(xy 464.68547 -30.241748) (xy 464.81483 -30.241748) (xy 464.943936 -30.249871) (xy 465.072276 -30.266084)
			(xy 465.199346 -30.290324) (xy 465.324642 -30.322494) (xy 465.447672 -30.362469) (xy 465.567948 -30.41009)
			(xy 465.684997 -30.465169) (xy 465.798357 -30.527489) (xy 465.90758 -30.596804) (xy 466.012235 -30.67284)
			(xy 466.111909 -30.755298) (xy 466.206209 -30.843851) (xy 466.294762 -30.938151) (xy 466.37722 -31.037825)
			(xy 466.453256 -31.14248) (xy 466.522571 -31.251703) (xy 466.584891 -31.365063) (xy 466.63997 -31.482112)
			(xy 466.687591 -31.602388) (xy 466.727566 -31.725418) (xy 466.759736 -31.850714) (xy 466.783976 -31.977784)
			(xy 466.800189 -32.106124) (xy 466.808312 -32.23523) (xy 466.80882 -32.29991) (xy 466.80882 -33.90011)
			(xy 466.808312 -33.96479) (xy 466.800189 -34.093896) (xy 466.783976 -34.222236) (xy 466.759736 -34.349306)
			(xy 466.727566 -34.474602) (xy 466.687591 -34.597632) (xy 466.63997 -34.717908) (xy 466.584891 -34.834957)
			(xy 466.522571 -34.948317) (xy 466.453256 -35.05754) (xy 466.37722 -35.162195) (xy 466.294762 -35.261869)
			(xy 466.206209 -35.356169) (xy 466.111909 -35.444722) (xy 466.012235 -35.52718) (xy 465.90758 -35.603216)
			(xy 465.798357 -35.672531) (xy 465.684997 -35.734851) (xy 465.567948 -35.78993) (xy 465.447672 -35.837551)
			(xy 465.324642 -35.877526) (xy 465.199346 -35.909696) (xy 465.072276 -35.933936) (xy 464.943936 -35.950149)
			(xy 464.81483 -35.958272) (xy 464.68547 -35.958272) (xy 464.556364 -35.950149) (xy 464.428024 -35.933936)
			(xy 464.300954 -35.909696) (xy 464.175658 -35.877526) (xy 464.052628 -35.837551) (xy 463.932352 -35.78993)
			(xy 463.815303 -35.734851) (xy 463.701943 -35.672531) (xy 463.59272 -35.603216) (xy 463.488065 -35.52718)
			(xy 463.388391 -35.444722) (xy 463.294091 -35.356169) (xy 463.205538 -35.261869) (xy 463.12308 -35.162195)
			(xy 463.047044 -35.05754) (xy 462.977729 -34.948317) (xy 462.915409 -34.834957) (xy 462.86033 -34.717908)
			(xy 462.812709 -34.597632) (xy 462.772734 -34.474602) (xy 462.740564 -34.349306) (xy 462.716324 -34.222236)
			(xy 462.700111 -34.093896) (xy 462.691988 -33.96479) (xy 462.69148 -33.90011) (xy 259.230448 -33.90011)
			(xy 259.230056 -33.901828) (xy 259.191086 -34.03709) (xy 259.144594 -34.169955) (xy 259.090726 -34.300003)
			(xy 259.02965 -34.426827) (xy 258.961559 -34.550026) (xy 258.886668 -34.669214) (xy 258.805211 -34.784015)
			(xy 258.717446 -34.894068) (xy 258.623648 -34.999027) (xy 258.524113 -35.098562) (xy 258.419153 -35.192359)
			(xy 258.324611 -35.267753) (xy 356.989346 -35.267753) (xy 356.989346 -35.213247) (xy 356.997102 -35.159297)
			(xy 357.012458 -35.106999) (xy 357.035099 -35.057419) (xy 357.064566 -35.011566) (xy 357.100259 -34.970373)
			(xy 357.14145 -34.934678) (xy 357.187302 -34.905209) (xy 357.236881 -34.882565) (xy 357.289177 -34.867207)
			(xy 357.343127 -34.859447) (xy 357.37038 -34.85896) (xy 358.23398 -34.85896) (xy 358.261232 -34.859486)
			(xy 358.31518 -34.86724) (xy 358.367476 -34.882593) (xy 358.417054 -34.905232) (xy 358.462906 -34.934697)
			(xy 358.504098 -34.970388) (xy 358.539791 -35.011578) (xy 358.569258 -35.057428) (xy 358.5919 -35.107005)
			(xy 358.607256 -35.1593) (xy 358.615013 -35.213249) (xy 358.615013 -35.267751) (xy 358.607256 -35.3217)
			(xy 358.5919 -35.373995) (xy 358.569258 -35.423572) (xy 358.539791 -35.469422) (xy 358.504098 -35.510612)
			(xy 358.462906 -35.546303) (xy 358.417054 -35.575768) (xy 358.367476 -35.598407) (xy 358.31518 -35.61376)
			(xy 358.261232 -35.621514) (xy 358.23398 -35.621976) (xy 357.37038 -35.621976) (xy 357.343127 -35.621553)
			(xy 357.289177 -35.613793) (xy 357.236881 -35.598435) (xy 357.187302 -35.575791) (xy 357.14145 -35.546322)
			(xy 357.100259 -35.510627) (xy 357.064566 -35.469434) (xy 357.035099 -35.423581) (xy 357.012458 -35.374001)
			(xy 356.997102 -35.321703) (xy 356.989346 -35.267753) (xy 258.324611 -35.267753) (xy 258.309099 -35.280123)
			(xy 258.194297 -35.361579) (xy 258.075109 -35.436469) (xy 257.951909 -35.504559) (xy 257.825085 -35.565634)
			(xy 257.695036 -35.619502) (xy 257.562171 -35.665993) (xy 257.426909 -35.704961) (xy 257.289674 -35.736283)
			(xy 257.150899 -35.759862) (xy 257.01102 -35.775622) (xy 256.870478 -35.783514) (xy 256.800096 -35.784028)
			(xy 225.300032 -35.784028) (xy 225.229649 -35.783544) (xy 225.089104 -35.775653) (xy 224.949222 -35.759894)
			(xy 224.810444 -35.736316) (xy 224.673207 -35.704995) (xy 224.537941 -35.666027) (xy 224.405074 -35.619536)
			(xy 224.275022 -35.565669) (xy 224.148195 -35.504594) (xy 224.024992 -35.436504) (xy 223.905801 -35.361613)
			(xy 223.790997 -35.280156) (xy 223.68094 -35.192391) (xy 223.575978 -35.098593) (xy 223.47644 -34.999057)
			(xy 223.38264 -34.894096) (xy 223.294872 -34.784042) (xy 223.213414 -34.669239) (xy 223.138521 -34.550049)
			(xy 223.070428 -34.426848) (xy 223.009351 -34.300022) (xy 222.955481 -34.169971) (xy 222.908988 -34.037104)
			(xy 222.870017 -33.90184) (xy 222.838693 -33.764603) (xy 222.815113 -33.625825) (xy 222.799351 -33.485944)
			(xy 222.791457 -33.345399) (xy 222.79102 -33.275016) (xy 222.79102 -13.780008) (xy 222.790499 -13.724238)
			(xy 222.782164 -13.613011) (xy 222.765541 -13.502717) (xy 222.740722 -13.393974) (xy 222.707846 -13.287389)
			(xy 222.667097 -13.183559) (xy 222.618703 -13.083065) (xy 222.562935 -12.986469) (xy 222.500103 -12.894309)
			(xy 222.430561 -12.807103) (xy 222.354696 -12.725338) (xy 222.272933 -12.64947) (xy 222.185729 -12.579925)
			(xy 222.093572 -12.517091) (xy 221.996977 -12.461319) (xy 221.896485 -12.412922) (xy 221.792656 -12.37217)
			(xy 221.686073 -12.339291) (xy 221.57733 -12.314468) (xy 221.467037 -12.297841) (xy 221.35581 -12.289503)
			(xy 221.30004 -12.289028) (xy 196.701918 -12.289028) (xy 196.631535 -12.288544) (xy 196.49099 -12.280652)
			(xy 196.35111 -12.264892) (xy 196.212332 -12.241314) (xy 196.075095 -12.209992) (xy 195.939831 -12.171024)
			(xy 195.806964 -12.124532) (xy 195.676913 -12.070665) (xy 195.550086 -12.009589) (xy 195.426884 -11.941499)
			(xy 195.307694 -11.866608) (xy 195.19289 -11.785152) (xy 195.082834 -11.697386) (xy 194.977873 -11.603588)
			(xy 194.878335 -11.504052) (xy 194.784536 -11.399092) (xy 194.696769 -11.289037) (xy 194.615311 -11.174234)
			(xy 194.540418 -11.055045) (xy 194.472326 -10.931844) (xy 194.411249 -10.805018) (xy 194.35738 -10.674968)
			(xy 194.310887 -10.542102) (xy 194.271917 -10.406837) (xy 194.240593 -10.269601) (xy 194.217013 -10.130824)
			(xy 194.201251 -9.990943) (xy 194.193357 -9.850399) (xy 194.192906 -9.780016) (xy 194.192906 -6.279896)
			(xy 194.19238 -6.247749) (xy 194.183988 -6.184006) (xy 194.167348 -6.121904) (xy 194.142744 -6.062504)
			(xy 194.110598 -6.006824) (xy 194.07146 -5.955816) (xy 194.025999 -5.910353) (xy 193.974992 -5.871213)
			(xy 193.919314 -5.839064) (xy 193.859915 -5.814458) (xy 193.797813 -5.797816) (xy 193.734071 -5.789421)
			(xy 193.701924 -5.788914) (xy 127.102108 -5.788914) (xy 127.06996 -5.789416) (xy 127.006214 -5.797808)
			(xy 126.944108 -5.814448) (xy 126.884706 -5.839052) (xy 126.829023 -5.8712) (xy 126.778013 -5.91034)
			(xy 126.732548 -5.955804) (xy 126.693406 -6.006813) (xy 126.661257 -6.062495) (xy 126.636652 -6.121897)
			(xy 126.62001 -6.184002) (xy 126.611617 -6.247748) (xy 126.611126 -6.279896) (xy 126.611126 -9.780016)
			(xy 126.610632 -9.850398) (xy 126.602738 -9.990941) (xy 126.586977 -10.13082) (xy 126.563397 -10.269595)
			(xy 126.532074 -10.40683) (xy 126.519617 -10.450068) (xy 127.350273 -10.450068) (xy 127.354278 -10.36216)
			(xy 127.366261 -10.27498) (xy 127.386121 -10.189251) (xy 127.413696 -10.105683) (xy 127.448755 -10.024969)
			(xy 127.491008 -9.947777) (xy 127.540106 -9.874748) (xy 127.595642 -9.806486) (xy 127.657154 -9.743556)
			(xy 127.724135 -9.686482) (xy 127.796028 -9.635734) (xy 127.872237 -9.591734) (xy 127.952132 -9.554847)
			(xy 128.035051 -9.525378) (xy 128.120306 -9.503571) (xy 128.20719 -9.489607) (xy 128.294984 -9.483601)
			(xy 128.382961 -9.485605) (xy 128.470391 -9.4956) (xy 128.55655 -9.513504) (xy 128.640724 -9.539168)
			(xy 128.722215 -9.572381) (xy 128.800349 -9.612867) (xy 128.874477 -9.660289) (xy 128.943985 -9.714256)
			(xy 129.008299 -9.774321) (xy 129.066883 -9.839985) (xy 129.119254 -9.910704) (xy 129.164977 -9.985892)
			(xy 129.203674 -10.064927) (xy 129.235023 -10.147153) (xy 129.258765 -10.231889) (xy 129.265884 -10.270548)
			(xy 131.63909 -10.270548) (xy 131.63909 -10.216052) (xy 131.646845 -10.16211) (xy 131.662198 -10.10982)
			(xy 131.684835 -10.060247) (xy 131.714296 -10.014401) (xy 131.749982 -9.973213) (xy 131.791165 -9.937522)
			(xy 131.837009 -9.908056) (xy 131.886579 -9.885413) (xy 131.938866 -9.870055) (xy 131.992808 -9.862293)
			(xy 132.020056 -9.861804) (xy 132.883656 -9.861804) (xy 132.910912 -9.86224) (xy 132.964869 -9.869992)
			(xy 133.017174 -9.885345) (xy 133.066761 -9.907985) (xy 133.112622 -9.937453) (xy 133.153821 -9.973148)
			(xy 133.18952 -10.014343) (xy 133.218993 -10.0602) (xy 133.24164 -10.109785) (xy 133.256999 -10.162088)
			(xy 133.264757 -10.216044) (xy 133.264757 -10.270556) (xy 133.256999 -10.324512) (xy 133.24164 -10.376815)
			(xy 133.218993 -10.4264) (xy 133.18952 -10.472257) (xy 133.153821 -10.513452) (xy 133.112622 -10.549147)
			(xy 133.066761 -10.578615) (xy 133.017174 -10.601255) (xy 132.964869 -10.616608) (xy 132.910912 -10.62436)
			(xy 132.883656 -10.62482) (xy 132.020056 -10.62482) (xy 131.992808 -10.624307) (xy 131.938866 -10.616545)
			(xy 131.886579 -10.601187) (xy 131.837009 -10.578544) (xy 131.791165 -10.549078) (xy 131.749982 -10.513387)
			(xy 131.714296 -10.472199) (xy 131.684835 -10.426353) (xy 131.662198 -10.37678) (xy 131.646845 -10.32449)
			(xy 131.63909 -10.270548) (xy 129.265884 -10.270548) (xy 129.274703 -10.318433) (xy 129.282705 -10.406068)
			(xy 129.283206 -10.450068) (xy 129.282705 -10.494068) (xy 129.274703 -10.581703) (xy 129.258765 -10.668247)
			(xy 129.235023 -10.752983) (xy 129.203674 -10.835209) (xy 129.164977 -10.914244) (xy 129.119254 -10.989432)
			(xy 129.087321 -11.032553) (xy 168.158867 -11.032553) (xy 168.158867 -10.978047) (xy 168.166625 -10.924096)
			(xy 168.181981 -10.871798) (xy 168.204625 -10.822218) (xy 168.234094 -10.776365) (xy 168.269789 -10.735173)
			(xy 168.310983 -10.699481) (xy 168.356837 -10.670014) (xy 168.406419 -10.647374) (xy 168.458717 -10.63202)
			(xy 168.512669 -10.624266) (xy 168.539922 -10.623804) (xy 169.403522 -10.623804) (xy 169.430773 -10.624267)
			(xy 169.48472 -10.632027) (xy 169.537014 -10.647384) (xy 169.58659 -10.670027) (xy 169.632439 -10.699495)
			(xy 169.673628 -10.735188) (xy 169.709318 -10.776379) (xy 169.738783 -10.822229) (xy 169.761424 -10.871807)
			(xy 169.776778 -10.924101) (xy 169.784534 -10.978049) (xy 169.784534 -11.032551) (xy 169.776778 -11.086499)
			(xy 169.761424 -11.138793) (xy 169.738783 -11.188371) (xy 169.709318 -11.234221) (xy 169.673628 -11.275412)
			(xy 169.632439 -11.311105) (xy 169.58659 -11.340573) (xy 169.537014 -11.363216) (xy 169.48472 -11.378573)
			(xy 169.430773 -11.386333) (xy 169.403522 -11.38682) (xy 168.539922 -11.38682) (xy 168.512669 -11.386334)
			(xy 168.458717 -11.37858) (xy 168.406419 -11.363226) (xy 168.356837 -11.340586) (xy 168.310983 -11.311119)
			(xy 168.269789 -11.275427) (xy 168.234094 -11.234235) (xy 168.204625 -11.188382) (xy 168.181981 -11.138802)
			(xy 168.166625 -11.086504) (xy 168.158867 -11.032553) (xy 129.087321 -11.032553) (xy 129.066883 -11.060151)
			(xy 129.008299 -11.125815) (xy 128.943985 -11.18588) (xy 128.874477 -11.239847) (xy 128.800349 -11.287269)
			(xy 128.722215 -11.327755) (xy 128.640724 -11.360968) (xy 128.55655 -11.386632) (xy 128.470391 -11.404536)
			(xy 128.382961 -11.414531) (xy 128.294984 -11.416535) (xy 128.20719 -11.410529) (xy 128.120306 -11.396565)
			(xy 128.035051 -11.374758) (xy 127.952132 -11.345289) (xy 127.872237 -11.308402) (xy 127.796028 -11.264402)
			(xy 127.724135 -11.213654) (xy 127.657154 -11.15658) (xy 127.595642 -11.09365) (xy 127.540106 -11.025388)
			(xy 127.491008 -10.952359) (xy 127.448755 -10.875167) (xy 127.413696 -10.794453) (xy 127.386121 -10.710885)
			(xy 127.366261 -10.625156) (xy 127.354278 -10.537976) (xy 127.350273 -10.450068) (xy 126.519617 -10.450068)
			(xy 126.493105 -10.542092) (xy 126.446613 -10.674957) (xy 126.392744 -10.805006) (xy 126.331668 -10.93183)
			(xy 126.263578 -11.05503) (xy 126.188687 -11.174218) (xy 126.10723 -11.28902) (xy 126.019465 -11.399074)
			(xy 125.973895 -11.450066) (xy 191.515245 -11.450066) (xy 191.51925 -11.362158) (xy 191.531233 -11.274978)
			(xy 191.551093 -11.189249) (xy 191.578668 -11.105681) (xy 191.613727 -11.024967) (xy 191.65598 -10.947775)
			(xy 191.705078 -10.874746) (xy 191.760614 -10.806484) (xy 191.822126 -10.743554) (xy 191.889107 -10.68648)
			(xy 191.961 -10.635732) (xy 192.037209 -10.591732) (xy 192.117104 -10.554845) (xy 192.200023 -10.525376)
			(xy 192.285278 -10.503569) (xy 192.372162 -10.489605) (xy 192.459956 -10.483599) (xy 192.547933 -10.485603)
			(xy 192.635363 -10.495598) (xy 192.721522 -10.513502) (xy 192.805696 -10.539166) (xy 192.887187 -10.572379)
			(xy 192.965321 -10.612865) (xy 193.039449 -10.660287) (xy 193.108957 -10.714254) (xy 193.173271 -10.774319)
			(xy 193.231855 -10.839983) (xy 193.284226 -10.910702) (xy 193.329949 -10.98589) (xy 193.368646 -11.064925)
			(xy 193.399995 -11.147151) (xy 193.423737 -11.231887) (xy 193.439675 -11.318431) (xy 193.447677 -11.406066)
			(xy 193.448178 -11.450066) (xy 193.447677 -11.494066) (xy 193.439675 -11.581701) (xy 193.423737 -11.668245)
			(xy 193.399995 -11.752981) (xy 193.368646 -11.835207) (xy 193.329949 -11.914242) (xy 193.284226 -11.98943)
			(xy 193.231855 -12.060149) (xy 193.173271 -12.125813) (xy 193.108957 -12.185878) (xy 193.039449 -12.239845)
			(xy 192.965321 -12.287267) (xy 192.887187 -12.327753) (xy 192.805696 -12.360966) (xy 192.721522 -12.38663)
			(xy 192.635363 -12.404534) (xy 192.547933 -12.414529) (xy 192.459956 -12.416533) (xy 192.372162 -12.410527)
			(xy 192.285278 -12.396563) (xy 192.200023 -12.374756) (xy 192.117104 -12.345287) (xy 192.037209 -12.3084)
			(xy 191.961 -12.2644) (xy 191.889107 -12.213652) (xy 191.822126 -12.156578) (xy 191.760614 -12.093648)
			(xy 191.705078 -12.025386) (xy 191.65598 -11.952357) (xy 191.613727 -11.875165) (xy 191.578668 -11.794451)
			(xy 191.551093 -11.710883) (xy 191.531233 -11.625154) (xy 191.51925 -11.537974) (xy 191.515245 -11.450066)
			(xy 125.973895 -11.450066) (xy 125.925667 -11.504033) (xy 125.826132 -11.603569) (xy 125.721172 -11.697366)
			(xy 125.611118 -11.785131) (xy 125.496317 -11.866588) (xy 125.377128 -11.941479) (xy 125.253928 -12.009569)
			(xy 125.206611 -12.032356) (xy 166.354411 -12.032356) (xy 166.354411 -11.977844) (xy 166.362169 -11.923886)
			(xy 166.377527 -11.871582) (xy 166.400173 -11.821995) (xy 166.429645 -11.776137) (xy 166.465343 -11.734939)
			(xy 166.506541 -11.699241) (xy 166.552401 -11.66977) (xy 166.601987 -11.647125) (xy 166.654292 -11.631768)
			(xy 166.70825 -11.624011) (xy 166.735506 -11.623548) (xy 167.599106 -11.623548) (xy 167.626354 -11.624123)
			(xy 167.680295 -11.631879) (xy 167.732583 -11.647233) (xy 167.782153 -11.669872) (xy 167.827998 -11.699335)
			(xy 167.869182 -11.735022) (xy 167.904869 -11.776207) (xy 167.934331 -11.822052) (xy 167.956969 -11.871623)
			(xy 167.972322 -11.923911) (xy 167.980078 -11.977852) (xy 167.980078 -12.032348) (xy 167.980077 -12.032358)
			(xy 169.954311 -12.032358) (xy 169.954311 -11.977842) (xy 169.96207 -11.92388) (xy 169.97743 -11.871573)
			(xy 170.000079 -11.821984) (xy 170.029555 -11.776123) (xy 170.065258 -11.734924) (xy 170.106461 -11.699226)
			(xy 170.152326 -11.669756) (xy 170.201918 -11.647114) (xy 170.254227 -11.63176) (xy 170.30819 -11.624008)
			(xy 170.335448 -11.623548) (xy 171.199048 -11.623548) (xy 171.226294 -11.624125) (xy 171.28023 -11.631887)
			(xy 171.332513 -11.647244) (xy 171.382078 -11.669885) (xy 171.427917 -11.699349) (xy 171.469097 -11.735037)
			(xy 171.504779 -11.776221) (xy 171.534238 -11.822064) (xy 171.556873 -11.871632) (xy 171.572224 -11.923917)
			(xy 171.579978 -11.977854) (xy 171.579978 -12.032346) (xy 171.572224 -12.086283) (xy 171.556873 -12.138568)
			(xy 171.534238 -12.188136) (xy 171.504779 -12.233979) (xy 171.469097 -12.275163) (xy 171.427917 -12.310851)
			(xy 171.382078 -12.340315) (xy 171.332513 -12.362956) (xy 171.28023 -12.378313) (xy 171.226294 -12.386075)
			(xy 171.199048 -12.386564) (xy 170.335448 -12.386564) (xy 170.30819 -12.386192) (xy 170.254227 -12.37844)
			(xy 170.201918 -12.363086) (xy 170.152326 -12.340444) (xy 170.106461 -12.310974) (xy 170.065258 -12.275276)
			(xy 170.029555 -12.234077) (xy 170.000079 -12.188216) (xy 169.97743 -12.138627) (xy 169.96207 -12.08632)
			(xy 169.954311 -12.032358) (xy 167.980077 -12.032358) (xy 167.972322 -12.086289) (xy 167.956969 -12.138577)
			(xy 167.934331 -12.188148) (xy 167.904869 -12.233993) (xy 167.869182 -12.275178) (xy 167.827998 -12.310865)
			(xy 167.782153 -12.340328) (xy 167.732583 -12.362967) (xy 167.680295 -12.378321) (xy 167.626354 -12.386077)
			(xy 167.599106 -12.386564) (xy 166.735506 -12.386564) (xy 166.70825 -12.386189) (xy 166.654292 -12.378432)
			(xy 166.601987 -12.363075) (xy 166.552401 -12.34043) (xy 166.506541 -12.310959) (xy 166.465343 -12.275261)
			(xy 166.429645 -12.234063) (xy 166.400173 -12.188205) (xy 166.377527 -12.138618) (xy 166.362169 -12.086314)
			(xy 166.354411 -12.032356) (xy 125.206611 -12.032356) (xy 125.127104 -12.070645) (xy 124.997055 -12.124513)
			(xy 124.86419 -12.171005) (xy 124.728928 -12.209974) (xy 124.591693 -12.241298) (xy 124.452918 -12.264877)
			(xy 124.313039 -12.280639) (xy 124.172496 -12.288532) (xy 124.102114 -12.289028) (xy 83.70189 -12.289028)
			(xy 83.631508 -12.288534) (xy 83.490965 -12.280641) (xy 83.351086 -12.26488) (xy 83.21231 -12.2413)
			(xy 83.075075 -12.209977) (xy 82.939812 -12.171008) (xy 82.806947 -12.124516) (xy 82.676898 -12.070648)
			(xy 82.550073 -12.009572) (xy 82.426873 -11.941482) (xy 82.307684 -11.866591) (xy 82.192882 -11.785134)
			(xy 82.082828 -11.697369) (xy 81.977868 -11.603571) (xy 81.878333 -11.504036) (xy 81.784535 -11.399076)
			(xy 81.696769 -11.289022) (xy 81.615313 -11.174221) (xy 81.540421 -11.055032) (xy 81.47233 -10.931832)
			(xy 81.411254 -10.805008) (xy 81.357386 -10.674959) (xy 81.310894 -10.542094) (xy 81.271924 -10.406831)
			(xy 81.240601 -10.269596) (xy 81.217021 -10.13082) (xy 81.20126 -9.990941) (xy 81.193366 -9.850398)
			(xy 81.192878 -9.780016) (xy 81.192878 -0.999998) (xy 81.192375 -0.96785) (xy 81.183982 -0.904106)
			(xy 81.167341 -0.842001) (xy 81.142736 -0.782601) (xy 81.110589 -0.72692) (xy 81.071448 -0.675911)
			(xy 81.025984 -0.630448) (xy 80.974975 -0.591308) (xy 80.919294 -0.559161) (xy 80.859893 -0.534557)
			(xy 80.797789 -0.517916) (xy 80.734044 -0.509525) (xy 80.701896 -0.509016) (xy 14.10208 -0.509016)
			(xy 14.069935 -0.509543) (xy 14.006194 -0.517937) (xy 13.944095 -0.534579) (xy 13.884698 -0.559184)
			(xy 13.829022 -0.59133) (xy 13.778017 -0.630469) (xy 13.732558 -0.675931) (xy 13.69342 -0.726937)
			(xy 13.661276 -0.782614) (xy 13.636673 -0.842012) (xy 13.620034 -0.904112) (xy 13.611642 -0.967853)
			(xy 13.611098 -0.999998) (xy 13.611098 -5.184498) (xy 14.350702 -5.184498) (xy 14.35331 -5.097781)
			(xy 14.363685 -5.011647) (xy 14.381743 -4.926791) (xy 14.40734 -4.843896) (xy 14.440268 -4.763631)
			(xy 14.480262 -4.686643) (xy 14.526999 -4.613552) (xy 14.580104 -4.544948) (xy 14.639148 -4.481383)
			(xy 14.703655 -4.42337) (xy 14.738096 -4.396994) (xy 14.773029 -4.371293) (xy 14.846784 -4.325653)
			(xy 14.924335 -4.28681) (xy 15.005056 -4.255076) (xy 15.088297 -4.230709) (xy 15.173387 -4.213903)
			(xy 15.259642 -4.204794) (xy 15.346366 -4.203455) (xy 15.432861 -4.209898) (xy 15.518429 -4.224071)
			(xy 15.602382 -4.245858) (xy 15.684044 -4.275086) (xy 15.762756 -4.311517) (xy 15.837884 -4.35486)
			(xy 15.908824 -4.404764) (xy 15.975003 -4.460828) (xy 16.035889 -4.5226) (xy 16.090991 -4.589582)
			(xy 16.139865 -4.661235) (xy 16.182118 -4.736981) (xy 16.217409 -4.816211) (xy 16.245454 -4.898286)
			(xy 16.266027 -4.982545) (xy 16.267136 -4.989901) (xy 20.44038 -4.989901) (xy 20.44038 -4.935399)
			(xy 20.448136 -4.881452) (xy 20.463491 -4.829158) (xy 20.486132 -4.779581) (xy 20.515597 -4.733731)
			(xy 20.551288 -4.692541) (xy 20.592478 -4.65685) (xy 20.638328 -4.627384) (xy 20.687904 -4.604742)
			(xy 20.740198 -4.589387) (xy 20.794145 -4.58163) (xy 20.821396 -4.581144) (xy 21.684996 -4.581144)
			(xy 21.712249 -4.581603) (xy 21.766201 -4.58936) (xy 21.818499 -4.604715) (xy 21.86808 -4.627358)
			(xy 21.913934 -4.656826) (xy 21.955128 -4.69252) (xy 21.990822 -4.733713) (xy 22.02029 -4.779566)
			(xy 22.042933 -4.829147) (xy 22.05829 -4.881445) (xy 22.066047 -4.935397) (xy 22.066047 -4.989901)
			(xy 24.04032 -4.989901) (xy 24.04032 -4.935399) (xy 24.048076 -4.881452) (xy 24.063431 -4.829157)
			(xy 24.086072 -4.779581) (xy 24.115538 -4.73373) (xy 24.151229 -4.692541) (xy 24.192419 -4.656849)
			(xy 24.238269 -4.627383) (xy 24.287846 -4.604742) (xy 24.34014 -4.589387) (xy 24.394087 -4.58163)
			(xy 24.421338 -4.581144) (xy 25.284938 -4.581144) (xy 25.312191 -4.581603) (xy 25.366143 -4.58936)
			(xy 25.418441 -4.604716) (xy 25.468021 -4.627358) (xy 25.513875 -4.656827) (xy 25.555068 -4.69252)
			(xy 25.590762 -4.733713) (xy 25.620231 -4.779567) (xy 25.642873 -4.829147) (xy 25.65823 -4.881446)
			(xy 25.665987 -4.935397) (xy 25.665987 -4.989903) (xy 25.66598 -4.989954) (xy 27.64023 -4.989954)
			(xy 27.64023 -4.935446) (xy 27.647987 -4.881493) (xy 27.663343 -4.829194) (xy 27.685985 -4.779612)
			(xy 27.715454 -4.733756) (xy 27.751147 -4.692562) (xy 27.79234 -4.656866) (xy 27.838194 -4.627395)
			(xy 27.887775 -4.60475) (xy 27.940074 -4.589391) (xy 27.994026 -4.581631) (xy 28.02128 -4.581144)
			(xy 28.88488 -4.581144) (xy 28.91213 -4.581702) (xy 28.966077 -4.589456) (xy 29.01837 -4.604808)
			(xy 29.067947 -4.627446) (xy 29.113797 -4.65691) (xy 29.154986 -4.692599) (xy 29.190678 -4.733787)
			(xy 29.220144 -4.779636) (xy 29.242785 -4.829211) (xy 29.25814 -4.881504) (xy 29.265897 -4.93545)
			(xy 29.265897 -4.98995) (xy 29.265896 -4.989954) (xy 31.24043 -4.989954) (xy 31.24043 -4.935446)
			(xy 31.248187 -4.881494) (xy 31.263543 -4.829195) (xy 31.286185 -4.779613) (xy 31.315653 -4.733758)
			(xy 31.351346 -4.692563) (xy 31.392538 -4.656867) (xy 31.438392 -4.627396) (xy 31.487972 -4.604751)
			(xy 31.540271 -4.589392) (xy 31.594222 -4.581632) (xy 31.621476 -4.581144) (xy 32.485076 -4.581144)
			(xy 32.512327 -4.581702) (xy 32.566273 -4.589455) (xy 32.618567 -4.604807) (xy 32.668144 -4.627445)
			(xy 32.713995 -4.656909) (xy 32.755185 -4.692598) (xy 32.790877 -4.733786) (xy 32.820343 -4.779635)
			(xy 32.842985 -4.82921) (xy 32.85834 -4.881503) (xy 32.866097 -4.935449) (xy 32.866097 -4.989951)
			(xy 32.866096 -4.989958) (xy 40.350307 -4.989958) (xy 40.350307 -4.935442) (xy 40.358066 -4.881481)
			(xy 40.373426 -4.829173) (xy 40.396074 -4.779584) (xy 40.42555 -4.733723) (xy 40.461252 -4.692524)
			(xy 40.502455 -4.656826) (xy 40.548319 -4.627355) (xy 40.59791 -4.604712) (xy 40.65022 -4.589358)
			(xy 40.704182 -4.581604) (xy 40.73144 -4.581144) (xy 41.59504 -4.581144) (xy 41.622286 -4.581729)
			(xy 41.676222 -4.589489) (xy 41.728506 -4.604846) (xy 41.778072 -4.627486) (xy 41.823911 -4.65695)
			(xy 41.865091 -4.692637) (xy 41.900774 -4.733821) (xy 41.930233 -4.779663) (xy 41.952868 -4.829232)
			(xy 41.968219 -4.881517) (xy 41.975974 -4.935454) (xy 41.975974 -4.989946) (xy 41.975973 -4.989954)
			(xy 43.95033 -4.989954) (xy 43.95033 -4.935446) (xy 43.958087 -4.881493) (xy 43.973443 -4.829193)
			(xy 43.996086 -4.779611) (xy 44.025554 -4.733756) (xy 44.061248 -4.692561) (xy 44.102441 -4.656865)
			(xy 44.148295 -4.627394) (xy 44.197876 -4.604749) (xy 44.250176 -4.589391) (xy 44.304128 -4.581631)
			(xy 44.331382 -4.581144) (xy 45.194982 -4.581144) (xy 45.222232 -4.581702) (xy 45.276178 -4.589456)
			(xy 45.328472 -4.604808) (xy 45.378048 -4.627447) (xy 45.423898 -4.656911) (xy 45.465087 -4.6926)
			(xy 45.500778 -4.733788) (xy 45.530244 -4.779636) (xy 45.552885 -4.829211) (xy 45.56824 -4.881504)
			(xy 45.575997 -4.93545) (xy 45.575997 -4.98995) (xy 45.575996 -4.989954) (xy 51.56043 -4.989954)
			(xy 51.56043 -4.935446) (xy 51.568187 -4.881494) (xy 51.583543 -4.829195) (xy 51.606185 -4.779613)
			(xy 51.635653 -4.733758) (xy 51.671346 -4.692563) (xy 51.712538 -4.656867) (xy 51.758392 -4.627396)
			(xy 51.807972 -4.604751) (xy 51.860271 -4.589392) (xy 51.914222 -4.581632) (xy 51.941476 -4.581144)
			(xy 52.805076 -4.581144) (xy 52.832327 -4.581702) (xy 52.886273 -4.589455) (xy 52.938567 -4.604807)
			(xy 52.988144 -4.627445) (xy 53.033995 -4.656909) (xy 53.075185 -4.692598) (xy 53.110877 -4.733786)
			(xy 53.140343 -4.779635) (xy 53.162985 -4.82921) (xy 53.17834 -4.881503) (xy 53.186097 -4.935449)
			(xy 53.186097 -4.989951) (xy 53.186096 -4.989957) (xy 55.160307 -4.989957) (xy 55.160307 -4.935443)
			(xy 55.168065 -4.881484) (xy 55.183424 -4.829178) (xy 55.206071 -4.77959) (xy 55.235544 -4.73373)
			(xy 55.271245 -4.692532) (xy 55.312445 -4.656834) (xy 55.358306 -4.627362) (xy 55.407894 -4.604718)
			(xy 55.460201 -4.589362) (xy 55.514161 -4.581606) (xy 55.541418 -4.581144) (xy 56.405018 -4.581144)
			(xy 56.432265 -4.581727) (xy 56.486204 -4.589485) (xy 56.53849 -4.60484) (xy 56.588058 -4.627479)
			(xy 56.633901 -4.656942) (xy 56.675084 -4.692629) (xy 56.710769 -4.733814) (xy 56.74023 -4.779657)
			(xy 56.762867 -4.829227) (xy 56.778219 -4.881514) (xy 56.785974 -4.935453) (xy 56.785974 -4.989947)
			(xy 56.778219 -5.043886) (xy 56.762867 -5.096173) (xy 56.74023 -5.145743) (xy 56.710769 -5.191586)
			(xy 56.675084 -5.232771) (xy 56.633901 -5.268458) (xy 56.588058 -5.297921) (xy 56.53849 -5.32056)
			(xy 56.486204 -5.335915) (xy 56.432265 -5.343673) (xy 56.405018 -5.34416) (xy 55.541418 -5.34416)
			(xy 55.514161 -5.343794) (xy 55.460201 -5.336038) (xy 55.407894 -5.320682) (xy 55.358306 -5.298038)
			(xy 55.312445 -5.268566) (xy 55.271245 -5.232868) (xy 55.235544 -5.19167) (xy 55.206071 -5.14581)
			(xy 55.183424 -5.096222) (xy 55.168065 -5.043916) (xy 55.160307 -4.989957) (xy 53.186096 -4.989957)
			(xy 53.17834 -5.043897) (xy 53.162985 -5.09619) (xy 53.140343 -5.145765) (xy 53.110877 -5.191614)
			(xy 53.075185 -5.232802) (xy 53.033995 -5.268491) (xy 52.988144 -5.297955) (xy 52.938567 -5.320593)
			(xy 52.886273 -5.335945) (xy 52.832327 -5.343698) (xy 52.805076 -5.34416) (xy 51.941476 -5.34416)
			(xy 51.914222 -5.343768) (xy 51.860271 -5.336008) (xy 51.807972 -5.320649) (xy 51.758392 -5.298004)
			(xy 51.712538 -5.268533) (xy 51.671346 -5.232837) (xy 51.635653 -5.191642) (xy 51.606185 -5.145787)
			(xy 51.583543 -5.096205) (xy 51.568187 -5.043906) (xy 51.56043 -4.989954) (xy 45.575996 -4.989954)
			(xy 45.56824 -5.043896) (xy 45.552885 -5.096189) (xy 45.530244 -5.145764) (xy 45.500778 -5.191612)
			(xy 45.465087 -5.2328) (xy 45.423898 -5.268489) (xy 45.378048 -5.297953) (xy 45.328472 -5.320592)
			(xy 45.276178 -5.335944) (xy 45.222232 -5.343698) (xy 45.194982 -5.34416) (xy 44.331382 -5.34416)
			(xy 44.304128 -5.343769) (xy 44.250176 -5.336009) (xy 44.197876 -5.320651) (xy 44.148295 -5.298006)
			(xy 44.102441 -5.268535) (xy 44.061248 -5.232839) (xy 44.025554 -5.191644) (xy 43.996086 -5.145789)
			(xy 43.973443 -5.096207) (xy 43.958087 -5.043907) (xy 43.95033 -4.989954) (xy 41.975973 -4.989954)
			(xy 41.968219 -5.043883) (xy 41.952868 -5.096168) (xy 41.930233 -5.145737) (xy 41.900774 -5.191579)
			(xy 41.865091 -5.232763) (xy 41.823911 -5.26845) (xy 41.778072 -5.297914) (xy 41.728506 -5.320554)
			(xy 41.676222 -5.335911) (xy 41.622286 -5.343671) (xy 41.59504 -5.34416) (xy 40.73144 -5.34416) (xy 40.704182 -5.343796)
			(xy 40.65022 -5.336042) (xy 40.59791 -5.320688) (xy 40.548319 -5.298045) (xy 40.502455 -5.268574)
			(xy 40.461252 -5.232876) (xy 40.42555 -5.191677) (xy 40.396074 -5.145816) (xy 40.373426 -5.096227)
			(xy 40.358066 -5.043919) (xy 40.350307 -4.989958) (xy 32.866096 -4.989958) (xy 32.85834 -5.043897)
			(xy 32.842985 -5.09619) (xy 32.820343 -5.145765) (xy 32.790877 -5.191614) (xy 32.755185 -5.232802)
			(xy 32.713995 -5.268491) (xy 32.668144 -5.297955) (xy 32.618567 -5.320593) (xy 32.566273 -5.335945)
			(xy 32.512327 -5.343698) (xy 32.485076 -5.34416) (xy 31.621476 -5.34416) (xy 31.594222 -5.343768)
			(xy 31.540271 -5.336008) (xy 31.487972 -5.320649) (xy 31.438392 -5.298004) (xy 31.392538 -5.268533)
			(xy 31.351346 -5.232837) (xy 31.315653 -5.191642) (xy 31.286185 -5.145787) (xy 31.263543 -5.096205)
			(xy 31.248187 -5.043906) (xy 31.24043 -4.989954) (xy 29.265896 -4.989954) (xy 29.25814 -5.043896)
			(xy 29.242785 -5.096189) (xy 29.220144 -5.145764) (xy 29.190678 -5.191613) (xy 29.154986 -5.232801)
			(xy 29.113797 -5.26849) (xy 29.067947 -5.297954) (xy 29.01837 -5.320592) (xy 28.966077 -5.335944)
			(xy 28.91213 -5.343698) (xy 28.88488 -5.34416) (xy 28.02128 -5.34416) (xy 27.994026 -5.343769) (xy 27.940074 -5.336009)
			(xy 27.887775 -5.32065) (xy 27.838194 -5.298005) (xy 27.79234 -5.268534) (xy 27.751147 -5.232838)
			(xy 27.715454 -5.191644) (xy 27.685985 -5.145788) (xy 27.663343 -5.096206) (xy 27.647987 -5.043907)
			(xy 27.64023 -4.989954) (xy 25.66598 -4.989954) (xy 25.65823 -5.043854) (xy 25.642873 -5.096153)
			(xy 25.620231 -5.145733) (xy 25.590762 -5.191587) (xy 25.555068 -5.23278) (xy 25.513875 -5.268473)
			(xy 25.468021 -5.297942) (xy 25.418441 -5.320584) (xy 25.366143 -5.33594) (xy 25.312191 -5.343697)
			(xy 25.284938 -5.34416) (xy 24.421338 -5.34416) (xy 24.394087 -5.34367) (xy 24.34014 -5.335913) (xy 24.287846 -5.320558)
			(xy 24.238269 -5.297917) (xy 24.192419 -5.268451) (xy 24.151229 -5.232759) (xy 24.115538 -5.19157)
			(xy 24.086072 -5.145719) (xy 24.063431 -5.096143) (xy 24.048076 -5.043848) (xy 24.04032 -4.989901)
			(xy 22.066047 -4.989901) (xy 22.066047 -4.989903) (xy 22.05829 -5.043855) (xy 22.042933 -5.096153)
			(xy 22.02029 -5.145734) (xy 21.990822 -5.191587) (xy 21.955128 -5.23278) (xy 21.913934 -5.268474)
			(xy 21.86808 -5.297942) (xy 21.818499 -5.320585) (xy 21.766201 -5.33594) (xy 21.712249 -5.343697)
			(xy 21.684996 -5.34416) (xy 20.821396 -5.34416) (xy 20.794145 -5.34367) (xy 20.740198 -5.335913)
			(xy 20.687904 -5.320558) (xy 20.638328 -5.297916) (xy 20.592478 -5.26845) (xy 20.551288 -5.232759)
			(xy 20.515597 -5.191569) (xy 20.486132 -5.145719) (xy 20.463491 -5.096142) (xy 20.448136 -5.043848)
			(xy 20.44038 -4.989901) (xy 16.267136 -4.989901) (xy 16.278962 -5.06831) (xy 16.284155 -5.154889)
			(xy 16.281564 -5.241584) (xy 16.27121 -5.327698) (xy 16.253177 -5.412537) (xy 16.22761 -5.495418)
			(xy 16.194714 -5.575672) (xy 16.154755 -5.652653) (xy 16.108054 -5.725741) (xy 16.054988 -5.794348)
			(xy 15.995985 -5.85792) (xy 15.931519 -5.915946) (xy 15.897098 -5.94233) (xy 15.862132 -5.968006)
			(xy 15.788377 -6.013689) (xy 15.710822 -6.052572) (xy 15.630093 -6.084344) (xy 15.546839 -6.108746)
			(xy 15.461732 -6.125584) (xy 15.375458 -6.13472) (xy 15.288712 -6.136082) (xy 15.202194 -6.129659)
			(xy 15.116601 -6.115502) (xy 15.032622 -6.093724) (xy 14.950935 -6.064503) (xy 14.872197 -6.028073)
			(xy 14.797045 -5.984729) (xy 14.726083 -5.934818) (xy 14.659883 -5.878744) (xy 14.598979 -5.816959)
			(xy 14.543862 -5.749961) (xy 14.494977 -5.678289) (xy 14.452716 -5.602521) (xy 14.417421 -5.523269)
			(xy 14.389376 -5.44117) (xy 14.368808 -5.356887) (xy 14.355882 -5.271099) (xy 14.350702 -5.184498)
			(xy 13.611098 -5.184498) (xy 13.611098 -6.169914) (xy 78.515217 -6.169914) (xy 78.519222 -6.082006)
			(xy 78.531205 -5.994826) (xy 78.551065 -5.909097) (xy 78.57864 -5.825529) (xy 78.613699 -5.744815)
			(xy 78.655952 -5.667623) (xy 78.70505 -5.594594) (xy 78.760586 -5.526332) (xy 78.822098 -5.463402)
			(xy 78.889079 -5.406328) (xy 78.960972 -5.35558) (xy 79.037181 -5.31158) (xy 79.117076 -5.274693)
			(xy 79.199995 -5.245224) (xy 79.28525 -5.223417) (xy 79.372134 -5.209453) (xy 79.459928 -5.203447)
			(xy 79.547905 -5.205451) (xy 79.635335 -5.215446) (xy 79.721494 -5.23335) (xy 79.805668 -5.259014)
			(xy 79.887159 -5.292227) (xy 79.965293 -5.332713) (xy 80.039421 -5.380135) (xy 80.108929 -5.434102)
			(xy 80.173243 -5.494167) (xy 80.231827 -5.559831) (xy 80.284198 -5.63055) (xy 80.329921 -5.705738)
			(xy 80.368618 -5.784773) (xy 80.399967 -5.866999) (xy 80.423709 -5.951735) (xy 80.439647 -6.038279)
			(xy 80.447649 -6.125914) (xy 80.44815 -6.169914) (xy 80.447649 -6.213914) (xy 80.439647 -6.301549)
			(xy 80.423709 -6.388093) (xy 80.399967 -6.472829) (xy 80.368618 -6.555055) (xy 80.329921 -6.63409)
			(xy 80.284198 -6.709278) (xy 80.231827 -6.779997) (xy 80.173243 -6.845661) (xy 80.108929 -6.905726)
			(xy 80.039421 -6.959693) (xy 79.965293 -7.007115) (xy 79.887159 -7.047601) (xy 79.805668 -7.080814)
			(xy 79.721494 -7.106478) (xy 79.635335 -7.124382) (xy 79.547905 -7.134377) (xy 79.459928 -7.136381)
			(xy 79.372134 -7.130375) (xy 79.28525 -7.116411) (xy 79.199995 -7.094604) (xy 79.117076 -7.065135)
			(xy 79.037181 -7.028248) (xy 78.960972 -6.984248) (xy 78.889079 -6.9335) (xy 78.822098 -6.876426)
			(xy 78.760586 -6.813496) (xy 78.70505 -6.745234) (xy 78.655952 -6.672205) (xy 78.613699 -6.595013)
			(xy 78.57864 -6.514299) (xy 78.551065 -6.430731) (xy 78.531205 -6.345002) (xy 78.519222 -6.257822)
			(xy 78.515217 -6.169914) (xy 13.611098 -6.169914) (xy 13.611098 -6.751654) (xy 18.635651 -6.751654)
			(xy 18.635651 -6.697146) (xy 18.643409 -6.643192) (xy 18.658767 -6.590891) (xy 18.681411 -6.541309)
			(xy 18.710882 -6.495454) (xy 18.746579 -6.45426) (xy 18.787775 -6.418566) (xy 18.833632 -6.389099)
			(xy 18.883216 -6.366458) (xy 18.935517 -6.351104) (xy 18.989472 -6.34335) (xy 19.016726 -6.342888)
			(xy 19.880326 -6.342888) (xy 19.907576 -6.343384) (xy 19.96152 -6.351143) (xy 20.013811 -6.3665)
			(xy 20.063385 -6.389143) (xy 20.109231 -6.418609) (xy 20.150418 -6.4543) (xy 20.186106 -6.49549)
			(xy 20.21557 -6.541338) (xy 20.238209 -6.590913) (xy 20.253563 -6.643205) (xy 20.261318 -6.69715)
			(xy 20.261318 -6.75165) (xy 22.235674 -6.75165) (xy 22.235674 -6.69715) (xy 22.243429 -6.643204)
			(xy 22.258783 -6.590912) (xy 22.281422 -6.541336) (xy 22.310886 -6.495487) (xy 22.346574 -6.454297)
			(xy 22.387761 -6.418605) (xy 22.433608 -6.389138) (xy 22.483182 -6.366494) (xy 22.535473 -6.351136)
			(xy 22.589418 -6.343376) (xy 22.616668 -6.342888) (xy 23.480268 -6.342888) (xy 23.507522 -6.343357)
			(xy 23.561476 -6.35111) (xy 23.613777 -6.366463) (xy 23.663361 -6.389104) (xy 23.709217 -6.418571)
			(xy 23.750413 -6.454264) (xy 23.78611 -6.495457) (xy 23.815581 -6.541311) (xy 23.838225 -6.590893)
			(xy 23.853583 -6.643193) (xy 23.861341 -6.697146) (xy 23.861341 -6.751654) (xy 25.835551 -6.751654)
			(xy 25.835551 -6.697146) (xy 25.843309 -6.643194) (xy 25.858665 -6.590895) (xy 25.881309 -6.541314)
			(xy 25.910778 -6.495459) (xy 25.946473 -6.454266) (xy 25.987667 -6.418572) (xy 26.033522 -6.389104)
			(xy 26.083104 -6.366462) (xy 26.135404 -6.351107) (xy 26.189356 -6.343351) (xy 26.21661 -6.342888)
			(xy 27.08021 -6.342888) (xy 27.10746 -6.343382) (xy 27.161407 -6.35114) (xy 27.2137 -6.366496) (xy 27.263275 -6.389137)
			(xy 27.309124 -6.418604) (xy 27.350312 -6.454295) (xy 27.386002 -6.495484) (xy 27.415467 -6.541334)
			(xy 27.438108 -6.59091) (xy 27.453462 -6.643203) (xy 27.461218 -6.697149) (xy 27.461218 -6.751651)
			(xy 27.461218 -6.751653) (xy 29.435751 -6.751653) (xy 29.435751 -6.697147) (xy 29.443509 -6.643195)
			(xy 29.458865 -6.590896) (xy 29.481508 -6.541315) (xy 29.510977 -6.495461) (xy 29.546672 -6.454268)
			(xy 29.587866 -6.418574) (xy 29.63372 -6.389105) (xy 29.683301 -6.366463) (xy 29.7356 -6.351107)
			(xy 29.789553 -6.343351) (xy 29.816806 -6.342888) (xy 30.680406 -6.342888) (xy 30.707657 -6.343382)
			(xy 30.761603 -6.351139) (xy 30.813897 -6.366495) (xy 30.863473 -6.389136) (xy 30.909322 -6.418602)
			(xy 30.950511 -6.454293) (xy 30.986201 -6.495483) (xy 31.015667 -6.541333) (xy 31.038307 -6.590909)
			(xy 31.053662 -6.643203) (xy 31.061418 -6.697149) (xy 31.061418 -6.75165) (xy 38.545774 -6.75165)
			(xy 38.545774 -6.69715) (xy 38.55353 -6.643204) (xy 38.568883 -6.590911) (xy 38.591522 -6.541336)
			(xy 38.620986 -6.495486) (xy 38.656675 -6.454296) (xy 38.697862 -6.418604) (xy 38.743709 -6.389137)
			(xy 38.793283 -6.366494) (xy 38.845575 -6.351136) (xy 38.89952 -6.343376) (xy 38.92677 -6.342888)
			(xy 39.79037 -6.342888) (xy 39.817624 -6.343357) (xy 39.871578 -6.351111) (xy 39.923878 -6.366464)
			(xy 39.973462 -6.389105) (xy 40.019318 -6.418571) (xy 40.060514 -6.454265) (xy 40.096211 -6.495458)
			(xy 40.125681 -6.541312) (xy 40.148326 -6.590893) (xy 40.163683 -6.643193) (xy 40.171441 -6.697146)
			(xy 40.171441 -6.751654) (xy 42.145651 -6.751654) (xy 42.145651 -6.697146) (xy 42.153409 -6.643194)
			(xy 42.168766 -6.590894) (xy 42.191409 -6.541313) (xy 42.220879 -6.495459) (xy 42.256574 -6.454265)
			(xy 42.297768 -6.418571) (xy 42.343624 -6.389103) (xy 42.393206 -6.366461) (xy 42.445506 -6.351106)
			(xy 42.499458 -6.343351) (xy 42.526712 -6.342888) (xy 43.390312 -6.342888) (xy 43.417562 -6.343383)
			(xy 43.471508 -6.35114) (xy 43.523801 -6.366496) (xy 43.573376 -6.389138) (xy 43.619225 -6.418604)
			(xy 43.660413 -6.454295) (xy 43.696103 -6.495485) (xy 43.725568 -6.541334) (xy 43.748208 -6.59091)
			(xy 43.763562 -6.643203) (xy 43.771318 -6.69715) (xy 43.771318 -6.75165) (xy 43.771318 -6.751653)
			(xy 49.755751 -6.751653) (xy 49.755751 -6.697147) (xy 49.763509 -6.643195) (xy 49.778865 -6.590896)
			(xy 49.801508 -6.541315) (xy 49.830977 -6.495461) (xy 49.866672 -6.454268) (xy 49.907866 -6.418574)
			(xy 49.95372 -6.389105) (xy 50.003301 -6.366463) (xy 50.0556 -6.351107) (xy 50.109553 -6.343351)
			(xy 50.136806 -6.342888) (xy 51.000406 -6.342888) (xy 51.027657 -6.343382) (xy 51.081603 -6.351139)
			(xy 51.133897 -6.366495) (xy 51.183473 -6.389136) (xy 51.229322 -6.418602) (xy 51.270511 -6.454293)
			(xy 51.306201 -6.495483) (xy 51.335667 -6.541333) (xy 51.358307 -6.590909) (xy 51.373662 -6.643203)
			(xy 51.381418 -6.697149) (xy 51.381418 -6.751651) (xy 51.381417 -6.751655) (xy 53.355652 -6.751655)
			(xy 53.355652 -6.697145) (xy 53.36341 -6.643189) (xy 53.378768 -6.590887) (xy 53.401415 -6.541303)
			(xy 53.430887 -6.495447) (xy 53.466587 -6.454253) (xy 53.507785 -6.418559) (xy 53.553645 -6.389092)
			(xy 53.603232 -6.366452) (xy 53.655536 -6.3511) (xy 53.709493 -6.343348) (xy 53.736748 -6.342888)
			(xy 54.600348 -6.342888) (xy 54.627597 -6.343385) (xy 54.681539 -6.351147) (xy 54.733827 -6.366506)
			(xy 54.783398 -6.38915) (xy 54.829242 -6.418617) (xy 54.870426 -6.454308) (xy 54.906112 -6.495497)
			(xy 54.935573 -6.541344) (xy 54.958211 -6.590918) (xy 54.973563 -6.643208) (xy 54.981318 -6.697151)
			(xy 54.981318 -6.751649) (xy 54.981318 -6.751651) (xy 56.955674 -6.751651) (xy 56.955674 -6.697149)
			(xy 56.96343 -6.643201) (xy 56.978785 -6.590907) (xy 57.001426 -6.54133) (xy 57.030891 -6.49548)
			(xy 57.066582 -6.454289) (xy 57.107771 -6.418597) (xy 57.153621 -6.38913) (xy 57.203198 -6.366488)
			(xy 57.255492 -6.351132) (xy 57.309439 -6.343374) (xy 57.33669 -6.342888) (xy 58.20029 -6.342888)
			(xy 58.227543 -6.343359) (xy 58.281494 -6.351114) (xy 58.333793 -6.366469) (xy 58.383374 -6.389111)
			(xy 58.429228 -6.418578) (xy 58.470421 -6.454272) (xy 58.506116 -6.495464) (xy 58.535584 -6.541317)
			(xy 58.558227 -6.590898) (xy 58.573583 -6.643196) (xy 58.581341 -6.697147) (xy 58.581341 -6.751651)
			(xy 70.950574 -6.751651) (xy 70.950574 -6.697149) (xy 70.95833 -6.643203) (xy 70.973684 -6.590909)
			(xy 70.996324 -6.541332) (xy 71.025789 -6.495482) (xy 71.061479 -6.454292) (xy 71.102668 -6.4186)
			(xy 71.148516 -6.389133) (xy 71.198092 -6.366491) (xy 71.250385 -6.351134) (xy 71.304331 -6.343375)
			(xy 71.331582 -6.342888) (xy 72.195182 -6.342888) (xy 72.222435 -6.343358) (xy 72.276388 -6.351113)
			(xy 72.328687 -6.366467) (xy 72.378269 -6.389108) (xy 72.424124 -6.418576) (xy 72.465318 -6.454269)
			(xy 72.501014 -6.495462) (xy 72.530483 -6.541315) (xy 72.553126 -6.590896) (xy 72.568483 -6.643195)
			(xy 72.576241 -6.697147) (xy 72.576241 -6.751653) (xy 72.568483 -6.805605) (xy 72.553126 -6.857904)
			(xy 72.530483 -6.907485) (xy 72.501014 -6.953338) (xy 72.465318 -6.994531) (xy 72.424124 -7.030224)
			(xy 72.378269 -7.059692) (xy 72.328687 -7.082333) (xy 72.276388 -7.097687) (xy 72.222435 -7.105442)
			(xy 72.195182 -7.105904) (xy 71.331582 -7.105904) (xy 71.304331 -7.105425) (xy 71.250385 -7.097666)
			(xy 71.198092 -7.082309) (xy 71.148516 -7.059667) (xy 71.102668 -7.0302) (xy 71.061479 -6.994508)
			(xy 71.025789 -6.953318) (xy 70.996324 -6.907468) (xy 70.973684 -6.857891) (xy 70.95833 -6.805597)
			(xy 70.950574 -6.751651) (xy 58.581341 -6.751651) (xy 58.581341 -6.751653) (xy 58.573583 -6.805604)
			(xy 58.558227 -6.857902) (xy 58.535584 -6.907483) (xy 58.506116 -6.953336) (xy 58.470421 -6.994528)
			(xy 58.429228 -7.030222) (xy 58.383374 -7.059689) (xy 58.333793 -7.082331) (xy 58.281494 -7.097686)
			(xy 58.227543 -7.105441) (xy 58.20029 -7.105904) (xy 57.33669 -7.105904) (xy 57.309439 -7.105426)
			(xy 57.255492 -7.097668) (xy 57.203198 -7.082312) (xy 57.153621 -7.05967) (xy 57.107771 -7.030203)
			(xy 57.066582 -6.994511) (xy 57.030891 -6.95332) (xy 57.001426 -6.90747) (xy 56.978785 -6.857893)
			(xy 56.96343 -6.805599) (xy 56.955674 -6.751651) (xy 54.981318 -6.751651) (xy 54.973563 -6.805592)
			(xy 54.958211 -6.857882) (xy 54.935573 -6.907456) (xy 54.906112 -6.953303) (xy 54.870426 -6.994492)
			(xy 54.829242 -7.030183) (xy 54.783398 -7.05965) (xy 54.733827 -7.082294) (xy 54.681539 -7.097653)
			(xy 54.627597 -7.105415) (xy 54.600348 -7.105904) (xy 53.736748 -7.105904) (xy 53.709493 -7.105452)
			(xy 53.655536 -7.0977) (xy 53.603232 -7.082348) (xy 53.553645 -7.059708) (xy 53.507785 -7.030241)
			(xy 53.466587 -6.994547) (xy 53.430887 -6.953353) (xy 53.401415 -6.907497) (xy 53.378768 -6.857913)
			(xy 53.36341 -6.805611) (xy 53.355652 -6.751655) (xy 51.381417 -6.751655) (xy 51.373662 -6.805597)
			(xy 51.358307 -6.857891) (xy 51.335667 -6.907467) (xy 51.306201 -6.953317) (xy 51.270511 -6.994507)
			(xy 51.229322 -7.030198) (xy 51.183473 -7.059664) (xy 51.133897 -7.082305) (xy 51.081603 -7.097661)
			(xy 51.027657 -7.105418) (xy 51.000406 -7.105904) (xy 50.136806 -7.105904) (xy 50.109553 -7.105449)
			(xy 50.0556 -7.097693) (xy 50.003301 -7.082337) (xy 49.95372 -7.059695) (xy 49.907866 -7.030226)
			(xy 49.866672 -6.994532) (xy 49.830977 -6.953339) (xy 49.801508 -6.907485) (xy 49.778865 -6.857904)
			(xy 49.763509 -6.805605) (xy 49.755751 -6.751653) (xy 43.771318 -6.751653) (xy 43.763562 -6.805597)
			(xy 43.748208 -6.85789) (xy 43.725568 -6.907466) (xy 43.696103 -6.953315) (xy 43.660413 -6.994505)
			(xy 43.619225 -7.030196) (xy 43.573376 -7.059662) (xy 43.523801 -7.082304) (xy 43.471508 -7.09766)
			(xy 43.417562 -7.105417) (xy 43.390312 -7.105904) (xy 42.526712 -7.105904) (xy 42.499458 -7.105449)
			(xy 42.445506 -7.097694) (xy 42.393206 -7.082339) (xy 42.343624 -7.059697) (xy 42.297768 -7.030229)
			(xy 42.256574 -6.994535) (xy 42.220879 -6.953341) (xy 42.191409 -6.907487) (xy 42.168766 -6.857906)
			(xy 42.153409 -6.805606) (xy 42.145651 -6.751654) (xy 40.171441 -6.751654) (xy 40.163683 -6.805607)
			(xy 40.148326 -6.857907) (xy 40.125681 -6.907488) (xy 40.096211 -6.953342) (xy 40.060514 -6.994535)
			(xy 40.019318 -7.030229) (xy 39.973462 -7.059695) (xy 39.923878 -7.082336) (xy 39.871578 -7.097689)
			(xy 39.817624 -7.105443) (xy 39.79037 -7.105904) (xy 38.92677 -7.105904) (xy 38.89952 -7.105424)
			(xy 38.845575 -7.097664) (xy 38.793283 -7.082306) (xy 38.743709 -7.059663) (xy 38.697862 -7.030196)
			(xy 38.656675 -6.994504) (xy 38.620986 -6.953314) (xy 38.591522 -6.907464) (xy 38.568883 -6.857889)
			(xy 38.55353 -6.805596) (xy 38.545774 -6.75165) (xy 31.061418 -6.75165) (xy 31.061418 -6.751651)
			(xy 31.053662 -6.805597) (xy 31.038307 -6.857891) (xy 31.015667 -6.907467) (xy 30.986201 -6.953317)
			(xy 30.950511 -6.994507) (xy 30.909322 -7.030198) (xy 30.863473 -7.059664) (xy 30.813897 -7.082305)
			(xy 30.761603 -7.097661) (xy 30.707657 -7.105418) (xy 30.680406 -7.105904) (xy 29.816806 -7.105904)
			(xy 29.789553 -7.105449) (xy 29.7356 -7.097693) (xy 29.683301 -7.082337) (xy 29.63372 -7.059695)
			(xy 29.587866 -7.030226) (xy 29.546672 -6.994532) (xy 29.510977 -6.953339) (xy 29.481508 -6.907485)
			(xy 29.458865 -6.857904) (xy 29.443509 -6.805605) (xy 29.435751 -6.751653) (xy 27.461218 -6.751653)
			(xy 27.453462 -6.805597) (xy 27.438108 -6.85789) (xy 27.415467 -6.907466) (xy 27.386002 -6.953316)
			(xy 27.350312 -6.994505) (xy 27.309124 -7.030196) (xy 27.263275 -7.059663) (xy 27.2137 -7.082304)
			(xy 27.161407 -7.09766) (xy 27.10746 -7.105418) (xy 27.08021 -7.105904) (xy 26.21661 -7.105904) (xy 26.189356 -7.105449)
			(xy 26.135404 -7.097693) (xy 26.083104 -7.082338) (xy 26.033522 -7.059696) (xy 25.987667 -7.030228)
			(xy 25.946473 -6.994534) (xy 25.910778 -6.953341) (xy 25.881309 -6.907486) (xy 25.858665 -6.857905)
			(xy 25.843309 -6.805606) (xy 25.835551 -6.751654) (xy 23.861341 -6.751654) (xy 23.853583 -6.805607)
			(xy 23.838225 -6.857907) (xy 23.815581 -6.907489) (xy 23.78611 -6.953343) (xy 23.750413 -6.994536)
			(xy 23.709217 -7.030229) (xy 23.663361 -7.059696) (xy 23.613777 -7.082337) (xy 23.561476 -7.09769)
			(xy 23.507522 -7.105443) (xy 23.480268 -7.105904) (xy 22.616668 -7.105904) (xy 22.589418 -7.105424)
			(xy 22.535473 -7.097664) (xy 22.483182 -7.082306) (xy 22.433608 -7.059662) (xy 22.387761 -7.030195)
			(xy 22.346574 -6.994503) (xy 22.310886 -6.953313) (xy 22.281422 -6.907464) (xy 22.258783 -6.857888)
			(xy 22.243429 -6.805596) (xy 22.235674 -6.75165) (xy 20.261318 -6.75165) (xy 20.253563 -6.805595)
			(xy 20.238209 -6.857887) (xy 20.21557 -6.907462) (xy 20.186106 -6.95331) (xy 20.150418 -6.9945) (xy 20.109231 -7.030191)
			(xy 20.063385 -7.059657) (xy 20.013811 -7.0823) (xy 19.96152 -7.097657) (xy 19.907576 -7.105416)
			(xy 19.880326 -7.105904) (xy 19.016726 -7.105904) (xy 18.989472 -7.10545) (xy 18.935517 -7.097696)
			(xy 18.883216 -7.082342) (xy 18.833632 -7.059701) (xy 18.787775 -7.030234) (xy 18.746579 -6.99454)
			(xy 18.710882 -6.953346) (xy 18.681411 -6.907491) (xy 18.658767 -6.857909) (xy 18.643409 -6.805608)
			(xy 18.635651 -6.751654) (xy 13.611098 -6.751654) (xy 13.611098 -9.780016) (xy 13.610604 -9.850398)
			(xy 13.602711 -9.990941) (xy 13.58695 -10.13082) (xy 13.563371 -10.269596) (xy 13.532048 -10.406831)
			(xy 13.493079 -10.542094) (xy 13.446587 -10.674959) (xy 13.392719 -10.805008) (xy 13.331643 -10.931832)
			(xy 13.263553 -11.055033) (xy 13.188662 -11.174221) (xy 13.107205 -11.289023) (xy 13.01944 -11.399077)
			(xy 12.925642 -11.504037) (xy 12.826107 -11.603572) (xy 12.721147 -11.69737) (xy 12.611093 -11.785135)
			(xy 12.496291 -11.866592) (xy 12.377103 -11.941483) (xy 12.253902 -12.009573) (xy 12.127078 -12.070649)
			(xy 11.997029 -12.124517) (xy 11.864164 -12.171009) (xy 11.728901 -12.209978) (xy 11.591666 -12.241301)
			(xy 11.45289 -12.26488) (xy 11.313011 -12.280641) (xy 11.172468 -12.288534) (xy 11.102086 -12.289028)
			(xy 1.999996 -12.289028) (xy 1.944227 -12.289537) (xy 1.833 -12.297872) (xy 1.722707 -12.314497)
			(xy 1.613965 -12.339317) (xy 1.507382 -12.372193) (xy 1.403554 -12.412943) (xy 1.303061 -12.461339)
			(xy 1.206466 -12.517108) (xy 1.114309 -12.579941) (xy 1.027105 -12.649484) (xy 0.945341 -12.72535)
			(xy 0.869476 -12.807114) (xy 0.802299 -12.891351) (xy 56.954662 -12.891351) (xy 56.954662 -12.836849)
			(xy 56.962418 -12.782901) (xy 56.977772 -12.730606) (xy 57.000413 -12.681029) (xy 57.029878 -12.635178)
			(xy 57.065568 -12.593986) (xy 57.106757 -12.558293) (xy 57.152606 -12.528825) (xy 57.202182 -12.506181)
			(xy 57.254476 -12.490823) (xy 57.308423 -12.483064) (xy 57.335674 -12.482576) (xy 58.199274 -12.482576)
			(xy 58.226527 -12.48307) (xy 58.280478 -12.490823) (xy 58.332777 -12.506176) (xy 58.382358 -12.528816)
			(xy 58.428213 -12.558282) (xy 58.469407 -12.593975) (xy 58.505102 -12.635166) (xy 58.534571 -12.681019)
			(xy 58.557215 -12.730598) (xy 58.572571 -12.782896) (xy 58.580329 -12.836847) (xy 58.580329 -12.891353)
			(xy 58.580329 -12.891355) (xy 70.949739 -12.891355) (xy 70.949739 -12.836845) (xy 70.957497 -12.78289)
			(xy 70.972854 -12.730588) (xy 70.995499 -12.681005) (xy 71.024971 -12.635149) (xy 71.060668 -12.593954)
			(xy 71.101865 -12.558259) (xy 71.147722 -12.52879) (xy 71.197307 -12.506147) (xy 71.24961 -12.490793)
			(xy 71.303565 -12.483038) (xy 71.33082 -12.482576) (xy 72.19442 -12.482576) (xy 72.221669 -12.483096)
			(xy 72.275612 -12.490854) (xy 72.327902 -12.50621) (xy 72.377475 -12.528852) (xy 72.423321 -12.558317)
			(xy 72.464507 -12.594007) (xy 72.500195 -12.635195) (xy 72.529658 -12.681043) (xy 72.552297 -12.730616)
			(xy 72.56765 -12.782907) (xy 72.575406 -12.836851) (xy 72.575406 -12.891349) (xy 72.56765 -12.945293)
			(xy 72.552297 -12.997584) (xy 72.529658 -13.047157) (xy 72.500195 -13.093005) (xy 72.464507 -13.134193)
			(xy 72.423321 -13.169883) (xy 72.377475 -13.199348) (xy 72.327902 -13.22199) (xy 72.275612 -13.237346)
			(xy 72.221669 -13.245104) (xy 72.19442 -13.245592) (xy 71.33082 -13.245592) (xy 71.303565 -13.245162)
			(xy 71.24961 -13.237407) (xy 71.197307 -13.222053) (xy 71.147722 -13.19941) (xy 71.101865 -13.169941)
			(xy 71.060668 -13.134246) (xy 71.024971 -13.093051) (xy 70.995499 -13.047195) (xy 70.972854 -12.997612)
			(xy 70.957497 -12.94531) (xy 70.949739 -12.891355) (xy 58.580329 -12.891355) (xy 58.572571 -12.945304)
			(xy 58.557215 -12.997602) (xy 58.534571 -13.047181) (xy 58.505102 -13.093034) (xy 58.469407 -13.134225)
			(xy 58.428213 -13.169918) (xy 58.382358 -13.199384) (xy 58.332777 -13.222024) (xy 58.280478 -13.237377)
			(xy 58.226527 -13.24513) (xy 58.199274 -13.245592) (xy 57.335674 -13.245592) (xy 57.308423 -13.245136)
			(xy 57.254476 -13.237377) (xy 57.202182 -13.222019) (xy 57.152606 -13.199375) (xy 57.106757 -13.169907)
			(xy 57.065568 -13.134214) (xy 57.029878 -13.093022) (xy 57.000413 -13.047171) (xy 56.977772 -12.997594)
			(xy 56.962418 -12.945299) (xy 56.954662 -12.891351) (xy 0.802299 -12.891351) (xy 0.799933 -12.894318)
			(xy 0.737102 -12.986476) (xy 0.681333 -13.083072) (xy 0.632939 -13.183565) (xy 0.59219 -13.287393)
			(xy 0.559313 -13.393977) (xy 0.534494 -13.502719) (xy 0.517871 -13.613012) (xy 0.509536 -13.724239)
			(xy 0.509016 -13.780008) (xy 0.509016 -15.222054) (xy 135.233343 -15.222054) (xy 135.233343 -15.167546)
			(xy 135.2411 -15.113592) (xy 135.256457 -15.061292) (xy 135.279101 -15.011709) (xy 135.308571 -14.965854)
			(xy 135.344267 -14.92466) (xy 135.385462 -14.888965) (xy 135.431318 -14.859497) (xy 135.480901 -14.836854)
			(xy 135.533202 -14.821498) (xy 135.587156 -14.813742) (xy 135.61441 -14.81328) (xy 136.47801 -14.81328)
			(xy 136.50526 -14.813791) (xy 136.559205 -14.821548) (xy 136.611497 -14.836904) (xy 136.661071 -14.859545)
			(xy 136.706919 -14.88901) (xy 136.748106 -14.924701) (xy 136.783796 -14.965889) (xy 136.81326 -15.011738)
			(xy 136.8359 -15.061313) (xy 136.851254 -15.113605) (xy 136.85901 -15.16755) (xy 136.85901 -15.22205)
			(xy 136.851254 -15.275995) (xy 136.8359 -15.328287) (xy 136.81326 -15.377862) (xy 136.783796 -15.423711)
			(xy 136.748106 -15.464899) (xy 136.706919 -15.50059) (xy 136.661071 -15.530055) (xy 136.611497 -15.552696)
			(xy 136.559205 -15.568052) (xy 136.50526 -15.575809) (xy 136.47801 -15.576296) (xy 135.61441 -15.576296)
			(xy 135.587156 -15.575858) (xy 135.533202 -15.568102) (xy 135.480901 -15.552746) (xy 135.431318 -15.530103)
			(xy 135.385462 -15.500635) (xy 135.344267 -15.46494) (xy 135.308571 -15.423746) (xy 135.279101 -15.377891)
			(xy 135.256457 -15.328308) (xy 135.2411 -15.276008) (xy 135.233343 -15.222054) (xy 0.509016 -15.222054)
			(xy 0.509016 -17.639611) (xy 15.152858 -17.639611) (xy 15.152858 -17.585109) (xy 15.160614 -17.531161)
			(xy 15.175969 -17.478867) (xy 15.19861 -17.42929) (xy 15.228076 -17.383439) (xy 15.263768 -17.342249)
			(xy 15.304958 -17.306558) (xy 15.350808 -17.277091) (xy 15.400385 -17.25445) (xy 15.452679 -17.239095)
			(xy 15.506627 -17.231338) (xy 15.533878 -17.230852) (xy 16.397478 -17.230852) (xy 16.424731 -17.231315)
			(xy 16.478682 -17.239072) (xy 16.53098 -17.254428) (xy 16.580561 -17.27707) (xy 16.626414 -17.306538)
			(xy 16.667607 -17.342232) (xy 16.703301 -17.383424) (xy 16.732769 -17.429278) (xy 16.755412 -17.478858)
			(xy 16.770768 -17.531156) (xy 16.778525 -17.585107) (xy 16.778525 -17.639611) (xy 20.740858 -17.639611)
			(xy 20.740858 -17.585109) (xy 20.748614 -17.531161) (xy 20.763969 -17.478867) (xy 20.78661 -17.42929)
			(xy 20.816076 -17.383439) (xy 20.851768 -17.342249) (xy 20.892958 -17.306558) (xy 20.938808 -17.277091)
			(xy 20.988385 -17.25445) (xy 21.040679 -17.239095) (xy 21.094627 -17.231338) (xy 21.121878 -17.230852)
			(xy 21.985478 -17.230852) (xy 22.012729 -17.231394) (xy 22.066677 -17.239147) (xy 22.118972 -17.2545)
			(xy 22.168549 -17.277139) (xy 22.2144 -17.306603) (xy 22.255591 -17.342293) (xy 22.291284 -17.383482)
			(xy 22.320751 -17.429331) (xy 22.343392 -17.478908) (xy 22.358748 -17.531202) (xy 22.366505 -17.585149)
			(xy 22.366505 -17.639651) (xy 22.366505 -17.639653) (xy 26.328838 -17.639653) (xy 26.328838 -17.585147)
			(xy 26.336595 -17.531195) (xy 26.35195 -17.478897) (xy 26.374592 -17.429316) (xy 26.404059 -17.383462)
			(xy 26.439752 -17.342268) (xy 26.480944 -17.306573) (xy 26.526797 -17.277103) (xy 26.576376 -17.254458)
			(xy 26.628674 -17.239099) (xy 26.682625 -17.231339) (xy 26.709878 -17.230852) (xy 27.573478 -17.230852)
			(xy 27.600729 -17.231394) (xy 27.654677 -17.239147) (xy 27.706972 -17.2545) (xy 27.756549 -17.277139)
			(xy 27.8024 -17.306603) (xy 27.843591 -17.342293) (xy 27.879284 -17.383482) (xy 27.908751 -17.429331)
			(xy 27.931392 -17.478908) (xy 27.946748 -17.531202) (xy 27.954505 -17.585149) (xy 27.954505 -17.639651)
			(xy 27.954505 -17.639653) (xy 31.916838 -17.639653) (xy 31.916838 -17.585147) (xy 31.924595 -17.531195)
			(xy 31.93995 -17.478897) (xy 31.962592 -17.429316) (xy 31.992059 -17.383462) (xy 32.027752 -17.342268)
			(xy 32.068944 -17.306573) (xy 32.114797 -17.277103) (xy 32.164376 -17.254458) (xy 32.216674 -17.239099)
			(xy 32.270625 -17.231339) (xy 32.297878 -17.230852) (xy 33.161478 -17.230852) (xy 33.188729 -17.231394)
			(xy 33.242677 -17.239147) (xy 33.294972 -17.2545) (xy 33.344549 -17.277139) (xy 33.3904 -17.306603)
			(xy 33.431591 -17.342293) (xy 33.467284 -17.383482) (xy 33.496751 -17.429331) (xy 33.519392 -17.478908)
			(xy 33.534748 -17.531202) (xy 33.542505 -17.585149) (xy 33.542505 -17.639651) (xy 33.542505 -17.639653)
			(xy 37.504838 -17.639653) (xy 37.504838 -17.585147) (xy 37.512595 -17.531195) (xy 37.52795 -17.478897)
			(xy 37.550592 -17.429316) (xy 37.580059 -17.383462) (xy 37.615752 -17.342268) (xy 37.656944 -17.306573)
			(xy 37.702797 -17.277103) (xy 37.752376 -17.254458) (xy 37.804674 -17.239099) (xy 37.858625 -17.231339)
			(xy 37.885878 -17.230852) (xy 38.749478 -17.230852) (xy 38.776729 -17.231394) (xy 38.830677 -17.239147)
			(xy 38.882972 -17.2545) (xy 38.932549 -17.277139) (xy 38.9784 -17.306603) (xy 39.019591 -17.342293)
			(xy 39.055284 -17.383482) (xy 39.084751 -17.429331) (xy 39.107392 -17.478908) (xy 39.122748 -17.531202)
			(xy 39.130505 -17.585149) (xy 39.130505 -17.639651) (xy 39.130505 -17.639654) (xy 43.398638 -17.639654)
			(xy 43.398638 -17.585146) (xy 43.406395 -17.531193) (xy 43.421751 -17.478894) (xy 43.444395 -17.429312)
			(xy 43.473863 -17.383457) (xy 43.509558 -17.342262) (xy 43.550752 -17.306567) (xy 43.596606 -17.277097)
			(xy 43.646188 -17.254454) (xy 43.698487 -17.239096) (xy 43.75244 -17.231338) (xy 43.779694 -17.230852)
			(xy 44.643294 -17.230852) (xy 44.670544 -17.231395) (xy 44.72449 -17.23915) (xy 44.776783 -17.254504)
			(xy 44.826359 -17.277144) (xy 44.872208 -17.306609) (xy 44.913397 -17.342299) (xy 44.949088 -17.383487)
			(xy 44.978553 -17.429336) (xy 45.001194 -17.478911) (xy 45.016548 -17.531204) (xy 45.024305 -17.58515)
			(xy 45.024305 -17.63965) (xy 45.024304 -17.639654) (xy 48.986638 -17.639654) (xy 48.986638 -17.585146)
			(xy 48.994395 -17.531193) (xy 49.009751 -17.478894) (xy 49.032395 -17.429312) (xy 49.061863 -17.383457)
			(xy 49.097558 -17.342262) (xy 49.138752 -17.306567) (xy 49.184606 -17.277097) (xy 49.234188 -17.254454)
			(xy 49.286487 -17.239096) (xy 49.34044 -17.231338) (xy 49.367694 -17.230852) (xy 50.231294 -17.230852)
			(xy 50.258544 -17.231395) (xy 50.31249 -17.23915) (xy 50.364783 -17.254504) (xy 50.414359 -17.277144)
			(xy 50.460208 -17.306609) (xy 50.501397 -17.342299) (xy 50.537088 -17.383487) (xy 50.566553 -17.429336)
			(xy 50.589194 -17.478911) (xy 50.604548 -17.531204) (xy 50.612305 -17.58515) (xy 50.612305 -17.63965)
			(xy 50.612304 -17.639657) (xy 54.608615 -17.639657) (xy 54.608615 -17.585143) (xy 54.616374 -17.531184)
			(xy 54.631733 -17.478878) (xy 54.65438 -17.42929) (xy 54.683854 -17.383431) (xy 54.719554 -17.342233)
			(xy 54.760755 -17.306536) (xy 54.806617 -17.277065) (xy 54.856206 -17.254422) (xy 54.908513 -17.239067)
			(xy 54.962473 -17.231313) (xy 54.98973 -17.230852) (xy 55.85333 -17.230852) (xy 55.880577 -17.23142)
			(xy 55.934516 -17.239179) (xy 55.986801 -17.254535) (xy 56.03637 -17.277176) (xy 56.082211 -17.30664)
			(xy 56.123394 -17.342328) (xy 56.159078 -17.383513) (xy 56.188538 -17.429357) (xy 56.211175 -17.478927)
			(xy 56.226527 -17.531214) (xy 56.234282 -17.585153) (xy 56.234282 -17.639647) (xy 56.226527 -17.693586)
			(xy 56.211175 -17.745873) (xy 56.188538 -17.795443) (xy 56.159078 -17.841287) (xy 56.123394 -17.882472)
			(xy 56.082211 -17.91816) (xy 56.03637 -17.947624) (xy 55.986801 -17.970265) (xy 55.934516 -17.985621)
			(xy 55.880577 -17.99338) (xy 55.85333 -17.993868) (xy 54.98973 -17.993868) (xy 54.962473 -17.993487)
			(xy 54.908513 -17.985733) (xy 54.856206 -17.970378) (xy 54.806617 -17.947735) (xy 54.760755 -17.918264)
			(xy 54.719554 -17.882567) (xy 54.683854 -17.841369) (xy 54.65438 -17.79551) (xy 54.631733 -17.745922)
			(xy 54.616374 -17.693616) (xy 54.608615 -17.639657) (xy 50.612304 -17.639657) (xy 50.604548 -17.693596)
			(xy 50.589194 -17.745889) (xy 50.566553 -17.795464) (xy 50.537088 -17.841313) (xy 50.501397 -17.882501)
			(xy 50.460208 -17.918191) (xy 50.414359 -17.947656) (xy 50.364783 -17.970296) (xy 50.31249 -17.98565)
			(xy 50.258544 -17.993405) (xy 50.231294 -17.993868) (xy 49.367694 -17.993868) (xy 49.34044 -17.993462)
			(xy 49.286487 -17.985704) (xy 49.234188 -17.970346) (xy 49.184606 -17.947703) (xy 49.138752 -17.918233)
			(xy 49.097558 -17.882538) (xy 49.061863 -17.841343) (xy 49.032395 -17.795488) (xy 49.009751 -17.745906)
			(xy 48.994395 -17.693607) (xy 48.986638 -17.639654) (xy 45.024304 -17.639654) (xy 45.016548 -17.693596)
			(xy 45.001194 -17.745889) (xy 44.978553 -17.795464) (xy 44.949088 -17.841313) (xy 44.913397 -17.882501)
			(xy 44.872208 -17.918191) (xy 44.826359 -17.947656) (xy 44.776783 -17.970296) (xy 44.72449 -17.98565)
			(xy 44.670544 -17.993405) (xy 44.643294 -17.993868) (xy 43.779694 -17.993868) (xy 43.75244 -17.993462)
			(xy 43.698487 -17.985704) (xy 43.646188 -17.970346) (xy 43.596606 -17.947703) (xy 43.550752 -17.918233)
			(xy 43.509558 -17.882538) (xy 43.473863 -17.841343) (xy 43.444395 -17.795488) (xy 43.421751 -17.745906)
			(xy 43.406395 -17.693607) (xy 43.398638 -17.639654) (xy 39.130505 -17.639654) (xy 39.122748 -17.693598)
			(xy 39.107392 -17.745892) (xy 39.084751 -17.795469) (xy 39.055284 -17.841318) (xy 39.019591 -17.882507)
			(xy 38.9784 -17.918197) (xy 38.932549 -17.947661) (xy 38.882972 -17.9703) (xy 38.830677 -17.985653)
			(xy 38.776729 -17.993406) (xy 38.749478 -17.993868) (xy 37.885878 -17.993868) (xy 37.858625 -17.993461)
			(xy 37.804674 -17.985701) (xy 37.752376 -17.970342) (xy 37.702797 -17.947697) (xy 37.656944 -17.918227)
			(xy 37.615752 -17.882532) (xy 37.580059 -17.841338) (xy 37.550592 -17.795484) (xy 37.52795 -17.745903)
			(xy 37.512595 -17.693605) (xy 37.504838 -17.639653) (xy 33.542505 -17.639653) (xy 33.534748 -17.693598)
			(xy 33.519392 -17.745892) (xy 33.496751 -17.795469) (xy 33.467284 -17.841318) (xy 33.431591 -17.882507)
			(xy 33.3904 -17.918197) (xy 33.344549 -17.947661) (xy 33.294972 -17.9703) (xy 33.242677 -17.985653)
			(xy 33.188729 -17.993406) (xy 33.161478 -17.993868) (xy 32.297878 -17.993868) (xy 32.270625 -17.993461)
			(xy 32.216674 -17.985701) (xy 32.164376 -17.970342) (xy 32.114797 -17.947697) (xy 32.068944 -17.918227)
			(xy 32.027752 -17.882532) (xy 31.992059 -17.841338) (xy 31.962592 -17.795484) (xy 31.93995 -17.745903)
			(xy 31.924595 -17.693605) (xy 31.916838 -17.639653) (xy 27.954505 -17.639653) (xy 27.946748 -17.693598)
			(xy 27.931392 -17.745892) (xy 27.908751 -17.795469) (xy 27.879284 -17.841318) (xy 27.843591 -17.882507)
			(xy 27.8024 -17.918197) (xy 27.756549 -17.947661) (xy 27.706972 -17.9703) (xy 27.654677 -17.985653)
			(xy 27.600729 -17.993406) (xy 27.573478 -17.993868) (xy 26.709878 -17.993868) (xy 26.682625 -17.993461)
			(xy 26.628674 -17.985701) (xy 26.576376 -17.970342) (xy 26.526797 -17.947697) (xy 26.480944 -17.918227)
			(xy 26.439752 -17.882532) (xy 26.404059 -17.841338) (xy 26.374592 -17.795484) (xy 26.35195 -17.745903)
			(xy 26.336595 -17.693605) (xy 26.328838 -17.639653) (xy 22.366505 -17.639653) (xy 22.358748 -17.693598)
			(xy 22.343392 -17.745892) (xy 22.320751 -17.795469) (xy 22.291284 -17.841318) (xy 22.255591 -17.882507)
			(xy 22.2144 -17.918197) (xy 22.168549 -17.947661) (xy 22.118972 -17.9703) (xy 22.066677 -17.985653)
			(xy 22.012729 -17.993406) (xy 21.985478 -17.993868) (xy 21.121878 -17.993868) (xy 21.094627 -17.993382)
			(xy 21.040679 -17.985625) (xy 20.988385 -17.97027) (xy 20.938808 -17.947629) (xy 20.892958 -17.918162)
			(xy 20.851768 -17.882471) (xy 20.816076 -17.841281) (xy 20.78661 -17.79543) (xy 20.763969 -17.745853)
			(xy 20.748614 -17.693559) (xy 20.740858 -17.639611) (xy 16.778525 -17.639611) (xy 16.778525 -17.639613)
			(xy 16.770768 -17.693564) (xy 16.755412 -17.745862) (xy 16.732769 -17.795442) (xy 16.703301 -17.841296)
			(xy 16.667607 -17.882488) (xy 16.626414 -17.918182) (xy 16.580561 -17.94765) (xy 16.53098 -17.970292)
			(xy 16.478682 -17.985648) (xy 16.424731 -17.993405) (xy 16.397478 -17.993868) (xy 15.533878 -17.993868)
			(xy 15.506627 -17.993382) (xy 15.452679 -17.985625) (xy 15.400385 -17.97027) (xy 15.350808 -17.947629)
			(xy 15.304958 -17.918162) (xy 15.263768 -17.882471) (xy 15.228076 -17.841281) (xy 15.19861 -17.79543)
			(xy 15.175969 -17.745853) (xy 15.160614 -17.693559) (xy 15.152858 -17.639611) (xy 0.509016 -17.639611)
			(xy 0.509016 -18.171947) (xy 131.633522 -18.171947) (xy 131.633522 -18.117453) (xy 131.641277 -18.063515)
			(xy 131.656629 -18.011229) (xy 131.679265 -17.961659) (xy 131.708725 -17.915816) (xy 131.744409 -17.874631)
			(xy 131.78559 -17.838944) (xy 131.831431 -17.80948) (xy 131.880999 -17.78684) (xy 131.933283 -17.771484)
			(xy 131.987221 -17.763724) (xy 132.014468 -17.763236) (xy 132.878068 -17.763236) (xy 132.905326 -17.763609)
			(xy 132.959286 -17.771363) (xy 133.011594 -17.786718) (xy 133.061184 -17.809361) (xy 133.107046 -17.838832)
			(xy 133.148248 -17.87453) (xy 133.183949 -17.915728) (xy 133.213423 -17.961588) (xy 133.236071 -18.011176)
			(xy 133.25143 -18.063483) (xy 133.259189 -18.117443) (xy 133.259189 -18.17195) (xy 137.033499 -18.17195)
			(xy 137.033499 -18.11745) (xy 137.041256 -18.063505) (xy 137.05661 -18.011212) (xy 137.079251 -17.961637)
			(xy 137.108716 -17.915789) (xy 137.144406 -17.874601) (xy 137.185595 -17.838911) (xy 137.231444 -17.809447)
			(xy 137.28102 -17.786807) (xy 137.333312 -17.771454) (xy 137.387258 -17.763699) (xy 137.414508 -17.763236)
			(xy 138.278108 -17.763236) (xy 138.305362 -17.763634) (xy 138.359315 -17.771393) (xy 138.411615 -17.78675)
			(xy 138.461197 -17.809395) (xy 138.507052 -17.838864) (xy 138.548246 -17.87456) (xy 138.58394 -17.915755)
			(xy 138.613409 -17.96161) (xy 138.636052 -18.011193) (xy 138.651409 -18.063493) (xy 138.659166 -18.117446)
			(xy 138.659166 -18.171946) (xy 140.633522 -18.171946) (xy 140.633522 -18.117454) (xy 140.641276 -18.063517)
			(xy 140.656627 -18.011232) (xy 140.679262 -17.961664) (xy 140.70872 -17.915822) (xy 140.744402 -17.874638)
			(xy 140.785582 -17.83895) (xy 140.83142 -17.809486) (xy 140.880986 -17.786845) (xy 140.933268 -17.771487)
			(xy 140.987204 -17.763726) (xy 141.01445 -17.763236) (xy 141.87805 -17.763236) (xy 141.905308 -17.763608)
			(xy 141.959271 -17.77136) (xy 142.011581 -17.786713) (xy 142.061173 -17.809355) (xy 142.107038 -17.838825)
			(xy 142.148241 -17.874523) (xy 142.183945 -17.915722) (xy 142.213421 -17.961583) (xy 142.236069 -18.011172)
			(xy 142.25143 -18.06348) (xy 142.259189 -18.117442) (xy 142.259189 -18.171951) (xy 185.748399 -18.171951)
			(xy 185.748399 -18.117449) (xy 185.756156 -18.063503) (xy 185.771511 -18.011209) (xy 185.794153 -17.961633)
			(xy 185.823619 -17.915784) (xy 185.859311 -17.874596) (xy 185.900502 -17.838906) (xy 185.946353 -17.809442)
			(xy 185.99593 -17.786804) (xy 186.048224 -17.771451) (xy 186.102171 -17.763698) (xy 186.129422 -17.763236)
			(xy 186.993022 -17.763236) (xy 187.020275 -17.763635) (xy 187.074227 -17.771395) (xy 187.126525 -17.786754)
			(xy 187.176105 -17.809399) (xy 187.201242 -17.825555) (xy 218.803143 -17.825555) (xy 218.803143 -17.771045)
			(xy 218.810901 -17.717091) (xy 218.826258 -17.66479) (xy 218.848903 -17.615207) (xy 218.878374 -17.569351)
			(xy 218.914071 -17.528157) (xy 218.955267 -17.492462) (xy 219.001124 -17.462993) (xy 219.050709 -17.440351)
			(xy 219.10301 -17.424996) (xy 219.156965 -17.417242) (xy 219.18422 -17.41678) (xy 220.04782 -17.41678)
			(xy 220.075069 -17.417292) (xy 220.129013 -17.42505) (xy 220.181304 -17.440407) (xy 220.230877 -17.463048)
			(xy 220.276723 -17.492514) (xy 220.31791 -17.528204) (xy 220.353598 -17.569393) (xy 220.383062 -17.615241)
			(xy 220.4057 -17.664815) (xy 220.421054 -17.717106) (xy 220.42881 -17.771051) (xy 220.42881 -17.825549)
			(xy 220.421054 -17.879494) (xy 220.4057 -17.931785) (xy 220.383062 -17.981359) (xy 220.353598 -18.027207)
			(xy 220.31791 -18.068396) (xy 220.276723 -18.104086) (xy 220.230877 -18.133552) (xy 220.181304 -18.156193)
			(xy 220.129013 -18.17155) (xy 220.075069 -18.179308) (xy 220.04782 -18.179796) (xy 219.18422 -18.179796)
			(xy 219.156965 -18.179358) (xy 219.10301 -18.171604) (xy 219.050709 -18.156249) (xy 219.001124 -18.133607)
			(xy 218.955267 -18.104138) (xy 218.914071 -18.068443) (xy 218.878374 -18.027249) (xy 218.848903 -17.981393)
			(xy 218.826258 -17.93181) (xy 218.810901 -17.879509) (xy 218.803143 -17.825555) (xy 187.201242 -17.825555)
			(xy 187.221958 -17.838869) (xy 187.263151 -17.874565) (xy 187.298844 -17.915759) (xy 187.328311 -17.961614)
			(xy 187.350954 -18.011196) (xy 187.366309 -18.063495) (xy 187.374066 -18.117447) (xy 187.374066 -18.171953)
			(xy 187.366309 -18.225905) (xy 187.350954 -18.278204) (xy 187.328311 -18.327786) (xy 187.298844 -18.373641)
			(xy 187.263151 -18.414835) (xy 187.221958 -18.450531) (xy 187.176105 -18.480001) (xy 187.126525 -18.502646)
			(xy 187.074227 -18.518005) (xy 187.020275 -18.525765) (xy 186.993022 -18.526252) (xy 186.129422 -18.526252)
			(xy 186.102171 -18.525702) (xy 186.048224 -18.517949) (xy 185.99593 -18.502596) (xy 185.946353 -18.479958)
			(xy 185.900502 -18.450494) (xy 185.859311 -18.414804) (xy 185.823619 -18.373616) (xy 185.794153 -18.327767)
			(xy 185.771511 -18.278191) (xy 185.756156 -18.225897) (xy 185.748399 -18.171951) (xy 142.259189 -18.171951)
			(xy 142.259189 -18.171958) (xy 142.25143 -18.22592) (xy 142.236069 -18.278228) (xy 142.213421 -18.327817)
			(xy 142.183945 -18.373678) (xy 142.148241 -18.414877) (xy 142.107038 -18.450575) (xy 142.061173 -18.480045)
			(xy 142.011581 -18.502687) (xy 141.959271 -18.51804) (xy 141.905308 -18.525792) (xy 141.87805 -18.526252)
			(xy 141.01445 -18.526252) (xy 140.987204 -18.525674) (xy 140.933268 -18.517913) (xy 140.880986 -18.502555)
			(xy 140.83142 -18.479914) (xy 140.785582 -18.45045) (xy 140.744402 -18.414762) (xy 140.70872 -18.373578)
			(xy 140.679262 -18.327736) (xy 140.656627 -18.278168) (xy 140.641276 -18.225883) (xy 140.633522 -18.171946)
			(xy 138.659166 -18.171946) (xy 138.659166 -18.171954) (xy 138.651409 -18.225907) (xy 138.636052 -18.278207)
			(xy 138.613409 -18.32779) (xy 138.58394 -18.373645) (xy 138.548246 -18.41484) (xy 138.507052 -18.450536)
			(xy 138.461197 -18.480005) (xy 138.411615 -18.50265) (xy 138.359315 -18.518007) (xy 138.305362 -18.525766)
			(xy 138.278108 -18.526252) (xy 137.414508 -18.526252) (xy 137.387258 -18.525701) (xy 137.333312 -18.517946)
			(xy 137.28102 -18.502593) (xy 137.231444 -18.479953) (xy 137.185595 -18.450489) (xy 137.144406 -18.414799)
			(xy 137.108716 -18.373611) (xy 137.079251 -18.327763) (xy 137.05661 -18.278188) (xy 137.041256 -18.225895)
			(xy 137.033499 -18.17195) (xy 133.259189 -18.17195) (xy 133.259189 -18.171957) (xy 133.25143 -18.225917)
			(xy 133.236071 -18.278224) (xy 133.213423 -18.327812) (xy 133.183949 -18.373672) (xy 133.148248 -18.41487)
			(xy 133.107046 -18.450568) (xy 133.061184 -18.480039) (xy 133.011594 -18.502682) (xy 132.959286 -18.518037)
			(xy 132.905326 -18.525791) (xy 132.878068 -18.526252) (xy 132.014468 -18.526252) (xy 131.987221 -18.525676)
			(xy 131.933283 -18.517916) (xy 131.880999 -18.50256) (xy 131.831431 -18.47992) (xy 131.78559 -18.450456)
			(xy 131.744409 -18.414769) (xy 131.708725 -18.373584) (xy 131.679265 -18.327741) (xy 131.656629 -18.278171)
			(xy 131.641277 -18.225885) (xy 131.633522 -18.171947) (xy 0.509016 -18.171947) (xy 0.509016 -19.163611)
			(xy 17.946858 -19.163611) (xy 17.946858 -19.109109) (xy 17.954614 -19.055161) (xy 17.969969 -19.002867)
			(xy 17.99261 -18.95329) (xy 18.022076 -18.907439) (xy 18.057768 -18.866249) (xy 18.098958 -18.830558)
			(xy 18.144808 -18.801091) (xy 18.194385 -18.77845) (xy 18.246679 -18.763095) (xy 18.300627 -18.755338)
			(xy 18.327878 -18.754852) (xy 19.191478 -18.754852) (xy 19.218731 -18.755315) (xy 19.272682 -18.763072)
			(xy 19.32498 -18.778428) (xy 19.374561 -18.80107) (xy 19.420414 -18.830538) (xy 19.461607 -18.866232)
			(xy 19.497301 -18.907424) (xy 19.526769 -18.953278) (xy 19.549412 -19.002858) (xy 19.564768 -19.055156)
			(xy 19.572525 -19.109107) (xy 19.572525 -19.163613) (xy 19.572519 -19.163653) (xy 23.534838 -19.163653)
			(xy 23.534838 -19.109147) (xy 23.542595 -19.055195) (xy 23.55795 -19.002897) (xy 23.580592 -18.953316)
			(xy 23.610059 -18.907462) (xy 23.645752 -18.866268) (xy 23.686944 -18.830573) (xy 23.732797 -18.801103)
			(xy 23.782376 -18.778458) (xy 23.834674 -18.763099) (xy 23.888625 -18.755339) (xy 23.915878 -18.754852)
			(xy 24.779478 -18.754852) (xy 24.806729 -18.755394) (xy 24.860677 -18.763147) (xy 24.912972 -18.7785)
			(xy 24.962549 -18.801139) (xy 25.0084 -18.830603) (xy 25.049591 -18.866293) (xy 25.085284 -18.907482)
			(xy 25.114751 -18.953331) (xy 25.137392 -19.002908) (xy 25.152748 -19.055202) (xy 25.160505 -19.109149)
			(xy 25.160505 -19.163651) (xy 25.160505 -19.163653) (xy 29.122838 -19.163653) (xy 29.122838 -19.109147)
			(xy 29.130595 -19.055195) (xy 29.14595 -19.002897) (xy 29.168592 -18.953316) (xy 29.198059 -18.907462)
			(xy 29.233752 -18.866268) (xy 29.274944 -18.830573) (xy 29.320797 -18.801103) (xy 29.370376 -18.778458)
			(xy 29.422674 -18.763099) (xy 29.476625 -18.755339) (xy 29.503878 -18.754852) (xy 30.367478 -18.754852)
			(xy 30.394729 -18.755394) (xy 30.448677 -18.763147) (xy 30.500972 -18.7785) (xy 30.550549 -18.801139)
			(xy 30.5964 -18.830603) (xy 30.637591 -18.866293) (xy 30.673284 -18.907482) (xy 30.702751 -18.953331)
			(xy 30.725392 -19.002908) (xy 30.740748 -19.055202) (xy 30.748505 -19.109149) (xy 30.748505 -19.163651)
			(xy 30.748505 -19.163653) (xy 34.710838 -19.163653) (xy 34.710838 -19.109147) (xy 34.718595 -19.055195)
			(xy 34.73395 -19.002897) (xy 34.756592 -18.953316) (xy 34.786059 -18.907462) (xy 34.821752 -18.866268)
			(xy 34.862944 -18.830573) (xy 34.908797 -18.801103) (xy 34.958376 -18.778458) (xy 35.010674 -18.763099)
			(xy 35.064625 -18.755339) (xy 35.091878 -18.754852) (xy 35.955478 -18.754852) (xy 35.982729 -18.755394)
			(xy 36.036677 -18.763147) (xy 36.088972 -18.7785) (xy 36.138549 -18.801139) (xy 36.1844 -18.830603)
			(xy 36.225591 -18.866293) (xy 36.261284 -18.907482) (xy 36.290751 -18.953331) (xy 36.313392 -19.002908)
			(xy 36.328748 -19.055202) (xy 36.336505 -19.109149) (xy 36.336505 -19.163651) (xy 36.336505 -19.163654)
			(xy 40.604638 -19.163654) (xy 40.604638 -19.109146) (xy 40.612395 -19.055193) (xy 40.627751 -19.002894)
			(xy 40.650395 -18.953312) (xy 40.679863 -18.907457) (xy 40.715558 -18.866262) (xy 40.756752 -18.830567)
			(xy 40.802606 -18.801097) (xy 40.852188 -18.778454) (xy 40.904487 -18.763096) (xy 40.95844 -18.755338)
			(xy 40.985694 -18.754852) (xy 41.849294 -18.754852) (xy 41.876544 -18.755395) (xy 41.93049 -18.76315)
			(xy 41.982783 -18.778504) (xy 42.032359 -18.801144) (xy 42.078208 -18.830609) (xy 42.119397 -18.866299)
			(xy 42.155088 -18.907487) (xy 42.184553 -18.953336) (xy 42.207194 -19.002911) (xy 42.222548 -19.055204)
			(xy 42.230305 -19.10915) (xy 42.230305 -19.16365) (xy 42.230304 -19.163654) (xy 46.192638 -19.163654)
			(xy 46.192638 -19.109146) (xy 46.200395 -19.055193) (xy 46.215751 -19.002894) (xy 46.238395 -18.953312)
			(xy 46.267863 -18.907457) (xy 46.303558 -18.866262) (xy 46.344752 -18.830567) (xy 46.390606 -18.801097)
			(xy 46.440188 -18.778454) (xy 46.492487 -18.763096) (xy 46.54644 -18.755338) (xy 46.573694 -18.754852)
			(xy 47.437294 -18.754852) (xy 47.464544 -18.755395) (xy 47.51849 -18.76315) (xy 47.570783 -18.778504)
			(xy 47.620359 -18.801144) (xy 47.666208 -18.830609) (xy 47.707397 -18.866299) (xy 47.743088 -18.907487)
			(xy 47.772553 -18.953336) (xy 47.795194 -19.002911) (xy 47.810548 -19.055204) (xy 47.818305 -19.10915)
			(xy 47.818305 -19.16365) (xy 47.818304 -19.163657) (xy 51.814615 -19.163657) (xy 51.814615 -19.109143)
			(xy 51.822374 -19.055184) (xy 51.837733 -19.002878) (xy 51.86038 -18.95329) (xy 51.889854 -18.907431)
			(xy 51.925554 -18.866233) (xy 51.966755 -18.830536) (xy 52.012617 -18.801065) (xy 52.062206 -18.778422)
			(xy 52.114513 -18.763067) (xy 52.168473 -18.755313) (xy 52.19573 -18.754852) (xy 53.05933 -18.754852)
			(xy 53.086577 -18.75542) (xy 53.140516 -18.763179) (xy 53.192801 -18.778535) (xy 53.24237 -18.801176)
			(xy 53.288211 -18.83064) (xy 53.329394 -18.866328) (xy 53.365078 -18.907513) (xy 53.394538 -18.953357)
			(xy 53.417175 -19.002927) (xy 53.432527 -19.055214) (xy 53.440282 -19.109153) (xy 53.440282 -19.163647)
			(xy 53.440281 -19.163657) (xy 57.402615 -19.163657) (xy 57.402615 -19.109143) (xy 57.410374 -19.055184)
			(xy 57.425733 -19.002878) (xy 57.44838 -18.95329) (xy 57.477854 -18.907431) (xy 57.513554 -18.866233)
			(xy 57.554755 -18.830536) (xy 57.600617 -18.801065) (xy 57.650206 -18.778422) (xy 57.702513 -18.763067)
			(xy 57.756473 -18.755313) (xy 57.78373 -18.754852) (xy 58.64733 -18.754852) (xy 58.674577 -18.75542)
			(xy 58.728516 -18.763179) (xy 58.780801 -18.778535) (xy 58.83037 -18.801176) (xy 58.876211 -18.83064)
			(xy 58.917394 -18.866328) (xy 58.953078 -18.907513) (xy 58.982538 -18.953357) (xy 59.005175 -19.002927)
			(xy 59.020527 -19.055214) (xy 59.028282 -19.109153) (xy 59.028282 -19.163647) (xy 59.020527 -19.217586)
			(xy 59.005175 -19.269873) (xy 58.982538 -19.319443) (xy 58.953078 -19.365287) (xy 58.917394 -19.406472)
			(xy 58.876211 -19.44216) (xy 58.83037 -19.471624) (xy 58.780801 -19.494265) (xy 58.728516 -19.509621)
			(xy 58.674577 -19.51738) (xy 58.64733 -19.517868) (xy 57.78373 -19.517868) (xy 57.756473 -19.517487)
			(xy 57.702513 -19.509733) (xy 57.650206 -19.494378) (xy 57.600617 -19.471735) (xy 57.554755 -19.442264)
			(xy 57.513554 -19.406567) (xy 57.477854 -19.365369) (xy 57.44838 -19.31951) (xy 57.425733 -19.269922)
			(xy 57.410374 -19.217616) (xy 57.402615 -19.163657) (xy 53.440281 -19.163657) (xy 53.432527 -19.217586)
			(xy 53.417175 -19.269873) (xy 53.394538 -19.319443) (xy 53.365078 -19.365287) (xy 53.329394 -19.406472)
			(xy 53.288211 -19.44216) (xy 53.24237 -19.471624) (xy 53.192801 -19.494265) (xy 53.140516 -19.509621)
			(xy 53.086577 -19.51738) (xy 53.05933 -19.517868) (xy 52.19573 -19.517868) (xy 52.168473 -19.517487)
			(xy 52.114513 -19.509733) (xy 52.062206 -19.494378) (xy 52.012617 -19.471735) (xy 51.966755 -19.442264)
			(xy 51.925554 -19.406567) (xy 51.889854 -19.365369) (xy 51.86038 -19.31951) (xy 51.837733 -19.269922)
			(xy 51.822374 -19.217616) (xy 51.814615 -19.163657) (xy 47.818304 -19.163657) (xy 47.810548 -19.217596)
			(xy 47.795194 -19.269889) (xy 47.772553 -19.319464) (xy 47.743088 -19.365313) (xy 47.707397 -19.406501)
			(xy 47.666208 -19.442191) (xy 47.620359 -19.471656) (xy 47.570783 -19.494296) (xy 47.51849 -19.50965)
			(xy 47.464544 -19.517405) (xy 47.437294 -19.517868) (xy 46.573694 -19.517868) (xy 46.54644 -19.517462)
			(xy 46.492487 -19.509704) (xy 46.440188 -19.494346) (xy 46.390606 -19.471703) (xy 46.344752 -19.442233)
			(xy 46.303558 -19.406538) (xy 46.267863 -19.365343) (xy 46.238395 -19.319488) (xy 46.215751 -19.269906)
			(xy 46.200395 -19.217607) (xy 46.192638 -19.163654) (xy 42.230304 -19.163654) (xy 42.222548 -19.217596)
			(xy 42.207194 -19.269889) (xy 42.184553 -19.319464) (xy 42.155088 -19.365313) (xy 42.119397 -19.406501)
			(xy 42.078208 -19.442191) (xy 42.032359 -19.471656) (xy 41.982783 -19.494296) (xy 41.93049 -19.50965)
			(xy 41.876544 -19.517405) (xy 41.849294 -19.517868) (xy 40.985694 -19.517868) (xy 40.95844 -19.517462)
			(xy 40.904487 -19.509704) (xy 40.852188 -19.494346) (xy 40.802606 -19.471703) (xy 40.756752 -19.442233)
			(xy 40.715558 -19.406538) (xy 40.679863 -19.365343) (xy 40.650395 -19.319488) (xy 40.627751 -19.269906)
			(xy 40.612395 -19.217607) (xy 40.604638 -19.163654) (xy 36.336505 -19.163654) (xy 36.328748 -19.217598)
			(xy 36.313392 -19.269892) (xy 36.290751 -19.319469) (xy 36.261284 -19.365318) (xy 36.225591 -19.406507)
			(xy 36.1844 -19.442197) (xy 36.138549 -19.471661) (xy 36.088972 -19.4943) (xy 36.036677 -19.509653)
			(xy 35.982729 -19.517406) (xy 35.955478 -19.517868) (xy 35.091878 -19.517868) (xy 35.064625 -19.517461)
			(xy 35.010674 -19.509701) (xy 34.958376 -19.494342) (xy 34.908797 -19.471697) (xy 34.862944 -19.442227)
			(xy 34.821752 -19.406532) (xy 34.786059 -19.365338) (xy 34.756592 -19.319484) (xy 34.73395 -19.269903)
			(xy 34.718595 -19.217605) (xy 34.710838 -19.163653) (xy 30.748505 -19.163653) (xy 30.740748 -19.217598)
			(xy 30.725392 -19.269892) (xy 30.702751 -19.319469) (xy 30.673284 -19.365318) (xy 30.637591 -19.406507)
			(xy 30.5964 -19.442197) (xy 30.550549 -19.471661) (xy 30.500972 -19.4943) (xy 30.448677 -19.509653)
			(xy 30.394729 -19.517406) (xy 30.367478 -19.517868) (xy 29.503878 -19.517868) (xy 29.476625 -19.517461)
			(xy 29.422674 -19.509701) (xy 29.370376 -19.494342) (xy 29.320797 -19.471697) (xy 29.274944 -19.442227)
			(xy 29.233752 -19.406532) (xy 29.198059 -19.365338) (xy 29.168592 -19.319484) (xy 29.14595 -19.269903)
			(xy 29.130595 -19.217605) (xy 29.122838 -19.163653) (xy 25.160505 -19.163653) (xy 25.152748 -19.217598)
			(xy 25.137392 -19.269892) (xy 25.114751 -19.319469) (xy 25.085284 -19.365318) (xy 25.049591 -19.406507)
			(xy 25.0084 -19.442197) (xy 24.962549 -19.471661) (xy 24.912972 -19.4943) (xy 24.860677 -19.509653)
			(xy 24.806729 -19.517406) (xy 24.779478 -19.517868) (xy 23.915878 -19.517868) (xy 23.888625 -19.517461)
			(xy 23.834674 -19.509701) (xy 23.782376 -19.494342) (xy 23.732797 -19.471697) (xy 23.686944 -19.442227)
			(xy 23.645752 -19.406532) (xy 23.610059 -19.365338) (xy 23.580592 -19.319484) (xy 23.55795 -19.269903)
			(xy 23.542595 -19.217605) (xy 23.534838 -19.163653) (xy 19.572519 -19.163653) (xy 19.564768 -19.217564)
			(xy 19.549412 -19.269862) (xy 19.526769 -19.319442) (xy 19.497301 -19.365296) (xy 19.461607 -19.406488)
			(xy 19.420414 -19.442182) (xy 19.374561 -19.47165) (xy 19.32498 -19.494292) (xy 19.272682 -19.509648)
			(xy 19.218731 -19.517405) (xy 19.191478 -19.517868) (xy 18.327878 -19.517868) (xy 18.300627 -19.517382)
			(xy 18.246679 -19.509625) (xy 18.194385 -19.49427) (xy 18.144808 -19.471629) (xy 18.098958 -19.442162)
			(xy 18.057768 -19.406471) (xy 18.022076 -19.365281) (xy 17.99261 -19.31943) (xy 17.969969 -19.269853)
			(xy 17.954614 -19.217559) (xy 17.946858 -19.163611) (xy 0.509016 -19.163611) (xy 0.509016 -20.187751)
			(xy 138.828766 -20.187751) (xy 138.828766 -20.133249) (xy 138.836522 -20.079301) (xy 138.851877 -20.027006)
			(xy 138.874517 -19.977429) (xy 138.903982 -19.931578) (xy 138.939673 -19.890387) (xy 138.980862 -19.854694)
			(xy 139.026711 -19.825227) (xy 139.076288 -19.802584) (xy 139.128582 -19.787226) (xy 139.182529 -19.779467)
			(xy 139.20978 -19.77898) (xy 140.07338 -19.77898) (xy 140.100633 -19.779466) (xy 140.154584 -19.78722)
			(xy 140.206883 -19.802574) (xy 140.256464 -19.825215) (xy 140.302318 -19.854681) (xy 140.343512 -19.890374)
			(xy 140.379207 -19.931566) (xy 140.408676 -19.977418) (xy 140.431319 -20.026998) (xy 140.446675 -20.079296)
			(xy 140.454433 -20.133247) (xy 140.454433 -20.187753) (xy 140.446675 -20.241704) (xy 140.431319 -20.294002)
			(xy 140.408676 -20.343582) (xy 140.379207 -20.389434) (xy 140.343512 -20.430626) (xy 140.302318 -20.466319)
			(xy 140.256464 -20.495785) (xy 140.206883 -20.518426) (xy 140.154584 -20.53378) (xy 140.100633 -20.541534)
			(xy 140.07338 -20.541996) (xy 139.20978 -20.541996) (xy 139.182529 -20.541533) (xy 139.128582 -20.533774)
			(xy 139.076288 -20.518416) (xy 139.026711 -20.495773) (xy 138.980862 -20.466306) (xy 138.939673 -20.430613)
			(xy 138.903982 -20.389422) (xy 138.874517 -20.343571) (xy 138.851877 -20.293994) (xy 138.836522 -20.241699)
			(xy 138.828766 -20.187751) (xy 0.509016 -20.187751) (xy 0.509016 -21.521251) (xy 15.232366 -21.521251)
			(xy 15.232366 -21.466749) (xy 15.240122 -21.412801) (xy 15.255477 -21.360506) (xy 15.278117 -21.310929)
			(xy 15.307582 -21.265078) (xy 15.343273 -21.223887) (xy 15.384462 -21.188194) (xy 15.430311 -21.158727)
			(xy 15.479888 -21.136084) (xy 15.532182 -21.120726) (xy 15.586129 -21.112967) (xy 15.61338 -21.11248)
			(xy 16.47698 -21.11248) (xy 16.504233 -21.112966) (xy 16.558184 -21.12072) (xy 16.610483 -21.136074)
			(xy 16.660064 -21.158715) (xy 16.705918 -21.188181) (xy 16.747112 -21.223874) (xy 16.782807 -21.265066)
			(xy 16.812276 -21.310918) (xy 16.834919 -21.360498) (xy 16.850275 -21.412796) (xy 16.858033 -21.466747)
			(xy 16.858033 -21.521253) (xy 16.850275 -21.575204) (xy 16.834919 -21.627502) (xy 16.812276 -21.677082)
			(xy 16.782807 -21.722934) (xy 16.747112 -21.764126) (xy 16.705918 -21.799819) (xy 16.660064 -21.829285)
			(xy 16.610483 -21.851926) (xy 16.558184 -21.86728) (xy 16.504233 -21.875034) (xy 16.47698 -21.875496)
			(xy 15.61338 -21.875496) (xy 15.586129 -21.875033) (xy 15.532182 -21.867274) (xy 15.479888 -21.851916)
			(xy 15.430311 -21.829273) (xy 15.384462 -21.799806) (xy 15.343273 -21.764113) (xy 15.307582 -21.722922)
			(xy 15.278117 -21.677071) (xy 15.255477 -21.627494) (xy 15.240122 -21.575199) (xy 15.232366 -21.521251)
			(xy 0.509016 -21.521251) (xy 0.509016 -24.929338) (xy 133.555232 -24.929338) (xy 133.555232 -24.065738)
			(xy 133.555718 -24.038487) (xy 133.563474 -23.984539) (xy 133.578829 -23.932244) (xy 133.601471 -23.882667)
			(xy 133.630937 -23.836817) (xy 133.666628 -23.795626) (xy 133.707819 -23.759935) (xy 133.753669 -23.730469)
			(xy 133.803246 -23.707827) (xy 133.855541 -23.692472) (xy 133.909489 -23.684716) (xy 133.963991 -23.684716)
			(xy 134.017939 -23.692472) (xy 134.070234 -23.707827) (xy 134.119811 -23.730469) (xy 134.165661 -23.759935)
			(xy 134.206852 -23.795626) (xy 134.242543 -23.836817) (xy 134.272009 -23.882667) (xy 134.294651 -23.932244)
			(xy 134.310006 -23.984539) (xy 134.317762 -24.038487) (xy 134.318248 -24.065738) (xy 134.318248 -24.929338)
			(xy 134.317762 -24.956589) (xy 134.310006 -25.010537) (xy 134.294651 -25.062832) (xy 134.272009 -25.112409)
			(xy 134.242543 -25.158259) (xy 134.206852 -25.19945) (xy 134.165661 -25.235141) (xy 134.119811 -25.264607)
			(xy 134.070234 -25.287249) (xy 134.017939 -25.302604) (xy 133.963991 -25.31036) (xy 133.909489 -25.31036)
			(xy 133.855541 -25.302604) (xy 133.803246 -25.287249) (xy 133.753669 -25.264607) (xy 133.707819 -25.235141)
			(xy 133.666628 -25.19945) (xy 133.630937 -25.158259) (xy 133.601471 -25.112409) (xy 133.578829 -25.062832)
			(xy 133.563474 -25.010537) (xy 133.555718 -24.956589) (xy 133.555232 -24.929338) (xy 0.509016 -24.929338)
			(xy 0.509016 -29.070615) (xy 12.244307 -29.070615) (xy 12.252198 -28.941486) (xy 12.268182 -28.813107)
			(xy 12.292195 -28.685984) (xy 12.324144 -28.560621) (xy 12.363901 -28.437511) (xy 12.41131 -28.31714)
			(xy 12.466183 -28.199984) (xy 12.528305 -28.086504) (xy 12.59743 -27.97715) (xy 12.673285 -27.872351)
			(xy 12.75557 -27.772522) (xy 12.843962 -27.678057) (xy 12.938111 -27.589329) (xy 13.037646 -27.506688)
			(xy 13.142173 -27.43046) (xy 13.25128 -27.360945) (xy 13.364537 -27.298419) (xy 13.481497 -27.243128)
			(xy 13.601698 -27.19529) (xy 13.724665 -27.155093) (xy 13.849914 -27.122698) (xy 13.97695 -27.098231)
			(xy 14.105271 -27.081789) (xy 14.234372 -27.073437) (xy 14.363742 -27.073208) (xy 14.492871 -27.081103)
			(xy 14.62125 -27.097091) (xy 14.748372 -27.121108) (xy 14.873734 -27.15306) (xy 14.996843 -27.19282)
			(xy 15.117212 -27.240232) (xy 15.234367 -27.295109) (xy 15.347845 -27.357234) (xy 15.457198 -27.426362)
			(xy 15.561994 -27.50222) (xy 15.661821 -27.584508) (xy 15.709392 -27.628342) (xy 16.877792 -28.721304)
			(xy 16.92464 -28.765906) (xy 17.013363 -28.860052) (xy 17.096 -28.959584) (xy 17.172224 -29.064107)
			(xy 17.241734 -29.17321) (xy 17.304257 -29.286463) (xy 17.359545 -29.403418) (xy 17.407381 -29.523614)
			(xy 17.447575 -29.646576) (xy 17.479969 -29.771819) (xy 17.504435 -29.898849) (xy 17.520877 -30.027165)
			(xy 17.529229 -30.15626) (xy 17.529459 -30.285624) (xy 17.521566 -30.414748) (xy 17.50558 -30.543122)
			(xy 17.481566 -30.670238) (xy 17.449617 -30.795596) (xy 17.40986 -30.9187) (xy 17.362452 -31.039065)
			(xy 17.30758 -31.156215) (xy 17.24546 -31.26969) (xy 17.176338 -31.379039) (xy 17.100486 -31.483833)
			(xy 17.018204 -31.583657) (xy 16.929816 -31.678118) (xy 16.835671 -31.766843) (xy 16.736141 -31.849481)
			(xy 16.631619 -31.925706) (xy 16.522517 -31.995218) (xy 16.409265 -32.057743) (xy 16.292311 -32.113033)
			(xy 16.172116 -32.16087) (xy 16.049154 -32.201066) (xy 15.923911 -32.233462) (xy 15.796882 -32.25793)
			(xy 15.668566 -32.274374) (xy 15.539471 -32.282728) (xy 15.410107 -32.28296) (xy 15.280983 -32.275069)
			(xy 15.152609 -32.259085) (xy 15.025493 -32.235073) (xy 14.900134 -32.203126) (xy 14.77703 -32.163371)
			(xy 14.656664 -32.115965) (xy 14.539512 -32.061094) (xy 14.426037 -31.998976) (xy 14.316687 -31.929855)
			(xy 14.211892 -31.854005) (xy 14.112066 -31.771724) (xy 14.064488 -31.727902) (xy 12.896088 -30.63494)
			(xy 12.849198 -30.590378) (xy 12.760467 -30.496232) (xy 12.677823 -30.3967) (xy 12.601592 -30.292174)
			(xy 12.532074 -30.183069) (xy 12.469545 -30.069814) (xy 12.41425 -29.952855) (xy 12.366409 -29.832656)
			(xy 12.32621 -29.70969) (xy 12.293811 -29.584442) (xy 12.26934 -29.457407) (xy 12.252895 -29.329086)
			(xy 12.244539 -29.199985) (xy 12.244307 -29.070615) (xy 0.509016 -29.070615) (xy 0.509016 -37.099629)
			(xy 170.600616 -37.099629) (xy 170.600616 -37.000299) (xy 170.608608 -36.901292) (xy 170.624542 -36.803249)
			(xy 170.648313 -36.706806) (xy 170.679768 -36.612588) (xy 170.718701 -36.521208) (xy 170.764862 -36.433256)
			(xy 170.81795 -36.349304) (xy 170.877621 -36.269895) (xy 170.943489 -36.195546) (xy 171.015126 -36.126738)
			(xy 171.092067 -36.063918) (xy 171.173813 -36.007493) (xy 171.259835 -35.957828) (xy 171.349574 -35.915246)
			(xy 171.442448 -35.880024) (xy 171.537856 -35.852388) (xy 171.635178 -35.83252) (xy 171.733783 -35.820547)
			(xy 171.833032 -35.816548) (xy 171.932281 -35.820547) (xy 172.030886 -35.83252) (xy 172.128208 -35.852388)
			(xy 172.223616 -35.880024) (xy 172.31649 -35.915246) (xy 172.406229 -35.957828) (xy 172.492251 -36.007493)
			(xy 172.573997 -36.063918) (xy 172.650938 -36.126738) (xy 172.722575 -36.195546) (xy 172.788443 -36.269895)
			(xy 172.848114 -36.349304) (xy 172.901202 -36.433256) (xy 172.947363 -36.521208) (xy 172.986296 -36.612588)
			(xy 173.017751 -36.706806) (xy 173.041522 -36.803249) (xy 173.057456 -36.901292) (xy 173.065448 -37.000299)
			(xy 173.065948 -37.049964) (xy 173.065448 -37.099629) (xy 173.057456 -37.198636) (xy 173.041522 -37.296679)
			(xy 173.017751 -37.393122) (xy 172.986296 -37.48734) (xy 172.947363 -37.57872) (xy 172.901202 -37.666672)
			(xy 172.848114 -37.750624) (xy 172.788443 -37.830033) (xy 172.722575 -37.904382) (xy 172.650938 -37.97319)
			(xy 172.573997 -38.03601) (xy 172.492251 -38.092435) (xy 172.406229 -38.1421) (xy 172.31649 -38.184682)
			(xy 172.223616 -38.219904) (xy 172.128208 -38.24754) (xy 172.030886 -38.267408) (xy 171.932281 -38.279381)
			(xy 171.833032 -38.283381) (xy 171.733783 -38.279381) (xy 171.635178 -38.267408) (xy 171.537856 -38.24754)
			(xy 171.442448 -38.219904) (xy 171.349574 -38.184682) (xy 171.259835 -38.1421) (xy 171.173813 -38.092435)
			(xy 171.092067 -38.03601) (xy 171.015126 -37.97319) (xy 170.943489 -37.904382) (xy 170.877621 -37.830033)
			(xy 170.81795 -37.750624) (xy 170.764862 -37.666672) (xy 170.718701 -37.57872) (xy 170.679768 -37.48734)
			(xy 170.648313 -37.393122) (xy 170.624542 -37.296679) (xy 170.608608 -37.198636) (xy 170.600616 -37.099629)
			(xy 0.509016 -37.099629) (xy 0.509016 -39.657528) (xy 357.003604 -39.657528) (xy 357.003604 -38.793928)
			(xy 357.00409 -38.766659) (xy 357.011852 -38.712675) (xy 357.027217 -38.660345) (xy 357.049874 -38.610735)
			(xy 357.07936 -38.564854) (xy 357.115075 -38.523637) (xy 357.156292 -38.487922) (xy 357.202173 -38.458436)
			(xy 357.251783 -38.435779) (xy 357.304113 -38.420414) (xy 357.358097 -38.412652) (xy 357.412635 -38.412652)
			(xy 357.466619 -38.420414) (xy 357.518949 -38.435779) (xy 357.568559 -38.458436) (xy 357.61444 -38.487922)
			(xy 357.655657 -38.523637) (xy 357.691372 -38.564854) (xy 357.720858 -38.610735) (xy 357.743515 -38.660345)
			(xy 357.75888 -38.712675) (xy 357.766642 -38.766659) (xy 357.767128 -38.793928) (xy 357.767128 -39.657528)
			(xy 357.766642 -39.684797) (xy 357.75888 -39.738781) (xy 357.743515 -39.791111) (xy 357.720858 -39.840721)
			(xy 357.691372 -39.886602) (xy 357.655657 -39.927819) (xy 357.61444 -39.963534) (xy 357.568559 -39.99302)
			(xy 357.518949 -40.015677) (xy 357.466619 -40.031042) (xy 357.412635 -40.038804) (xy 357.358097 -40.038804)
			(xy 357.304113 -40.031042) (xy 357.251783 -40.015677) (xy 357.202173 -39.99302) (xy 357.156292 -39.963534)
			(xy 357.115075 -39.927819) (xy 357.07936 -39.886602) (xy 357.049874 -39.840721) (xy 357.027217 -39.791111)
			(xy 357.011852 -39.738781) (xy 357.00409 -39.684797) (xy 357.003604 -39.657528) (xy 0.509016 -39.657528)
			(xy 0.509016 -40.744902) (xy 235.083357 -40.744902) (xy 235.087362 -40.656994) (xy 235.099345 -40.569814)
			(xy 235.119205 -40.484085) (xy 235.14678 -40.400517) (xy 235.181839 -40.319803) (xy 235.224092 -40.242611)
			(xy 235.27319 -40.169582) (xy 235.328726 -40.10132) (xy 235.390238 -40.03839) (xy 235.457219 -39.981316)
			(xy 235.529112 -39.930568) (xy 235.605321 -39.886568) (xy 235.685216 -39.849681) (xy 235.768135 -39.820212)
			(xy 235.85339 -39.798405) (xy 235.940274 -39.784441) (xy 236.028068 -39.778435) (xy 236.116045 -39.780439)
			(xy 236.203475 -39.790434) (xy 236.289634 -39.808338) (xy 236.373808 -39.834002) (xy 236.455299 -39.867215)
			(xy 236.533433 -39.907701) (xy 236.607561 -39.955123) (xy 236.677069 -40.00909) (xy 236.741383 -40.069155)
			(xy 236.799967 -40.134819) (xy 236.852338 -40.205538) (xy 236.898061 -40.280726) (xy 236.936758 -40.359761)
			(xy 236.968107 -40.441987) (xy 236.991849 -40.526723) (xy 237.007787 -40.613267) (xy 237.015789 -40.700902)
			(xy 237.01629 -40.744902) (xy 237.015789 -40.788902) (xy 237.007787 -40.876537) (xy 236.991849 -40.963081)
			(xy 236.968107 -41.047817) (xy 236.936758 -41.130043) (xy 236.898061 -41.209078) (xy 236.852338 -41.284266)
			(xy 236.799967 -41.354985) (xy 236.741383 -41.420649) (xy 236.677069 -41.480714) (xy 236.607561 -41.534681)
			(xy 236.533433 -41.582103) (xy 236.455299 -41.622589) (xy 236.373808 -41.655802) (xy 236.289634 -41.681466)
			(xy 236.203475 -41.69937) (xy 236.116045 -41.709365) (xy 236.028068 -41.711369) (xy 235.940274 -41.705363)
			(xy 235.85339 -41.691399) (xy 235.768135 -41.669592) (xy 235.685216 -41.640123) (xy 235.605321 -41.603236)
			(xy 235.529112 -41.559236) (xy 235.457219 -41.508488) (xy 235.390238 -41.451414) (xy 235.328726 -41.388484)
			(xy 235.27319 -41.320222) (xy 235.224092 -41.247193) (xy 235.181839 -41.170001) (xy 235.14678 -41.089287)
			(xy 235.119205 -41.005719) (xy 235.099345 -40.91999) (xy 235.087362 -40.83281) (xy 235.083357 -40.744902)
			(xy 0.509016 -40.744902) (xy 0.509016 -43.999912) (xy 16.983969 -43.999912) (xy 16.987993 -43.914144)
			(xy 17.000031 -43.82913) (xy 17.019978 -43.745616) (xy 17.047657 -43.664337) (xy 17.082825 -43.586008)
			(xy 17.125174 -43.511315) (xy 17.174331 -43.440917) (xy 17.229864 -43.375431) (xy 17.291286 -43.315433)
			(xy 17.358055 -43.26145) (xy 17.429587 -43.213957) (xy 17.505251 -43.173371) (xy 17.584384 -43.140048)
			(xy 17.666289 -43.114282) (xy 17.750247 -43.096299) (xy 17.835521 -43.086257) (xy 17.92136 -43.084244)
			(xy 18.00701 -43.090278) (xy 18.091718 -43.104306) (xy 18.174741 -43.126205) (xy 18.255349 -43.155782)
			(xy 18.332833 -43.192777) (xy 18.406512 -43.236865) (xy 18.475738 -43.287659) (xy 18.539905 -43.344712)
			(xy 18.598446 -43.407523) (xy 18.650849 -43.47554) (xy 18.696652 -43.548165) (xy 18.735453 -43.62476)
			(xy 18.766912 -43.704652) (xy 18.790751 -43.787139) (xy 18.806761 -43.871496) (xy 18.814801 -43.956981)
			(xy 18.815304 -43.999912) (xy 18.814801 -44.042843) (xy 18.806761 -44.128328) (xy 18.790751 -44.212685)
			(xy 18.766912 -44.295172) (xy 18.735453 -44.375064) (xy 18.696652 -44.451659) (xy 18.650849 -44.524284)
			(xy 18.598446 -44.592301) (xy 18.539905 -44.655112) (xy 18.475738 -44.712165) (xy 18.406512 -44.762959)
			(xy 18.332833 -44.807047) (xy 18.255349 -44.844042) (xy 18.174741 -44.873619) (xy 18.091718 -44.895518)
			(xy 18.00701 -44.909546) (xy 17.92136 -44.91558) (xy 17.835521 -44.913567) (xy 17.750247 -44.903525)
			(xy 17.666289 -44.885542) (xy 17.584384 -44.859776) (xy 17.505251 -44.826453) (xy 17.429587 -44.785867)
			(xy 17.358055 -44.738374) (xy 17.291286 -44.684391) (xy 17.229864 -44.624393) (xy 17.174331 -44.558907)
			(xy 17.125174 -44.488509) (xy 17.082825 -44.413816) (xy 17.047657 -44.335487) (xy 17.019978 -44.254208)
			(xy 17.000031 -44.170694) (xy 16.987993 -44.08568) (xy 16.983969 -43.999912) (xy 0.509016 -43.999912)
			(xy 0.509016 -47.049813) (xy 59.781451 -47.049813) (xy 59.785436 -46.895317) (xy 59.79737 -46.74123)
			(xy 59.817219 -46.587962) (xy 59.844933 -46.43592) (xy 59.880436 -46.285505) (xy 59.923635 -46.137118)
			(xy 59.974415 -45.991151) (xy 60.032642 -45.847991) (xy 60.098162 -45.708019) (xy 60.1708 -45.571605)
			(xy 60.250363 -45.439111) (xy 60.336642 -45.310889) (xy 60.429407 -45.187278) (xy 60.528412 -45.068606)
			(xy 60.633395 -44.955188) (xy 60.744077 -44.847324) (xy 60.860165 -44.745302) (xy 60.981351 -44.64939)
			(xy 61.107313 -44.559844) (xy 61.237718 -44.476901) (xy 61.37222 -44.400781) (xy 61.510462 -44.331685)
			(xy 61.652077 -44.269798) (xy 61.796691 -44.215282) (xy 61.943919 -44.168283) (xy 62.093371 -44.128926)
			(xy 62.244652 -44.097314) (xy 62.397358 -44.073531) (xy 62.551087 -44.057641) (xy 62.70543 -44.049685)
			(xy 62.782704 -44.049188) (xy 64.383158 -44.049188) (xy 64.460432 -44.049684) (xy 64.614774 -44.057653)
			(xy 64.768502 -44.073557) (xy 64.921207 -44.097353) (xy 65.072484 -44.128978) (xy 65.221933 -44.168349)
			(xy 65.369158 -44.21536) (xy 65.513767 -44.269888) (xy 65.655377 -44.331788) (xy 65.793613 -44.400896)
			(xy 65.928108 -44.477028) (xy 66.058506 -44.559982) (xy 66.184461 -44.649539) (xy 66.305639 -44.745461)
			(xy 66.421718 -44.847494) (xy 66.532391 -44.955367) (xy 66.637364 -45.068794) (xy 66.736359 -45.187475)
			(xy 66.829113 -45.311094) (xy 66.915381 -45.439324) (xy 66.994934 -45.571824) (xy 67.06756 -45.708245)
			(xy 67.133068 -45.848223) (xy 67.191283 -45.991387) (xy 67.242051 -46.137359) (xy 67.285237 -46.28575)
			(xy 67.320727 -46.436168) (xy 67.348428 -46.588213) (xy 67.368264 -46.741483) (xy 67.380185 -46.89557)
			(xy 67.384154 -47.04994) (xy 89.78165 -47.04994) (xy 89.78563 -46.895439) (xy 89.797557 -46.741349)
			(xy 89.817402 -46.588076) (xy 89.84511 -46.436028) (xy 89.880608 -46.285609) (xy 89.923803 -46.137216)
			(xy 89.97458 -45.991243) (xy 90.032804 -45.848078) (xy 90.098321 -45.708101) (xy 90.170957 -45.571681)
			(xy 90.250519 -45.439181) (xy 90.336796 -45.310953) (xy 90.42956 -45.187337) (xy 90.528565 -45.068659)
			(xy 90.633548 -44.955236) (xy 90.74423 -44.847368) (xy 90.860319 -44.74534) (xy 90.981506 -44.649424)
			(xy 91.10747 -44.559873) (xy 91.237877 -44.476926) (xy 91.372381 -44.400801) (xy 91.510626 -44.331702)
			(xy 91.652244 -44.269811) (xy 91.796861 -44.215293) (xy 91.944092 -44.168291) (xy 92.093548 -44.128931)
			(xy 92.244832 -44.097317) (xy 92.397543 -44.073533) (xy 92.551275 -44.057642) (xy 92.705622 -44.049686)
			(xy 92.782898 -44.049188) (xy 94.383098 -44.049188) (xy 94.460374 -44.049669) (xy 94.614722 -44.057625)
			(xy 94.768456 -44.073516) (xy 94.921168 -44.0973) (xy 95.072452 -44.128914) (xy 95.221909 -44.168274)
			(xy 95.369142 -44.215276) (xy 95.513759 -44.269795) (xy 95.655379 -44.331686) (xy 95.793624 -44.400785)
			(xy 95.928129 -44.47691) (xy 96.058537 -44.559858) (xy 96.184502 -44.649409) (xy 96.30569 -44.745326)
			(xy 96.421779 -44.847354) (xy 96.532463 -44.955223) (xy 96.637446 -45.068647) (xy 96.736452 -45.187325)
			(xy 96.829216 -45.310943) (xy 96.915495 -45.439171) (xy 96.995057 -45.571672) (xy 97.038059 -45.652436)
			(xy 155.97378 -45.652436) (xy 155.97378 -44.788836) (xy 155.974266 -44.761567) (xy 155.982028 -44.707583)
			(xy 155.997393 -44.655253) (xy 156.02005 -44.605643) (xy 156.049536 -44.559762) (xy 156.085251 -44.518545)
			(xy 156.126468 -44.48283) (xy 156.172349 -44.453344) (xy 156.221959 -44.430687) (xy 156.274289 -44.415322)
			(xy 156.328273 -44.40756) (xy 156.382811 -44.40756) (xy 156.436795 -44.415322) (xy 156.489125 -44.430687)
			(xy 156.538735 -44.453344) (xy 156.584616 -44.48283) (xy 156.625833 -44.518545) (xy 156.661548 -44.559762)
			(xy 156.691034 -44.605643) (xy 156.713691 -44.655253) (xy 156.72159 -44.682156) (xy 159.179768 -44.682156)
			(xy 159.179768 -43.818556) (xy 159.180254 -43.791287) (xy 159.188016 -43.737303) (xy 159.203381 -43.684973)
			(xy 159.226038 -43.635363) (xy 159.255524 -43.589482) (xy 159.291239 -43.548265) (xy 159.332456 -43.51255)
			(xy 159.378337 -43.483064) (xy 159.427947 -43.460407) (xy 159.480277 -43.445042) (xy 159.534261 -43.43728)
			(xy 159.588799 -43.43728) (xy 159.642783 -43.445042) (xy 159.695113 -43.460407) (xy 159.74185 -43.481752)
			(xy 178.891692 -43.481752) (xy 178.891692 -42.618152) (xy 178.892178 -42.590901) (xy 178.899934 -42.536953)
			(xy 178.915289 -42.484658) (xy 178.937931 -42.435081) (xy 178.967397 -42.389231) (xy 179.003088 -42.34804)
			(xy 179.044279 -42.312349) (xy 179.090129 -42.282883) (xy 179.139706 -42.260241) (xy 179.192001 -42.244886)
			(xy 179.245949 -42.23713) (xy 179.300451 -42.23713) (xy 179.354399 -42.244886) (xy 179.406694 -42.260241)
			(xy 179.456271 -42.282883) (xy 179.502121 -42.312349) (xy 179.543312 -42.34804) (xy 179.579003 -42.389231)
			(xy 179.608469 -42.435081) (xy 179.631111 -42.484658) (xy 179.646466 -42.536953) (xy 179.654222 -42.590901)
			(xy 179.654708 -42.618152) (xy 179.654708 -43.481752) (xy 179.654222 -43.509003) (xy 179.647839 -43.5534)
			(xy 353.767583 -43.5534) (xy 353.771544 -43.500544) (xy 353.783339 -43.44887) (xy 353.802705 -43.39953)
			(xy 353.829208 -43.353628) (xy 353.862256 -43.312189) (xy 353.901112 -43.276139) (xy 353.944908 -43.246283)
			(xy 353.992664 -43.223289) (xy 354.043314 -43.207669) (xy 354.095726 -43.199773) (xy 354.122228 -43.199304)
			(xy 354.122736 -43.199304) (xy 354.153713 -43.199978) (xy 354.214715 -43.210807) (xy 354.272905 -43.232077)
			(xy 354.300028 -43.247056) (xy 354.328004 -43.238767) (xy 354.385663 -43.229845) (xy 354.414836 -43.229276)
			(xy 354.99548 -43.229276) (xy 355.004624 -43.225466) (xy 355.025917 -43.217194) (xy 355.070087 -43.205543)
			(xy 355.115388 -43.199665) (xy 355.138228 -43.199304) (xy 355.162681 -43.199729) (xy 355.211118 -43.206478)
			(xy 355.25817 -43.219815) (xy 355.280722 -43.229276) (xy 355.307866 -43.229907) (xy 355.361565 -43.237931)
			(xy 355.413585 -43.253486) (xy 355.462874 -43.276259) (xy 355.508436 -43.305789) (xy 355.549352 -43.341481)
			(xy 355.584795 -43.382612) (xy 355.61405 -43.428352) (xy 355.636524 -43.477777) (xy 355.651765 -43.52989)
			(xy 355.659465 -43.583636) (xy 355.659944 -43.610784) (xy 355.659468 -43.634951) (xy 356.178591 -43.634951)
			(xy 356.178591 -43.580449) (xy 356.186348 -43.526502) (xy 356.201703 -43.474208) (xy 356.224344 -43.424632)
			(xy 356.253811 -43.378783) (xy 356.289502 -43.337594) (xy 356.330692 -43.301903) (xy 356.376543 -43.272438)
			(xy 356.42612 -43.249799) (xy 356.478414 -43.234445) (xy 356.532361 -43.22669) (xy 356.559612 -43.226228)
			(xy 357.423212 -43.226228) (xy 357.450465 -43.226643) (xy 357.504417 -43.234401) (xy 357.556715 -43.249759)
			(xy 357.606295 -43.272403) (xy 357.652149 -43.301872) (xy 357.693341 -43.337567) (xy 357.729035 -43.378761)
			(xy 357.758503 -43.424615) (xy 357.781145 -43.474196) (xy 357.796501 -43.526495) (xy 357.804258 -43.580447)
			(xy 357.804258 -43.634953) (xy 357.803812 -43.638056) (xy 358.339039 -43.638056) (xy 358.339039 -43.583544)
			(xy 358.346797 -43.529588) (xy 358.362156 -43.477285) (xy 358.384802 -43.4277) (xy 358.414274 -43.381843)
			(xy 358.449974 -43.340648) (xy 358.491172 -43.304953) (xy 358.537032 -43.275485) (xy 358.586619 -43.252843)
			(xy 358.638923 -43.23749) (xy 358.69288 -43.229736) (xy 358.720136 -43.229276) (xy 359.583736 -43.229276)
			(xy 359.610984 -43.229797) (xy 359.664926 -43.237557) (xy 359.717214 -43.252915) (xy 359.766785 -43.275557)
			(xy 359.812629 -43.305023) (xy 359.853813 -43.340713) (xy 359.889499 -43.3819) (xy 359.91896 -43.427747)
			(xy 359.941598 -43.47732) (xy 359.956951 -43.529609) (xy 359.964706 -43.583552) (xy 359.964706 -43.638048)
			(xy 359.956951 -43.691991) (xy 359.941598 -43.74428) (xy 359.91896 -43.793853) (xy 359.889499 -43.8397)
			(xy 359.853813 -43.880887) (xy 359.812629 -43.916577) (xy 359.766785 -43.946043) (xy 359.717214 -43.968685)
			(xy 359.664926 -43.984043) (xy 359.610984 -43.991803) (xy 359.583736 -43.992292) (xy 358.720136 -43.992292)
			(xy 358.69288 -43.991864) (xy 358.638923 -43.98411) (xy 358.586619 -43.968757) (xy 358.537032 -43.946115)
			(xy 358.491172 -43.916647) (xy 358.449974 -43.880952) (xy 358.414274 -43.839757) (xy 358.384802 -43.7939)
			(xy 358.362156 -43.744315) (xy 358.346797 -43.692012) (xy 358.339039 -43.638056) (xy 357.803812 -43.638056)
			(xy 357.796501 -43.688905) (xy 357.781145 -43.741204) (xy 357.758503 -43.790785) (xy 357.729035 -43.836639)
			(xy 357.693341 -43.877833) (xy 357.652149 -43.913528) (xy 357.606295 -43.942997) (xy 357.556715 -43.965641)
			(xy 357.504417 -43.980999) (xy 357.450465 -43.988757) (xy 357.423212 -43.989244) (xy 356.559612 -43.989244)
			(xy 356.532361 -43.98871) (xy 356.478414 -43.980955) (xy 356.42612 -43.965601) (xy 356.376543 -43.942962)
			(xy 356.330692 -43.913497) (xy 356.289502 -43.877806) (xy 356.253811 -43.836617) (xy 356.224344 -43.790768)
			(xy 356.201703 -43.741192) (xy 356.186348 -43.688898) (xy 356.178591 -43.634951) (xy 355.659468 -43.634951)
			(xy 355.659407 -43.638033) (xy 355.651654 -43.691977) (xy 355.636302 -43.744269) (xy 355.613666 -43.793843)
			(xy 355.584204 -43.839692) (xy 355.548518 -43.880882) (xy 355.507334 -43.916573) (xy 355.461489 -43.946041)
			(xy 355.411917 -43.968684) (xy 355.359628 -43.984043) (xy 355.305685 -43.991803) (xy 355.278436 -43.992292)
			(xy 354.414836 -43.992292) (xy 354.388369 -43.991825) (xy 354.335944 -43.984518) (xy 354.285033 -43.970025)
			(xy 354.236619 -43.948625) (xy 354.191633 -43.920731) (xy 354.170996 -43.904154) (xy 354.158864 -43.905712)
			(xy 354.134459 -43.907367) (xy 354.122228 -43.907456) (xy 354.095726 -43.907027) (xy 354.043314 -43.899131)
			(xy 353.992664 -43.883511) (xy 353.944908 -43.860517) (xy 353.901112 -43.830661) (xy 353.862256 -43.794611)
			(xy 353.829208 -43.753172) (xy 353.802705 -43.70727) (xy 353.783339 -43.65793) (xy 353.771544 -43.606256)
			(xy 353.767583 -43.5534) (xy 179.647839 -43.5534) (xy 179.646466 -43.562951) (xy 179.631111 -43.615246)
			(xy 179.608469 -43.664823) (xy 179.579003 -43.710673) (xy 179.543312 -43.751864) (xy 179.502121 -43.787555)
			(xy 179.456271 -43.817021) (xy 179.406694 -43.839663) (xy 179.354399 -43.855018) (xy 179.300451 -43.862774)
			(xy 179.245949 -43.862774) (xy 179.192001 -43.855018) (xy 179.139706 -43.839663) (xy 179.090129 -43.817021)
			(xy 179.044279 -43.787555) (xy 179.003088 -43.751864) (xy 178.967397 -43.710673) (xy 178.937931 -43.664823)
			(xy 178.915289 -43.615246) (xy 178.899934 -43.562951) (xy 178.892178 -43.509003) (xy 178.891692 -43.481752)
			(xy 159.74185 -43.481752) (xy 159.744723 -43.483064) (xy 159.790604 -43.51255) (xy 159.831821 -43.548265)
			(xy 159.867536 -43.589482) (xy 159.897022 -43.635363) (xy 159.919679 -43.684973) (xy 159.935044 -43.737303)
			(xy 159.942806 -43.791287) (xy 159.943292 -43.818556) (xy 159.943292 -44.682156) (xy 159.942806 -44.709425)
			(xy 159.935044 -44.763409) (xy 159.919679 -44.815739) (xy 159.897022 -44.865349) (xy 159.867536 -44.91123)
			(xy 159.831821 -44.952447) (xy 159.79991 -44.980098) (xy 181.659784 -44.980098) (xy 181.659784 -44.116498)
			(xy 181.66027 -44.089247) (xy 181.668026 -44.035299) (xy 181.683381 -43.983004) (xy 181.706023 -43.933427)
			(xy 181.735489 -43.887577) (xy 181.77118 -43.846386) (xy 181.812371 -43.810695) (xy 181.858221 -43.781229)
			(xy 181.907798 -43.758587) (xy 181.960093 -43.743232) (xy 182.014041 -43.735476) (xy 182.068543 -43.735476)
			(xy 182.122491 -43.743232) (xy 182.174786 -43.758587) (xy 182.224363 -43.781229) (xy 182.270213 -43.810695)
			(xy 182.311404 -43.846386) (xy 182.347095 -43.887577) (xy 182.376561 -43.933427) (xy 182.399203 -43.983004)
			(xy 182.414558 -44.035299) (xy 182.422314 -44.089247) (xy 182.4228 -44.116498) (xy 182.4228 -44.840452)
			(xy 348.511075 -44.840452) (xy 348.511075 -44.785948) (xy 348.518832 -44.731999) (xy 348.534188 -44.679702)
			(xy 348.556831 -44.630124) (xy 348.586298 -44.584273) (xy 348.621992 -44.543082) (xy 348.663184 -44.50739)
			(xy 348.709036 -44.477924) (xy 348.758616 -44.455283) (xy 348.810912 -44.439929) (xy 348.864862 -44.432174)
			(xy 348.892114 -44.431712) (xy 349.755714 -44.431712) (xy 349.782966 -44.432159) (xy 349.836915 -44.439917)
			(xy 349.889211 -44.455274) (xy 349.938789 -44.477918) (xy 349.98464 -44.507386) (xy 350.025831 -44.543079)
			(xy 350.061523 -44.584271) (xy 350.090989 -44.630123) (xy 350.11363 -44.679702) (xy 350.128986 -44.731999)
			(xy 350.136742 -44.785948) (xy 350.136742 -44.840452) (xy 350.128986 -44.894401) (xy 350.11363 -44.946698)
			(xy 350.090989 -44.996277) (xy 350.072098 -45.025673) (xy 355.559288 -45.025673) (xy 355.559288 -44.971127)
			(xy 355.56705 -44.917137) (xy 355.582418 -44.864802) (xy 355.605077 -44.815186) (xy 355.634567 -44.7693)
			(xy 355.670288 -44.728078) (xy 355.711511 -44.692359) (xy 355.757398 -44.662871) (xy 355.807015 -44.640213)
			(xy 355.859351 -44.624847) (xy 355.913341 -44.617087) (xy 355.940614 -44.616624) (xy 356.804214 -44.616624)
			(xy 356.831482 -44.617139) (xy 356.885462 -44.624902) (xy 356.937788 -44.640268) (xy 356.987394 -44.662925)
			(xy 357.033272 -44.69241) (xy 357.074486 -44.728124) (xy 357.110199 -44.769339) (xy 357.139682 -44.815218)
			(xy 357.162337 -44.864825) (xy 357.177701 -44.917152) (xy 357.185462 -44.971132) (xy 357.185462 -45.025668)
			(xy 357.177701 -45.079648) (xy 357.162337 -45.131975) (xy 357.139682 -45.181582) (xy 357.110199 -45.227461)
			(xy 357.074486 -45.268676) (xy 357.033272 -45.30439) (xy 356.987394 -45.333875) (xy 356.937788 -45.356532)
			(xy 356.885462 -45.371898) (xy 356.831482 -45.379661) (xy 356.804214 -45.380148) (xy 355.940614 -45.380148)
			(xy 355.913341 -45.379713) (xy 355.859351 -45.371953) (xy 355.807015 -45.356587) (xy 355.757398 -45.333929)
			(xy 355.711511 -45.304441) (xy 355.670288 -45.268722) (xy 355.634567 -45.2275) (xy 355.605077 -45.181614)
			(xy 355.582418 -45.131998) (xy 355.56705 -45.079663) (xy 355.559288 -45.025673) (xy 350.072098 -45.025673)
			(xy 350.061523 -45.042129) (xy 350.025831 -45.083321) (xy 349.98464 -45.119014) (xy 349.938789 -45.148482)
			(xy 349.889211 -45.171126) (xy 349.836915 -45.186483) (xy 349.782966 -45.194241) (xy 349.755714 -45.194728)
			(xy 348.892114 -45.194728) (xy 348.864862 -45.194226) (xy 348.810912 -45.186471) (xy 348.758616 -45.171117)
			(xy 348.709036 -45.148476) (xy 348.663184 -45.11901) (xy 348.621992 -45.083318) (xy 348.586298 -45.042127)
			(xy 348.556831 -44.996276) (xy 348.534188 -44.946698) (xy 348.518832 -44.894401) (xy 348.511075 -44.840452)
			(xy 182.4228 -44.840452) (xy 182.4228 -44.980098) (xy 182.422314 -45.007349) (xy 182.414558 -45.061297)
			(xy 182.399203 -45.113592) (xy 182.376561 -45.163169) (xy 182.347095 -45.209019) (xy 182.311404 -45.25021)
			(xy 182.270213 -45.285901) (xy 182.224363 -45.315367) (xy 182.174786 -45.338009) (xy 182.122491 -45.353364)
			(xy 182.068543 -45.36112) (xy 182.014041 -45.36112) (xy 181.960093 -45.353364) (xy 181.907798 -45.338009)
			(xy 181.858221 -45.315367) (xy 181.812371 -45.285901) (xy 181.77118 -45.25021) (xy 181.735489 -45.209019)
			(xy 181.706023 -45.163169) (xy 181.683381 -45.113592) (xy 181.668026 -45.061297) (xy 181.66027 -45.007349)
			(xy 181.659784 -44.980098) (xy 159.79991 -44.980098) (xy 159.790604 -44.988162) (xy 159.744723 -45.017648)
			(xy 159.695113 -45.040305) (xy 159.642783 -45.05567) (xy 159.588799 -45.063432) (xy 159.534261 -45.063432)
			(xy 159.480277 -45.05567) (xy 159.427947 -45.040305) (xy 159.378337 -45.017648) (xy 159.332456 -44.988162)
			(xy 159.291239 -44.952447) (xy 159.255524 -44.91123) (xy 159.226038 -44.865349) (xy 159.203381 -44.815739)
			(xy 159.188016 -44.763409) (xy 159.180254 -44.709425) (xy 159.179768 -44.682156) (xy 156.72159 -44.682156)
			(xy 156.729056 -44.707583) (xy 156.736818 -44.761567) (xy 156.737304 -44.788836) (xy 156.737304 -45.652436)
			(xy 156.736818 -45.679705) (xy 156.729056 -45.733689) (xy 156.713691 -45.786019) (xy 156.691034 -45.835629)
			(xy 156.661548 -45.88151) (xy 156.625833 -45.922727) (xy 156.584616 -45.958442) (xy 156.538735 -45.987928)
			(xy 156.489125 -46.010585) (xy 156.436795 -46.02595) (xy 156.382811 -46.033712) (xy 156.328273 -46.033712)
			(xy 156.274289 -46.02595) (xy 156.221959 -46.010585) (xy 156.172349 -45.987928) (xy 156.126468 -45.958442)
			(xy 156.085251 -45.922727) (xy 156.049536 -45.88151) (xy 156.02005 -45.835629) (xy 155.997393 -45.786019)
			(xy 155.982028 -45.733689) (xy 155.974266 -45.679705) (xy 155.97378 -45.652436) (xy 97.038059 -45.652436)
			(xy 97.067693 -45.708092) (xy 97.133211 -45.848071) (xy 97.191435 -45.991237) (xy 97.242212 -46.13721)
			(xy 97.285407 -46.285604) (xy 97.320906 -46.436025) (xy 97.329238 -46.481746) (xy 178.630072 -46.481746)
			(xy 178.630072 -45.618146) (xy 178.630558 -45.590895) (xy 178.638314 -45.536947) (xy 178.653669 -45.484652)
			(xy 178.676311 -45.435075) (xy 178.705777 -45.389225) (xy 178.741468 -45.348034) (xy 178.782659 -45.312343)
			(xy 178.828509 -45.282877) (xy 178.878086 -45.260235) (xy 178.930381 -45.24488) (xy 178.984329 -45.237124)
			(xy 179.038831 -45.237124) (xy 179.092779 -45.24488) (xy 179.145074 -45.260235) (xy 179.194651 -45.282877)
			(xy 179.240501 -45.312343) (xy 179.281692 -45.348034) (xy 179.317383 -45.389225) (xy 179.346849 -45.435075)
			(xy 179.369491 -45.484652) (xy 179.384846 -45.536947) (xy 179.392602 -45.590895) (xy 179.393088 -45.618146)
			(xy 179.393088 -46.481746) (xy 179.392602 -46.508997) (xy 179.384846 -46.562945) (xy 179.369491 -46.61524)
			(xy 179.346849 -46.664817) (xy 179.317383 -46.710667) (xy 179.281692 -46.751858) (xy 179.240501 -46.787549)
			(xy 179.194651 -46.817015) (xy 179.145074 -46.839657) (xy 179.092779 -46.855012) (xy 179.038831 -46.862768)
			(xy 178.984329 -46.862768) (xy 178.930381 -46.855012) (xy 178.878086 -46.839657) (xy 178.828509 -46.817015)
			(xy 178.782659 -46.787549) (xy 178.741468 -46.751858) (xy 178.705777 -46.710667) (xy 178.676311 -46.664817)
			(xy 178.653669 -46.61524) (xy 178.638314 -46.562945) (xy 178.630558 -46.508997) (xy 178.630072 -46.481746)
			(xy 97.329238 -46.481746) (xy 97.348615 -46.588073) (xy 97.368459 -46.741347) (xy 97.380387 -46.895438)
			(xy 97.384366 -47.04994) (xy 97.380387 -47.204442) (xy 97.368459 -47.358533) (xy 97.348615 -47.511807)
			(xy 97.320906 -47.663855) (xy 97.285407 -47.814276) (xy 97.242212 -47.96267) (xy 97.239575 -47.97025)
			(xy 155.567386 -47.97025) (xy 155.567386 -47.91575) (xy 155.575142 -47.861805) (xy 155.590495 -47.809513)
			(xy 155.613135 -47.759938) (xy 155.642598 -47.71409) (xy 155.678287 -47.672901) (xy 155.719474 -47.63721)
			(xy 155.765321 -47.607744) (xy 155.814895 -47.585102) (xy 155.867186 -47.569746) (xy 155.92113 -47.561987)
			(xy 155.94838 -47.5615) (xy 156.81198 -47.5615) (xy 156.839234 -47.561946) (xy 156.893189 -47.569701)
			(xy 156.94549 -47.585055) (xy 156.995074 -47.607697) (xy 157.04093 -47.637165) (xy 157.082126 -47.67286)
			(xy 157.117823 -47.714054) (xy 157.147293 -47.759909) (xy 157.169938 -47.809491) (xy 157.185295 -47.861792)
			(xy 157.193053 -47.915746) (xy 157.193053 -47.970249) (xy 158.785586 -47.970249) (xy 158.785586 -47.915751)
			(xy 158.793341 -47.861808) (xy 158.808694 -47.809518) (xy 158.831331 -47.759944) (xy 158.860793 -47.714097)
			(xy 158.89648 -47.672908) (xy 158.937664 -47.637217) (xy 158.983509 -47.607751) (xy 159.03308 -47.585108)
			(xy 159.085369 -47.569749) (xy 159.139311 -47.561988) (xy 159.16656 -47.5615) (xy 160.03016 -47.5615)
			(xy 160.057415 -47.561945) (xy 160.111372 -47.569697) (xy 160.163675 -47.58505) (xy 160.213262 -47.607691)
			(xy 160.259121 -47.637158) (xy 160.300319 -47.672853) (xy 160.336018 -47.714047) (xy 160.36549 -47.759903)
			(xy 160.388136 -47.809487) (xy 160.403494 -47.861789) (xy 160.411253 -47.915745) (xy 160.411253 -47.970255)
			(xy 160.403494 -48.024211) (xy 160.402353 -48.028098) (xy 181.659784 -48.028098) (xy 181.659784 -47.164498)
			(xy 181.66027 -47.137247) (xy 181.668026 -47.083299) (xy 181.683381 -47.031004) (xy 181.706023 -46.981427)
			(xy 181.735489 -46.935577) (xy 181.77118 -46.894386) (xy 181.812371 -46.858695) (xy 181.858221 -46.829229)
			(xy 181.907798 -46.806587) (xy 181.960093 -46.791232) (xy 182.014041 -46.783476) (xy 182.068543 -46.783476)
			(xy 182.122491 -46.791232) (xy 182.174786 -46.806587) (xy 182.224363 -46.829229) (xy 182.225669 -46.830068)
			(xy 356.445326 -46.830068) (xy 356.445326 -46.775532) (xy 356.453087 -46.721552) (xy 356.468451 -46.669225)
			(xy 356.491104 -46.619618) (xy 356.520587 -46.573739) (xy 356.556298 -46.532522) (xy 356.597512 -46.496807)
			(xy 356.643388 -46.467321) (xy 356.692994 -46.444663) (xy 356.745319 -46.429294) (xy 356.799298 -46.421529)
			(xy 356.826566 -46.42104) (xy 357.690166 -46.42104) (xy 357.717439 -46.421497) (xy 357.77143 -46.429255)
			(xy 357.823767 -46.444619) (xy 357.873384 -46.467275) (xy 357.919272 -46.496761) (xy 357.960497 -46.532479)
			(xy 357.996218 -46.5737) (xy 358.025709 -46.619586) (xy 358.048369 -46.669202) (xy 358.063737 -46.721537)
			(xy 358.0715 -46.775527) (xy 358.0715 -46.830069) (xy 358.762026 -46.830069) (xy 358.762026 -46.775531)
			(xy 358.769788 -46.721547) (xy 358.785153 -46.669218) (xy 358.807809 -46.619608) (xy 358.837295 -46.573728)
			(xy 358.87301 -46.53251) (xy 358.914228 -46.496795) (xy 358.960108 -46.467309) (xy 359.009718 -46.444653)
			(xy 359.062047 -46.429288) (xy 359.116031 -46.421526) (xy 359.1433 -46.42104) (xy 360.0069 -46.42104)
			(xy 360.03417 -46.421522) (xy 360.088153 -46.429284) (xy 360.140483 -46.44465) (xy 360.190094 -46.467306)
			(xy 360.235975 -46.496792) (xy 360.277193 -46.532507) (xy 360.312908 -46.573725) (xy 360.342394 -46.619606)
			(xy 360.36505 -46.669217) (xy 360.380416 -46.721547) (xy 360.388178 -46.77553) (xy 360.388178 -46.83007)
			(xy 360.388178 -46.830073) (xy 361.088604 -46.830073) (xy 361.088604 -46.775527) (xy 361.096367 -46.721537)
			(xy 361.111735 -46.669202) (xy 361.134395 -46.619586) (xy 361.163887 -46.573701) (xy 361.199608 -46.53248)
			(xy 361.240833 -46.496763) (xy 361.286721 -46.467276) (xy 361.336339 -46.444621) (xy 361.388676 -46.429258)
			(xy 361.442667 -46.421501) (xy 361.46994 -46.42104) (xy 362.33354 -46.42104) (xy 362.360808 -46.421525)
			(xy 362.414787 -46.429291) (xy 362.467112 -46.44466) (xy 362.516718 -46.467319) (xy 362.562594 -46.496806)
			(xy 362.603807 -46.532522) (xy 362.639518 -46.573738) (xy 362.669 -46.619618) (xy 362.691654 -46.669225)
			(xy 362.707017 -46.721552) (xy 362.714778 -46.775532) (xy 362.714778 -46.830068) (xy 362.707017 -46.884048)
			(xy 362.691654 -46.936375) (xy 362.672751 -46.977768) (xy 396.642323 -46.977768) (xy 396.642323 -46.891996)
			(xy 396.650237 -46.806588) (xy 396.665998 -46.722276) (xy 396.689471 -46.639777) (xy 396.720456 -46.559796)
			(xy 396.758688 -46.483015) (xy 396.803842 -46.41009) (xy 396.855532 -46.341642) (xy 396.913317 -46.278255)
			(xy 396.976704 -46.22047) (xy 397.045152 -46.16878) (xy 397.118077 -46.123626) (xy 397.194858 -46.085394)
			(xy 397.274839 -46.054409) (xy 397.357338 -46.030936) (xy 397.44165 -46.015175) (xy 397.527058 -46.007261)
			(xy 397.61283 -46.007261) (xy 397.698238 -46.015175) (xy 397.78255 -46.030936) (xy 397.865049 -46.054409)
			(xy 397.94503 -46.085394) (xy 398.021811 -46.123626) (xy 398.094736 -46.16878) (xy 398.163184 -46.22047)
			(xy 398.226571 -46.278255) (xy 398.284356 -46.341642) (xy 398.336046 -46.41009) (xy 398.3812 -46.483015)
			(xy 398.419432 -46.559796) (xy 398.450417 -46.639777) (xy 398.47389 -46.722276) (xy 398.489651 -46.806588)
			(xy 398.497565 -46.891996) (xy 398.49806 -46.934882) (xy 398.497565 -46.977768) (xy 398.489651 -47.063176)
			(xy 398.47389 -47.147488) (xy 398.450417 -47.229987) (xy 398.419432 -47.309968) (xy 398.3812 -47.386749)
			(xy 398.336046 -47.459674) (xy 398.284356 -47.528122) (xy 398.226571 -47.591509) (xy 398.163184 -47.649294)
			(xy 398.094736 -47.700984) (xy 398.021811 -47.746138) (xy 397.94503 -47.78437) (xy 397.865049 -47.815355)
			(xy 397.78255 -47.838828) (xy 397.698238 -47.854589) (xy 397.61283 -47.862503) (xy 397.527058 -47.862503)
			(xy 397.44165 -47.854589) (xy 397.357338 -47.838828) (xy 397.274839 -47.815355) (xy 397.194858 -47.78437)
			(xy 397.118077 -47.746138) (xy 397.045152 -47.700984) (xy 396.976704 -47.649294) (xy 396.913317 -47.591509)
			(xy 396.855532 -47.528122) (xy 396.803842 -47.459674) (xy 396.758688 -47.386749) (xy 396.720456 -47.309968)
			(xy 396.689471 -47.229987) (xy 396.665998 -47.147488) (xy 396.650237 -47.063176) (xy 396.642323 -46.977768)
			(xy 362.672751 -46.977768) (xy 362.669 -46.985982) (xy 362.639518 -47.031862) (xy 362.603807 -47.073078)
			(xy 362.562594 -47.108794) (xy 362.516718 -47.138281) (xy 362.467112 -47.16094) (xy 362.414787 -47.176309)
			(xy 362.360808 -47.184075) (xy 362.33354 -47.184564) (xy 361.46994 -47.184564) (xy 361.442667 -47.184099)
			(xy 361.388676 -47.176342) (xy 361.336339 -47.160979) (xy 361.286721 -47.138324) (xy 361.240833 -47.108837)
			(xy 361.199608 -47.07312) (xy 361.163887 -47.031899) (xy 361.134395 -46.986014) (xy 361.111735 -46.936398)
			(xy 361.096367 -46.884063) (xy 361.088604 -46.830073) (xy 360.388178 -46.830073) (xy 360.380416 -46.884053)
			(xy 360.36505 -46.936383) (xy 360.342394 -46.985994) (xy 360.312908 -47.031875) (xy 360.277193 -47.073093)
			(xy 360.235975 -47.108808) (xy 360.190094 -47.138294) (xy 360.140483 -47.16095) (xy 360.088153 -47.176316)
			(xy 360.03417 -47.184078) (xy 360.0069 -47.184564) (xy 359.1433 -47.184564) (xy 359.116031 -47.184074)
			(xy 359.062047 -47.176312) (xy 359.009718 -47.160947) (xy 358.960108 -47.138291) (xy 358.914228 -47.108805)
			(xy 358.87301 -47.07309) (xy 358.837295 -47.031872) (xy 358.807809 -46.985992) (xy 358.785153 -46.936382)
			(xy 358.769788 -46.884053) (xy 358.762026 -46.830069) (xy 358.0715 -46.830069) (xy 358.0715 -46.830073)
			(xy 358.063737 -46.884063) (xy 358.048369 -46.936398) (xy 358.025709 -46.986014) (xy 357.996218 -47.0319)
			(xy 357.960497 -47.073121) (xy 357.919272 -47.108839) (xy 357.873384 -47.138325) (xy 357.823767 -47.160981)
			(xy 357.77143 -47.176345) (xy 357.717439 -47.184103) (xy 357.690166 -47.184564) (xy 356.826566 -47.184564)
			(xy 356.799298 -47.184071) (xy 356.745319 -47.176306) (xy 356.692994 -47.160937) (xy 356.643388 -47.138279)
			(xy 356.597512 -47.108793) (xy 356.556298 -47.073078) (xy 356.520587 -47.031861) (xy 356.491104 -46.985982)
			(xy 356.468451 -46.936375) (xy 356.453087 -46.884048) (xy 356.445326 -46.830068) (xy 182.225669 -46.830068)
			(xy 182.270213 -46.858695) (xy 182.311404 -46.894386) (xy 182.347095 -46.935577) (xy 182.376561 -46.981427)
			(xy 182.399203 -47.031004) (xy 182.414558 -47.083299) (xy 182.422314 -47.137247) (xy 182.4228 -47.164498)
			(xy 182.4228 -48.028098) (xy 182.422314 -48.055349) (xy 182.414558 -48.109297) (xy 182.399203 -48.161592)
			(xy 182.376561 -48.211169) (xy 182.347095 -48.257019) (xy 182.311404 -48.29821) (xy 182.270213 -48.333901)
			(xy 182.224363 -48.363367) (xy 182.174786 -48.386009) (xy 182.122491 -48.401364) (xy 182.068543 -48.40912)
			(xy 182.014041 -48.40912) (xy 181.960093 -48.401364) (xy 181.907798 -48.386009) (xy 181.858221 -48.363367)
			(xy 181.812371 -48.333901) (xy 181.77118 -48.29821) (xy 181.735489 -48.257019) (xy 181.706023 -48.211169)
			(xy 181.683381 -48.161592) (xy 181.668026 -48.109297) (xy 181.66027 -48.055349) (xy 181.659784 -48.028098)
			(xy 160.402353 -48.028098) (xy 160.388136 -48.076513) (xy 160.36549 -48.126097) (xy 160.336018 -48.171953)
			(xy 160.300319 -48.213147) (xy 160.259121 -48.248842) (xy 160.213262 -48.278309) (xy 160.163675 -48.30095)
			(xy 160.111372 -48.316303) (xy 160.057415 -48.324055) (xy 160.03016 -48.324516) (xy 159.16656 -48.324516)
			(xy 159.139311 -48.324012) (xy 159.085369 -48.316251) (xy 159.03308 -48.300892) (xy 158.983509 -48.278249)
			(xy 158.937664 -48.248783) (xy 158.89648 -48.213092) (xy 158.860793 -48.171903) (xy 158.831331 -48.126056)
			(xy 158.808694 -48.076482) (xy 158.793341 -48.024192) (xy 158.785586 -47.970249) (xy 157.193053 -47.970249)
			(xy 157.193053 -47.970254) (xy 157.185295 -48.024208) (xy 157.169938 -48.076509) (xy 157.147293 -48.126091)
			(xy 157.117823 -48.171946) (xy 157.082126 -48.21314) (xy 157.04093 -48.248835) (xy 156.995074 -48.278303)
			(xy 156.94549 -48.300945) (xy 156.893189 -48.316299) (xy 156.839234 -48.324054) (xy 156.81198 -48.324516)
			(xy 155.94838 -48.324516) (xy 155.92113 -48.324013) (xy 155.867186 -48.316254) (xy 155.814895 -48.300898)
			(xy 155.765321 -48.278256) (xy 155.719474 -48.24879) (xy 155.678287 -48.213099) (xy 155.642598 -48.17191)
			(xy 155.613135 -48.126062) (xy 155.590495 -48.076487) (xy 155.575142 -48.024195) (xy 155.567386 -47.97025)
			(xy 97.239575 -47.97025) (xy 97.191435 -48.108643) (xy 97.133211 -48.251809) (xy 97.067693 -48.391788)
			(xy 96.995057 -48.528208) (xy 96.915495 -48.660709) (xy 96.829216 -48.788937) (xy 96.736452 -48.912555)
			(xy 96.637446 -49.031233) (xy 96.532463 -49.144657) (xy 96.421779 -49.252526) (xy 96.30569 -49.354554)
			(xy 96.184502 -49.450471) (xy 96.140518 -49.48174) (xy 178.630072 -49.48174) (xy 178.630072 -48.61814)
			(xy 178.630558 -48.590889) (xy 178.638314 -48.536941) (xy 178.653669 -48.484646) (xy 178.676311 -48.435069)
			(xy 178.705777 -48.389219) (xy 178.741468 -48.348028) (xy 178.782659 -48.312337) (xy 178.828509 -48.282871)
			(xy 178.878086 -48.260229) (xy 178.930381 -48.244874) (xy 178.984329 -48.237118) (xy 179.038831 -48.237118)
			(xy 179.092779 -48.244874) (xy 179.145074 -48.260229) (xy 179.194651 -48.282871) (xy 179.240501 -48.312337)
			(xy 179.281692 -48.348028) (xy 179.317383 -48.389219) (xy 179.346849 -48.435069) (xy 179.369491 -48.484646)
			(xy 179.384846 -48.536941) (xy 179.392602 -48.590889) (xy 179.393088 -48.61814) (xy 179.393088 -49.48174)
			(xy 179.392602 -49.508991) (xy 179.384846 -49.562939) (xy 179.369491 -49.615234) (xy 179.346849 -49.664811)
			(xy 179.317383 -49.710661) (xy 179.281692 -49.751852) (xy 179.240501 -49.787543) (xy 179.194651 -49.817009)
			(xy 179.145074 -49.839651) (xy 179.092779 -49.855006) (xy 179.038831 -49.862762) (xy 178.984329 -49.862762)
			(xy 178.930381 -49.855006) (xy 178.878086 -49.839651) (xy 178.828509 -49.817009) (xy 178.782659 -49.787543)
			(xy 178.741468 -49.751852) (xy 178.705777 -49.710661) (xy 178.676311 -49.664811) (xy 178.653669 -49.615234)
			(xy 178.638314 -49.562939) (xy 178.630558 -49.508991) (xy 178.630072 -49.48174) (xy 96.140518 -49.48174)
			(xy 96.058537 -49.540022) (xy 95.928129 -49.62297) (xy 95.793624 -49.699095) (xy 95.655379 -49.768194)
			(xy 95.513759 -49.830085) (xy 95.369142 -49.884604) (xy 95.221909 -49.931606) (xy 95.072452 -49.970966)
			(xy 94.921168 -50.00258) (xy 94.768456 -50.026364) (xy 94.614722 -50.042255) (xy 94.460374 -50.050211)
			(xy 94.383098 -50.0507) (xy 92.782898 -50.0507) (xy 92.705622 -50.050194) (xy 92.551275 -50.042238)
			(xy 92.397543 -50.026347) (xy 92.244832 -50.002563) (xy 92.093548 -49.970949) (xy 91.944092 -49.931589)
			(xy 91.796861 -49.884587) (xy 91.652244 -49.830069) (xy 91.510626 -49.768178) (xy 91.372381 -49.699079)
			(xy 91.237877 -49.622954) (xy 91.10747 -49.540007) (xy 90.981506 -49.450456) (xy 90.860319 -49.35454)
			(xy 90.74423 -49.252512) (xy 90.633548 -49.144644) (xy 90.528565 -49.031221) (xy 90.42956 -48.912543)
			(xy 90.336796 -48.788927) (xy 90.250519 -48.660699) (xy 90.170957 -48.528199) (xy 90.098321 -48.391779)
			(xy 90.032804 -48.251802) (xy 89.97458 -48.108637) (xy 89.923803 -47.962664) (xy 89.880608 -47.814271)
			(xy 89.84511 -47.663852) (xy 89.817402 -47.511804) (xy 89.797557 -47.358531) (xy 89.78563 -47.204441)
			(xy 89.78165 -47.04994) (xy 67.384154 -47.04994) (xy 67.384157 -47.050067) (xy 67.380172 -47.204564)
			(xy 67.368238 -47.35865) (xy 67.348389 -47.511918) (xy 67.320675 -47.663961) (xy 67.285172 -47.814376)
			(xy 67.241973 -47.962763) (xy 67.191193 -48.108731) (xy 67.132966 -48.25189) (xy 67.067447 -48.391863)
			(xy 66.994809 -48.528277) (xy 66.915245 -48.660771) (xy 66.828966 -48.788993) (xy 66.736201 -48.912605)
			(xy 66.637196 -49.031277) (xy 66.532213 -49.144695) (xy 66.421531 -49.252559) (xy 66.305444 -49.354582)
			(xy 66.184258 -49.450493) (xy 66.058295 -49.54004) (xy 65.927891 -49.622983) (xy 65.793389 -49.699104)
			(xy 65.655147 -49.768199) (xy 65.513531 -49.830087) (xy 65.368918 -49.884603) (xy 65.22169 -49.931602)
			(xy 65.072237 -49.970961) (xy 64.920957 -50.002573) (xy 64.76825 -50.026356) (xy 64.614521 -50.042247)
			(xy 64.460178 -50.050202) (xy 64.382904 -50.0507) (xy 62.78245 -50.0507) (xy 62.705176 -50.050188)
			(xy 62.550834 -50.04222) (xy 62.397107 -50.026316) (xy 62.244402 -50.002521) (xy 62.093124 -49.970896)
			(xy 61.943675 -49.931526) (xy 61.796451 -49.884514) (xy 61.651842 -49.829987) (xy 61.510232 -49.768087)
			(xy 61.371996 -49.69898) (xy 61.2375 -49.622848) (xy 61.107102 -49.539894) (xy 60.981148 -49.450337)
			(xy 60.85997 -49.354416) (xy 60.743891 -49.252383) (xy 60.633218 -49.14451) (xy 60.528245 -49.031083)
			(xy 60.429249 -48.912403) (xy 60.336495 -48.788784) (xy 60.250227 -48.660555) (xy 60.170674 -48.528054)
			(xy 60.098048 -48.391634) (xy 60.032541 -48.251656) (xy 59.974326 -48.108492) (xy 59.923558 -47.96252)
			(xy 59.880371 -47.814129) (xy 59.844881 -47.663712) (xy 59.81718 -47.511667) (xy 59.797344 -47.358397)
			(xy 59.785423 -47.20431) (xy 59.781451 -47.049813) (xy 0.509016 -47.049813) (xy 0.509016 -50.949098)
			(xy 181.659784 -50.949098) (xy 181.659784 -50.085498) (xy 181.66027 -50.058247) (xy 181.668026 -50.004299)
			(xy 181.683381 -49.952004) (xy 181.706023 -49.902427) (xy 181.735489 -49.856577) (xy 181.77118 -49.815386)
			(xy 181.812371 -49.779695) (xy 181.858221 -49.750229) (xy 181.907798 -49.727587) (xy 181.960093 -49.712232)
			(xy 182.014041 -49.704476) (xy 182.068543 -49.704476) (xy 182.122491 -49.712232) (xy 182.174786 -49.727587)
			(xy 182.224363 -49.750229) (xy 182.270213 -49.779695) (xy 182.311404 -49.815386) (xy 182.347095 -49.856577)
			(xy 182.376561 -49.902427) (xy 182.399203 -49.952004) (xy 182.414558 -50.004299) (xy 182.422314 -50.058247)
			(xy 182.4228 -50.085498) (xy 182.4228 -50.949098) (xy 182.422314 -50.976349) (xy 182.414558 -51.030297)
			(xy 182.399203 -51.082592) (xy 182.376561 -51.132169) (xy 182.347095 -51.178019) (xy 182.311404 -51.21921)
			(xy 182.270213 -51.254901) (xy 182.224363 -51.284367) (xy 182.174786 -51.307009) (xy 182.122491 -51.322364)
			(xy 182.068543 -51.33012) (xy 182.014041 -51.33012) (xy 181.960093 -51.322364) (xy 181.907798 -51.307009)
			(xy 181.858221 -51.284367) (xy 181.812371 -51.254901) (xy 181.77118 -51.21921) (xy 181.735489 -51.178019)
			(xy 181.706023 -51.132169) (xy 181.683381 -51.082592) (xy 181.668026 -51.030297) (xy 181.66027 -50.976349)
			(xy 181.659784 -50.949098) (xy 0.509016 -50.949098) (xy 0.509016 -52.481734) (xy 178.630072 -52.481734)
			(xy 178.630072 -51.618134) (xy 178.630558 -51.590883) (xy 178.638314 -51.536935) (xy 178.653669 -51.48464)
			(xy 178.676311 -51.435063) (xy 178.705777 -51.389213) (xy 178.741468 -51.348022) (xy 178.782659 -51.312331)
			(xy 178.828509 -51.282865) (xy 178.878086 -51.260223) (xy 178.930381 -51.244868) (xy 178.984329 -51.237112)
			(xy 179.038831 -51.237112) (xy 179.092779 -51.244868) (xy 179.145074 -51.260223) (xy 179.194651 -51.282865)
			(xy 179.240501 -51.312331) (xy 179.281692 -51.348022) (xy 179.317383 -51.389213) (xy 179.346849 -51.435063)
			(xy 179.369491 -51.48464) (xy 179.384846 -51.536935) (xy 179.392602 -51.590883) (xy 179.393088 -51.618134)
			(xy 179.393088 -51.999896) (xy 201.367397 -51.999896) (xy 201.371407 -51.837793) (xy 201.38343 -51.676088)
			(xy 201.403434 -51.515174) (xy 201.431372 -51.355447) (xy 201.467175 -51.197297) (xy 201.510755 -51.041111)
			(xy 201.562006 -50.887271) (xy 201.620802 -50.736154) (xy 201.687 -50.58813) (xy 201.760436 -50.44356)
			(xy 201.840933 -50.302799) (xy 201.928292 -50.166191) (xy 202.0223 -50.034071) (xy 202.122727 -49.906761)
			(xy 202.229327 -49.784573) (xy 202.341839 -49.667807) (xy 202.459987 -49.556748) (xy 202.583484 -49.451667)
			(xy 202.712026 -49.352823) (xy 202.845299 -49.260456) (xy 202.982977 -49.174793) (xy 203.124723 -49.096044)
			(xy 203.27019 -49.024401) (xy 203.419022 -48.960039) (xy 203.570854 -48.903117) (xy 203.725316 -48.853773)
			(xy 203.882029 -48.812128) (xy 204.04061 -48.778283) (xy 204.200671 -48.752323) (xy 204.361819 -48.73431)
			(xy 204.523661 -48.724289) (xy 204.685801 -48.722283) (xy 204.847842 -48.728299) (xy 205.009386 -48.74232)
			(xy 205.17004 -48.764313) (xy 205.32941 -48.794225) (xy 205.487105 -48.831981) (xy 205.64274 -48.877489)
			(xy 205.795934 -48.930639) (xy 205.946312 -48.9913) (xy 206.093507 -49.059323) (xy 206.237157 -49.134542)
			(xy 206.376912 -49.216773) (xy 206.512428 -49.305815) (xy 206.643376 -49.40145) (xy 206.769434 -49.503444)
			(xy 206.890294 -49.611547) (xy 207.00566 -49.725494) (xy 207.115249 -49.845008) (xy 207.218794 -49.969795)
			(xy 207.316041 -50.09955) (xy 207.406753 -50.233955) (xy 207.424818 -50.263806) (xy 239.457992 -50.263806)
			(xy 239.457992 -49.400206) (xy 239.458478 -49.372955) (xy 239.466234 -49.319007) (xy 239.481589 -49.266712)
			(xy 239.504231 -49.217135) (xy 239.533697 -49.171285) (xy 239.569388 -49.130094) (xy 239.610579 -49.094403)
			(xy 239.656429 -49.064937) (xy 239.706006 -49.042295) (xy 239.758301 -49.02694) (xy 239.812249 -49.019184)
			(xy 239.866751 -49.019184) (xy 239.920699 -49.02694) (xy 239.972994 -49.042295) (xy 240.022571 -49.064937)
			(xy 240.068421 -49.094403) (xy 240.109612 -49.130094) (xy 240.145303 -49.171285) (xy 240.174769 -49.217135)
			(xy 240.197411 -49.266712) (xy 240.212766 -49.319007) (xy 240.220522 -49.372955) (xy 240.221008 -49.400206)
			(xy 240.221008 -50.263806) (xy 240.220522 -50.291057) (xy 240.212766 -50.345005) (xy 240.197411 -50.3973)
			(xy 240.174769 -50.446877) (xy 240.145303 -50.492727) (xy 240.109612 -50.533918) (xy 240.068421 -50.569609)
			(xy 240.022571 -50.599075) (xy 239.972994 -50.621717) (xy 239.920699 -50.637072) (xy 239.866751 -50.644828)
			(xy 239.812249 -50.644828) (xy 239.758301 -50.637072) (xy 239.706006 -50.621717) (xy 239.656429 -50.599075)
			(xy 239.610579 -50.569609) (xy 239.569388 -50.533918) (xy 239.533697 -50.492727) (xy 239.504231 -50.446877)
			(xy 239.481589 -50.3973) (xy 239.466234 -50.345005) (xy 239.458478 -50.291057) (xy 239.457992 -50.263806)
			(xy 207.424818 -50.263806) (xy 207.490706 -50.372682) (xy 207.567696 -50.515391) (xy 207.637535 -50.661732)
			(xy 207.70005 -50.811349) (xy 207.755091 -50.963874) (xy 207.802521 -51.118934) (xy 207.842224 -51.27615)
			(xy 207.874105 -51.435138) (xy 207.898083 -51.595507) (xy 207.914102 -51.756866) (xy 207.922121 -51.91882)
			(xy 207.922622 -51.999896) (xy 207.922121 -52.080972) (xy 207.914102 -52.242926) (xy 207.898083 -52.404285)
			(xy 207.874105 -52.564654) (xy 207.842224 -52.723642) (xy 207.802521 -52.880858) (xy 207.794624 -52.906676)
			(xy 228.815392 -52.906676) (xy 228.815392 -52.043076) (xy 228.815878 -52.015825) (xy 228.823634 -51.961877)
			(xy 228.838989 -51.909582) (xy 228.861631 -51.860005) (xy 228.891097 -51.814155) (xy 228.926788 -51.772964)
			(xy 228.967979 -51.737273) (xy 229.013829 -51.707807) (xy 229.063406 -51.685165) (xy 229.115701 -51.66981)
			(xy 229.169649 -51.662054) (xy 229.224151 -51.662054) (xy 229.278099 -51.66981) (xy 229.330394 -51.685165)
			(xy 229.379971 -51.707807) (xy 229.425821 -51.737273) (xy 229.467012 -51.772964) (xy 229.502703 -51.814155)
			(xy 229.532169 -51.860005) (xy 229.554811 -51.909582) (xy 229.570166 -51.961877) (xy 229.577922 -52.015825)
			(xy 229.578408 -52.043076) (xy 229.578408 -52.90185) (xy 241.926872 -52.90185) (xy 241.926872 -52.03825)
			(xy 241.927358 -52.010999) (xy 241.935114 -51.957051) (xy 241.950469 -51.904756) (xy 241.973111 -51.855179)
			(xy 242.002577 -51.809329) (xy 242.038268 -51.768138) (xy 242.079459 -51.732447) (xy 242.125309 -51.702981)
			(xy 242.174886 -51.680339) (xy 242.227181 -51.664984) (xy 242.281129 -51.657228) (xy 242.335631 -51.657228)
			(xy 242.389579 -51.664984) (xy 242.441874 -51.680339) (xy 242.491451 -51.702981) (xy 242.537301 -51.732447)
			(xy 242.578492 -51.768138) (xy 242.614183 -51.809329) (xy 242.643649 -51.855179) (xy 242.666291 -51.904756)
			(xy 242.681646 -51.957051) (xy 242.687806 -51.999896) (xy 265.367269 -51.999896) (xy 265.371279 -51.837793)
			(xy 265.383302 -51.676088) (xy 265.403306 -51.515174) (xy 265.431244 -51.355447) (xy 265.467047 -51.197297)
			(xy 265.510627 -51.041111) (xy 265.561878 -50.887271) (xy 265.620674 -50.736154) (xy 265.686872 -50.58813)
			(xy 265.760308 -50.44356) (xy 265.840805 -50.302799) (xy 265.928164 -50.166191) (xy 266.022172 -50.034071)
			(xy 266.122599 -49.906761) (xy 266.229199 -49.784573) (xy 266.341711 -49.667807) (xy 266.459859 -49.556748)
			(xy 266.583356 -49.451667) (xy 266.711898 -49.352823) (xy 266.845171 -49.260456) (xy 266.982849 -49.174793)
			(xy 267.124595 -49.096044) (xy 267.270062 -49.024401) (xy 267.418894 -48.960039) (xy 267.570726 -48.903117)
			(xy 267.725188 -48.853773) (xy 267.881901 -48.812128) (xy 268.040482 -48.778283) (xy 268.200543 -48.752323)
			(xy 268.361691 -48.73431) (xy 268.523533 -48.724289) (xy 268.685673 -48.722283) (xy 268.847714 -48.728299)
			(xy 269.009258 -48.74232) (xy 269.169912 -48.764313) (xy 269.329282 -48.794225) (xy 269.486977 -48.831981)
			(xy 269.642612 -48.877489) (xy 269.795806 -48.930639) (xy 269.946184 -48.9913) (xy 270.093379 -49.059323)
			(xy 270.237029 -49.134542) (xy 270.376784 -49.216773) (xy 270.5123 -49.305815) (xy 270.643248 -49.40145)
			(xy 270.769306 -49.503444) (xy 270.890166 -49.611547) (xy 271.005532 -49.725494) (xy 271.115121 -49.845008)
			(xy 271.218666 -49.969795) (xy 271.315913 -50.09955) (xy 271.406625 -50.233955) (xy 271.40723 -50.234955)
			(xy 350.291827 -50.234955) (xy 350.291827 -50.180445) (xy 350.299585 -50.126489) (xy 350.314942 -50.074187)
			(xy 350.337587 -50.024602) (xy 350.367058 -49.978745) (xy 350.402755 -49.937549) (xy 350.443952 -49.901853)
			(xy 350.489809 -49.872383) (xy 350.539394 -49.849739) (xy 350.591697 -49.834383) (xy 350.645653 -49.826626)
			(xy 350.672908 -49.826164) (xy 351.536508 -49.826164) (xy 351.563757 -49.826707) (xy 351.6177 -49.834464)
			(xy 351.66999 -49.849818) (xy 351.719562 -49.872458) (xy 351.765408 -49.901922) (xy 351.806594 -49.937611)
			(xy 351.842282 -49.978798) (xy 351.871746 -50.024645) (xy 351.894385 -50.074218) (xy 351.909738 -50.126508)
			(xy 351.917494 -50.180451) (xy 351.917494 -50.234949) (xy 351.917493 -50.234956) (xy 352.489927 -50.234956)
			(xy 352.489927 -50.180444) (xy 352.497685 -50.126487) (xy 352.513044 -50.074183) (xy 352.535689 -50.024598)
			(xy 352.565162 -49.97874) (xy 352.600861 -49.937544) (xy 352.642059 -49.901848) (xy 352.687919 -49.872378)
			(xy 352.737506 -49.849735) (xy 352.78981 -49.83438) (xy 352.843768 -49.826625) (xy 352.871024 -49.826164)
			(xy 353.734624 -49.826164) (xy 353.761872 -49.826708) (xy 353.815813 -49.834467) (xy 353.868101 -49.849823)
			(xy 353.917672 -49.872463) (xy 353.963516 -49.901928) (xy 354.0047 -49.937617) (xy 354.040386 -49.978804)
			(xy 354.069848 -50.024649) (xy 354.092486 -50.074221) (xy 354.107839 -50.12651) (xy 354.115594 -50.180452)
			(xy 354.115594 -50.234948) (xy 354.115593 -50.234956) (xy 354.712427 -50.234956) (xy 354.712427 -50.180444)
			(xy 354.720185 -50.126487) (xy 354.735544 -50.074183) (xy 354.758189 -50.024598) (xy 354.787662 -49.97874)
			(xy 354.823361 -49.937544) (xy 354.864559 -49.901848) (xy 354.910419 -49.872378) (xy 354.960006 -49.849735)
			(xy 355.01231 -49.83438) (xy 355.066268 -49.826625) (xy 355.093524 -49.826164) (xy 355.957124 -49.826164)
			(xy 355.984372 -49.826708) (xy 356.038313 -49.834467) (xy 356.090601 -49.849823) (xy 356.140172 -49.872463)
			(xy 356.186016 -49.901928) (xy 356.2272 -49.937617) (xy 356.262886 -49.978804) (xy 356.292348 -50.024649)
			(xy 356.314986 -50.074221) (xy 356.330339 -50.12651) (xy 356.338094 -50.180452) (xy 356.338094 -50.234948)
			(xy 356.338093 -50.234957) (xy 356.942527 -50.234957) (xy 356.942527 -50.180443) (xy 356.950286 -50.126484)
			(xy 356.965645 -50.074179) (xy 356.988293 -50.024592) (xy 357.017767 -49.978734) (xy 357.053468 -49.937537)
			(xy 357.094669 -49.90184) (xy 357.140531 -49.872371) (xy 357.19012 -49.84973) (xy 357.242427 -49.834376)
			(xy 357.296387 -49.826624) (xy 357.323644 -49.826164) (xy 358.187244 -49.826164) (xy 358.214491 -49.826709)
			(xy 358.26843 -49.83447) (xy 358.320716 -49.849828) (xy 358.370284 -49.87247) (xy 358.416125 -49.901935)
			(xy 358.457307 -49.937624) (xy 358.492991 -49.97881) (xy 358.522451 -50.024655) (xy 358.545087 -50.074226)
			(xy 358.560439 -50.126513) (xy 358.568194 -50.180453) (xy 358.568194 -50.234947) (xy 358.560439 -50.288887)
			(xy 358.545087 -50.341174) (xy 358.522451 -50.390745) (xy 358.492991 -50.43659) (xy 358.457307 -50.477776)
			(xy 358.416125 -50.513465) (xy 358.370284 -50.54293) (xy 358.320716 -50.565572) (xy 358.26843 -50.58093)
			(xy 358.214491 -50.588691) (xy 358.187244 -50.58918) (xy 357.323644 -50.58918) (xy 357.296387 -50.588776)
			(xy 357.242427 -50.581024) (xy 357.19012 -50.56567) (xy 357.140531 -50.543029) (xy 357.094669 -50.51356)
			(xy 357.053468 -50.477863) (xy 357.017767 -50.436666) (xy 356.988293 -50.390808) (xy 356.965645 -50.341221)
			(xy 356.950286 -50.288916) (xy 356.942527 -50.234957) (xy 356.338093 -50.234957) (xy 356.330339 -50.28889)
			(xy 356.314986 -50.341179) (xy 356.292348 -50.390751) (xy 356.262886 -50.436596) (xy 356.2272 -50.477783)
			(xy 356.186016 -50.513472) (xy 356.140172 -50.542937) (xy 356.090601 -50.565577) (xy 356.038313 -50.580933)
			(xy 355.984372 -50.588692) (xy 355.957124 -50.58918) (xy 355.093524 -50.58918) (xy 355.066268 -50.588775)
			(xy 355.01231 -50.58102) (xy 354.960006 -50.565665) (xy 354.910419 -50.543022) (xy 354.864559 -50.513552)
			(xy 354.823361 -50.477856) (xy 354.787662 -50.43666) (xy 354.758189 -50.390802) (xy 354.735544 -50.341217)
			(xy 354.720185 -50.288913) (xy 354.712427 -50.234956) (xy 354.115593 -50.234956) (xy 354.107839 -50.28889)
			(xy 354.092486 -50.341179) (xy 354.069848 -50.390751) (xy 354.040386 -50.436596) (xy 354.0047 -50.477783)
			(xy 353.963516 -50.513472) (xy 353.917672 -50.542937) (xy 353.868101 -50.565577) (xy 353.815813 -50.580933)
			(xy 353.761872 -50.588692) (xy 353.734624 -50.58918) (xy 352.871024 -50.58918) (xy 352.843768 -50.588775)
			(xy 352.78981 -50.58102) (xy 352.737506 -50.565665) (xy 352.687919 -50.543022) (xy 352.642059 -50.513552)
			(xy 352.600861 -50.477856) (xy 352.565162 -50.43666) (xy 352.535689 -50.390802) (xy 352.513044 -50.341217)
			(xy 352.497685 -50.288913) (xy 352.489927 -50.234956) (xy 351.917493 -50.234956) (xy 351.909738 -50.288892)
			(xy 351.894385 -50.341182) (xy 351.871746 -50.390755) (xy 351.842282 -50.436602) (xy 351.806594 -50.477789)
			(xy 351.765408 -50.513477) (xy 351.719562 -50.542942) (xy 351.66999 -50.565582) (xy 351.6177 -50.580936)
			(xy 351.563757 -50.588693) (xy 351.536508 -50.58918) (xy 350.672908 -50.58918) (xy 350.645653 -50.588774)
			(xy 350.591697 -50.581017) (xy 350.539394 -50.565661) (xy 350.489809 -50.543017) (xy 350.443952 -50.513547)
			(xy 350.402755 -50.477851) (xy 350.367058 -50.436655) (xy 350.337587 -50.390798) (xy 350.314942 -50.341213)
			(xy 350.299585 -50.288911) (xy 350.291827 -50.234955) (xy 271.40723 -50.234955) (xy 271.490578 -50.372682)
			(xy 271.567568 -50.515391) (xy 271.637407 -50.661732) (xy 271.699922 -50.811349) (xy 271.754963 -50.963874)
			(xy 271.802393 -51.118934) (xy 271.842096 -51.27615) (xy 271.873977 -51.435138) (xy 271.897955 -51.595507)
			(xy 271.913974 -51.756866) (xy 271.921993 -51.91882) (xy 271.922494 -51.999896) (xy 271.921993 -52.080972)
			(xy 271.913974 -52.242926) (xy 271.897955 -52.404285) (xy 271.873977 -52.564654) (xy 271.842096 -52.723642)
			(xy 271.802393 -52.880858) (xy 271.754963 -53.035918) (xy 271.699922 -53.188443) (xy 271.637407 -53.33806)
			(xy 271.567568 -53.484401) (xy 271.490578 -53.62711) (xy 271.406625 -53.765837) (xy 271.315913 -53.900242)
			(xy 271.218666 -54.029997) (xy 271.115121 -54.154784) (xy 271.005532 -54.274298) (xy 270.890166 -54.388245)
			(xy 270.769306 -54.496348) (xy 270.643248 -54.598342) (xy 270.5123 -54.693977) (xy 270.376784 -54.783019)
			(xy 270.237029 -54.86525) (xy 270.093379 -54.940469) (xy 269.946184 -55.008492) (xy 269.795806 -55.069153)
			(xy 269.642612 -55.122303) (xy 269.486977 -55.167811) (xy 269.329282 -55.205567) (xy 269.169912 -55.235479)
			(xy 269.009258 -55.257472) (xy 268.847714 -55.271493) (xy 268.685673 -55.277509) (xy 268.523533 -55.275503)
			(xy 268.361691 -55.265482) (xy 268.200543 -55.247469) (xy 268.040482 -55.221509) (xy 267.881901 -55.187664)
			(xy 267.725188 -55.146019) (xy 267.570726 -55.096675) (xy 267.418894 -55.039753) (xy 267.270062 -54.975391)
			(xy 267.124595 -54.903748) (xy 266.982849 -54.824999) (xy 266.845171 -54.739336) (xy 266.711898 -54.646969)
			(xy 266.583356 -54.548125) (xy 266.459859 -54.443044) (xy 266.341711 -54.331985) (xy 266.229199 -54.215219)
			(xy 266.122599 -54.093031) (xy 266.022172 -53.965721) (xy 265.928164 -53.833601) (xy 265.840805 -53.696993)
			(xy 265.760308 -53.556232) (xy 265.686872 -53.411662) (xy 265.620674 -53.263638) (xy 265.561878 -53.112521)
			(xy 265.510627 -52.958681) (xy 265.467047 -52.802495) (xy 265.431244 -52.644345) (xy 265.403306 -52.484618)
			(xy 265.383302 -52.323704) (xy 265.371279 -52.161999) (xy 265.367269 -51.999896) (xy 242.687806 -51.999896)
			(xy 242.689402 -52.010999) (xy 242.689888 -52.03825) (xy 242.689888 -52.90185) (xy 242.689402 -52.929101)
			(xy 242.681646 -52.983049) (xy 242.666291 -53.035344) (xy 242.643649 -53.084921) (xy 242.614183 -53.130771)
			(xy 242.578492 -53.171962) (xy 242.537301 -53.207653) (xy 242.491451 -53.237119) (xy 242.441874 -53.259761)
			(xy 242.389579 -53.275116) (xy 242.335631 -53.282872) (xy 242.281129 -53.282872) (xy 242.227181 -53.275116)
			(xy 242.174886 -53.259761) (xy 242.125309 -53.237119) (xy 242.079459 -53.207653) (xy 242.038268 -53.171962)
			(xy 242.002577 -53.130771) (xy 241.973111 -53.084921) (xy 241.950469 -53.035344) (xy 241.935114 -52.983049)
			(xy 241.927358 -52.929101) (xy 241.926872 -52.90185) (xy 229.578408 -52.90185) (xy 229.578408 -52.906676)
			(xy 229.577922 -52.933927) (xy 229.570166 -52.987875) (xy 229.554811 -53.04017) (xy 229.532169 -53.089747)
			(xy 229.502703 -53.135597) (xy 229.467012 -53.176788) (xy 229.425821 -53.212479) (xy 229.379971 -53.241945)
			(xy 229.330394 -53.264587) (xy 229.278099 -53.279942) (xy 229.224151 -53.287698) (xy 229.169649 -53.287698)
			(xy 229.115701 -53.279942) (xy 229.063406 -53.264587) (xy 229.013829 -53.241945) (xy 228.967979 -53.212479)
			(xy 228.926788 -53.176788) (xy 228.891097 -53.135597) (xy 228.861631 -53.089747) (xy 228.838989 -53.04017)
			(xy 228.823634 -52.987875) (xy 228.815878 -52.933927) (xy 228.815392 -52.906676) (xy 207.794624 -52.906676)
			(xy 207.755091 -53.035918) (xy 207.70005 -53.188443) (xy 207.637535 -53.33806) (xy 207.567696 -53.484401)
			(xy 207.490706 -53.62711) (xy 207.406753 -53.765837) (xy 207.316041 -53.900242) (xy 207.218794 -54.029997)
			(xy 207.115249 -54.154784) (xy 207.00566 -54.274298) (xy 206.890294 -54.388245) (xy 206.769434 -54.496348)
			(xy 206.643376 -54.598342) (xy 206.512428 -54.693977) (xy 206.493338 -54.70652) (xy 230.115872 -54.70652)
			(xy 230.115872 -53.84292) (xy 230.116358 -53.815669) (xy 230.124114 -53.761721) (xy 230.139469 -53.709426)
			(xy 230.162111 -53.659849) (xy 230.191577 -53.613999) (xy 230.227268 -53.572808) (xy 230.268459 -53.537117)
			(xy 230.314309 -53.507651) (xy 230.363886 -53.485009) (xy 230.416181 -53.469654) (xy 230.470129 -53.461898)
			(xy 230.524631 -53.461898) (xy 230.578579 -53.469654) (xy 230.630874 -53.485009) (xy 230.680451 -53.507651)
			(xy 230.726301 -53.537117) (xy 230.767492 -53.572808) (xy 230.803183 -53.613999) (xy 230.832649 -53.659849)
			(xy 230.855291 -53.709426) (xy 230.870646 -53.761721) (xy 230.878402 -53.815669) (xy 230.878888 -53.84292)
			(xy 230.878888 -54.70652) (xy 230.878811 -54.710838) (xy 240.282476 -54.710838) (xy 240.282476 -53.847238)
			(xy 240.282962 -53.819987) (xy 240.290718 -53.766039) (xy 240.306073 -53.713744) (xy 240.328715 -53.664167)
			(xy 240.358181 -53.618317) (xy 240.393872 -53.577126) (xy 240.435063 -53.541435) (xy 240.480913 -53.511969)
			(xy 240.53049 -53.489327) (xy 240.582785 -53.473972) (xy 240.636733 -53.466216) (xy 240.691235 -53.466216)
			(xy 240.745183 -53.473972) (xy 240.797478 -53.489327) (xy 240.847055 -53.511969) (xy 240.892905 -53.541435)
			(xy 240.934096 -53.577126) (xy 240.969787 -53.618317) (xy 240.999253 -53.664167) (xy 241.021895 -53.713744)
			(xy 241.03725 -53.766039) (xy 241.045006 -53.819987) (xy 241.045492 -53.847238) (xy 241.045492 -54.710838)
			(xy 241.045006 -54.738089) (xy 241.03725 -54.792037) (xy 241.021895 -54.844332) (xy 240.999253 -54.893909)
			(xy 240.969787 -54.939759) (xy 240.934096 -54.98095) (xy 240.892905 -55.016641) (xy 240.847055 -55.046107)
			(xy 240.797478 -55.068749) (xy 240.745183 -55.084104) (xy 240.691235 -55.09186) (xy 240.636733 -55.09186)
			(xy 240.582785 -55.084104) (xy 240.53049 -55.068749) (xy 240.480913 -55.046107) (xy 240.435063 -55.016641)
			(xy 240.393872 -54.98095) (xy 240.358181 -54.939759) (xy 240.328715 -54.893909) (xy 240.306073 -54.844332)
			(xy 240.290718 -54.792037) (xy 240.282962 -54.738089) (xy 240.282476 -54.710838) (xy 230.878811 -54.710838)
			(xy 230.878402 -54.733771) (xy 230.870646 -54.787719) (xy 230.855291 -54.840014) (xy 230.832649 -54.889591)
			(xy 230.803183 -54.935441) (xy 230.767492 -54.976632) (xy 230.726301 -55.012323) (xy 230.680451 -55.041789)
			(xy 230.630874 -55.064431) (xy 230.578579 -55.079786) (xy 230.524631 -55.087542) (xy 230.470129 -55.087542)
			(xy 230.416181 -55.079786) (xy 230.363886 -55.064431) (xy 230.314309 -55.041789) (xy 230.268459 -55.012323)
			(xy 230.227268 -54.976632) (xy 230.191577 -54.935441) (xy 230.162111 -54.889591) (xy 230.139469 -54.840014)
			(xy 230.124114 -54.787719) (xy 230.116358 -54.733771) (xy 230.115872 -54.70652) (xy 206.493338 -54.70652)
			(xy 206.376912 -54.783019) (xy 206.237157 -54.86525) (xy 206.093507 -54.940469) (xy 205.946312 -55.008492)
			(xy 205.795934 -55.069153) (xy 205.64274 -55.122303) (xy 205.487105 -55.167811) (xy 205.32941 -55.205567)
			(xy 205.17004 -55.235479) (xy 205.009386 -55.257472) (xy 204.847842 -55.271493) (xy 204.685801 -55.277509)
			(xy 204.523661 -55.275503) (xy 204.361819 -55.265482) (xy 204.200671 -55.247469) (xy 204.04061 -55.221509)
			(xy 203.882029 -55.187664) (xy 203.725316 -55.146019) (xy 203.570854 -55.096675) (xy 203.419022 -55.039753)
			(xy 203.27019 -54.975391) (xy 203.124723 -54.903748) (xy 202.982977 -54.824999) (xy 202.845299 -54.739336)
			(xy 202.712026 -54.646969) (xy 202.583484 -54.548125) (xy 202.459987 -54.443044) (xy 202.341839 -54.331985)
			(xy 202.229327 -54.215219) (xy 202.122727 -54.093031) (xy 202.0223 -53.965721) (xy 201.928292 -53.833601)
			(xy 201.840933 -53.696993) (xy 201.760436 -53.556232) (xy 201.687 -53.411662) (xy 201.620802 -53.263638)
			(xy 201.562006 -53.112521) (xy 201.510755 -52.958681) (xy 201.467175 -52.802495) (xy 201.431372 -52.644345)
			(xy 201.403434 -52.484618) (xy 201.38343 -52.323704) (xy 201.371407 -52.161999) (xy 201.367397 -51.999896)
			(xy 179.393088 -51.999896) (xy 179.393088 -52.481734) (xy 179.392602 -52.508985) (xy 179.384846 -52.562933)
			(xy 179.369491 -52.615228) (xy 179.346849 -52.664805) (xy 179.317383 -52.710655) (xy 179.281692 -52.751846)
			(xy 179.240501 -52.787537) (xy 179.194651 -52.817003) (xy 179.145074 -52.839645) (xy 179.092779 -52.855)
			(xy 179.038831 -52.862756) (xy 178.984329 -52.862756) (xy 178.930381 -52.855) (xy 178.878086 -52.839645)
			(xy 178.828509 -52.817003) (xy 178.782659 -52.787537) (xy 178.741468 -52.751846) (xy 178.705777 -52.710655)
			(xy 178.676311 -52.664805) (xy 178.653669 -52.615228) (xy 178.638314 -52.562933) (xy 178.630558 -52.508985)
			(xy 178.630072 -52.481734) (xy 0.509016 -52.481734) (xy 0.509016 -53.954934) (xy 181.659784 -53.954934)
			(xy 181.659784 -53.091334) (xy 181.66027 -53.064083) (xy 181.668026 -53.010135) (xy 181.683381 -52.95784)
			(xy 181.706023 -52.908263) (xy 181.735489 -52.862413) (xy 181.77118 -52.821222) (xy 181.812371 -52.785531)
			(xy 181.858221 -52.756065) (xy 181.907798 -52.733423) (xy 181.960093 -52.718068) (xy 182.014041 -52.710312)
			(xy 182.068543 -52.710312) (xy 182.122491 -52.718068) (xy 182.174786 -52.733423) (xy 182.224363 -52.756065)
			(xy 182.270213 -52.785531) (xy 182.311404 -52.821222) (xy 182.347095 -52.862413) (xy 182.376561 -52.908263)
			(xy 182.399203 -52.95784) (xy 182.414558 -53.010135) (xy 182.422314 -53.064083) (xy 182.4228 -53.091334)
			(xy 182.4228 -53.954934) (xy 182.422314 -53.982185) (xy 182.414558 -54.036133) (xy 182.399203 -54.088428)
			(xy 182.376561 -54.138005) (xy 182.347095 -54.183855) (xy 182.311404 -54.225046) (xy 182.270213 -54.260737)
			(xy 182.224363 -54.290203) (xy 182.174786 -54.312845) (xy 182.122491 -54.3282) (xy 182.068543 -54.335956)
			(xy 182.014041 -54.335956) (xy 181.960093 -54.3282) (xy 181.907798 -54.312845) (xy 181.858221 -54.290203)
			(xy 181.812371 -54.260737) (xy 181.77118 -54.225046) (xy 181.735489 -54.183855) (xy 181.706023 -54.138005)
			(xy 181.683381 -54.088428) (xy 181.668026 -54.036133) (xy 181.66027 -53.982185) (xy 181.659784 -53.954934)
			(xy 0.509016 -53.954934) (xy 0.509016 -55.481728) (xy 178.630072 -55.481728) (xy 178.630072 -54.618128)
			(xy 178.630558 -54.590877) (xy 178.638314 -54.536929) (xy 178.653669 -54.484634) (xy 178.676311 -54.435057)
			(xy 178.705777 -54.389207) (xy 178.741468 -54.348016) (xy 178.782659 -54.312325) (xy 178.828509 -54.282859)
			(xy 178.878086 -54.260217) (xy 178.930381 -54.244862) (xy 178.984329 -54.237106) (xy 179.038831 -54.237106)
			(xy 179.092779 -54.244862) (xy 179.145074 -54.260217) (xy 179.194651 -54.282859) (xy 179.240501 -54.312325)
			(xy 179.281692 -54.348016) (xy 179.317383 -54.389207) (xy 179.346849 -54.435057) (xy 179.369491 -54.484634)
			(xy 179.384846 -54.536929) (xy 179.392602 -54.590877) (xy 179.393088 -54.618128) (xy 179.393088 -55.481728)
			(xy 179.392602 -55.508979) (xy 179.384846 -55.562927) (xy 179.369491 -55.615222) (xy 179.346849 -55.664799)
			(xy 179.317383 -55.710649) (xy 179.281692 -55.75184) (xy 179.240501 -55.787531) (xy 179.194651 -55.816997)
			(xy 179.145074 -55.839639) (xy 179.092779 -55.854994) (xy 179.038831 -55.86275) (xy 178.984329 -55.86275)
			(xy 178.930381 -55.854994) (xy 178.878086 -55.839639) (xy 178.828509 -55.816997) (xy 178.782659 -55.787531)
			(xy 178.741468 -55.75184) (xy 178.705777 -55.710649) (xy 178.676311 -55.664799) (xy 178.653669 -55.615222)
			(xy 178.638314 -55.562927) (xy 178.630558 -55.508979) (xy 178.630072 -55.481728) (xy 0.509016 -55.481728)
			(xy 0.509016 -57.094435) (xy 170.841915 -57.094435) (xy 170.841915 -57.005413) (xy 170.849895 -56.916749)
			(xy 170.865791 -56.829158) (xy 170.889474 -56.743343) (xy 170.920754 -56.659998) (xy 170.95938 -56.579792)
			(xy 171.005039 -56.503371) (xy 171.057365 -56.43135) (xy 171.115936 -56.36431) (xy 171.180281 -56.30279)
			(xy 171.249881 -56.247286) (xy 171.324177 -56.198244) (xy 171.402569 -56.156059) (xy 171.484428 -56.121071)
			(xy 171.569093 -56.093562) (xy 171.655883 -56.073752) (xy 171.744099 -56.061802) (xy 171.833032 -56.057809)
			(xy 171.921965 -56.061802) (xy 172.010181 -56.073752) (xy 172.096971 -56.093562) (xy 172.181636 -56.121071)
			(xy 172.263495 -56.156059) (xy 172.341887 -56.198244) (xy 172.416183 -56.247286) (xy 172.485783 -56.30279)
			(xy 172.550128 -56.36431) (xy 172.608699 -56.43135) (xy 172.661025 -56.503371) (xy 172.663117 -56.506872)
			(xy 228.815392 -56.506872) (xy 228.815392 -55.643272) (xy 228.815878 -55.616021) (xy 228.823634 -55.562073)
			(xy 228.838989 -55.509778) (xy 228.861631 -55.460201) (xy 228.891097 -55.414351) (xy 228.926788 -55.37316)
			(xy 228.967979 -55.337469) (xy 229.013829 -55.308003) (xy 229.063406 -55.285361) (xy 229.115701 -55.270006)
			(xy 229.169649 -55.26225) (xy 229.224151 -55.26225) (xy 229.278099 -55.270006) (xy 229.330394 -55.285361)
			(xy 229.379971 -55.308003) (xy 229.425821 -55.337469) (xy 229.467012 -55.37316) (xy 229.502703 -55.414351)
			(xy 229.532169 -55.460201) (xy 229.554811 -55.509778) (xy 229.570166 -55.562073) (xy 229.577922 -55.616021)
			(xy 229.578408 -55.643272) (xy 229.578408 -55.911852) (xy 357.10365 -55.911852) (xy 357.10365 -55.857348)
			(xy 357.111406 -55.803398) (xy 357.126762 -55.751101) (xy 357.149403 -55.701521) (xy 357.17887 -55.655668)
			(xy 357.214562 -55.614476) (xy 357.255752 -55.578782) (xy 357.301604 -55.549313) (xy 357.351182 -55.526669)
			(xy 357.403478 -55.511311) (xy 357.457428 -55.503551) (xy 357.48468 -55.503064) (xy 358.34828 -55.503064)
			(xy 358.375532 -55.503582) (xy 358.429481 -55.511336) (xy 358.481777 -55.526689) (xy 358.531356 -55.549329)
			(xy 358.577209 -55.578794) (xy 358.618401 -55.614485) (xy 358.654094 -55.655675) (xy 358.683562 -55.701526)
			(xy 358.706204 -55.751104) (xy 358.72156 -55.8034) (xy 358.729317 -55.857348) (xy 358.729317 -55.911852)
			(xy 358.729316 -55.911856) (xy 359.950927 -55.911856) (xy 359.950927 -55.857344) (xy 359.958685 -55.803388)
			(xy 359.974043 -55.751084) (xy 359.996689 -55.701499) (xy 360.026161 -55.655642) (xy 360.061859 -55.614445)
			(xy 360.103058 -55.578749) (xy 360.148917 -55.549279) (xy 360.198503 -55.526636) (xy 360.250807 -55.511281)
			(xy 360.304764 -55.503526) (xy 360.33202 -55.503064) (xy 361.19562 -55.503064) (xy 361.222868 -55.503608)
			(xy 361.27681 -55.511366) (xy 361.329098 -55.526722) (xy 361.378669 -55.549362) (xy 361.424514 -55.578827)
			(xy 361.465699 -55.614516) (xy 361.501385 -55.655702) (xy 361.530847 -55.701548) (xy 361.553485 -55.75112)
			(xy 361.568838 -55.80341) (xy 361.576594 -55.857352) (xy 361.576594 -55.911848) (xy 361.576593 -55.911857)
			(xy 363.514527 -55.911857) (xy 363.514527 -55.857343) (xy 363.522286 -55.803385) (xy 363.537645 -55.75108)
			(xy 363.560292 -55.701493) (xy 363.589766 -55.655635) (xy 363.625466 -55.614438) (xy 363.666667 -55.578742)
			(xy 363.712529 -55.549273) (xy 363.762117 -55.526631) (xy 363.814424 -55.511277) (xy 363.868383 -55.503524)
			(xy 363.89564 -55.503064) (xy 364.75924 -55.503064) (xy 364.786487 -55.503609) (xy 364.840427 -55.511369)
			(xy 364.892713 -55.526727) (xy 364.942281 -55.549369) (xy 364.988123 -55.578834) (xy 365.029306 -55.614523)
			(xy 365.06499 -55.655709) (xy 365.094451 -55.701554) (xy 365.117087 -55.751125) (xy 365.132439 -55.803412)
			(xy 365.140194 -55.857353) (xy 365.140194 -55.911847) (xy 365.132439 -55.965788) (xy 365.117087 -56.018075)
			(xy 365.094451 -56.067646) (xy 365.06499 -56.113491) (xy 365.029306 -56.154677) (xy 364.988123 -56.190366)
			(xy 364.942281 -56.219831) (xy 364.892713 -56.242473) (xy 364.840427 -56.257831) (xy 364.786487 -56.265591)
			(xy 364.75924 -56.26608) (xy 363.89564 -56.26608) (xy 363.868383 -56.265676) (xy 363.814424 -56.257923)
			(xy 363.762117 -56.242569) (xy 363.712529 -56.219927) (xy 363.666667 -56.190458) (xy 363.625466 -56.154762)
			(xy 363.589766 -56.113565) (xy 363.560292 -56.067707) (xy 363.537645 -56.01812) (xy 363.522286 -55.965815)
			(xy 363.514527 -55.911857) (xy 361.576593 -55.911857) (xy 361.568838 -55.96579) (xy 361.553485 -56.01808)
			(xy 361.530847 -56.067652) (xy 361.501385 -56.113498) (xy 361.465699 -56.154684) (xy 361.424514 -56.190373)
			(xy 361.378669 -56.219838) (xy 361.329098 -56.242478) (xy 361.27681 -56.257834) (xy 361.222868 -56.265592)
			(xy 361.19562 -56.26608) (xy 360.33202 -56.26608) (xy 360.304764 -56.265674) (xy 360.250807 -56.257919)
			(xy 360.198503 -56.242564) (xy 360.148917 -56.219921) (xy 360.103058 -56.190451) (xy 360.061859 -56.154755)
			(xy 360.026161 -56.113558) (xy 359.996689 -56.067701) (xy 359.974043 -56.018116) (xy 359.958685 -55.965812)
			(xy 359.950927 -55.911856) (xy 358.729316 -55.911856) (xy 358.72156 -55.9658) (xy 358.706204 -56.018096)
			(xy 358.683562 -56.067674) (xy 358.654094 -56.113525) (xy 358.618401 -56.154715) (xy 358.577209 -56.190406)
			(xy 358.531356 -56.219871) (xy 358.481777 -56.242511) (xy 358.429481 -56.257864) (xy 358.375532 -56.265618)
			(xy 358.34828 -56.26608) (xy 357.48468 -56.26608) (xy 357.457428 -56.265649) (xy 357.403478 -56.257889)
			(xy 357.351182 -56.242531) (xy 357.301604 -56.219887) (xy 357.255752 -56.190418) (xy 357.214562 -56.154724)
			(xy 357.17887 -56.113532) (xy 357.149403 -56.067679) (xy 357.126762 -56.018099) (xy 357.111406 -55.965802)
			(xy 357.10365 -55.911852) (xy 229.578408 -55.911852) (xy 229.578408 -56.506872) (xy 229.577922 -56.534123)
			(xy 229.570166 -56.588071) (xy 229.554811 -56.640366) (xy 229.532169 -56.689943) (xy 229.502703 -56.735793)
			(xy 229.467012 -56.776984) (xy 229.425821 -56.812675) (xy 229.379971 -56.842141) (xy 229.330394 -56.864783)
			(xy 229.278099 -56.880138) (xy 229.224151 -56.887894) (xy 229.169649 -56.887894) (xy 229.115701 -56.880138)
			(xy 229.063406 -56.864783) (xy 229.013829 -56.842141) (xy 228.967979 -56.812675) (xy 228.926788 -56.776984)
			(xy 228.891097 -56.735793) (xy 228.861631 -56.689943) (xy 228.838989 -56.640366) (xy 228.823634 -56.588071)
			(xy 228.815878 -56.534123) (xy 228.815392 -56.506872) (xy 172.663117 -56.506872) (xy 172.706684 -56.579792)
			(xy 172.74531 -56.659998) (xy 172.77659 -56.743343) (xy 172.800273 -56.829158) (xy 172.816169 -56.916749)
			(xy 172.824149 -57.005413) (xy 172.824648 -57.049924) (xy 172.824149 -57.094435) (xy 172.816169 -57.183099)
			(xy 172.800273 -57.27069) (xy 172.77659 -57.356505) (xy 172.74531 -57.43985) (xy 172.706684 -57.520056)
			(xy 172.661025 -57.596477) (xy 172.608699 -57.668498) (xy 172.550128 -57.735538) (xy 172.485783 -57.797058)
			(xy 172.416183 -57.852562) (xy 172.341887 -57.901604) (xy 172.263495 -57.943789) (xy 172.181636 -57.978777)
			(xy 172.096971 -58.006286) (xy 172.010181 -58.026096) (xy 171.921965 -58.038046) (xy 171.833032 -58.04204)
			(xy 171.744099 -58.038046) (xy 171.655883 -58.026096) (xy 171.569093 -58.006286) (xy 171.484428 -57.978777)
			(xy 171.402569 -57.943789) (xy 171.324177 -57.901604) (xy 171.249881 -57.852562) (xy 171.180281 -57.797058)
			(xy 171.115936 -57.735538) (xy 171.057365 -57.668498) (xy 171.005039 -57.596477) (xy 170.95938 -57.520056)
			(xy 170.920754 -57.43985) (xy 170.889474 -57.356505) (xy 170.865791 -57.27069) (xy 170.849895 -57.183099)
			(xy 170.841915 -57.094435) (xy 0.509016 -57.094435) (xy 0.509016 -58.306716) (xy 230.115872 -58.306716)
			(xy 230.115872 -57.443116) (xy 230.116358 -57.415865) (xy 230.124114 -57.361917) (xy 230.139469 -57.309622)
			(xy 230.162111 -57.260045) (xy 230.191577 -57.214195) (xy 230.227268 -57.173004) (xy 230.268459 -57.137313)
			(xy 230.314309 -57.107847) (xy 230.363886 -57.085205) (xy 230.416181 -57.06985) (xy 230.470129 -57.062094)
			(xy 230.524631 -57.062094) (xy 230.578579 -57.06985) (xy 230.630874 -57.085205) (xy 230.680451 -57.107847)
			(xy 230.726301 -57.137313) (xy 230.767492 -57.173004) (xy 230.803183 -57.214195) (xy 230.832649 -57.260045)
			(xy 230.855291 -57.309622) (xy 230.870646 -57.361917) (xy 230.878402 -57.415865) (xy 230.878888 -57.443116)
			(xy 230.878888 -58.30189) (xy 240.282476 -58.30189) (xy 240.282476 -57.43829) (xy 240.282962 -57.411039)
			(xy 240.290718 -57.357091) (xy 240.306073 -57.304796) (xy 240.328715 -57.255219) (xy 240.358181 -57.209369)
			(xy 240.393872 -57.168178) (xy 240.435063 -57.132487) (xy 240.480913 -57.103021) (xy 240.53049 -57.080379)
			(xy 240.582785 -57.065024) (xy 240.636733 -57.057268) (xy 240.691235 -57.057268) (xy 240.745183 -57.065024)
			(xy 240.797478 -57.080379) (xy 240.847055 -57.103021) (xy 240.892905 -57.132487) (xy 240.934096 -57.168178)
			(xy 240.969787 -57.209369) (xy 240.999253 -57.255219) (xy 241.021895 -57.304796) (xy 241.03725 -57.357091)
			(xy 241.045006 -57.411039) (xy 241.045492 -57.43829) (xy 241.045492 -58.30189) (xy 241.045006 -58.329141)
			(xy 241.03725 -58.383089) (xy 241.021895 -58.435384) (xy 240.999253 -58.484961) (xy 240.969787 -58.530811)
			(xy 240.941894 -58.563002) (xy 242.736116 -58.563002) (xy 242.736116 -57.699402) (xy 242.736602 -57.672151)
			(xy 242.744358 -57.618203) (xy 242.759713 -57.565908) (xy 242.782355 -57.516331) (xy 242.811821 -57.470481)
			(xy 242.847512 -57.42929) (xy 242.888703 -57.393599) (xy 242.934553 -57.364133) (xy 242.98413 -57.341491)
			(xy 243.036425 -57.326136) (xy 243.090373 -57.31838) (xy 243.144875 -57.31838) (xy 243.198823 -57.326136)
			(xy 243.251118 -57.341491) (xy 243.300695 -57.364133) (xy 243.346545 -57.393599) (xy 243.387736 -57.42929)
			(xy 243.423427 -57.470481) (xy 243.452893 -57.516331) (xy 243.475535 -57.565908) (xy 243.49089 -57.618203)
			(xy 243.498646 -57.672151) (xy 243.499132 -57.699402) (xy 243.499132 -58.563002) (xy 243.498646 -58.590253)
			(xy 243.49089 -58.644201) (xy 243.475535 -58.696496) (xy 243.452893 -58.746073) (xy 243.423427 -58.791923)
			(xy 243.387736 -58.833114) (xy 243.346545 -58.868805) (xy 243.300695 -58.898271) (xy 243.251118 -58.920913)
			(xy 243.198823 -58.936268) (xy 243.144875 -58.944024) (xy 243.090373 -58.944024) (xy 243.036425 -58.936268)
			(xy 242.98413 -58.920913) (xy 242.934553 -58.898271) (xy 242.888703 -58.868805) (xy 242.847512 -58.833114)
			(xy 242.811821 -58.791923) (xy 242.782355 -58.746073) (xy 242.759713 -58.696496) (xy 242.744358 -58.644201)
			(xy 242.736602 -58.590253) (xy 242.736116 -58.563002) (xy 240.941894 -58.563002) (xy 240.934096 -58.572002)
			(xy 240.892905 -58.607693) (xy 240.847055 -58.637159) (xy 240.797478 -58.659801) (xy 240.745183 -58.675156)
			(xy 240.691235 -58.682912) (xy 240.636733 -58.682912) (xy 240.582785 -58.675156) (xy 240.53049 -58.659801)
			(xy 240.480913 -58.637159) (xy 240.435063 -58.607693) (xy 240.393872 -58.572002) (xy 240.358181 -58.530811)
			(xy 240.328715 -58.484961) (xy 240.306073 -58.435384) (xy 240.290718 -58.383089) (xy 240.282962 -58.329141)
			(xy 240.282476 -58.30189) (xy 230.878888 -58.30189) (xy 230.878888 -58.306716) (xy 230.878402 -58.333967)
			(xy 230.870646 -58.387915) (xy 230.855291 -58.44021) (xy 230.832649 -58.489787) (xy 230.803183 -58.535637)
			(xy 230.767492 -58.576828) (xy 230.726301 -58.612519) (xy 230.680451 -58.641985) (xy 230.630874 -58.664627)
			(xy 230.578579 -58.679982) (xy 230.524631 -58.687738) (xy 230.470129 -58.687738) (xy 230.416181 -58.679982)
			(xy 230.363886 -58.664627) (xy 230.314309 -58.641985) (xy 230.268459 -58.612519) (xy 230.227268 -58.576828)
			(xy 230.191577 -58.535637) (xy 230.162111 -58.489787) (xy 230.139469 -58.44021) (xy 230.124114 -58.387915)
			(xy 230.116358 -58.333967) (xy 230.115872 -58.306716) (xy 0.509016 -58.306716) (xy 0.509016 -59.99988)
			(xy 16.983969 -59.99988) (xy 16.987993 -59.914112) (xy 17.000031 -59.829098) (xy 17.019978 -59.745584)
			(xy 17.047657 -59.664305) (xy 17.082825 -59.585976) (xy 17.125174 -59.511283) (xy 17.174331 -59.440885)
			(xy 17.229864 -59.375399) (xy 17.291286 -59.315401) (xy 17.358055 -59.261418) (xy 17.429587 -59.213925)
			(xy 17.505251 -59.173339) (xy 17.584384 -59.140016) (xy 17.666289 -59.11425) (xy 17.750247 -59.096267)
			(xy 17.835521 -59.086225) (xy 17.92136 -59.084212) (xy 18.00701 -59.090246) (xy 18.091718 -59.104274)
			(xy 18.174741 -59.126173) (xy 18.255349 -59.15575) (xy 18.332833 -59.192745) (xy 18.406512 -59.236833)
			(xy 18.475738 -59.287627) (xy 18.539905 -59.34468) (xy 18.598446 -59.407491) (xy 18.650849 -59.475508)
			(xy 18.696652 -59.548133) (xy 18.735453 -59.624728) (xy 18.766912 -59.70462) (xy 18.790751 -59.787107)
			(xy 18.806761 -59.871464) (xy 18.814801 -59.956949) (xy 18.815304 -59.99988) (xy 18.814801 -60.042811)
			(xy 18.806761 -60.128296) (xy 18.790751 -60.212653) (xy 18.766912 -60.29514) (xy 18.735453 -60.375032)
			(xy 18.73545 -60.375038) (xy 233.333297 -60.375038) (xy 233.337302 -60.28713) (xy 233.349285 -60.19995)
			(xy 233.369145 -60.114221) (xy 233.39672 -60.030653) (xy 233.431779 -59.949939) (xy 233.474032 -59.872747)
			(xy 233.52313 -59.799718) (xy 233.578666 -59.731456) (xy 233.640178 -59.668526) (xy 233.707159 -59.611452)
			(xy 233.779052 -59.560704) (xy 233.855261 -59.516704) (xy 233.935156 -59.479817) (xy 234.018075 -59.450348)
			(xy 234.10333 -59.428541) (xy 234.190214 -59.414577) (xy 234.278008 -59.408571) (xy 234.365985 -59.410575)
			(xy 234.453415 -59.42057) (xy 234.539574 -59.438474) (xy 234.623748 -59.464138) (xy 234.705239 -59.497351)
			(xy 234.783373 -59.537837) (xy 234.857501 -59.585259) (xy 234.927009 -59.639226) (xy 234.991323 -59.699291)
			(xy 235.049907 -59.764955) (xy 235.102278 -59.835674) (xy 235.148001 -59.910862) (xy 235.186698 -59.989897)
			(xy 235.218047 -60.072123) (xy 235.241789 -60.156859) (xy 235.257727 -60.243403) (xy 235.265729 -60.331038)
			(xy 235.26623 -60.375038) (xy 235.265729 -60.419038) (xy 235.257727 -60.506673) (xy 235.241789 -60.593217)
			(xy 235.218047 -60.677953) (xy 235.186698 -60.760179) (xy 235.148001 -60.839214) (xy 235.102278 -60.914402)
			(xy 235.049907 -60.985121) (xy 234.991323 -61.050785) (xy 234.927009 -61.11085) (xy 234.857501 -61.164817)
			(xy 234.783373 -61.212239) (xy 234.705239 -61.252725) (xy 234.623748 -61.285938) (xy 234.539574 -61.311602)
			(xy 234.453415 -61.329506) (xy 234.365985 -61.339501) (xy 234.278008 -61.341505) (xy 234.190214 -61.335499)
			(xy 234.10333 -61.321535) (xy 234.018075 -61.299728) (xy 233.935156 -61.270259) (xy 233.855261 -61.233372)
			(xy 233.779052 -61.189372) (xy 233.707159 -61.138624) (xy 233.640178 -61.08155) (xy 233.578666 -61.01862)
			(xy 233.52313 -60.950358) (xy 233.474032 -60.877329) (xy 233.431779 -60.800137) (xy 233.39672 -60.719423)
			(xy 233.369145 -60.635855) (xy 233.349285 -60.550126) (xy 233.337302 -60.462946) (xy 233.333297 -60.375038)
			(xy 18.73545 -60.375038) (xy 18.696652 -60.451627) (xy 18.650849 -60.524252) (xy 18.598446 -60.592269)
			(xy 18.539905 -60.65508) (xy 18.475738 -60.712133) (xy 18.406512 -60.762927) (xy 18.332833 -60.807015)
			(xy 18.255349 -60.84401) (xy 18.174741 -60.873587) (xy 18.091718 -60.895486) (xy 18.00701 -60.909514)
			(xy 17.92136 -60.915548) (xy 17.835521 -60.913535) (xy 17.750247 -60.903493) (xy 17.666289 -60.88551)
			(xy 17.584384 -60.859744) (xy 17.505251 -60.826421) (xy 17.429587 -60.785835) (xy 17.358055 -60.738342)
			(xy 17.291286 -60.684359) (xy 17.229864 -60.624361) (xy 17.174331 -60.558875) (xy 17.125174 -60.488477)
			(xy 17.082825 -60.413784) (xy 17.047657 -60.335455) (xy 17.019978 -60.254176) (xy 17.000031 -60.170662)
			(xy 16.987993 -60.085648) (xy 16.983969 -59.99988) (xy 0.509016 -59.99988) (xy 0.509016 -74.760836)
			(xy 39.554404 -74.760836) (xy 39.554404 -66.060828) (xy 39.554909 -65.955304) (xy 39.562993 -65.74441)
			(xy 39.579149 -65.533981) (xy 39.603352 -65.324324) (xy 39.635569 -65.115749) (xy 39.675751 -64.908561)
			(xy 39.723839 -64.703064) (xy 39.779763 -64.49956) (xy 39.84344 -64.298347) (xy 39.914778 -64.09972)
			(xy 39.993672 -63.903972) (xy 40.080005 -63.71139) (xy 40.173652 -63.522255) (xy 40.274474 -63.336846)
			(xy 40.382324 -63.155435) (xy 40.497043 -62.978288) (xy 40.618463 -62.805666) (xy 40.746406 -62.63782)
			(xy 40.880684 -62.474998) (xy 41.0211 -62.317439) (xy 41.167448 -62.165374) (xy 41.319513 -62.019026)
			(xy 41.477072 -61.87861) (xy 41.639894 -61.744332) (xy 41.80774 -61.616389) (xy 41.980362 -61.494969)
			(xy 42.157509 -61.38025) (xy 42.33892 -61.2724) (xy 42.524329 -61.171578) (xy 42.713464 -61.077931)
			(xy 42.906046 -60.991598) (xy 43.101794 -60.912704) (xy 43.300421 -60.841366) (xy 43.501634 -60.777689)
			(xy 43.705138 -60.721765) (xy 43.910635 -60.673677) (xy 44.117823 -60.633495) (xy 44.326398 -60.601278)
			(xy 44.536055 -60.577075) (xy 44.746484 -60.560919) (xy 44.957378 -60.552835) (xy 45.168426 -60.552835)
			(xy 45.37932 -60.560919) (xy 45.589749 -60.577075) (xy 45.799406 -60.601278) (xy 46.007981 -60.633495)
			(xy 46.215169 -60.673677) (xy 46.420666 -60.721765) (xy 46.62417 -60.777689) (xy 46.825383 -60.841366)
			(xy 47.02401 -60.912704) (xy 47.219758 -60.991598) (xy 47.41234 -61.077931) (xy 47.601475 -61.171578)
			(xy 47.786884 -61.2724) (xy 47.968295 -61.38025) (xy 48.145442 -61.494969) (xy 48.318064 -61.616389)
			(xy 48.48591 -61.744332) (xy 48.648732 -61.87861) (xy 48.806291 -62.019026) (xy 48.958356 -62.165374)
			(xy 49.104704 -62.317439) (xy 49.24512 -62.474998) (xy 49.379398 -62.63782) (xy 49.507341 -62.805666)
			(xy 49.628761 -62.978288) (xy 49.74348 -63.155435) (xy 49.85133 -63.336846) (xy 49.952152 -63.522255)
			(xy 50.045799 -63.71139) (xy 50.132132 -63.903972) (xy 50.211026 -64.09972) (xy 50.282364 -64.298347)
			(xy 50.346041 -64.49956) (xy 50.401965 -64.703064) (xy 50.450053 -64.908561) (xy 50.490235 -65.115749)
			(xy 50.522452 -65.324324) (xy 50.546655 -65.533981) (xy 50.562811 -65.74441) (xy 50.570895 -65.955304)
			(xy 50.5714 -66.060828) (xy 50.5714 -74.760836) (xy 50.571366 -74.767948) (xy 173.354492 -74.767948)
			(xy 173.354492 -66.06794) (xy 173.354997 -65.962416) (xy 173.363081 -65.751522) (xy 173.379237 -65.541093)
			(xy 173.40344 -65.331436) (xy 173.435657 -65.122861) (xy 173.475839 -64.915673) (xy 173.523927 -64.710176)
			(xy 173.579851 -64.506672) (xy 173.643528 -64.305459) (xy 173.714866 -64.106832) (xy 173.79376 -63.911084)
			(xy 173.880093 -63.718502) (xy 173.97374 -63.529367) (xy 174.074562 -63.343958) (xy 174.182412 -63.162547)
			(xy 174.297131 -62.9854) (xy 174.418551 -62.812778) (xy 174.546494 -62.644932) (xy 174.680772 -62.48211)
			(xy 174.821188 -62.324551) (xy 174.967536 -62.172486) (xy 175.119601 -62.026138) (xy 175.27716 -61.885722)
			(xy 175.439982 -61.751444) (xy 175.607828 -61.623501) (xy 175.78045 -61.502081) (xy 175.957597 -61.387362)
			(xy 176.139008 -61.279512) (xy 176.324417 -61.17869) (xy 176.513552 -61.085043) (xy 176.706134 -60.99871)
			(xy 176.901882 -60.919816) (xy 177.100509 -60.848478) (xy 177.301722 -60.784801) (xy 177.505226 -60.728877)
			(xy 177.710723 -60.680789) (xy 177.917911 -60.640607) (xy 178.126486 -60.60839) (xy 178.336143 -60.584187)
			(xy 178.546572 -60.568031) (xy 178.757466 -60.559947) (xy 178.968514 -60.559947) (xy 179.179408 -60.568031)
			(xy 179.389837 -60.584187) (xy 179.599494 -60.60839) (xy 179.808069 -60.640607) (xy 180.015257 -60.680789)
			(xy 180.220754 -60.728877) (xy 180.424258 -60.784801) (xy 180.625471 -60.848478) (xy 180.824098 -60.919816)
			(xy 181.019846 -60.99871) (xy 181.212428 -61.085043) (xy 181.401563 -61.17869) (xy 181.586972 -61.279512)
			(xy 181.768383 -61.387362) (xy 181.94553 -61.502081) (xy 182.118152 -61.623501) (xy 182.285998 -61.751444)
			(xy 182.44882 -61.885722) (xy 182.606379 -62.026138) (xy 182.758444 -62.172486) (xy 182.904792 -62.324551)
			(xy 183.045208 -62.48211) (xy 183.179486 -62.644932) (xy 183.307429 -62.812778) (xy 183.428849 -62.9854)
			(xy 183.543568 -63.162547) (xy 183.651418 -63.343958) (xy 183.75224 -63.529367) (xy 183.845887 -63.718502)
			(xy 183.93222 -63.911084) (xy 184.011114 -64.106832) (xy 184.082452 -64.305459) (xy 184.146129 -64.506672)
			(xy 184.202053 -64.710176) (xy 184.250141 -64.915673) (xy 184.290323 -65.122861) (xy 184.32254 -65.331436)
			(xy 184.346743 -65.541093) (xy 184.362899 -65.751522) (xy 184.370983 -65.962416) (xy 184.371488 -66.06794)
			(xy 184.371488 -74.760836) (xy 287.494472 -74.760836) (xy 287.494472 -66.060828) (xy 287.494977 -65.955304)
			(xy 287.503061 -65.74441) (xy 287.519217 -65.533981) (xy 287.54342 -65.324324) (xy 287.575637 -65.115749)
			(xy 287.615819 -64.908561) (xy 287.663907 -64.703064) (xy 287.719831 -64.49956) (xy 287.783508 -64.298347)
			(xy 287.854846 -64.09972) (xy 287.93374 -63.903972) (xy 288.020073 -63.71139) (xy 288.11372 -63.522255)
			(xy 288.214542 -63.336846) (xy 288.322392 -63.155435) (xy 288.437111 -62.978288) (xy 288.558531 -62.805666)
			(xy 288.686474 -62.63782) (xy 288.820752 -62.474998) (xy 288.961168 -62.317439) (xy 289.107516 -62.165374)
			(xy 289.259581 -62.019026) (xy 289.41714 -61.87861) (xy 289.579962 -61.744332) (xy 289.747808 -61.616389)
			(xy 289.92043 -61.494969) (xy 290.097577 -61.38025) (xy 290.278988 -61.2724) (xy 290.464397 -61.171578)
			(xy 290.653532 -61.077931) (xy 290.846114 -60.991598) (xy 291.041862 -60.912704) (xy 291.240489 -60.841366)
			(xy 291.441702 -60.777689) (xy 291.645206 -60.721765) (xy 291.850703 -60.673677) (xy 292.057891 -60.633495)
			(xy 292.266466 -60.601278) (xy 292.476123 -60.577075) (xy 292.686552 -60.560919) (xy 292.897446 -60.552835)
			(xy 293.108494 -60.552835) (xy 293.319388 -60.560919) (xy 293.529817 -60.577075) (xy 293.739474 -60.601278)
			(xy 293.948049 -60.633495) (xy 294.155237 -60.673677) (xy 294.360734 -60.721765) (xy 294.564238 -60.777689)
			(xy 294.765451 -60.841366) (xy 294.964078 -60.912704) (xy 295.159826 -60.991598) (xy 295.352408 -61.077931)
			(xy 295.541543 -61.171578) (xy 295.726952 -61.2724) (xy 295.908363 -61.38025) (xy 296.063868 -61.480954)
			(xy 351.822512 -61.480954) (xy 351.822512 -60.617354) (xy 351.822998 -60.590103) (xy 351.830754 -60.536155)
			(xy 351.846109 -60.48386) (xy 351.868751 -60.434283) (xy 351.898217 -60.388433) (xy 351.933908 -60.347242)
			(xy 351.975099 -60.311551) (xy 352.020949 -60.282085) (xy 352.070526 -60.259443) (xy 352.122821 -60.244088)
			(xy 352.176769 -60.236332) (xy 352.231271 -60.236332) (xy 352.285219 -60.244088) (xy 352.337514 -60.259443)
			(xy 352.387091 -60.282085) (xy 352.432941 -60.311551) (xy 352.474132 -60.347242) (xy 352.509823 -60.388433)
			(xy 352.539289 -60.434283) (xy 352.561931 -60.48386) (xy 352.577286 -60.536155) (xy 352.585042 -60.590103)
			(xy 352.585528 -60.617354) (xy 352.585528 -61.223271) (xy 355.46889 -61.223271) (xy 355.46889 -61.168729)
			(xy 355.476653 -61.114741) (xy 355.492019 -61.062408) (xy 355.514676 -61.012794) (xy 355.544164 -60.966909)
			(xy 355.579881 -60.925688) (xy 355.621101 -60.88997) (xy 355.666985 -60.860481) (xy 355.716598 -60.837822)
			(xy 355.768931 -60.822455) (xy 355.822919 -60.814691) (xy 355.85019 -60.814204) (xy 356.71379 -60.814204)
			(xy 356.741059 -60.814735) (xy 356.795042 -60.822495) (xy 356.847371 -60.837859) (xy 356.896981 -60.860514)
			(xy 356.942862 -60.889999) (xy 356.98408 -60.925713) (xy 357.019795 -60.96693) (xy 357.049281 -61.01281)
			(xy 357.071937 -61.062419) (xy 357.087303 -61.114748) (xy 357.095065 -61.168731) (xy 357.095065 -61.223269)
			(xy 357.087303 -61.277252) (xy 357.071937 -61.329581) (xy 357.049281 -61.37919) (xy 357.019795 -61.42507)
			(xy 356.98408 -61.466287) (xy 356.942862 -61.502001) (xy 356.896981 -61.531486) (xy 356.847371 -61.554141)
			(xy 356.795042 -61.569505) (xy 356.741059 -61.577265) (xy 356.71379 -61.577728) (xy 355.85019 -61.577728)
			(xy 355.822919 -61.577309) (xy 355.768931 -61.569545) (xy 355.716598 -61.554178) (xy 355.666985 -61.531519)
			(xy 355.621101 -61.50203) (xy 355.579881 -61.466312) (xy 355.544164 -61.425091) (xy 355.514676 -61.379206)
			(xy 355.492019 -61.329592) (xy 355.476653 -61.277259) (xy 355.46889 -61.223271) (xy 352.585528 -61.223271)
			(xy 352.585528 -61.480954) (xy 352.585042 -61.508205) (xy 352.577286 -61.562153) (xy 352.561931 -61.614448)
			(xy 352.539289 -61.664025) (xy 352.509823 -61.709875) (xy 352.474132 -61.751066) (xy 352.432941 -61.786757)
			(xy 352.387091 -61.816223) (xy 352.337514 -61.838865) (xy 352.285219 -61.85422) (xy 352.231271 -61.861976)
			(xy 352.176769 -61.861976) (xy 352.122821 -61.85422) (xy 352.070526 -61.838865) (xy 352.020949 -61.816223)
			(xy 351.975099 -61.786757) (xy 351.933908 -61.751066) (xy 351.898217 -61.709875) (xy 351.868751 -61.664025)
			(xy 351.846109 -61.614448) (xy 351.830754 -61.562153) (xy 351.822998 -61.508205) (xy 351.822512 -61.480954)
			(xy 296.063868 -61.480954) (xy 296.08551 -61.494969) (xy 296.258132 -61.616389) (xy 296.425978 -61.744332)
			(xy 296.5888 -61.87861) (xy 296.746359 -62.019026) (xy 296.898424 -62.165374) (xy 297.044772 -62.317439)
			(xy 297.185188 -62.474998) (xy 297.319466 -62.63782) (xy 297.447409 -62.805666) (xy 297.568829 -62.978288)
			(xy 297.683548 -63.155435) (xy 297.751584 -63.269876) (xy 350.300544 -63.269876) (xy 350.300544 -62.406276)
			(xy 350.30103 -62.379025) (xy 350.308786 -62.325077) (xy 350.324141 -62.272782) (xy 350.346783 -62.223205)
			(xy 350.376249 -62.177355) (xy 350.41194 -62.136164) (xy 350.453131 -62.100473) (xy 350.498981 -62.071007)
			(xy 350.548558 -62.048365) (xy 350.600853 -62.03301) (xy 350.654801 -62.025254) (xy 350.709303 -62.025254)
			(xy 350.763251 -62.03301) (xy 350.815546 -62.048365) (xy 350.865123 -62.071007) (xy 350.910973 -62.100473)
			(xy 350.952164 -62.136164) (xy 350.987855 -62.177355) (xy 351.017321 -62.223205) (xy 351.039963 -62.272782)
			(xy 351.055318 -62.325077) (xy 351.063074 -62.379025) (xy 351.06356 -62.406276) (xy 351.06356 -63.269876)
			(xy 351.063074 -63.297127) (xy 351.055318 -63.351075) (xy 351.039963 -63.40337) (xy 351.017321 -63.452947)
			(xy 350.987855 -63.498797) (xy 350.952164 -63.539988) (xy 350.910973 -63.575679) (xy 350.865123 -63.605145)
			(xy 350.815546 -63.627787) (xy 350.763251 -63.643142) (xy 350.709303 -63.650898) (xy 350.654801 -63.650898)
			(xy 350.600853 -63.643142) (xy 350.548558 -63.627787) (xy 350.498981 -63.605145) (xy 350.453131 -63.575679)
			(xy 350.41194 -63.539988) (xy 350.376249 -63.498797) (xy 350.346783 -63.452947) (xy 350.324141 -63.40337)
			(xy 350.308786 -63.351075) (xy 350.30103 -63.297127) (xy 350.300544 -63.269876) (xy 297.751584 -63.269876)
			(xy 297.791398 -63.336846) (xy 297.89222 -63.522255) (xy 297.985867 -63.71139) (xy 298.0722 -63.903972)
			(xy 298.151094 -64.09972) (xy 298.222432 -64.298347) (xy 298.286109 -64.49956) (xy 298.342033 -64.703064)
			(xy 298.390121 -64.908561) (xy 298.396302 -64.940434) (xy 325.410068 -64.940434) (xy 325.410068 -64.076834)
			(xy 325.410554 -64.049565) (xy 325.418316 -63.995581) (xy 325.433681 -63.943251) (xy 325.456338 -63.893641)
			(xy 325.485824 -63.84776) (xy 325.521539 -63.806543) (xy 325.562756 -63.770828) (xy 325.608637 -63.741342)
			(xy 325.658247 -63.718685) (xy 325.710577 -63.70332) (xy 325.764561 -63.695558) (xy 325.819099 -63.695558)
			(xy 325.873083 -63.70332) (xy 325.925413 -63.718685) (xy 325.975023 -63.741342) (xy 326.020904 -63.770828)
			(xy 326.062121 -63.806543) (xy 326.097836 -63.84776) (xy 326.127322 -63.893641) (xy 326.149979 -63.943251)
			(xy 326.165344 -63.995581) (xy 326.173106 -64.049565) (xy 326.173592 -64.076834) (xy 326.173592 -64.940434)
			(xy 326.173106 -64.967703) (xy 326.165344 -65.021687) (xy 326.149979 -65.074017) (xy 326.127322 -65.123627)
			(xy 326.097836 -65.169508) (xy 326.062121 -65.210725) (xy 326.020904 -65.24644) (xy 325.975023 -65.275926)
			(xy 325.925413 -65.298583) (xy 325.873083 -65.313948) (xy 325.819099 -65.32171) (xy 325.764561 -65.32171)
			(xy 325.710577 -65.313948) (xy 325.658247 -65.298583) (xy 325.608637 -65.275926) (xy 325.562756 -65.24644)
			(xy 325.521539 -65.210725) (xy 325.485824 -65.169508) (xy 325.456338 -65.123627) (xy 325.433681 -65.074017)
			(xy 325.418316 -65.021687) (xy 325.410554 -64.967703) (xy 325.410068 -64.940434) (xy 298.396302 -64.940434)
			(xy 298.430303 -65.115749) (xy 298.46252 -65.324324) (xy 298.463125 -65.329562) (xy 352.362008 -65.329562)
			(xy 352.362008 -64.465962) (xy 352.362494 -64.438711) (xy 352.37025 -64.384763) (xy 352.385605 -64.332468)
			(xy 352.408247 -64.282891) (xy 352.437713 -64.237041) (xy 352.473404 -64.19585) (xy 352.514595 -64.160159)
			(xy 352.560445 -64.130693) (xy 352.610022 -64.108051) (xy 352.662317 -64.092696) (xy 352.716265 -64.08494)
			(xy 352.770767 -64.08494) (xy 352.824715 -64.092696) (xy 352.87701 -64.108051) (xy 352.926587 -64.130693)
			(xy 352.972437 -64.160159) (xy 353.013628 -64.19585) (xy 353.049319 -64.237041) (xy 353.078785 -64.282891)
			(xy 353.101427 -64.332468) (xy 353.116782 -64.384763) (xy 353.124538 -64.438711) (xy 353.125024 -64.465962)
			(xy 353.125024 -65.329562) (xy 353.124538 -65.356813) (xy 353.116782 -65.410761) (xy 353.101427 -65.463056)
			(xy 353.078785 -65.512633) (xy 353.049319 -65.558483) (xy 353.013628 -65.599674) (xy 352.972437 -65.635365)
			(xy 352.926587 -65.664831) (xy 352.87701 -65.687473) (xy 352.824715 -65.702828) (xy 352.770767 -65.710584)
			(xy 352.716265 -65.710584) (xy 352.662317 -65.702828) (xy 352.610022 -65.687473) (xy 352.560445 -65.664831)
			(xy 352.514595 -65.635365) (xy 352.473404 -65.599674) (xy 352.437713 -65.558483) (xy 352.408247 -65.512633)
			(xy 352.385605 -65.463056) (xy 352.37025 -65.410761) (xy 352.362494 -65.356813) (xy 352.362008 -65.329562)
			(xy 298.463125 -65.329562) (xy 298.486723 -65.533981) (xy 298.502879 -65.74441) (xy 298.510963 -65.955304)
			(xy 298.511468 -66.060828) (xy 298.511468 -68.449952) (xy 314.840884 -68.449952) (xy 314.844867 -68.321934)
			(xy 314.856802 -68.194412) (xy 314.876641 -68.067878) (xy 314.904308 -67.942822) (xy 314.939697 -67.819729)
			(xy 314.98267 -67.699073) (xy 315.033061 -67.581323) (xy 315.090675 -67.466933) (xy 315.155289 -67.356346)
			(xy 315.226653 -67.24999) (xy 315.304491 -67.148277) (xy 315.388502 -67.051599) (xy 315.478361 -66.960332)
			(xy 315.57372 -66.874827) (xy 315.674211 -66.795417) (xy 315.779444 -66.722407) (xy 315.889013 -66.656081)
			(xy 316.002493 -66.596695) (xy 316.119445 -66.544479) (xy 316.239418 -66.499635) (xy 316.361946 -66.462337)
			(xy 316.486557 -66.432728) (xy 316.612766 -66.410923) (xy 316.740088 -66.397007) (xy 316.868028 -66.391033)
			(xy 316.996092 -66.393025) (xy 317.123785 -66.402975) (xy 317.250612 -66.420844) (xy 317.376083 -66.446563)
			(xy 317.499712 -66.480033) (xy 317.621021 -66.521124) (xy 317.739541 -66.569678) (xy 317.854813 -66.625506)
			(xy 317.966391 -66.688392) (xy 318.073844 -66.758094) (xy 318.176756 -66.834341) (xy 318.274728 -66.916838)
			(xy 318.323666 -66.963544) (xy 350.27108 -66.963544) (xy 350.27108 -66.099944) (xy 350.271566 -66.072693)
			(xy 350.279322 -66.018745) (xy 350.294677 -65.96645) (xy 350.317319 -65.916873) (xy 350.346785 -65.871023)
			(xy 350.382476 -65.829832) (xy 350.423667 -65.794141) (xy 350.469517 -65.764675) (xy 350.519094 -65.742033)
			(xy 350.571389 -65.726678) (xy 350.625337 -65.718922) (xy 350.679839 -65.718922) (xy 350.733787 -65.726678)
			(xy 350.786082 -65.742033) (xy 350.835659 -65.764675) (xy 350.881509 -65.794141) (xy 350.9227 -65.829832)
			(xy 350.958391 -65.871023) (xy 350.987857 -65.916873) (xy 351.010499 -65.96645) (xy 351.025854 -66.018745)
			(xy 351.03361 -66.072693) (xy 351.034096 -66.099944) (xy 351.034096 -66.963544) (xy 351.03361 -66.990795)
			(xy 351.025854 -67.044743) (xy 351.010499 -67.097038) (xy 351.005595 -67.107776) (xy 396.642323 -67.107776)
			(xy 396.642323 -67.022004) (xy 396.650237 -66.936596) (xy 396.665998 -66.852284) (xy 396.689471 -66.769785)
			(xy 396.720456 -66.689804) (xy 396.758688 -66.613023) (xy 396.803842 -66.540098) (xy 396.855532 -66.47165)
			(xy 396.913317 -66.408263) (xy 396.976704 -66.350478) (xy 397.045152 -66.298788) (xy 397.118077 -66.253634)
			(xy 397.194858 -66.215402) (xy 397.274839 -66.184417) (xy 397.357338 -66.160944) (xy 397.44165 -66.145183)
			(xy 397.527058 -66.137269) (xy 397.61283 -66.137269) (xy 397.698238 -66.145183) (xy 397.78255 -66.160944)
			(xy 397.865049 -66.184417) (xy 397.94503 -66.215402) (xy 398.021811 -66.253634) (xy 398.094736 -66.298788)
			(xy 398.163184 -66.350478) (xy 398.226571 -66.408263) (xy 398.284356 -66.47165) (xy 398.336046 -66.540098)
			(xy 398.3812 -66.613023) (xy 398.419432 -66.689804) (xy 398.450417 -66.769785) (xy 398.47389 -66.852284)
			(xy 398.489651 -66.936596) (xy 398.497565 -67.022004) (xy 398.49806 -67.06489) (xy 398.497565 -67.107776)
			(xy 398.489651 -67.193184) (xy 398.47389 -67.277496) (xy 398.450417 -67.359995) (xy 398.419432 -67.439976)
			(xy 398.3812 -67.516757) (xy 398.336046 -67.589682) (xy 398.284356 -67.65813) (xy 398.226571 -67.721517)
			(xy 398.163184 -67.779302) (xy 398.094736 -67.830992) (xy 398.021811 -67.876146) (xy 397.94503 -67.914378)
			(xy 397.865049 -67.945363) (xy 397.78255 -67.968836) (xy 397.698238 -67.984597) (xy 397.61283 -67.992511)
			(xy 397.527058 -67.992511) (xy 397.44165 -67.984597) (xy 397.357338 -67.968836) (xy 397.274839 -67.945363)
			(xy 397.194858 -67.914378) (xy 397.118077 -67.876146) (xy 397.045152 -67.830992) (xy 396.976704 -67.779302)
			(xy 396.913317 -67.721517) (xy 396.855532 -67.65813) (xy 396.803842 -67.589682) (xy 396.758688 -67.516757)
			(xy 396.720456 -67.439976) (xy 396.689471 -67.359995) (xy 396.665998 -67.277496) (xy 396.650237 -67.193184)
			(xy 396.642323 -67.107776) (xy 351.005595 -67.107776) (xy 350.987857 -67.146615) (xy 350.958391 -67.192465)
			(xy 350.9227 -67.233656) (xy 350.881509 -67.269347) (xy 350.835659 -67.298813) (xy 350.786082 -67.321455)
			(xy 350.733787 -67.33681) (xy 350.679839 -67.344566) (xy 350.625337 -67.344566) (xy 350.571389 -67.33681)
			(xy 350.519094 -67.321455) (xy 350.469517 -67.298813) (xy 350.423667 -67.269347) (xy 350.382476 -67.233656)
			(xy 350.346785 -67.192465) (xy 350.317319 -67.146615) (xy 350.294677 -67.097038) (xy 350.279322 -67.044743)
			(xy 350.271566 -66.990795) (xy 350.27108 -66.963544) (xy 318.323666 -66.963544) (xy 318.367382 -67.005267)
			(xy 318.454359 -67.099285) (xy 318.535323 -67.198528) (xy 318.60996 -67.302613) (xy 318.677982 -67.411137)
			(xy 318.739126 -67.52368) (xy 318.793154 -67.639806) (xy 318.839859 -67.759067) (xy 318.879059 -67.881)
			(xy 318.910602 -68.005135) (xy 318.934367 -68.130991) (xy 318.950261 -68.25808) (xy 318.958224 -68.385912)
			(xy 318.958722 -68.449952) (xy 318.958224 -68.513992) (xy 318.950261 -68.641824) (xy 318.934367 -68.768913)
			(xy 318.910602 -68.894769) (xy 318.879059 -69.018904) (xy 318.851129 -69.10578) (xy 351.73158 -69.10578)
			(xy 351.73158 -68.24218) (xy 351.732066 -68.214911) (xy 351.739828 -68.160927) (xy 351.755193 -68.108597)
			(xy 351.77785 -68.058987) (xy 351.807336 -68.013106) (xy 351.843051 -67.971889) (xy 351.884268 -67.936174)
			(xy 351.930149 -67.906688) (xy 351.979759 -67.884031) (xy 352.032089 -67.868666) (xy 352.086073 -67.860904)
			(xy 352.140611 -67.860904) (xy 352.194595 -67.868666) (xy 352.246925 -67.884031) (xy 352.296535 -67.906688)
			(xy 352.342416 -67.936174) (xy 352.383633 -67.971889) (xy 352.419348 -68.013106) (xy 352.448834 -68.058987)
			(xy 352.471491 -68.108597) (xy 352.486856 -68.160927) (xy 352.494618 -68.214911) (xy 352.495104 -68.24218)
			(xy 352.495104 -69.10578) (xy 352.494618 -69.133049) (xy 352.486856 -69.187033) (xy 352.471491 -69.239363)
			(xy 352.448834 -69.288973) (xy 352.419348 -69.334854) (xy 352.383633 -69.376071) (xy 352.342416 -69.411786)
			(xy 352.296535 -69.441272) (xy 352.246925 -69.463929) (xy 352.194595 -69.479294) (xy 352.140611 -69.487056)
			(xy 352.086073 -69.487056) (xy 352.032089 -69.479294) (xy 351.979759 -69.463929) (xy 351.930149 -69.441272)
			(xy 351.884268 -69.411786) (xy 351.843051 -69.376071) (xy 351.807336 -69.334854) (xy 351.77785 -69.288973)
			(xy 351.755193 -69.239363) (xy 351.739828 -69.187033) (xy 351.732066 -69.133049) (xy 351.73158 -69.10578)
			(xy 318.851129 -69.10578) (xy 318.839859 -69.140837) (xy 318.793154 -69.260098) (xy 318.739126 -69.376224)
			(xy 318.677982 -69.488767) (xy 318.60996 -69.597291) (xy 318.535323 -69.701376) (xy 318.454359 -69.800619)
			(xy 318.367382 -69.894637) (xy 318.274728 -69.983066) (xy 318.176756 -70.065563) (xy 318.073844 -70.14181)
			(xy 317.966391 -70.211512) (xy 317.854813 -70.274398) (xy 317.739541 -70.330226) (xy 317.621021 -70.37878)
			(xy 317.499712 -70.419871) (xy 317.376083 -70.453341) (xy 317.250612 -70.47906) (xy 317.123785 -70.496929)
			(xy 316.996092 -70.506879) (xy 316.868028 -70.508871) (xy 316.740088 -70.502897) (xy 316.612766 -70.488981)
			(xy 316.486557 -70.467176) (xy 316.361946 -70.437567) (xy 316.239418 -70.400269) (xy 316.119445 -70.355425)
			(xy 316.002493 -70.303209) (xy 315.889013 -70.243823) (xy 315.779444 -70.177497) (xy 315.674211 -70.104487)
			(xy 315.57372 -70.025077) (xy 315.478361 -69.939572) (xy 315.388502 -69.848305) (xy 315.304491 -69.751627)
			(xy 315.226653 -69.649914) (xy 315.155289 -69.543558) (xy 315.090675 -69.432971) (xy 315.033061 -69.318581)
			(xy 314.98267 -69.200831) (xy 314.939697 -69.080175) (xy 314.904308 -68.957082) (xy 314.876641 -68.832026)
			(xy 314.856802 -68.705492) (xy 314.844867 -68.57797) (xy 314.840884 -68.449952) (xy 298.511468 -68.449952)
			(xy 298.511468 -71.213074) (xy 341.168388 -71.213074) (xy 341.168388 -71.158526) (xy 341.176151 -71.104534)
			(xy 341.19152 -71.052197) (xy 341.214181 -71.00258) (xy 341.243673 -70.956692) (xy 341.279395 -70.91547)
			(xy 341.320621 -70.879751) (xy 341.366511 -70.850263) (xy 341.416131 -70.827607) (xy 341.46847 -70.812243)
			(xy 341.522462 -70.804485) (xy 341.549736 -70.804024) (xy 342.413336 -70.804024) (xy 342.440603 -70.804541)
			(xy 342.49458 -70.812306) (xy 342.546904 -70.827674) (xy 342.596508 -70.850332) (xy 342.642382 -70.879817)
			(xy 342.683594 -70.915531) (xy 342.719304 -70.956747) (xy 342.748786 -71.002624) (xy 342.771438 -71.05223)
			(xy 342.786801 -71.104555) (xy 342.794562 -71.158533) (xy 342.794562 -71.213067) (xy 342.786801 -71.267045)
			(xy 342.771438 -71.31937) (xy 342.748786 -71.368976) (xy 342.719304 -71.414853) (xy 342.683594 -71.456069)
			(xy 342.642382 -71.491783) (xy 342.596508 -71.521268) (xy 342.546904 -71.543926) (xy 342.49458 -71.559294)
			(xy 342.440603 -71.567059) (xy 342.413336 -71.567548) (xy 341.549736 -71.567548) (xy 341.522462 -71.567115)
			(xy 341.46847 -71.559357) (xy 341.416131 -71.543993) (xy 341.366511 -71.521337) (xy 341.320621 -71.491849)
			(xy 341.279395 -71.45613) (xy 341.243673 -71.414908) (xy 341.214181 -71.36902) (xy 341.19152 -71.319403)
			(xy 341.176151 -71.267066) (xy 341.168388 -71.213074) (xy 298.511468 -71.213074) (xy 298.511468 -71.844253)
			(xy 346.360454 -71.844253) (xy 346.360454 -71.789747) (xy 346.368211 -71.735796) (xy 346.383567 -71.683499)
			(xy 346.406209 -71.633919) (xy 346.435677 -71.588066) (xy 346.47137 -71.546873) (xy 346.512562 -71.511179)
			(xy 346.558415 -71.481711) (xy 346.607995 -71.459068) (xy 346.660293 -71.443712) (xy 346.714243 -71.435954)
			(xy 346.741496 -71.435468) (xy 347.605096 -71.435468) (xy 347.632347 -71.435979) (xy 347.686295 -71.443735)
			(xy 347.73859 -71.45909) (xy 347.788168 -71.481731) (xy 347.834019 -71.511197) (xy 347.875209 -71.546888)
			(xy 347.910901 -71.588078) (xy 347.940367 -71.633929) (xy 347.963009 -71.683506) (xy 347.978364 -71.735801)
			(xy 347.986121 -71.789749) (xy 347.986121 -71.844251) (xy 347.978364 -71.898199) (xy 347.963009 -71.950494)
			(xy 347.940367 -72.000071) (xy 347.910901 -72.045922) (xy 347.875209 -72.087112) (xy 347.834019 -72.122803)
			(xy 347.788168 -72.152269) (xy 347.73859 -72.17491) (xy 347.686295 -72.190265) (xy 347.632347 -72.198021)
			(xy 347.605096 -72.198484) (xy 346.741496 -72.198484) (xy 346.714243 -72.198046) (xy 346.660293 -72.190288)
			(xy 346.607995 -72.174932) (xy 346.558415 -72.152289) (xy 346.512562 -72.122821) (xy 346.47137 -72.087127)
			(xy 346.435677 -72.045934) (xy 346.406209 -72.000081) (xy 346.383567 -71.950501) (xy 346.368211 -71.898204)
			(xy 346.360454 -71.844253) (xy 298.511468 -71.844253) (xy 298.511468 -72.404055) (xy 332.037847 -72.404055)
			(xy 332.037847 -72.349545) (xy 332.045606 -72.295589) (xy 332.060964 -72.243286) (xy 332.083611 -72.193702)
			(xy 332.113083 -72.147846) (xy 332.148782 -72.106651) (xy 332.189981 -72.070957) (xy 332.235841 -72.041489)
			(xy 332.285427 -72.018849) (xy 332.337732 -72.003496) (xy 332.391689 -71.995744) (xy 332.418944 -71.995284)
			(xy 333.282544 -71.995284) (xy 333.309793 -71.995789) (xy 333.363734 -72.00355) (xy 333.416023 -72.018909)
			(xy 333.465593 -72.041552) (xy 333.511437 -72.071019) (xy 333.552622 -72.10671) (xy 333.588308 -72.147898)
			(xy 333.617769 -72.193745) (xy 333.640407 -72.243318) (xy 333.655759 -72.295609) (xy 333.660251 -72.326853)
			(xy 343.845854 -72.326853) (xy 343.845854 -72.272347) (xy 343.853611 -72.218396) (xy 343.868967 -72.166099)
			(xy 343.891609 -72.116519) (xy 343.921077 -72.070666) (xy 343.95677 -72.029473) (xy 343.997962 -71.993779)
			(xy 344.043815 -71.964311) (xy 344.093395 -71.941668) (xy 344.145693 -71.926312) (xy 344.199643 -71.918554)
			(xy 344.226896 -71.918068) (xy 345.090496 -71.918068) (xy 345.117747 -71.918579) (xy 345.171695 -71.926335)
			(xy 345.22399 -71.94169) (xy 345.273568 -71.964331) (xy 345.319419 -71.993797) (xy 345.360609 -72.029488)
			(xy 345.396301 -72.070678) (xy 345.425767 -72.116529) (xy 345.448409 -72.166106) (xy 345.463764 -72.218401)
			(xy 345.471521 -72.272349) (xy 345.471521 -72.326851) (xy 345.463764 -72.380799) (xy 345.448409 -72.433094)
			(xy 345.425767 -72.482671) (xy 345.396301 -72.528522) (xy 345.360609 -72.569712) (xy 345.319419 -72.605403)
			(xy 345.273568 -72.634869) (xy 345.22399 -72.65751) (xy 345.171695 -72.672865) (xy 345.117747 -72.680621)
			(xy 345.090496 -72.681084) (xy 344.226896 -72.681084) (xy 344.199643 -72.680646) (xy 344.145693 -72.672888)
			(xy 344.093395 -72.657532) (xy 344.043815 -72.634889) (xy 343.997962 -72.605421) (xy 343.95677 -72.569727)
			(xy 343.921077 -72.528534) (xy 343.891609 -72.482681) (xy 343.868967 -72.433101) (xy 343.853611 -72.380804)
			(xy 343.845854 -72.326853) (xy 333.660251 -72.326853) (xy 333.663514 -72.349551) (xy 333.663514 -72.404049)
			(xy 333.655759 -72.457991) (xy 333.640407 -72.510282) (xy 333.617769 -72.559855) (xy 333.588308 -72.605702)
			(xy 333.552622 -72.64689) (xy 333.511437 -72.682581) (xy 333.465593 -72.712048) (xy 333.416023 -72.734691)
			(xy 333.363734 -72.75005) (xy 333.309793 -72.757811) (xy 333.282544 -72.7583) (xy 332.418944 -72.7583)
			(xy 332.391689 -72.757856) (xy 332.337732 -72.750104) (xy 332.285427 -72.734751) (xy 332.235841 -72.712111)
			(xy 332.189981 -72.682643) (xy 332.148782 -72.646949) (xy 332.113083 -72.605754) (xy 332.083611 -72.559898)
			(xy 332.060964 -72.510314) (xy 332.045606 -72.458011) (xy 332.037847 -72.404055) (xy 298.511468 -72.404055)
			(xy 298.511468 -74.617072) (xy 327.277726 -74.617072) (xy 327.281813 -74.561227) (xy 327.293988 -74.506573)
			(xy 327.31399 -74.454274) (xy 327.341395 -74.405445) (xy 327.375617 -74.361126) (xy 327.415927 -74.322262)
			(xy 327.461466 -74.289681) (xy 327.511264 -74.264078) (xy 327.564259 -74.245999) (xy 327.619321 -74.235828)
			(xy 327.675278 -74.233783) (xy 327.730936 -74.239908) (xy 327.785109 -74.25407) (xy 327.836643 -74.27597)
			(xy 327.884439 -74.305139) (xy 327.927478 -74.340957) (xy 327.941626 -74.356747) (xy 330.744122 -74.356747)
			(xy 330.744122 -74.302253) (xy 330.751877 -74.248315) (xy 330.767229 -74.196029) (xy 330.789865 -74.146459)
			(xy 330.819325 -74.100616) (xy 330.855009 -74.059431) (xy 330.89619 -74.023744) (xy 330.942031 -73.99428)
			(xy 330.991599 -73.97164) (xy 331.043883 -73.956284) (xy 331.097821 -73.948524) (xy 331.125068 -73.948036)
			(xy 331.988668 -73.948036) (xy 332.015926 -73.948409) (xy 332.069886 -73.956163) (xy 332.122194 -73.971518)
			(xy 332.171784 -73.994161) (xy 332.217646 -74.023632) (xy 332.258848 -74.05933) (xy 332.294549 -74.100528)
			(xy 332.324023 -74.146388) (xy 332.346671 -74.195976) (xy 332.36203 -74.248283) (xy 332.369789 -74.302243)
			(xy 332.369789 -74.356757) (xy 332.36203 -74.410717) (xy 332.346671 -74.463024) (xy 332.324023 -74.512612)
			(xy 332.294549 -74.558472) (xy 332.26684 -74.590448) (xy 336.274202 -74.590448) (xy 336.274202 -74.535953)
			(xy 336.281957 -74.482012) (xy 336.297309 -74.429724) (xy 336.319945 -74.380153) (xy 336.349406 -74.334308)
			(xy 336.38509 -74.293121) (xy 336.426272 -74.257432) (xy 336.472114 -74.227966) (xy 336.521683 -74.205324)
			(xy 336.573969 -74.189966) (xy 336.627909 -74.182205) (xy 336.655156 -74.181716) (xy 337.518756 -74.181716)
			(xy 337.546013 -74.182128) (xy 337.599972 -74.18988) (xy 337.652278 -74.205233) (xy 337.701867 -74.227875)
			(xy 337.747729 -74.257344) (xy 337.788929 -74.29304) (xy 337.82463 -74.334236) (xy 337.854104 -74.380094)
			(xy 337.876751 -74.42968) (xy 337.89211 -74.481985) (xy 337.899869 -74.535943) (xy 337.899869 -74.55185)
			(xy 339.156294 -74.55185) (xy 339.156294 -74.49735) (xy 339.16405 -74.443405) (xy 339.179404 -74.391113)
			(xy 339.202044 -74.341539) (xy 339.231509 -74.29569) (xy 339.267198 -74.254502) (xy 339.308386 -74.218812)
			(xy 339.354233 -74.189347) (xy 339.403808 -74.166707) (xy 339.456099 -74.151352) (xy 339.510044 -74.143595)
			(xy 339.537294 -74.143108) (xy 340.400894 -74.143108) (xy 340.428148 -74.143538) (xy 340.482102 -74.151295)
			(xy 340.534403 -74.166651) (xy 340.583986 -74.189294) (xy 340.629842 -74.218763) (xy 340.671037 -74.254459)
			(xy 340.706733 -74.295653) (xy 340.736203 -74.341509) (xy 340.758847 -74.391091) (xy 340.774204 -74.443392)
			(xy 340.781961 -74.497346) (xy 340.781961 -74.551854) (xy 340.774204 -74.605808) (xy 340.758847 -74.658109)
			(xy 340.736203 -74.707691) (xy 340.706733 -74.753547) (xy 340.694254 -74.767948) (xy 421.29456 -74.767948)
			(xy 421.29456 -66.06794) (xy 421.295065 -65.962416) (xy 421.303149 -65.751522) (xy 421.319305 -65.541093)
			(xy 421.343508 -65.331436) (xy 421.375725 -65.122861) (xy 421.415907 -64.915673) (xy 421.463995 -64.710176)
			(xy 421.519919 -64.506672) (xy 421.583596 -64.305459) (xy 421.654934 -64.106832) (xy 421.733828 -63.911084)
			(xy 421.820161 -63.718502) (xy 421.913808 -63.529367) (xy 422.01463 -63.343958) (xy 422.12248 -63.162547)
			(xy 422.237199 -62.9854) (xy 422.358619 -62.812778) (xy 422.486562 -62.644932) (xy 422.62084 -62.48211)
			(xy 422.761256 -62.324551) (xy 422.907604 -62.172486) (xy 423.059669 -62.026138) (xy 423.217228 -61.885722)
			(xy 423.38005 -61.751444) (xy 423.547896 -61.623501) (xy 423.720518 -61.502081) (xy 423.897665 -61.387362)
			(xy 424.079076 -61.279512) (xy 424.264485 -61.17869) (xy 424.45362 -61.085043) (xy 424.646202 -60.99871)
			(xy 424.84195 -60.919816) (xy 425.040577 -60.848478) (xy 425.24179 -60.784801) (xy 425.445294 -60.728877)
			(xy 425.650791 -60.680789) (xy 425.857979 -60.640607) (xy 426.066554 -60.60839) (xy 426.276211 -60.584187)
			(xy 426.48664 -60.568031) (xy 426.697534 -60.559947) (xy 426.908582 -60.559947) (xy 427.119476 -60.568031)
			(xy 427.329905 -60.584187) (xy 427.539562 -60.60839) (xy 427.748137 -60.640607) (xy 427.955325 -60.680789)
			(xy 428.160822 -60.728877) (xy 428.364326 -60.784801) (xy 428.565539 -60.848478) (xy 428.764166 -60.919816)
			(xy 428.959914 -60.99871) (xy 429.152496 -61.085043) (xy 429.341631 -61.17869) (xy 429.52704 -61.279512)
			(xy 429.708451 -61.387362) (xy 429.885598 -61.502081) (xy 430.05822 -61.623501) (xy 430.226066 -61.751444)
			(xy 430.388888 -61.885722) (xy 430.546447 -62.026138) (xy 430.698512 -62.172486) (xy 430.84486 -62.324551)
			(xy 430.985276 -62.48211) (xy 431.119554 -62.644932) (xy 431.247497 -62.812778) (xy 431.368917 -62.9854)
			(xy 431.483636 -63.162547) (xy 431.591486 -63.343958) (xy 431.692308 -63.529367) (xy 431.785955 -63.718502)
			(xy 431.872288 -63.911084) (xy 431.951182 -64.106832) (xy 432.02252 -64.305459) (xy 432.086197 -64.506672)
			(xy 432.142121 -64.710176) (xy 432.190209 -64.915673) (xy 432.230391 -65.122861) (xy 432.262608 -65.331436)
			(xy 432.286811 -65.541093) (xy 432.302967 -65.751522) (xy 432.311051 -65.962416) (xy 432.311556 -66.06794)
			(xy 432.311556 -74.767948) (xy 432.311051 -74.873472) (xy 432.302967 -75.084366) (xy 432.286811 -75.294795)
			(xy 432.262608 -75.504452) (xy 432.230391 -75.713027) (xy 432.190209 -75.920215) (xy 432.142121 -76.125712)
			(xy 432.086197 -76.329216) (xy 432.02252 -76.530429) (xy 431.951182 -76.729056) (xy 431.872288 -76.924804)
			(xy 431.785955 -77.117386) (xy 431.692308 -77.306521) (xy 431.591486 -77.49193) (xy 431.483636 -77.673341)
			(xy 431.368917 -77.850488) (xy 431.247497 -78.02311) (xy 431.119554 -78.190956) (xy 430.985276 -78.353778)
			(xy 430.84486 -78.511337) (xy 430.698512 -78.663402) (xy 430.546447 -78.80975) (xy 430.388888 -78.950166)
			(xy 430.226066 -79.084444) (xy 430.05822 -79.212387) (xy 429.885598 -79.333807) (xy 429.708451 -79.448526)
			(xy 429.52704 -79.556376) (xy 429.341631 -79.657198) (xy 429.152496 -79.750845) (xy 428.959914 -79.837178)
			(xy 428.764166 -79.916072) (xy 428.565539 -79.98741) (xy 428.364326 -80.051087) (xy 428.160822 -80.107011)
			(xy 427.955325 -80.155099) (xy 427.748137 -80.195281) (xy 427.539562 -80.227498) (xy 427.329905 -80.251701)
			(xy 427.119476 -80.267857) (xy 426.908582 -80.275941) (xy 426.697534 -80.275941) (xy 426.48664 -80.267857)
			(xy 426.276211 -80.251701) (xy 426.066554 -80.227498) (xy 425.857979 -80.195281) (xy 425.650791 -80.155099)
			(xy 425.445294 -80.107011) (xy 425.24179 -80.051087) (xy 425.040577 -79.98741) (xy 424.84195 -79.916072)
			(xy 424.646202 -79.837178) (xy 424.45362 -79.750845) (xy 424.264485 -79.657198) (xy 424.079076 -79.556376)
			(xy 423.897665 -79.448526) (xy 423.720518 -79.333807) (xy 423.547896 -79.212387) (xy 423.38005 -79.084444)
			(xy 423.217228 -78.950166) (xy 423.059669 -78.80975) (xy 422.907604 -78.663402) (xy 422.761256 -78.511337)
			(xy 422.62084 -78.353778) (xy 422.486562 -78.190956) (xy 422.358619 -78.02311) (xy 422.237199 -77.850488)
			(xy 422.12248 -77.673341) (xy 422.01463 -77.49193) (xy 421.913808 -77.306521) (xy 421.820161 -77.117386)
			(xy 421.733828 -76.924804) (xy 421.654934 -76.729056) (xy 421.583596 -76.530429) (xy 421.519919 -76.329216)
			(xy 421.463995 -76.125712) (xy 421.415907 -75.920215) (xy 421.375725 -75.713027) (xy 421.343508 -75.504452)
			(xy 421.319305 -75.294795) (xy 421.303149 -75.084366) (xy 421.295065 -74.873472) (xy 421.29456 -74.767948)
			(xy 340.694254 -74.767948) (xy 340.671037 -74.794741) (xy 340.629842 -74.830437) (xy 340.583986 -74.859906)
			(xy 340.534403 -74.882549) (xy 340.482102 -74.897905) (xy 340.428148 -74.905662) (xy 340.400894 -74.906124)
			(xy 339.537294 -74.906124) (xy 339.510044 -74.905605) (xy 339.456099 -74.897848) (xy 339.403808 -74.882493)
			(xy 339.354233 -74.859853) (xy 339.308386 -74.830388) (xy 339.267198 -74.794698) (xy 339.231509 -74.75351)
			(xy 339.202044 -74.707661) (xy 339.179404 -74.658087) (xy 339.16405 -74.605795) (xy 339.156294 -74.55185)
			(xy 337.899869 -74.55185) (xy 337.899869 -74.590457) (xy 337.89211 -74.644415) (xy 337.876751 -74.69672)
			(xy 337.854104 -74.746306) (xy 337.82463 -74.792164) (xy 337.788929 -74.83336) (xy 337.747729 -74.869056)
			(xy 337.701867 -74.898525) (xy 337.652278 -74.921167) (xy 337.599972 -74.93652) (xy 337.546013 -74.944272)
			(xy 337.518756 -74.944732) (xy 336.655156 -74.944732) (xy 336.627909 -74.944195) (xy 336.573969 -74.936434)
			(xy 336.521683 -74.921076) (xy 336.472114 -74.898434) (xy 336.426272 -74.868968) (xy 336.38509 -74.833279)
			(xy 336.349406 -74.792092) (xy 336.319945 -74.746247) (xy 336.297309 -74.696676) (xy 336.281957 -74.644388)
			(xy 336.274202 -74.590448) (xy 332.26684 -74.590448) (xy 332.258848 -74.59967) (xy 332.217646 -74.635368)
			(xy 332.171784 -74.664839) (xy 332.122194 -74.687482) (xy 332.069886 -74.702837) (xy 332.015926 -74.710591)
			(xy 331.988668 -74.711052) (xy 331.125068 -74.711052) (xy 331.097821 -74.710476) (xy 331.043883 -74.702716)
			(xy 330.991599 -74.68736) (xy 330.942031 -74.66472) (xy 330.89619 -74.635256) (xy 330.855009 -74.599569)
			(xy 330.819325 -74.558384) (xy 330.789865 -74.512541) (xy 330.767229 -74.462971) (xy 330.751877 -74.410685)
			(xy 330.744122 -74.356747) (xy 327.941626 -74.356747) (xy 327.964844 -74.38266) (xy 327.99574 -74.429358)
			(xy 328.019507 -74.480058) (xy 328.035639 -74.533678) (xy 328.043791 -74.589075) (xy 328.044302 -74.617072)
			(xy 328.043791 -74.645069) (xy 328.035639 -74.700466) (xy 328.019507 -74.754086) (xy 327.99574 -74.804786)
			(xy 327.964844 -74.851484) (xy 327.927478 -74.893187) (xy 327.884439 -74.929005) (xy 327.836643 -74.958174)
			(xy 327.785109 -74.980074) (xy 327.730936 -74.994236) (xy 327.675278 -75.000361) (xy 327.619321 -74.998316)
			(xy 327.564259 -74.988145) (xy 327.511264 -74.970066) (xy 327.461466 -74.944463) (xy 327.415927 -74.911882)
			(xy 327.375617 -74.873018) (xy 327.341395 -74.828699) (xy 327.31399 -74.77987) (xy 327.293988 -74.727571)
			(xy 327.281813 -74.672917) (xy 327.277726 -74.617072) (xy 298.511468 -74.617072) (xy 298.511468 -74.760836)
			(xy 298.510963 -74.86636) (xy 298.502879 -75.077254) (xy 298.486723 -75.287683) (xy 298.46252 -75.49734)
			(xy 298.430303 -75.705915) (xy 298.390121 -75.913103) (xy 298.342033 -76.1186) (xy 298.333664 -76.149054)
			(xy 327.558346 -76.149054) (xy 327.558346 -76.094546) (xy 327.566103 -76.040594) (xy 327.581459 -75.988295)
			(xy 327.604102 -75.938714) (xy 327.633571 -75.892859) (xy 327.669266 -75.851666) (xy 327.710459 -75.815971)
			(xy 327.756314 -75.786502) (xy 327.805895 -75.763859) (xy 327.858194 -75.748503) (xy 327.912146 -75.740746)
			(xy 327.9394 -75.74026) (xy 328.803 -75.74026) (xy 328.830249 -75.74081) (xy 328.884192 -75.748566)
			(xy 328.936482 -75.76392) (xy 328.986055 -75.786559) (xy 329.031902 -75.816023) (xy 329.073089 -75.851711)
			(xy 329.108777 -75.892898) (xy 329.138241 -75.938745) (xy 329.16088 -75.988318) (xy 329.169581 -76.017949)
			(xy 334.874382 -76.017949) (xy 334.874382 -75.963451) (xy 334.882137 -75.909507) (xy 334.89749 -75.857216)
			(xy 334.920128 -75.807642) (xy 334.949591 -75.761793) (xy 334.985278 -75.720605) (xy 335.026463 -75.684914)
			(xy 335.072308 -75.655447) (xy 335.12188 -75.632803) (xy 335.17417 -75.617445) (xy 335.228113 -75.609684)
			(xy 335.255362 -75.609196) (xy 336.118962 -75.609196) (xy 336.146217 -75.609649) (xy 336.200173 -75.617401)
			(xy 336.252475 -75.632754) (xy 336.302061 -75.655395) (xy 336.347919 -75.684862) (xy 336.389117 -75.720556)
			(xy 336.424815 -75.76175) (xy 336.454287 -75.807606) (xy 336.476932 -75.857189) (xy 336.49229 -75.90949)
			(xy 336.500049 -75.963445) (xy 336.500049 -76.017955) (xy 336.49229 -76.07191) (xy 336.476932 -76.124211)
			(xy 336.454287 -76.173794) (xy 336.424815 -76.21965) (xy 336.389117 -76.260844) (xy 336.347919 -76.296538)
			(xy 336.302061 -76.326005) (xy 336.252475 -76.348646) (xy 336.200173 -76.363999) (xy 336.146217 -76.371751)
			(xy 336.118962 -76.372212) (xy 335.255362 -76.372212) (xy 335.228113 -76.371716) (xy 335.17417 -76.363955)
			(xy 335.12188 -76.348597) (xy 335.072308 -76.325953) (xy 335.026463 -76.296486) (xy 334.985278 -76.260795)
			(xy 334.949591 -76.219607) (xy 334.920128 -76.173758) (xy 334.89749 -76.124184) (xy 334.882137 -76.071893)
			(xy 334.874382 -76.017949) (xy 329.169581 -76.017949) (xy 329.176234 -76.040608) (xy 329.18399 -76.094551)
			(xy 329.18399 -76.149049) (xy 329.176234 -76.202992) (xy 329.16088 -76.255282) (xy 329.138241 -76.304855)
			(xy 329.108777 -76.350702) (xy 329.073089 -76.391889) (xy 329.031902 -76.427577) (xy 328.986055 -76.457041)
			(xy 328.936482 -76.47968) (xy 328.884192 -76.495034) (xy 328.830249 -76.50279) (xy 328.803 -76.503276)
			(xy 327.9394 -76.503276) (xy 327.912146 -76.502854) (xy 327.858194 -76.495097) (xy 327.805895 -76.479741)
			(xy 327.756314 -76.457098) (xy 327.710459 -76.427629) (xy 327.669266 -76.391934) (xy 327.633571 -76.350741)
			(xy 327.604102 -76.304886) (xy 327.581459 -76.255305) (xy 327.566103 -76.203006) (xy 327.558346 -76.149054)
			(xy 298.333664 -76.149054) (xy 298.286109 -76.322104) (xy 298.222432 -76.523317) (xy 298.151094 -76.721944)
			(xy 298.0722 -76.917692) (xy 297.985867 -77.110274) (xy 297.89222 -77.299409) (xy 297.791398 -77.484818)
			(xy 297.683548 -77.666229) (xy 297.568829 -77.843376) (xy 297.455321 -78.00475) (xy 330.84567 -78.00475)
			(xy 330.84567 -77.95025) (xy 330.853426 -77.896304) (xy 330.868779 -77.84401) (xy 330.891419 -77.794434)
			(xy 330.920883 -77.748584) (xy 330.956571 -77.707394) (xy 330.997759 -77.671702) (xy 331.043606 -77.642234)
			(xy 331.09318 -77.619591) (xy 331.145472 -77.604232) (xy 331.199418 -77.596472) (xy 331.226668 -77.595984)
			(xy 332.090268 -77.595984) (xy 332.117522 -77.596461) (xy 332.171475 -77.604214) (xy 332.223776 -77.619567)
			(xy 332.273359 -77.642207) (xy 332.319215 -77.671674) (xy 332.360411 -77.707367) (xy 332.396107 -77.748559)
			(xy 332.425577 -77.794413) (xy 332.448222 -77.843994) (xy 332.463579 -77.896294) (xy 332.471337 -77.950246)
			(xy 332.471337 -78.004754) (xy 332.463579 -78.058706) (xy 332.448222 -78.111006) (xy 332.425577 -78.160587)
			(xy 332.396107 -78.206441) (xy 332.360411 -78.247633) (xy 332.319215 -78.283326) (xy 332.273359 -78.312793)
			(xy 332.223776 -78.335433) (xy 332.171475 -78.350786) (xy 332.117522 -78.358539) (xy 332.090268 -78.359)
			(xy 331.226668 -78.359) (xy 331.199418 -78.358528) (xy 331.145472 -78.350768) (xy 331.09318 -78.335409)
			(xy 331.043606 -78.312766) (xy 330.997759 -78.283298) (xy 330.956571 -78.247606) (xy 330.920883 -78.206416)
			(xy 330.891419 -78.160566) (xy 330.868779 -78.11099) (xy 330.853426 -78.058696) (xy 330.84567 -78.00475)
			(xy 297.455321 -78.00475) (xy 297.447409 -78.015998) (xy 297.319466 -78.183844) (xy 297.185188 -78.346666)
			(xy 297.044772 -78.504225) (xy 296.898424 -78.65629) (xy 296.746359 -78.802638) (xy 296.5888 -78.943054)
			(xy 296.425978 -79.077332) (xy 296.258132 -79.205275) (xy 296.08551 -79.326695) (xy 295.908363 -79.441414)
			(xy 295.726952 -79.549264) (xy 295.541543 -79.650086) (xy 295.352408 -79.743733) (xy 295.159826 -79.830066)
			(xy 294.964078 -79.90896) (xy 294.765451 -79.980298) (xy 294.564238 -80.043975) (xy 294.360734 -80.099899)
			(xy 294.155237 -80.147987) (xy 293.948049 -80.188169) (xy 293.739474 -80.220386) (xy 293.529817 -80.244589)
			(xy 293.319388 -80.260745) (xy 293.108494 -80.268829) (xy 292.897446 -80.268829) (xy 292.686552 -80.260745)
			(xy 292.476123 -80.244589) (xy 292.266466 -80.220386) (xy 292.057891 -80.188169) (xy 291.850703 -80.147987)
			(xy 291.645206 -80.099899) (xy 291.441702 -80.043975) (xy 291.240489 -79.980298) (xy 291.041862 -79.90896)
			(xy 290.846114 -79.830066) (xy 290.653532 -79.743733) (xy 290.464397 -79.650086) (xy 290.278988 -79.549264)
			(xy 290.097577 -79.441414) (xy 289.92043 -79.326695) (xy 289.747808 -79.205275) (xy 289.579962 -79.077332)
			(xy 289.41714 -78.943054) (xy 289.259581 -78.802638) (xy 289.107516 -78.65629) (xy 288.961168 -78.504225)
			(xy 288.820752 -78.346666) (xy 288.686474 -78.183844) (xy 288.558531 -78.015998) (xy 288.437111 -77.843376)
			(xy 288.322392 -77.666229) (xy 288.214542 -77.484818) (xy 288.11372 -77.299409) (xy 288.020073 -77.110274)
			(xy 287.93374 -76.917692) (xy 287.854846 -76.721944) (xy 287.783508 -76.523317) (xy 287.719831 -76.322104)
			(xy 287.663907 -76.1186) (xy 287.615819 -75.913103) (xy 287.575637 -75.705915) (xy 287.54342 -75.49734)
			(xy 287.519217 -75.287683) (xy 287.503061 -75.077254) (xy 287.494977 -74.86636) (xy 287.494472 -74.760836)
			(xy 184.371488 -74.760836) (xy 184.371488 -74.767948) (xy 184.370983 -74.873472) (xy 184.362899 -75.084366)
			(xy 184.346743 -75.294795) (xy 184.32254 -75.504452) (xy 184.290323 -75.713027) (xy 184.250141 -75.920215)
			(xy 184.202053 -76.125712) (xy 184.146129 -76.329216) (xy 184.082452 -76.530429) (xy 184.011114 -76.729056)
			(xy 183.93222 -76.924804) (xy 183.845887 -77.117386) (xy 183.75224 -77.306521) (xy 183.651418 -77.49193)
			(xy 183.543568 -77.673341) (xy 183.428849 -77.850488) (xy 183.307429 -78.02311) (xy 183.179486 -78.190956)
			(xy 183.045208 -78.353778) (xy 182.904792 -78.511337) (xy 182.758444 -78.663402) (xy 182.606379 -78.80975)
			(xy 182.44882 -78.950166) (xy 182.285998 -79.084444) (xy 182.118152 -79.212387) (xy 181.94553 -79.333807)
			(xy 181.768383 -79.448526) (xy 181.586972 -79.556376) (xy 181.401563 -79.657198) (xy 181.212428 -79.750845)
			(xy 181.019846 -79.837178) (xy 180.824098 -79.916072) (xy 180.625471 -79.98741) (xy 180.424258 -80.051087)
			(xy 180.220754 -80.107011) (xy 180.015257 -80.155099) (xy 179.808069 -80.195281) (xy 179.599494 -80.227498)
			(xy 179.389837 -80.251701) (xy 179.179408 -80.267857) (xy 178.968514 -80.275941) (xy 178.757466 -80.275941)
			(xy 178.546572 -80.267857) (xy 178.336143 -80.251701) (xy 178.126486 -80.227498) (xy 177.917911 -80.195281)
			(xy 177.710723 -80.155099) (xy 177.505226 -80.107011) (xy 177.301722 -80.051087) (xy 177.100509 -79.98741)
			(xy 176.901882 -79.916072) (xy 176.706134 -79.837178) (xy 176.513552 -79.750845) (xy 176.324417 -79.657198)
			(xy 176.139008 -79.556376) (xy 175.957597 -79.448526) (xy 175.78045 -79.333807) (xy 175.607828 -79.212387)
			(xy 175.439982 -79.084444) (xy 175.27716 -78.950166) (xy 175.119601 -78.80975) (xy 174.967536 -78.663402)
			(xy 174.821188 -78.511337) (xy 174.680772 -78.353778) (xy 174.546494 -78.190956) (xy 174.418551 -78.02311)
			(xy 174.297131 -77.850488) (xy 174.182412 -77.673341) (xy 174.074562 -77.49193) (xy 173.97374 -77.306521)
			(xy 173.880093 -77.117386) (xy 173.79376 -76.924804) (xy 173.714866 -76.729056) (xy 173.643528 -76.530429)
			(xy 173.579851 -76.329216) (xy 173.523927 -76.125712) (xy 173.475839 -75.920215) (xy 173.435657 -75.713027)
			(xy 173.40344 -75.504452) (xy 173.379237 -75.294795) (xy 173.363081 -75.084366) (xy 173.354997 -74.873472)
			(xy 173.354492 -74.767948) (xy 50.571366 -74.767948) (xy 50.570895 -74.86636) (xy 50.562811 -75.077254)
			(xy 50.546655 -75.287683) (xy 50.522452 -75.49734) (xy 50.490235 -75.705915) (xy 50.450053 -75.913103)
			(xy 50.401965 -76.1186) (xy 50.346041 -76.322104) (xy 50.282364 -76.523317) (xy 50.211026 -76.721944)
			(xy 50.132132 -76.917692) (xy 50.045799 -77.110274) (xy 49.952152 -77.299409) (xy 49.85133 -77.484818)
			(xy 49.74348 -77.666229) (xy 49.628761 -77.843376) (xy 49.507341 -78.015998) (xy 49.379398 -78.183844)
			(xy 49.24512 -78.346666) (xy 49.104704 -78.504225) (xy 48.958356 -78.65629) (xy 48.806291 -78.802638)
			(xy 48.648732 -78.943054) (xy 48.48591 -79.077332) (xy 48.318064 -79.205275) (xy 48.145442 -79.326695)
			(xy 47.968295 -79.441414) (xy 47.786884 -79.549264) (xy 47.601475 -79.650086) (xy 47.41234 -79.743733)
			(xy 47.219758 -79.830066) (xy 47.02401 -79.90896) (xy 46.825383 -79.980298) (xy 46.62417 -80.043975)
			(xy 46.420666 -80.099899) (xy 46.215169 -80.147987) (xy 46.007981 -80.188169) (xy 45.799406 -80.220386)
			(xy 45.589749 -80.244589) (xy 45.37932 -80.260745) (xy 45.168426 -80.268829) (xy 44.957378 -80.268829)
			(xy 44.746484 -80.260745) (xy 44.536055 -80.244589) (xy 44.326398 -80.220386) (xy 44.117823 -80.188169)
			(xy 43.910635 -80.147987) (xy 43.705138 -80.099899) (xy 43.501634 -80.043975) (xy 43.300421 -79.980298)
			(xy 43.101794 -79.90896) (xy 42.906046 -79.830066) (xy 42.713464 -79.743733) (xy 42.524329 -79.650086)
			(xy 42.33892 -79.549264) (xy 42.157509 -79.441414) (xy 41.980362 -79.326695) (xy 41.80774 -79.205275)
			(xy 41.639894 -79.077332) (xy 41.477072 -78.943054) (xy 41.319513 -78.802638) (xy 41.167448 -78.65629)
			(xy 41.0211 -78.504225) (xy 40.880684 -78.346666) (xy 40.746406 -78.183844) (xy 40.618463 -78.015998)
			(xy 40.497043 -77.843376) (xy 40.382324 -77.666229) (xy 40.274474 -77.484818) (xy 40.173652 -77.299409)
			(xy 40.080005 -77.110274) (xy 39.993672 -76.917692) (xy 39.914778 -76.721944) (xy 39.84344 -76.523317)
			(xy 39.779763 -76.322104) (xy 39.723839 -76.1186) (xy 39.675751 -75.913103) (xy 39.635569 -75.705915)
			(xy 39.603352 -75.49734) (xy 39.579149 -75.287683) (xy 39.562993 -75.077254) (xy 39.554909 -74.86636)
			(xy 39.554404 -74.760836) (xy 0.509016 -74.760836) (xy 0.509016 -77.671676) (xy 0.509504 -77.724899)
			(xy 0.51712 -77.831071) (xy 0.532286 -77.93643) (xy 0.554925 -78.04044) (xy 0.584921 -78.142572)
			(xy 0.622123 -78.242305) (xy 0.666339 -78.339132) (xy 0.717347 -78.43256) (xy 0.774885 -78.522114)
			(xy 0.838661 -78.607338) (xy 0.908351 -78.687799) (xy 0.945642 -78.725776) (xy 1.77419 -79.554324)
			(xy 1.823602 -79.604436) (xy 1.917388 -79.709385) (xy 2.005143 -79.819428) (xy 2.08659 -79.934217)
			(xy 2.161473 -80.053392) (xy 2.229556 -80.176578) (xy 2.290626 -80.303388) (xy 2.344491 -80.433422)
			(xy 2.39098 -80.566271) (xy 2.429948 -80.701518) (xy 2.461272 -80.838737) (xy 2.484853 -80.977496)
			(xy 2.500618 -81.117359) (xy 2.508516 -81.257886) (xy 2.509012 -81.32826) (xy 2.509012 -81.69181)
			(xy 232.140667 -81.69181) (xy 232.145062 -81.517977) (xy 232.15749 -81.344533) (xy 232.177927 -81.171849)
			(xy 232.206328 -81.000295) (xy 232.242632 -80.830238) (xy 232.286762 -80.662042) (xy 232.338623 -80.496067)
			(xy 232.398104 -80.332668) (xy 232.465078 -80.172194) (xy 232.539402 -80.01499) (xy 232.620917 -79.86139)
			(xy 232.709448 -79.711725) (xy 232.804805 -79.566315) (xy 232.906785 -79.425469) (xy 233.01517 -79.289491)
			(xy 233.129727 -79.158671) (xy 233.250212 -79.033288) (xy 233.376366 -78.913612) (xy 233.50792 -78.799897)
			(xy 233.644592 -78.692389) (xy 233.715052 -78.641448) (xy 238.08436 -78.641448) (xy 238.15482 -78.692389)
			(xy 238.291492 -78.799897) (xy 238.423046 -78.913612) (xy 238.5492 -79.033288) (xy 238.669685 -79.158671)
			(xy 238.784242 -79.289491) (xy 238.892627 -79.425469) (xy 238.994607 -79.566315) (xy 239.089964 -79.711725)
			(xy 239.178495 -79.86139) (xy 239.26001 -80.01499) (xy 239.334334 -80.172194) (xy 239.401308 -80.332668)
			(xy 239.460789 -80.496067) (xy 239.51265 -80.662042) (xy 239.553507 -80.817765) (xy 333.938166 -80.817765)
			(xy 333.938166 -80.763235) (xy 333.945926 -80.70926) (xy 333.961289 -80.656938) (xy 333.98394 -80.607335)
			(xy 334.01342 -80.561461) (xy 334.049129 -80.520248) (xy 334.090338 -80.484537) (xy 334.136211 -80.455054)
			(xy 334.185812 -80.432398) (xy 334.238132 -80.417032) (xy 334.292107 -80.409268) (xy 334.319372 -80.40878)
			(xy 335.182972 -80.40878) (xy 335.210247 -80.409158) (xy 335.264243 -80.416917) (xy 335.316585 -80.432283)
			(xy 335.366207 -80.454941) (xy 335.412099 -80.484432) (xy 335.453327 -80.520153) (xy 335.489052 -80.561378)
			(xy 335.518545 -80.607268) (xy 335.541207 -80.656889) (xy 335.556577 -80.709229) (xy 335.56434 -80.763225)
			(xy 335.56434 -80.817775) (xy 335.556577 -80.871771) (xy 335.541207 -80.924111) (xy 335.518545 -80.973732)
			(xy 335.489052 -81.019622) (xy 335.453327 -81.060847) (xy 335.412099 -81.096568) (xy 335.366207 -81.126059)
			(xy 335.316585 -81.148717) (xy 335.264243 -81.164083) (xy 335.210247 -81.171842) (xy 335.182972 -81.172304)
			(xy 334.319372 -81.172304) (xy 334.292107 -81.171732) (xy 334.238132 -81.163968) (xy 334.185812 -81.148602)
			(xy 334.136211 -81.125946) (xy 334.090338 -81.096463) (xy 334.049129 -81.060752) (xy 334.01342 -81.019539)
			(xy 333.98394 -80.973665) (xy 333.961289 -80.924062) (xy 333.945926 -80.87174) (xy 333.938166 -80.817765)
			(xy 239.553507 -80.817765) (xy 239.55678 -80.830238) (xy 239.593084 -81.000295) (xy 239.621485 -81.171849)
			(xy 239.641922 -81.344533) (xy 239.65435 -81.517977) (xy 239.658745 -81.69181) (xy 239.655095 -81.865661)
			(xy 239.643409 -82.039157) (xy 239.640092 -82.06825) (xy 331.768962 -82.06825) (xy 331.768962 -82.01375)
			(xy 331.776717 -81.959803) (xy 331.792071 -81.90751) (xy 331.81471 -81.857933) (xy 331.844174 -81.812083)
			(xy 331.879862 -81.770892) (xy 331.921049 -81.735199) (xy 331.966896 -81.70573) (xy 332.01647 -81.683086)
			(xy 332.068762 -81.667726) (xy 332.122708 -81.659965) (xy 332.149958 -81.659476) (xy 333.013558 -81.659476)
			(xy 333.040812 -81.659968) (xy 333.094765 -81.66772) (xy 333.147066 -81.683072) (xy 333.196649 -81.705711)
			(xy 333.242505 -81.735177) (xy 333.283701 -81.770869) (xy 333.319398 -81.812061) (xy 333.348869 -81.857914)
			(xy 333.371513 -81.907495) (xy 333.386871 -81.959794) (xy 333.394629 -82.013746) (xy 333.394629 -82.068254)
			(xy 333.386871 -82.122206) (xy 333.371513 -82.174505) (xy 333.348869 -82.224086) (xy 333.319398 -82.269939)
			(xy 333.294774 -82.298353) (xy 336.189263 -82.298353) (xy 336.189263 -82.243847) (xy 336.197021 -82.189895)
			(xy 336.212377 -82.137597) (xy 336.235021 -82.088017) (xy 336.26449 -82.042163) (xy 336.300185 -82.000971)
			(xy 336.341379 -81.965278) (xy 336.387234 -81.935811) (xy 336.436816 -81.91317) (xy 336.489115 -81.897816)
			(xy 336.543067 -81.890062) (xy 336.57032 -81.8896) (xy 337.43392 -81.8896) (xy 337.461171 -81.890071)
			(xy 337.515118 -81.89783) (xy 337.567411 -81.913187) (xy 337.616987 -81.93583) (xy 337.662836 -81.965298)
			(xy 337.692804 -81.991267) (xy 339.478646 -81.991267) (xy 339.478646 -81.936733) (xy 339.486407 -81.882755)
			(xy 339.50177 -81.830431) (xy 339.524423 -81.780825) (xy 339.553905 -81.734948) (xy 339.589615 -81.693734)
			(xy 339.630827 -81.65802) (xy 339.676702 -81.628535) (xy 339.726306 -81.605879) (xy 339.77863 -81.590512)
			(xy 339.832607 -81.582748) (xy 339.859874 -81.58226) (xy 340.723474 -81.58226) (xy 340.750748 -81.582678)
			(xy 340.804741 -81.590437) (xy 340.857079 -81.605802) (xy 340.906699 -81.62846) (xy 340.952588 -81.657948)
			(xy 340.993814 -81.693668) (xy 341.029536 -81.734891) (xy 341.059028 -81.780778) (xy 341.081689 -81.830396)
			(xy 341.097057 -81.882734) (xy 341.10482 -81.936726) (xy 341.10482 -81.991274) (xy 341.097057 -82.045266)
			(xy 341.081689 -82.097604) (xy 341.059028 -82.147222) (xy 341.029536 -82.193109) (xy 340.993814 -82.234332)
			(xy 340.952588 -82.270052) (xy 340.906699 -82.29954) (xy 340.857079 -82.322198) (xy 340.804741 -82.337563)
			(xy 340.750748 -82.345322) (xy 340.723474 -82.345784) (xy 339.859874 -82.345784) (xy 339.832607 -82.345252)
			(xy 339.77863 -82.337488) (xy 339.726306 -82.322121) (xy 339.676702 -82.299465) (xy 339.630827 -82.26998)
			(xy 339.589615 -82.234266) (xy 339.553905 -82.193052) (xy 339.524423 -82.147175) (xy 339.50177 -82.097569)
			(xy 339.486407 -82.045245) (xy 339.478646 -81.991267) (xy 337.692804 -81.991267) (xy 337.704024 -82.00099)
			(xy 337.739714 -82.04218) (xy 337.76918 -82.088031) (xy 337.79182 -82.137608) (xy 337.807174 -82.189902)
			(xy 337.81493 -82.243849) (xy 337.81493 -82.298351) (xy 337.807174 -82.352298) (xy 337.79182 -82.404592)
			(xy 337.769179 -82.454169) (xy 337.739714 -82.50002) (xy 337.704024 -82.54121) (xy 337.662836 -82.576902)
			(xy 337.616987 -82.60637) (xy 337.567411 -82.629013) (xy 337.515118 -82.64437) (xy 337.461171 -82.652129)
			(xy 337.43392 -82.652616) (xy 336.57032 -82.652616) (xy 336.543067 -82.652138) (xy 336.489115 -82.644384)
			(xy 336.436816 -82.62903) (xy 336.387234 -82.606389) (xy 336.341379 -82.576922) (xy 336.300185 -82.541229)
			(xy 336.26449 -82.500037) (xy 336.235021 -82.454183) (xy 336.212377 -82.404603) (xy 336.197021 -82.352305)
			(xy 336.189263 -82.298353) (xy 333.294774 -82.298353) (xy 333.283701 -82.311131) (xy 333.242505 -82.346823)
			(xy 333.196649 -82.376289) (xy 333.147066 -82.398928) (xy 333.094765 -82.41428) (xy 333.040812 -82.422032)
			(xy 333.013558 -82.422492) (xy 332.149958 -82.422492) (xy 332.122708 -82.422035) (xy 332.068762 -82.414274)
			(xy 332.01647 -82.398914) (xy 331.966896 -82.37627) (xy 331.921049 -82.346801) (xy 331.879862 -82.311108)
			(xy 331.844174 -82.269917) (xy 331.81471 -82.224067) (xy 331.792071 -82.17449) (xy 331.776717 -82.122197)
			(xy 331.768962 -82.06825) (xy 239.640092 -82.06825) (xy 239.623713 -82.211927) (xy 239.596047 -82.383601)
			(xy 239.560472 -82.553811) (xy 239.517063 -82.722195) (xy 239.465913 -82.888391) (xy 239.407133 -83.052043)
			(xy 239.340846 -83.212802) (xy 239.267197 -83.370324) (xy 239.186341 -83.524271) (xy 239.148735 -83.588471)
			(xy 341.356398 -83.588471) (xy 341.356398 -83.533929) (xy 341.364161 -83.479942) (xy 341.379527 -83.427609)
			(xy 341.402184 -83.377996) (xy 341.431672 -83.332112) (xy 341.467389 -83.290892) (xy 341.508609 -83.255174)
			(xy 341.554492 -83.225686) (xy 341.604106 -83.203028) (xy 341.656438 -83.187661) (xy 341.710425 -83.179899)
			(xy 341.737696 -83.179412) (xy 342.601296 -83.179412) (xy 342.628565 -83.179927) (xy 342.682549 -83.187688)
			(xy 342.734879 -83.203053) (xy 342.784489 -83.225709) (xy 342.83037 -83.255194) (xy 342.871588 -83.290909)
			(xy 342.907303 -83.332127) (xy 342.936789 -83.378008) (xy 342.959445 -83.427618) (xy 342.974811 -83.479947)
			(xy 342.982573 -83.533931) (xy 342.982573 -83.588469) (xy 342.974811 -83.642453) (xy 342.959445 -83.694782)
			(xy 342.936789 -83.744392) (xy 342.907303 -83.790273) (xy 342.871588 -83.831491) (xy 342.83037 -83.867206)
			(xy 342.784489 -83.896691) (xy 342.734879 -83.919347) (xy 342.682549 -83.934712) (xy 342.628565 -83.942473)
			(xy 342.601296 -83.942936) (xy 341.737696 -83.942936) (xy 341.710425 -83.942501) (xy 341.656438 -83.934739)
			(xy 341.604106 -83.919372) (xy 341.554492 -83.896714) (xy 341.508609 -83.867226) (xy 341.467389 -83.831508)
			(xy 341.431672 -83.790288) (xy 341.402184 -83.744404) (xy 341.379527 -83.694791) (xy 341.364161 -83.642458)
			(xy 341.356398 -83.588471) (xy 239.148735 -83.588471) (xy 239.098452 -83.674314) (xy 239.003718 -83.820132)
			(xy 238.902342 -83.961413) (xy 238.794541 -84.097854) (xy 238.680545 -84.229164) (xy 238.560599 -84.355062)
			(xy 238.434958 -84.475277) (xy 238.393119 -84.511757) (xy 337.882119 -84.511757) (xy 337.882119 -84.457243)
			(xy 337.889878 -84.403284) (xy 337.905237 -84.350979) (xy 337.927883 -84.301392) (xy 337.957357 -84.255533)
			(xy 337.993057 -84.214336) (xy 338.034257 -84.178639) (xy 338.080119 -84.149169) (xy 338.129707 -84.126526)
			(xy 338.182014 -84.111171) (xy 338.235973 -84.103417) (xy 338.26323 -84.102956) (xy 339.12683 -84.102956)
			(xy 339.154077 -84.103516) (xy 339.208017 -84.111275) (xy 339.260303 -84.126632) (xy 339.309871 -84.149272)
			(xy 339.355714 -84.178737) (xy 339.396896 -84.214425) (xy 339.432581 -84.25561) (xy 339.462042 -84.301455)
			(xy 339.484679 -84.351025) (xy 339.500031 -84.403313) (xy 339.503159 -84.425069) (xy 344.644951 -84.425069)
			(xy 344.644951 -84.370531) (xy 344.652713 -84.316548) (xy 344.668079 -84.26422) (xy 344.690737 -84.214611)
			(xy 344.720223 -84.168731) (xy 344.75594 -84.127516) (xy 344.797159 -84.091803) (xy 344.843041 -84.06232)
			(xy 344.892652 -84.039668) (xy 344.944981 -84.024306) (xy 344.998965 -84.016549) (xy 345.026234 -84.016088)
			(xy 345.889834 -84.016088) (xy 345.917105 -84.016477) (xy 345.971092 -84.024243) (xy 346.023425 -84.039614)
			(xy 346.073037 -84.062275) (xy 346.11892 -84.091766) (xy 346.160139 -84.127485) (xy 346.195855 -84.168708)
			(xy 346.225341 -84.214593) (xy 346.247998 -84.264207) (xy 346.263364 -84.316541) (xy 346.271126 -84.370529)
			(xy 346.271126 -84.425071) (xy 346.263364 -84.479059) (xy 346.247998 -84.531393) (xy 346.225341 -84.581007)
			(xy 346.195855 -84.626892) (xy 346.160139 -84.668115) (xy 346.11892 -84.703834) (xy 346.073037 -84.733325)
			(xy 346.023425 -84.755986) (xy 345.971092 -84.771357) (xy 345.917105 -84.779123) (xy 345.889834 -84.779612)
			(xy 345.026234 -84.779612) (xy 344.998965 -84.779051) (xy 344.944981 -84.771294) (xy 344.892652 -84.755932)
			(xy 344.843041 -84.73328) (xy 344.797159 -84.703797) (xy 344.75594 -84.668084) (xy 344.720223 -84.626869)
			(xy 344.690737 -84.580989) (xy 344.668079 -84.53138) (xy 344.652713 -84.479052) (xy 344.644951 -84.425069)
			(xy 339.503159 -84.425069) (xy 339.507786 -84.457253) (xy 339.507786 -84.511747) (xy 339.500031 -84.565687)
			(xy 339.484679 -84.617975) (xy 339.462042 -84.667545) (xy 339.432581 -84.71339) (xy 339.396896 -84.754575)
			(xy 339.355714 -84.790263) (xy 339.309871 -84.819728) (xy 339.260303 -84.842368) (xy 339.208017 -84.857725)
			(xy 339.154077 -84.865484) (xy 339.12683 -84.865972) (xy 338.26323 -84.865972) (xy 338.235973 -84.865583)
			(xy 338.182014 -84.857829) (xy 338.129707 -84.842474) (xy 338.080119 -84.819831) (xy 338.034257 -84.790361)
			(xy 337.993057 -84.754664) (xy 337.957357 -84.713467) (xy 337.927883 -84.667608) (xy 337.905237 -84.618021)
			(xy 337.889878 -84.565716) (xy 337.882119 -84.511757) (xy 238.393119 -84.511757) (xy 238.303893 -84.589554)
			(xy 238.167683 -84.697647) (xy 238.02662 -84.799326) (xy 237.881005 -84.894371) (xy 237.73115 -84.982581)
			(xy 237.577377 -85.063767) (xy 237.420014 -85.137754) (xy 237.259397 -85.204384) (xy 237.095871 -85.263515)
			(xy 236.929785 -85.315021) (xy 236.761494 -85.35879) (xy 236.59136 -85.39473) (xy 236.419746 -85.422763)
			(xy 236.247019 -85.44283) (xy 236.073548 -85.454887) (xy 235.899706 -85.458909) (xy 235.725864 -85.454887)
			(xy 235.552393 -85.44283) (xy 235.379666 -85.422763) (xy 235.208052 -85.39473) (xy 235.037918 -85.35879)
			(xy 234.869627 -85.315021) (xy 234.703541 -85.263515) (xy 234.540015 -85.204384) (xy 234.379398 -85.137754)
			(xy 234.222035 -85.063767) (xy 234.068262 -84.982581) (xy 233.918407 -84.894371) (xy 233.772792 -84.799326)
			(xy 233.631729 -84.697647) (xy 233.495519 -84.589554) (xy 233.364454 -84.475277) (xy 233.238813 -84.355062)
			(xy 233.118867 -84.229164) (xy 233.004871 -84.097854) (xy 232.89707 -83.961413) (xy 232.795694 -83.820132)
			(xy 232.70096 -83.674314) (xy 232.613071 -83.524271) (xy 232.532215 -83.370324) (xy 232.458566 -83.212802)
			(xy 232.392279 -83.052043) (xy 232.333499 -82.888391) (xy 232.282349 -82.722195) (xy 232.23894 -82.553811)
			(xy 232.203365 -82.383601) (xy 232.175699 -82.211927) (xy 232.156003 -82.039157) (xy 232.144317 -81.865661)
			(xy 232.140667 -81.69181) (xy 2.509012 -81.69181) (xy 2.509012 -85.764678) (xy 10.421355 -85.764678)
			(xy 10.421355 -85.635538) (xy 10.429305 -85.506643) (xy 10.445175 -85.378483) (xy 10.468904 -85.251542)
			(xy 10.500403 -85.126303) (xy 10.539552 -85.00324) (xy 10.586203 -84.882821) (xy 10.640178 -84.765502)
			(xy 10.701273 -84.651728) (xy 10.769256 -84.541931) (xy 10.84387 -84.436528) (xy 10.924831 -84.335918)
			(xy 11.011831 -84.240483) (xy 11.104542 -84.150584) (xy 11.202612 -84.066563) (xy 11.305667 -83.988739)
			(xy 11.413318 -83.917407) (xy 11.525157 -83.852837) (xy 11.640758 -83.795275) (xy 11.759683 -83.744938)
			(xy 11.881482 -83.702018) (xy 12.005692 -83.666677) (xy 12.131841 -83.63905) (xy 12.259453 -83.619241)
			(xy 12.388042 -83.607325) (xy 12.51712 -83.603349) (xy 12.646198 -83.607325) (xy 12.774787 -83.619241)
			(xy 12.902399 -83.63905) (xy 13.028548 -83.666677) (xy 13.152758 -83.702018) (xy 13.274557 -83.744938)
			(xy 13.393482 -83.795275) (xy 13.509083 -83.852837) (xy 13.620922 -83.917407) (xy 13.728573 -83.988739)
			(xy 13.831628 -84.066563) (xy 13.929698 -84.150584) (xy 14.022409 -84.240483) (xy 14.109409 -84.335918)
			(xy 14.19037 -84.436528) (xy 14.264984 -84.541931) (xy 14.332967 -84.651728) (xy 14.394062 -84.765502)
			(xy 14.448037 -84.882821) (xy 14.494688 -85.00324) (xy 14.533837 -85.126303) (xy 14.565336 -85.251542)
			(xy 14.589065 -85.378483) (xy 14.604935 -85.506643) (xy 14.612885 -85.635538) (xy 14.613382 -85.700108)
			(xy 14.612885 -85.764678) (xy 14.608278 -85.839368) (xy 342.975946 -85.839368) (xy 342.975946 -85.784832)
			(xy 342.983708 -85.730852) (xy 342.999072 -85.678525) (xy 343.021727 -85.628918) (xy 343.051211 -85.58304)
			(xy 343.086924 -85.541824) (xy 343.12814 -85.506111) (xy 343.174018 -85.476627) (xy 343.223625 -85.453972)
			(xy 343.275952 -85.438608) (xy 343.329932 -85.430846) (xy 343.3572 -85.43036) (xy 344.2208 -85.43036)
			(xy 344.248071 -85.430802) (xy 344.302058 -85.438565) (xy 344.35439 -85.453931) (xy 344.404003 -85.476588)
			(xy 344.449887 -85.506076) (xy 344.491107 -85.541793) (xy 344.526824 -85.583013) (xy 344.556312 -85.628897)
			(xy 344.578969 -85.67851) (xy 344.594335 -85.730842) (xy 344.602098 -85.784829) (xy 344.602098 -85.839371)
			(xy 344.594335 -85.893358) (xy 344.578969 -85.94569) (xy 344.556312 -85.995303) (xy 344.526824 -86.041187)
			(xy 344.491107 -86.082407) (xy 344.449887 -86.118124) (xy 344.404003 -86.147612) (xy 344.35439 -86.170269)
			(xy 344.302058 -86.185635) (xy 344.248071 -86.193398) (xy 344.2208 -86.193884) (xy 343.3572 -86.193884)
			(xy 343.329932 -86.193354) (xy 343.275952 -86.185592) (xy 343.223625 -86.170228) (xy 343.174018 -86.147573)
			(xy 343.12814 -86.118089) (xy 343.086924 -86.082376) (xy 343.051211 -86.04116) (xy 343.021727 -85.995282)
			(xy 342.999072 -85.945675) (xy 342.983708 -85.893348) (xy 342.975946 -85.839368) (xy 14.608278 -85.839368)
			(xy 14.604935 -85.893573) (xy 14.589065 -86.021733) (xy 14.565336 -86.148674) (xy 14.533837 -86.273913)
			(xy 14.494688 -86.396976) (xy 14.448037 -86.517395) (xy 14.394062 -86.634714) (xy 14.332967 -86.748488)
			(xy 14.264984 -86.858285) (xy 14.19037 -86.963688) (xy 14.109409 -87.064298) (xy 14.022409 -87.159733)
			(xy 13.929698 -87.249632) (xy 13.831628 -87.333653) (xy 13.728573 -87.411477) (xy 13.620922 -87.482809)
			(xy 13.509083 -87.547379) (xy 13.393482 -87.604941) (xy 13.274557 -87.655278) (xy 13.152758 -87.698198)
			(xy 13.028548 -87.733539) (xy 12.902399 -87.761166) (xy 12.774787 -87.780975) (xy 12.646198 -87.792891)
			(xy 12.51712 -87.796868) (xy 12.388042 -87.792891) (xy 12.259453 -87.780975) (xy 12.131841 -87.761166)
			(xy 12.005692 -87.733539) (xy 11.881482 -87.698198) (xy 11.759683 -87.655278) (xy 11.640758 -87.604941)
			(xy 11.525157 -87.547379) (xy 11.413318 -87.482809) (xy 11.305667 -87.411477) (xy 11.202612 -87.333653)
			(xy 11.104542 -87.249632) (xy 11.011831 -87.159733) (xy 10.924831 -87.064298) (xy 10.84387 -86.963688)
			(xy 10.769256 -86.858285) (xy 10.701273 -86.748488) (xy 10.640178 -86.634714) (xy 10.586203 -86.517395)
			(xy 10.539552 -86.396976) (xy 10.500403 -86.273913) (xy 10.468904 -86.148674) (xy 10.445175 -86.021733)
			(xy 10.429305 -85.893573) (xy 10.421355 -85.764678) (xy 2.509012 -85.764678) (xy 2.509012 -98.341434)
			(xy 261.733792 -98.341434) (xy 261.733792 -97.477834) (xy 261.734278 -97.450583) (xy 261.742034 -97.396635)
			(xy 261.757389 -97.34434) (xy 261.780031 -97.294763) (xy 261.809497 -97.248913) (xy 261.845188 -97.207722)
			(xy 261.886379 -97.172031) (xy 261.932229 -97.142565) (xy 261.981806 -97.119923) (xy 262.034101 -97.104568)
			(xy 262.088049 -97.096812) (xy 262.142551 -97.096812) (xy 262.196499 -97.104568) (xy 262.248794 -97.119923)
			(xy 262.298371 -97.142565) (xy 262.344221 -97.172031) (xy 262.385412 -97.207722) (xy 262.421103 -97.248913)
			(xy 262.450569 -97.294763) (xy 262.473211 -97.34434) (xy 262.488566 -97.396635) (xy 262.496322 -97.450583)
			(xy 262.496808 -97.477834) (xy 262.496808 -98.341434) (xy 262.496322 -98.368685) (xy 262.488566 -98.422633)
			(xy 262.473211 -98.474928) (xy 262.450569 -98.524505) (xy 262.421103 -98.570355) (xy 262.385412 -98.611546)
			(xy 262.344221 -98.647237) (xy 262.298371 -98.676703) (xy 262.248794 -98.699345) (xy 262.196499 -98.7147)
			(xy 262.142551 -98.722456) (xy 262.088049 -98.722456) (xy 262.034101 -98.7147) (xy 261.981806 -98.699345)
			(xy 261.932229 -98.676703) (xy 261.886379 -98.647237) (xy 261.845188 -98.611546) (xy 261.809497 -98.570355)
			(xy 261.780031 -98.524505) (xy 261.757389 -98.474928) (xy 261.742034 -98.422633) (xy 261.734278 -98.368685)
			(xy 261.733792 -98.341434) (xy 2.509012 -98.341434) (xy 2.509012 -106.40187) (xy 11.713464 -106.40187)
			(xy 11.713464 -105.53827) (xy 11.71395 -105.511001) (xy 11.721712 -105.457017) (xy 11.737077 -105.404687)
			(xy 11.759734 -105.355077) (xy 11.78922 -105.309196) (xy 11.824935 -105.267979) (xy 11.866152 -105.232264)
			(xy 11.912033 -105.202778) (xy 11.961643 -105.180121) (xy 12.013973 -105.164756) (xy 12.067957 -105.156994)
			(xy 12.122495 -105.156994) (xy 12.176479 -105.164756) (xy 12.228809 -105.180121) (xy 12.278419 -105.202778)
			(xy 12.3243 -105.232264) (xy 12.365517 -105.267979) (xy 12.401232 -105.309196) (xy 12.430718 -105.355077)
			(xy 12.453375 -105.404687) (xy 12.46874 -105.457017) (xy 12.476502 -105.511001) (xy 12.476988 -105.53827)
			(xy 12.476988 -105.664) (xy 15.57274 -105.664) (xy 15.57274 -104.8004) (xy 15.573226 -104.773131)
			(xy 15.580988 -104.719147) (xy 15.596353 -104.666817) (xy 15.61901 -104.617207) (xy 15.648496 -104.571326)
			(xy 15.684211 -104.530109) (xy 15.725428 -104.494394) (xy 15.771309 -104.464908) (xy 15.820919 -104.442251)
			(xy 15.873249 -104.426886) (xy 15.927233 -104.419124) (xy 15.981771 -104.419124) (xy 16.035755 -104.426886)
			(xy 16.088085 -104.442251) (xy 16.137695 -104.464908) (xy 16.183576 -104.494394) (xy 16.224793 -104.530109)
			(xy 16.260508 -104.571326) (xy 16.289994 -104.617207) (xy 16.312651 -104.666817) (xy 16.328016 -104.719147)
			(xy 16.335778 -104.773131) (xy 16.336264 -104.8004) (xy 16.336264 -105.664) (xy 16.335778 -105.691269)
			(xy 16.328016 -105.745253) (xy 16.312651 -105.797583) (xy 16.289994 -105.847193) (xy 16.260508 -105.893074)
			(xy 16.224793 -105.934291) (xy 16.183576 -105.970006) (xy 16.137695 -105.999492) (xy 16.088085 -106.022149)
			(xy 16.035755 -106.037514) (xy 15.981771 -106.045276) (xy 15.927233 -106.045276) (xy 15.873249 -106.037514)
			(xy 15.820919 -106.022149) (xy 15.771309 -105.999492) (xy 15.725428 -105.970006) (xy 15.684211 -105.934291)
			(xy 15.648496 -105.893074) (xy 15.61901 -105.847193) (xy 15.596353 -105.797583) (xy 15.580988 -105.745253)
			(xy 15.573226 -105.691269) (xy 15.57274 -105.664) (xy 12.476988 -105.664) (xy 12.476988 -106.40187)
			(xy 12.476502 -106.429139) (xy 12.46874 -106.483123) (xy 12.453375 -106.535453) (xy 12.430718 -106.585063)
			(xy 12.401232 -106.630944) (xy 12.365517 -106.672161) (xy 12.3243 -106.707876) (xy 12.278419 -106.737362)
			(xy 12.228809 -106.760019) (xy 12.176479 -106.775384) (xy 12.122495 -106.783146) (xy 12.067957 -106.783146)
			(xy 12.013973 -106.775384) (xy 11.961643 -106.760019) (xy 11.912033 -106.737362) (xy 11.866152 -106.707876)
			(xy 11.824935 -106.672161) (xy 11.78922 -106.630944) (xy 11.759734 -106.585063) (xy 11.737077 -106.535453)
			(xy 11.721712 -106.483123) (xy 11.71395 -106.429139) (xy 11.713464 -106.40187) (xy 2.509012 -106.40187)
			(xy 2.509012 -108.943971) (xy 11.292822 -108.943971) (xy 11.292822 -108.889469) (xy 11.300578 -108.835522)
			(xy 11.315933 -108.783228) (xy 11.338574 -108.733651) (xy 11.36804 -108.687801) (xy 11.403731 -108.646611)
			(xy 11.444921 -108.61092) (xy 11.490771 -108.581454) (xy 11.540348 -108.558813) (xy 11.592642 -108.543458)
			(xy 11.646589 -108.535702) (xy 11.67384 -108.535216) (xy 12.53744 -108.535216) (xy 12.564692 -108.535694)
			(xy 12.61864 -108.54345) (xy 12.670935 -108.558806) (xy 12.720513 -108.581447) (xy 12.766364 -108.610914)
			(xy 12.807554 -108.646606) (xy 12.843246 -108.687796) (xy 12.872713 -108.733647) (xy 12.895354 -108.783225)
			(xy 12.91071 -108.83552) (xy 12.918466 -108.889468) (xy 12.918466 -108.943972) (xy 12.918466 -108.943973)
			(xy 15.156389 -108.943973) (xy 15.156389 -108.889467) (xy 15.164146 -108.835517) (xy 15.179502 -108.783219)
			(xy 15.202145 -108.733639) (xy 15.231613 -108.687786) (xy 15.267307 -108.646594) (xy 15.308499 -108.610901)
			(xy 15.354353 -108.581433) (xy 15.403933 -108.558791) (xy 15.45623 -108.543435) (xy 15.510181 -108.535679)
			(xy 15.537434 -108.535216) (xy 16.401034 -108.535216) (xy 16.428285 -108.535694) (xy 16.482233 -108.543451)
			(xy 16.534528 -108.558807) (xy 16.584105 -108.581448) (xy 16.629956 -108.610915) (xy 16.671146 -108.646607)
			(xy 16.706837 -108.687798) (xy 16.707863 -108.689394) (xy 238.647224 -108.689394) (xy 238.647224 -107.825794)
			(xy 238.64771 -107.798525) (xy 238.655472 -107.744541) (xy 238.670837 -107.692211) (xy 238.693494 -107.642601)
			(xy 238.72298 -107.59672) (xy 238.758695 -107.555503) (xy 238.799912 -107.519788) (xy 238.845793 -107.490302)
			(xy 238.895403 -107.467645) (xy 238.947733 -107.45228) (xy 239.001717 -107.444518) (xy 239.056255 -107.444518)
			(xy 239.110239 -107.45228) (xy 239.162569 -107.467645) (xy 239.212179 -107.490302) (xy 239.25806 -107.519788)
			(xy 239.299277 -107.555503) (xy 239.334992 -107.59672) (xy 239.364478 -107.642601) (xy 239.387135 -107.692211)
			(xy 239.4025 -107.744541) (xy 239.410262 -107.798525) (xy 239.410748 -107.825794) (xy 239.410748 -108.689394)
			(xy 239.410262 -108.716663) (xy 239.4025 -108.770647) (xy 239.387135 -108.822977) (xy 239.364478 -108.872587)
			(xy 239.334992 -108.918468) (xy 239.299277 -108.959685) (xy 239.25806 -108.9954) (xy 239.212179 -109.024886)
			(xy 239.162569 -109.047543) (xy 239.110239 -109.062908) (xy 239.056255 -109.07067) (xy 239.001717 -109.07067)
			(xy 238.947733 -109.062908) (xy 238.895403 -109.047543) (xy 238.845793 -109.024886) (xy 238.799912 -108.9954)
			(xy 238.758695 -108.959685) (xy 238.72298 -108.918468) (xy 238.693494 -108.872587) (xy 238.670837 -108.822977)
			(xy 238.655472 -108.770647) (xy 238.64771 -108.716663) (xy 238.647224 -108.689394) (xy 16.707863 -108.689394)
			(xy 16.736304 -108.733648) (xy 16.758945 -108.783226) (xy 16.7743 -108.835521) (xy 16.782056 -108.889469)
			(xy 16.782056 -108.943971) (xy 16.7743 -108.997919) (xy 16.758945 -109.050214) (xy 16.736304 -109.099792)
			(xy 16.706837 -109.145642) (xy 16.671146 -109.186833) (xy 16.629956 -109.222525) (xy 16.584105 -109.251992)
			(xy 16.534528 -109.274633) (xy 16.482233 -109.289989) (xy 16.428285 -109.297746) (xy 16.401034 -109.298232)
			(xy 15.537434 -109.298232) (xy 15.510181 -109.297761) (xy 15.45623 -109.290005) (xy 15.403933 -109.274649)
			(xy 15.354353 -109.252007) (xy 15.308499 -109.222539) (xy 15.267307 -109.186846) (xy 15.231613 -109.145654)
			(xy 15.202145 -109.099801) (xy 15.179502 -109.050221) (xy 15.164146 -108.997923) (xy 15.156389 -108.943973)
			(xy 12.918466 -108.943973) (xy 12.91071 -108.99792) (xy 12.895354 -109.050215) (xy 12.872713 -109.099793)
			(xy 12.843246 -109.145644) (xy 12.807554 -109.186834) (xy 12.766364 -109.222526) (xy 12.720513 -109.251993)
			(xy 12.670935 -109.274634) (xy 12.61864 -109.28999) (xy 12.564692 -109.297746) (xy 12.53744 -109.298232)
			(xy 11.67384 -109.298232) (xy 11.646589 -109.297738) (xy 11.592642 -109.289982) (xy 11.540348 -109.274627)
			(xy 11.490771 -109.251986) (xy 11.444921 -109.22252) (xy 11.403731 -109.186829) (xy 11.36804 -109.145639)
			(xy 11.338574 -109.099789) (xy 11.315933 -109.050212) (xy 11.300578 -108.997918) (xy 11.292822 -108.943971)
			(xy 2.509012 -108.943971) (xy 2.509012 -109.550266) (xy 250.428546 -109.550266) (xy 250.428546 -109.495734)
			(xy 250.436306 -109.441757) (xy 250.451669 -109.389434) (xy 250.474321 -109.339829) (xy 250.503801 -109.293953)
			(xy 250.53951 -109.252739) (xy 250.580721 -109.217025) (xy 250.626594 -109.18754) (xy 250.676196 -109.164883)
			(xy 250.728518 -109.149515) (xy 250.782494 -109.141749) (xy 250.80976 -109.14126) (xy 251.67336 -109.14126)
			(xy 251.700634 -109.141677) (xy 251.754629 -109.149435) (xy 251.806969 -109.164798) (xy 251.85659 -109.187455)
			(xy 251.902482 -109.216943) (xy 251.943709 -109.252663) (xy 251.979433 -109.293886) (xy 252.008926 -109.339775)
			(xy 252.031588 -109.389393) (xy 252.046957 -109.441732) (xy 252.05472 -109.495726) (xy 252.05472 -109.550274)
			(xy 252.046957 -109.604268) (xy 252.031588 -109.656607) (xy 252.008926 -109.706225) (xy 251.979433 -109.752114)
			(xy 251.943709 -109.793337) (xy 251.902482 -109.829057) (xy 251.85659 -109.858545) (xy 251.806969 -109.881202)
			(xy 251.754629 -109.896565) (xy 251.700634 -109.904323) (xy 251.67336 -109.904784) (xy 250.80976 -109.904784)
			(xy 250.782494 -109.904251) (xy 250.728518 -109.896485) (xy 250.676196 -109.881117) (xy 250.626594 -109.85846)
			(xy 250.580721 -109.828975) (xy 250.53951 -109.793262) (xy 250.503801 -109.752047) (xy 250.474321 -109.706171)
			(xy 250.451669 -109.656566) (xy 250.436306 -109.604243) (xy 250.428546 -109.550266) (xy 2.509012 -109.550266)
			(xy 2.509012 -111.158274) (xy 239.40262 -111.158274) (xy 239.40262 -110.294674) (xy 239.403106 -110.267423)
			(xy 239.410862 -110.213475) (xy 239.426217 -110.16118) (xy 239.448859 -110.111603) (xy 239.478325 -110.065753)
			(xy 239.514016 -110.024562) (xy 239.555207 -109.988871) (xy 239.601057 -109.959405) (xy 239.650634 -109.936763)
			(xy 239.702929 -109.921408) (xy 239.756877 -109.913652) (xy 239.811379 -109.913652) (xy 239.865327 -109.921408)
			(xy 239.917622 -109.936763) (xy 239.967199 -109.959405) (xy 240.000574 -109.980854) (xy 256.88563 -109.980854)
			(xy 256.88563 -109.926346) (xy 256.893387 -109.872392) (xy 256.908744 -109.820091) (xy 256.931388 -109.770508)
			(xy 256.960857 -109.724652) (xy 256.996552 -109.683457) (xy 257.037747 -109.647761) (xy 257.083602 -109.61829)
			(xy 257.133185 -109.595646) (xy 257.185486 -109.580288) (xy 257.23944 -109.57253) (xy 257.266694 -109.572044)
			(xy 258.130294 -109.572044) (xy 258.157544 -109.572603) (xy 258.211488 -109.580358) (xy 258.26378 -109.595712)
			(xy 258.313355 -109.618351) (xy 258.359203 -109.647815) (xy 258.400391 -109.683504) (xy 258.436081 -109.724692)
			(xy 258.465546 -109.77054) (xy 258.488186 -109.820114) (xy 258.503541 -109.872406) (xy 258.511297 -109.92635)
			(xy 258.511297 -109.98085) (xy 258.503541 -110.034794) (xy 258.488186 -110.087086) (xy 258.465546 -110.13666)
			(xy 258.436081 -110.182508) (xy 258.400391 -110.223696) (xy 258.359203 -110.259385) (xy 258.313355 -110.288849)
			(xy 258.26378 -110.311488) (xy 258.211488 -110.326842) (xy 258.157544 -110.334597) (xy 258.130294 -110.33506)
			(xy 257.266694 -110.33506) (xy 257.23944 -110.33467) (xy 257.185486 -110.326912) (xy 257.133185 -110.311554)
			(xy 257.083602 -110.28891) (xy 257.037747 -110.259439) (xy 256.996552 -110.223743) (xy 256.960857 -110.182548)
			(xy 256.931388 -110.136692) (xy 256.908744 -110.087109) (xy 256.893387 -110.034808) (xy 256.88563 -109.980854)
			(xy 240.000574 -109.980854) (xy 240.013049 -109.988871) (xy 240.05424 -110.024562) (xy 240.089931 -110.065753)
			(xy 240.119397 -110.111603) (xy 240.142039 -110.16118) (xy 240.157394 -110.213475) (xy 240.16515 -110.267423)
			(xy 240.165636 -110.294674) (xy 240.165636 -111.158274) (xy 240.16515 -111.185525) (xy 240.157394 -111.239473)
			(xy 240.142039 -111.291768) (xy 240.119397 -111.341345) (xy 240.089931 -111.387195) (xy 240.05424 -111.428386)
			(xy 240.013049 -111.464077) (xy 239.967199 -111.493543) (xy 239.917622 -111.516185) (xy 239.865327 -111.53154)
			(xy 239.811379 -111.539296) (xy 239.756877 -111.539296) (xy 239.702929 -111.53154) (xy 239.650634 -111.516185)
			(xy 239.601057 -111.493543) (xy 239.555207 -111.464077) (xy 239.514016 -111.428386) (xy 239.478325 -111.387195)
			(xy 239.448859 -111.341345) (xy 239.426217 -111.291768) (xy 239.410862 -111.239473) (xy 239.403106 -111.185525)
			(xy 239.40262 -111.158274) (xy 2.509012 -111.158274) (xy 2.509012 -114.734161) (xy 11.255226 -114.734161)
			(xy 11.255226 -114.679659) (xy 11.262982 -114.625711) (xy 11.278337 -114.573416) (xy 11.300979 -114.523839)
			(xy 11.330445 -114.477988) (xy 11.366136 -114.436798) (xy 11.407326 -114.401106) (xy 11.453177 -114.371639)
			(xy 11.502754 -114.348998) (xy 11.555049 -114.333643) (xy 11.608997 -114.325886) (xy 11.636248 -114.3254)
			(xy 12.499848 -114.3254) (xy 12.527101 -114.325867) (xy 12.581052 -114.333624) (xy 12.633349 -114.34898)
			(xy 12.68293 -114.371622) (xy 12.728783 -114.40109) (xy 12.769975 -114.436783) (xy 12.805669 -114.477976)
			(xy 12.835137 -114.523829) (xy 12.85778 -114.573409) (xy 12.873136 -114.625706) (xy 12.880893 -114.679657)
			(xy 12.880893 -114.734163) (xy 12.873136 -114.788114) (xy 12.85778 -114.840411) (xy 12.835137 -114.889991)
			(xy 12.805669 -114.935844) (xy 12.769975 -114.977037) (xy 12.728783 -115.01273) (xy 12.68293 -115.042198)
			(xy 12.633349 -115.06484) (xy 12.581052 -115.080196) (xy 12.527101 -115.087953) (xy 12.499848 -115.088416)
			(xy 11.636248 -115.088416) (xy 11.608997 -115.087934) (xy 11.555049 -115.080177) (xy 11.502754 -115.064822)
			(xy 11.453177 -115.042181) (xy 11.407326 -115.012714) (xy 11.366136 -114.977022) (xy 11.330445 -114.935832)
			(xy 11.300979 -114.889981) (xy 11.278337 -114.840404) (xy 11.262982 -114.788109) (xy 11.255226 -114.734161)
			(xy 2.509012 -114.734161) (xy 2.509012 -116.393573) (xy 230.652992 -116.393573) (xy 230.652992 -116.339027)
			(xy 230.660755 -116.285035) (xy 230.676123 -116.232698) (xy 230.698784 -116.183081) (xy 230.728276 -116.137195)
			(xy 230.763998 -116.095973) (xy 230.805224 -116.060254) (xy 230.851113 -116.030767) (xy 230.900732 -116.008111)
			(xy 230.95307 -115.992747) (xy 231.007063 -115.984989) (xy 231.034336 -115.984528) (xy 231.897936 -115.984528)
			(xy 231.925203 -115.985037) (xy 231.979181 -115.992802) (xy 232.031505 -116.008171) (xy 232.081109 -116.030828)
			(xy 232.126985 -116.060314) (xy 232.168197 -116.096029) (xy 232.203907 -116.137244) (xy 232.233389 -116.183122)
			(xy 232.256042 -116.232729) (xy 232.271405 -116.285054) (xy 232.277026 -116.324151) (xy 236.866903 -116.324151)
			(xy 236.866903 -116.269649) (xy 236.87466 -116.215701) (xy 236.890016 -116.163407) (xy 236.912659 -116.113831)
			(xy 236.942127 -116.067981) (xy 236.97782 -116.026793) (xy 237.019012 -115.991104) (xy 237.064864 -115.961641)
			(xy 237.114443 -115.939003) (xy 237.166739 -115.923652) (xy 237.220687 -115.915901) (xy 237.247938 -115.91544)
			(xy 238.111538 -115.91544) (xy 238.138791 -115.915832) (xy 238.192741 -115.923594) (xy 238.245038 -115.938955)
			(xy 238.294617 -115.961601) (xy 238.340468 -115.991072) (xy 238.381659 -116.026768) (xy 238.417351 -116.067962)
			(xy 238.446817 -116.113817) (xy 238.469459 -116.163398) (xy 238.484814 -116.215696) (xy 238.49257 -116.269647)
			(xy 238.49257 -116.324153) (xy 238.484814 -116.378104) (xy 238.469459 -116.430402) (xy 238.446817 -116.479983)
			(xy 238.417351 -116.525838) (xy 238.381659 -116.567032) (xy 238.340468 -116.602728) (xy 238.294617 -116.632199)
			(xy 238.245038 -116.654845) (xy 238.192741 -116.670206) (xy 238.138791 -116.677968) (xy 238.111538 -116.678456)
			(xy 237.247938 -116.678456) (xy 237.220687 -116.677899) (xy 237.166739 -116.670148) (xy 237.114443 -116.654797)
			(xy 237.064864 -116.632159) (xy 237.019012 -116.602696) (xy 236.97782 -116.567007) (xy 236.942127 -116.525819)
			(xy 236.912659 -116.479969) (xy 236.890016 -116.430393) (xy 236.87466 -116.378099) (xy 236.866903 -116.324151)
			(xy 232.277026 -116.324151) (xy 232.279166 -116.339033) (xy 232.279166 -116.393567) (xy 232.271405 -116.447546)
			(xy 232.256042 -116.499871) (xy 232.233389 -116.549478) (xy 232.203907 -116.595356) (xy 232.168197 -116.636571)
			(xy 232.126985 -116.672286) (xy 232.081109 -116.701772) (xy 232.031505 -116.724429) (xy 231.979181 -116.739798)
			(xy 231.925203 -116.747563) (xy 231.897936 -116.748052) (xy 231.034336 -116.748052) (xy 231.007063 -116.747611)
			(xy 230.95307 -116.739853) (xy 230.900732 -116.724489) (xy 230.851113 -116.701833) (xy 230.805224 -116.672346)
			(xy 230.763998 -116.636627) (xy 230.728276 -116.595405) (xy 230.698784 -116.549519) (xy 230.676123 -116.499902)
			(xy 230.660755 -116.447565) (xy 230.652992 -116.393573) (xy 2.509012 -116.393573) (xy 2.509012 -117.632251)
			(xy 233.564903 -117.632251) (xy 233.564903 -117.577749) (xy 233.57266 -117.523801) (xy 233.588016 -117.471507)
			(xy 233.610659 -117.421931) (xy 233.640127 -117.376081) (xy 233.67582 -117.334893) (xy 233.717012 -117.299204)
			(xy 233.762864 -117.269741) (xy 233.812443 -117.247103) (xy 233.864739 -117.231752) (xy 233.918687 -117.224001)
			(xy 233.945938 -117.22354) (xy 234.809538 -117.22354) (xy 234.836791 -117.223932) (xy 234.890741 -117.231694)
			(xy 234.943038 -117.247055) (xy 234.992617 -117.269701) (xy 235.038468 -117.299172) (xy 235.079659 -117.334868)
			(xy 235.115351 -117.376062) (xy 235.144817 -117.421917) (xy 235.167459 -117.471498) (xy 235.182814 -117.523796)
			(xy 235.19057 -117.577747) (xy 235.19057 -117.632251) (xy 238.898903 -117.632251) (xy 238.898903 -117.577749)
			(xy 238.90666 -117.523801) (xy 238.922016 -117.471507) (xy 238.944659 -117.421931) (xy 238.974127 -117.376081)
			(xy 239.00982 -117.334893) (xy 239.051012 -117.299204) (xy 239.096864 -117.269741) (xy 239.146443 -117.247103)
			(xy 239.198739 -117.231752) (xy 239.252687 -117.224001) (xy 239.279938 -117.22354) (xy 240.143538 -117.22354)
			(xy 240.170791 -117.223932) (xy 240.224741 -117.231694) (xy 240.277038 -117.247055) (xy 240.326617 -117.269701)
			(xy 240.372468 -117.299172) (xy 240.413659 -117.334868) (xy 240.449351 -117.376062) (xy 240.478817 -117.421917)
			(xy 240.501459 -117.471498) (xy 240.516814 -117.523796) (xy 240.52457 -117.577747) (xy 240.52457 -117.632253)
			(xy 240.516814 -117.686204) (xy 240.501459 -117.738502) (xy 240.478817 -117.788083) (xy 240.449351 -117.833938)
			(xy 240.413659 -117.875132) (xy 240.372468 -117.910828) (xy 240.326617 -117.940299) (xy 240.277038 -117.962945)
			(xy 240.224741 -117.978306) (xy 240.170791 -117.986068) (xy 240.143538 -117.986556) (xy 239.279938 -117.986556)
			(xy 239.252687 -117.985999) (xy 239.198739 -117.978248) (xy 239.146443 -117.962897) (xy 239.096864 -117.940259)
			(xy 239.051012 -117.910796) (xy 239.00982 -117.875107) (xy 238.974127 -117.833919) (xy 238.944659 -117.788069)
			(xy 238.922016 -117.738493) (xy 238.90666 -117.686199) (xy 238.898903 -117.632251) (xy 235.19057 -117.632251)
			(xy 235.19057 -117.632253) (xy 235.182814 -117.686204) (xy 235.167459 -117.738502) (xy 235.144817 -117.788083)
			(xy 235.115351 -117.833938) (xy 235.079659 -117.875132) (xy 235.038468 -117.910828) (xy 234.992617 -117.940299)
			(xy 234.943038 -117.962945) (xy 234.890741 -117.978306) (xy 234.836791 -117.986068) (xy 234.809538 -117.986556)
			(xy 233.945938 -117.986556) (xy 233.918687 -117.985999) (xy 233.864739 -117.978248) (xy 233.812443 -117.962897)
			(xy 233.762864 -117.940259) (xy 233.717012 -117.910796) (xy 233.67582 -117.875107) (xy 233.640127 -117.833919)
			(xy 233.610659 -117.788069) (xy 233.588016 -117.738493) (xy 233.57266 -117.686199) (xy 233.564903 -117.632251)
			(xy 2.509012 -117.632251) (xy 2.509012 -123.093988) (xy 227.217732 -123.093988) (xy 227.217732 -122.230388)
			(xy 227.218218 -122.203137) (xy 227.225974 -122.149189) (xy 227.241329 -122.096894) (xy 227.263971 -122.047317)
			(xy 227.293437 -122.001467) (xy 227.329128 -121.960276) (xy 227.370319 -121.924585) (xy 227.416169 -121.895119)
			(xy 227.465746 -121.872477) (xy 227.518041 -121.857122) (xy 227.571989 -121.849366) (xy 227.626491 -121.849366)
			(xy 227.680439 -121.857122) (xy 227.732734 -121.872477) (xy 227.782311 -121.895119) (xy 227.828161 -121.924585)
			(xy 227.869352 -121.960276) (xy 227.905043 -122.001467) (xy 227.934509 -122.047317) (xy 227.957151 -122.096894)
			(xy 227.972506 -122.149189) (xy 227.980262 -122.203137) (xy 227.980748 -122.230388) (xy 227.980748 -122.921014)
			(xy 245.563136 -122.921014) (xy 245.563136 -122.057414) (xy 245.563622 -122.030163) (xy 245.571378 -121.976215)
			(xy 245.586733 -121.92392) (xy 245.609375 -121.874343) (xy 245.638841 -121.828493) (xy 245.674532 -121.787302)
			(xy 245.715723 -121.751611) (xy 245.761573 -121.722145) (xy 245.81115 -121.699503) (xy 245.863445 -121.684148)
			(xy 245.917393 -121.676392) (xy 245.971895 -121.676392) (xy 246.025843 -121.684148) (xy 246.078138 -121.699503)
			(xy 246.127715 -121.722145) (xy 246.173565 -121.751611) (xy 246.214756 -121.787302) (xy 246.250447 -121.828493)
			(xy 246.279913 -121.874343) (xy 246.302555 -121.92392) (xy 246.31791 -121.976215) (xy 246.325666 -122.030163)
			(xy 246.326152 -122.057414) (xy 246.326152 -122.921014) (xy 246.325666 -122.948265) (xy 246.31791 -123.002213)
			(xy 246.302555 -123.054508) (xy 246.279913 -123.104085) (xy 246.250447 -123.149935) (xy 246.214756 -123.191126)
			(xy 246.173565 -123.226817) (xy 246.127715 -123.256283) (xy 246.078138 -123.278925) (xy 246.025843 -123.29428)
			(xy 245.971895 -123.302036) (xy 245.917393 -123.302036) (xy 245.863445 -123.29428) (xy 245.81115 -123.278925)
			(xy 245.761573 -123.256283) (xy 245.715723 -123.226817) (xy 245.674532 -123.191126) (xy 245.638841 -123.149935)
			(xy 245.609375 -123.104085) (xy 245.586733 -123.054508) (xy 245.571378 -123.002213) (xy 245.563622 -122.948265)
			(xy 245.563136 -122.921014) (xy 227.980748 -122.921014) (xy 227.980748 -123.093988) (xy 227.980262 -123.121239)
			(xy 227.972506 -123.175187) (xy 227.957151 -123.227482) (xy 227.934509 -123.277059) (xy 227.905043 -123.322909)
			(xy 227.869352 -123.3641) (xy 227.828161 -123.399791) (xy 227.782311 -123.429257) (xy 227.732734 -123.451899)
			(xy 227.680439 -123.467254) (xy 227.626491 -123.47501) (xy 227.571989 -123.47501) (xy 227.518041 -123.467254)
			(xy 227.465746 -123.451899) (xy 227.416169 -123.429257) (xy 227.370319 -123.399791) (xy 227.329128 -123.3641)
			(xy 227.293437 -123.322909) (xy 227.263971 -123.277059) (xy 227.241329 -123.227482) (xy 227.225974 -123.175187)
			(xy 227.218218 -123.121239) (xy 227.217732 -123.093988) (xy 2.509012 -123.093988) (xy 2.509012 -125.221746)
			(xy 225.535744 -125.221746) (xy 225.535744 -124.358146) (xy 225.53623 -124.330877) (xy 225.543992 -124.276893)
			(xy 225.559357 -124.224563) (xy 225.582014 -124.174953) (xy 225.6115 -124.129072) (xy 225.647215 -124.087855)
			(xy 225.688432 -124.05214) (xy 225.734313 -124.022654) (xy 225.783923 -123.999997) (xy 225.836253 -123.984632)
			(xy 225.890237 -123.97687) (xy 225.944775 -123.97687) (xy 225.998759 -123.984632) (xy 226.051089 -123.999997)
			(xy 226.100699 -124.022654) (xy 226.14658 -124.05214) (xy 226.187797 -124.087855) (xy 226.223512 -124.129072)
			(xy 226.252998 -124.174953) (xy 226.275655 -124.224563) (xy 226.29102 -124.276893) (xy 226.298782 -124.330877)
			(xy 226.299268 -124.358146) (xy 226.299268 -125.221746) (xy 226.298782 -125.249015) (xy 226.29102 -125.302999)
			(xy 226.275655 -125.355329) (xy 226.252998 -125.404939) (xy 226.223512 -125.45082) (xy 226.187797 -125.492037)
			(xy 226.14658 -125.527752) (xy 226.100699 -125.557238) (xy 226.051089 -125.579895) (xy 225.998759 -125.59526)
			(xy 225.944775 -125.603022) (xy 225.890237 -125.603022) (xy 225.836253 -125.59526) (xy 225.783923 -125.579895)
			(xy 225.734313 -125.557238) (xy 225.688432 -125.527752) (xy 225.647215 -125.492037) (xy 225.6115 -125.45082)
			(xy 225.582014 -125.404939) (xy 225.559357 -125.355329) (xy 225.543992 -125.302999) (xy 225.53623 -125.249015)
			(xy 225.535744 -125.221746) (xy 2.509012 -125.221746) (xy 2.509012 -127.325628) (xy 227.034852 -127.325628)
			(xy 227.034852 -126.462028) (xy 227.035338 -126.434777) (xy 227.043094 -126.380829) (xy 227.058449 -126.328534)
			(xy 227.081091 -126.278957) (xy 227.110557 -126.233107) (xy 227.146248 -126.191916) (xy 227.187439 -126.156225)
			(xy 227.233289 -126.126759) (xy 227.282866 -126.104117) (xy 227.335161 -126.088762) (xy 227.389109 -126.081006)
			(xy 227.443611 -126.081006) (xy 227.497559 -126.088762) (xy 227.549854 -126.104117) (xy 227.599431 -126.126759)
			(xy 227.645281 -126.156225) (xy 227.686472 -126.191916) (xy 227.722163 -126.233107) (xy 227.751629 -126.278957)
			(xy 227.774271 -126.328534) (xy 227.789626 -126.380829) (xy 227.797382 -126.434777) (xy 227.797868 -126.462028)
			(xy 227.797868 -127.140208) (xy 242.041172 -127.140208) (xy 242.041172 -126.276608) (xy 242.041658 -126.249357)
			(xy 242.049414 -126.195409) (xy 242.064769 -126.143114) (xy 242.087411 -126.093537) (xy 242.116877 -126.047687)
			(xy 242.152568 -126.006496) (xy 242.193759 -125.970805) (xy 242.239609 -125.941339) (xy 242.289186 -125.918697)
			(xy 242.341481 -125.903342) (xy 242.395429 -125.895586) (xy 242.449931 -125.895586) (xy 242.503879 -125.903342)
			(xy 242.556174 -125.918697) (xy 242.605751 -125.941339) (xy 242.651601 -125.970805) (xy 242.692792 -126.006496)
			(xy 242.728483 -126.047687) (xy 242.757949 -126.093537) (xy 242.780591 -126.143114) (xy 242.795946 -126.195409)
			(xy 242.803702 -126.249357) (xy 242.804188 -126.276608) (xy 242.804188 -127.140208) (xy 242.803702 -127.167459)
			(xy 242.795946 -127.221407) (xy 242.780591 -127.273702) (xy 242.757949 -127.323279) (xy 242.728483 -127.369129)
			(xy 242.692792 -127.41032) (xy 242.651601 -127.446011) (xy 242.605751 -127.475477) (xy 242.556174 -127.498119)
			(xy 242.503879 -127.513474) (xy 242.449931 -127.52123) (xy 242.395429 -127.52123) (xy 242.341481 -127.513474)
			(xy 242.289186 -127.498119) (xy 242.239609 -127.475477) (xy 242.193759 -127.446011) (xy 242.152568 -127.41032)
			(xy 242.116877 -127.369129) (xy 242.087411 -127.323279) (xy 242.064769 -127.273702) (xy 242.049414 -127.221407)
			(xy 242.041658 -127.167459) (xy 242.041172 -127.140208) (xy 227.797868 -127.140208) (xy 227.797868 -127.325628)
			(xy 227.797382 -127.352879) (xy 227.789626 -127.406827) (xy 227.774271 -127.459122) (xy 227.751629 -127.508699)
			(xy 227.722163 -127.554549) (xy 227.686472 -127.59574) (xy 227.645281 -127.631431) (xy 227.599431 -127.660897)
			(xy 227.549854 -127.683539) (xy 227.519478 -127.692458) (xy 458.401155 -127.692458) (xy 458.401155 -127.563318)
			(xy 458.409105 -127.434423) (xy 458.424975 -127.306263) (xy 458.448704 -127.179322) (xy 458.480203 -127.054083)
			(xy 458.519352 -126.93102) (xy 458.566003 -126.810601) (xy 458.619978 -126.693282) (xy 458.681073 -126.579508)
			(xy 458.749056 -126.469711) (xy 458.82367 -126.364308) (xy 458.904631 -126.263698) (xy 458.991631 -126.168263)
			(xy 459.084342 -126.078364) (xy 459.182412 -125.994343) (xy 459.285467 -125.916519) (xy 459.393118 -125.845187)
			(xy 459.504957 -125.780617) (xy 459.620558 -125.723055) (xy 459.739483 -125.672718) (xy 459.861282 -125.629798)
			(xy 459.985492 -125.594457) (xy 460.111641 -125.56683) (xy 460.239253 -125.547021) (xy 460.367842 -125.535105)
			(xy 460.49692 -125.531129) (xy 460.625998 -125.535105) (xy 460.754587 -125.547021) (xy 460.882199 -125.56683)
			(xy 461.008348 -125.594457) (xy 461.132558 -125.629798) (xy 461.254357 -125.672718) (xy 461.373282 -125.723055)
			(xy 461.488883 -125.780617) (xy 461.600722 -125.845187) (xy 461.708373 -125.916519) (xy 461.811428 -125.994343)
			(xy 461.909498 -126.078364) (xy 462.002209 -126.168263) (xy 462.089209 -126.263698) (xy 462.17017 -126.364308)
			(xy 462.244784 -126.469711) (xy 462.312767 -126.579508) (xy 462.373862 -126.693282) (xy 462.427837 -126.810601)
			(xy 462.474488 -126.93102) (xy 462.513637 -127.054083) (xy 462.545136 -127.179322) (xy 462.568865 -127.306263)
			(xy 462.584735 -127.434423) (xy 462.592685 -127.563318) (xy 462.593182 -127.627888) (xy 462.592685 -127.692458)
			(xy 462.584735 -127.821353) (xy 462.568865 -127.949513) (xy 462.545136 -128.076454) (xy 462.513637 -128.201693)
			(xy 462.474488 -128.324756) (xy 462.427837 -128.445175) (xy 462.373862 -128.562494) (xy 462.312767 -128.676268)
			(xy 462.244784 -128.786065) (xy 462.17017 -128.891468) (xy 462.089209 -128.992078) (xy 462.002209 -129.087513)
			(xy 461.909498 -129.177412) (xy 461.811428 -129.261433) (xy 461.708373 -129.339257) (xy 461.600722 -129.410589)
			(xy 461.488883 -129.475159) (xy 461.373282 -129.532721) (xy 461.254357 -129.583058) (xy 461.132558 -129.625978)
			(xy 461.008348 -129.661319) (xy 460.882199 -129.688946) (xy 460.754587 -129.708755) (xy 460.625998 -129.720671)
			(xy 460.49692 -129.724648) (xy 460.367842 -129.720671) (xy 460.239253 -129.708755) (xy 460.111641 -129.688946)
			(xy 459.985492 -129.661319) (xy 459.861282 -129.625978) (xy 459.739483 -129.583058) (xy 459.620558 -129.532721)
			(xy 459.504957 -129.475159) (xy 459.393118 -129.410589) (xy 459.285467 -129.339257) (xy 459.182412 -129.261433)
			(xy 459.084342 -129.177412) (xy 458.991631 -129.087513) (xy 458.904631 -128.992078) (xy 458.82367 -128.891468)
			(xy 458.749056 -128.786065) (xy 458.681073 -128.676268) (xy 458.619978 -128.562494) (xy 458.566003 -128.445175)
			(xy 458.519352 -128.324756) (xy 458.480203 -128.201693) (xy 458.448704 -128.076454) (xy 458.424975 -127.949513)
			(xy 458.409105 -127.821353) (xy 458.401155 -127.692458) (xy 227.519478 -127.692458) (xy 227.497559 -127.698894)
			(xy 227.443611 -127.70665) (xy 227.389109 -127.70665) (xy 227.335161 -127.698894) (xy 227.282866 -127.683539)
			(xy 227.233289 -127.660897) (xy 227.187439 -127.631431) (xy 227.146248 -127.59574) (xy 227.110557 -127.554549)
			(xy 227.081091 -127.508699) (xy 227.058449 -127.459122) (xy 227.043094 -127.406827) (xy 227.035338 -127.352879)
			(xy 227.034852 -127.325628) (xy 2.509012 -127.325628) (xy 2.509012 -129.073148) (xy 223.562672 -129.073148)
			(xy 223.562672 -128.209548) (xy 223.563115 -128.182788) (xy 223.570596 -128.129795) (xy 223.585403 -128.078365)
			(xy 223.607247 -128.029506) (xy 223.621092 -128.006602) (xy 223.636032 -127.983032) (xy 223.671662 -127.940084)
			(xy 223.713174 -127.902792) (xy 223.759681 -127.871951) (xy 223.810187 -127.848221) (xy 223.863614 -127.832109)
			(xy 223.918819 -127.823961) (xy 223.94672 -127.823468) (xy 223.973934 -127.823967) (xy 224.027808 -127.831715)
			(xy 224.080031 -127.84705) (xy 224.12954 -127.869661) (xy 224.175327 -127.899088) (xy 224.216462 -127.93473)
			(xy 224.252105 -127.975863) (xy 224.281533 -128.02165) (xy 224.304145 -128.071158) (xy 224.319483 -128.123381)
			(xy 224.327232 -128.177254) (xy 224.32772 -128.204468) (xy 224.32772 -128.204722) (xy 224.325942 -128.241552)
			(xy 224.325688 -128.243838) (xy 224.325688 -129.019808) (xy 240.086896 -129.019808) (xy 240.086896 -128.156208)
			(xy 240.087382 -128.128939) (xy 240.095144 -128.074955) (xy 240.110509 -128.022625) (xy 240.133166 -127.973015)
			(xy 240.162652 -127.927134) (xy 240.198367 -127.885917) (xy 240.239584 -127.850202) (xy 240.285465 -127.820716)
			(xy 240.335075 -127.798059) (xy 240.387405 -127.782694) (xy 240.441389 -127.774932) (xy 240.495927 -127.774932)
			(xy 240.549911 -127.782694) (xy 240.602241 -127.798059) (xy 240.651851 -127.820716) (xy 240.697732 -127.850202)
			(xy 240.738949 -127.885917) (xy 240.774664 -127.927134) (xy 240.80415 -127.973015) (xy 240.826807 -128.022625)
			(xy 240.842172 -128.074955) (xy 240.849934 -128.128939) (xy 240.85042 -128.156208) (xy 240.85042 -129.019808)
			(xy 240.849934 -129.047077) (xy 240.842172 -129.101061) (xy 240.826807 -129.153391) (xy 240.80415 -129.203001)
			(xy 240.774664 -129.248882) (xy 240.738949 -129.290099) (xy 240.697732 -129.325814) (xy 240.651851 -129.3553)
			(xy 240.602241 -129.377957) (xy 240.549911 -129.393322) (xy 240.495927 -129.401084) (xy 240.441389 -129.401084)
			(xy 240.387405 -129.393322) (xy 240.335075 -129.377957) (xy 240.285465 -129.3553) (xy 240.239584 -129.325814)
			(xy 240.198367 -129.290099) (xy 240.162652 -129.248882) (xy 240.133166 -129.203001) (xy 240.110509 -129.153391)
			(xy 240.095144 -129.101061) (xy 240.087382 -129.047077) (xy 240.086896 -129.019808) (xy 224.325688 -129.019808)
			(xy 224.325942 -129.022602) (xy 224.327226 -129.033861) (xy 224.328622 -129.056482) (xy 224.328736 -129.067814)
			(xy 224.328736 -129.068068) (xy 224.328226 -129.095352) (xy 224.320425 -129.14936) (xy 224.305035 -129.201713)
			(xy 224.282367 -129.251351) (xy 224.26803 -129.27457) (xy 224.253042 -129.297814) (xy 224.217376 -129.340083)
			(xy 224.175977 -129.376756) (xy 224.129714 -129.407061) (xy 224.079557 -129.430365) (xy 224.026559 -129.446176)
			(xy 223.971833 -129.454165) (xy 223.94418 -129.454656) (xy 223.91693 -129.454141) (xy 223.862986 -129.446383)
			(xy 223.810695 -129.431028) (xy 223.761121 -129.408388) (xy 223.715273 -129.378924) (xy 223.674084 -129.343236)
			(xy 223.638393 -129.30205) (xy 223.608926 -129.256204) (xy 223.586282 -129.206631) (xy 223.570923 -129.154341)
			(xy 223.563161 -129.100398) (xy 223.562672 -129.073148) (xy 2.509012 -129.073148) (xy 2.509012 -131.09702)
			(xy 228.682804 -131.09702) (xy 228.682804 -130.23342) (xy 228.68329 -130.206151) (xy 228.691052 -130.152167)
			(xy 228.706417 -130.099837) (xy 228.729074 -130.050227) (xy 228.75856 -130.004346) (xy 228.794275 -129.963129)
			(xy 228.835492 -129.927414) (xy 228.881373 -129.897928) (xy 228.930983 -129.875271) (xy 228.983313 -129.859906)
			(xy 229.037297 -129.852144) (xy 229.091835 -129.852144) (xy 229.145819 -129.859906) (xy 229.198149 -129.875271)
			(xy 229.247759 -129.897928) (xy 229.29364 -129.927414) (xy 229.334857 -129.963129) (xy 229.370572 -130.004346)
			(xy 229.400058 -130.050227) (xy 229.422715 -130.099837) (xy 229.43808 -130.152167) (xy 229.445842 -130.206151)
			(xy 229.446328 -130.23342) (xy 229.446328 -130.721608) (xy 242.041172 -130.721608) (xy 242.041172 -129.858008)
			(xy 242.041658 -129.830757) (xy 242.049414 -129.776809) (xy 242.064769 -129.724514) (xy 242.087411 -129.674937)
			(xy 242.116877 -129.629087) (xy 242.152568 -129.587896) (xy 242.193759 -129.552205) (xy 242.239609 -129.522739)
			(xy 242.289186 -129.500097) (xy 242.341481 -129.484742) (xy 242.395429 -129.476986) (xy 242.449931 -129.476986)
			(xy 242.503879 -129.484742) (xy 242.556174 -129.500097) (xy 242.605751 -129.522739) (xy 242.651601 -129.552205)
			(xy 242.692792 -129.587896) (xy 242.728483 -129.629087) (xy 242.757949 -129.674937) (xy 242.780591 -129.724514)
			(xy 242.795946 -129.776809) (xy 242.803702 -129.830757) (xy 242.804188 -129.858008) (xy 242.804188 -130.721608)
			(xy 242.803702 -130.748859) (xy 242.795946 -130.802807) (xy 242.780591 -130.855102) (xy 242.757949 -130.904679)
			(xy 242.728483 -130.950529) (xy 242.692792 -130.99172) (xy 242.651601 -131.027411) (xy 242.605751 -131.056877)
			(xy 242.556174 -131.079519) (xy 242.503879 -131.094874) (xy 242.449931 -131.10263) (xy 242.395429 -131.10263)
			(xy 242.341481 -131.094874) (xy 242.289186 -131.079519) (xy 242.239609 -131.056877) (xy 242.193759 -131.027411)
			(xy 242.152568 -130.99172) (xy 242.116877 -130.950529) (xy 242.087411 -130.904679) (xy 242.064769 -130.855102)
			(xy 242.049414 -130.802807) (xy 242.041658 -130.748859) (xy 242.041172 -130.721608) (xy 229.446328 -130.721608)
			(xy 229.446328 -131.09702) (xy 229.445842 -131.124289) (xy 229.43808 -131.178273) (xy 229.422715 -131.230603)
			(xy 229.400058 -131.280213) (xy 229.370572 -131.326094) (xy 229.334857 -131.367311) (xy 229.29364 -131.403026)
			(xy 229.247759 -131.432512) (xy 229.198149 -131.455169) (xy 229.145819 -131.470534) (xy 229.091835 -131.478296)
			(xy 229.037297 -131.478296) (xy 228.983313 -131.470534) (xy 228.930983 -131.455169) (xy 228.881373 -131.432512)
			(xy 228.835492 -131.403026) (xy 228.794275 -131.367311) (xy 228.75856 -131.326094) (xy 228.729074 -131.280213)
			(xy 228.706417 -131.230603) (xy 228.691052 -131.178273) (xy 228.68329 -131.124289) (xy 228.682804 -131.09702)
			(xy 2.509012 -131.09702) (xy 2.509012 -132.529347) (xy 231.621126 -132.529347) (xy 231.621126 -132.474853)
			(xy 231.628881 -132.420915) (xy 231.644233 -132.368628) (xy 231.666869 -132.319059) (xy 231.69633 -132.273216)
			(xy 231.732014 -132.232031) (xy 231.773196 -132.196344) (xy 231.819038 -132.166881) (xy 231.868606 -132.144241)
			(xy 231.920891 -132.128886) (xy 231.974829 -132.121128) (xy 232.002076 -132.12064) (xy 232.865676 -132.12064)
			(xy 232.892933 -132.121005) (xy 232.946894 -132.128761) (xy 232.999201 -132.144116) (xy 233.048791 -132.16676)
			(xy 233.094653 -132.196231) (xy 233.135853 -132.23193) (xy 233.171554 -132.273128) (xy 233.201028 -132.318988)
			(xy 233.223675 -132.368576) (xy 233.239034 -132.420883) (xy 233.246793 -132.474843) (xy 233.246793 -132.529357)
			(xy 233.239034 -132.583317) (xy 233.223675 -132.635624) (xy 233.201028 -132.685212) (xy 233.171554 -132.731072)
			(xy 233.135853 -132.77227) (xy 233.094653 -132.807968) (xy 233.048791 -132.83744) (xy 232.999201 -132.860084)
			(xy 232.946894 -132.875439) (xy 232.892933 -132.883195) (xy 232.865676 -132.883656) (xy 232.002076 -132.883656)
			(xy 231.974829 -132.883072) (xy 231.920891 -132.875314) (xy 231.868606 -132.859959) (xy 231.819038 -132.837319)
			(xy 231.773196 -132.807856) (xy 231.732014 -132.772169) (xy 231.69633 -132.730984) (xy 231.666869 -132.685141)
			(xy 231.644233 -132.635572) (xy 231.628881 -132.583285) (xy 231.621126 -132.529347) (xy 2.509012 -132.529347)
			(xy 2.509012 -135.31065) (xy 225.204003 -135.31065) (xy 225.204003 -135.25615) (xy 225.21176 -135.202204)
			(xy 225.227115 -135.149911) (xy 225.249756 -135.100336) (xy 225.279222 -135.054487) (xy 225.314914 -135.013299)
			(xy 225.356103 -134.97761) (xy 225.401953 -134.948146) (xy 225.45153 -134.925508) (xy 225.503823 -134.910156)
			(xy 225.55777 -134.902402) (xy 225.58502 -134.90194) (xy 226.44862 -134.90194) (xy 226.475874 -134.902331)
			(xy 226.529826 -134.910091) (xy 226.582125 -134.92545) (xy 226.631706 -134.948095) (xy 226.67756 -134.977566)
			(xy 226.718753 -135.013262) (xy 226.754446 -135.054456) (xy 226.755856 -135.05665) (xy 228.531403 -135.05665)
			(xy 228.531403 -135.00215) (xy 228.53916 -134.948204) (xy 228.554515 -134.895911) (xy 228.577156 -134.846336)
			(xy 228.606622 -134.800487) (xy 228.642314 -134.759299) (xy 228.683503 -134.72361) (xy 228.729353 -134.694146)
			(xy 228.77893 -134.671508) (xy 228.831223 -134.656156) (xy 228.88517 -134.648402) (xy 228.91242 -134.64794)
			(xy 229.77602 -134.64794) (xy 229.803274 -134.648331) (xy 229.857226 -134.656091) (xy 229.909525 -134.67145)
			(xy 229.959106 -134.694095) (xy 230.00496 -134.723566) (xy 230.046153 -134.759262) (xy 230.081846 -134.800456)
			(xy 230.111315 -134.846312) (xy 230.133957 -134.895894) (xy 230.149313 -134.948193) (xy 230.15707 -135.002146)
			(xy 230.15707 -135.056654) (xy 230.149313 -135.110607) (xy 230.145996 -135.121904) (xy 234.029504 -135.121904)
			(xy 234.029504 -134.258304) (xy 234.02999 -134.231035) (xy 234.037752 -134.177051) (xy 234.053117 -134.124721)
			(xy 234.075774 -134.075111) (xy 234.10526 -134.02923) (xy 234.140975 -133.988013) (xy 234.182192 -133.952298)
			(xy 234.228073 -133.922812) (xy 234.277683 -133.900155) (xy 234.330013 -133.88479) (xy 234.383997 -133.877028)
			(xy 234.438535 -133.877028) (xy 234.492519 -133.88479) (xy 234.544849 -133.900155) (xy 234.594459 -133.922812)
			(xy 234.64034 -133.952298) (xy 234.681557 -133.988013) (xy 234.717272 -134.02923) (xy 234.746758 -134.075111)
			(xy 234.769415 -134.124721) (xy 234.78478 -134.177051) (xy 234.792542 -134.231035) (xy 234.793028 -134.258304)
			(xy 234.793028 -134.768971) (xy 236.02439 -134.768971) (xy 236.02439 -134.714429) (xy 236.032152 -134.660443)
			(xy 236.047518 -134.608111) (xy 236.070174 -134.558498) (xy 236.09966 -134.512615) (xy 236.135376 -134.471394)
			(xy 236.176594 -134.435676) (xy 236.222475 -134.406186) (xy 236.272087 -134.383527) (xy 236.324418 -134.368158)
			(xy 236.378403 -134.360392) (xy 236.405674 -134.359904) (xy 237.178342 -134.359904) (xy 237.205607 -134.360461)
			(xy 237.259581 -134.368227) (xy 237.311901 -134.383595) (xy 237.361502 -134.406251) (xy 237.407373 -134.435736)
			(xy 237.448582 -134.471448) (xy 237.48429 -134.512661) (xy 237.513769 -134.558535) (xy 237.53642 -134.608138)
			(xy 237.551782 -134.66046) (xy 237.559542 -134.714435) (xy 237.559542 -134.768965) (xy 237.551782 -134.82294)
			(xy 237.53642 -134.875262) (xy 237.513769 -134.924865) (xy 237.48429 -134.970739) (xy 237.448582 -135.011952)
			(xy 237.407373 -135.047664) (xy 237.361502 -135.077149) (xy 237.311901 -135.099805) (xy 237.259581 -135.115173)
			(xy 237.205607 -135.122939) (xy 237.178342 -135.123428) (xy 236.405674 -135.123428) (xy 236.378403 -135.123008)
			(xy 236.324418 -135.115242) (xy 236.272087 -135.099873) (xy 236.222475 -135.077214) (xy 236.176594 -135.047724)
			(xy 236.135376 -135.012006) (xy 236.09966 -134.970785) (xy 236.070174 -134.924902) (xy 236.047518 -134.875289)
			(xy 236.032152 -134.822957) (xy 236.02439 -134.768971) (xy 234.793028 -134.768971) (xy 234.793028 -135.121904)
			(xy 234.792542 -135.149173) (xy 234.786383 -135.192008) (xy 238.645192 -135.192008) (xy 238.645192 -134.328408)
			(xy 238.645678 -134.301157) (xy 238.653434 -134.247209) (xy 238.668789 -134.194914) (xy 238.691431 -134.145337)
			(xy 238.720897 -134.099487) (xy 238.756588 -134.058296) (xy 238.797779 -134.022605) (xy 238.843629 -133.993139)
			(xy 238.893206 -133.970497) (xy 238.945501 -133.955142) (xy 238.999449 -133.947386) (xy 239.053951 -133.947386)
			(xy 239.107899 -133.955142) (xy 239.160194 -133.970497) (xy 239.209771 -133.993139) (xy 239.255621 -134.022605)
			(xy 239.271831 -134.036651) (xy 242.034062 -134.036651) (xy 242.034062 -133.982149) (xy 242.041817 -133.928203)
			(xy 242.057171 -133.875909) (xy 242.07981 -133.826333) (xy 242.109274 -133.780482) (xy 242.144963 -133.739291)
			(xy 242.18615 -133.703598) (xy 242.231997 -133.67413) (xy 242.281572 -133.651485) (xy 242.333864 -133.636126)
			(xy 242.387809 -133.628365) (xy 242.41506 -133.627876) (xy 243.27866 -133.627876) (xy 243.305914 -133.628369)
			(xy 243.359867 -133.636121) (xy 243.412167 -133.651473) (xy 243.46175 -133.674112) (xy 243.507606 -133.703577)
			(xy 243.548802 -133.73927) (xy 243.584499 -133.780462) (xy 243.613969 -133.826315) (xy 243.636613 -133.875895)
			(xy 243.651971 -133.928194) (xy 243.659729 -133.982146) (xy 243.659729 -134.036654) (xy 243.651971 -134.090606)
			(xy 243.636613 -134.142905) (xy 243.613969 -134.192485) (xy 243.584499 -134.238338) (xy 243.548802 -134.27953)
			(xy 243.507606 -134.315223) (xy 243.46175 -134.344688) (xy 243.412167 -134.367327) (xy 243.359867 -134.382679)
			(xy 243.305914 -134.390431) (xy 243.27866 -134.390892) (xy 242.41506 -134.390892) (xy 242.387809 -134.390435)
			(xy 242.333864 -134.382674) (xy 242.281572 -134.367315) (xy 242.231997 -134.34467) (xy 242.18615 -134.315202)
			(xy 242.144963 -134.279509) (xy 242.109274 -134.238318) (xy 242.07981 -134.192467) (xy 242.057171 -134.142891)
			(xy 242.041817 -134.090597) (xy 242.034062 -134.036651) (xy 239.271831 -134.036651) (xy 239.296812 -134.058296)
			(xy 239.332503 -134.099487) (xy 239.361969 -134.145337) (xy 239.384611 -134.194914) (xy 239.399966 -134.247209)
			(xy 239.407722 -134.301157) (xy 239.408208 -134.328408) (xy 239.408208 -135.192008) (xy 239.407722 -135.219259)
			(xy 239.399966 -135.273207) (xy 239.384611 -135.325502) (xy 239.361969 -135.375079) (xy 239.332503 -135.420929)
			(xy 239.296812 -135.46212) (xy 239.255621 -135.497811) (xy 239.250425 -135.50115) (xy 244.457203 -135.50115)
			(xy 244.457203 -135.44665) (xy 244.46496 -135.392704) (xy 244.480315 -135.340411) (xy 244.502956 -135.290836)
			(xy 244.532422 -135.244987) (xy 244.568114 -135.203799) (xy 244.609303 -135.16811) (xy 244.655153 -135.138646)
			(xy 244.70473 -135.116008) (xy 244.757023 -135.100656) (xy 244.81097 -135.092902) (xy 244.83822 -135.09244)
			(xy 245.70182 -135.09244) (xy 245.729074 -135.092831) (xy 245.783026 -135.100591) (xy 245.835325 -135.11595)
			(xy 245.884906 -135.138595) (xy 245.93076 -135.168066) (xy 245.971953 -135.203762) (xy 246.007646 -135.244956)
			(xy 246.037115 -135.290812) (xy 246.059757 -135.340394) (xy 246.075113 -135.392693) (xy 246.08287 -135.446646)
			(xy 246.08287 -135.501154) (xy 246.075113 -135.555107) (xy 246.059757 -135.607406) (xy 246.037115 -135.656988)
			(xy 246.007646 -135.702844) (xy 245.971953 -135.744038) (xy 245.93076 -135.779734) (xy 245.884906 -135.809205)
			(xy 245.835325 -135.83185) (xy 245.783026 -135.847209) (xy 245.729074 -135.854969) (xy 245.70182 -135.855456)
			(xy 244.83822 -135.855456) (xy 244.81097 -135.854898) (xy 244.757023 -135.847144) (xy 244.70473 -135.831792)
			(xy 244.655153 -135.809154) (xy 244.609303 -135.77969) (xy 244.568114 -135.744001) (xy 244.532422 -135.702813)
			(xy 244.502956 -135.656964) (xy 244.480315 -135.607389) (xy 244.46496 -135.555096) (xy 244.457203 -135.50115)
			(xy 239.250425 -135.50115) (xy 239.209771 -135.527277) (xy 239.160194 -135.549919) (xy 239.107899 -135.565274)
			(xy 239.053951 -135.57303) (xy 238.999449 -135.57303) (xy 238.945501 -135.565274) (xy 238.893206 -135.549919)
			(xy 238.843629 -135.527277) (xy 238.797779 -135.497811) (xy 238.756588 -135.46212) (xy 238.720897 -135.420929)
			(xy 238.691431 -135.375079) (xy 238.668789 -135.325502) (xy 238.653434 -135.273207) (xy 238.645678 -135.219259)
			(xy 238.645192 -135.192008) (xy 234.786383 -135.192008) (xy 234.78478 -135.203157) (xy 234.769415 -135.255487)
			(xy 234.746758 -135.305097) (xy 234.717272 -135.350978) (xy 234.681557 -135.392195) (xy 234.64034 -135.42791)
			(xy 234.594459 -135.457396) (xy 234.544849 -135.480053) (xy 234.492519 -135.495418) (xy 234.438535 -135.50318)
			(xy 234.383997 -135.50318) (xy 234.330013 -135.495418) (xy 234.277683 -135.480053) (xy 234.228073 -135.457396)
			(xy 234.182192 -135.42791) (xy 234.140975 -135.392195) (xy 234.10526 -135.350978) (xy 234.075774 -135.305097)
			(xy 234.053117 -135.255487) (xy 234.037752 -135.203157) (xy 234.02999 -135.149173) (xy 234.029504 -135.121904)
			(xy 230.145996 -135.121904) (xy 230.133957 -135.162906) (xy 230.111315 -135.212488) (xy 230.081846 -135.258344)
			(xy 230.046153 -135.299538) (xy 230.00496 -135.335234) (xy 229.959106 -135.364705) (xy 229.909525 -135.38735)
			(xy 229.857226 -135.402709) (xy 229.803274 -135.410469) (xy 229.77602 -135.410956) (xy 228.91242 -135.410956)
			(xy 228.88517 -135.410398) (xy 228.831223 -135.402644) (xy 228.77893 -135.387292) (xy 228.729353 -135.364654)
			(xy 228.683503 -135.33519) (xy 228.642314 -135.299501) (xy 228.606622 -135.258313) (xy 228.577156 -135.212464)
			(xy 228.554515 -135.162889) (xy 228.53916 -135.110596) (xy 228.531403 -135.05665) (xy 226.755856 -135.05665)
			(xy 226.783915 -135.100312) (xy 226.806557 -135.149894) (xy 226.821913 -135.202193) (xy 226.82967 -135.256146)
			(xy 226.82967 -135.310654) (xy 226.821913 -135.364607) (xy 226.806557 -135.416906) (xy 226.783915 -135.466488)
			(xy 226.754446 -135.512344) (xy 226.718753 -135.553538) (xy 226.67756 -135.589234) (xy 226.631706 -135.618705)
			(xy 226.582125 -135.64135) (xy 226.529826 -135.656709) (xy 226.475874 -135.664469) (xy 226.44862 -135.664956)
			(xy 225.58502 -135.664956) (xy 225.55777 -135.664398) (xy 225.503823 -135.656644) (xy 225.45153 -135.641292)
			(xy 225.401953 -135.618654) (xy 225.356103 -135.58919) (xy 225.314914 -135.553501) (xy 225.279222 -135.512313)
			(xy 225.249756 -135.466464) (xy 225.227115 -135.416889) (xy 225.21176 -135.364596) (xy 225.204003 -135.31065)
			(xy 2.509012 -135.31065) (xy 2.509012 -137.199664) (xy 337.46447 -137.199664) (xy 337.46447 -137.145136)
			(xy 337.47223 -137.091163) (xy 337.487591 -137.038843) (xy 337.510241 -136.989242) (xy 337.539719 -136.943369)
			(xy 337.575425 -136.902158) (xy 337.616632 -136.866447) (xy 337.662502 -136.836963) (xy 337.7121 -136.814307)
			(xy 337.764418 -136.79894) (xy 337.81839 -136.791173) (xy 337.845654 -136.790684) (xy 338.618322 -136.790684)
			(xy 338.645594 -136.79108) (xy 338.699581 -136.798845) (xy 338.751915 -136.814214) (xy 338.801528 -136.836874)
			(xy 338.847412 -136.866364) (xy 338.888632 -136.902084) (xy 338.924349 -136.943306) (xy 338.953836 -136.989191)
			(xy 338.976493 -137.038806) (xy 338.991859 -137.09114) (xy 338.999622 -137.145128) (xy 338.999622 -137.199672)
			(xy 338.991859 -137.25366) (xy 338.976493 -137.305994) (xy 338.953836 -137.355609) (xy 338.924349 -137.401494)
			(xy 338.888632 -137.442716) (xy 338.847412 -137.478436) (xy 338.801528 -137.507926) (xy 338.751915 -137.530586)
			(xy 338.699581 -137.545955) (xy 338.645594 -137.55372) (xy 338.618322 -137.554208) (xy 337.845654 -137.554208)
			(xy 337.81839 -137.553627) (xy 337.764418 -137.54586) (xy 337.7121 -137.530493) (xy 337.662502 -137.507837)
			(xy 337.616632 -137.478353) (xy 337.575425 -137.442642) (xy 337.539719 -137.401431) (xy 337.510241 -137.355558)
			(xy 337.487591 -137.305957) (xy 337.47223 -137.253637) (xy 337.46447 -137.199664) (xy 2.509012 -137.199664)
			(xy 2.509012 -137.622788) (xy 340.085172 -137.622788) (xy 340.085172 -136.759188) (xy 340.085658 -136.731937)
			(xy 340.093414 -136.677989) (xy 340.108769 -136.625694) (xy 340.131411 -136.576117) (xy 340.160877 -136.530267)
			(xy 340.196568 -136.489076) (xy 340.237759 -136.453385) (xy 340.283609 -136.423919) (xy 340.333186 -136.401277)
			(xy 340.385481 -136.385922) (xy 340.439429 -136.378166) (xy 340.493931 -136.378166) (xy 340.547879 -136.385922)
			(xy 340.600174 -136.401277) (xy 340.649751 -136.423919) (xy 340.695601 -136.453385) (xy 340.736792 -136.489076)
			(xy 340.772483 -136.530267) (xy 340.801949 -136.576117) (xy 340.824591 -136.625694) (xy 340.839946 -136.677989)
			(xy 340.847702 -136.731937) (xy 340.848188 -136.759188) (xy 340.848188 -137.622788) (xy 340.847702 -137.650039)
			(xy 340.839946 -137.703987) (xy 340.824591 -137.756282) (xy 340.801949 -137.805859) (xy 340.772483 -137.851709)
			(xy 340.736792 -137.8929) (xy 340.695601 -137.928591) (xy 340.649751 -137.958057) (xy 340.600174 -137.980699)
			(xy 340.547879 -137.996054) (xy 340.493931 -138.00381) (xy 340.439429 -138.00381) (xy 340.385481 -137.996054)
			(xy 340.333186 -137.980699) (xy 340.283609 -137.958057) (xy 340.237759 -137.928591) (xy 340.196568 -137.8929)
			(xy 340.160877 -137.851709) (xy 340.131411 -137.805859) (xy 340.108769 -137.756282) (xy 340.093414 -137.703987)
			(xy 340.085658 -137.650039) (xy 340.085172 -137.622788) (xy 2.509012 -137.622788) (xy 2.509012 -153.766012)
			(xy 24.445731 -153.766012) (xy 24.449724 -153.556271) (xy 24.4617 -153.346834) (xy 24.481641 -153.138005)
			(xy 24.509518 -152.930086) (xy 24.54529 -152.723379) (xy 24.588905 -152.518184) (xy 24.640301 -152.314799)
			(xy 24.699403 -152.113517) (xy 24.766125 -151.914631) (xy 24.84037 -151.71843) (xy 24.92203 -151.525198)
			(xy 25.010988 -151.335214) (xy 25.107115 -151.148755) (xy 25.21027 -150.966091) (xy 25.320305 -150.787486)
			(xy 25.437059 -150.6132) (xy 25.560364 -150.443485) (xy 25.690041 -150.278587) (xy 25.825902 -150.118746)
			(xy 25.967749 -149.964193) (xy 26.115378 -149.815153) (xy 26.268573 -149.67184) (xy 26.427114 -149.534464)
			(xy 26.590769 -149.403223) (xy 26.759303 -149.278308) (xy 26.932469 -149.1599) (xy 27.110019 -149.04817)
			(xy 27.291693 -148.94328) (xy 27.477228 -148.845383) (xy 27.666356 -148.754621) (xy 27.858803 -148.671124)
			(xy 28.054288 -148.595014) (xy 28.25253 -148.526402) (xy 28.45324 -148.465387) (xy 28.656127 -148.412058)
			(xy 28.860897 -148.366491) (xy 29.067254 -148.328752) (xy 29.274898 -148.298898) (xy 29.483528 -148.27697)
			(xy 29.692841 -148.263001) (xy 29.902535 -148.25701) (xy 30.112304 -148.259007) (xy 30.321846 -148.268989)
			(xy 30.530856 -148.286941) (xy 30.73903 -148.312837) (xy 30.946068 -148.346639) (xy 31.151669 -148.388299)
			(xy 31.355535 -148.437757) (xy 31.55737 -148.49494) (xy 31.756882 -148.559765) (xy 31.953781 -148.632139)
			(xy 32.147782 -148.711956) (xy 32.338604 -148.799102) (xy 32.52597 -148.893449) (xy 32.709608 -148.99486)
			(xy 32.889252 -149.10319) (xy 33.064642 -149.21828) (xy 33.235523 -149.339964) (xy 33.401647 -149.468065)
			(xy 33.562774 -149.602398) (xy 33.718671 -149.742767) (xy 33.86911 -149.88897) (xy 34.013874 -150.040794)
			(xy 34.152753 -150.19802) (xy 34.285546 -150.360419) (xy 34.41206 -150.527755) (xy 34.532112 -150.699787)
			(xy 34.645527 -150.876264) (xy 34.752141 -151.056932) (xy 34.8518 -151.241527) (xy 34.944359 -151.429782)
			(xy 35.029684 -151.621425) (xy 35.107651 -151.816177) (xy 35.178147 -152.013757) (xy 35.24107 -152.213876)
			(xy 35.296329 -152.416247) (xy 35.343843 -152.620574) (xy 35.383544 -152.826562) (xy 35.415374 -153.033913)
			(xy 35.439287 -153.242324) (xy 35.455248 -153.451495) (xy 35.463235 -153.661122) (xy 35.463734 -153.766012)
			(xy 35.463235 -153.870902) (xy 35.455248 -154.080529) (xy 35.44312 -154.239468) (xy 186.742832 -154.239468)
			(xy 186.742832 -153.375868) (xy 186.743318 -153.348617) (xy 186.751074 -153.294669) (xy 186.766429 -153.242374)
			(xy 186.789071 -153.192797) (xy 186.818537 -153.146947) (xy 186.854228 -153.105756) (xy 186.895419 -153.070065)
			(xy 186.941269 -153.040599) (xy 186.990846 -153.017957) (xy 187.043141 -153.002602) (xy 187.097089 -152.994846)
			(xy 187.151591 -152.994846) (xy 187.205539 -153.002602) (xy 187.257834 -153.017957) (xy 187.307411 -153.040599)
			(xy 187.353261 -153.070065) (xy 187.394452 -153.105756) (xy 187.430143 -153.146947) (xy 187.459609 -153.192797)
			(xy 187.482251 -153.242374) (xy 187.497606 -153.294669) (xy 187.505362 -153.348617) (xy 187.505848 -153.375868)
			(xy 187.505848 -153.774902) (xy 188.445657 -153.774902) (xy 188.44965 -153.565161) (xy 188.461626 -153.355724)
			(xy 188.481567 -153.146895) (xy 188.509444 -152.938976) (xy 188.545216 -152.732269) (xy 188.588831 -152.527074)
			(xy 188.640227 -152.323689) (xy 188.699329 -152.122407) (xy 188.766051 -151.923521) (xy 188.840296 -151.72732)
			(xy 188.921956 -151.534088) (xy 189.010914 -151.344104) (xy 189.107041 -151.157645) (xy 189.210196 -150.974981)
			(xy 189.320231 -150.796376) (xy 189.436985 -150.62209) (xy 189.56029 -150.452375) (xy 189.689967 -150.287477)
			(xy 189.825828 -150.127636) (xy 189.967675 -149.973083) (xy 190.115304 -149.824043) (xy 190.268499 -149.68073)
			(xy 190.42704 -149.543354) (xy 190.590695 -149.412113) (xy 190.759229 -149.287198) (xy 190.932395 -149.16879)
			(xy 191.109945 -149.05706) (xy 191.291619 -148.95217) (xy 191.477154 -148.854273) (xy 191.666282 -148.763511)
			(xy 191.858729 -148.680014) (xy 192.054214 -148.603904) (xy 192.252456 -148.535292) (xy 192.453166 -148.474277)
			(xy 192.656053 -148.420948) (xy 192.860823 -148.375381) (xy 193.06718 -148.337642) (xy 193.274824 -148.307788)
			(xy 193.483454 -148.28586) (xy 193.692767 -148.271891) (xy 193.902461 -148.2659) (xy 194.11223 -148.267897)
			(xy 194.321772 -148.277879) (xy 194.530782 -148.295831) (xy 194.738956 -148.321727) (xy 194.945994 -148.355529)
			(xy 195.151595 -148.397189) (xy 195.355461 -148.446647) (xy 195.557296 -148.50383) (xy 195.756808 -148.568655)
			(xy 195.953707 -148.641029) (xy 196.147708 -148.720846) (xy 196.33853 -148.807992) (xy 196.525896 -148.902339)
			(xy 196.709534 -149.00375) (xy 196.889178 -149.11208) (xy 197.064568 -149.22717) (xy 197.235449 -149.348854)
			(xy 197.401573 -149.476955) (xy 197.5627 -149.611288) (xy 197.718597 -149.751657) (xy 197.869036 -149.89786)
			(xy 198.0138 -150.049684) (xy 198.152679 -150.20691) (xy 198.285472 -150.369309) (xy 198.411986 -150.536645)
			(xy 198.532038 -150.708677) (xy 198.645453 -150.885154) (xy 198.752067 -151.065822) (xy 198.851726 -151.250417)
			(xy 198.944285 -151.438672) (xy 199.02961 -151.630315) (xy 199.107577 -151.825067) (xy 199.178073 -152.022647)
			(xy 199.240996 -152.222766) (xy 199.296255 -152.425137) (xy 199.343769 -152.629464) (xy 199.38347 -152.835452)
			(xy 199.4153 -153.042803) (xy 199.439213 -153.251214) (xy 199.455174 -153.460385) (xy 199.463161 -153.670012)
			(xy 199.463618 -153.766012) (xy 272.385799 -153.766012) (xy 272.389792 -153.556271) (xy 272.401768 -153.346834)
			(xy 272.421709 -153.138005) (xy 272.449586 -152.930086) (xy 272.485358 -152.723379) (xy 272.528973 -152.518184)
			(xy 272.580369 -152.314799) (xy 272.639471 -152.113517) (xy 272.706193 -151.914631) (xy 272.780438 -151.71843)
			(xy 272.862098 -151.525198) (xy 272.951056 -151.335214) (xy 273.047183 -151.148755) (xy 273.150338 -150.966091)
			(xy 273.260373 -150.787486) (xy 273.377127 -150.6132) (xy 273.500432 -150.443485) (xy 273.630109 -150.278587)
			(xy 273.76597 -150.118746) (xy 273.907817 -149.964193) (xy 274.055446 -149.815153) (xy 274.208641 -149.67184)
			(xy 274.367182 -149.534464) (xy 274.530837 -149.403223) (xy 274.699371 -149.278308) (xy 274.872537 -149.1599)
			(xy 275.050087 -149.04817) (xy 275.231761 -148.94328) (xy 275.417296 -148.845383) (xy 275.606424 -148.754621)
			(xy 275.798871 -148.671124) (xy 275.994356 -148.595014) (xy 276.192598 -148.526402) (xy 276.393308 -148.465387)
			(xy 276.596195 -148.412058) (xy 276.800965 -148.366491) (xy 277.007322 -148.328752) (xy 277.214966 -148.298898)
			(xy 277.423596 -148.27697) (xy 277.632909 -148.263001) (xy 277.842603 -148.25701) (xy 278.052372 -148.259007)
			(xy 278.261914 -148.268989) (xy 278.470924 -148.286941) (xy 278.679098 -148.312837) (xy 278.886136 -148.346639)
			(xy 279.091737 -148.388299) (xy 279.295603 -148.437757) (xy 279.497438 -148.49494) (xy 279.69695 -148.559765)
			(xy 279.893849 -148.632139) (xy 280.08785 -148.711956) (xy 280.278672 -148.799102) (xy 280.466038 -148.893449)
			(xy 280.649676 -148.99486) (xy 280.82932 -149.10319) (xy 281.00471 -149.21828) (xy 281.175591 -149.339964)
			(xy 281.341715 -149.468065) (xy 281.502842 -149.602398) (xy 281.658739 -149.742767) (xy 281.809178 -149.88897)
			(xy 281.953942 -150.040794) (xy 282.092821 -150.19802) (xy 282.225614 -150.360419) (xy 282.352128 -150.527755)
			(xy 282.47218 -150.699787) (xy 282.585595 -150.876264) (xy 282.692209 -151.056932) (xy 282.791868 -151.241527)
			(xy 282.884427 -151.429782) (xy 282.969752 -151.621425) (xy 283.047719 -151.816177) (xy 283.118215 -152.013757)
			(xy 283.181138 -152.213876) (xy 283.236397 -152.416247) (xy 283.283911 -152.620574) (xy 283.323612 -152.826562)
			(xy 283.355442 -153.033913) (xy 283.379355 -153.242324) (xy 283.395316 -153.451495) (xy 283.403303 -153.661122)
			(xy 283.403802 -153.766012) (xy 283.40376 -153.774902) (xy 436.385725 -153.774902) (xy 436.389718 -153.565161)
			(xy 436.401694 -153.355724) (xy 436.421635 -153.146895) (xy 436.449512 -152.938976) (xy 436.485284 -152.732269)
			(xy 436.528899 -152.527074) (xy 436.580295 -152.323689) (xy 436.639397 -152.122407) (xy 436.706119 -151.923521)
			(xy 436.780364 -151.72732) (xy 436.862024 -151.534088) (xy 436.950982 -151.344104) (xy 437.047109 -151.157645)
			(xy 437.150264 -150.974981) (xy 437.260299 -150.796376) (xy 437.377053 -150.62209) (xy 437.500358 -150.452375)
			(xy 437.630035 -150.287477) (xy 437.765896 -150.127636) (xy 437.907743 -149.973083) (xy 438.055372 -149.824043)
			(xy 438.208567 -149.68073) (xy 438.367108 -149.543354) (xy 438.530763 -149.412113) (xy 438.699297 -149.287198)
			(xy 438.872463 -149.16879) (xy 439.050013 -149.05706) (xy 439.231687 -148.95217) (xy 439.417222 -148.854273)
			(xy 439.60635 -148.763511) (xy 439.798797 -148.680014) (xy 439.994282 -148.603904) (xy 440.192524 -148.535292)
			(xy 440.393234 -148.474277) (xy 440.596121 -148.420948) (xy 440.800891 -148.375381) (xy 441.007248 -148.337642)
			(xy 441.214892 -148.307788) (xy 441.423522 -148.28586) (xy 441.632835 -148.271891) (xy 441.842529 -148.2659)
			(xy 442.052298 -148.267897) (xy 442.26184 -148.277879) (xy 442.47085 -148.295831) (xy 442.679024 -148.321727)
			(xy 442.886062 -148.355529) (xy 443.091663 -148.397189) (xy 443.295529 -148.446647) (xy 443.497364 -148.50383)
			(xy 443.696876 -148.568655) (xy 443.893775 -148.641029) (xy 444.087776 -148.720846) (xy 444.278598 -148.807992)
			(xy 444.465964 -148.902339) (xy 444.649602 -149.00375) (xy 444.829246 -149.11208) (xy 445.004636 -149.22717)
			(xy 445.175517 -149.348854) (xy 445.341641 -149.476955) (xy 445.502768 -149.611288) (xy 445.658665 -149.751657)
			(xy 445.809104 -149.89786) (xy 445.953868 -150.049684) (xy 446.092747 -150.20691) (xy 446.22554 -150.369309)
			(xy 446.352054 -150.536645) (xy 446.472106 -150.708677) (xy 446.585521 -150.885154) (xy 446.692135 -151.065822)
			(xy 446.791794 -151.250417) (xy 446.884353 -151.438672) (xy 446.969678 -151.630315) (xy 447.047645 -151.825067)
			(xy 447.118141 -152.022647) (xy 447.181064 -152.222766) (xy 447.236323 -152.425137) (xy 447.283837 -152.629464)
			(xy 447.323538 -152.835452) (xy 447.355368 -153.042803) (xy 447.379281 -153.251214) (xy 447.395242 -153.460385)
			(xy 447.403229 -153.670012) (xy 447.403728 -153.774902) (xy 447.403229 -153.879792) (xy 447.395242 -154.089419)
			(xy 447.379281 -154.29859) (xy 447.355368 -154.507001) (xy 447.323538 -154.714352) (xy 447.283837 -154.92034)
			(xy 447.236323 -155.124667) (xy 447.181064 -155.327038) (xy 447.118141 -155.527157) (xy 447.047645 -155.724737)
			(xy 446.969678 -155.919489) (xy 446.884353 -156.111132) (xy 446.791794 -156.299387) (xy 446.692135 -156.483982)
			(xy 446.585521 -156.66465) (xy 446.472106 -156.841127) (xy 446.352054 -157.013159) (xy 446.22554 -157.180495)
			(xy 446.092747 -157.342894) (xy 445.953868 -157.50012) (xy 445.809104 -157.651944) (xy 445.658665 -157.798147)
			(xy 445.502768 -157.938516) (xy 445.341641 -158.072849) (xy 445.175517 -158.20095) (xy 445.004636 -158.322634)
			(xy 444.829246 -158.437724) (xy 444.649602 -158.546054) (xy 444.465964 -158.647465) (xy 444.278598 -158.741812)
			(xy 444.087776 -158.828958) (xy 443.893775 -158.908775) (xy 443.696876 -158.981149) (xy 443.497364 -159.045974)
			(xy 443.295529 -159.103157) (xy 443.091663 -159.152615) (xy 442.886062 -159.194275) (xy 442.679024 -159.228077)
			(xy 442.47085 -159.253973) (xy 442.26184 -159.271925) (xy 442.052298 -159.281907) (xy 441.842529 -159.283904)
			(xy 441.632835 -159.277913) (xy 441.423522 -159.263944) (xy 441.214892 -159.242016) (xy 441.007248 -159.212162)
			(xy 440.800891 -159.174423) (xy 440.596121 -159.128856) (xy 440.393234 -159.075527) (xy 440.192524 -159.014512)
			(xy 439.994282 -158.9459) (xy 439.798797 -158.86979) (xy 439.60635 -158.786293) (xy 439.417222 -158.695531)
			(xy 439.231687 -158.597634) (xy 439.050013 -158.492744) (xy 438.872463 -158.381014) (xy 438.699297 -158.262606)
			(xy 438.530763 -158.137691) (xy 438.367108 -158.00645) (xy 438.208567 -157.869074) (xy 438.055372 -157.725761)
			(xy 437.907743 -157.576721) (xy 437.765896 -157.422168) (xy 437.630035 -157.262327) (xy 437.500358 -157.097429)
			(xy 437.377053 -156.927714) (xy 437.260299 -156.753428) (xy 437.150264 -156.574823) (xy 437.047109 -156.392159)
			(xy 436.950982 -156.2057) (xy 436.862024 -156.015716) (xy 436.780364 -155.822484) (xy 436.706119 -155.626283)
			(xy 436.639397 -155.427397) (xy 436.580295 -155.226115) (xy 436.528899 -155.02273) (xy 436.485284 -154.817535)
			(xy 436.449512 -154.610828) (xy 436.421635 -154.402909) (xy 436.401694 -154.19408) (xy 436.389718 -153.984643)
			(xy 436.385725 -153.774902) (xy 283.40376 -153.774902) (xy 283.403303 -153.870902) (xy 283.395316 -154.080529)
			(xy 283.379355 -154.2897) (xy 283.355442 -154.498111) (xy 283.323612 -154.705462) (xy 283.283911 -154.91145)
			(xy 283.236397 -155.115777) (xy 283.181138 -155.318148) (xy 283.118215 -155.518267) (xy 283.047719 -155.715847)
			(xy 282.969752 -155.910599) (xy 282.884427 -156.102242) (xy 282.791868 -156.290497) (xy 282.692209 -156.475092)
			(xy 282.585595 -156.65576) (xy 282.47218 -156.832237) (xy 282.352128 -157.004269) (xy 282.225614 -157.171605)
			(xy 282.092821 -157.334004) (xy 281.953942 -157.49123) (xy 281.809178 -157.643054) (xy 281.658739 -157.789257)
			(xy 281.502842 -157.929626) (xy 281.341715 -158.063959) (xy 281.175591 -158.19206) (xy 281.00471 -158.313744)
			(xy 280.82932 -158.428834) (xy 280.649676 -158.537164) (xy 280.466038 -158.638575) (xy 280.278672 -158.732922)
			(xy 280.08785 -158.820068) (xy 279.893849 -158.899885) (xy 279.69695 -158.972259) (xy 279.497438 -159.037084)
			(xy 279.295603 -159.094267) (xy 279.091737 -159.143725) (xy 278.886136 -159.185385) (xy 278.679098 -159.219187)
			(xy 278.470924 -159.245083) (xy 278.261914 -159.263035) (xy 278.052372 -159.273017) (xy 277.842603 -159.275014)
			(xy 277.632909 -159.269023) (xy 277.423596 -159.255054) (xy 277.214966 -159.233126) (xy 277.007322 -159.203272)
			(xy 276.800965 -159.165533) (xy 276.596195 -159.119966) (xy 276.393308 -159.066637) (xy 276.192598 -159.005622)
			(xy 275.994356 -158.93701) (xy 275.798871 -158.8609) (xy 275.606424 -158.777403) (xy 275.417296 -158.686641)
			(xy 275.231761 -158.588744) (xy 275.050087 -158.483854) (xy 274.872537 -158.372124) (xy 274.699371 -158.253716)
			(xy 274.530837 -158.128801) (xy 274.367182 -157.99756) (xy 274.208641 -157.860184) (xy 274.055446 -157.716871)
			(xy 273.907817 -157.567831) (xy 273.76597 -157.413278) (xy 273.630109 -157.253437) (xy 273.500432 -157.088539)
			(xy 273.377127 -156.918824) (xy 273.260373 -156.744538) (xy 273.150338 -156.565933) (xy 273.047183 -156.383269)
			(xy 272.951056 -156.19681) (xy 272.862098 -156.006826) (xy 272.780438 -155.813594) (xy 272.706193 -155.617393)
			(xy 272.639471 -155.418507) (xy 272.580369 -155.217225) (xy 272.528973 -155.01384) (xy 272.485358 -154.808645)
			(xy 272.449586 -154.601938) (xy 272.421709 -154.394019) (xy 272.401768 -154.18519) (xy 272.389792 -153.975753)
			(xy 272.385799 -153.766012) (xy 199.463618 -153.766012) (xy 199.46366 -153.774902) (xy 199.463161 -153.879792)
			(xy 199.455174 -154.089419) (xy 199.439213 -154.29859) (xy 199.4153 -154.507001) (xy 199.38347 -154.714352)
			(xy 199.343769 -154.92034) (xy 199.296255 -155.124667) (xy 199.240996 -155.327038) (xy 199.178073 -155.527157)
			(xy 199.107577 -155.724737) (xy 199.02961 -155.919489) (xy 198.944285 -156.111132) (xy 198.851726 -156.299387)
			(xy 198.752067 -156.483982) (xy 198.645453 -156.66465) (xy 198.532038 -156.841127) (xy 198.411986 -157.013159)
			(xy 198.285472 -157.180495) (xy 198.152679 -157.342894) (xy 198.0138 -157.50012) (xy 197.869036 -157.651944)
			(xy 197.718597 -157.798147) (xy 197.5627 -157.938516) (xy 197.401573 -158.072849) (xy 197.235449 -158.20095)
			(xy 197.064568 -158.322634) (xy 196.889178 -158.437724) (xy 196.709534 -158.546054) (xy 196.525896 -158.647465)
			(xy 196.33853 -158.741812) (xy 196.147708 -158.828958) (xy 195.953707 -158.908775) (xy 195.756808 -158.981149)
			(xy 195.557296 -159.045974) (xy 195.355461 -159.103157) (xy 195.151595 -159.152615) (xy 194.945994 -159.194275)
			(xy 194.738956 -159.228077) (xy 194.530782 -159.253973) (xy 194.321772 -159.271925) (xy 194.11223 -159.281907)
			(xy 193.902461 -159.283904) (xy 193.692767 -159.277913) (xy 193.483454 -159.263944) (xy 193.274824 -159.242016)
			(xy 193.06718 -159.212162) (xy 192.860823 -159.174423) (xy 192.656053 -159.128856) (xy 192.453166 -159.075527)
			(xy 192.252456 -159.014512) (xy 192.054214 -158.9459) (xy 191.858729 -158.86979) (xy 191.666282 -158.786293)
			(xy 191.477154 -158.695531) (xy 191.291619 -158.597634) (xy 191.109945 -158.492744) (xy 190.932395 -158.381014)
			(xy 190.759229 -158.262606) (xy 190.590695 -158.137691) (xy 190.42704 -158.00645) (xy 190.268499 -157.869074)
			(xy 190.115304 -157.725761) (xy 189.967675 -157.576721) (xy 189.825828 -157.422168) (xy 189.689967 -157.262327)
			(xy 189.56029 -157.097429) (xy 189.436985 -156.927714) (xy 189.320231 -156.753428) (xy 189.210196 -156.574823)
			(xy 189.107041 -156.392159) (xy 189.010914 -156.2057) (xy 188.921956 -156.015716) (xy 188.840296 -155.822484)
			(xy 188.766051 -155.626283) (xy 188.699329 -155.427397) (xy 188.640227 -155.226115) (xy 188.588831 -155.02273)
			(xy 188.545216 -154.817535) (xy 188.509444 -154.610828) (xy 188.481567 -154.402909) (xy 188.461626 -154.19408)
			(xy 188.44965 -153.984643) (xy 188.445657 -153.774902) (xy 187.505848 -153.774902) (xy 187.505848 -154.239468)
			(xy 187.505362 -154.266719) (xy 187.497606 -154.320667) (xy 187.482251 -154.372962) (xy 187.459609 -154.422539)
			(xy 187.430143 -154.468389) (xy 187.394452 -154.50958) (xy 187.353261 -154.545271) (xy 187.307411 -154.574737)
			(xy 187.257834 -154.597379) (xy 187.205539 -154.612734) (xy 187.151591 -154.62049) (xy 187.097089 -154.62049)
			(xy 187.043141 -154.612734) (xy 186.990846 -154.597379) (xy 186.941269 -154.574737) (xy 186.895419 -154.545271)
			(xy 186.854228 -154.50958) (xy 186.818537 -154.468389) (xy 186.789071 -154.422539) (xy 186.766429 -154.372962)
			(xy 186.751074 -154.320667) (xy 186.743318 -154.266719) (xy 186.742832 -154.239468) (xy 35.44312 -154.239468)
			(xy 35.439287 -154.2897) (xy 35.415374 -154.498111) (xy 35.383544 -154.705462) (xy 35.343843 -154.91145)
			(xy 35.296329 -155.115777) (xy 35.24107 -155.318148) (xy 35.178147 -155.518267) (xy 35.107651 -155.715847)
			(xy 35.029684 -155.910599) (xy 34.944359 -156.102242) (xy 34.8518 -156.290497) (xy 34.752141 -156.475092)
			(xy 34.645527 -156.65576) (xy 34.532112 -156.832237) (xy 34.41206 -157.004269) (xy 34.285546 -157.171605)
			(xy 34.152753 -157.334004) (xy 34.013874 -157.49123) (xy 33.86911 -157.643054) (xy 33.718671 -157.789257)
			(xy 33.562774 -157.929626) (xy 33.401647 -158.063959) (xy 33.235523 -158.19206) (xy 33.064642 -158.313744)
			(xy 32.889252 -158.428834) (xy 32.709608 -158.537164) (xy 32.52597 -158.638575) (xy 32.338604 -158.732922)
			(xy 32.147782 -158.820068) (xy 31.953781 -158.899885) (xy 31.756882 -158.972259) (xy 31.55737 -159.037084)
			(xy 31.355535 -159.094267) (xy 31.151669 -159.143725) (xy 30.946068 -159.185385) (xy 30.73903 -159.219187)
			(xy 30.530856 -159.245083) (xy 30.321846 -159.263035) (xy 30.112304 -159.273017) (xy 29.902535 -159.275014)
			(xy 29.692841 -159.269023) (xy 29.483528 -159.255054) (xy 29.274898 -159.233126) (xy 29.067254 -159.203272)
			(xy 28.860897 -159.165533) (xy 28.656127 -159.119966) (xy 28.45324 -159.066637) (xy 28.25253 -159.005622)
			(xy 28.054288 -158.93701) (xy 27.858803 -158.8609) (xy 27.666356 -158.777403) (xy 27.477228 -158.686641)
			(xy 27.291693 -158.588744) (xy 27.110019 -158.483854) (xy 26.932469 -158.372124) (xy 26.759303 -158.253716)
			(xy 26.590769 -158.128801) (xy 26.427114 -157.99756) (xy 26.268573 -157.860184) (xy 26.115378 -157.716871)
			(xy 25.967749 -157.567831) (xy 25.825902 -157.413278) (xy 25.690041 -157.253437) (xy 25.560364 -157.088539)
			(xy 25.437059 -156.918824) (xy 25.320305 -156.744538) (xy 25.21027 -156.565933) (xy 25.107115 -156.383269)
			(xy 25.010988 -156.19681) (xy 24.92203 -156.006826) (xy 24.84037 -155.813594) (xy 24.766125 -155.617393)
			(xy 24.699403 -155.418507) (xy 24.640301 -155.217225) (xy 24.588905 -155.01384) (xy 24.54529 -154.808645)
			(xy 24.509518 -154.601938) (xy 24.481641 -154.394019) (xy 24.4617 -154.18519) (xy 24.449724 -153.975753)
			(xy 24.445731 -153.766012) (xy 2.509012 -153.766012) (xy 2.509012 -160.911354) (xy 372.506163 -160.911354)
			(xy 372.506163 -160.856846) (xy 372.513921 -160.802893) (xy 372.529279 -160.750593) (xy 372.551924 -160.701011)
			(xy 372.581395 -160.655157) (xy 372.617092 -160.613964) (xy 372.658289 -160.578271) (xy 372.704146 -160.548805)
			(xy 372.75373 -160.526165) (xy 372.806032 -160.510813) (xy 372.859986 -160.503061) (xy 372.88724 -160.5026)
			(xy 373.75084 -160.5026) (xy 373.77809 -160.503073) (xy 373.832034 -160.510834) (xy 373.884326 -160.526193)
			(xy 373.933899 -160.548837) (xy 373.979745 -160.578305) (xy 374.020931 -160.613997) (xy 374.056619 -160.655187)
			(xy 374.086083 -160.701036) (xy 374.108721 -160.750612) (xy 374.124075 -160.802905) (xy 374.13183 -160.85685)
			(xy 374.13183 -160.91135) (xy 374.124075 -160.965295) (xy 374.108721 -161.017588) (xy 374.086083 -161.067164)
			(xy 374.056619 -161.113013) (xy 374.020931 -161.154203) (xy 373.979745 -161.189895) (xy 373.933899 -161.219363)
			(xy 373.884326 -161.242007) (xy 373.832034 -161.257366) (xy 373.77809 -161.265127) (xy 373.75084 -161.265616)
			(xy 372.88724 -161.265616) (xy 372.859986 -161.265139) (xy 372.806032 -161.257387) (xy 372.75373 -161.242035)
			(xy 372.704146 -161.219395) (xy 372.658289 -161.189929) (xy 372.617092 -161.154236) (xy 372.581395 -161.113043)
			(xy 372.551924 -161.067189) (xy 372.529279 -161.017607) (xy 372.513921 -160.965307) (xy 372.506163 -160.911354)
			(xy 2.509012 -160.911354) (xy 2.509012 -161.58445) (xy 296.753286 -161.58445) (xy 296.753286 -161.52995)
			(xy 296.761042 -161.476005) (xy 296.776395 -161.423713) (xy 296.799035 -161.374138) (xy 296.828498 -161.32829)
			(xy 296.864187 -161.287101) (xy 296.905374 -161.25141) (xy 296.951221 -161.221944) (xy 297.000795 -161.199302)
			(xy 297.053086 -161.183946) (xy 297.10703 -161.176187) (xy 297.13428 -161.1757) (xy 297.99788 -161.1757)
			(xy 298.025134 -161.176146) (xy 298.079089 -161.183901) (xy 298.13139 -161.199255) (xy 298.180974 -161.221897)
			(xy 298.22683 -161.251365) (xy 298.268026 -161.28706) (xy 298.303723 -161.328254) (xy 298.333193 -161.374109)
			(xy 298.355838 -161.423691) (xy 298.371195 -161.475992) (xy 298.378953 -161.529946) (xy 298.378953 -161.584454)
			(xy 298.371195 -161.638408) (xy 298.355838 -161.690709) (xy 298.333193 -161.740291) (xy 298.303723 -161.786146)
			(xy 298.268026 -161.82734) (xy 298.22683 -161.863035) (xy 298.180974 -161.892503) (xy 298.13139 -161.915145)
			(xy 298.079089 -161.930499) (xy 298.025134 -161.938254) (xy 297.99788 -161.938716) (xy 297.13428 -161.938716)
			(xy 297.10703 -161.938213) (xy 297.053086 -161.930454) (xy 297.000795 -161.915098) (xy 296.951221 -161.892456)
			(xy 296.905374 -161.86299) (xy 296.864187 -161.827299) (xy 296.828498 -161.78611) (xy 296.799035 -161.740262)
			(xy 296.776395 -161.690687) (xy 296.761042 -161.638395) (xy 296.753286 -161.58445) (xy 2.509012 -161.58445)
			(xy 2.509012 -162.128053) (xy 292.574946 -162.128053) (xy 292.574946 -162.073547) (xy 292.582702 -162.019597)
			(xy 292.598058 -161.967299) (xy 292.620699 -161.917719) (xy 292.650166 -161.871866) (xy 292.685859 -161.830673)
			(xy 292.72705 -161.794978) (xy 292.772902 -161.765509) (xy 292.822481 -161.742865) (xy 292.874777 -161.727507)
			(xy 292.928727 -161.719747) (xy 292.95598 -161.71926) (xy 293.81958 -161.71926) (xy 293.846832 -161.719786)
			(xy 293.90078 -161.72754) (xy 293.953076 -161.742893) (xy 294.002654 -161.765532) (xy 294.048506 -161.794997)
			(xy 294.089698 -161.830688) (xy 294.125391 -161.871878) (xy 294.154858 -161.917728) (xy 294.1775 -161.967305)
			(xy 294.192856 -162.0196) (xy 294.200613 -162.073549) (xy 294.200613 -162.128051) (xy 294.192856 -162.182)
			(xy 294.1775 -162.234295) (xy 294.154858 -162.283872) (xy 294.125391 -162.329722) (xy 294.089698 -162.370912)
			(xy 294.048506 -162.406603) (xy 294.002654 -162.436068) (xy 293.953076 -162.458707) (xy 293.90078 -162.47406)
			(xy 293.846832 -162.481814) (xy 293.81958 -162.482276) (xy 292.95598 -162.482276) (xy 292.928727 -162.481853)
			(xy 292.874777 -162.474093) (xy 292.822481 -162.458735) (xy 292.772902 -162.436091) (xy 292.72705 -162.406622)
			(xy 292.685859 -162.370927) (xy 292.650166 -162.329734) (xy 292.620699 -162.283881) (xy 292.598058 -162.234301)
			(xy 292.582702 -162.182003) (xy 292.574946 -162.128053) (xy 2.509012 -162.128053) (xy 2.509012 -163.123651)
			(xy 294.731403 -163.123651) (xy 294.731403 -163.069149) (xy 294.73916 -163.015201) (xy 294.754516 -162.962907)
			(xy 294.777159 -162.91333) (xy 294.806627 -162.867481) (xy 294.842321 -162.826292) (xy 294.883513 -162.790603)
			(xy 294.929365 -162.76114) (xy 294.978944 -162.738502) (xy 295.03124 -162.723152) (xy 295.085189 -162.7154)
			(xy 295.11244 -162.71494) (xy 295.97604 -162.71494) (xy 296.003293 -162.715333) (xy 296.057243 -162.723095)
			(xy 296.10954 -162.738455) (xy 296.159118 -162.761102) (xy 296.204969 -162.790573) (xy 296.24616 -162.826269)
			(xy 296.281851 -162.867463) (xy 296.311318 -162.913317) (xy 296.333959 -162.962898) (xy 296.349314 -163.015196)
			(xy 296.35707 -163.069147) (xy 296.35707 -163.110951) (xy 300.192403 -163.110951) (xy 300.192403 -163.056449)
			(xy 300.20016 -163.002501) (xy 300.215516 -162.950207) (xy 300.238159 -162.90063) (xy 300.267627 -162.854781)
			(xy 300.303321 -162.813592) (xy 300.344513 -162.777903) (xy 300.390365 -162.74844) (xy 300.439944 -162.725802)
			(xy 300.49224 -162.710452) (xy 300.546189 -162.7027) (xy 300.57344 -162.70224) (xy 301.43704 -162.70224)
			(xy 301.464293 -162.702633) (xy 301.518243 -162.710395) (xy 301.57054 -162.725755) (xy 301.620118 -162.748402)
			(xy 301.665969 -162.777873) (xy 301.70716 -162.813569) (xy 301.742851 -162.854763) (xy 301.772318 -162.900617)
			(xy 301.794959 -162.950198) (xy 301.810314 -163.002496) (xy 301.81807 -163.056447) (xy 301.81807 -163.110953)
			(xy 301.810314 -163.164904) (xy 301.794959 -163.217202) (xy 301.772318 -163.266783) (xy 301.742851 -163.312637)
			(xy 301.70716 -163.353831) (xy 301.665969 -163.389527) (xy 301.620118 -163.418998) (xy 301.57054 -163.441645)
			(xy 301.518243 -163.457005) (xy 301.464293 -163.464767) (xy 301.43704 -163.465256) (xy 300.57344 -163.465256)
			(xy 300.546189 -163.4647) (xy 300.49224 -163.456948) (xy 300.439944 -163.441598) (xy 300.390365 -163.41896)
			(xy 300.344513 -163.389497) (xy 300.303321 -163.353808) (xy 300.267627 -163.312619) (xy 300.238159 -163.26677)
			(xy 300.215516 -163.217193) (xy 300.20016 -163.164899) (xy 300.192403 -163.110951) (xy 296.35707 -163.110951)
			(xy 296.35707 -163.123653) (xy 296.349314 -163.177604) (xy 296.333959 -163.229902) (xy 296.311318 -163.279483)
			(xy 296.281851 -163.325337) (xy 296.24616 -163.366531) (xy 296.204969 -163.402227) (xy 296.159118 -163.431698)
			(xy 296.10954 -163.454345) (xy 296.057243 -163.469705) (xy 296.003293 -163.477467) (xy 295.97604 -163.477956)
			(xy 295.11244 -163.477956) (xy 295.085189 -163.4774) (xy 295.03124 -163.469648) (xy 294.978944 -163.454298)
			(xy 294.929365 -163.43166) (xy 294.883513 -163.402197) (xy 294.842321 -163.366508) (xy 294.806627 -163.325319)
			(xy 294.777159 -163.27947) (xy 294.754516 -163.229893) (xy 294.73916 -163.177599) (xy 294.731403 -163.123651)
			(xy 2.509012 -163.123651) (xy 2.509012 -167.565832) (xy 348.657164 -167.565832) (xy 348.657658 -167.532531)
			(xy 348.666337 -167.466499) (xy 348.683566 -167.402165) (xy 348.709048 -167.340632) (xy 348.742347 -167.282953)
			(xy 348.782893 -167.230117) (xy 348.829992 -167.183027) (xy 348.882836 -167.142492) (xy 348.911418 -167.125396)
			(xy 349.83547 -166.591742) (xy 349.864533 -166.575642) (xy 349.925937 -166.550271) (xy 349.990123 -166.533114)
			(xy 350.055996 -166.524463) (xy 350.089216 -166.523924) (xy 350.089724 -166.523924) (xy 350.120458 -166.524315)
			(xy 350.181477 -166.531727) (xy 350.241158 -166.54644) (xy 350.29863 -166.56824) (xy 350.353056 -166.596808)
			(xy 350.403641 -166.631729) (xy 350.449648 -166.672492) (xy 350.490406 -166.718503) (xy 350.525321 -166.769092)
			(xy 350.553883 -166.823521) (xy 350.57377 -166.875968) (xy 369.614196 -166.875968) (xy 369.614752 -166.84267)
			(xy 369.623426 -166.776641) (xy 369.640648 -166.71231) (xy 369.666122 -166.650779) (xy 369.699412 -166.593101)
			(xy 369.739949 -166.540263) (xy 369.787038 -166.493171) (xy 369.839873 -166.452631) (xy 369.86845 -166.435532)
			(xy 370.792502 -165.901878) (xy 370.82156 -165.885769) (xy 370.882966 -165.8604) (xy 370.947153 -165.843245)
			(xy 371.013028 -165.834597) (xy 371.046248 -165.83406) (xy 371.046756 -165.83406) (xy 371.077486 -165.834579)
			(xy 371.138498 -165.841982) (xy 371.198173 -165.856685) (xy 371.255641 -165.878475) (xy 371.310063 -165.907032)
			(xy 371.360647 -165.941941) (xy 371.406653 -165.982693) (xy 371.447412 -166.028694) (xy 371.482329 -166.079272)
			(xy 371.510894 -166.133689) (xy 371.532692 -166.191154) (xy 371.547404 -166.250827) (xy 371.554816 -166.311838)
			(xy 371.555264 -166.342568) (xy 371.554757 -166.375868) (xy 371.546077 -166.4419) (xy 371.52885 -166.506232)
			(xy 371.503369 -166.567765) (xy 371.470072 -166.625443) (xy 371.429528 -166.67828) (xy 371.382432 -166.72537)
			(xy 371.329591 -166.765907) (xy 371.30101 -166.783004) (xy 370.964111 -166.977568) (xy 373.398796 -166.977568)
			(xy 373.399226 -166.946836) (xy 373.406638 -166.885821) (xy 373.421351 -166.826144) (xy 373.443149 -166.768676)
			(xy 373.471715 -166.714254) (xy 373.506633 -166.663671) (xy 373.547392 -166.617667) (xy 373.5934 -166.57691)
			(xy 373.643984 -166.541996) (xy 373.698409 -166.513434) (xy 373.755879 -166.49164) (xy 373.815556 -166.476932)
			(xy 373.876572 -166.469524) (xy 373.907304 -166.46906) (xy 373.907812 -166.46906) (xy 373.941031 -166.469606)
			(xy 374.006903 -166.478264) (xy 374.071088 -166.495419) (xy 374.132496 -166.520778) (xy 374.161558 -166.536878)
			(xy 375.08561 -167.070532) (xy 375.114171 -167.087654) (xy 375.166997 -167.128201) (xy 375.214079 -167.175295)
			(xy 375.254613 -167.22813) (xy 375.287906 -167.285802) (xy 375.313388 -167.347326) (xy 375.330623 -167.411649)
			(xy 375.339318 -167.477672) (xy 375.339864 -167.510968) (xy 375.339432 -167.541701) (xy 375.332026 -167.60272)
			(xy 375.317319 -167.6624) (xy 375.295524 -167.719873) (xy 375.266961 -167.774299) (xy 375.232044 -167.824885)
			(xy 375.191284 -167.870893) (xy 375.145275 -167.911651) (xy 375.094689 -167.946567) (xy 375.040262 -167.975129)
			(xy 374.982789 -167.996923) (xy 374.923108 -168.011629) (xy 374.862089 -168.019033) (xy 374.831356 -168.019476)
			(xy 374.830848 -168.019476) (xy 374.797629 -168.018942) (xy 374.731757 -168.01028) (xy 374.667571 -167.993122)
			(xy 374.606164 -167.967759) (xy 374.577102 -167.951658) (xy 373.65305 -167.418004) (xy 373.624495 -167.400872)
			(xy 373.571672 -167.360325) (xy 373.524591 -167.313232) (xy 373.484057 -167.260398) (xy 373.450764 -167.202727)
			(xy 373.42528 -167.141205) (xy 373.408042 -167.076884) (xy 373.399344 -167.010863) (xy 373.398796 -166.977568)
			(xy 370.964111 -166.977568) (xy 370.376958 -167.316658) (xy 370.34791 -167.332786) (xy 370.2865 -167.35815)
			(xy 370.22231 -167.375299) (xy 370.156433 -167.383942) (xy 370.123212 -167.384476) (xy 370.122704 -167.384476)
			(xy 370.091971 -167.384059) (xy 370.030952 -167.37665) (xy 369.971272 -167.36194) (xy 369.9138 -167.340143)
			(xy 369.859375 -167.311577) (xy 369.808789 -167.276659) (xy 369.762782 -167.235898) (xy 369.722023 -167.189889)
			(xy 369.687108 -167.139301) (xy 369.658546 -167.084874) (xy 369.636752 -167.027401) (xy 369.622045 -166.96772)
			(xy 369.61464 -166.906701) (xy 369.614196 -166.875968) (xy 350.57377 -166.875968) (xy 350.575676 -166.880996)
			(xy 350.590383 -166.940678) (xy 350.597788 -167.001698) (xy 350.598232 -167.032432) (xy 350.597712 -167.065732)
			(xy 350.589036 -167.131763) (xy 350.571812 -167.196097) (xy 350.546334 -167.25763) (xy 350.513038 -167.315309)
			(xy 350.472496 -167.368145) (xy 350.4254 -167.415235) (xy 350.372559 -167.455772) (xy 350.343978 -167.472868)
			(xy 349.419926 -168.006522) (xy 349.390862 -168.02262) (xy 349.329459 -168.047992) (xy 349.265273 -168.06515)
			(xy 349.1994 -168.073802) (xy 349.16618 -168.07434) (xy 349.165672 -168.07434) (xy 349.134942 -168.07387)
			(xy 349.073929 -168.066459) (xy 349.014255 -168.051748) (xy 348.956789 -168.029953) (xy 348.902369 -168.001389)
			(xy 348.851788 -167.966475) (xy 348.805784 -167.925719) (xy 348.765027 -167.879715) (xy 348.730113 -167.829135)
			(xy 348.701549 -167.774715) (xy 348.679753 -167.717249) (xy 348.665041 -167.657575) (xy 348.65763 -167.596562)
			(xy 348.657164 -167.565832) (xy 2.509012 -167.565832) (xy 2.509012 -168.302432) (xy 352.441764 -168.302432)
			(xy 352.442268 -168.271702) (xy 352.449672 -168.210689) (xy 352.464377 -168.151013) (xy 352.486168 -168.093545)
			(xy 352.514727 -168.039122) (xy 352.549637 -167.988539) (xy 352.59039 -167.942533) (xy 352.636392 -167.901774)
			(xy 352.686971 -167.866858) (xy 352.74139 -167.838292) (xy 352.798856 -167.816495) (xy 352.85853 -167.801783)
			(xy 352.919542 -167.794371) (xy 352.950272 -167.793924) (xy 352.95078 -167.793924) (xy 352.983998 -167.794489)
			(xy 353.049869 -167.803142) (xy 353.114055 -167.820291) (xy 353.175463 -167.845645) (xy 353.204526 -167.861742)
			(xy 354.128578 -168.395396) (xy 354.157139 -168.412518) (xy 354.209962 -168.453067) (xy 354.257042 -168.500162)
			(xy 354.297574 -168.552998) (xy 354.330866 -168.61067) (xy 354.356349 -168.672193) (xy 354.373586 -168.736515)
			(xy 354.382284 -168.802536) (xy 354.382832 -168.835832) (xy 354.382374 -168.866563) (xy 354.374962 -168.927576)
			(xy 354.360251 -168.987251) (xy 354.338454 -169.044717) (xy 354.30989 -169.099138) (xy 354.274975 -169.149719)
			(xy 354.234218 -169.195723) (xy 354.188213 -169.23648) (xy 354.137631 -169.271394) (xy 354.08321 -169.299957)
			(xy 354.025743 -169.321753) (xy 353.966068 -169.336464) (xy 353.905055 -169.343875) (xy 353.874324 -169.34434)
			(xy 353.873816 -169.34434) (xy 353.840597 -169.343782) (xy 353.774726 -169.335127) (xy 353.710541 -169.317976)
			(xy 353.649132 -169.292621) (xy 353.62007 -169.276522) (xy 352.696018 -168.742868) (xy 352.667463 -168.725735)
			(xy 352.614637 -168.685191) (xy 352.567553 -168.638099) (xy 352.527018 -168.585266) (xy 352.493724 -168.527595)
			(xy 352.468241 -168.466072) (xy 352.451005 -168.40175) (xy 352.44231 -168.335728) (xy 352.441764 -168.302432)
			(xy 2.509012 -168.302432) (xy 2.509012 -170.613832) (xy 348.657164 -170.613832) (xy 348.657658 -170.580531)
			(xy 348.666337 -170.514499) (xy 348.683566 -170.450165) (xy 348.709048 -170.388632) (xy 348.742347 -170.330953)
			(xy 348.782893 -170.278117) (xy 348.829992 -170.231027) (xy 348.882836 -170.190492) (xy 348.911418 -170.173396)
			(xy 349.83547 -169.639742) (xy 349.864533 -169.623642) (xy 349.925937 -169.598271) (xy 349.990123 -169.581114)
			(xy 350.055996 -169.572463) (xy 350.089216 -169.571924) (xy 350.089724 -169.571924) (xy 350.120458 -169.572315)
			(xy 350.181477 -169.579727) (xy 350.241158 -169.59444) (xy 350.29863 -169.61624) (xy 350.353056 -169.644808)
			(xy 350.403641 -169.679729) (xy 350.449648 -169.720492) (xy 350.490406 -169.766503) (xy 350.525321 -169.817092)
			(xy 350.553883 -169.871521) (xy 350.57377 -169.923968) (xy 369.614196 -169.923968) (xy 369.614752 -169.89067)
			(xy 369.623426 -169.824641) (xy 369.640648 -169.76031) (xy 369.666122 -169.698779) (xy 369.699412 -169.641101)
			(xy 369.739949 -169.588263) (xy 369.787038 -169.541171) (xy 369.839873 -169.500631) (xy 369.86845 -169.483532)
			(xy 370.792502 -168.949878) (xy 370.82156 -168.933769) (xy 370.882966 -168.9084) (xy 370.947153 -168.891245)
			(xy 371.013028 -168.882597) (xy 371.046248 -168.88206) (xy 371.046756 -168.88206) (xy 371.077486 -168.882579)
			(xy 371.138498 -168.889982) (xy 371.198173 -168.904685) (xy 371.255641 -168.926475) (xy 371.310063 -168.955032)
			(xy 371.360647 -168.989941) (xy 371.406653 -169.030693) (xy 371.447412 -169.076694) (xy 371.482329 -169.127272)
			(xy 371.510894 -169.181689) (xy 371.532692 -169.239154) (xy 371.547404 -169.298827) (xy 371.554816 -169.359838)
			(xy 371.555264 -169.390568) (xy 371.554757 -169.423868) (xy 371.546077 -169.4899) (xy 371.52885 -169.554232)
			(xy 371.503369 -169.615765) (xy 371.470072 -169.673443) (xy 371.429528 -169.72628) (xy 371.382432 -169.77337)
			(xy 371.329591 -169.813907) (xy 371.30101 -169.831004) (xy 370.376958 -170.364658) (xy 370.34791 -170.380786)
			(xy 370.2865 -170.40615) (xy 370.22231 -170.423299) (xy 370.156433 -170.431942) (xy 370.123212 -170.432476)
			(xy 370.122704 -170.432476) (xy 370.091971 -170.432059) (xy 370.030952 -170.42465) (xy 369.971272 -170.40994)
			(xy 369.9138 -170.388143) (xy 369.859375 -170.359577) (xy 369.808789 -170.324659) (xy 369.762782 -170.283898)
			(xy 369.722023 -170.237889) (xy 369.687108 -170.187301) (xy 369.658546 -170.132874) (xy 369.636752 -170.075401)
			(xy 369.622045 -170.01572) (xy 369.61464 -169.954701) (xy 369.614196 -169.923968) (xy 350.57377 -169.923968)
			(xy 350.575676 -169.928996) (xy 350.590383 -169.988678) (xy 350.597788 -170.049698) (xy 350.598232 -170.080432)
			(xy 350.597712 -170.113732) (xy 350.589036 -170.179763) (xy 350.571812 -170.244097) (xy 350.546334 -170.30563)
			(xy 350.513038 -170.363309) (xy 350.472496 -170.416145) (xy 350.4254 -170.463235) (xy 350.372559 -170.503772)
			(xy 350.343978 -170.520868) (xy 350.10208 -170.660568) (xy 373.398796 -170.660568) (xy 373.399226 -170.629836)
			(xy 373.406638 -170.568821) (xy 373.421351 -170.509144) (xy 373.443149 -170.451676) (xy 373.471715 -170.397254)
			(xy 373.506633 -170.346671) (xy 373.547392 -170.300667) (xy 373.5934 -170.25991) (xy 373.643984 -170.224996)
			(xy 373.698409 -170.196434) (xy 373.755879 -170.17464) (xy 373.815556 -170.159932) (xy 373.876572 -170.152524)
			(xy 373.907304 -170.15206) (xy 373.907812 -170.15206) (xy 373.941031 -170.152606) (xy 374.006903 -170.161264)
			(xy 374.071088 -170.178419) (xy 374.132496 -170.203778) (xy 374.161558 -170.219878) (xy 375.08561 -170.753532)
			(xy 375.114171 -170.770654) (xy 375.166997 -170.811201) (xy 375.214079 -170.858295) (xy 375.254613 -170.91113)
			(xy 375.287906 -170.968802) (xy 375.313388 -171.030326) (xy 375.330623 -171.094649) (xy 375.339318 -171.160672)
			(xy 375.339864 -171.193968) (xy 375.339432 -171.224701) (xy 375.332026 -171.28572) (xy 375.317319 -171.3454)
			(xy 375.295524 -171.402873) (xy 375.266961 -171.457299) (xy 375.232044 -171.507885) (xy 375.191284 -171.553893)
			(xy 375.145275 -171.594651) (xy 375.094689 -171.629567) (xy 375.040262 -171.658129) (xy 374.982789 -171.679923)
			(xy 374.923108 -171.694629) (xy 374.862089 -171.702033) (xy 374.831356 -171.702476) (xy 374.830848 -171.702476)
			(xy 374.797629 -171.701942) (xy 374.731757 -171.69328) (xy 374.667571 -171.676122) (xy 374.606164 -171.650759)
			(xy 374.577102 -171.634658) (xy 373.65305 -171.101004) (xy 373.624495 -171.083872) (xy 373.571672 -171.043325)
			(xy 373.524591 -170.996232) (xy 373.484057 -170.943398) (xy 373.450764 -170.885727) (xy 373.42528 -170.824205)
			(xy 373.408042 -170.759884) (xy 373.399344 -170.693863) (xy 373.398796 -170.660568) (xy 350.10208 -170.660568)
			(xy 349.419926 -171.054522) (xy 349.390862 -171.07062) (xy 349.329459 -171.095992) (xy 349.265273 -171.11315)
			(xy 349.1994 -171.121802) (xy 349.16618 -171.12234) (xy 349.165672 -171.12234) (xy 349.134942 -171.12187)
			(xy 349.073929 -171.114459) (xy 349.014255 -171.099748) (xy 348.956789 -171.077953) (xy 348.902369 -171.049389)
			(xy 348.851788 -171.014475) (xy 348.805784 -170.973719) (xy 348.765027 -170.927715) (xy 348.730113 -170.877135)
			(xy 348.701549 -170.822715) (xy 348.679753 -170.765249) (xy 348.665041 -170.705575) (xy 348.65763 -170.644562)
			(xy 348.657164 -170.613832) (xy 2.509012 -170.613832) (xy 2.509012 -171.985432) (xy 352.441764 -171.985432)
			(xy 352.442268 -171.954702) (xy 352.449672 -171.893689) (xy 352.464377 -171.834013) (xy 352.486168 -171.776545)
			(xy 352.514727 -171.722122) (xy 352.549637 -171.671539) (xy 352.59039 -171.625533) (xy 352.636392 -171.584774)
			(xy 352.686971 -171.549858) (xy 352.74139 -171.521292) (xy 352.798856 -171.499495) (xy 352.85853 -171.484783)
			(xy 352.919542 -171.477371) (xy 352.950272 -171.476924) (xy 352.95078 -171.476924) (xy 352.983998 -171.477489)
			(xy 353.049869 -171.486142) (xy 353.114055 -171.503291) (xy 353.175463 -171.528645) (xy 353.204526 -171.544742)
			(xy 354.128578 -172.078396) (xy 354.157139 -172.095518) (xy 354.209962 -172.136067) (xy 354.257042 -172.183162)
			(xy 354.297574 -172.235998) (xy 354.330866 -172.29367) (xy 354.356349 -172.355193) (xy 354.373586 -172.419515)
			(xy 354.382284 -172.485536) (xy 354.382832 -172.518832) (xy 354.382374 -172.549563) (xy 354.374962 -172.610576)
			(xy 354.360251 -172.670251) (xy 354.338454 -172.727717) (xy 354.30989 -172.782138) (xy 354.274975 -172.832719)
			(xy 354.234218 -172.878723) (xy 354.188213 -172.91948) (xy 354.137631 -172.954394) (xy 354.104147 -172.971968)
			(xy 369.614196 -172.971968) (xy 369.614752 -172.93867) (xy 369.623426 -172.872641) (xy 369.640648 -172.80831)
			(xy 369.666122 -172.746779) (xy 369.699412 -172.689101) (xy 369.739949 -172.636263) (xy 369.787038 -172.589171)
			(xy 369.839873 -172.548631) (xy 369.86845 -172.531532) (xy 370.792502 -171.997878) (xy 370.82156 -171.981769)
			(xy 370.882966 -171.9564) (xy 370.947153 -171.939245) (xy 371.013028 -171.930597) (xy 371.046248 -171.93006)
			(xy 371.046756 -171.93006) (xy 371.077486 -171.930579) (xy 371.138498 -171.937982) (xy 371.198173 -171.952685)
			(xy 371.255641 -171.974475) (xy 371.310063 -172.003032) (xy 371.360647 -172.037941) (xy 371.406653 -172.078693)
			(xy 371.447412 -172.124694) (xy 371.482329 -172.175272) (xy 371.510894 -172.229689) (xy 371.532692 -172.287154)
			(xy 371.547404 -172.346827) (xy 371.554816 -172.407838) (xy 371.555264 -172.438568) (xy 371.554757 -172.471868)
			(xy 371.546077 -172.5379) (xy 371.52885 -172.602232) (xy 371.503369 -172.663765) (xy 371.470072 -172.721443)
			(xy 371.429528 -172.77428) (xy 371.382432 -172.82137) (xy 371.329591 -172.861907) (xy 371.30101 -172.879004)
			(xy 370.376958 -173.412658) (xy 370.34791 -173.428786) (xy 370.2865 -173.45415) (xy 370.22231 -173.471299)
			(xy 370.156433 -173.479942) (xy 370.123212 -173.480476) (xy 370.122704 -173.480476) (xy 370.091971 -173.480059)
			(xy 370.030952 -173.47265) (xy 369.971272 -173.45794) (xy 369.9138 -173.436143) (xy 369.859375 -173.407577)
			(xy 369.808789 -173.372659) (xy 369.762782 -173.331898) (xy 369.722023 -173.285889) (xy 369.687108 -173.235301)
			(xy 369.658546 -173.180874) (xy 369.636752 -173.123401) (xy 369.622045 -173.06372) (xy 369.61464 -173.002701)
			(xy 369.614196 -172.971968) (xy 354.104147 -172.971968) (xy 354.08321 -172.982957) (xy 354.025743 -173.004753)
			(xy 353.966068 -173.019464) (xy 353.905055 -173.026875) (xy 353.874324 -173.02734) (xy 353.873816 -173.02734)
			(xy 353.840597 -173.026782) (xy 353.774726 -173.018127) (xy 353.710541 -173.000976) (xy 353.649132 -172.975621)
			(xy 353.62007 -172.959522) (xy 352.696018 -172.425868) (xy 352.667463 -172.408735) (xy 352.614637 -172.368191)
			(xy 352.567553 -172.321099) (xy 352.527018 -172.268266) (xy 352.493724 -172.210595) (xy 352.468241 -172.149072)
			(xy 352.451005 -172.08475) (xy 352.44231 -172.018728) (xy 352.441764 -171.985432) (xy 2.509012 -171.985432)
			(xy 2.509012 -173.661832) (xy 348.657164 -173.661832) (xy 348.657658 -173.628531) (xy 348.666337 -173.562499)
			(xy 348.683566 -173.498165) (xy 348.709048 -173.436632) (xy 348.742347 -173.378953) (xy 348.782893 -173.326117)
			(xy 348.829992 -173.279027) (xy 348.882836 -173.238492) (xy 348.911418 -173.221396) (xy 349.83547 -172.687742)
			(xy 349.864533 -172.671642) (xy 349.925937 -172.646271) (xy 349.990123 -172.629114) (xy 350.055996 -172.620463)
			(xy 350.089216 -172.619924) (xy 350.089724 -172.619924) (xy 350.120458 -172.620315) (xy 350.181477 -172.627727)
			(xy 350.241158 -172.64244) (xy 350.29863 -172.66424) (xy 350.353056 -172.692808) (xy 350.403641 -172.727729)
			(xy 350.449648 -172.768492) (xy 350.490406 -172.814503) (xy 350.525321 -172.865092) (xy 350.553883 -172.919521)
			(xy 350.575676 -172.976996) (xy 350.590383 -173.036678) (xy 350.597788 -173.097698) (xy 350.598232 -173.128432)
			(xy 350.597712 -173.161732) (xy 350.589036 -173.227763) (xy 350.571812 -173.292097) (xy 350.546334 -173.35363)
			(xy 350.513038 -173.411309) (xy 350.472496 -173.464145) (xy 350.4254 -173.511235) (xy 350.372559 -173.551772)
			(xy 350.343978 -173.568868) (xy 349.419926 -174.102522) (xy 349.390862 -174.11862) (xy 349.329459 -174.143992)
			(xy 349.265273 -174.16115) (xy 349.1994 -174.169802) (xy 349.16618 -174.17034) (xy 349.165672 -174.17034)
			(xy 349.134942 -174.16987) (xy 349.073929 -174.162459) (xy 349.014255 -174.147748) (xy 348.956789 -174.125953)
			(xy 348.902369 -174.097389) (xy 348.851788 -174.062475) (xy 348.805784 -174.021719) (xy 348.765027 -173.975715)
			(xy 348.730113 -173.925135) (xy 348.701549 -173.870715) (xy 348.679753 -173.813249) (xy 348.665041 -173.753575)
			(xy 348.65763 -173.692562) (xy 348.657164 -173.661832) (xy 2.509012 -173.661832) (xy 2.509012 -174.343568)
			(xy 373.398796 -174.343568) (xy 373.399226 -174.312836) (xy 373.406638 -174.251821) (xy 373.421351 -174.192144)
			(xy 373.443149 -174.134676) (xy 373.471715 -174.080254) (xy 373.506633 -174.029671) (xy 373.547392 -173.983667)
			(xy 373.5934 -173.94291) (xy 373.643984 -173.907996) (xy 373.698409 -173.879434) (xy 373.755879 -173.85764)
			(xy 373.815556 -173.842932) (xy 373.876572 -173.835524) (xy 373.907304 -173.83506) (xy 373.907812 -173.83506)
			(xy 373.941031 -173.835606) (xy 374.006903 -173.844264) (xy 374.071088 -173.861419) (xy 374.132496 -173.886778)
			(xy 374.161558 -173.902878) (xy 375.08561 -174.436532) (xy 375.114171 -174.453654) (xy 375.166997 -174.494201)
			(xy 375.214079 -174.541295) (xy 375.254613 -174.59413) (xy 375.287906 -174.651802) (xy 375.313388 -174.713326)
			(xy 375.330623 -174.777649) (xy 375.339318 -174.843672) (xy 375.339864 -174.876968) (xy 375.339432 -174.907701)
			(xy 375.332026 -174.96872) (xy 375.317319 -175.0284) (xy 375.295524 -175.085873) (xy 375.266961 -175.140299)
			(xy 375.232044 -175.190885) (xy 375.191284 -175.236893) (xy 375.145275 -175.277651) (xy 375.094689 -175.312567)
			(xy 375.040262 -175.341129) (xy 374.982789 -175.362923) (xy 374.923108 -175.377629) (xy 374.862089 -175.385033)
			(xy 374.831356 -175.385476) (xy 374.830848 -175.385476) (xy 374.797629 -175.384942) (xy 374.731757 -175.37628)
			(xy 374.667571 -175.359122) (xy 374.606164 -175.333759) (xy 374.577102 -175.317658) (xy 373.65305 -174.784004)
			(xy 373.624495 -174.766872) (xy 373.571672 -174.726325) (xy 373.524591 -174.679232) (xy 373.484057 -174.626398)
			(xy 373.450764 -174.568727) (xy 373.42528 -174.507205) (xy 373.408042 -174.442884) (xy 373.399344 -174.376863)
			(xy 373.398796 -174.343568) (xy 2.509012 -174.343568) (xy 2.509012 -175.83404) (xy 23.37714 -175.83404)
			(xy 23.381229 -175.778158) (xy 23.393412 -175.723468) (xy 23.413428 -175.671134) (xy 23.440851 -175.622272)
			(xy 23.475096 -175.577924) (xy 23.515432 -175.539034) (xy 23.561002 -175.506432) (xy 23.610833 -175.480813)
			(xy 23.663863 -175.462721) (xy 23.718961 -175.452544) (xy 23.774955 -175.450498) (xy 23.83065 -175.456626)
			(xy 23.884859 -175.470798) (xy 23.936427 -175.492712) (xy 23.984255 -175.521901) (xy 24.027323 -175.557742)
			(xy 24.064713 -175.599472) (xy 24.095629 -175.646202) (xy 24.119412 -175.696935) (xy 24.135554 -175.750591)
			(xy 24.143713 -175.806025) (xy 24.144224 -175.83404) (xy 24.143713 -175.862055) (xy 24.135554 -175.917489)
			(xy 24.119412 -175.971145) (xy 24.095629 -176.021878) (xy 24.064713 -176.068608) (xy 24.027323 -176.110338)
			(xy 23.984255 -176.146179) (xy 23.936427 -176.175368) (xy 23.884859 -176.197282) (xy 23.83065 -176.211454)
			(xy 23.774955 -176.217582) (xy 23.718961 -176.215536) (xy 23.663863 -176.205359) (xy 23.610833 -176.187267)
			(xy 23.561002 -176.161648) (xy 23.515432 -176.129046) (xy 23.475096 -176.090156) (xy 23.440851 -176.045808)
			(xy 23.413428 -175.996946) (xy 23.393412 -175.944612) (xy 23.381229 -175.889922) (xy 23.37714 -175.83404)
			(xy 2.509012 -175.83404) (xy 2.509012 -176.709832) (xy 348.657164 -176.709832) (xy 348.657658 -176.676531)
			(xy 348.666337 -176.610499) (xy 348.683566 -176.546165) (xy 348.709048 -176.484632) (xy 348.742347 -176.426953)
			(xy 348.782893 -176.374117) (xy 348.829992 -176.327027) (xy 348.882836 -176.286492) (xy 348.911418 -176.269396)
			(xy 349.83547 -175.735742) (xy 349.864533 -175.719642) (xy 349.925937 -175.694271) (xy 349.990123 -175.677114)
			(xy 350.055996 -175.668463) (xy 350.089216 -175.667924) (xy 350.089724 -175.667924) (xy 350.120458 -175.668315)
			(xy 350.121421 -175.668432) (xy 352.441764 -175.668432) (xy 352.442268 -175.637702) (xy 352.449672 -175.576689)
			(xy 352.464377 -175.517013) (xy 352.486168 -175.459545) (xy 352.514727 -175.405122) (xy 352.549637 -175.354539)
			(xy 352.59039 -175.308533) (xy 352.636392 -175.267774) (xy 352.686971 -175.232858) (xy 352.74139 -175.204292)
			(xy 352.798856 -175.182495) (xy 352.85853 -175.167783) (xy 352.919542 -175.160371) (xy 352.950272 -175.159924)
			(xy 352.95078 -175.159924) (xy 352.983998 -175.160489) (xy 353.049869 -175.169142) (xy 353.114055 -175.186291)
			(xy 353.175463 -175.211645) (xy 353.204526 -175.227742) (xy 354.128578 -175.761396) (xy 354.157139 -175.778518)
			(xy 354.209962 -175.819067) (xy 354.257042 -175.866162) (xy 354.297574 -175.918998) (xy 354.330866 -175.97667)
			(xy 354.3488 -176.019968) (xy 369.614196 -176.019968) (xy 369.614752 -175.98667) (xy 369.623426 -175.920641)
			(xy 369.640648 -175.85631) (xy 369.666122 -175.794779) (xy 369.699412 -175.737101) (xy 369.739949 -175.684263)
			(xy 369.787038 -175.637171) (xy 369.839873 -175.596631) (xy 369.86845 -175.579532) (xy 370.792502 -175.045878)
			(xy 370.82156 -175.029769) (xy 370.882966 -175.0044) (xy 370.947153 -174.987245) (xy 371.013028 -174.978597)
			(xy 371.046248 -174.97806) (xy 371.046756 -174.97806) (xy 371.077486 -174.978579) (xy 371.138498 -174.985982)
			(xy 371.198173 -175.000685) (xy 371.255641 -175.022475) (xy 371.310063 -175.051032) (xy 371.360647 -175.085941)
			(xy 371.406653 -175.126693) (xy 371.447412 -175.172694) (xy 371.482329 -175.223272) (xy 371.510894 -175.277689)
			(xy 371.532692 -175.335154) (xy 371.547404 -175.394827) (xy 371.554816 -175.455838) (xy 371.555264 -175.486568)
			(xy 371.554757 -175.519868) (xy 371.546077 -175.5859) (xy 371.543089 -175.597058) (xy 434.095902 -175.597058)
			(xy 434.099991 -175.541176) (xy 434.112174 -175.486486) (xy 434.13219 -175.434152) (xy 434.159613 -175.38529)
			(xy 434.193858 -175.340942) (xy 434.234194 -175.302052) (xy 434.279764 -175.26945) (xy 434.329595 -175.243831)
			(xy 434.382625 -175.225739) (xy 434.437723 -175.215562) (xy 434.493717 -175.213516) (xy 434.549412 -175.219644)
			(xy 434.603621 -175.233816) (xy 434.655189 -175.25573) (xy 434.703017 -175.284919) (xy 434.746085 -175.32076)
			(xy 434.783475 -175.36249) (xy 434.814391 -175.40922) (xy 434.838174 -175.459953) (xy 434.854316 -175.513609)
			(xy 434.862475 -175.569043) (xy 434.862986 -175.597058) (xy 434.862475 -175.625073) (xy 434.854316 -175.680507)
			(xy 434.838174 -175.734163) (xy 434.814391 -175.784896) (xy 434.783475 -175.831626) (xy 434.746085 -175.873356)
			(xy 434.703017 -175.909197) (xy 434.655189 -175.938386) (xy 434.603621 -175.9603) (xy 434.549412 -175.974472)
			(xy 434.493717 -175.9806) (xy 434.437723 -175.978554) (xy 434.382625 -175.968377) (xy 434.329595 -175.950285)
			(xy 434.279764 -175.924666) (xy 434.234194 -175.892064) (xy 434.193858 -175.853174) (xy 434.159613 -175.808826)
			(xy 434.13219 -175.759964) (xy 434.112174 -175.70763) (xy 434.099991 -175.65294) (xy 434.095902 -175.597058)
			(xy 371.543089 -175.597058) (xy 371.52885 -175.650232) (xy 371.503369 -175.711765) (xy 371.470072 -175.769443)
			(xy 371.429528 -175.82228) (xy 371.382432 -175.86937) (xy 371.329591 -175.909907) (xy 371.30101 -175.927004)
			(xy 370.376958 -176.460658) (xy 370.34791 -176.476786) (xy 370.2865 -176.50215) (xy 370.22231 -176.519299)
			(xy 370.156433 -176.527942) (xy 370.123212 -176.528476) (xy 370.122704 -176.528476) (xy 370.091971 -176.528059)
			(xy 370.030952 -176.52065) (xy 369.971272 -176.50594) (xy 369.9138 -176.484143) (xy 369.859375 -176.455577)
			(xy 369.808789 -176.420659) (xy 369.762782 -176.379898) (xy 369.722023 -176.333889) (xy 369.687108 -176.283301)
			(xy 369.658546 -176.228874) (xy 369.636752 -176.171401) (xy 369.622045 -176.11172) (xy 369.61464 -176.050701)
			(xy 369.614196 -176.019968) (xy 354.3488 -176.019968) (xy 354.356349 -176.038193) (xy 354.373586 -176.102515)
			(xy 354.382284 -176.168536) (xy 354.382832 -176.201832) (xy 354.382374 -176.232563) (xy 354.374962 -176.293576)
			(xy 354.360251 -176.353251) (xy 354.338454 -176.410717) (xy 354.30989 -176.465138) (xy 354.274975 -176.515719)
			(xy 354.234218 -176.561723) (xy 354.188213 -176.60248) (xy 354.137631 -176.637394) (xy 354.08321 -176.665957)
			(xy 354.025743 -176.687753) (xy 353.966068 -176.702464) (xy 353.905055 -176.709875) (xy 353.874324 -176.71034)
			(xy 353.873816 -176.71034) (xy 353.840597 -176.709782) (xy 353.774726 -176.701127) (xy 353.710541 -176.683976)
			(xy 353.649132 -176.658621) (xy 353.62007 -176.642522) (xy 352.696018 -176.108868) (xy 352.667463 -176.091735)
			(xy 352.614637 -176.051191) (xy 352.567553 -176.004099) (xy 352.527018 -175.951266) (xy 352.493724 -175.893595)
			(xy 352.468241 -175.832072) (xy 352.451005 -175.76775) (xy 352.44231 -175.701728) (xy 352.441764 -175.668432)
			(xy 350.121421 -175.668432) (xy 350.181477 -175.675727) (xy 350.241158 -175.69044) (xy 350.29863 -175.71224)
			(xy 350.353056 -175.740808) (xy 350.403641 -175.775729) (xy 350.449648 -175.816492) (xy 350.490406 -175.862503)
			(xy 350.525321 -175.913092) (xy 350.553883 -175.967521) (xy 350.575676 -176.024996) (xy 350.590383 -176.084678)
			(xy 350.597788 -176.145698) (xy 350.598232 -176.176432) (xy 350.597712 -176.209732) (xy 350.589036 -176.275763)
			(xy 350.571812 -176.340097) (xy 350.546334 -176.40163) (xy 350.513038 -176.459309) (xy 350.472496 -176.512145)
			(xy 350.4254 -176.559235) (xy 350.372559 -176.599772) (xy 350.343978 -176.616868) (xy 349.419926 -177.150522)
			(xy 349.390862 -177.16662) (xy 349.329459 -177.191992) (xy 349.265273 -177.20915) (xy 349.1994 -177.217802)
			(xy 349.16618 -177.21834) (xy 349.165672 -177.21834) (xy 349.134942 -177.21787) (xy 349.073929 -177.210459)
			(xy 349.014255 -177.195748) (xy 348.956789 -177.173953) (xy 348.902369 -177.145389) (xy 348.851788 -177.110475)
			(xy 348.805784 -177.069719) (xy 348.765027 -177.023715) (xy 348.730113 -176.973135) (xy 348.701549 -176.918715)
			(xy 348.679753 -176.861249) (xy 348.665041 -176.801575) (xy 348.65763 -176.740562) (xy 348.657164 -176.709832)
			(xy 2.509012 -176.709832) (xy 2.509012 -179.757832) (xy 348.657164 -179.757832) (xy 348.657658 -179.724531)
			(xy 348.666337 -179.658499) (xy 348.683566 -179.594165) (xy 348.709048 -179.532632) (xy 348.742347 -179.474953)
			(xy 348.782893 -179.422117) (xy 348.829992 -179.375027) (xy 348.882836 -179.334492) (xy 348.911418 -179.317396)
			(xy 349.83547 -178.783742) (xy 349.864533 -178.767642) (xy 349.925937 -178.742271) (xy 349.990123 -178.725114)
			(xy 350.055996 -178.716463) (xy 350.089216 -178.715924) (xy 350.089724 -178.715924) (xy 350.120458 -178.716315)
			(xy 350.181477 -178.723727) (xy 350.241158 -178.73844) (xy 350.29863 -178.76024) (xy 350.353056 -178.788808)
			(xy 350.403641 -178.823729) (xy 350.449648 -178.864492) (xy 350.490406 -178.910503) (xy 350.525321 -178.961092)
			(xy 350.553883 -179.015521) (xy 350.575676 -179.072996) (xy 350.590383 -179.132678) (xy 350.597788 -179.193698)
			(xy 350.598232 -179.224432) (xy 350.597712 -179.257732) (xy 350.589036 -179.323763) (xy 350.581628 -179.351432)
			(xy 352.441764 -179.351432) (xy 352.442268 -179.320702) (xy 352.449672 -179.259689) (xy 352.464377 -179.200013)
			(xy 352.486168 -179.142545) (xy 352.514727 -179.088122) (xy 352.549637 -179.037539) (xy 352.59039 -178.991533)
			(xy 352.636392 -178.950774) (xy 352.686971 -178.915858) (xy 352.74139 -178.887292) (xy 352.798856 -178.865495)
			(xy 352.85853 -178.850783) (xy 352.919542 -178.843371) (xy 352.950272 -178.842924) (xy 352.95078 -178.842924)
			(xy 352.983998 -178.843489) (xy 353.049869 -178.852142) (xy 353.114055 -178.869291) (xy 353.175463 -178.894645)
			(xy 353.204526 -178.910742) (xy 353.476772 -179.067968) (xy 369.614196 -179.067968) (xy 369.614752 -179.03467)
			(xy 369.623426 -178.968641) (xy 369.640648 -178.90431) (xy 369.666122 -178.842779) (xy 369.699412 -178.785101)
			(xy 369.739949 -178.732263) (xy 369.787038 -178.685171) (xy 369.839873 -178.644631) (xy 369.86845 -178.627532)
			(xy 370.792502 -178.093878) (xy 370.82156 -178.077769) (xy 370.882966 -178.0524) (xy 370.947153 -178.035245)
			(xy 371.013028 -178.026597) (xy 371.046248 -178.02606) (xy 371.046756 -178.02606) (xy 371.076835 -178.026568)
			(xy 373.398796 -178.026568) (xy 373.399226 -177.995836) (xy 373.406638 -177.934821) (xy 373.421351 -177.875144)
			(xy 373.443149 -177.817676) (xy 373.471715 -177.763254) (xy 373.506633 -177.712671) (xy 373.547392 -177.666667)
			(xy 373.5934 -177.62591) (xy 373.643984 -177.590996) (xy 373.698409 -177.562434) (xy 373.755879 -177.54064)
			(xy 373.815556 -177.525932) (xy 373.876572 -177.518524) (xy 373.907304 -177.51806) (xy 373.907812 -177.51806)
			(xy 373.941031 -177.518606) (xy 374.006903 -177.527264) (xy 374.071088 -177.544419) (xy 374.132496 -177.569778)
			(xy 374.161558 -177.585878) (xy 375.08561 -178.119532) (xy 375.114171 -178.136654) (xy 375.166997 -178.177201)
			(xy 375.214079 -178.224295) (xy 375.254613 -178.27713) (xy 375.287906 -178.334802) (xy 375.313388 -178.396326)
			(xy 375.330623 -178.460649) (xy 375.339318 -178.526672) (xy 375.339864 -178.559968) (xy 375.339432 -178.590701)
			(xy 375.332026 -178.65172) (xy 375.317319 -178.7114) (xy 375.295524 -178.768873) (xy 375.266961 -178.823299)
			(xy 375.232044 -178.873885) (xy 375.191284 -178.919893) (xy 375.145275 -178.960651) (xy 375.094689 -178.995567)
			(xy 375.040262 -179.024129) (xy 374.982789 -179.045923) (xy 374.923108 -179.060629) (xy 374.862089 -179.068033)
			(xy 374.831356 -179.068476) (xy 374.830848 -179.068476) (xy 374.797629 -179.067942) (xy 374.731757 -179.05928)
			(xy 374.667571 -179.042122) (xy 374.606164 -179.016759) (xy 374.577102 -179.000658) (xy 373.65305 -178.467004)
			(xy 373.624495 -178.449872) (xy 373.571672 -178.409325) (xy 373.524591 -178.362232) (xy 373.484057 -178.309398)
			(xy 373.450764 -178.251727) (xy 373.42528 -178.190205) (xy 373.408042 -178.125884) (xy 373.399344 -178.059863)
			(xy 373.398796 -178.026568) (xy 371.076835 -178.026568) (xy 371.077486 -178.026579) (xy 371.138498 -178.033982)
			(xy 371.198173 -178.048685) (xy 371.255641 -178.070475) (xy 371.310063 -178.099032) (xy 371.360647 -178.133941)
			(xy 371.406653 -178.174693) (xy 371.447412 -178.220694) (xy 371.482329 -178.271272) (xy 371.510894 -178.325689)
			(xy 371.532692 -178.383154) (xy 371.547404 -178.442827) (xy 371.554816 -178.503838) (xy 371.555264 -178.534568)
			(xy 371.554757 -178.567868) (xy 371.546077 -178.6339) (xy 371.52885 -178.698232) (xy 371.503369 -178.759765)
			(xy 371.470072 -178.817443) (xy 371.429528 -178.87028) (xy 371.382432 -178.91737) (xy 371.329591 -178.957907)
			(xy 371.30101 -178.975004) (xy 370.376958 -179.508658) (xy 370.34791 -179.524786) (xy 370.2865 -179.55015)
			(xy 370.22231 -179.567299) (xy 370.156433 -179.575942) (xy 370.123212 -179.576476) (xy 370.122704 -179.576476)
			(xy 370.091971 -179.576059) (xy 370.030952 -179.56865) (xy 369.971272 -179.55394) (xy 369.9138 -179.532143)
			(xy 369.859375 -179.503577) (xy 369.808789 -179.468659) (xy 369.762782 -179.427898) (xy 369.722023 -179.381889)
			(xy 369.687108 -179.331301) (xy 369.658546 -179.276874) (xy 369.636752 -179.219401) (xy 369.622045 -179.15972)
			(xy 369.61464 -179.098701) (xy 369.614196 -179.067968) (xy 353.476772 -179.067968) (xy 354.128578 -179.444396)
			(xy 354.157139 -179.461518) (xy 354.209962 -179.502067) (xy 354.257042 -179.549162) (xy 354.297574 -179.601998)
			(xy 354.330866 -179.65967) (xy 354.356349 -179.721193) (xy 354.373586 -179.785515) (xy 354.382284 -179.851536)
			(xy 354.382832 -179.884832) (xy 354.382374 -179.915563) (xy 354.374962 -179.976576) (xy 354.360251 -180.036251)
			(xy 354.338454 -180.093717) (xy 354.30989 -180.148138) (xy 354.274975 -180.198719) (xy 354.234218 -180.244723)
			(xy 354.188213 -180.28548) (xy 354.137631 -180.320394) (xy 354.08321 -180.348957) (xy 354.025743 -180.370753)
			(xy 353.966068 -180.385464) (xy 353.905055 -180.392875) (xy 353.874324 -180.39334) (xy 353.873816 -180.39334)
			(xy 353.840597 -180.392782) (xy 353.774726 -180.384127) (xy 353.710541 -180.366976) (xy 353.649132 -180.341621)
			(xy 353.62007 -180.325522) (xy 352.696018 -179.791868) (xy 352.667463 -179.774735) (xy 352.614637 -179.734191)
			(xy 352.567553 -179.687099) (xy 352.527018 -179.634266) (xy 352.493724 -179.576595) (xy 352.468241 -179.515072)
			(xy 352.451005 -179.45075) (xy 352.44231 -179.384728) (xy 352.441764 -179.351432) (xy 350.581628 -179.351432)
			(xy 350.571812 -179.388097) (xy 350.546334 -179.44963) (xy 350.513038 -179.507309) (xy 350.472496 -179.560145)
			(xy 350.4254 -179.607235) (xy 350.372559 -179.647772) (xy 350.343978 -179.664868) (xy 349.419926 -180.198522)
			(xy 349.390862 -180.21462) (xy 349.329459 -180.239992) (xy 349.265273 -180.25715) (xy 349.1994 -180.265802)
			(xy 349.16618 -180.26634) (xy 349.165672 -180.26634) (xy 349.134942 -180.26587) (xy 349.073929 -180.258459)
			(xy 349.014255 -180.243748) (xy 348.956789 -180.221953) (xy 348.902369 -180.193389) (xy 348.851788 -180.158475)
			(xy 348.805784 -180.117719) (xy 348.765027 -180.071715) (xy 348.730113 -180.021135) (xy 348.701549 -179.966715)
			(xy 348.679753 -179.909249) (xy 348.665041 -179.849575) (xy 348.65763 -179.788562) (xy 348.657164 -179.757832)
			(xy 2.509012 -179.757832) (xy 2.509012 -182.805832) (xy 348.657164 -182.805832) (xy 348.657658 -182.772531)
			(xy 348.666337 -182.706499) (xy 348.683566 -182.642165) (xy 348.709048 -182.580632) (xy 348.742347 -182.522953)
			(xy 348.782893 -182.470117) (xy 348.829992 -182.423027) (xy 348.882836 -182.382492) (xy 348.911418 -182.365396)
			(xy 349.83547 -181.831742) (xy 349.864533 -181.815642) (xy 349.925937 -181.790271) (xy 349.990123 -181.773114)
			(xy 350.055996 -181.764463) (xy 350.089216 -181.763924) (xy 350.089724 -181.763924) (xy 350.120458 -181.764315)
			(xy 350.181477 -181.771727) (xy 350.241158 -181.78644) (xy 350.29863 -181.80824) (xy 350.353056 -181.836808)
			(xy 350.403641 -181.871729) (xy 350.449648 -181.912492) (xy 350.490406 -181.958503) (xy 350.525321 -182.009092)
			(xy 350.553883 -182.063521) (xy 350.57377 -182.115968) (xy 369.614196 -182.115968) (xy 369.614752 -182.08267)
			(xy 369.623426 -182.016641) (xy 369.640648 -181.95231) (xy 369.666122 -181.890779) (xy 369.699412 -181.833101)
			(xy 369.739949 -181.780263) (xy 369.787038 -181.733171) (xy 369.839873 -181.692631) (xy 369.86845 -181.675532)
			(xy 370.792502 -181.141878) (xy 370.82156 -181.125769) (xy 370.882966 -181.1004) (xy 370.947153 -181.083245)
			(xy 371.013028 -181.074597) (xy 371.046248 -181.07406) (xy 371.046756 -181.07406) (xy 371.077486 -181.074579)
			(xy 371.138498 -181.081982) (xy 371.198173 -181.096685) (xy 371.255641 -181.118475) (xy 371.310063 -181.147032)
			(xy 371.360647 -181.181941) (xy 371.406653 -181.222693) (xy 371.447412 -181.268694) (xy 371.482329 -181.319272)
			(xy 371.510894 -181.373689) (xy 371.532692 -181.431154) (xy 371.547404 -181.490827) (xy 371.554816 -181.551838)
			(xy 371.555264 -181.582568) (xy 371.554757 -181.615868) (xy 371.546077 -181.6819) (xy 371.538668 -181.709568)
			(xy 373.398796 -181.709568) (xy 373.399226 -181.678836) (xy 373.406638 -181.617821) (xy 373.421351 -181.558144)
			(xy 373.443149 -181.500676) (xy 373.471715 -181.446254) (xy 373.506633 -181.395671) (xy 373.547392 -181.349667)
			(xy 373.5934 -181.30891) (xy 373.643984 -181.273996) (xy 373.698409 -181.245434) (xy 373.755879 -181.22364)
			(xy 373.815556 -181.208932) (xy 373.876572 -181.201524) (xy 373.907304 -181.20106) (xy 373.907812 -181.20106)
			(xy 373.941031 -181.201606) (xy 374.006903 -181.210264) (xy 374.071088 -181.227419) (xy 374.132496 -181.252778)
			(xy 374.161558 -181.268878) (xy 375.08561 -181.802532) (xy 375.114171 -181.819654) (xy 375.166997 -181.860201)
			(xy 375.214079 -181.907295) (xy 375.254613 -181.96013) (xy 375.287906 -182.017802) (xy 375.313388 -182.079326)
			(xy 375.330623 -182.143649) (xy 375.339318 -182.209672) (xy 375.339864 -182.242968) (xy 375.339432 -182.273701)
			(xy 375.332026 -182.33472) (xy 375.317319 -182.3944) (xy 375.295524 -182.451873) (xy 375.266961 -182.506299)
			(xy 375.232044 -182.556885) (xy 375.191284 -182.602893) (xy 375.145275 -182.643651) (xy 375.094689 -182.678567)
			(xy 375.040262 -182.707129) (xy 374.982789 -182.728923) (xy 374.923108 -182.743629) (xy 374.862089 -182.751033)
			(xy 374.831356 -182.751476) (xy 374.830848 -182.751476) (xy 374.797629 -182.750942) (xy 374.731757 -182.74228)
			(xy 374.667571 -182.725122) (xy 374.606164 -182.699759) (xy 374.577102 -182.683658) (xy 373.65305 -182.150004)
			(xy 373.624495 -182.132872) (xy 373.571672 -182.092325) (xy 373.524591 -182.045232) (xy 373.484057 -181.992398)
			(xy 373.450764 -181.934727) (xy 373.42528 -181.873205) (xy 373.408042 -181.808884) (xy 373.399344 -181.742863)
			(xy 373.398796 -181.709568) (xy 371.538668 -181.709568) (xy 371.52885 -181.746232) (xy 371.503369 -181.807765)
			(xy 371.470072 -181.865443) (xy 371.429528 -181.91828) (xy 371.382432 -181.96537) (xy 371.329591 -182.005907)
			(xy 371.30101 -182.023004) (xy 370.376958 -182.556658) (xy 370.34791 -182.572786) (xy 370.2865 -182.59815)
			(xy 370.22231 -182.615299) (xy 370.156433 -182.623942) (xy 370.123212 -182.624476) (xy 370.122704 -182.624476)
			(xy 370.091971 -182.624059) (xy 370.030952 -182.61665) (xy 369.971272 -182.60194) (xy 369.9138 -182.580143)
			(xy 369.859375 -182.551577) (xy 369.808789 -182.516659) (xy 369.762782 -182.475898) (xy 369.722023 -182.429889)
			(xy 369.687108 -182.379301) (xy 369.658546 -182.324874) (xy 369.636752 -182.267401) (xy 369.622045 -182.20772)
			(xy 369.61464 -182.146701) (xy 369.614196 -182.115968) (xy 350.57377 -182.115968) (xy 350.575676 -182.120996)
			(xy 350.590383 -182.180678) (xy 350.597788 -182.241698) (xy 350.598232 -182.272432) (xy 350.597712 -182.305732)
			(xy 350.589036 -182.371763) (xy 350.571812 -182.436097) (xy 350.546334 -182.49763) (xy 350.513038 -182.555309)
			(xy 350.472496 -182.608145) (xy 350.4254 -182.655235) (xy 350.372559 -182.695772) (xy 350.343978 -182.712868)
			(xy 349.775297 -183.04129) (xy 352.441764 -183.04129) (xy 352.442192 -183.010552) (xy 352.449601 -182.949525)
			(xy 352.46431 -182.889835) (xy 352.486105 -182.832352) (xy 352.514667 -182.777914) (xy 352.549581 -182.727315)
			(xy 352.590338 -182.681292) (xy 352.636344 -182.640516) (xy 352.686928 -182.60558) (xy 352.741353 -182.576994)
			(xy 352.798826 -182.555175) (xy 352.85851 -182.540441) (xy 352.919534 -182.533005) (xy 352.950272 -182.532528)
			(xy 352.95078 -182.532528) (xy 352.984007 -182.533118) (xy 353.049889 -182.541823) (xy 353.114077 -182.559036)
			(xy 353.175475 -182.584464) (xy 353.204526 -182.6006) (xy 354.128578 -183.134254) (xy 354.157165 -183.151335)
			(xy 354.209988 -183.19189) (xy 354.257067 -183.238991) (xy 354.297597 -183.291832) (xy 354.330886 -183.34951)
			(xy 354.356365 -183.411039) (xy 354.373597 -183.475367) (xy 354.382288 -183.541392) (xy 354.382832 -183.57469)
			(xy 354.382389 -183.605428) (xy 354.374982 -183.666455) (xy 354.360275 -183.726145) (xy 354.338483 -183.783627)
			(xy 354.309922 -183.838065) (xy 354.275009 -183.888665) (xy 354.234254 -183.934688) (xy 354.188249 -183.975465)
			(xy 354.137666 -184.010401) (xy 354.083241 -184.038987) (xy 354.025768 -184.060806) (xy 353.966085 -184.07554)
			(xy 353.905061 -184.082975) (xy 353.874324 -184.083452) (xy 353.873816 -184.083452) (xy 353.840589 -184.082867)
			(xy 353.774706 -184.07416) (xy 353.710519 -184.056946) (xy 353.649121 -184.031517) (xy 353.62007 -184.01538)
			(xy 352.696018 -183.481726) (xy 352.667489 -183.464552) (xy 352.614663 -183.424014) (xy 352.567578 -183.376928)
			(xy 352.527041 -183.324101) (xy 352.493744 -183.266436) (xy 352.468257 -183.204918) (xy 352.451015 -183.140601)
			(xy 352.442314 -183.074584) (xy 352.441764 -183.04129) (xy 349.775297 -183.04129) (xy 349.419926 -183.246522)
			(xy 349.390862 -183.26262) (xy 349.329459 -183.287992) (xy 349.265273 -183.30515) (xy 349.1994 -183.313802)
			(xy 349.16618 -183.31434) (xy 349.165672 -183.31434) (xy 349.134942 -183.31387) (xy 349.073929 -183.306459)
			(xy 349.014255 -183.291748) (xy 348.956789 -183.269953) (xy 348.902369 -183.241389) (xy 348.851788 -183.206475)
			(xy 348.805784 -183.165719) (xy 348.765027 -183.119715) (xy 348.730113 -183.069135) (xy 348.701549 -183.014715)
			(xy 348.679753 -182.957249) (xy 348.665041 -182.897575) (xy 348.65763 -182.836562) (xy 348.657164 -182.805832)
			(xy 2.509012 -182.805832) (xy 2.509012 -185.011568) (xy 372.585996 -185.011568) (xy 372.586426 -184.980836)
			(xy 372.593838 -184.919821) (xy 372.608551 -184.860144) (xy 372.630349 -184.802676) (xy 372.658915 -184.748254)
			(xy 372.693833 -184.697671) (xy 372.734592 -184.651667) (xy 372.7806 -184.61091) (xy 372.831184 -184.575996)
			(xy 372.885609 -184.547434) (xy 372.943079 -184.52564) (xy 373.002756 -184.510932) (xy 373.063772 -184.503524)
			(xy 373.094504 -184.50306) (xy 373.095012 -184.50306) (xy 373.128231 -184.503606) (xy 373.194103 -184.512264)
			(xy 373.258288 -184.529419) (xy 373.319696 -184.554778) (xy 373.348758 -184.570878) (xy 374.27281 -185.104532)
			(xy 374.301371 -185.121654) (xy 374.354197 -185.162201) (xy 374.401279 -185.209295) (xy 374.441813 -185.26213)
			(xy 374.475106 -185.319802) (xy 374.500588 -185.381326) (xy 374.517823 -185.445649) (xy 374.526518 -185.511672)
			(xy 374.527064 -185.544968) (xy 374.526632 -185.575701) (xy 374.519226 -185.63672) (xy 374.504519 -185.6964)
			(xy 374.482724 -185.753873) (xy 374.454161 -185.808299) (xy 374.419244 -185.858885) (xy 374.378484 -185.904893)
			(xy 374.332475 -185.945651) (xy 374.281889 -185.980567) (xy 374.227462 -186.009129) (xy 374.169989 -186.030923)
			(xy 374.110308 -186.045629) (xy 374.049289 -186.053033) (xy 374.018556 -186.053476) (xy 374.018048 -186.053476)
			(xy 373.984829 -186.052942) (xy 373.918957 -186.04428) (xy 373.854771 -186.027122) (xy 373.793364 -186.001759)
			(xy 373.764302 -185.985658) (xy 372.84025 -185.452004) (xy 372.811695 -185.434872) (xy 372.758872 -185.394325)
			(xy 372.711791 -185.347232) (xy 372.671257 -185.294398) (xy 372.637964 -185.236727) (xy 372.61248 -185.175205)
			(xy 372.595242 -185.110884) (xy 372.586544 -185.044863) (xy 372.585996 -185.011568) (xy 2.509012 -185.011568)
			(xy 2.509012 -186.714892) (xy 351.367344 -186.714892) (xy 351.367848 -186.684163) (xy 351.375257 -186.623152)
			(xy 351.389965 -186.563479) (xy 351.411758 -186.506014) (xy 351.440318 -186.451595) (xy 351.475229 -186.401014)
			(xy 351.515982 -186.355011) (xy 351.561983 -186.314254) (xy 351.612561 -186.279339) (xy 351.666978 -186.250774)
			(xy 351.724441 -186.228977) (xy 351.784113 -186.214264) (xy 351.845123 -186.206851) (xy 351.875852 -186.206384)
			(xy 351.87636 -186.206384) (xy 351.90958 -186.206906) (xy 351.975453 -186.215571) (xy 352.039638 -186.232732)
			(xy 352.101045 -186.258098) (xy 352.130106 -186.274202) (xy 353.054158 -186.807856) (xy 353.082741 -186.824943)
			(xy 353.135565 -186.865496) (xy 353.182645 -186.912596) (xy 353.223176 -186.965436) (xy 353.256466 -187.023114)
			(xy 353.281945 -187.084642) (xy 353.299177 -187.148969) (xy 353.307868 -187.214995) (xy 353.308412 -187.248292)
			(xy 353.307955 -187.279024) (xy 353.300547 -187.340039) (xy 353.285839 -187.399717) (xy 353.264044 -187.457187)
			(xy 353.235482 -187.51161) (xy 353.200567 -187.562194) (xy 353.15981 -187.608201) (xy 353.113804 -187.648959)
			(xy 353.063221 -187.683875) (xy 353.008798 -187.712439) (xy 352.951329 -187.734235) (xy 352.891651 -187.748945)
			(xy 352.830636 -187.756354) (xy 352.799904 -187.7568) (xy 352.799396 -187.7568) (xy 352.766177 -187.756256)
			(xy 352.700305 -187.747598) (xy 352.636119 -187.730443) (xy 352.574711 -187.705083) (xy 352.54565 -187.688982)
			(xy 351.621598 -187.155328) (xy 351.593065 -187.13816) (xy 351.54024 -187.09762) (xy 351.493156 -187.050533)
			(xy 351.45262 -186.997705) (xy 351.419323 -186.940039) (xy 351.393837 -186.878521) (xy 351.376595 -186.814204)
			(xy 351.367894 -186.748186) (xy 351.367344 -186.714892) (xy 2.509012 -186.714892) (xy 2.509012 -206.024988)
			(xy 86.700624 -206.024988) (xy 86.704605 -205.891968) (xy 86.716534 -205.759423) (xy 86.736369 -205.62783)
			(xy 86.764038 -205.497658) (xy 86.799442 -205.369373) (xy 86.842455 -205.243436) (xy 86.892922 -205.120297)
			(xy 86.950663 -205.000396) (xy 87.015472 -204.884163) (xy 87.087116 -204.772013) (xy 87.165338 -204.664349)
			(xy 87.249859 -204.561556) (xy 87.340377 -204.464001) (xy 87.436566 -204.372035) (xy 87.538084 -204.285985)
			(xy 87.644565 -204.206161) (xy 87.75563 -204.132848) (xy 87.870881 -204.066308) (xy 87.989905 -204.006779)
			(xy 88.112276 -203.954475) (xy 88.237555 -203.909583) (xy 88.365296 -203.872264) (xy 88.495039 -203.842651)
			(xy 88.626321 -203.82085) (xy 88.758672 -203.80694) (xy 88.891618 -203.800969) (xy 89.024683 -203.80296)
			(xy 89.157391 -203.812905) (xy 89.289267 -203.830769) (xy 89.419838 -203.856487) (xy 89.548638 -203.889968)
			(xy 89.675204 -203.931092) (xy 89.799085 -203.979712) (xy 89.919836 -204.035653) (xy 90.037026 -204.098715)
			(xy 90.150235 -204.168673) (xy 90.259057 -204.245277) (xy 90.363103 -204.328251) (xy 90.462001 -204.417299)
			(xy 90.555396 -204.512102) (xy 90.642954 -204.61232) (xy 90.724363 -204.717596) (xy 90.799329 -204.827552)
			(xy 90.867586 -204.941794) (xy 90.928888 -205.059914) (xy 90.983017 -205.181489) (xy 91.029778 -205.306083)
			(xy 91.069004 -205.433251) (xy 91.100554 -205.562537) (xy 91.124317 -205.693478) (xy 91.140206 -205.825606)
			(xy 91.148164 -205.958448) (xy 91.148662 -206.024988) (xy 132.710692 -206.024988) (xy 132.714673 -205.891968)
			(xy 132.726602 -205.759423) (xy 132.746437 -205.62783) (xy 132.774106 -205.497658) (xy 132.80951 -205.369373)
			(xy 132.852523 -205.243436) (xy 132.90299 -205.120297) (xy 132.960731 -205.000396) (xy 133.02554 -204.884163)
			(xy 133.097184 -204.772013) (xy 133.175406 -204.664349) (xy 133.259927 -204.561556) (xy 133.350445 -204.464001)
			(xy 133.446634 -204.372035) (xy 133.548152 -204.285985) (xy 133.654633 -204.206161) (xy 133.765698 -204.132848)
			(xy 133.880949 -204.066308) (xy 133.999973 -204.006779) (xy 134.122344 -203.954475) (xy 134.247623 -203.909583)
			(xy 134.375364 -203.872264) (xy 134.505107 -203.842651) (xy 134.636389 -203.82085) (xy 134.76874 -203.80694)
			(xy 134.901686 -203.800969) (xy 135.034751 -203.80296) (xy 135.167459 -203.812905) (xy 135.299335 -203.830769)
			(xy 135.429906 -203.856487) (xy 135.558706 -203.889968) (xy 135.685272 -203.931092) (xy 135.809153 -203.979712)
			(xy 135.929904 -204.035653) (xy 136.047094 -204.098715) (xy 136.160303 -204.168673) (xy 136.269125 -204.245277)
			(xy 136.373171 -204.328251) (xy 136.472069 -204.417299) (xy 136.565464 -204.512102) (xy 136.653022 -204.61232)
			(xy 136.734431 -204.717596) (xy 136.809397 -204.827552) (xy 136.877654 -204.941794) (xy 136.938956 -205.059914)
			(xy 136.993085 -205.181489) (xy 137.039846 -205.306083) (xy 137.079072 -205.433251) (xy 137.110622 -205.562537)
			(xy 137.134385 -205.693478) (xy 137.150274 -205.825606) (xy 137.158232 -205.958448) (xy 137.15873 -206.024988)
			(xy 334.640692 -206.024988) (xy 334.644673 -205.891968) (xy 334.656602 -205.759423) (xy 334.676437 -205.62783)
			(xy 334.704106 -205.497658) (xy 334.73951 -205.369373) (xy 334.782523 -205.243436) (xy 334.83299 -205.120297)
			(xy 334.890731 -205.000396) (xy 334.95554 -204.884163) (xy 335.027184 -204.772013) (xy 335.105406 -204.664349)
			(xy 335.189927 -204.561556) (xy 335.280445 -204.464001) (xy 335.376634 -204.372035) (xy 335.478152 -204.285985)
			(xy 335.584633 -204.206161) (xy 335.695698 -204.132848) (xy 335.810949 -204.066308) (xy 335.929973 -204.006779)
			(xy 336.052344 -203.954475) (xy 336.177623 -203.909583) (xy 336.305364 -203.872264) (xy 336.435107 -203.842651)
			(xy 336.566389 -203.82085) (xy 336.69874 -203.80694) (xy 336.831686 -203.800969) (xy 336.964751 -203.80296)
			(xy 337.097459 -203.812905) (xy 337.229335 -203.830769) (xy 337.359906 -203.856487) (xy 337.488706 -203.889968)
			(xy 337.615272 -203.931092) (xy 337.739153 -203.979712) (xy 337.859904 -204.035653) (xy 337.977094 -204.098715)
			(xy 338.090303 -204.168673) (xy 338.199125 -204.245277) (xy 338.303171 -204.328251) (xy 338.402069 -204.417299)
			(xy 338.495464 -204.512102) (xy 338.583022 -204.61232) (xy 338.664431 -204.717596) (xy 338.739397 -204.827552)
			(xy 338.807654 -204.941794) (xy 338.868956 -205.059914) (xy 338.923085 -205.181489) (xy 338.969846 -205.306083)
			(xy 339.009072 -205.433251) (xy 339.040622 -205.562537) (xy 339.064385 -205.693478) (xy 339.080274 -205.825606)
			(xy 339.088232 -205.958448) (xy 339.08873 -206.024988) (xy 380.650506 -206.024988) (xy 380.654487 -205.891968)
			(xy 380.666416 -205.759423) (xy 380.686251 -205.62783) (xy 380.71392 -205.497658) (xy 380.749324 -205.369373)
			(xy 380.792337 -205.243436) (xy 380.842804 -205.120297) (xy 380.900545 -205.000396) (xy 380.965354 -204.884163)
			(xy 381.036998 -204.772013) (xy 381.11522 -204.664349) (xy 381.199741 -204.561556) (xy 381.290259 -204.464001)
			(xy 381.386448 -204.372035) (xy 381.487966 -204.285985) (xy 381.594447 -204.206161) (xy 381.705512 -204.132848)
			(xy 381.820763 -204.066308) (xy 381.939787 -204.006779) (xy 382.062158 -203.954475) (xy 382.187437 -203.909583)
			(xy 382.315178 -203.872264) (xy 382.444921 -203.842651) (xy 382.576203 -203.82085) (xy 382.708554 -203.80694)
			(xy 382.8415 -203.800969) (xy 382.974565 -203.80296) (xy 383.107273 -203.812905) (xy 383.239149 -203.830769)
			(xy 383.36972 -203.856487) (xy 383.49852 -203.889968) (xy 383.625086 -203.931092) (xy 383.748967 -203.979712)
			(xy 383.869718 -204.035653) (xy 383.986908 -204.098715) (xy 384.100117 -204.168673) (xy 384.208939 -204.245277)
			(xy 384.312985 -204.328251) (xy 384.411883 -204.417299) (xy 384.505278 -204.512102) (xy 384.592836 -204.61232)
			(xy 384.674245 -204.717596) (xy 384.749211 -204.827552) (xy 384.817468 -204.941794) (xy 384.87877 -205.059914)
			(xy 384.932899 -205.181489) (xy 384.97966 -205.306083) (xy 385.018886 -205.433251) (xy 385.050436 -205.562537)
			(xy 385.074199 -205.693478) (xy 385.090088 -205.825606) (xy 385.098046 -205.958448) (xy 385.098544 -206.024988)
			(xy 385.098046 -206.091528) (xy 385.090088 -206.22437) (xy 385.074199 -206.356498) (xy 385.050436 -206.487439)
			(xy 385.018886 -206.616725) (xy 384.97966 -206.743893) (xy 384.932899 -206.868487) (xy 384.87877 -206.990062)
			(xy 384.817468 -207.108182) (xy 384.749211 -207.222424) (xy 384.674245 -207.33238) (xy 384.592836 -207.437656)
			(xy 384.505278 -207.537874) (xy 384.411883 -207.632677) (xy 384.312985 -207.721725) (xy 384.208939 -207.804699)
			(xy 384.100117 -207.881303) (xy 383.986908 -207.951261) (xy 383.869718 -208.014323) (xy 383.748967 -208.070264)
			(xy 383.625086 -208.118884) (xy 383.49852 -208.160008) (xy 383.36972 -208.193489) (xy 383.239149 -208.219207)
			(xy 383.107273 -208.237071) (xy 382.974565 -208.247016) (xy 382.8415 -208.249007) (xy 382.708554 -208.243036)
			(xy 382.576203 -208.229126) (xy 382.444921 -208.207325) (xy 382.315178 -208.177712) (xy 382.187437 -208.140393)
			(xy 382.062158 -208.095501) (xy 381.939787 -208.043197) (xy 381.820763 -207.983668) (xy 381.705512 -207.917128)
			(xy 381.594447 -207.843815) (xy 381.487966 -207.763991) (xy 381.386448 -207.677941) (xy 381.290259 -207.585975)
			(xy 381.199741 -207.48842) (xy 381.11522 -207.385627) (xy 381.036998 -207.277963) (xy 380.965354 -207.165813)
			(xy 380.900545 -207.04958) (xy 380.842804 -206.929679) (xy 380.792337 -206.80654) (xy 380.749324 -206.680603)
			(xy 380.71392 -206.552318) (xy 380.686251 -206.422146) (xy 380.666416 -206.290553) (xy 380.654487 -206.158008)
			(xy 380.650506 -206.024988) (xy 339.08873 -206.024988) (xy 339.088232 -206.091528) (xy 339.080274 -206.22437)
			(xy 339.064385 -206.356498) (xy 339.040622 -206.487439) (xy 339.009072 -206.616725) (xy 338.969846 -206.743893)
			(xy 338.923085 -206.868487) (xy 338.868956 -206.990062) (xy 338.807654 -207.108182) (xy 338.739397 -207.222424)
			(xy 338.664431 -207.33238) (xy 338.583022 -207.437656) (xy 338.495464 -207.537874) (xy 338.402069 -207.632677)
			(xy 338.303171 -207.721725) (xy 338.199125 -207.804699) (xy 338.090303 -207.881303) (xy 337.977094 -207.951261)
			(xy 337.859904 -208.014323) (xy 337.739153 -208.070264) (xy 337.615272 -208.118884) (xy 337.488706 -208.160008)
			(xy 337.359906 -208.193489) (xy 337.229335 -208.219207) (xy 337.097459 -208.237071) (xy 336.964751 -208.247016)
			(xy 336.831686 -208.249007) (xy 336.69874 -208.243036) (xy 336.566389 -208.229126) (xy 336.435107 -208.207325)
			(xy 336.305364 -208.177712) (xy 336.177623 -208.140393) (xy 336.052344 -208.095501) (xy 335.929973 -208.043197)
			(xy 335.810949 -207.983668) (xy 335.695698 -207.917128) (xy 335.584633 -207.843815) (xy 335.478152 -207.763991)
			(xy 335.376634 -207.677941) (xy 335.280445 -207.585975) (xy 335.189927 -207.48842) (xy 335.105406 -207.385627)
			(xy 335.027184 -207.277963) (xy 334.95554 -207.165813) (xy 334.890731 -207.04958) (xy 334.83299 -206.929679)
			(xy 334.782523 -206.80654) (xy 334.73951 -206.680603) (xy 334.704106 -206.552318) (xy 334.676437 -206.422146)
			(xy 334.656602 -206.290553) (xy 334.644673 -206.158008) (xy 334.640692 -206.024988) (xy 137.15873 -206.024988)
			(xy 137.158232 -206.091528) (xy 137.150274 -206.22437) (xy 137.134385 -206.356498) (xy 137.110622 -206.487439)
			(xy 137.079072 -206.616725) (xy 137.039846 -206.743893) (xy 136.993085 -206.868487) (xy 136.938956 -206.990062)
			(xy 136.877654 -207.108182) (xy 136.809397 -207.222424) (xy 136.734431 -207.33238) (xy 136.653022 -207.437656)
			(xy 136.565464 -207.537874) (xy 136.472069 -207.632677) (xy 136.373171 -207.721725) (xy 136.269125 -207.804699)
			(xy 136.160303 -207.881303) (xy 136.047094 -207.951261) (xy 135.929904 -208.014323) (xy 135.809153 -208.070264)
			(xy 135.685272 -208.118884) (xy 135.558706 -208.160008) (xy 135.429906 -208.193489) (xy 135.299335 -208.219207)
			(xy 135.167459 -208.237071) (xy 135.034751 -208.247016) (xy 134.901686 -208.249007) (xy 134.76874 -208.243036)
			(xy 134.636389 -208.229126) (xy 134.505107 -208.207325) (xy 134.375364 -208.177712) (xy 134.247623 -208.140393)
			(xy 134.122344 -208.095501) (xy 133.999973 -208.043197) (xy 133.880949 -207.983668) (xy 133.765698 -207.917128)
			(xy 133.654633 -207.843815) (xy 133.548152 -207.763991) (xy 133.446634 -207.677941) (xy 133.350445 -207.585975)
			(xy 133.259927 -207.48842) (xy 133.175406 -207.385627) (xy 133.097184 -207.277963) (xy 133.02554 -207.165813)
			(xy 132.960731 -207.04958) (xy 132.90299 -206.929679) (xy 132.852523 -206.80654) (xy 132.80951 -206.680603)
			(xy 132.774106 -206.552318) (xy 132.746437 -206.422146) (xy 132.726602 -206.290553) (xy 132.714673 -206.158008)
			(xy 132.710692 -206.024988) (xy 91.148662 -206.024988) (xy 91.148164 -206.091528) (xy 91.140206 -206.22437)
			(xy 91.124317 -206.356498) (xy 91.100554 -206.487439) (xy 91.069004 -206.616725) (xy 91.029778 -206.743893)
			(xy 90.983017 -206.868487) (xy 90.928888 -206.990062) (xy 90.867586 -207.108182) (xy 90.799329 -207.222424)
			(xy 90.724363 -207.33238) (xy 90.642954 -207.437656) (xy 90.555396 -207.537874) (xy 90.462001 -207.632677)
			(xy 90.363103 -207.721725) (xy 90.259057 -207.804699) (xy 90.150235 -207.881303) (xy 90.037026 -207.951261)
			(xy 89.919836 -208.014323) (xy 89.799085 -208.070264) (xy 89.675204 -208.118884) (xy 89.548638 -208.160008)
			(xy 89.419838 -208.193489) (xy 89.289267 -208.219207) (xy 89.157391 -208.237071) (xy 89.024683 -208.247016)
			(xy 88.891618 -208.249007) (xy 88.758672 -208.243036) (xy 88.626321 -208.229126) (xy 88.495039 -208.207325)
			(xy 88.365296 -208.177712) (xy 88.237555 -208.140393) (xy 88.112276 -208.095501) (xy 87.989905 -208.043197)
			(xy 87.870881 -207.983668) (xy 87.75563 -207.917128) (xy 87.644565 -207.843815) (xy 87.538084 -207.763991)
			(xy 87.436566 -207.677941) (xy 87.340377 -207.585975) (xy 87.249859 -207.48842) (xy 87.165338 -207.385627)
			(xy 87.087116 -207.277963) (xy 87.015472 -207.165813) (xy 86.950663 -207.04958) (xy 86.892922 -206.929679)
			(xy 86.842455 -206.80654) (xy 86.799442 -206.680603) (xy 86.764038 -206.552318) (xy 86.736369 -206.422146)
			(xy 86.716534 -206.290553) (xy 86.704605 -206.158008) (xy 86.700624 -206.024988) (xy 2.509012 -206.024988)
			(xy 2.509012 -213.732618) (xy 90.13825 -213.732618) (xy 90.138749 -213.705931) (xy 90.146704 -213.653152)
			(xy 90.162436 -213.602149) (xy 90.185594 -213.55406) (xy 90.215661 -213.50996) (xy 90.251965 -213.470833)
			(xy 90.293695 -213.437555) (xy 90.339919 -213.410868) (xy 90.389604 -213.391368) (xy 90.441641 -213.379491)
			(xy 90.494866 -213.375502) (xy 90.548091 -213.379491) (xy 90.600128 -213.391368) (xy 90.649813 -213.410868)
			(xy 90.696037 -213.437555) (xy 90.737767 -213.470833) (xy 90.774071 -213.50996) (xy 90.804138 -213.55406)
			(xy 90.827296 -213.602149) (xy 90.843028 -213.653152) (xy 90.850983 -213.705931) (xy 90.851482 -213.732618)
			(xy 92.01785 -213.732618) (xy 92.018349 -213.705931) (xy 92.026304 -213.653152) (xy 92.042036 -213.602149)
			(xy 92.065194 -213.55406) (xy 92.095261 -213.50996) (xy 92.131565 -213.470833) (xy 92.173295 -213.437555)
			(xy 92.219519 -213.410868) (xy 92.269204 -213.391368) (xy 92.321241 -213.379491) (xy 92.374466 -213.375502)
			(xy 92.427691 -213.379491) (xy 92.479728 -213.391368) (xy 92.529413 -213.410868) (xy 92.575637 -213.437555)
			(xy 92.617367 -213.470833) (xy 92.653671 -213.50996) (xy 92.683738 -213.55406) (xy 92.706896 -213.602149)
			(xy 92.722628 -213.653152) (xy 92.730583 -213.705931) (xy 92.731082 -213.732618) (xy 93.89745 -213.732618)
			(xy 93.897949 -213.705931) (xy 93.905904 -213.653152) (xy 93.921636 -213.602149) (xy 93.944794 -213.55406)
			(xy 93.974861 -213.50996) (xy 94.011165 -213.470833) (xy 94.052895 -213.437555) (xy 94.099119 -213.410868)
			(xy 94.148804 -213.391368) (xy 94.200841 -213.379491) (xy 94.254066 -213.375502) (xy 94.307291 -213.379491)
			(xy 94.359328 -213.391368) (xy 94.409013 -213.410868) (xy 94.455237 -213.437555) (xy 94.496967 -213.470833)
			(xy 94.533271 -213.50996) (xy 94.563338 -213.55406) (xy 94.586496 -213.602149) (xy 94.602228 -213.653152)
			(xy 94.610183 -213.705931) (xy 94.610682 -213.732618) (xy 95.77705 -213.732618) (xy 95.777549 -213.705931)
			(xy 95.785504 -213.653152) (xy 95.801236 -213.602149) (xy 95.824394 -213.55406) (xy 95.854461 -213.50996)
			(xy 95.890765 -213.470833) (xy 95.932495 -213.437555) (xy 95.978719 -213.410868) (xy 96.028404 -213.391368)
			(xy 96.080441 -213.379491) (xy 96.133666 -213.375502) (xy 96.186891 -213.379491) (xy 96.238928 -213.391368)
			(xy 96.288613 -213.410868) (xy 96.334837 -213.437555) (xy 96.376567 -213.470833) (xy 96.412871 -213.50996)
			(xy 96.442938 -213.55406) (xy 96.466096 -213.602149) (xy 96.481828 -213.653152) (xy 96.489783 -213.705931)
			(xy 96.490282 -213.732618) (xy 97.65665 -213.732618) (xy 97.657149 -213.705931) (xy 97.665104 -213.653152)
			(xy 97.680836 -213.602149) (xy 97.703994 -213.55406) (xy 97.734061 -213.50996) (xy 97.770365 -213.470833)
			(xy 97.812095 -213.437555) (xy 97.858319 -213.410868) (xy 97.908004 -213.391368) (xy 97.960041 -213.379491)
			(xy 98.013266 -213.375502) (xy 98.066491 -213.379491) (xy 98.118528 -213.391368) (xy 98.168213 -213.410868)
			(xy 98.214437 -213.437555) (xy 98.256167 -213.470833) (xy 98.292471 -213.50996) (xy 98.322538 -213.55406)
			(xy 98.345696 -213.602149) (xy 98.361428 -213.653152) (xy 98.369383 -213.705931) (xy 98.369882 -213.732618)
			(xy 99.53625 -213.732618) (xy 99.536749 -213.705931) (xy 99.544704 -213.653152) (xy 99.560436 -213.602149)
			(xy 99.583594 -213.55406) (xy 99.613661 -213.50996) (xy 99.649965 -213.470833) (xy 99.691695 -213.437555)
			(xy 99.737919 -213.410868) (xy 99.787604 -213.391368) (xy 99.839641 -213.379491) (xy 99.892866 -213.375502)
			(xy 99.946091 -213.379491) (xy 99.998128 -213.391368) (xy 100.047813 -213.410868) (xy 100.094037 -213.437555)
			(xy 100.135767 -213.470833) (xy 100.172071 -213.50996) (xy 100.202138 -213.55406) (xy 100.225296 -213.602149)
			(xy 100.241028 -213.653152) (xy 100.248983 -213.705931) (xy 100.249482 -213.732618) (xy 101.41585 -213.732618)
			(xy 101.416349 -213.705931) (xy 101.424304 -213.653152) (xy 101.440036 -213.602149) (xy 101.463194 -213.55406)
			(xy 101.493261 -213.50996) (xy 101.529565 -213.470833) (xy 101.571295 -213.437555) (xy 101.617519 -213.410868)
			(xy 101.667204 -213.391368) (xy 101.719241 -213.379491) (xy 101.772466 -213.375502) (xy 101.825691 -213.379491)
			(xy 101.877728 -213.391368) (xy 101.927413 -213.410868) (xy 101.973637 -213.437555) (xy 102.015367 -213.470833)
			(xy 102.051671 -213.50996) (xy 102.081738 -213.55406) (xy 102.104896 -213.602149) (xy 102.120628 -213.653152)
			(xy 102.128583 -213.705931) (xy 102.129082 -213.732618) (xy 103.29545 -213.732618) (xy 103.295949 -213.705931)
			(xy 103.303904 -213.653152) (xy 103.319636 -213.602149) (xy 103.342794 -213.55406) (xy 103.372861 -213.50996)
			(xy 103.409165 -213.470833) (xy 103.450895 -213.437555) (xy 103.497119 -213.410868) (xy 103.546804 -213.391368)
			(xy 103.598841 -213.379491) (xy 103.652066 -213.375502) (xy 103.705291 -213.379491) (xy 103.757328 -213.391368)
			(xy 103.807013 -213.410868) (xy 103.853237 -213.437555) (xy 103.894967 -213.470833) (xy 103.931271 -213.50996)
			(xy 103.961338 -213.55406) (xy 103.984496 -213.602149) (xy 104.000228 -213.653152) (xy 104.008183 -213.705931)
			(xy 104.008682 -213.732618) (xy 105.17505 -213.732618) (xy 105.175549 -213.705931) (xy 105.183504 -213.653152)
			(xy 105.199236 -213.602149) (xy 105.222394 -213.55406) (xy 105.252461 -213.50996) (xy 105.288765 -213.470833)
			(xy 105.330495 -213.437555) (xy 105.376719 -213.410868) (xy 105.426404 -213.391368) (xy 105.478441 -213.379491)
			(xy 105.531666 -213.375502) (xy 105.584891 -213.379491) (xy 105.636928 -213.391368) (xy 105.686613 -213.410868)
			(xy 105.732837 -213.437555) (xy 105.774567 -213.470833) (xy 105.810871 -213.50996) (xy 105.840938 -213.55406)
			(xy 105.864096 -213.602149) (xy 105.879828 -213.653152) (xy 105.887783 -213.705931) (xy 105.888282 -213.732618)
			(xy 107.05465 -213.732618) (xy 107.055149 -213.705931) (xy 107.063104 -213.653152) (xy 107.078836 -213.602149)
			(xy 107.101994 -213.55406) (xy 107.132061 -213.50996) (xy 107.168365 -213.470833) (xy 107.210095 -213.437555)
			(xy 107.256319 -213.410868) (xy 107.306004 -213.391368) (xy 107.358041 -213.379491) (xy 107.411266 -213.375502)
			(xy 107.464491 -213.379491) (xy 107.516528 -213.391368) (xy 107.566213 -213.410868) (xy 107.612437 -213.437555)
			(xy 107.654167 -213.470833) (xy 107.690471 -213.50996) (xy 107.720538 -213.55406) (xy 107.743696 -213.602149)
			(xy 107.759428 -213.653152) (xy 107.767383 -213.705931) (xy 107.767882 -213.732618) (xy 114.57305 -213.732618)
			(xy 114.573549 -213.705931) (xy 114.581504 -213.653152) (xy 114.597236 -213.602149) (xy 114.620394 -213.55406)
			(xy 114.650461 -213.50996) (xy 114.686765 -213.470833) (xy 114.728495 -213.437555) (xy 114.774719 -213.410868)
			(xy 114.824404 -213.391368) (xy 114.876441 -213.379491) (xy 114.929666 -213.375502) (xy 114.982891 -213.379491)
			(xy 115.034928 -213.391368) (xy 115.084613 -213.410868) (xy 115.130837 -213.437555) (xy 115.172567 -213.470833)
			(xy 115.208871 -213.50996) (xy 115.238938 -213.55406) (xy 115.262096 -213.602149) (xy 115.277828 -213.653152)
			(xy 115.285783 -213.705931) (xy 115.286282 -213.732618) (xy 116.45265 -213.732618) (xy 116.453149 -213.705931)
			(xy 116.461104 -213.653152) (xy 116.476836 -213.602149) (xy 116.499994 -213.55406) (xy 116.530061 -213.50996)
			(xy 116.566365 -213.470833) (xy 116.608095 -213.437555) (xy 116.654319 -213.410868) (xy 116.704004 -213.391368)
			(xy 116.756041 -213.379491) (xy 116.809266 -213.375502) (xy 116.862491 -213.379491) (xy 116.914528 -213.391368)
			(xy 116.964213 -213.410868) (xy 117.010437 -213.437555) (xy 117.052167 -213.470833) (xy 117.088471 -213.50996)
			(xy 117.118538 -213.55406) (xy 117.141696 -213.602149) (xy 117.157428 -213.653152) (xy 117.165383 -213.705931)
			(xy 117.165882 -213.732618) (xy 118.33225 -213.732618) (xy 118.332749 -213.705931) (xy 118.340704 -213.653152)
			(xy 118.356436 -213.602149) (xy 118.379594 -213.55406) (xy 118.409661 -213.50996) (xy 118.445965 -213.470833)
			(xy 118.487695 -213.437555) (xy 118.533919 -213.410868) (xy 118.583604 -213.391368) (xy 118.635641 -213.379491)
			(xy 118.688866 -213.375502) (xy 118.742091 -213.379491) (xy 118.794128 -213.391368) (xy 118.843813 -213.410868)
			(xy 118.890037 -213.437555) (xy 118.931767 -213.470833) (xy 118.968071 -213.50996) (xy 118.998138 -213.55406)
			(xy 119.021296 -213.602149) (xy 119.037028 -213.653152) (xy 119.044983 -213.705931) (xy 119.045482 -213.732618)
			(xy 120.21185 -213.732618) (xy 120.212349 -213.705931) (xy 120.220304 -213.653152) (xy 120.236036 -213.602149)
			(xy 120.259194 -213.55406) (xy 120.289261 -213.50996) (xy 120.325565 -213.470833) (xy 120.367295 -213.437555)
			(xy 120.413519 -213.410868) (xy 120.463204 -213.391368) (xy 120.515241 -213.379491) (xy 120.568466 -213.375502)
			(xy 120.621691 -213.379491) (xy 120.673728 -213.391368) (xy 120.723413 -213.410868) (xy 120.769637 -213.437555)
			(xy 120.811367 -213.470833) (xy 120.847671 -213.50996) (xy 120.877738 -213.55406) (xy 120.900896 -213.602149)
			(xy 120.916628 -213.653152) (xy 120.924583 -213.705931) (xy 120.925082 -213.732618) (xy 122.09145 -213.732618)
			(xy 122.091949 -213.705931) (xy 122.099904 -213.653152) (xy 122.115636 -213.602149) (xy 122.138794 -213.55406)
			(xy 122.168861 -213.50996) (xy 122.205165 -213.470833) (xy 122.246895 -213.437555) (xy 122.293119 -213.410868)
			(xy 122.342804 -213.391368) (xy 122.394841 -213.379491) (xy 122.448066 -213.375502) (xy 122.501291 -213.379491)
			(xy 122.553328 -213.391368) (xy 122.603013 -213.410868) (xy 122.649237 -213.437555) (xy 122.690967 -213.470833)
			(xy 122.727271 -213.50996) (xy 122.757338 -213.55406) (xy 122.780496 -213.602149) (xy 122.796228 -213.653152)
			(xy 122.804183 -213.705931) (xy 122.804682 -213.732618) (xy 123.970796 -213.732618) (xy 123.971295 -213.705931)
			(xy 123.97925 -213.653152) (xy 123.994982 -213.602149) (xy 124.01814 -213.55406) (xy 124.048207 -213.50996)
			(xy 124.084511 -213.470833) (xy 124.126241 -213.437555) (xy 124.172465 -213.410868) (xy 124.22215 -213.391368)
			(xy 124.274187 -213.379491) (xy 124.327412 -213.375502) (xy 124.380637 -213.379491) (xy 124.432674 -213.391368)
			(xy 124.482359 -213.410868) (xy 124.528583 -213.437555) (xy 124.570313 -213.470833) (xy 124.606617 -213.50996)
			(xy 124.636684 -213.55406) (xy 124.659842 -213.602149) (xy 124.675574 -213.653152) (xy 124.683529 -213.705931)
			(xy 124.684028 -213.732618) (xy 125.850396 -213.732618) (xy 125.850895 -213.705931) (xy 125.85885 -213.653152)
			(xy 125.874582 -213.602149) (xy 125.89774 -213.55406) (xy 125.927807 -213.50996) (xy 125.964111 -213.470833)
			(xy 126.005841 -213.437555) (xy 126.052065 -213.410868) (xy 126.10175 -213.391368) (xy 126.153787 -213.379491)
			(xy 126.207012 -213.375502) (xy 126.260237 -213.379491) (xy 126.312274 -213.391368) (xy 126.361959 -213.410868)
			(xy 126.408183 -213.437555) (xy 126.449913 -213.470833) (xy 126.486217 -213.50996) (xy 126.516284 -213.55406)
			(xy 126.539442 -213.602149) (xy 126.555174 -213.653152) (xy 126.563129 -213.705931) (xy 126.563628 -213.732618)
			(xy 127.73025 -213.732618) (xy 127.730749 -213.705931) (xy 127.738704 -213.653152) (xy 127.754436 -213.602149)
			(xy 127.777594 -213.55406) (xy 127.807661 -213.50996) (xy 127.843965 -213.470833) (xy 127.885695 -213.437555)
			(xy 127.931919 -213.410868) (xy 127.981604 -213.391368) (xy 128.033641 -213.379491) (xy 128.086866 -213.375502)
			(xy 128.140091 -213.379491) (xy 128.192128 -213.391368) (xy 128.241813 -213.410868) (xy 128.288037 -213.437555)
			(xy 128.329767 -213.470833) (xy 128.366071 -213.50996) (xy 128.396138 -213.55406) (xy 128.419296 -213.602149)
			(xy 128.435028 -213.653152) (xy 128.442983 -213.705931) (xy 128.443482 -213.732618) (xy 129.60985 -213.732618)
			(xy 129.610349 -213.705931) (xy 129.618304 -213.653152) (xy 129.634036 -213.602149) (xy 129.657194 -213.55406)
			(xy 129.687261 -213.50996) (xy 129.723565 -213.470833) (xy 129.765295 -213.437555) (xy 129.811519 -213.410868)
			(xy 129.861204 -213.391368) (xy 129.913241 -213.379491) (xy 129.966466 -213.375502) (xy 130.019691 -213.379491)
			(xy 130.071728 -213.391368) (xy 130.121413 -213.410868) (xy 130.167637 -213.437555) (xy 130.209367 -213.470833)
			(xy 130.245671 -213.50996) (xy 130.275738 -213.55406) (xy 130.298896 -213.602149) (xy 130.314628 -213.653152)
			(xy 130.322583 -213.705931) (xy 130.323082 -213.732618) (xy 131.48945 -213.732618) (xy 131.489949 -213.705931)
			(xy 131.497904 -213.653152) (xy 131.513636 -213.602149) (xy 131.536794 -213.55406) (xy 131.566861 -213.50996)
			(xy 131.603165 -213.470833) (xy 131.644895 -213.437555) (xy 131.691119 -213.410868) (xy 131.740804 -213.391368)
			(xy 131.792841 -213.379491) (xy 131.846066 -213.375502) (xy 131.899291 -213.379491) (xy 131.951328 -213.391368)
			(xy 132.001013 -213.410868) (xy 132.047237 -213.437555) (xy 132.088967 -213.470833) (xy 132.125271 -213.50996)
			(xy 132.155338 -213.55406) (xy 132.178496 -213.602149) (xy 132.194228 -213.653152) (xy 132.202183 -213.705931)
			(xy 132.202682 -213.732618) (xy 338.078318 -213.732618) (xy 338.078817 -213.705931) (xy 338.086772 -213.653152)
			(xy 338.102504 -213.602149) (xy 338.125662 -213.55406) (xy 338.155729 -213.50996) (xy 338.192033 -213.470833)
			(xy 338.233763 -213.437555) (xy 338.279987 -213.410868) (xy 338.329672 -213.391368) (xy 338.381709 -213.379491)
			(xy 338.434934 -213.375502) (xy 338.488159 -213.379491) (xy 338.540196 -213.391368) (xy 338.589881 -213.410868)
			(xy 338.636105 -213.437555) (xy 338.677835 -213.470833) (xy 338.714139 -213.50996) (xy 338.744206 -213.55406)
			(xy 338.767364 -213.602149) (xy 338.783096 -213.653152) (xy 338.791051 -213.705931) (xy 338.79155 -213.732618)
			(xy 339.957918 -213.732618) (xy 339.958417 -213.705931) (xy 339.966372 -213.653152) (xy 339.982104 -213.602149)
			(xy 340.005262 -213.55406) (xy 340.035329 -213.50996) (xy 340.071633 -213.470833) (xy 340.113363 -213.437555)
			(xy 340.159587 -213.410868) (xy 340.209272 -213.391368) (xy 340.261309 -213.379491) (xy 340.314534 -213.375502)
			(xy 340.367759 -213.379491) (xy 340.419796 -213.391368) (xy 340.469481 -213.410868) (xy 340.515705 -213.437555)
			(xy 340.557435 -213.470833) (xy 340.593739 -213.50996) (xy 340.623806 -213.55406) (xy 340.646964 -213.602149)
			(xy 340.662696 -213.653152) (xy 340.670651 -213.705931) (xy 340.67115 -213.732618) (xy 341.837518 -213.732618)
			(xy 341.838017 -213.705931) (xy 341.845972 -213.653152) (xy 341.861704 -213.602149) (xy 341.884862 -213.55406)
			(xy 341.914929 -213.50996) (xy 341.951233 -213.470833) (xy 341.992963 -213.437555) (xy 342.039187 -213.410868)
			(xy 342.088872 -213.391368) (xy 342.140909 -213.379491) (xy 342.194134 -213.375502) (xy 342.247359 -213.379491)
			(xy 342.299396 -213.391368) (xy 342.349081 -213.410868) (xy 342.395305 -213.437555) (xy 342.437035 -213.470833)
			(xy 342.473339 -213.50996) (xy 342.503406 -213.55406) (xy 342.526564 -213.602149) (xy 342.542296 -213.653152)
			(xy 342.550251 -213.705931) (xy 342.55075 -213.732618) (xy 343.717118 -213.732618) (xy 343.717617 -213.705931)
			(xy 343.725572 -213.653152) (xy 343.741304 -213.602149) (xy 343.764462 -213.55406) (xy 343.794529 -213.50996)
			(xy 343.830833 -213.470833) (xy 343.872563 -213.437555) (xy 343.918787 -213.410868) (xy 343.968472 -213.391368)
			(xy 344.020509 -213.379491) (xy 344.073734 -213.375502) (xy 344.126959 -213.379491) (xy 344.178996 -213.391368)
			(xy 344.228681 -213.410868) (xy 344.274905 -213.437555) (xy 344.316635 -213.470833) (xy 344.352939 -213.50996)
			(xy 344.383006 -213.55406) (xy 344.406164 -213.602149) (xy 344.421896 -213.653152) (xy 344.429851 -213.705931)
			(xy 344.43035 -213.732618) (xy 345.596718 -213.732618) (xy 345.597217 -213.705931) (xy 345.605172 -213.653152)
			(xy 345.620904 -213.602149) (xy 345.644062 -213.55406) (xy 345.674129 -213.50996) (xy 345.710433 -213.470833)
			(xy 345.752163 -213.437555) (xy 345.798387 -213.410868) (xy 345.848072 -213.391368) (xy 345.900109 -213.379491)
			(xy 345.953334 -213.375502) (xy 346.006559 -213.379491) (xy 346.058596 -213.391368) (xy 346.108281 -213.410868)
			(xy 346.154505 -213.437555) (xy 346.196235 -213.470833) (xy 346.232539 -213.50996) (xy 346.262606 -213.55406)
			(xy 346.285764 -213.602149) (xy 346.301496 -213.653152) (xy 346.309451 -213.705931) (xy 346.30995 -213.732618)
			(xy 347.476318 -213.732618) (xy 347.476817 -213.705931) (xy 347.484772 -213.653152) (xy 347.500504 -213.602149)
			(xy 347.523662 -213.55406) (xy 347.553729 -213.50996) (xy 347.590033 -213.470833) (xy 347.631763 -213.437555)
			(xy 347.677987 -213.410868) (xy 347.727672 -213.391368) (xy 347.779709 -213.379491) (xy 347.832934 -213.375502)
			(xy 347.886159 -213.379491) (xy 347.938196 -213.391368) (xy 347.987881 -213.410868) (xy 348.034105 -213.437555)
			(xy 348.075835 -213.470833) (xy 348.112139 -213.50996) (xy 348.142206 -213.55406) (xy 348.165364 -213.602149)
			(xy 348.181096 -213.653152) (xy 348.189051 -213.705931) (xy 348.18955 -213.732618) (xy 349.355918 -213.732618)
			(xy 349.356417 -213.705931) (xy 349.364372 -213.653152) (xy 349.380104 -213.602149) (xy 349.403262 -213.55406)
			(xy 349.433329 -213.50996) (xy 349.469633 -213.470833) (xy 349.511363 -213.437555) (xy 349.557587 -213.410868)
			(xy 349.607272 -213.391368) (xy 349.659309 -213.379491) (xy 349.712534 -213.375502) (xy 349.765759 -213.379491)
			(xy 349.817796 -213.391368) (xy 349.867481 -213.410868) (xy 349.913705 -213.437555) (xy 349.955435 -213.470833)
			(xy 349.991739 -213.50996) (xy 350.021806 -213.55406) (xy 350.044964 -213.602149) (xy 350.060696 -213.653152)
			(xy 350.068651 -213.705931) (xy 350.06915 -213.732618) (xy 351.235518 -213.732618) (xy 351.236017 -213.705931)
			(xy 351.243972 -213.653152) (xy 351.259704 -213.602149) (xy 351.282862 -213.55406) (xy 351.312929 -213.50996)
			(xy 351.349233 -213.470833) (xy 351.390963 -213.437555) (xy 351.437187 -213.410868) (xy 351.486872 -213.391368)
			(xy 351.538909 -213.379491) (xy 351.592134 -213.375502) (xy 351.645359 -213.379491) (xy 351.697396 -213.391368)
			(xy 351.747081 -213.410868) (xy 351.793305 -213.437555) (xy 351.835035 -213.470833) (xy 351.871339 -213.50996)
			(xy 351.901406 -213.55406) (xy 351.924564 -213.602149) (xy 351.940296 -213.653152) (xy 351.948251 -213.705931)
			(xy 351.94875 -213.732618) (xy 353.115118 -213.732618) (xy 353.115617 -213.705931) (xy 353.123572 -213.653152)
			(xy 353.139304 -213.602149) (xy 353.162462 -213.55406) (xy 353.192529 -213.50996) (xy 353.228833 -213.470833)
			(xy 353.270563 -213.437555) (xy 353.316787 -213.410868) (xy 353.366472 -213.391368) (xy 353.418509 -213.379491)
			(xy 353.471734 -213.375502) (xy 353.524959 -213.379491) (xy 353.576996 -213.391368) (xy 353.626681 -213.410868)
			(xy 353.672905 -213.437555) (xy 353.714635 -213.470833) (xy 353.750939 -213.50996) (xy 353.781006 -213.55406)
			(xy 353.804164 -213.602149) (xy 353.819896 -213.653152) (xy 353.827851 -213.705931) (xy 353.82835 -213.732618)
			(xy 354.994718 -213.732618) (xy 354.995217 -213.705931) (xy 355.003172 -213.653152) (xy 355.018904 -213.602149)
			(xy 355.042062 -213.55406) (xy 355.072129 -213.50996) (xy 355.108433 -213.470833) (xy 355.150163 -213.437555)
			(xy 355.196387 -213.410868) (xy 355.246072 -213.391368) (xy 355.298109 -213.379491) (xy 355.351334 -213.375502)
			(xy 355.404559 -213.379491) (xy 355.456596 -213.391368) (xy 355.506281 -213.410868) (xy 355.552505 -213.437555)
			(xy 355.594235 -213.470833) (xy 355.630539 -213.50996) (xy 355.660606 -213.55406) (xy 355.683764 -213.602149)
			(xy 355.699496 -213.653152) (xy 355.707451 -213.705931) (xy 355.70795 -213.732618) (xy 355.70795 -213.732872)
			(xy 355.70742 -213.760689) (xy 355.698758 -213.815644) (xy 355.68167 -213.868588) (xy 355.669596 -213.893654)
			(xy 355.657658 -213.917022) (xy 355.8413 -214.26551) (xy 355.867208 -214.269066) (xy 355.89263 -214.2728)
			(xy 355.942086 -214.286744) (xy 355.989029 -214.307641) (xy 356.032487 -214.335058) (xy 356.07156 -214.368428)
			(xy 356.10544 -214.407061) (xy 356.133425 -214.450156) (xy 356.154936 -214.49682) (xy 356.169527 -214.546089)
			(xy 356.176896 -214.596942) (xy 356.177342 -214.622634) (xy 356.176843 -214.649321) (xy 356.168888 -214.7021)
			(xy 356.153156 -214.753103) (xy 356.129998 -214.801192) (xy 356.099931 -214.845292) (xy 356.063627 -214.884419)
			(xy 356.021897 -214.917697) (xy 355.975673 -214.944384) (xy 355.925988 -214.963884) (xy 355.873951 -214.975761)
			(xy 355.820726 -214.97975) (xy 355.767501 -214.975761) (xy 355.715464 -214.963884) (xy 355.665779 -214.944384)
			(xy 355.619555 -214.917697) (xy 355.577825 -214.884419) (xy 355.541521 -214.845292) (xy 355.511454 -214.801192)
			(xy 355.488296 -214.753103) (xy 355.472564 -214.7021) (xy 355.464609 -214.649321) (xy 355.46411 -214.622634)
			(xy 355.46411 -214.62238) (xy 355.464653 -214.594564) (xy 355.473309 -214.539609) (xy 355.490392 -214.486664)
			(xy 355.502464 -214.461598) (xy 355.514402 -214.43823) (xy 355.33076 -214.089742) (xy 355.304852 -214.086186)
			(xy 355.279446 -214.082354) (xy 355.229995 -214.068422) (xy 355.183055 -214.047536) (xy 355.139598 -214.02013)
			(xy 355.100525 -213.986771) (xy 355.066643 -213.948149) (xy 355.038655 -213.905065) (xy 355.01714 -213.858411)
			(xy 355.002544 -213.809151) (xy 354.995168 -213.758306) (xy 354.994718 -213.732618) (xy 353.82835 -213.732618)
			(xy 353.82835 -213.732872) (xy 353.82782 -213.760689) (xy 353.819158 -213.815644) (xy 353.80207 -213.868588)
			(xy 353.789996 -213.893654) (xy 353.778058 -213.917022) (xy 353.9617 -214.26551) (xy 353.987608 -214.269066)
			(xy 354.01303 -214.2728) (xy 354.062486 -214.286744) (xy 354.109429 -214.307641) (xy 354.152887 -214.335058)
			(xy 354.19196 -214.368428) (xy 354.22584 -214.407061) (xy 354.253825 -214.450156) (xy 354.275336 -214.49682)
			(xy 354.289927 -214.546089) (xy 354.297296 -214.596942) (xy 354.297742 -214.622634) (xy 354.297243 -214.649321)
			(xy 354.289288 -214.7021) (xy 354.273556 -214.753103) (xy 354.250398 -214.801192) (xy 354.220331 -214.845292)
			(xy 354.184027 -214.884419) (xy 354.142297 -214.917697) (xy 354.096073 -214.944384) (xy 354.046388 -214.963884)
			(xy 353.994351 -214.975761) (xy 353.941126 -214.97975) (xy 353.887901 -214.975761) (xy 353.835864 -214.963884)
			(xy 353.786179 -214.944384) (xy 353.739955 -214.917697) (xy 353.698225 -214.884419) (xy 353.661921 -214.845292)
			(xy 353.631854 -214.801192) (xy 353.608696 -214.753103) (xy 353.592964 -214.7021) (xy 353.585009 -214.649321)
			(xy 353.58451 -214.622634) (xy 353.58451 -214.62238) (xy 353.585053 -214.594564) (xy 353.593709 -214.539609)
			(xy 353.610792 -214.486664) (xy 353.622864 -214.461598) (xy 353.634802 -214.43823) (xy 353.45116 -214.089742)
			(xy 353.425252 -214.086186) (xy 353.399846 -214.082354) (xy 353.350395 -214.068422) (xy 353.303455 -214.047536)
			(xy 353.259998 -214.02013) (xy 353.220925 -213.986771) (xy 353.187043 -213.948149) (xy 353.159055 -213.905065)
			(xy 353.13754 -213.858411) (xy 353.122944 -213.809151) (xy 353.115568 -213.758306) (xy 353.115118 -213.732618)
			(xy 351.94875 -213.732618) (xy 351.94875 -213.732872) (xy 351.94822 -213.760689) (xy 351.939558 -213.815644)
			(xy 351.92247 -213.868588) (xy 351.910396 -213.893654) (xy 351.898458 -213.917022) (xy 352.0821 -214.26551)
			(xy 352.108008 -214.269066) (xy 352.13343 -214.2728) (xy 352.182886 -214.286744) (xy 352.229829 -214.307641)
			(xy 352.273287 -214.335058) (xy 352.31236 -214.368428) (xy 352.34624 -214.407061) (xy 352.374225 -214.450156)
			(xy 352.395736 -214.49682) (xy 352.410327 -214.546089) (xy 352.417696 -214.596942) (xy 352.418142 -214.622634)
			(xy 352.417643 -214.649321) (xy 352.409688 -214.7021) (xy 352.393956 -214.753103) (xy 352.370798 -214.801192)
			(xy 352.340731 -214.845292) (xy 352.304427 -214.884419) (xy 352.262697 -214.917697) (xy 352.216473 -214.944384)
			(xy 352.166788 -214.963884) (xy 352.114751 -214.975761) (xy 352.061526 -214.97975) (xy 352.008301 -214.975761)
			(xy 351.956264 -214.963884) (xy 351.906579 -214.944384) (xy 351.860355 -214.917697) (xy 351.818625 -214.884419)
			(xy 351.782321 -214.845292) (xy 351.752254 -214.801192) (xy 351.729096 -214.753103) (xy 351.713364 -214.7021)
			(xy 351.705409 -214.649321) (xy 351.70491 -214.622634) (xy 351.70491 -214.62238) (xy 351.705453 -214.594564)
			(xy 351.714109 -214.539609) (xy 351.731192 -214.486664) (xy 351.743264 -214.461598) (xy 351.755202 -214.43823)
			(xy 351.57156 -214.089742) (xy 351.545652 -214.086186) (xy 351.520246 -214.082354) (xy 351.470795 -214.068422)
			(xy 351.423855 -214.047536) (xy 351.380398 -214.02013) (xy 351.341325 -213.986771) (xy 351.307443 -213.948149)
			(xy 351.279455 -213.905065) (xy 351.25794 -213.858411) (xy 351.243344 -213.809151) (xy 351.235968 -213.758306)
			(xy 351.235518 -213.732618) (xy 350.06915 -213.732618) (xy 350.06915 -213.732872) (xy 350.06862 -213.760689)
			(xy 350.059958 -213.815644) (xy 350.04287 -213.868588) (xy 350.030796 -213.893654) (xy 350.018858 -213.917022)
			(xy 350.2025 -214.26551) (xy 350.228408 -214.269066) (xy 350.25383 -214.2728) (xy 350.303286 -214.286744)
			(xy 350.350229 -214.307641) (xy 350.393687 -214.335058) (xy 350.43276 -214.368428) (xy 350.46664 -214.407061)
			(xy 350.494625 -214.450156) (xy 350.516136 -214.49682) (xy 350.530727 -214.546089) (xy 350.538096 -214.596942)
			(xy 350.538542 -214.622634) (xy 350.538043 -214.649321) (xy 350.530088 -214.7021) (xy 350.514356 -214.753103)
			(xy 350.491198 -214.801192) (xy 350.461131 -214.845292) (xy 350.424827 -214.884419) (xy 350.383097 -214.917697)
			(xy 350.336873 -214.944384) (xy 350.287188 -214.963884) (xy 350.235151 -214.975761) (xy 350.181926 -214.97975)
			(xy 350.128701 -214.975761) (xy 350.076664 -214.963884) (xy 350.026979 -214.944384) (xy 349.980755 -214.917697)
			(xy 349.939025 -214.884419) (xy 349.902721 -214.845292) (xy 349.872654 -214.801192) (xy 349.849496 -214.753103)
			(xy 349.833764 -214.7021) (xy 349.825809 -214.649321) (xy 349.82531 -214.622634) (xy 349.82531 -214.62238)
			(xy 349.825853 -214.594564) (xy 349.834509 -214.539609) (xy 349.851592 -214.486664) (xy 349.863664 -214.461598)
			(xy 349.875602 -214.43823) (xy 349.69196 -214.089742) (xy 349.666052 -214.086186) (xy 349.640646 -214.082354)
			(xy 349.591195 -214.068422) (xy 349.544255 -214.047536) (xy 349.500798 -214.02013) (xy 349.461725 -213.986771)
			(xy 349.427843 -213.948149) (xy 349.399855 -213.905065) (xy 349.37834 -213.858411) (xy 349.363744 -213.809151)
			(xy 349.356368 -213.758306) (xy 349.355918 -213.732618) (xy 348.18955 -213.732618) (xy 348.18955 -213.732872)
			(xy 348.18902 -213.760689) (xy 348.180358 -213.815644) (xy 348.16327 -213.868588) (xy 348.151196 -213.893654)
			(xy 348.139258 -213.917022) (xy 348.3229 -214.26551) (xy 348.348808 -214.269066) (xy 348.37423 -214.2728)
			(xy 348.423686 -214.286744) (xy 348.470629 -214.307641) (xy 348.514087 -214.335058) (xy 348.55316 -214.368428)
			(xy 348.58704 -214.407061) (xy 348.615025 -214.450156) (xy 348.636536 -214.49682) (xy 348.651127 -214.546089)
			(xy 348.658496 -214.596942) (xy 348.658942 -214.622634) (xy 348.658443 -214.649321) (xy 348.650488 -214.7021)
			(xy 348.634756 -214.753103) (xy 348.611598 -214.801192) (xy 348.581531 -214.845292) (xy 348.545227 -214.884419)
			(xy 348.503497 -214.917697) (xy 348.457273 -214.944384) (xy 348.407588 -214.963884) (xy 348.355551 -214.975761)
			(xy 348.302326 -214.97975) (xy 348.249101 -214.975761) (xy 348.197064 -214.963884) (xy 348.147379 -214.944384)
			(xy 348.101155 -214.917697) (xy 348.059425 -214.884419) (xy 348.023121 -214.845292) (xy 347.993054 -214.801192)
			(xy 347.969896 -214.753103) (xy 347.954164 -214.7021) (xy 347.946209 -214.649321) (xy 347.94571 -214.622634)
			(xy 347.94571 -214.62238) (xy 347.946253 -214.594564) (xy 347.954909 -214.539609) (xy 347.971992 -214.486664)
			(xy 347.984064 -214.461598) (xy 347.996002 -214.43823) (xy 347.81236 -214.089742) (xy 347.786452 -214.086186)
			(xy 347.761046 -214.082354) (xy 347.711595 -214.068422) (xy 347.664655 -214.047536) (xy 347.621198 -214.02013)
			(xy 347.582125 -213.986771) (xy 347.548243 -213.948149) (xy 347.520255 -213.905065) (xy 347.49874 -213.858411)
			(xy 347.484144 -213.809151) (xy 347.476768 -213.758306) (xy 347.476318 -213.732618) (xy 346.30995 -213.732618)
			(xy 346.30995 -213.732872) (xy 346.30942 -213.760689) (xy 346.300758 -213.815644) (xy 346.28367 -213.868588)
			(xy 346.271596 -213.893654) (xy 346.259658 -213.917022) (xy 346.4433 -214.26551) (xy 346.469208 -214.269066)
			(xy 346.49463 -214.2728) (xy 346.544086 -214.286744) (xy 346.591029 -214.307641) (xy 346.634487 -214.335058)
			(xy 346.67356 -214.368428) (xy 346.70744 -214.407061) (xy 346.735425 -214.450156) (xy 346.756936 -214.49682)
			(xy 346.771527 -214.546089) (xy 346.778896 -214.596942) (xy 346.779342 -214.622634) (xy 346.778843 -214.649321)
			(xy 346.770888 -214.7021) (xy 346.755156 -214.753103) (xy 346.731998 -214.801192) (xy 346.701931 -214.845292)
			(xy 346.665627 -214.884419) (xy 346.623897 -214.917697) (xy 346.577673 -214.944384) (xy 346.527988 -214.963884)
			(xy 346.475951 -214.975761) (xy 346.422726 -214.97975) (xy 346.369501 -214.975761) (xy 346.317464 -214.963884)
			(xy 346.267779 -214.944384) (xy 346.221555 -214.917697) (xy 346.179825 -214.884419) (xy 346.143521 -214.845292)
			(xy 346.113454 -214.801192) (xy 346.090296 -214.753103) (xy 346.074564 -214.7021) (xy 346.066609 -214.649321)
			(xy 346.06611 -214.622634) (xy 346.06611 -214.62238) (xy 346.066653 -214.594564) (xy 346.075309 -214.539609)
			(xy 346.092392 -214.486664) (xy 346.104464 -214.461598) (xy 346.116402 -214.43823) (xy 345.93276 -214.089742)
			(xy 345.906852 -214.086186) (xy 345.881446 -214.082354) (xy 345.831995 -214.068422) (xy 345.785055 -214.047536)
			(xy 345.741598 -214.02013) (xy 345.702525 -213.986771) (xy 345.668643 -213.948149) (xy 345.640655 -213.905065)
			(xy 345.61914 -213.858411) (xy 345.604544 -213.809151) (xy 345.597168 -213.758306) (xy 345.596718 -213.732618)
			(xy 344.43035 -213.732618) (xy 344.43035 -213.732872) (xy 344.42982 -213.760689) (xy 344.421158 -213.815644)
			(xy 344.40407 -213.868588) (xy 344.391996 -213.893654) (xy 344.380058 -213.917022) (xy 344.5637 -214.26551)
			(xy 344.589608 -214.269066) (xy 344.61503 -214.2728) (xy 344.664486 -214.286744) (xy 344.711429 -214.307641)
			(xy 344.754887 -214.335058) (xy 344.79396 -214.368428) (xy 344.82784 -214.407061) (xy 344.855825 -214.450156)
			(xy 344.877336 -214.49682) (xy 344.891927 -214.546089) (xy 344.899296 -214.596942) (xy 344.899742 -214.622634)
			(xy 344.899243 -214.649321) (xy 344.891288 -214.7021) (xy 344.875556 -214.753103) (xy 344.852398 -214.801192)
			(xy 344.822331 -214.845292) (xy 344.786027 -214.884419) (xy 344.744297 -214.917697) (xy 344.698073 -214.944384)
			(xy 344.648388 -214.963884) (xy 344.596351 -214.975761) (xy 344.543126 -214.97975) (xy 344.489901 -214.975761)
			(xy 344.437864 -214.963884) (xy 344.388179 -214.944384) (xy 344.341955 -214.917697) (xy 344.300225 -214.884419)
			(xy 344.263921 -214.845292) (xy 344.233854 -214.801192) (xy 344.210696 -214.753103) (xy 344.194964 -214.7021)
			(xy 344.187009 -214.649321) (xy 344.18651 -214.622634) (xy 344.18651 -214.62238) (xy 344.187053 -214.594564)
			(xy 344.195709 -214.539609) (xy 344.212792 -214.486664) (xy 344.224864 -214.461598) (xy 344.236802 -214.43823)
			(xy 344.05316 -214.089742) (xy 344.027252 -214.086186) (xy 344.001846 -214.082354) (xy 343.952395 -214.068422)
			(xy 343.905455 -214.047536) (xy 343.861998 -214.02013) (xy 343.822925 -213.986771) (xy 343.789043 -213.948149)
			(xy 343.761055 -213.905065) (xy 343.73954 -213.858411) (xy 343.724944 -213.809151) (xy 343.717568 -213.758306)
			(xy 343.717118 -213.732618) (xy 342.55075 -213.732618) (xy 342.55075 -213.732872) (xy 342.55022 -213.760689)
			(xy 342.541558 -213.815644) (xy 342.52447 -213.868588) (xy 342.512396 -213.893654) (xy 342.500458 -213.917022)
			(xy 342.6841 -214.26551) (xy 342.710008 -214.269066) (xy 342.73543 -214.2728) (xy 342.784886 -214.286744)
			(xy 342.831829 -214.307641) (xy 342.875287 -214.335058) (xy 342.91436 -214.368428) (xy 342.94824 -214.407061)
			(xy 342.976225 -214.450156) (xy 342.997736 -214.49682) (xy 343.012327 -214.546089) (xy 343.019696 -214.596942)
			(xy 343.020142 -214.622634) (xy 343.019643 -214.649321) (xy 343.011688 -214.7021) (xy 342.995956 -214.753103)
			(xy 342.972798 -214.801192) (xy 342.942731 -214.845292) (xy 342.906427 -214.884419) (xy 342.864697 -214.917697)
			(xy 342.818473 -214.944384) (xy 342.768788 -214.963884) (xy 342.716751 -214.975761) (xy 342.663526 -214.97975)
			(xy 342.610301 -214.975761) (xy 342.558264 -214.963884) (xy 342.508579 -214.944384) (xy 342.462355 -214.917697)
			(xy 342.420625 -214.884419) (xy 342.384321 -214.845292) (xy 342.354254 -214.801192) (xy 342.331096 -214.753103)
			(xy 342.315364 -214.7021) (xy 342.307409 -214.649321) (xy 342.30691 -214.622634) (xy 342.30691 -214.62238)
			(xy 342.307453 -214.594564) (xy 342.316109 -214.539609) (xy 342.333192 -214.486664) (xy 342.345264 -214.461598)
			(xy 342.357202 -214.43823) (xy 342.17356 -214.089742) (xy 342.147652 -214.086186) (xy 342.122246 -214.082354)
			(xy 342.072795 -214.068422) (xy 342.025855 -214.047536) (xy 341.982398 -214.02013) (xy 341.943325 -213.986771)
			(xy 341.909443 -213.948149) (xy 341.881455 -213.905065) (xy 341.85994 -213.858411) (xy 341.845344 -213.809151)
			(xy 341.837968 -213.758306) (xy 341.837518 -213.732618) (xy 340.67115 -213.732618) (xy 340.67115 -213.732872)
			(xy 340.67062 -213.760689) (xy 340.661958 -213.815644) (xy 340.64487 -213.868588) (xy 340.632796 -213.893654)
			(xy 340.620858 -213.917022) (xy 340.8045 -214.26551) (xy 340.830408 -214.269066) (xy 340.85583 -214.2728)
			(xy 340.905286 -214.286744) (xy 340.952229 -214.307641) (xy 340.995687 -214.335058) (xy 341.03476 -214.368428)
			(xy 341.06864 -214.407061) (xy 341.096625 -214.450156) (xy 341.118136 -214.49682) (xy 341.132727 -214.546089)
			(xy 341.140096 -214.596942) (xy 341.140542 -214.622634) (xy 341.140043 -214.649321) (xy 341.132088 -214.7021)
			(xy 341.116356 -214.753103) (xy 341.093198 -214.801192) (xy 341.063131 -214.845292) (xy 341.026827 -214.884419)
			(xy 340.985097 -214.917697) (xy 340.938873 -214.944384) (xy 340.889188 -214.963884) (xy 340.837151 -214.975761)
			(xy 340.783926 -214.97975) (xy 340.730701 -214.975761) (xy 340.678664 -214.963884) (xy 340.628979 -214.944384)
			(xy 340.582755 -214.917697) (xy 340.541025 -214.884419) (xy 340.504721 -214.845292) (xy 340.474654 -214.801192)
			(xy 340.451496 -214.753103) (xy 340.435764 -214.7021) (xy 340.427809 -214.649321) (xy 340.42731 -214.622634)
			(xy 340.42731 -214.62238) (xy 340.427853 -214.594564) (xy 340.436509 -214.539609) (xy 340.453592 -214.486664)
			(xy 340.465664 -214.461598) (xy 340.477602 -214.43823) (xy 340.29396 -214.089742) (xy 340.268052 -214.086186)
			(xy 340.242646 -214.082354) (xy 340.193195 -214.068422) (xy 340.146255 -214.047536) (xy 340.102798 -214.02013)
			(xy 340.063725 -213.986771) (xy 340.029843 -213.948149) (xy 340.001855 -213.905065) (xy 339.98034 -213.858411)
			(xy 339.965744 -213.809151) (xy 339.958368 -213.758306) (xy 339.957918 -213.732618) (xy 338.79155 -213.732618)
			(xy 338.79155 -213.732872) (xy 338.79102 -213.760689) (xy 338.782358 -213.815644) (xy 338.76527 -213.868588)
			(xy 338.753196 -213.893654) (xy 338.741258 -213.917022) (xy 338.9249 -214.26551) (xy 338.950808 -214.269066)
			(xy 338.97623 -214.2728) (xy 339.025686 -214.286744) (xy 339.072629 -214.307641) (xy 339.116087 -214.335058)
			(xy 339.15516 -214.368428) (xy 339.18904 -214.407061) (xy 339.217025 -214.450156) (xy 339.238536 -214.49682)
			(xy 339.253127 -214.546089) (xy 339.260496 -214.596942) (xy 339.260942 -214.622634) (xy 339.260443 -214.649321)
			(xy 339.252488 -214.7021) (xy 339.236756 -214.753103) (xy 339.213598 -214.801192) (xy 339.183531 -214.845292)
			(xy 339.147227 -214.884419) (xy 339.105497 -214.917697) (xy 339.059273 -214.944384) (xy 339.009588 -214.963884)
			(xy 338.957551 -214.975761) (xy 338.904326 -214.97975) (xy 338.851101 -214.975761) (xy 338.799064 -214.963884)
			(xy 338.749379 -214.944384) (xy 338.703155 -214.917697) (xy 338.661425 -214.884419) (xy 338.625121 -214.845292)
			(xy 338.595054 -214.801192) (xy 338.571896 -214.753103) (xy 338.556164 -214.7021) (xy 338.548209 -214.649321)
			(xy 338.54771 -214.622634) (xy 338.54771 -214.62238) (xy 338.548253 -214.594564) (xy 338.556909 -214.539609)
			(xy 338.573992 -214.486664) (xy 338.586064 -214.461598) (xy 338.598002 -214.43823) (xy 338.41436 -214.089742)
			(xy 338.388452 -214.086186) (xy 338.363046 -214.082354) (xy 338.313595 -214.068422) (xy 338.266655 -214.047536)
			(xy 338.223198 -214.02013) (xy 338.184125 -213.986771) (xy 338.150243 -213.948149) (xy 338.122255 -213.905065)
			(xy 338.10074 -213.858411) (xy 338.086144 -213.809151) (xy 338.078768 -213.758306) (xy 338.078318 -213.732618)
			(xy 132.202682 -213.732618) (xy 132.202682 -213.732872) (xy 132.202159 -213.760689) (xy 132.193495 -213.815645)
			(xy 132.176404 -213.868589) (xy 132.164328 -213.893654) (xy 132.15239 -213.917022) (xy 132.336032 -214.26551)
			(xy 132.36194 -214.269066) (xy 132.387354 -214.272854) (xy 132.436809 -214.286788) (xy 132.483752 -214.307677)
			(xy 132.527211 -214.335087) (xy 132.566286 -214.368451) (xy 132.600167 -214.407078) (xy 132.628154 -214.450168)
			(xy 132.649666 -214.496829) (xy 132.664258 -214.546094) (xy 132.671628 -214.596944) (xy 132.672074 -214.622634)
			(xy 132.671575 -214.649321) (xy 132.66362 -214.7021) (xy 132.647888 -214.753103) (xy 132.62473 -214.801192)
			(xy 132.594663 -214.845292) (xy 132.558359 -214.884419) (xy 132.516629 -214.917697) (xy 132.470405 -214.944384)
			(xy 132.42072 -214.963884) (xy 132.368683 -214.975761) (xy 132.315458 -214.97975) (xy 132.262233 -214.975761)
			(xy 132.210196 -214.963884) (xy 132.160511 -214.944384) (xy 132.114287 -214.917697) (xy 132.072557 -214.884419)
			(xy 132.036253 -214.845292) (xy 132.006186 -214.801192) (xy 131.983028 -214.753103) (xy 131.967296 -214.7021)
			(xy 131.959341 -214.649321) (xy 131.958842 -214.622634) (xy 131.958842 -214.62238) (xy 131.959392 -214.594564)
			(xy 131.968046 -214.53961) (xy 131.985126 -214.486664) (xy 131.997196 -214.461598) (xy 132.009134 -214.43823)
			(xy 131.825492 -214.089742) (xy 131.799584 -214.086186) (xy 131.77417 -214.082408) (xy 131.724718 -214.068466)
			(xy 131.677778 -214.047572) (xy 131.634323 -214.020159) (xy 131.59525 -213.986793) (xy 131.561371 -213.948166)
			(xy 131.533384 -213.905078) (xy 131.511871 -213.858419) (xy 131.497275 -213.809156) (xy 131.489899 -213.758308)
			(xy 131.48945 -213.732618) (xy 130.323082 -213.732618) (xy 130.323082 -213.732872) (xy 130.322559 -213.760689)
			(xy 130.313895 -213.815645) (xy 130.296804 -213.868589) (xy 130.284728 -213.893654) (xy 130.27279 -213.917022)
			(xy 130.456432 -214.26551) (xy 130.48234 -214.269066) (xy 130.507754 -214.272854) (xy 130.557209 -214.286788)
			(xy 130.604152 -214.307677) (xy 130.647611 -214.335087) (xy 130.686686 -214.368451) (xy 130.720567 -214.407078)
			(xy 130.748554 -214.450168) (xy 130.770066 -214.496829) (xy 130.784658 -214.546094) (xy 130.792028 -214.596944)
			(xy 130.792474 -214.622634) (xy 130.791975 -214.649321) (xy 130.78402 -214.7021) (xy 130.768288 -214.753103)
			(xy 130.74513 -214.801192) (xy 130.715063 -214.845292) (xy 130.678759 -214.884419) (xy 130.637029 -214.917697)
			(xy 130.590805 -214.944384) (xy 130.54112 -214.963884) (xy 130.489083 -214.975761) (xy 130.435858 -214.97975)
			(xy 130.382633 -214.975761) (xy 130.330596 -214.963884) (xy 130.280911 -214.944384) (xy 130.234687 -214.917697)
			(xy 130.192957 -214.884419) (xy 130.156653 -214.845292) (xy 130.126586 -214.801192) (xy 130.103428 -214.753103)
			(xy 130.087696 -214.7021) (xy 130.079741 -214.649321) (xy 130.079242 -214.622634) (xy 130.079242 -214.62238)
			(xy 130.079792 -214.594564) (xy 130.088446 -214.53961) (xy 130.105526 -214.486664) (xy 130.117596 -214.461598)
			(xy 130.129534 -214.43823) (xy 129.945892 -214.089742) (xy 129.919984 -214.086186) (xy 129.89457 -214.082408)
			(xy 129.845118 -214.068466) (xy 129.798178 -214.047572) (xy 129.754723 -214.020159) (xy 129.71565 -213.986793)
			(xy 129.681771 -213.948166) (xy 129.653784 -213.905078) (xy 129.632271 -213.858419) (xy 129.617675 -213.809156)
			(xy 129.610299 -213.758308) (xy 129.60985 -213.732618) (xy 128.443482 -213.732618) (xy 128.443482 -213.732872)
			(xy 128.442959 -213.760689) (xy 128.434295 -213.815645) (xy 128.417204 -213.868589) (xy 128.405128 -213.893654)
			(xy 128.39319 -213.917022) (xy 128.576832 -214.26551) (xy 128.60274 -214.269066) (xy 128.628154 -214.272854)
			(xy 128.677609 -214.286788) (xy 128.724552 -214.307677) (xy 128.768011 -214.335087) (xy 128.807086 -214.368451)
			(xy 128.840967 -214.407078) (xy 128.868954 -214.450168) (xy 128.890466 -214.496829) (xy 128.905058 -214.546094)
			(xy 128.912428 -214.596944) (xy 128.912874 -214.622634) (xy 128.912375 -214.649321) (xy 128.90442 -214.7021)
			(xy 128.888688 -214.753103) (xy 128.86553 -214.801192) (xy 128.835463 -214.845292) (xy 128.799159 -214.884419)
			(xy 128.757429 -214.917697) (xy 128.711205 -214.944384) (xy 128.66152 -214.963884) (xy 128.609483 -214.975761)
			(xy 128.556258 -214.97975) (xy 128.503033 -214.975761) (xy 128.450996 -214.963884) (xy 128.401311 -214.944384)
			(xy 128.355087 -214.917697) (xy 128.313357 -214.884419) (xy 128.277053 -214.845292) (xy 128.246986 -214.801192)
			(xy 128.223828 -214.753103) (xy 128.208096 -214.7021) (xy 128.200141 -214.649321) (xy 128.199642 -214.622634)
			(xy 128.199642 -214.62238) (xy 128.200192 -214.594564) (xy 128.208846 -214.53961) (xy 128.225926 -214.486664)
			(xy 128.237996 -214.461598) (xy 128.249934 -214.43823) (xy 128.066292 -214.089742) (xy 128.040384 -214.086186)
			(xy 128.01497 -214.082408) (xy 127.965518 -214.068466) (xy 127.918578 -214.047572) (xy 127.875123 -214.020159)
			(xy 127.83605 -213.986793) (xy 127.802171 -213.948166) (xy 127.774184 -213.905078) (xy 127.752671 -213.858419)
			(xy 127.738075 -213.809156) (xy 127.730699 -213.758308) (xy 127.73025 -213.732618) (xy 126.563628 -213.732618)
			(xy 126.563628 -213.732872) (xy 126.5631 -213.760689) (xy 126.554437 -213.815644) (xy 126.537349 -213.868589)
			(xy 126.525274 -213.893654) (xy 126.513336 -213.917022) (xy 126.697232 -214.26551) (xy 126.72314 -214.269066)
			(xy 126.748554 -214.272854) (xy 126.798009 -214.286788) (xy 126.844952 -214.307677) (xy 126.888411 -214.335087)
			(xy 126.927486 -214.368451) (xy 126.961367 -214.407078) (xy 126.989354 -214.450168) (xy 127.010866 -214.496829)
			(xy 127.025458 -214.546094) (xy 127.032828 -214.596944) (xy 127.033274 -214.622634) (xy 127.032775 -214.649321)
			(xy 127.02482 -214.7021) (xy 127.009088 -214.753103) (xy 126.98593 -214.801192) (xy 126.955863 -214.845292)
			(xy 126.919559 -214.884419) (xy 126.877829 -214.917697) (xy 126.831605 -214.944384) (xy 126.78192 -214.963884)
			(xy 126.729883 -214.975761) (xy 126.676658 -214.97975) (xy 126.623433 -214.975761) (xy 126.571396 -214.963884)
			(xy 126.521711 -214.944384) (xy 126.475487 -214.917697) (xy 126.433757 -214.884419) (xy 126.397453 -214.845292)
			(xy 126.367386 -214.801192) (xy 126.344228 -214.753103) (xy 126.328496 -214.7021) (xy 126.320541 -214.649321)
			(xy 126.320042 -214.622634) (xy 126.320042 -214.62238) (xy 126.320592 -214.594564) (xy 126.329246 -214.53961)
			(xy 126.346326 -214.486664) (xy 126.358396 -214.461598) (xy 126.370334 -214.43823) (xy 126.186692 -214.089742)
			(xy 126.16053 -214.086186) (xy 126.135122 -214.082372) (xy 126.08567 -214.068436) (xy 126.03873 -214.047548)
			(xy 125.995274 -214.020139) (xy 125.956201 -213.986778) (xy 125.92232 -213.948155) (xy 125.894332 -213.905069)
			(xy 125.872818 -213.858413) (xy 125.858221 -213.809152) (xy 125.850846 -213.758307) (xy 125.850396 -213.732618)
			(xy 124.684028 -213.732618) (xy 124.683406 -213.761872) (xy 124.673809 -213.819588) (xy 124.654925 -213.874965)
			(xy 124.64161 -213.90102) (xy 124.62891 -213.924642) (xy 124.805694 -214.265002) (xy 124.832872 -214.267796)
			(xy 124.858915 -214.270933) (xy 124.909767 -214.283795) (xy 124.958187 -214.303965) (xy 125.00313 -214.331009)
			(xy 125.043628 -214.364344) (xy 125.078807 -214.403251) (xy 125.107909 -214.446891) (xy 125.130305 -214.494322)
			(xy 125.145513 -214.544522) (xy 125.153205 -214.596408) (xy 125.153674 -214.622634) (xy 125.153175 -214.649321)
			(xy 125.14522 -214.7021) (xy 125.129488 -214.753103) (xy 125.10633 -214.801192) (xy 125.076263 -214.845292)
			(xy 125.039959 -214.884419) (xy 124.998229 -214.917697) (xy 124.952005 -214.944384) (xy 124.90232 -214.963884)
			(xy 124.850283 -214.975761) (xy 124.797058 -214.97975) (xy 124.743833 -214.975761) (xy 124.691796 -214.963884)
			(xy 124.642111 -214.944384) (xy 124.595887 -214.917697) (xy 124.554157 -214.884419) (xy 124.517853 -214.845292)
			(xy 124.487786 -214.801192) (xy 124.464628 -214.753103) (xy 124.448896 -214.7021) (xy 124.440941 -214.649321)
			(xy 124.440442 -214.622634) (xy 124.441103 -214.592125) (xy 124.45152 -214.532002) (xy 124.471991 -214.474519)
			(xy 124.486416 -214.447628) (xy 124.499878 -214.423752) (xy 124.326904 -214.09025) (xy 124.298964 -214.088218)
			(xy 124.272482 -214.085641) (xy 124.220665 -214.073553) (xy 124.17122 -214.053903) (xy 124.125242 -214.027125)
			(xy 124.083751 -213.993815) (xy 124.047669 -213.954712) (xy 124.017795 -213.910682) (xy 123.994793 -213.862704)
			(xy 123.979173 -213.811841) (xy 123.971282 -213.759222) (xy 123.970796 -213.732618) (xy 122.804682 -213.732618)
			(xy 122.804682 -213.732872) (xy 122.804159 -213.760689) (xy 122.795495 -213.815645) (xy 122.778404 -213.868589)
			(xy 122.766328 -213.893654) (xy 122.75439 -213.917022) (xy 122.938032 -214.26551) (xy 122.96394 -214.269066)
			(xy 122.989354 -214.272854) (xy 123.038809 -214.286788) (xy 123.085752 -214.307677) (xy 123.129211 -214.335087)
			(xy 123.168286 -214.368451) (xy 123.202167 -214.407078) (xy 123.230154 -214.450168) (xy 123.251666 -214.496829)
			(xy 123.266258 -214.546094) (xy 123.273628 -214.596944) (xy 123.274074 -214.622634) (xy 123.273575 -214.649321)
			(xy 123.26562 -214.7021) (xy 123.249888 -214.753103) (xy 123.22673 -214.801192) (xy 123.196663 -214.845292)
			(xy 123.160359 -214.884419) (xy 123.118629 -214.917697) (xy 123.072405 -214.944384) (xy 123.02272 -214.963884)
			(xy 122.970683 -214.975761) (xy 122.917458 -214.97975) (xy 122.864233 -214.975761) (xy 122.812196 -214.963884)
			(xy 122.762511 -214.944384) (xy 122.716287 -214.917697) (xy 122.674557 -214.884419) (xy 122.638253 -214.845292)
			(xy 122.608186 -214.801192) (xy 122.585028 -214.753103) (xy 122.569296 -214.7021) (xy 122.561341 -214.649321)
			(xy 122.560842 -214.622634) (xy 122.560842 -214.62238) (xy 122.561392 -214.594564) (xy 122.570046 -214.53961)
			(xy 122.587126 -214.486664) (xy 122.599196 -214.461598) (xy 122.611134 -214.43823) (xy 122.427492 -214.089742)
			(xy 122.401584 -214.086186) (xy 122.37617 -214.082408) (xy 122.326718 -214.068466) (xy 122.279778 -214.047572)
			(xy 122.236323 -214.020159) (xy 122.19725 -213.986793) (xy 122.163371 -213.948166) (xy 122.135384 -213.905078)
			(xy 122.113871 -213.858419) (xy 122.099275 -213.809156) (xy 122.091899 -213.758308) (xy 122.09145 -213.732618)
			(xy 120.925082 -213.732618) (xy 120.925082 -213.732872) (xy 120.924559 -213.760689) (xy 120.915895 -213.815645)
			(xy 120.898804 -213.868589) (xy 120.886728 -213.893654) (xy 120.87479 -213.917022) (xy 121.058432 -214.26551)
			(xy 121.08434 -214.269066) (xy 121.109754 -214.272854) (xy 121.159209 -214.286788) (xy 121.206152 -214.307677)
			(xy 121.249611 -214.335087) (xy 121.288686 -214.368451) (xy 121.322567 -214.407078) (xy 121.350554 -214.450168)
			(xy 121.372066 -214.496829) (xy 121.386658 -214.546094) (xy 121.394028 -214.596944) (xy 121.394474 -214.622634)
			(xy 121.393975 -214.649321) (xy 121.38602 -214.7021) (xy 121.370288 -214.753103) (xy 121.34713 -214.801192)
			(xy 121.317063 -214.845292) (xy 121.280759 -214.884419) (xy 121.239029 -214.917697) (xy 121.192805 -214.944384)
			(xy 121.14312 -214.963884) (xy 121.091083 -214.975761) (xy 121.037858 -214.97975) (xy 120.984633 -214.975761)
			(xy 120.932596 -214.963884) (xy 120.882911 -214.944384) (xy 120.836687 -214.917697) (xy 120.794957 -214.884419)
			(xy 120.758653 -214.845292) (xy 120.728586 -214.801192) (xy 120.705428 -214.753103) (xy 120.689696 -214.7021)
			(xy 120.681741 -214.649321) (xy 120.681242 -214.622634) (xy 120.681242 -214.62238) (xy 120.681792 -214.594564)
			(xy 120.690446 -214.53961) (xy 120.707526 -214.486664) (xy 120.719596 -214.461598) (xy 120.731534 -214.43823)
			(xy 120.547892 -214.089742) (xy 120.521984 -214.086186) (xy 120.49657 -214.082408) (xy 120.447118 -214.068466)
			(xy 120.400178 -214.047572) (xy 120.356723 -214.020159) (xy 120.31765 -213.986793) (xy 120.283771 -213.948166)
			(xy 120.255784 -213.905078) (xy 120.234271 -213.858419) (xy 120.219675 -213.809156) (xy 120.212299 -213.758308)
			(xy 120.21185 -213.732618) (xy 119.045482 -213.732618) (xy 119.045482 -213.732872) (xy 119.044959 -213.760689)
			(xy 119.036295 -213.815645) (xy 119.019204 -213.868589) (xy 119.007128 -213.893654) (xy 118.99519 -213.917022)
			(xy 119.178832 -214.26551) (xy 119.20474 -214.269066) (xy 119.230154 -214.272854) (xy 119.279609 -214.286788)
			(xy 119.326552 -214.307677) (xy 119.370011 -214.335087) (xy 119.409086 -214.368451) (xy 119.442967 -214.407078)
			(xy 119.470954 -214.450168) (xy 119.492466 -214.496829) (xy 119.507058 -214.546094) (xy 119.514428 -214.596944)
			(xy 119.514874 -214.622634) (xy 119.514375 -214.649321) (xy 119.50642 -214.7021) (xy 119.490688 -214.753103)
			(xy 119.46753 -214.801192) (xy 119.437463 -214.845292) (xy 119.401159 -214.884419) (xy 119.359429 -214.917697)
			(xy 119.313205 -214.944384) (xy 119.26352 -214.963884) (xy 119.211483 -214.975761) (xy 119.158258 -214.97975)
			(xy 119.105033 -214.975761) (xy 119.052996 -214.963884) (xy 119.003311 -214.944384) (xy 118.957087 -214.917697)
			(xy 118.915357 -214.884419) (xy 118.879053 -214.845292) (xy 118.848986 -214.801192) (xy 118.825828 -214.753103)
			(xy 118.810096 -214.7021) (xy 118.802141 -214.649321) (xy 118.801642 -214.622634) (xy 118.801642 -214.62238)
			(xy 118.802192 -214.594564) (xy 118.810846 -214.53961) (xy 118.827926 -214.486664) (xy 118.839996 -214.461598)
			(xy 118.851934 -214.43823) (xy 118.668292 -214.089742) (xy 118.642384 -214.086186) (xy 118.61697 -214.082408)
			(xy 118.567518 -214.068466) (xy 118.520578 -214.047572) (xy 118.477123 -214.020159) (xy 118.43805 -213.986793)
			(xy 118.404171 -213.948166) (xy 118.376184 -213.905078) (xy 118.354671 -213.858419) (xy 118.340075 -213.809156)
			(xy 118.332699 -213.758308) (xy 118.33225 -213.732618) (xy 117.165882 -213.732618) (xy 117.165882 -213.732872)
			(xy 117.165359 -213.760689) (xy 117.156695 -213.815645) (xy 117.139604 -213.868589) (xy 117.127528 -213.893654)
			(xy 117.11559 -213.917022) (xy 117.299232 -214.26551) (xy 117.32514 -214.269066) (xy 117.350554 -214.272854)
			(xy 117.400009 -214.286788) (xy 117.446952 -214.307677) (xy 117.490411 -214.335087) (xy 117.529486 -214.368451)
			(xy 117.563367 -214.407078) (xy 117.591354 -214.450168) (xy 117.612866 -214.496829) (xy 117.627458 -214.546094)
			(xy 117.634828 -214.596944) (xy 117.635274 -214.622634) (xy 117.634775 -214.649321) (xy 117.62682 -214.7021)
			(xy 117.611088 -214.753103) (xy 117.58793 -214.801192) (xy 117.557863 -214.845292) (xy 117.521559 -214.884419)
			(xy 117.479829 -214.917697) (xy 117.433605 -214.944384) (xy 117.38392 -214.963884) (xy 117.331883 -214.975761)
			(xy 117.278658 -214.97975) (xy 117.225433 -214.975761) (xy 117.173396 -214.963884) (xy 117.123711 -214.944384)
			(xy 117.077487 -214.917697) (xy 117.035757 -214.884419) (xy 116.999453 -214.845292) (xy 116.969386 -214.801192)
			(xy 116.946228 -214.753103) (xy 116.930496 -214.7021) (xy 116.922541 -214.649321) (xy 116.922042 -214.622634)
			(xy 116.922042 -214.62238) (xy 116.922592 -214.594564) (xy 116.931246 -214.53961) (xy 116.948326 -214.486664)
			(xy 116.960396 -214.461598) (xy 116.972334 -214.43823) (xy 116.788692 -214.089742) (xy 116.762784 -214.086186)
			(xy 116.73737 -214.082408) (xy 116.687918 -214.068466) (xy 116.640978 -214.047572) (xy 116.597523 -214.020159)
			(xy 116.55845 -213.986793) (xy 116.524571 -213.948166) (xy 116.496584 -213.905078) (xy 116.475071 -213.858419)
			(xy 116.460475 -213.809156) (xy 116.453099 -213.758308) (xy 116.45265 -213.732618) (xy 115.286282 -213.732618)
			(xy 115.286282 -213.732872) (xy 115.285759 -213.760689) (xy 115.277095 -213.815645) (xy 115.260004 -213.868589)
			(xy 115.247928 -213.893654) (xy 115.23599 -213.917022) (xy 115.419632 -214.26551) (xy 115.44554 -214.269066)
			(xy 115.470954 -214.272854) (xy 115.520409 -214.286788) (xy 115.567352 -214.307677) (xy 115.610811 -214.335087)
			(xy 115.649886 -214.368451) (xy 115.683767 -214.407078) (xy 115.711754 -214.450168) (xy 115.733266 -214.496829)
			(xy 115.747858 -214.546094) (xy 115.755228 -214.596944) (xy 115.755674 -214.622634) (xy 115.755175 -214.649321)
			(xy 115.74722 -214.7021) (xy 115.731488 -214.753103) (xy 115.70833 -214.801192) (xy 115.678263 -214.845292)
			(xy 115.641959 -214.884419) (xy 115.600229 -214.917697) (xy 115.554005 -214.944384) (xy 115.50432 -214.963884)
			(xy 115.452283 -214.975761) (xy 115.399058 -214.97975) (xy 115.345833 -214.975761) (xy 115.293796 -214.963884)
			(xy 115.244111 -214.944384) (xy 115.197887 -214.917697) (xy 115.156157 -214.884419) (xy 115.119853 -214.845292)
			(xy 115.089786 -214.801192) (xy 115.066628 -214.753103) (xy 115.050896 -214.7021) (xy 115.042941 -214.649321)
			(xy 115.042442 -214.622634) (xy 115.042442 -214.62238) (xy 115.042992 -214.594564) (xy 115.051646 -214.53961)
			(xy 115.068726 -214.486664) (xy 115.080796 -214.461598) (xy 115.092734 -214.43823) (xy 114.909092 -214.089742)
			(xy 114.883184 -214.086186) (xy 114.85777 -214.082408) (xy 114.808318 -214.068466) (xy 114.761378 -214.047572)
			(xy 114.717923 -214.020159) (xy 114.67885 -213.986793) (xy 114.644971 -213.948166) (xy 114.616984 -213.905078)
			(xy 114.595471 -213.858419) (xy 114.580875 -213.809156) (xy 114.573499 -213.758308) (xy 114.57305 -213.732618)
			(xy 107.767882 -213.732618) (xy 107.767882 -213.732872) (xy 107.767359 -213.760689) (xy 107.758695 -213.815645)
			(xy 107.741604 -213.868589) (xy 107.729528 -213.893654) (xy 107.71759 -213.917022) (xy 107.901232 -214.26551)
			(xy 107.92714 -214.269066) (xy 107.952554 -214.272854) (xy 108.002009 -214.286788) (xy 108.048952 -214.307677)
			(xy 108.092411 -214.335087) (xy 108.131486 -214.368451) (xy 108.165367 -214.407078) (xy 108.193354 -214.450168)
			(xy 108.214866 -214.496829) (xy 108.229458 -214.546094) (xy 108.236828 -214.596944) (xy 108.237274 -214.622634)
			(xy 108.236775 -214.649321) (xy 108.22882 -214.7021) (xy 108.213088 -214.753103) (xy 108.18993 -214.801192)
			(xy 108.159863 -214.845292) (xy 108.123559 -214.884419) (xy 108.081829 -214.917697) (xy 108.035605 -214.944384)
			(xy 107.98592 -214.963884) (xy 107.933883 -214.975761) (xy 107.880658 -214.97975) (xy 107.827433 -214.975761)
			(xy 107.775396 -214.963884) (xy 107.725711 -214.944384) (xy 107.679487 -214.917697) (xy 107.637757 -214.884419)
			(xy 107.601453 -214.845292) (xy 107.571386 -214.801192) (xy 107.548228 -214.753103) (xy 107.532496 -214.7021)
			(xy 107.524541 -214.649321) (xy 107.524042 -214.622634) (xy 107.524042 -214.62238) (xy 107.524592 -214.594564)
			(xy 107.533246 -214.53961) (xy 107.550326 -214.486664) (xy 107.562396 -214.461598) (xy 107.574334 -214.43823)
			(xy 107.390692 -214.089742) (xy 107.364784 -214.086186) (xy 107.33937 -214.082408) (xy 107.289918 -214.068466)
			(xy 107.242978 -214.047572) (xy 107.199523 -214.020159) (xy 107.16045 -213.986793) (xy 107.126571 -213.948166)
			(xy 107.098584 -213.905078) (xy 107.077071 -213.858419) (xy 107.062475 -213.809156) (xy 107.055099 -213.758308)
			(xy 107.05465 -213.732618) (xy 105.888282 -213.732618) (xy 105.888282 -213.732872) (xy 105.887759 -213.760689)
			(xy 105.879095 -213.815645) (xy 105.862004 -213.868589) (xy 105.849928 -213.893654) (xy 105.83799 -213.917022)
			(xy 106.021632 -214.26551) (xy 106.04754 -214.269066) (xy 106.072954 -214.272854) (xy 106.122409 -214.286788)
			(xy 106.169352 -214.307677) (xy 106.212811 -214.335087) (xy 106.251886 -214.368451) (xy 106.285767 -214.407078)
			(xy 106.313754 -214.450168) (xy 106.335266 -214.496829) (xy 106.349858 -214.546094) (xy 106.357228 -214.596944)
			(xy 106.357674 -214.622634) (xy 106.357175 -214.649321) (xy 106.34922 -214.7021) (xy 106.333488 -214.753103)
			(xy 106.31033 -214.801192) (xy 106.280263 -214.845292) (xy 106.243959 -214.884419) (xy 106.202229 -214.917697)
			(xy 106.156005 -214.944384) (xy 106.10632 -214.963884) (xy 106.054283 -214.975761) (xy 106.001058 -214.97975)
			(xy 105.947833 -214.975761) (xy 105.895796 -214.963884) (xy 105.846111 -214.944384) (xy 105.799887 -214.917697)
			(xy 105.758157 -214.884419) (xy 105.721853 -214.845292) (xy 105.691786 -214.801192) (xy 105.668628 -214.753103)
			(xy 105.652896 -214.7021) (xy 105.644941 -214.649321) (xy 105.644442 -214.622634) (xy 105.644442 -214.62238)
			(xy 105.644992 -214.594564) (xy 105.653646 -214.53961) (xy 105.670726 -214.486664) (xy 105.682796 -214.461598)
			(xy 105.694734 -214.43823) (xy 105.511092 -214.089742) (xy 105.485184 -214.086186) (xy 105.45977 -214.082408)
			(xy 105.410318 -214.068466) (xy 105.363378 -214.047572) (xy 105.319923 -214.020159) (xy 105.28085 -213.986793)
			(xy 105.246971 -213.948166) (xy 105.218984 -213.905078) (xy 105.197471 -213.858419) (xy 105.182875 -213.809156)
			(xy 105.175499 -213.758308) (xy 105.17505 -213.732618) (xy 104.008682 -213.732618) (xy 104.008682 -213.732872)
			(xy 104.008159 -213.760689) (xy 103.999495 -213.815645) (xy 103.982404 -213.868589) (xy 103.970328 -213.893654)
			(xy 103.95839 -213.917022) (xy 104.142032 -214.26551) (xy 104.16794 -214.269066) (xy 104.193354 -214.272854)
			(xy 104.242809 -214.286788) (xy 104.289752 -214.307677) (xy 104.333211 -214.335087) (xy 104.372286 -214.368451)
			(xy 104.406167 -214.407078) (xy 104.434154 -214.450168) (xy 104.455666 -214.496829) (xy 104.470258 -214.546094)
			(xy 104.477628 -214.596944) (xy 104.478074 -214.622634) (xy 104.477575 -214.649321) (xy 104.46962 -214.7021)
			(xy 104.453888 -214.753103) (xy 104.43073 -214.801192) (xy 104.400663 -214.845292) (xy 104.364359 -214.884419)
			(xy 104.322629 -214.917697) (xy 104.276405 -214.944384) (xy 104.22672 -214.963884) (xy 104.174683 -214.975761)
			(xy 104.121458 -214.97975) (xy 104.068233 -214.975761) (xy 104.016196 -214.963884) (xy 103.966511 -214.944384)
			(xy 103.920287 -214.917697) (xy 103.878557 -214.884419) (xy 103.842253 -214.845292) (xy 103.812186 -214.801192)
			(xy 103.789028 -214.753103) (xy 103.773296 -214.7021) (xy 103.765341 -214.649321) (xy 103.764842 -214.622634)
			(xy 103.764842 -214.62238) (xy 103.765392 -214.594564) (xy 103.774046 -214.53961) (xy 103.791126 -214.486664)
			(xy 103.803196 -214.461598) (xy 103.815134 -214.43823) (xy 103.631492 -214.089742) (xy 103.605584 -214.086186)
			(xy 103.58017 -214.082408) (xy 103.530718 -214.068466) (xy 103.483778 -214.047572) (xy 103.440323 -214.020159)
			(xy 103.40125 -213.986793) (xy 103.367371 -213.948166) (xy 103.339384 -213.905078) (xy 103.317871 -213.858419)
			(xy 103.303275 -213.809156) (xy 103.295899 -213.758308) (xy 103.29545 -213.732618) (xy 102.129082 -213.732618)
			(xy 102.129082 -213.732872) (xy 102.128559 -213.760689) (xy 102.119895 -213.815645) (xy 102.102804 -213.868589)
			(xy 102.090728 -213.893654) (xy 102.07879 -213.917022) (xy 102.262432 -214.26551) (xy 102.28834 -214.269066)
			(xy 102.313754 -214.272854) (xy 102.363209 -214.286788) (xy 102.410152 -214.307677) (xy 102.453611 -214.335087)
			(xy 102.492686 -214.368451) (xy 102.526567 -214.407078) (xy 102.554554 -214.450168) (xy 102.576066 -214.496829)
			(xy 102.590658 -214.546094) (xy 102.598028 -214.596944) (xy 102.598474 -214.622634) (xy 102.597975 -214.649321)
			(xy 102.59002 -214.7021) (xy 102.574288 -214.753103) (xy 102.55113 -214.801192) (xy 102.521063 -214.845292)
			(xy 102.484759 -214.884419) (xy 102.443029 -214.917697) (xy 102.396805 -214.944384) (xy 102.34712 -214.963884)
			(xy 102.295083 -214.975761) (xy 102.241858 -214.97975) (xy 102.188633 -214.975761) (xy 102.136596 -214.963884)
			(xy 102.086911 -214.944384) (xy 102.040687 -214.917697) (xy 101.998957 -214.884419) (xy 101.962653 -214.845292)
			(xy 101.932586 -214.801192) (xy 101.909428 -214.753103) (xy 101.893696 -214.7021) (xy 101.885741 -214.649321)
			(xy 101.885242 -214.622634) (xy 101.885242 -214.62238) (xy 101.885792 -214.594564) (xy 101.894446 -214.53961)
			(xy 101.911526 -214.486664) (xy 101.923596 -214.461598) (xy 101.935534 -214.43823) (xy 101.751892 -214.089742)
			(xy 101.725984 -214.086186) (xy 101.70057 -214.082408) (xy 101.651118 -214.068466) (xy 101.604178 -214.047572)
			(xy 101.560723 -214.020159) (xy 101.52165 -213.986793) (xy 101.487771 -213.948166) (xy 101.459784 -213.905078)
			(xy 101.438271 -213.858419) (xy 101.423675 -213.809156) (xy 101.416299 -213.758308) (xy 101.41585 -213.732618)
			(xy 100.249482 -213.732618) (xy 100.249482 -213.732872) (xy 100.248959 -213.760689) (xy 100.240295 -213.815645)
			(xy 100.223204 -213.868589) (xy 100.211128 -213.893654) (xy 100.19919 -213.917022) (xy 100.382832 -214.26551)
			(xy 100.40874 -214.269066) (xy 100.434154 -214.272854) (xy 100.483609 -214.286788) (xy 100.530552 -214.307677)
			(xy 100.574011 -214.335087) (xy 100.613086 -214.368451) (xy 100.646967 -214.407078) (xy 100.674954 -214.450168)
			(xy 100.696466 -214.496829) (xy 100.711058 -214.546094) (xy 100.718428 -214.596944) (xy 100.718874 -214.622634)
			(xy 100.718375 -214.649321) (xy 100.71042 -214.7021) (xy 100.694688 -214.753103) (xy 100.67153 -214.801192)
			(xy 100.641463 -214.845292) (xy 100.605159 -214.884419) (xy 100.563429 -214.917697) (xy 100.517205 -214.944384)
			(xy 100.46752 -214.963884) (xy 100.415483 -214.975761) (xy 100.362258 -214.97975) (xy 100.309033 -214.975761)
			(xy 100.256996 -214.963884) (xy 100.207311 -214.944384) (xy 100.161087 -214.917697) (xy 100.119357 -214.884419)
			(xy 100.083053 -214.845292) (xy 100.052986 -214.801192) (xy 100.029828 -214.753103) (xy 100.014096 -214.7021)
			(xy 100.006141 -214.649321) (xy 100.005642 -214.622634) (xy 100.005642 -214.62238) (xy 100.006192 -214.594564)
			(xy 100.014846 -214.53961) (xy 100.031926 -214.486664) (xy 100.043996 -214.461598) (xy 100.055934 -214.43823)
			(xy 99.872292 -214.089742) (xy 99.846384 -214.086186) (xy 99.82097 -214.082408) (xy 99.771518 -214.068466)
			(xy 99.724578 -214.047572) (xy 99.681123 -214.020159) (xy 99.64205 -213.986793) (xy 99.608171 -213.948166)
			(xy 99.580184 -213.905078) (xy 99.558671 -213.858419) (xy 99.544075 -213.809156) (xy 99.536699 -213.758308)
			(xy 99.53625 -213.732618) (xy 98.369882 -213.732618) (xy 98.369882 -213.732872) (xy 98.369359 -213.760689)
			(xy 98.360695 -213.815645) (xy 98.343604 -213.868589) (xy 98.331528 -213.893654) (xy 98.31959 -213.917022)
			(xy 98.503232 -214.26551) (xy 98.52914 -214.269066) (xy 98.554554 -214.272854) (xy 98.604009 -214.286788)
			(xy 98.650952 -214.307677) (xy 98.694411 -214.335087) (xy 98.733486 -214.368451) (xy 98.767367 -214.407078)
			(xy 98.795354 -214.450168) (xy 98.816866 -214.496829) (xy 98.831458 -214.546094) (xy 98.838828 -214.596944)
			(xy 98.839274 -214.622634) (xy 98.838775 -214.649321) (xy 98.83082 -214.7021) (xy 98.815088 -214.753103)
			(xy 98.79193 -214.801192) (xy 98.761863 -214.845292) (xy 98.725559 -214.884419) (xy 98.683829 -214.917697)
			(xy 98.637605 -214.944384) (xy 98.58792 -214.963884) (xy 98.535883 -214.975761) (xy 98.482658 -214.97975)
			(xy 98.429433 -214.975761) (xy 98.377396 -214.963884) (xy 98.327711 -214.944384) (xy 98.281487 -214.917697)
			(xy 98.239757 -214.884419) (xy 98.203453 -214.845292) (xy 98.173386 -214.801192) (xy 98.150228 -214.753103)
			(xy 98.134496 -214.7021) (xy 98.126541 -214.649321) (xy 98.126042 -214.622634) (xy 98.126042 -214.62238)
			(xy 98.126592 -214.594564) (xy 98.135246 -214.53961) (xy 98.152326 -214.486664) (xy 98.164396 -214.461598)
			(xy 98.176334 -214.43823) (xy 97.992692 -214.089742) (xy 97.966784 -214.086186) (xy 97.94137 -214.082408)
			(xy 97.891918 -214.068466) (xy 97.844978 -214.047572) (xy 97.801523 -214.020159) (xy 97.76245 -213.986793)
			(xy 97.728571 -213.948166) (xy 97.700584 -213.905078) (xy 97.679071 -213.858419) (xy 97.664475 -213.809156)
			(xy 97.657099 -213.758308) (xy 97.65665 -213.732618) (xy 96.490282 -213.732618) (xy 96.490282 -213.732872)
			(xy 96.489759 -213.760689) (xy 96.481095 -213.815645) (xy 96.464004 -213.868589) (xy 96.451928 -213.893654)
			(xy 96.43999 -213.917022) (xy 96.623632 -214.26551) (xy 96.64954 -214.269066) (xy 96.674954 -214.272854)
			(xy 96.724409 -214.286788) (xy 96.771352 -214.307677) (xy 96.814811 -214.335087) (xy 96.853886 -214.368451)
			(xy 96.887767 -214.407078) (xy 96.915754 -214.450168) (xy 96.937266 -214.496829) (xy 96.951858 -214.546094)
			(xy 96.959228 -214.596944) (xy 96.959674 -214.622634) (xy 96.959175 -214.649321) (xy 96.95122 -214.7021)
			(xy 96.935488 -214.753103) (xy 96.91233 -214.801192) (xy 96.882263 -214.845292) (xy 96.845959 -214.884419)
			(xy 96.804229 -214.917697) (xy 96.758005 -214.944384) (xy 96.70832 -214.963884) (xy 96.656283 -214.975761)
			(xy 96.603058 -214.97975) (xy 96.549833 -214.975761) (xy 96.497796 -214.963884) (xy 96.448111 -214.944384)
			(xy 96.401887 -214.917697) (xy 96.360157 -214.884419) (xy 96.323853 -214.845292) (xy 96.293786 -214.801192)
			(xy 96.270628 -214.753103) (xy 96.254896 -214.7021) (xy 96.246941 -214.649321) (xy 96.246442 -214.622634)
			(xy 96.246442 -214.62238) (xy 96.246992 -214.594564) (xy 96.255646 -214.53961) (xy 96.272726 -214.486664)
			(xy 96.284796 -214.461598) (xy 96.296734 -214.43823) (xy 96.113092 -214.089742) (xy 96.087184 -214.086186)
			(xy 96.06177 -214.082408) (xy 96.012318 -214.068466) (xy 95.965378 -214.047572) (xy 95.921923 -214.020159)
			(xy 95.88285 -213.986793) (xy 95.848971 -213.948166) (xy 95.820984 -213.905078) (xy 95.799471 -213.858419)
			(xy 95.784875 -213.809156) (xy 95.777499 -213.758308) (xy 95.77705 -213.732618) (xy 94.610682 -213.732618)
			(xy 94.610682 -213.732872) (xy 94.610159 -213.760689) (xy 94.601495 -213.815645) (xy 94.584404 -213.868589)
			(xy 94.572328 -213.893654) (xy 94.56039 -213.917022) (xy 94.744032 -214.26551) (xy 94.76994 -214.269066)
			(xy 94.795354 -214.272854) (xy 94.844809 -214.286788) (xy 94.891752 -214.307677) (xy 94.935211 -214.335087)
			(xy 94.974286 -214.368451) (xy 95.008167 -214.407078) (xy 95.036154 -214.450168) (xy 95.057666 -214.496829)
			(xy 95.072258 -214.546094) (xy 95.079628 -214.596944) (xy 95.080074 -214.622634) (xy 95.079575 -214.649321)
			(xy 95.07162 -214.7021) (xy 95.055888 -214.753103) (xy 95.03273 -214.801192) (xy 95.002663 -214.845292)
			(xy 94.966359 -214.884419) (xy 94.924629 -214.917697) (xy 94.878405 -214.944384) (xy 94.82872 -214.963884)
			(xy 94.776683 -214.975761) (xy 94.723458 -214.97975) (xy 94.670233 -214.975761) (xy 94.618196 -214.963884)
			(xy 94.568511 -214.944384) (xy 94.522287 -214.917697) (xy 94.480557 -214.884419) (xy 94.444253 -214.845292)
			(xy 94.414186 -214.801192) (xy 94.391028 -214.753103) (xy 94.375296 -214.7021) (xy 94.367341 -214.649321)
			(xy 94.366842 -214.622634) (xy 94.366842 -214.62238) (xy 94.367392 -214.594564) (xy 94.376046 -214.53961)
			(xy 94.393126 -214.486664) (xy 94.405196 -214.461598) (xy 94.417134 -214.43823) (xy 94.233492 -214.089742)
			(xy 94.207584 -214.086186) (xy 94.18217 -214.082408) (xy 94.132718 -214.068466) (xy 94.085778 -214.047572)
			(xy 94.042323 -214.020159) (xy 94.00325 -213.986793) (xy 93.969371 -213.948166) (xy 93.941384 -213.905078)
			(xy 93.919871 -213.858419) (xy 93.905275 -213.809156) (xy 93.897899 -213.758308) (xy 93.89745 -213.732618)
			(xy 92.731082 -213.732618) (xy 92.731082 -213.732872) (xy 92.730559 -213.760689) (xy 92.721895 -213.815645)
			(xy 92.704804 -213.868589) (xy 92.692728 -213.893654) (xy 92.68079 -213.917022) (xy 92.864432 -214.26551)
			(xy 92.89034 -214.269066) (xy 92.915754 -214.272854) (xy 92.965209 -214.286788) (xy 93.012152 -214.307677)
			(xy 93.055611 -214.335087) (xy 93.094686 -214.368451) (xy 93.128567 -214.407078) (xy 93.156554 -214.450168)
			(xy 93.178066 -214.496829) (xy 93.192658 -214.546094) (xy 93.200028 -214.596944) (xy 93.200474 -214.622634)
			(xy 93.199975 -214.649321) (xy 93.19202 -214.7021) (xy 93.176288 -214.753103) (xy 93.15313 -214.801192)
			(xy 93.123063 -214.845292) (xy 93.086759 -214.884419) (xy 93.045029 -214.917697) (xy 92.998805 -214.944384)
			(xy 92.94912 -214.963884) (xy 92.897083 -214.975761) (xy 92.843858 -214.97975) (xy 92.790633 -214.975761)
			(xy 92.738596 -214.963884) (xy 92.688911 -214.944384) (xy 92.642687 -214.917697) (xy 92.600957 -214.884419)
			(xy 92.564653 -214.845292) (xy 92.534586 -214.801192) (xy 92.511428 -214.753103) (xy 92.495696 -214.7021)
			(xy 92.487741 -214.649321) (xy 92.487242 -214.622634) (xy 92.487242 -214.62238) (xy 92.487792 -214.594564)
			(xy 92.496446 -214.53961) (xy 92.513526 -214.486664) (xy 92.525596 -214.461598) (xy 92.537534 -214.43823)
			(xy 92.353892 -214.089742) (xy 92.327984 -214.086186) (xy 92.30257 -214.082408) (xy 92.253118 -214.068466)
			(xy 92.206178 -214.047572) (xy 92.162723 -214.020159) (xy 92.12365 -213.986793) (xy 92.089771 -213.948166)
			(xy 92.061784 -213.905078) (xy 92.040271 -213.858419) (xy 92.025675 -213.809156) (xy 92.018299 -213.758308)
			(xy 92.01785 -213.732618) (xy 90.851482 -213.732618) (xy 90.851482 -213.732872) (xy 90.850959 -213.760689)
			(xy 90.842295 -213.815645) (xy 90.825204 -213.868589) (xy 90.813128 -213.893654) (xy 90.80119 -213.917022)
			(xy 90.984832 -214.26551) (xy 91.01074 -214.269066) (xy 91.036154 -214.272854) (xy 91.085609 -214.286788)
			(xy 91.132552 -214.307677) (xy 91.176011 -214.335087) (xy 91.215086 -214.368451) (xy 91.248967 -214.407078)
			(xy 91.276954 -214.450168) (xy 91.298466 -214.496829) (xy 91.313058 -214.546094) (xy 91.320428 -214.596944)
			(xy 91.320874 -214.622634) (xy 91.320375 -214.649321) (xy 91.31242 -214.7021) (xy 91.296688 -214.753103)
			(xy 91.27353 -214.801192) (xy 91.243463 -214.845292) (xy 91.207159 -214.884419) (xy 91.165429 -214.917697)
			(xy 91.119205 -214.944384) (xy 91.06952 -214.963884) (xy 91.017483 -214.975761) (xy 90.964258 -214.97975)
			(xy 90.911033 -214.975761) (xy 90.858996 -214.963884) (xy 90.809311 -214.944384) (xy 90.763087 -214.917697)
			(xy 90.721357 -214.884419) (xy 90.685053 -214.845292) (xy 90.654986 -214.801192) (xy 90.631828 -214.753103)
			(xy 90.616096 -214.7021) (xy 90.608141 -214.649321) (xy 90.607642 -214.622634) (xy 90.607642 -214.62238)
			(xy 90.608192 -214.594564) (xy 90.616846 -214.53961) (xy 90.633926 -214.486664) (xy 90.645996 -214.461598)
			(xy 90.657934 -214.43823) (xy 90.474292 -214.089742) (xy 90.448384 -214.086186) (xy 90.42297 -214.082408)
			(xy 90.373518 -214.068466) (xy 90.326578 -214.047572) (xy 90.283123 -214.020159) (xy 90.24405 -213.986793)
			(xy 90.210171 -213.948166) (xy 90.182184 -213.905078) (xy 90.160671 -213.858419) (xy 90.146075 -213.809156)
			(xy 90.138699 -213.758308) (xy 90.13825 -213.732618) (xy 2.509012 -213.732618) (xy 2.509012 -215.436704)
			(xy 88.258396 -215.436704) (xy 88.258895 -215.410017) (xy 88.26685 -215.357238) (xy 88.282582 -215.306235)
			(xy 88.30574 -215.258146) (xy 88.335807 -215.214046) (xy 88.372111 -215.174919) (xy 88.413841 -215.141641)
			(xy 88.460065 -215.114954) (xy 88.50975 -215.095454) (xy 88.561787 -215.083577) (xy 88.615012 -215.079588)
			(xy 88.668237 -215.083577) (xy 88.720274 -215.095454) (xy 88.769959 -215.114954) (xy 88.816183 -215.141641)
			(xy 88.857913 -215.174919) (xy 88.894217 -215.214046) (xy 88.924284 -215.258146) (xy 88.947442 -215.306235)
			(xy 88.963174 -215.357238) (xy 88.971129 -215.410017) (xy 88.971628 -215.436704) (xy 89.198196 -215.436704)
			(xy 89.198581 -215.411033) (xy 89.205929 -215.36022) (xy 89.22049 -215.310987) (xy 89.241962 -215.264351)
			(xy 89.269901 -215.221277) (xy 89.303728 -215.182655) (xy 89.342746 -215.149285) (xy 89.386146 -215.121855)
			(xy 89.433031 -215.100934) (xy 89.482433 -215.086954) (xy 89.507822 -215.083136) (xy 89.532714 -215.079834)
			(xy 89.704672 -214.7824) (xy 89.69502 -214.759032) (xy 89.686439 -214.737327) (xy 89.674356 -214.692243)
			(xy 89.668242 -214.645971) (xy 89.667842 -214.622634) (xy 89.668341 -214.595947) (xy 89.676296 -214.543168)
			(xy 89.692028 -214.492165) (xy 89.715186 -214.444076) (xy 89.745253 -214.399976) (xy 89.781557 -214.360849)
			(xy 89.823287 -214.327571) (xy 89.869511 -214.300884) (xy 89.919196 -214.281384) (xy 89.971233 -214.269507)
			(xy 90.024458 -214.265518) (xy 90.077683 -214.269507) (xy 90.12972 -214.281384) (xy 90.179405 -214.300884)
			(xy 90.225629 -214.327571) (xy 90.267359 -214.360849) (xy 90.303663 -214.399976) (xy 90.33373 -214.444076)
			(xy 90.356888 -214.492165) (xy 90.37262 -214.543168) (xy 90.380575 -214.595947) (xy 90.381074 -214.622634)
			(xy 90.380664 -214.648303) (xy 90.373311 -214.699112) (xy 90.358749 -214.748341) (xy 90.337278 -214.794974)
			(xy 90.309342 -214.838045) (xy 90.275518 -214.876665) (xy 90.236505 -214.910036) (xy 90.193111 -214.937468)
			(xy 90.146231 -214.958393) (xy 90.096835 -214.97238) (xy 90.071448 -214.976202) (xy 90.046556 -214.979504)
			(xy 89.874598 -215.276938) (xy 89.88425 -215.300306) (xy 89.892811 -215.322019) (xy 89.904901 -215.367099)
			(xy 89.911024 -215.413368) (xy 89.911428 -215.436704) (xy 91.077796 -215.436704) (xy 91.078181 -215.411033)
			(xy 91.085529 -215.36022) (xy 91.10009 -215.310987) (xy 91.121562 -215.264351) (xy 91.149501 -215.221277)
			(xy 91.183328 -215.182655) (xy 91.222346 -215.149285) (xy 91.265746 -215.121855) (xy 91.312631 -215.100934)
			(xy 91.362033 -215.086954) (xy 91.387422 -215.083136) (xy 91.412314 -215.079834) (xy 91.584272 -214.7824)
			(xy 91.57462 -214.759032) (xy 91.566039 -214.737327) (xy 91.553956 -214.692243) (xy 91.547842 -214.645971)
			(xy 91.547442 -214.622634) (xy 91.547941 -214.595947) (xy 91.555896 -214.543168) (xy 91.571628 -214.492165)
			(xy 91.594786 -214.444076) (xy 91.624853 -214.399976) (xy 91.661157 -214.360849) (xy 91.702887 -214.327571)
			(xy 91.749111 -214.300884) (xy 91.798796 -214.281384) (xy 91.850833 -214.269507) (xy 91.904058 -214.265518)
			(xy 91.957283 -214.269507) (xy 92.00932 -214.281384) (xy 92.059005 -214.300884) (xy 92.105229 -214.327571)
			(xy 92.146959 -214.360849) (xy 92.183263 -214.399976) (xy 92.21333 -214.444076) (xy 92.236488 -214.492165)
			(xy 92.25222 -214.543168) (xy 92.260175 -214.595947) (xy 92.260674 -214.622634) (xy 92.260264 -214.648303)
			(xy 92.252911 -214.699112) (xy 92.238349 -214.748341) (xy 92.216878 -214.794974) (xy 92.188942 -214.838045)
			(xy 92.155118 -214.876665) (xy 92.116105 -214.910036) (xy 92.072711 -214.937468) (xy 92.025831 -214.958393)
			(xy 91.976435 -214.97238) (xy 91.951048 -214.976202) (xy 91.926156 -214.979504) (xy 91.754198 -215.276938)
			(xy 91.76385 -215.300306) (xy 91.772411 -215.322019) (xy 91.784501 -215.367099) (xy 91.790624 -215.413368)
			(xy 91.791028 -215.436704) (xy 92.957396 -215.436704) (xy 92.957781 -215.411033) (xy 92.965129 -215.36022)
			(xy 92.97969 -215.310987) (xy 93.001162 -215.264351) (xy 93.029101 -215.221277) (xy 93.062928 -215.182655)
			(xy 93.101946 -215.149285) (xy 93.145346 -215.121855) (xy 93.192231 -215.100934) (xy 93.241633 -215.086954)
			(xy 93.267022 -215.083136) (xy 93.291914 -215.079834) (xy 93.463872 -214.7824) (xy 93.45422 -214.759032)
			(xy 93.445639 -214.737327) (xy 93.433556 -214.692243) (xy 93.427442 -214.645971) (xy 93.427042 -214.622634)
			(xy 93.427541 -214.595947) (xy 93.435496 -214.543168) (xy 93.451228 -214.492165) (xy 93.474386 -214.444076)
			(xy 93.504453 -214.399976) (xy 93.540757 -214.360849) (xy 93.582487 -214.327571) (xy 93.628711 -214.300884)
			(xy 93.678396 -214.281384) (xy 93.730433 -214.269507) (xy 93.783658 -214.265518) (xy 93.836883 -214.269507)
			(xy 93.88892 -214.281384) (xy 93.938605 -214.300884) (xy 93.984829 -214.327571) (xy 94.026559 -214.360849)
			(xy 94.062863 -214.399976) (xy 94.09293 -214.444076) (xy 94.116088 -214.492165) (xy 94.13182 -214.543168)
			(xy 94.139775 -214.595947) (xy 94.140274 -214.622634) (xy 94.139864 -214.648303) (xy 94.132511 -214.699112)
			(xy 94.117949 -214.748341) (xy 94.096478 -214.794974) (xy 94.068542 -214.838045) (xy 94.034718 -214.876665)
			(xy 93.995705 -214.910036) (xy 93.952311 -214.937468) (xy 93.905431 -214.958393) (xy 93.856035 -214.97238)
			(xy 93.830648 -214.976202) (xy 93.805756 -214.979504) (xy 93.633798 -215.276938) (xy 93.64345 -215.300306)
			(xy 93.652011 -215.322019) (xy 93.664101 -215.367099) (xy 93.670224 -215.413368) (xy 93.670628 -215.436704)
			(xy 94.836996 -215.436704) (xy 94.837381 -215.411033) (xy 94.844729 -215.36022) (xy 94.85929 -215.310987)
			(xy 94.880762 -215.264351) (xy 94.908701 -215.221277) (xy 94.942528 -215.182655) (xy 94.981546 -215.149285)
			(xy 95.024946 -215.121855) (xy 95.071831 -215.100934) (xy 95.121233 -215.086954) (xy 95.146622 -215.083136)
			(xy 95.171514 -215.079834) (xy 95.343472 -214.7824) (xy 95.33382 -214.759032) (xy 95.325239 -214.737327)
			(xy 95.313156 -214.692243) (xy 95.307042 -214.645971) (xy 95.306642 -214.622634) (xy 95.307141 -214.595947)
			(xy 95.315096 -214.543168) (xy 95.330828 -214.492165) (xy 95.353986 -214.444076) (xy 95.384053 -214.399976)
			(xy 95.420357 -214.360849) (xy 95.462087 -214.327571) (xy 95.508311 -214.300884) (xy 95.557996 -214.281384)
			(xy 95.610033 -214.269507) (xy 95.663258 -214.265518) (xy 95.716483 -214.269507) (xy 95.76852 -214.281384)
			(xy 95.818205 -214.300884) (xy 95.864429 -214.327571) (xy 95.906159 -214.360849) (xy 95.942463 -214.399976)
			(xy 95.97253 -214.444076) (xy 95.995688 -214.492165) (xy 96.01142 -214.543168) (xy 96.019375 -214.595947)
			(xy 96.019874 -214.622634) (xy 96.019464 -214.648303) (xy 96.012111 -214.699112) (xy 95.997549 -214.748341)
			(xy 95.976078 -214.794974) (xy 95.948142 -214.838045) (xy 95.914318 -214.876665) (xy 95.875305 -214.910036)
			(xy 95.831911 -214.937468) (xy 95.785031 -214.958393) (xy 95.735635 -214.97238) (xy 95.710248 -214.976202)
			(xy 95.685356 -214.979504) (xy 95.513398 -215.276938) (xy 95.52305 -215.300306) (xy 95.531611 -215.322019)
			(xy 95.543701 -215.367099) (xy 95.549824 -215.413368) (xy 95.550228 -215.436704) (xy 96.716596 -215.436704)
			(xy 96.716981 -215.411033) (xy 96.724329 -215.36022) (xy 96.73889 -215.310987) (xy 96.760362 -215.264351)
			(xy 96.788301 -215.221277) (xy 96.822128 -215.182655) (xy 96.861146 -215.149285) (xy 96.904546 -215.121855)
			(xy 96.951431 -215.100934) (xy 97.000833 -215.086954) (xy 97.026222 -215.083136) (xy 97.051114 -215.079834)
			(xy 97.223072 -214.7824) (xy 97.21342 -214.759032) (xy 97.204839 -214.737327) (xy 97.192756 -214.692243)
			(xy 97.186642 -214.645971) (xy 97.186242 -214.622634) (xy 97.186741 -214.595947) (xy 97.194696 -214.543168)
			(xy 97.210428 -214.492165) (xy 97.233586 -214.444076) (xy 97.263653 -214.399976) (xy 97.299957 -214.360849)
			(xy 97.341687 -214.327571) (xy 97.387911 -214.300884) (xy 97.437596 -214.281384) (xy 97.489633 -214.269507)
			(xy 97.542858 -214.265518) (xy 97.596083 -214.269507) (xy 97.64812 -214.281384) (xy 97.697805 -214.300884)
			(xy 97.744029 -214.327571) (xy 97.785759 -214.360849) (xy 97.822063 -214.399976) (xy 97.85213 -214.444076)
			(xy 97.875288 -214.492165) (xy 97.89102 -214.543168) (xy 97.898975 -214.595947) (xy 97.899474 -214.622634)
			(xy 97.899064 -214.648303) (xy 97.891711 -214.699112) (xy 97.877149 -214.748341) (xy 97.855678 -214.794974)
			(xy 97.827742 -214.838045) (xy 97.793918 -214.876665) (xy 97.754905 -214.910036) (xy 97.711511 -214.937468)
			(xy 97.664631 -214.958393) (xy 97.615235 -214.97238) (xy 97.589848 -214.976202) (xy 97.564956 -214.979504)
			(xy 97.392998 -215.276938) (xy 97.40265 -215.300306) (xy 97.411211 -215.322019) (xy 97.423301 -215.367099)
			(xy 97.429424 -215.413368) (xy 97.429828 -215.436704) (xy 98.596196 -215.436704) (xy 98.596581 -215.411033)
			(xy 98.603929 -215.36022) (xy 98.61849 -215.310987) (xy 98.639962 -215.264351) (xy 98.667901 -215.221277)
			(xy 98.701728 -215.182655) (xy 98.740746 -215.149285) (xy 98.784146 -215.121855) (xy 98.831031 -215.100934)
			(xy 98.880433 -215.086954) (xy 98.905822 -215.083136) (xy 98.930714 -215.079834) (xy 99.102672 -214.7824)
			(xy 99.09302 -214.759032) (xy 99.084439 -214.737327) (xy 99.072356 -214.692243) (xy 99.066242 -214.645971)
			(xy 99.065842 -214.622634) (xy 99.066341 -214.595947) (xy 99.074296 -214.543168) (xy 99.090028 -214.492165)
			(xy 99.113186 -214.444076) (xy 99.143253 -214.399976) (xy 99.179557 -214.360849) (xy 99.221287 -214.327571)
			(xy 99.267511 -214.300884) (xy 99.317196 -214.281384) (xy 99.369233 -214.269507) (xy 99.422458 -214.265518)
			(xy 99.475683 -214.269507) (xy 99.52772 -214.281384) (xy 99.577405 -214.300884) (xy 99.623629 -214.327571)
			(xy 99.665359 -214.360849) (xy 99.701663 -214.399976) (xy 99.73173 -214.444076) (xy 99.754888 -214.492165)
			(xy 99.77062 -214.543168) (xy 99.778575 -214.595947) (xy 99.779074 -214.622634) (xy 99.778664 -214.648303)
			(xy 99.771311 -214.699112) (xy 99.756749 -214.748341) (xy 99.735278 -214.794974) (xy 99.707342 -214.838045)
			(xy 99.673518 -214.876665) (xy 99.634505 -214.910036) (xy 99.591111 -214.937468) (xy 99.544231 -214.958393)
			(xy 99.494835 -214.97238) (xy 99.469448 -214.976202) (xy 99.444556 -214.979504) (xy 99.272598 -215.276938)
			(xy 99.28225 -215.300306) (xy 99.290811 -215.322019) (xy 99.302901 -215.367099) (xy 99.309024 -215.413368)
			(xy 99.309428 -215.436704) (xy 100.475796 -215.436704) (xy 100.476181 -215.411033) (xy 100.483529 -215.36022)
			(xy 100.49809 -215.310987) (xy 100.519562 -215.264351) (xy 100.547501 -215.221277) (xy 100.581328 -215.182655)
			(xy 100.620346 -215.149285) (xy 100.663746 -215.121855) (xy 100.710631 -215.100934) (xy 100.760033 -215.086954)
			(xy 100.785422 -215.083136) (xy 100.810314 -215.079834) (xy 100.982272 -214.7824) (xy 100.97262 -214.759032)
			(xy 100.964039 -214.737327) (xy 100.951956 -214.692243) (xy 100.945842 -214.645971) (xy 100.945442 -214.622634)
			(xy 100.945941 -214.595947) (xy 100.953896 -214.543168) (xy 100.969628 -214.492165) (xy 100.992786 -214.444076)
			(xy 101.022853 -214.399976) (xy 101.059157 -214.360849) (xy 101.100887 -214.327571) (xy 101.147111 -214.300884)
			(xy 101.196796 -214.281384) (xy 101.248833 -214.269507) (xy 101.302058 -214.265518) (xy 101.355283 -214.269507)
			(xy 101.40732 -214.281384) (xy 101.457005 -214.300884) (xy 101.503229 -214.327571) (xy 101.544959 -214.360849)
			(xy 101.581263 -214.399976) (xy 101.61133 -214.444076) (xy 101.634488 -214.492165) (xy 101.65022 -214.543168)
			(xy 101.658175 -214.595947) (xy 101.658674 -214.622634) (xy 101.658264 -214.648303) (xy 101.650911 -214.699112)
			(xy 101.636349 -214.748341) (xy 101.614878 -214.794974) (xy 101.586942 -214.838045) (xy 101.553118 -214.876665)
			(xy 101.514105 -214.910036) (xy 101.470711 -214.937468) (xy 101.423831 -214.958393) (xy 101.374435 -214.97238)
			(xy 101.349048 -214.976202) (xy 101.324156 -214.979504) (xy 101.152198 -215.276938) (xy 101.16185 -215.300306)
			(xy 101.170411 -215.322019) (xy 101.182501 -215.367099) (xy 101.188624 -215.413368) (xy 101.189028 -215.436704)
			(xy 102.355396 -215.436704) (xy 102.355781 -215.411033) (xy 102.363129 -215.36022) (xy 102.37769 -215.310987)
			(xy 102.399162 -215.264351) (xy 102.427101 -215.221277) (xy 102.460928 -215.182655) (xy 102.499946 -215.149285)
			(xy 102.543346 -215.121855) (xy 102.590231 -215.100934) (xy 102.639633 -215.086954) (xy 102.665022 -215.083136)
			(xy 102.689914 -215.079834) (xy 102.861872 -214.7824) (xy 102.85222 -214.759032) (xy 102.843639 -214.737327)
			(xy 102.831556 -214.692243) (xy 102.825442 -214.645971) (xy 102.825042 -214.622634) (xy 102.825541 -214.595947)
			(xy 102.833496 -214.543168) (xy 102.849228 -214.492165) (xy 102.872386 -214.444076) (xy 102.902453 -214.399976)
			(xy 102.938757 -214.360849) (xy 102.980487 -214.327571) (xy 103.026711 -214.300884) (xy 103.076396 -214.281384)
			(xy 103.128433 -214.269507) (xy 103.181658 -214.265518) (xy 103.234883 -214.269507) (xy 103.28692 -214.281384)
			(xy 103.336605 -214.300884) (xy 103.382829 -214.327571) (xy 103.424559 -214.360849) (xy 103.460863 -214.399976)
			(xy 103.49093 -214.444076) (xy 103.514088 -214.492165) (xy 103.52982 -214.543168) (xy 103.537775 -214.595947)
			(xy 103.538274 -214.622634) (xy 103.537864 -214.648303) (xy 103.530511 -214.699112) (xy 103.515949 -214.748341)
			(xy 103.494478 -214.794974) (xy 103.466542 -214.838045) (xy 103.432718 -214.876665) (xy 103.393705 -214.910036)
			(xy 103.350311 -214.937468) (xy 103.303431 -214.958393) (xy 103.254035 -214.97238) (xy 103.228648 -214.976202)
			(xy 103.203756 -214.979504) (xy 103.031798 -215.276938) (xy 103.04145 -215.300306) (xy 103.050011 -215.322019)
			(xy 103.062101 -215.367099) (xy 103.068224 -215.413368) (xy 103.068628 -215.436704) (xy 104.234996 -215.436704)
			(xy 104.235381 -215.411033) (xy 104.242729 -215.36022) (xy 104.25729 -215.310987) (xy 104.278762 -215.264351)
			(xy 104.306701 -215.221277) (xy 104.340528 -215.182655) (xy 104.379546 -215.149285) (xy 104.422946 -215.121855)
			(xy 104.469831 -215.100934) (xy 104.519233 -215.086954) (xy 104.544622 -215.083136) (xy 104.569514 -215.079834)
			(xy 104.741472 -214.7824) (xy 104.73182 -214.759032) (xy 104.723239 -214.737327) (xy 104.711156 -214.692243)
			(xy 104.705042 -214.645971) (xy 104.704642 -214.622634) (xy 104.705141 -214.595947) (xy 104.713096 -214.543168)
			(xy 104.728828 -214.492165) (xy 104.751986 -214.444076) (xy 104.782053 -214.399976) (xy 104.818357 -214.360849)
			(xy 104.860087 -214.327571) (xy 104.906311 -214.300884) (xy 104.955996 -214.281384) (xy 105.008033 -214.269507)
			(xy 105.061258 -214.265518) (xy 105.114483 -214.269507) (xy 105.16652 -214.281384) (xy 105.216205 -214.300884)
			(xy 105.262429 -214.327571) (xy 105.304159 -214.360849) (xy 105.340463 -214.399976) (xy 105.37053 -214.444076)
			(xy 105.393688 -214.492165) (xy 105.40942 -214.543168) (xy 105.417375 -214.595947) (xy 105.417874 -214.622634)
			(xy 105.417464 -214.648303) (xy 105.410111 -214.699112) (xy 105.395549 -214.748341) (xy 105.374078 -214.794974)
			(xy 105.346142 -214.838045) (xy 105.312318 -214.876665) (xy 105.273305 -214.910036) (xy 105.229911 -214.937468)
			(xy 105.183031 -214.958393) (xy 105.133635 -214.97238) (xy 105.108248 -214.976202) (xy 105.083356 -214.979504)
			(xy 104.911398 -215.276938) (xy 104.92105 -215.300306) (xy 104.929611 -215.322019) (xy 104.941701 -215.367099)
			(xy 104.947824 -215.413368) (xy 104.948228 -215.436704) (xy 106.114596 -215.436704) (xy 106.114981 -215.411033)
			(xy 106.122329 -215.36022) (xy 106.13689 -215.310987) (xy 106.158362 -215.264351) (xy 106.186301 -215.221277)
			(xy 106.220128 -215.182655) (xy 106.259146 -215.149285) (xy 106.302546 -215.121855) (xy 106.349431 -215.100934)
			(xy 106.398833 -215.086954) (xy 106.424222 -215.083136) (xy 106.449114 -215.079834) (xy 106.621072 -214.7824)
			(xy 106.61142 -214.759032) (xy 106.602839 -214.737327) (xy 106.590756 -214.692243) (xy 106.584642 -214.645971)
			(xy 106.584242 -214.622634) (xy 106.584741 -214.595947) (xy 106.592696 -214.543168) (xy 106.608428 -214.492165)
			(xy 106.631586 -214.444076) (xy 106.661653 -214.399976) (xy 106.697957 -214.360849) (xy 106.739687 -214.327571)
			(xy 106.785911 -214.300884) (xy 106.835596 -214.281384) (xy 106.887633 -214.269507) (xy 106.940858 -214.265518)
			(xy 106.994083 -214.269507) (xy 107.04612 -214.281384) (xy 107.095805 -214.300884) (xy 107.142029 -214.327571)
			(xy 107.183759 -214.360849) (xy 107.220063 -214.399976) (xy 107.25013 -214.444076) (xy 107.273288 -214.492165)
			(xy 107.28902 -214.543168) (xy 107.296975 -214.595947) (xy 107.297474 -214.622634) (xy 107.297064 -214.648303)
			(xy 107.289711 -214.699112) (xy 107.275149 -214.748341) (xy 107.253678 -214.794974) (xy 107.225742 -214.838045)
			(xy 107.191918 -214.876665) (xy 107.152905 -214.910036) (xy 107.109511 -214.937468) (xy 107.062631 -214.958393)
			(xy 107.013235 -214.97238) (xy 106.987848 -214.976202) (xy 106.962956 -214.979504) (xy 106.790998 -215.276938)
			(xy 106.80065 -215.300306) (xy 106.809211 -215.322019) (xy 106.821301 -215.367099) (xy 106.827424 -215.413368)
			(xy 106.827828 -215.436704) (xy 107.994196 -215.436704) (xy 107.994581 -215.411033) (xy 108.001929 -215.36022)
			(xy 108.01649 -215.310987) (xy 108.037962 -215.264351) (xy 108.065901 -215.221277) (xy 108.099728 -215.182655)
			(xy 108.138746 -215.149285) (xy 108.182146 -215.121855) (xy 108.229031 -215.100934) (xy 108.278433 -215.086954)
			(xy 108.303822 -215.083136) (xy 108.328714 -215.079834) (xy 108.500672 -214.7824) (xy 108.49102 -214.759032)
			(xy 108.482439 -214.737327) (xy 108.470356 -214.692243) (xy 108.464242 -214.645971) (xy 108.463842 -214.622634)
			(xy 108.464341 -214.595947) (xy 108.472296 -214.543168) (xy 108.488028 -214.492165) (xy 108.511186 -214.444076)
			(xy 108.541253 -214.399976) (xy 108.577557 -214.360849) (xy 108.619287 -214.327571) (xy 108.665511 -214.300884)
			(xy 108.715196 -214.281384) (xy 108.767233 -214.269507) (xy 108.820458 -214.265518) (xy 108.873683 -214.269507)
			(xy 108.92572 -214.281384) (xy 108.975405 -214.300884) (xy 109.021629 -214.327571) (xy 109.063359 -214.360849)
			(xy 109.099663 -214.399976) (xy 109.12973 -214.444076) (xy 109.152888 -214.492165) (xy 109.16862 -214.543168)
			(xy 109.169112 -214.546434) (xy 110.34395 -214.546434) (xy 110.344449 -214.519747) (xy 110.352404 -214.466968)
			(xy 110.368136 -214.415965) (xy 110.391294 -214.367876) (xy 110.421361 -214.323776) (xy 110.457665 -214.284649)
			(xy 110.499395 -214.251371) (xy 110.545619 -214.224684) (xy 110.595304 -214.205184) (xy 110.647341 -214.193307)
			(xy 110.700566 -214.189318) (xy 110.753791 -214.193307) (xy 110.805828 -214.205184) (xy 110.855513 -214.224684)
			(xy 110.901737 -214.251371) (xy 110.943467 -214.284649) (xy 110.979771 -214.323776) (xy 111.009838 -214.367876)
			(xy 111.032996 -214.415965) (xy 111.048728 -214.466968) (xy 111.056683 -214.519747) (xy 111.057181 -214.5464)
			(xy 112.223635 -214.5464) (xy 112.227612 -214.493335) (xy 112.239452 -214.441456) (xy 112.258892 -214.39192)
			(xy 112.285497 -214.345835) (xy 112.318673 -214.304229) (xy 112.357679 -214.268033) (xy 112.401643 -214.238053)
			(xy 112.449585 -214.214961) (xy 112.500433 -214.199271) (xy 112.553051 -214.191334) (xy 112.579658 -214.190834)
			(xy 112.604627 -214.191287) (xy 112.654075 -214.198276) (xy 112.70206 -214.212107) (xy 112.747641 -214.232511)
			(xy 112.789922 -214.259085) (xy 112.828074 -214.291308) (xy 112.861347 -214.328548) (xy 112.875568 -214.349076)
			(xy 113.223548 -214.349076) (xy 113.237736 -214.328521) (xy 113.271006 -214.29127) (xy 113.30916 -214.259038)
			(xy 113.351446 -214.232459) (xy 113.397035 -214.212056) (xy 113.445029 -214.19823) (xy 113.494485 -214.191252)
			(xy 113.519458 -214.190834) (xy 113.546076 -214.191235) (xy 113.598717 -214.199164) (xy 113.649589 -214.214851)
			(xy 113.697554 -214.237945) (xy 113.741542 -214.26793) (xy 113.780568 -214.304137) (xy 113.813762 -214.345756)
			(xy 113.840382 -214.391858) (xy 113.859832 -214.441413) (xy 113.871679 -214.493314) (xy 113.875658 -214.5464)
			(xy 113.871679 -214.599486) (xy 113.859832 -214.651387) (xy 113.840382 -214.700942) (xy 113.813762 -214.747044)
			(xy 113.780568 -214.788663) (xy 113.741542 -214.82487) (xy 113.697554 -214.854855) (xy 113.649589 -214.877949)
			(xy 113.598717 -214.893636) (xy 113.546076 -214.901565) (xy 113.519458 -214.902034) (xy 113.494488 -214.901583)
			(xy 113.44504 -214.894596) (xy 113.397054 -214.880765) (xy 113.351473 -214.860362) (xy 113.309192 -214.833787)
			(xy 113.27104 -214.801563) (xy 113.237768 -214.764321) (xy 113.223548 -214.743792) (xy 112.875568 -214.743792)
			(xy 112.86136 -214.764332) (xy 112.828094 -214.801586) (xy 112.789944 -214.83382) (xy 112.747661 -214.860401)
			(xy 112.702076 -214.880806) (xy 112.654084 -214.894635) (xy 112.60463 -214.901615) (xy 112.579658 -214.902034)
			(xy 112.553051 -214.901466) (xy 112.500433 -214.893529) (xy 112.449585 -214.877839) (xy 112.401643 -214.854747)
			(xy 112.357679 -214.824767) (xy 112.318673 -214.788571) (xy 112.285497 -214.746965) (xy 112.258892 -214.70088)
			(xy 112.239452 -214.651344) (xy 112.227612 -214.599465) (xy 112.223635 -214.5464) (xy 111.057181 -214.5464)
			(xy 111.057182 -214.546434) (xy 111.057182 -214.546688) (xy 111.056628 -214.574504) (xy 111.047977 -214.629459)
			(xy 111.030898 -214.682404) (xy 111.018828 -214.70747) (xy 111.00689 -214.730838) (xy 111.190786 -215.07958)
			(xy 111.216694 -215.083136) (xy 111.242109 -215.08691) (xy 111.291563 -215.10085) (xy 111.338504 -215.121743)
			(xy 111.381961 -215.149156) (xy 111.421034 -215.182522) (xy 111.454914 -215.22115) (xy 111.4829 -215.26424)
			(xy 111.504413 -215.3109) (xy 111.519007 -215.360165) (xy 111.52638 -215.411014) (xy 111.526828 -215.436704)
			(xy 113.632996 -215.436704) (xy 113.633409 -215.411024) (xy 113.640776 -215.360196) (xy 113.655358 -215.31095)
			(xy 113.676852 -215.264305) (xy 113.704816 -215.221226) (xy 113.73867 -215.182603) (xy 113.777714 -215.149236)
			(xy 113.82114 -215.121815) (xy 113.868051 -215.100907) (xy 113.917476 -215.086944) (xy 113.942876 -215.083136)
			(xy 113.967514 -215.079834) (xy 114.139726 -214.7824) (xy 114.130074 -214.759032) (xy 114.12149 -214.737328)
			(xy 114.109409 -214.692244) (xy 114.103295 -214.645971) (xy 114.102896 -214.622634) (xy 114.103395 -214.595947)
			(xy 114.11135 -214.543168) (xy 114.127082 -214.492165) (xy 114.15024 -214.444076) (xy 114.180307 -214.399976)
			(xy 114.216611 -214.360849) (xy 114.258341 -214.327571) (xy 114.304565 -214.300884) (xy 114.35425 -214.281384)
			(xy 114.406287 -214.269507) (xy 114.459512 -214.265518) (xy 114.512737 -214.269507) (xy 114.564774 -214.281384)
			(xy 114.614459 -214.300884) (xy 114.660683 -214.327571) (xy 114.702413 -214.360849) (xy 114.738717 -214.399976)
			(xy 114.768784 -214.444076) (xy 114.791942 -214.492165) (xy 114.807674 -214.543168) (xy 114.815629 -214.595947)
			(xy 114.816128 -214.622634) (xy 114.815637 -214.648311) (xy 114.808279 -214.699135) (xy 114.793707 -214.748378)
			(xy 114.772221 -214.795022) (xy 114.744267 -214.8381) (xy 114.710422 -214.876723) (xy 114.671386 -214.910092)
			(xy 114.627967 -214.937515) (xy 114.581063 -214.958426) (xy 114.531645 -214.972392) (xy 114.506248 -214.976202)
			(xy 114.48161 -214.979504) (xy 114.309398 -215.276938) (xy 114.31905 -215.300306) (xy 114.327611 -215.322019)
			(xy 114.339701 -215.367099) (xy 114.345824 -215.413368) (xy 114.346228 -215.436704) (xy 115.512596 -215.436704)
			(xy 115.512981 -215.411033) (xy 115.520329 -215.36022) (xy 115.53489 -215.310987) (xy 115.556362 -215.264351)
			(xy 115.584301 -215.221277) (xy 115.618128 -215.182655) (xy 115.657146 -215.149285) (xy 115.700546 -215.121855)
			(xy 115.747431 -215.100934) (xy 115.796833 -215.086954) (xy 115.822222 -215.083136) (xy 115.847114 -215.079834)
			(xy 116.019072 -214.7824) (xy 116.00942 -214.759032) (xy 116.000839 -214.737327) (xy 115.988756 -214.692243)
			(xy 115.982642 -214.645971) (xy 115.982242 -214.622634) (xy 115.982741 -214.595947) (xy 115.990696 -214.543168)
			(xy 116.006428 -214.492165) (xy 116.029586 -214.444076) (xy 116.059653 -214.399976) (xy 116.095957 -214.360849)
			(xy 116.137687 -214.327571) (xy 116.183911 -214.300884) (xy 116.233596 -214.281384) (xy 116.285633 -214.269507)
			(xy 116.338858 -214.265518) (xy 116.392083 -214.269507) (xy 116.44412 -214.281384) (xy 116.493805 -214.300884)
			(xy 116.540029 -214.327571) (xy 116.581759 -214.360849) (xy 116.618063 -214.399976) (xy 116.64813 -214.444076)
			(xy 116.671288 -214.492165) (xy 116.68702 -214.543168) (xy 116.694975 -214.595947) (xy 116.695474 -214.622634)
			(xy 116.695064 -214.648303) (xy 116.687711 -214.699112) (xy 116.673149 -214.748341) (xy 116.651678 -214.794974)
			(xy 116.623742 -214.838045) (xy 116.589918 -214.876665) (xy 116.550905 -214.910036) (xy 116.507511 -214.937468)
			(xy 116.460631 -214.958393) (xy 116.411235 -214.97238) (xy 116.385848 -214.976202) (xy 116.360956 -214.979504)
			(xy 116.188998 -215.276938) (xy 116.19865 -215.300306) (xy 116.207211 -215.322019) (xy 116.219301 -215.367099)
			(xy 116.225424 -215.413368) (xy 116.225828 -215.436704) (xy 117.392196 -215.436704) (xy 117.392581 -215.411033)
			(xy 117.399929 -215.36022) (xy 117.41449 -215.310987) (xy 117.435962 -215.264351) (xy 117.463901 -215.221277)
			(xy 117.497728 -215.182655) (xy 117.536746 -215.149285) (xy 117.580146 -215.121855) (xy 117.627031 -215.100934)
			(xy 117.676433 -215.086954) (xy 117.701822 -215.083136) (xy 117.726714 -215.079834) (xy 117.898672 -214.7824)
			(xy 117.88902 -214.759032) (xy 117.880439 -214.737327) (xy 117.868356 -214.692243) (xy 117.862242 -214.645971)
			(xy 117.861842 -214.622634) (xy 117.862341 -214.595947) (xy 117.870296 -214.543168) (xy 117.886028 -214.492165)
			(xy 117.909186 -214.444076) (xy 117.939253 -214.399976) (xy 117.975557 -214.360849) (xy 118.017287 -214.327571)
			(xy 118.063511 -214.300884) (xy 118.113196 -214.281384) (xy 118.165233 -214.269507) (xy 118.218458 -214.265518)
			(xy 118.271683 -214.269507) (xy 118.32372 -214.281384) (xy 118.373405 -214.300884) (xy 118.419629 -214.327571)
			(xy 118.461359 -214.360849) (xy 118.497663 -214.399976) (xy 118.52773 -214.444076) (xy 118.550888 -214.492165)
			(xy 118.56662 -214.543168) (xy 118.574575 -214.595947) (xy 118.575074 -214.622634) (xy 118.574664 -214.648303)
			(xy 118.567311 -214.699112) (xy 118.552749 -214.748341) (xy 118.531278 -214.794974) (xy 118.503342 -214.838045)
			(xy 118.469518 -214.876665) (xy 118.430505 -214.910036) (xy 118.387111 -214.937468) (xy 118.340231 -214.958393)
			(xy 118.290835 -214.97238) (xy 118.265448 -214.976202) (xy 118.240556 -214.979504) (xy 118.068598 -215.276938)
			(xy 118.07825 -215.300306) (xy 118.086811 -215.322019) (xy 118.098901 -215.367099) (xy 118.105024 -215.413368)
			(xy 118.105428 -215.436704) (xy 119.271796 -215.436704) (xy 119.272181 -215.411033) (xy 119.279529 -215.36022)
			(xy 119.29409 -215.310987) (xy 119.315562 -215.264351) (xy 119.343501 -215.221277) (xy 119.377328 -215.182655)
			(xy 119.416346 -215.149285) (xy 119.459746 -215.121855) (xy 119.506631 -215.100934) (xy 119.556033 -215.086954)
			(xy 119.581422 -215.083136) (xy 119.606314 -215.079834) (xy 119.778272 -214.7824) (xy 119.76862 -214.759032)
			(xy 119.760039 -214.737327) (xy 119.747956 -214.692243) (xy 119.741842 -214.645971) (xy 119.741442 -214.622634)
			(xy 119.741941 -214.595947) (xy 119.749896 -214.543168) (xy 119.765628 -214.492165) (xy 119.788786 -214.444076)
			(xy 119.818853 -214.399976) (xy 119.855157 -214.360849) (xy 119.896887 -214.327571) (xy 119.943111 -214.300884)
			(xy 119.992796 -214.281384) (xy 120.044833 -214.269507) (xy 120.098058 -214.265518) (xy 120.151283 -214.269507)
			(xy 120.20332 -214.281384) (xy 120.253005 -214.300884) (xy 120.299229 -214.327571) (xy 120.340959 -214.360849)
			(xy 120.377263 -214.399976) (xy 120.40733 -214.444076) (xy 120.430488 -214.492165) (xy 120.44622 -214.543168)
			(xy 120.454175 -214.595947) (xy 120.454674 -214.622634) (xy 120.454264 -214.648303) (xy 120.446911 -214.699112)
			(xy 120.432349 -214.748341) (xy 120.410878 -214.794974) (xy 120.382942 -214.838045) (xy 120.349118 -214.876665)
			(xy 120.310105 -214.910036) (xy 120.266711 -214.937468) (xy 120.219831 -214.958393) (xy 120.170435 -214.97238)
			(xy 120.145048 -214.976202) (xy 120.120156 -214.979504) (xy 119.948198 -215.276938) (xy 119.95785 -215.300306)
			(xy 119.966411 -215.322019) (xy 119.978501 -215.367099) (xy 119.984624 -215.413368) (xy 119.985028 -215.436704)
			(xy 121.151396 -215.436704) (xy 121.151781 -215.411033) (xy 121.159129 -215.36022) (xy 121.17369 -215.310987)
			(xy 121.195162 -215.264351) (xy 121.223101 -215.221277) (xy 121.256928 -215.182655) (xy 121.295946 -215.149285)
			(xy 121.339346 -215.121855) (xy 121.386231 -215.100934) (xy 121.435633 -215.086954) (xy 121.461022 -215.083136)
			(xy 121.485914 -215.079834) (xy 121.657872 -214.7824) (xy 121.64822 -214.759032) (xy 121.639639 -214.737327)
			(xy 121.627556 -214.692243) (xy 121.621442 -214.645971) (xy 121.621042 -214.622634) (xy 121.621541 -214.595947)
			(xy 121.629496 -214.543168) (xy 121.645228 -214.492165) (xy 121.668386 -214.444076) (xy 121.698453 -214.399976)
			(xy 121.734757 -214.360849) (xy 121.776487 -214.327571) (xy 121.822711 -214.300884) (xy 121.872396 -214.281384)
			(xy 121.924433 -214.269507) (xy 121.977658 -214.265518) (xy 122.030883 -214.269507) (xy 122.08292 -214.281384)
			(xy 122.132605 -214.300884) (xy 122.178829 -214.327571) (xy 122.220559 -214.360849) (xy 122.256863 -214.399976)
			(xy 122.28693 -214.444076) (xy 122.310088 -214.492165) (xy 122.32582 -214.543168) (xy 122.333775 -214.595947)
			(xy 122.334274 -214.622634) (xy 122.333864 -214.648303) (xy 122.326511 -214.699112) (xy 122.311949 -214.748341)
			(xy 122.290478 -214.794974) (xy 122.262542 -214.838045) (xy 122.228718 -214.876665) (xy 122.189705 -214.910036)
			(xy 122.146311 -214.937468) (xy 122.099431 -214.958393) (xy 122.050035 -214.97238) (xy 122.024648 -214.976202)
			(xy 121.999756 -214.979504) (xy 121.827798 -215.276938) (xy 121.83745 -215.300306) (xy 121.846011 -215.322019)
			(xy 121.858101 -215.367099) (xy 121.864224 -215.413368) (xy 121.864628 -215.436704) (xy 123.030996 -215.436704)
			(xy 123.031381 -215.411033) (xy 123.038729 -215.36022) (xy 123.05329 -215.310987) (xy 123.074762 -215.264351)
			(xy 123.102701 -215.221277) (xy 123.136528 -215.182655) (xy 123.175546 -215.149285) (xy 123.218946 -215.121855)
			(xy 123.265831 -215.100934) (xy 123.315233 -215.086954) (xy 123.340622 -215.083136) (xy 123.365514 -215.079834)
			(xy 123.537472 -214.7824) (xy 123.52782 -214.759032) (xy 123.519239 -214.737327) (xy 123.507156 -214.692243)
			(xy 123.501042 -214.645971) (xy 123.500642 -214.622634) (xy 123.501141 -214.595947) (xy 123.509096 -214.543168)
			(xy 123.524828 -214.492165) (xy 123.547986 -214.444076) (xy 123.578053 -214.399976) (xy 123.614357 -214.360849)
			(xy 123.656087 -214.327571) (xy 123.702311 -214.300884) (xy 123.751996 -214.281384) (xy 123.804033 -214.269507)
			(xy 123.857258 -214.265518) (xy 123.910483 -214.269507) (xy 123.96252 -214.281384) (xy 124.012205 -214.300884)
			(xy 124.058429 -214.327571) (xy 124.100159 -214.360849) (xy 124.136463 -214.399976) (xy 124.16653 -214.444076)
			(xy 124.189688 -214.492165) (xy 124.20542 -214.543168) (xy 124.213375 -214.595947) (xy 124.213874 -214.622634)
			(xy 124.213464 -214.648303) (xy 124.206111 -214.699112) (xy 124.191549 -214.748341) (xy 124.170078 -214.794974)
			(xy 124.142142 -214.838045) (xy 124.108318 -214.876665) (xy 124.069305 -214.910036) (xy 124.025911 -214.937468)
			(xy 123.979031 -214.958393) (xy 123.929635 -214.97238) (xy 123.904248 -214.976202) (xy 123.879356 -214.979504)
			(xy 123.707398 -215.276938) (xy 123.71705 -215.300306) (xy 123.725611 -215.322019) (xy 123.737701 -215.367099)
			(xy 123.743824 -215.413368) (xy 123.744228 -215.436704) (xy 124.910596 -215.436704) (xy 124.910981 -215.411033)
			(xy 124.918329 -215.36022) (xy 124.93289 -215.310987) (xy 124.954362 -215.264351) (xy 124.982301 -215.221277)
			(xy 125.016128 -215.182655) (xy 125.055146 -215.149285) (xy 125.098546 -215.121855) (xy 125.145431 -215.100934)
			(xy 125.194833 -215.086954) (xy 125.220222 -215.083136) (xy 125.245114 -215.079834) (xy 125.417072 -214.7824)
			(xy 125.40742 -214.759032) (xy 125.398839 -214.737327) (xy 125.386756 -214.692243) (xy 125.380642 -214.645971)
			(xy 125.380242 -214.622634) (xy 125.380741 -214.595947) (xy 125.388696 -214.543168) (xy 125.404428 -214.492165)
			(xy 125.427586 -214.444076) (xy 125.457653 -214.399976) (xy 125.493957 -214.360849) (xy 125.535687 -214.327571)
			(xy 125.581911 -214.300884) (xy 125.631596 -214.281384) (xy 125.683633 -214.269507) (xy 125.736858 -214.265518)
			(xy 125.790083 -214.269507) (xy 125.84212 -214.281384) (xy 125.891805 -214.300884) (xy 125.938029 -214.327571)
			(xy 125.979759 -214.360849) (xy 126.016063 -214.399976) (xy 126.04613 -214.444076) (xy 126.069288 -214.492165)
			(xy 126.08502 -214.543168) (xy 126.092975 -214.595947) (xy 126.093474 -214.622634) (xy 126.093064 -214.648303)
			(xy 126.085711 -214.699112) (xy 126.071149 -214.748341) (xy 126.049678 -214.794974) (xy 126.021742 -214.838045)
			(xy 125.987918 -214.876665) (xy 125.948905 -214.910036) (xy 125.905511 -214.937468) (xy 125.858631 -214.958393)
			(xy 125.809235 -214.97238) (xy 125.783848 -214.976202) (xy 125.758956 -214.979504) (xy 125.586998 -215.276938)
			(xy 125.59665 -215.300306) (xy 125.605211 -215.322019) (xy 125.617301 -215.367099) (xy 125.623424 -215.413368)
			(xy 125.623828 -215.436704) (xy 126.790196 -215.436704) (xy 126.790581 -215.411033) (xy 126.797929 -215.36022)
			(xy 126.81249 -215.310987) (xy 126.833962 -215.264351) (xy 126.861901 -215.221277) (xy 126.895728 -215.182655)
			(xy 126.934746 -215.149285) (xy 126.978146 -215.121855) (xy 127.025031 -215.100934) (xy 127.074433 -215.086954)
			(xy 127.099822 -215.083136) (xy 127.124714 -215.079834) (xy 127.296672 -214.7824) (xy 127.28702 -214.759032)
			(xy 127.278439 -214.737327) (xy 127.266356 -214.692243) (xy 127.260242 -214.645971) (xy 127.259842 -214.622634)
			(xy 127.260341 -214.595947) (xy 127.268296 -214.543168) (xy 127.284028 -214.492165) (xy 127.307186 -214.444076)
			(xy 127.337253 -214.399976) (xy 127.373557 -214.360849) (xy 127.415287 -214.327571) (xy 127.461511 -214.300884)
			(xy 127.511196 -214.281384) (xy 127.563233 -214.269507) (xy 127.616458 -214.265518) (xy 127.669683 -214.269507)
			(xy 127.72172 -214.281384) (xy 127.771405 -214.300884) (xy 127.817629 -214.327571) (xy 127.859359 -214.360849)
			(xy 127.895663 -214.399976) (xy 127.92573 -214.444076) (xy 127.948888 -214.492165) (xy 127.96462 -214.543168)
			(xy 127.972575 -214.595947) (xy 127.973074 -214.622634) (xy 127.972664 -214.648303) (xy 127.965311 -214.699112)
			(xy 127.950749 -214.748341) (xy 127.929278 -214.794974) (xy 127.901342 -214.838045) (xy 127.867518 -214.876665)
			(xy 127.828505 -214.910036) (xy 127.785111 -214.937468) (xy 127.738231 -214.958393) (xy 127.688835 -214.97238)
			(xy 127.663448 -214.976202) (xy 127.638556 -214.979504) (xy 127.466598 -215.276938) (xy 127.47625 -215.300306)
			(xy 127.484811 -215.322019) (xy 127.496901 -215.367099) (xy 127.503024 -215.413368) (xy 127.503428 -215.436704)
			(xy 128.669796 -215.436704) (xy 128.670181 -215.411033) (xy 128.677529 -215.36022) (xy 128.69209 -215.310987)
			(xy 128.713562 -215.264351) (xy 128.741501 -215.221277) (xy 128.775328 -215.182655) (xy 128.814346 -215.149285)
			(xy 128.857746 -215.121855) (xy 128.904631 -215.100934) (xy 128.954033 -215.086954) (xy 128.979422 -215.083136)
			(xy 129.004314 -215.079834) (xy 129.176272 -214.7824) (xy 129.16662 -214.759032) (xy 129.158039 -214.737327)
			(xy 129.145956 -214.692243) (xy 129.139842 -214.645971) (xy 129.139442 -214.622634) (xy 129.139941 -214.595947)
			(xy 129.147896 -214.543168) (xy 129.163628 -214.492165) (xy 129.186786 -214.444076) (xy 129.216853 -214.399976)
			(xy 129.253157 -214.360849) (xy 129.294887 -214.327571) (xy 129.341111 -214.300884) (xy 129.390796 -214.281384)
			(xy 129.442833 -214.269507) (xy 129.496058 -214.265518) (xy 129.549283 -214.269507) (xy 129.60132 -214.281384)
			(xy 129.651005 -214.300884) (xy 129.697229 -214.327571) (xy 129.738959 -214.360849) (xy 129.775263 -214.399976)
			(xy 129.80533 -214.444076) (xy 129.828488 -214.492165) (xy 129.84422 -214.543168) (xy 129.852175 -214.595947)
			(xy 129.852674 -214.622634) (xy 129.852264 -214.648303) (xy 129.844911 -214.699112) (xy 129.830349 -214.748341)
			(xy 129.808878 -214.794974) (xy 129.780942 -214.838045) (xy 129.747118 -214.876665) (xy 129.708105 -214.910036)
			(xy 129.664711 -214.937468) (xy 129.617831 -214.958393) (xy 129.568435 -214.97238) (xy 129.543048 -214.976202)
			(xy 129.518156 -214.979504) (xy 129.346198 -215.276938) (xy 129.35585 -215.300306) (xy 129.364411 -215.322019)
			(xy 129.376501 -215.367099) (xy 129.382624 -215.413368) (xy 129.383028 -215.436704) (xy 130.549396 -215.436704)
			(xy 130.549781 -215.411033) (xy 130.557129 -215.36022) (xy 130.57169 -215.310987) (xy 130.593162 -215.264351)
			(xy 130.621101 -215.221277) (xy 130.654928 -215.182655) (xy 130.693946 -215.149285) (xy 130.737346 -215.121855)
			(xy 130.784231 -215.100934) (xy 130.833633 -215.086954) (xy 130.859022 -215.083136) (xy 130.883914 -215.079834)
			(xy 131.055872 -214.7824) (xy 131.04622 -214.759032) (xy 131.037639 -214.737327) (xy 131.025556 -214.692243)
			(xy 131.019442 -214.645971) (xy 131.019042 -214.622634) (xy 131.019541 -214.595947) (xy 131.027496 -214.543168)
			(xy 131.043228 -214.492165) (xy 131.066386 -214.444076) (xy 131.096453 -214.399976) (xy 131.132757 -214.360849)
			(xy 131.174487 -214.327571) (xy 131.220711 -214.300884) (xy 131.270396 -214.281384) (xy 131.322433 -214.269507)
			(xy 131.375658 -214.265518) (xy 131.428883 -214.269507) (xy 131.48092 -214.281384) (xy 131.530605 -214.300884)
			(xy 131.576829 -214.327571) (xy 131.618559 -214.360849) (xy 131.654863 -214.399976) (xy 131.68493 -214.444076)
			(xy 131.708088 -214.492165) (xy 131.72382 -214.543168) (xy 131.731775 -214.595947) (xy 131.732274 -214.622634)
			(xy 131.731864 -214.648303) (xy 131.724511 -214.699112) (xy 131.709949 -214.748341) (xy 131.688478 -214.794974)
			(xy 131.660542 -214.838045) (xy 131.626718 -214.876665) (xy 131.587705 -214.910036) (xy 131.544311 -214.937468)
			(xy 131.497431 -214.958393) (xy 131.448035 -214.97238) (xy 131.422648 -214.976202) (xy 131.397756 -214.979504)
			(xy 131.225798 -215.276938) (xy 131.23545 -215.300306) (xy 131.244011 -215.322019) (xy 131.256101 -215.367099)
			(xy 131.262224 -215.413368) (xy 131.262628 -215.436704) (xy 132.428996 -215.436704) (xy 132.429381 -215.411033)
			(xy 132.436729 -215.36022) (xy 132.45129 -215.310987) (xy 132.472762 -215.264351) (xy 132.500701 -215.221277)
			(xy 132.534528 -215.182655) (xy 132.573546 -215.149285) (xy 132.616946 -215.121855) (xy 132.663831 -215.100934)
			(xy 132.713233 -215.086954) (xy 132.738622 -215.083136) (xy 132.763514 -215.079834) (xy 132.935472 -214.7824)
			(xy 132.92582 -214.759032) (xy 132.917239 -214.737327) (xy 132.905156 -214.692243) (xy 132.899042 -214.645971)
			(xy 132.898642 -214.622634) (xy 132.899141 -214.595947) (xy 132.907096 -214.543168) (xy 132.922828 -214.492165)
			(xy 132.945986 -214.444076) (xy 132.976053 -214.399976) (xy 133.012357 -214.360849) (xy 133.054087 -214.327571)
			(xy 133.100311 -214.300884) (xy 133.149996 -214.281384) (xy 133.202033 -214.269507) (xy 133.255258 -214.265518)
			(xy 133.308483 -214.269507) (xy 133.36052 -214.281384) (xy 133.410205 -214.300884) (xy 133.456429 -214.327571)
			(xy 133.498159 -214.360849) (xy 133.534463 -214.399976) (xy 133.56453 -214.444076) (xy 133.587688 -214.492165)
			(xy 133.60342 -214.543168) (xy 133.603912 -214.546434) (xy 134.779512 -214.546434) (xy 134.780009 -214.519823)
			(xy 134.787942 -214.467195) (xy 134.803629 -214.416337) (xy 134.826722 -214.368385) (xy 134.856703 -214.32441)
			(xy 134.892904 -214.285395) (xy 134.934515 -214.252212) (xy 134.980607 -214.2256) (xy 135.03015 -214.206156)
			(xy 135.082038 -214.194313) (xy 135.135112 -214.190336) (xy 135.188186 -214.194313) (xy 135.240074 -214.206156)
			(xy 135.289617 -214.2256) (xy 135.335709 -214.252212) (xy 135.37732 -214.285395) (xy 135.413521 -214.32441)
			(xy 135.443502 -214.368385) (xy 135.466595 -214.416337) (xy 135.482282 -214.467195) (xy 135.490215 -214.519823)
			(xy 135.490712 -214.546434) (xy 135.490091 -214.57588) (xy 135.480393 -214.633967) (xy 135.461267 -214.689667)
			(xy 135.447786 -214.715852) (xy 135.641588 -215.082882) (xy 135.66751 -215.086051) (xy 135.718106 -215.098984)
			(xy 135.766267 -215.119175) (xy 135.81096 -215.146188) (xy 135.851225 -215.179443) (xy 135.886196 -215.218227)
			(xy 135.915122 -215.261707) (xy 135.937383 -215.308947) (xy 135.952499 -215.358934) (xy 135.960146 -215.410593)
			(xy 135.960612 -215.436704) (xy 336.198464 -215.436704) (xy 336.198963 -215.410017) (xy 336.206918 -215.357238)
			(xy 336.22265 -215.306235) (xy 336.245808 -215.258146) (xy 336.275875 -215.214046) (xy 336.312179 -215.174919)
			(xy 336.353909 -215.141641) (xy 336.400133 -215.114954) (xy 336.449818 -215.095454) (xy 336.501855 -215.083577)
			(xy 336.55508 -215.079588) (xy 336.608305 -215.083577) (xy 336.660342 -215.095454) (xy 336.710027 -215.114954)
			(xy 336.756251 -215.141641) (xy 336.797981 -215.174919) (xy 336.834285 -215.214046) (xy 336.864352 -215.258146)
			(xy 336.88751 -215.306235) (xy 336.903242 -215.357238) (xy 336.911197 -215.410017) (xy 336.911696 -215.436704)
			(xy 337.138264 -215.436704) (xy 337.138676 -215.411034) (xy 337.146024 -215.360224) (xy 337.160584 -215.310993)
			(xy 337.182053 -215.264359) (xy 337.209989 -215.221286) (xy 337.243813 -215.182665) (xy 337.282827 -215.149294)
			(xy 337.326223 -215.121863) (xy 337.373105 -215.10094) (xy 337.422502 -215.086956) (xy 337.44789 -215.083136)
			(xy 337.472782 -215.079834) (xy 337.64474 -214.7824) (xy 337.635088 -214.759032) (xy 337.626505 -214.737327)
			(xy 337.614424 -214.692243) (xy 337.60831 -214.645971) (xy 337.60791 -214.622634) (xy 337.608409 -214.595947)
			(xy 337.616364 -214.543168) (xy 337.632096 -214.492165) (xy 337.655254 -214.444076) (xy 337.685321 -214.399976)
			(xy 337.721625 -214.360849) (xy 337.763355 -214.327571) (xy 337.809579 -214.300884) (xy 337.859264 -214.281384)
			(xy 337.911301 -214.269507) (xy 337.964526 -214.265518) (xy 338.017751 -214.269507) (xy 338.069788 -214.281384)
			(xy 338.119473 -214.300884) (xy 338.165697 -214.327571) (xy 338.207427 -214.360849) (xy 338.243731 -214.399976)
			(xy 338.273798 -214.444076) (xy 338.296956 -214.492165) (xy 338.312688 -214.543168) (xy 338.320643 -214.595947)
			(xy 338.321142 -214.622634) (xy 338.32076 -214.648304) (xy 338.313406 -214.699116) (xy 338.298842 -214.748347)
			(xy 338.277369 -214.794981) (xy 338.24943 -214.838054) (xy 338.215602 -214.876675) (xy 338.176586 -214.910045)
			(xy 338.133188 -214.937475) (xy 338.086304 -214.958398) (xy 338.036904 -214.972382) (xy 338.011516 -214.976202)
			(xy 337.986624 -214.979504) (xy 337.814666 -215.276938) (xy 337.824318 -215.300306) (xy 337.832883 -215.322018)
			(xy 337.844971 -215.367098) (xy 337.851092 -215.413368) (xy 337.851496 -215.436704) (xy 339.017864 -215.436704)
			(xy 339.018276 -215.411034) (xy 339.025624 -215.360224) (xy 339.040184 -215.310993) (xy 339.061653 -215.264359)
			(xy 339.089589 -215.221286) (xy 339.123413 -215.182665) (xy 339.162427 -215.149294) (xy 339.205823 -215.121863)
			(xy 339.252705 -215.10094) (xy 339.302102 -215.086956) (xy 339.32749 -215.083136) (xy 339.352382 -215.079834)
			(xy 339.52434 -214.7824) (xy 339.514688 -214.759032) (xy 339.506105 -214.737327) (xy 339.494024 -214.692243)
			(xy 339.48791 -214.645971) (xy 339.48751 -214.622634) (xy 339.488009 -214.595947) (xy 339.495964 -214.543168)
			(xy 339.511696 -214.492165) (xy 339.534854 -214.444076) (xy 339.564921 -214.399976) (xy 339.601225 -214.360849)
			(xy 339.642955 -214.327571) (xy 339.689179 -214.300884) (xy 339.738864 -214.281384) (xy 339.790901 -214.269507)
			(xy 339.844126 -214.265518) (xy 339.897351 -214.269507) (xy 339.949388 -214.281384) (xy 339.999073 -214.300884)
			(xy 340.045297 -214.327571) (xy 340.087027 -214.360849) (xy 340.123331 -214.399976) (xy 340.153398 -214.444076)
			(xy 340.176556 -214.492165) (xy 340.192288 -214.543168) (xy 340.200243 -214.595947) (xy 340.200742 -214.622634)
			(xy 340.20036 -214.648304) (xy 340.193006 -214.699116) (xy 340.178442 -214.748347) (xy 340.156969 -214.794981)
			(xy 340.12903 -214.838054) (xy 340.095202 -214.876675) (xy 340.056186 -214.910045) (xy 340.012788 -214.937475)
			(xy 339.965904 -214.958398) (xy 339.916504 -214.972382) (xy 339.891116 -214.976202) (xy 339.866224 -214.979504)
			(xy 339.694266 -215.276938) (xy 339.703918 -215.300306) (xy 339.712483 -215.322018) (xy 339.724571 -215.367098)
			(xy 339.730692 -215.413368) (xy 339.731096 -215.436704) (xy 340.897464 -215.436704) (xy 340.897876 -215.411034)
			(xy 340.905224 -215.360224) (xy 340.919784 -215.310993) (xy 340.941253 -215.264359) (xy 340.969189 -215.221286)
			(xy 341.003013 -215.182665) (xy 341.042027 -215.149294) (xy 341.085423 -215.121863) (xy 341.132305 -215.10094)
			(xy 341.181702 -215.086956) (xy 341.20709 -215.083136) (xy 341.231982 -215.079834) (xy 341.40394 -214.7824)
			(xy 341.394288 -214.759032) (xy 341.385705 -214.737327) (xy 341.373624 -214.692243) (xy 341.36751 -214.645971)
			(xy 341.36711 -214.622634) (xy 341.367609 -214.595947) (xy 341.375564 -214.543168) (xy 341.391296 -214.492165)
			(xy 341.414454 -214.444076) (xy 341.444521 -214.399976) (xy 341.480825 -214.360849) (xy 341.522555 -214.327571)
			(xy 341.568779 -214.300884) (xy 341.618464 -214.281384) (xy 341.670501 -214.269507) (xy 341.723726 -214.265518)
			(xy 341.776951 -214.269507) (xy 341.828988 -214.281384) (xy 341.878673 -214.300884) (xy 341.924897 -214.327571)
			(xy 341.966627 -214.360849) (xy 342.002931 -214.399976) (xy 342.032998 -214.444076) (xy 342.056156 -214.492165)
			(xy 342.071888 -214.543168) (xy 342.079843 -214.595947) (xy 342.080342 -214.622634) (xy 342.07996 -214.648304)
			(xy 342.072606 -214.699116) (xy 342.058042 -214.748347) (xy 342.036569 -214.794981) (xy 342.00863 -214.838054)
			(xy 341.974802 -214.876675) (xy 341.935786 -214.910045) (xy 341.892388 -214.937475) (xy 341.845504 -214.958398)
			(xy 341.796104 -214.972382) (xy 341.770716 -214.976202) (xy 341.745824 -214.979504) (xy 341.573866 -215.276938)
			(xy 341.583518 -215.300306) (xy 341.592083 -215.322018) (xy 341.604171 -215.367098) (xy 341.610292 -215.413368)
			(xy 341.610696 -215.436704) (xy 342.777064 -215.436704) (xy 342.777476 -215.411034) (xy 342.784824 -215.360224)
			(xy 342.799384 -215.310993) (xy 342.820853 -215.264359) (xy 342.848789 -215.221286) (xy 342.882613 -215.182665)
			(xy 342.921627 -215.149294) (xy 342.965023 -215.121863) (xy 343.011905 -215.10094) (xy 343.061302 -215.086956)
			(xy 343.08669 -215.083136) (xy 343.111582 -215.079834) (xy 343.28354 -214.7824) (xy 343.273888 -214.759032)
			(xy 343.265305 -214.737327) (xy 343.253224 -214.692243) (xy 343.24711 -214.645971) (xy 343.24671 -214.622634)
			(xy 343.247209 -214.595947) (xy 343.255164 -214.543168) (xy 343.270896 -214.492165) (xy 343.294054 -214.444076)
			(xy 343.324121 -214.399976) (xy 343.360425 -214.360849) (xy 343.402155 -214.327571) (xy 343.448379 -214.300884)
			(xy 343.498064 -214.281384) (xy 343.550101 -214.269507) (xy 343.603326 -214.265518) (xy 343.656551 -214.269507)
			(xy 343.708588 -214.281384) (xy 343.758273 -214.300884) (xy 343.804497 -214.327571) (xy 343.846227 -214.360849)
			(xy 343.882531 -214.399976) (xy 343.912598 -214.444076) (xy 343.935756 -214.492165) (xy 343.951488 -214.543168)
			(xy 343.959443 -214.595947) (xy 343.959942 -214.622634) (xy 343.95956 -214.648304) (xy 343.952206 -214.699116)
			(xy 343.937642 -214.748347) (xy 343.916169 -214.794981) (xy 343.88823 -214.838054) (xy 343.854402 -214.876675)
			(xy 343.815386 -214.910045) (xy 343.771988 -214.937475) (xy 343.725104 -214.958398) (xy 343.675704 -214.972382)
			(xy 343.650316 -214.976202) (xy 343.625424 -214.979504) (xy 343.453466 -215.276938) (xy 343.463118 -215.300306)
			(xy 343.471683 -215.322018) (xy 343.483771 -215.367098) (xy 343.489892 -215.413368) (xy 343.490296 -215.436704)
			(xy 344.656664 -215.436704) (xy 344.657076 -215.411034) (xy 344.664424 -215.360224) (xy 344.678984 -215.310993)
			(xy 344.700453 -215.264359) (xy 344.728389 -215.221286) (xy 344.762213 -215.182665) (xy 344.801227 -215.149294)
			(xy 344.844623 -215.121863) (xy 344.891505 -215.10094) (xy 344.940902 -215.086956) (xy 344.96629 -215.083136)
			(xy 344.991182 -215.079834) (xy 345.16314 -214.7824) (xy 345.153488 -214.759032) (xy 345.144905 -214.737327)
			(xy 345.132824 -214.692243) (xy 345.12671 -214.645971) (xy 345.12631 -214.622634) (xy 345.126809 -214.595947)
			(xy 345.134764 -214.543168) (xy 345.150496 -214.492165) (xy 345.173654 -214.444076) (xy 345.203721 -214.399976)
			(xy 345.240025 -214.360849) (xy 345.281755 -214.327571) (xy 345.327979 -214.300884) (xy 345.377664 -214.281384)
			(xy 345.429701 -214.269507) (xy 345.482926 -214.265518) (xy 345.536151 -214.269507) (xy 345.588188 -214.281384)
			(xy 345.637873 -214.300884) (xy 345.684097 -214.327571) (xy 345.725827 -214.360849) (xy 345.762131 -214.399976)
			(xy 345.792198 -214.444076) (xy 345.815356 -214.492165) (xy 345.831088 -214.543168) (xy 345.839043 -214.595947)
			(xy 345.839542 -214.622634) (xy 345.83916 -214.648304) (xy 345.831806 -214.699116) (xy 345.817242 -214.748347)
			(xy 345.795769 -214.794981) (xy 345.76783 -214.838054) (xy 345.734002 -214.876675) (xy 345.694986 -214.910045)
			(xy 345.651588 -214.937475) (xy 345.604704 -214.958398) (xy 345.555304 -214.972382) (xy 345.529916 -214.976202)
			(xy 345.505024 -214.979504) (xy 345.333066 -215.276938) (xy 345.342718 -215.300306) (xy 345.351283 -215.322018)
			(xy 345.363371 -215.367098) (xy 345.369492 -215.413368) (xy 345.369896 -215.436704) (xy 346.536264 -215.436704)
			(xy 346.536676 -215.411034) (xy 346.544024 -215.360224) (xy 346.558584 -215.310993) (xy 346.580053 -215.264359)
			(xy 346.607989 -215.221286) (xy 346.641813 -215.182665) (xy 346.680827 -215.149294) (xy 346.724223 -215.121863)
			(xy 346.771105 -215.10094) (xy 346.820502 -215.086956) (xy 346.84589 -215.083136) (xy 346.870782 -215.079834)
			(xy 347.04274 -214.7824) (xy 347.033088 -214.759032) (xy 347.024505 -214.737327) (xy 347.012424 -214.692243)
			(xy 347.00631 -214.645971) (xy 347.00591 -214.622634) (xy 347.006409 -214.595947) (xy 347.014364 -214.543168)
			(xy 347.030096 -214.492165) (xy 347.053254 -214.444076) (xy 347.083321 -214.399976) (xy 347.119625 -214.360849)
			(xy 347.161355 -214.327571) (xy 347.207579 -214.300884) (xy 347.257264 -214.281384) (xy 347.309301 -214.269507)
			(xy 347.362526 -214.265518) (xy 347.415751 -214.269507) (xy 347.467788 -214.281384) (xy 347.517473 -214.300884)
			(xy 347.563697 -214.327571) (xy 347.605427 -214.360849) (xy 347.641731 -214.399976) (xy 347.671798 -214.444076)
			(xy 347.694956 -214.492165) (xy 347.710688 -214.543168) (xy 347.718643 -214.595947) (xy 347.719142 -214.622634)
			(xy 347.71876 -214.648304) (xy 347.711406 -214.699116) (xy 347.696842 -214.748347) (xy 347.675369 -214.794981)
			(xy 347.64743 -214.838054) (xy 347.613602 -214.876675) (xy 347.574586 -214.910045) (xy 347.531188 -214.937475)
			(xy 347.484304 -214.958398) (xy 347.434904 -214.972382) (xy 347.409516 -214.976202) (xy 347.384624 -214.979504)
			(xy 347.212666 -215.276938) (xy 347.222318 -215.300306) (xy 347.230883 -215.322018) (xy 347.242971 -215.367098)
			(xy 347.249092 -215.413368) (xy 347.249496 -215.436704) (xy 348.415864 -215.436704) (xy 348.416276 -215.411034)
			(xy 348.423624 -215.360224) (xy 348.438184 -215.310993) (xy 348.459653 -215.264359) (xy 348.487589 -215.221286)
			(xy 348.521413 -215.182665) (xy 348.560427 -215.149294) (xy 348.603823 -215.121863) (xy 348.650705 -215.10094)
			(xy 348.700102 -215.086956) (xy 348.72549 -215.083136) (xy 348.750382 -215.079834) (xy 348.92234 -214.7824)
			(xy 348.912688 -214.759032) (xy 348.904105 -214.737327) (xy 348.892024 -214.692243) (xy 348.88591 -214.645971)
			(xy 348.88551 -214.622634) (xy 348.886009 -214.595947) (xy 348.893964 -214.543168) (xy 348.909696 -214.492165)
			(xy 348.932854 -214.444076) (xy 348.962921 -214.399976) (xy 348.999225 -214.360849) (xy 349.040955 -214.327571)
			(xy 349.087179 -214.300884) (xy 349.136864 -214.281384) (xy 349.188901 -214.269507) (xy 349.242126 -214.265518)
			(xy 349.295351 -214.269507) (xy 349.347388 -214.281384) (xy 349.397073 -214.300884) (xy 349.443297 -214.327571)
			(xy 349.485027 -214.360849) (xy 349.521331 -214.399976) (xy 349.551398 -214.444076) (xy 349.574556 -214.492165)
			(xy 349.590288 -214.543168) (xy 349.598243 -214.595947) (xy 349.598742 -214.622634) (xy 349.59836 -214.648304)
			(xy 349.591006 -214.699116) (xy 349.576442 -214.748347) (xy 349.554969 -214.794981) (xy 349.52703 -214.838054)
			(xy 349.493202 -214.876675) (xy 349.454186 -214.910045) (xy 349.410788 -214.937475) (xy 349.363904 -214.958398)
			(xy 349.314504 -214.972382) (xy 349.289116 -214.976202) (xy 349.264224 -214.979504) (xy 349.092266 -215.276938)
			(xy 349.101918 -215.300306) (xy 349.110483 -215.322018) (xy 349.122571 -215.367098) (xy 349.128692 -215.413368)
			(xy 349.129096 -215.436704) (xy 350.295464 -215.436704) (xy 350.295876 -215.411034) (xy 350.303224 -215.360224)
			(xy 350.317784 -215.310993) (xy 350.339253 -215.264359) (xy 350.367189 -215.221286) (xy 350.401013 -215.182665)
			(xy 350.440027 -215.149294) (xy 350.483423 -215.121863) (xy 350.530305 -215.10094) (xy 350.579702 -215.086956)
			(xy 350.60509 -215.083136) (xy 350.629982 -215.079834) (xy 350.80194 -214.7824) (xy 350.792288 -214.759032)
			(xy 350.783705 -214.737327) (xy 350.771624 -214.692243) (xy 350.76551 -214.645971) (xy 350.76511 -214.622634)
			(xy 350.765609 -214.595947) (xy 350.773564 -214.543168) (xy 350.789296 -214.492165) (xy 350.812454 -214.444076)
			(xy 350.842521 -214.399976) (xy 350.878825 -214.360849) (xy 350.920555 -214.327571) (xy 350.966779 -214.300884)
			(xy 351.016464 -214.281384) (xy 351.068501 -214.269507) (xy 351.121726 -214.265518) (xy 351.174951 -214.269507)
			(xy 351.226988 -214.281384) (xy 351.276673 -214.300884) (xy 351.322897 -214.327571) (xy 351.364627 -214.360849)
			(xy 351.400931 -214.399976) (xy 351.430998 -214.444076) (xy 351.454156 -214.492165) (xy 351.469888 -214.543168)
			(xy 351.477843 -214.595947) (xy 351.478342 -214.622634) (xy 351.47796 -214.648304) (xy 351.470606 -214.699116)
			(xy 351.456042 -214.748347) (xy 351.434569 -214.794981) (xy 351.40663 -214.838054) (xy 351.372802 -214.876675)
			(xy 351.333786 -214.910045) (xy 351.290388 -214.937475) (xy 351.243504 -214.958398) (xy 351.194104 -214.972382)
			(xy 351.168716 -214.976202) (xy 351.143824 -214.979504) (xy 350.971866 -215.276938) (xy 350.981518 -215.300306)
			(xy 350.990083 -215.322018) (xy 351.002171 -215.367098) (xy 351.008292 -215.413368) (xy 351.008696 -215.436704)
			(xy 352.175064 -215.436704) (xy 352.175476 -215.411034) (xy 352.182824 -215.360224) (xy 352.197384 -215.310993)
			(xy 352.218853 -215.264359) (xy 352.246789 -215.221286) (xy 352.280613 -215.182665) (xy 352.319627 -215.149294)
			(xy 352.363023 -215.121863) (xy 352.409905 -215.10094) (xy 352.459302 -215.086956) (xy 352.48469 -215.083136)
			(xy 352.509582 -215.079834) (xy 352.68154 -214.7824) (xy 352.671888 -214.759032) (xy 352.663305 -214.737327)
			(xy 352.651224 -214.692243) (xy 352.64511 -214.645971) (xy 352.64471 -214.622634) (xy 352.645209 -214.595947)
			(xy 352.653164 -214.543168) (xy 352.668896 -214.492165) (xy 352.692054 -214.444076) (xy 352.722121 -214.399976)
			(xy 352.758425 -214.360849) (xy 352.800155 -214.327571) (xy 352.846379 -214.300884) (xy 352.896064 -214.281384)
			(xy 352.948101 -214.269507) (xy 353.001326 -214.265518) (xy 353.054551 -214.269507) (xy 353.106588 -214.281384)
			(xy 353.156273 -214.300884) (xy 353.202497 -214.327571) (xy 353.244227 -214.360849) (xy 353.280531 -214.399976)
			(xy 353.310598 -214.444076) (xy 353.333756 -214.492165) (xy 353.349488 -214.543168) (xy 353.357443 -214.595947)
			(xy 353.357942 -214.622634) (xy 353.35756 -214.648304) (xy 353.350206 -214.699116) (xy 353.335642 -214.748347)
			(xy 353.314169 -214.794981) (xy 353.28623 -214.838054) (xy 353.252402 -214.876675) (xy 353.213386 -214.910045)
			(xy 353.169988 -214.937475) (xy 353.123104 -214.958398) (xy 353.073704 -214.972382) (xy 353.048316 -214.976202)
			(xy 353.023424 -214.979504) (xy 352.851466 -215.276938) (xy 352.861118 -215.300306) (xy 352.869683 -215.322018)
			(xy 352.881771 -215.367098) (xy 352.887892 -215.413368) (xy 352.888296 -215.436704) (xy 354.054664 -215.436704)
			(xy 354.055076 -215.411034) (xy 354.062424 -215.360224) (xy 354.076984 -215.310993) (xy 354.098453 -215.264359)
			(xy 354.126389 -215.221286) (xy 354.160213 -215.182665) (xy 354.199227 -215.149294) (xy 354.242623 -215.121863)
			(xy 354.289505 -215.10094) (xy 354.338902 -215.086956) (xy 354.36429 -215.083136) (xy 354.389182 -215.079834)
			(xy 354.56114 -214.7824) (xy 354.551488 -214.759032) (xy 354.542905 -214.737327) (xy 354.530824 -214.692243)
			(xy 354.52471 -214.645971) (xy 354.52431 -214.622634) (xy 354.524809 -214.595947) (xy 354.532764 -214.543168)
			(xy 354.548496 -214.492165) (xy 354.571654 -214.444076) (xy 354.601721 -214.399976) (xy 354.638025 -214.360849)
			(xy 354.679755 -214.327571) (xy 354.725979 -214.300884) (xy 354.775664 -214.281384) (xy 354.827701 -214.269507)
			(xy 354.880926 -214.265518) (xy 354.934151 -214.269507) (xy 354.986188 -214.281384) (xy 355.035873 -214.300884)
			(xy 355.082097 -214.327571) (xy 355.123827 -214.360849) (xy 355.160131 -214.399976) (xy 355.190198 -214.444076)
			(xy 355.213356 -214.492165) (xy 355.229088 -214.543168) (xy 355.237043 -214.595947) (xy 355.237542 -214.622634)
			(xy 355.23716 -214.648304) (xy 355.229806 -214.699116) (xy 355.215242 -214.748347) (xy 355.193769 -214.794981)
			(xy 355.16583 -214.838054) (xy 355.132002 -214.876675) (xy 355.092986 -214.910045) (xy 355.049588 -214.937475)
			(xy 355.002704 -214.958398) (xy 354.953304 -214.972382) (xy 354.927916 -214.976202) (xy 354.903024 -214.979504)
			(xy 354.731066 -215.276938) (xy 354.740718 -215.300306) (xy 354.749283 -215.322018) (xy 354.761371 -215.367098)
			(xy 354.767492 -215.413368) (xy 354.767896 -215.436704) (xy 355.934264 -215.436704) (xy 355.934676 -215.411034)
			(xy 355.942024 -215.360224) (xy 355.956584 -215.310993) (xy 355.978053 -215.264359) (xy 356.005989 -215.221286)
			(xy 356.039813 -215.182665) (xy 356.078827 -215.149294) (xy 356.122223 -215.121863) (xy 356.169105 -215.10094)
			(xy 356.218502 -215.086956) (xy 356.24389 -215.083136) (xy 356.268782 -215.079834) (xy 356.44074 -214.7824)
			(xy 356.431088 -214.759032) (xy 356.422505 -214.737327) (xy 356.410424 -214.692243) (xy 356.40431 -214.645971)
			(xy 356.40391 -214.622634) (xy 356.404409 -214.595947) (xy 356.412364 -214.543168) (xy 356.428096 -214.492165)
			(xy 356.451254 -214.444076) (xy 356.481321 -214.399976) (xy 356.517625 -214.360849) (xy 356.559355 -214.327571)
			(xy 356.605579 -214.300884) (xy 356.655264 -214.281384) (xy 356.707301 -214.269507) (xy 356.760526 -214.265518)
			(xy 356.813751 -214.269507) (xy 356.865788 -214.281384) (xy 356.915473 -214.300884) (xy 356.961697 -214.327571)
			(xy 357.003427 -214.360849) (xy 357.039731 -214.399976) (xy 357.069798 -214.444076) (xy 357.092956 -214.492165)
			(xy 357.108688 -214.543168) (xy 357.116643 -214.595947) (xy 357.117142 -214.622634) (xy 358.28351 -214.622634)
			(xy 358.284009 -214.595947) (xy 358.291964 -214.543168) (xy 358.307696 -214.492165) (xy 358.330854 -214.444076)
			(xy 358.360921 -214.399976) (xy 358.397225 -214.360849) (xy 358.438955 -214.327571) (xy 358.485179 -214.300884)
			(xy 358.534864 -214.281384) (xy 358.586901 -214.269507) (xy 358.640126 -214.265518) (xy 358.693351 -214.269507)
			(xy 358.745388 -214.281384) (xy 358.795073 -214.300884) (xy 358.841297 -214.327571) (xy 358.883027 -214.360849)
			(xy 358.919331 -214.399976) (xy 358.949398 -214.444076) (xy 358.972556 -214.492165) (xy 358.988288 -214.543168)
			(xy 358.996243 -214.595947) (xy 358.996742 -214.622634) (xy 358.996742 -214.623142) (xy 358.996333 -214.646343)
			(xy 358.990277 -214.69235) (xy 358.978312 -214.737184) (xy 358.969818 -214.758778) (xy 358.960166 -214.781892)
			(xy 359.132378 -215.079834) (xy 359.15727 -215.083136) (xy 359.182638 -215.08705) (xy 359.232018 -215.101043)
			(xy 359.278883 -215.121969) (xy 359.322265 -215.149396) (xy 359.361268 -215.182758) (xy 359.395087 -215.221365)
			(xy 359.423023 -215.264421) (xy 359.444499 -215.311037) (xy 359.459073 -215.360249) (xy 359.466443 -215.411042)
			(xy 359.466896 -215.436704) (xy 359.466397 -215.463391) (xy 359.458442 -215.51617) (xy 359.44271 -215.567173)
			(xy 359.419552 -215.615262) (xy 359.389485 -215.659362) (xy 359.353181 -215.698489) (xy 359.311451 -215.731767)
			(xy 359.265227 -215.758454) (xy 359.215542 -215.777954) (xy 359.163505 -215.789831) (xy 359.11028 -215.79382)
			(xy 359.057055 -215.789831) (xy 359.005018 -215.777954) (xy 358.955333 -215.758454) (xy 358.909109 -215.731767)
			(xy 358.867379 -215.698489) (xy 358.831075 -215.659362) (xy 358.801008 -215.615262) (xy 358.77785 -215.567173)
			(xy 358.762118 -215.51617) (xy 358.754163 -215.463391) (xy 358.753664 -215.436704) (xy 358.753664 -215.436196)
			(xy 358.754053 -215.412994) (xy 358.760117 -215.366987) (xy 358.77209 -215.322154) (xy 358.780588 -215.30056)
			(xy 358.79024 -215.277446) (xy 358.618282 -214.979504) (xy 358.59339 -214.976202) (xy 358.567993 -214.972392)
			(xy 358.518575 -214.958421) (xy 358.471671 -214.937507) (xy 358.428252 -214.910082) (xy 358.389214 -214.876715)
			(xy 358.355365 -214.838093) (xy 358.327405 -214.795017) (xy 358.305912 -214.748376) (xy 358.291329 -214.699135)
			(xy 358.28396 -214.648311) (xy 358.28351 -214.622634) (xy 357.117142 -214.622634) (xy 357.11676 -214.648304)
			(xy 357.109406 -214.699116) (xy 357.094842 -214.748347) (xy 357.073369 -214.794981) (xy 357.04543 -214.838054)
			(xy 357.011602 -214.876675) (xy 356.972586 -214.910045) (xy 356.929188 -214.937475) (xy 356.882304 -214.958398)
			(xy 356.832904 -214.972382) (xy 356.807516 -214.976202) (xy 356.782624 -214.979504) (xy 356.610666 -215.276938)
			(xy 356.620318 -215.300306) (xy 356.628883 -215.322018) (xy 356.640971 -215.367098) (xy 356.647092 -215.413368)
			(xy 356.647496 -215.4367) (xy 356.874605 -215.4367) (xy 356.878582 -215.383629) (xy 356.890425 -215.331743)
			(xy 356.909867 -215.282202) (xy 356.936477 -215.236111) (xy 356.969658 -215.194501) (xy 357.00867 -215.158301)
			(xy 357.052641 -215.12832) (xy 357.10059 -215.105227) (xy 357.151445 -215.089537) (xy 357.20407 -215.081603)
			(xy 357.23068 -215.081104) (xy 357.255627 -215.081478) (xy 357.305031 -215.088451) (xy 357.352975 -215.102262)
			(xy 357.398517 -215.122641) (xy 357.440763 -215.149186) (xy 357.478883 -215.181378) (xy 357.512127 -215.218582)
			(xy 357.526336 -215.239092) (xy 357.874824 -215.239092) (xy 357.889031 -215.218584) (xy 357.922285 -215.181394)
			(xy 357.960409 -215.149215) (xy 358.002656 -215.12268) (xy 358.048196 -215.102308) (xy 358.096136 -215.0885)
			(xy 358.145535 -215.081526) (xy 358.17048 -215.081104) (xy 358.197094 -215.081567) (xy 358.249729 -215.089498)
			(xy 358.300594 -215.105185) (xy 358.348552 -215.128278) (xy 358.392533 -215.158262) (xy 358.431553 -215.194465)
			(xy 358.464742 -215.23608) (xy 358.491357 -215.282177) (xy 358.510804 -215.331726) (xy 358.522649 -215.38362)
			(xy 358.526627 -215.4367) (xy 358.522649 -215.48978) (xy 358.510804 -215.541674) (xy 358.491357 -215.591223)
			(xy 358.464742 -215.63732) (xy 358.431553 -215.678935) (xy 358.392533 -215.715138) (xy 358.348552 -215.745122)
			(xy 358.300594 -215.768215) (xy 358.249729 -215.783902) (xy 358.197094 -215.791833) (xy 358.17048 -215.792304)
			(xy 358.145535 -215.791881) (xy 358.096133 -215.784917) (xy 358.04819 -215.771113) (xy 358.002648 -215.750743)
			(xy 357.960402 -215.724205) (xy 357.922281 -215.692021) (xy 357.889034 -215.654823) (xy 357.874824 -215.634316)
			(xy 357.526336 -215.634316) (xy 357.512157 -215.654844) (xy 357.478899 -215.692034) (xy 357.440769 -215.72421)
			(xy 357.398518 -215.750743) (xy 357.352973 -215.771112) (xy 357.305029 -215.784916) (xy 357.255626 -215.791885)
			(xy 357.23068 -215.792304) (xy 357.20407 -215.791797) (xy 357.151445 -215.783863) (xy 357.10059 -215.768173)
			(xy 357.052641 -215.74508) (xy 357.00867 -215.715099) (xy 356.969658 -215.678899) (xy 356.936477 -215.637289)
			(xy 356.909867 -215.591198) (xy 356.890425 -215.541657) (xy 356.878582 -215.489771) (xy 356.874605 -215.4367)
			(xy 356.647496 -215.4367) (xy 356.647496 -215.436704) (xy 356.646997 -215.463391) (xy 356.639042 -215.51617)
			(xy 356.62331 -215.567173) (xy 356.600152 -215.615262) (xy 356.570085 -215.659362) (xy 356.533781 -215.698489)
			(xy 356.492051 -215.731767) (xy 356.445827 -215.758454) (xy 356.396142 -215.777954) (xy 356.344105 -215.789831)
			(xy 356.29088 -215.79382) (xy 356.237655 -215.789831) (xy 356.185618 -215.777954) (xy 356.135933 -215.758454)
			(xy 356.089709 -215.731767) (xy 356.047979 -215.698489) (xy 356.011675 -215.659362) (xy 355.981608 -215.615262)
			(xy 355.95845 -215.567173) (xy 355.942718 -215.51617) (xy 355.934763 -215.463391) (xy 355.934264 -215.436704)
			(xy 354.767896 -215.436704) (xy 354.767397 -215.463391) (xy 354.759442 -215.51617) (xy 354.74371 -215.567173)
			(xy 354.720552 -215.615262) (xy 354.690485 -215.659362) (xy 354.654181 -215.698489) (xy 354.612451 -215.731767)
			(xy 354.566227 -215.758454) (xy 354.516542 -215.777954) (xy 354.464505 -215.789831) (xy 354.41128 -215.79382)
			(xy 354.358055 -215.789831) (xy 354.306018 -215.777954) (xy 354.256333 -215.758454) (xy 354.210109 -215.731767)
			(xy 354.168379 -215.698489) (xy 354.132075 -215.659362) (xy 354.102008 -215.615262) (xy 354.07885 -215.567173)
			(xy 354.063118 -215.51617) (xy 354.055163 -215.463391) (xy 354.054664 -215.436704) (xy 352.888296 -215.436704)
			(xy 352.887797 -215.463391) (xy 352.879842 -215.51617) (xy 352.86411 -215.567173) (xy 352.840952 -215.615262)
			(xy 352.810885 -215.659362) (xy 352.774581 -215.698489) (xy 352.732851 -215.731767) (xy 352.686627 -215.758454)
			(xy 352.636942 -215.777954) (xy 352.584905 -215.789831) (xy 352.53168 -215.79382) (xy 352.478455 -215.789831)
			(xy 352.426418 -215.777954) (xy 352.376733 -215.758454) (xy 352.330509 -215.731767) (xy 352.288779 -215.698489)
			(xy 352.252475 -215.659362) (xy 352.222408 -215.615262) (xy 352.19925 -215.567173) (xy 352.183518 -215.51617)
			(xy 352.175563 -215.463391) (xy 352.175064 -215.436704) (xy 351.008696 -215.436704) (xy 351.008197 -215.463391)
			(xy 351.000242 -215.51617) (xy 350.98451 -215.567173) (xy 350.961352 -215.615262) (xy 350.931285 -215.659362)
			(xy 350.894981 -215.698489) (xy 350.853251 -215.731767) (xy 350.807027 -215.758454) (xy 350.757342 -215.777954)
			(xy 350.705305 -215.789831) (xy 350.65208 -215.79382) (xy 350.598855 -215.789831) (xy 350.546818 -215.777954)
			(xy 350.497133 -215.758454) (xy 350.450909 -215.731767) (xy 350.409179 -215.698489) (xy 350.372875 -215.659362)
			(xy 350.342808 -215.615262) (xy 350.31965 -215.567173) (xy 350.303918 -215.51617) (xy 350.295963 -215.463391)
			(xy 350.295464 -215.436704) (xy 349.129096 -215.436704) (xy 349.128597 -215.463391) (xy 349.120642 -215.51617)
			(xy 349.10491 -215.567173) (xy 349.081752 -215.615262) (xy 349.051685 -215.659362) (xy 349.015381 -215.698489)
			(xy 348.973651 -215.731767) (xy 348.927427 -215.758454) (xy 348.877742 -215.777954) (xy 348.825705 -215.789831)
			(xy 348.77248 -215.79382) (xy 348.719255 -215.789831) (xy 348.667218 -215.777954) (xy 348.617533 -215.758454)
			(xy 348.571309 -215.731767) (xy 348.529579 -215.698489) (xy 348.493275 -215.659362) (xy 348.463208 -215.615262)
			(xy 348.44005 -215.567173) (xy 348.424318 -215.51617) (xy 348.416363 -215.463391) (xy 348.415864 -215.436704)
			(xy 347.249496 -215.436704) (xy 347.248997 -215.463391) (xy 347.241042 -215.51617) (xy 347.22531 -215.567173)
			(xy 347.202152 -215.615262) (xy 347.172085 -215.659362) (xy 347.135781 -215.698489) (xy 347.094051 -215.731767)
			(xy 347.047827 -215.758454) (xy 346.998142 -215.777954) (xy 346.946105 -215.789831) (xy 346.89288 -215.79382)
			(xy 346.839655 -215.789831) (xy 346.787618 -215.777954) (xy 346.737933 -215.758454) (xy 346.691709 -215.731767)
			(xy 346.649979 -215.698489) (xy 346.613675 -215.659362) (xy 346.583608 -215.615262) (xy 346.56045 -215.567173)
			(xy 346.544718 -215.51617) (xy 346.536763 -215.463391) (xy 346.536264 -215.436704) (xy 345.369896 -215.436704)
			(xy 345.369397 -215.463391) (xy 345.361442 -215.51617) (xy 345.34571 -215.567173) (xy 345.322552 -215.615262)
			(xy 345.292485 -215.659362) (xy 345.256181 -215.698489) (xy 345.214451 -215.731767) (xy 345.168227 -215.758454)
			(xy 345.118542 -215.777954) (xy 345.066505 -215.789831) (xy 345.01328 -215.79382) (xy 344.960055 -215.789831)
			(xy 344.908018 -215.777954) (xy 344.858333 -215.758454) (xy 344.812109 -215.731767) (xy 344.770379 -215.698489)
			(xy 344.734075 -215.659362) (xy 344.704008 -215.615262) (xy 344.68085 -215.567173) (xy 344.665118 -215.51617)
			(xy 344.657163 -215.463391) (xy 344.656664 -215.436704) (xy 343.490296 -215.436704) (xy 343.489797 -215.463391)
			(xy 343.481842 -215.51617) (xy 343.46611 -215.567173) (xy 343.442952 -215.615262) (xy 343.412885 -215.659362)
			(xy 343.376581 -215.698489) (xy 343.334851 -215.731767) (xy 343.288627 -215.758454) (xy 343.238942 -215.777954)
			(xy 343.186905 -215.789831) (xy 343.13368 -215.79382) (xy 343.080455 -215.789831) (xy 343.028418 -215.777954)
			(xy 342.978733 -215.758454) (xy 342.932509 -215.731767) (xy 342.890779 -215.698489) (xy 342.854475 -215.659362)
			(xy 342.824408 -215.615262) (xy 342.80125 -215.567173) (xy 342.785518 -215.51617) (xy 342.777563 -215.463391)
			(xy 342.777064 -215.436704) (xy 341.610696 -215.436704) (xy 341.610197 -215.463391) (xy 341.602242 -215.51617)
			(xy 341.58651 -215.567173) (xy 341.563352 -215.615262) (xy 341.533285 -215.659362) (xy 341.496981 -215.698489)
			(xy 341.455251 -215.731767) (xy 341.409027 -215.758454) (xy 341.359342 -215.777954) (xy 341.307305 -215.789831)
			(xy 341.25408 -215.79382) (xy 341.200855 -215.789831) (xy 341.148818 -215.777954) (xy 341.099133 -215.758454)
			(xy 341.052909 -215.731767) (xy 341.011179 -215.698489) (xy 340.974875 -215.659362) (xy 340.944808 -215.615262)
			(xy 340.92165 -215.567173) (xy 340.905918 -215.51617) (xy 340.897963 -215.463391) (xy 340.897464 -215.436704)
			(xy 339.731096 -215.436704) (xy 339.730597 -215.463391) (xy 339.722642 -215.51617) (xy 339.70691 -215.567173)
			(xy 339.683752 -215.615262) (xy 339.653685 -215.659362) (xy 339.617381 -215.698489) (xy 339.575651 -215.731767)
			(xy 339.529427 -215.758454) (xy 339.479742 -215.777954) (xy 339.427705 -215.789831) (xy 339.37448 -215.79382)
			(xy 339.321255 -215.789831) (xy 339.269218 -215.777954) (xy 339.219533 -215.758454) (xy 339.173309 -215.731767)
			(xy 339.131579 -215.698489) (xy 339.095275 -215.659362) (xy 339.065208 -215.615262) (xy 339.04205 -215.567173)
			(xy 339.026318 -215.51617) (xy 339.018363 -215.463391) (xy 339.017864 -215.436704) (xy 337.851496 -215.436704)
			(xy 337.850997 -215.463391) (xy 337.843042 -215.51617) (xy 337.82731 -215.567173) (xy 337.804152 -215.615262)
			(xy 337.774085 -215.659362) (xy 337.737781 -215.698489) (xy 337.696051 -215.731767) (xy 337.649827 -215.758454)
			(xy 337.600142 -215.777954) (xy 337.548105 -215.789831) (xy 337.49488 -215.79382) (xy 337.441655 -215.789831)
			(xy 337.389618 -215.777954) (xy 337.339933 -215.758454) (xy 337.293709 -215.731767) (xy 337.251979 -215.698489)
			(xy 337.215675 -215.659362) (xy 337.185608 -215.615262) (xy 337.16245 -215.567173) (xy 337.146718 -215.51617)
			(xy 337.138763 -215.463391) (xy 337.138264 -215.436704) (xy 336.911696 -215.436704) (xy 336.911349 -215.460044)
			(xy 336.905241 -215.506324) (xy 336.893131 -215.551406) (xy 336.884518 -215.573102) (xy 336.874866 -215.59647)
			(xy 337.046824 -215.89365) (xy 337.071716 -215.896952) (xy 337.097092 -215.900814) (xy 337.146474 -215.914814)
			(xy 337.19334 -215.935747) (xy 337.236722 -215.963181) (xy 337.275724 -215.996549) (xy 337.309542 -216.035162)
			(xy 337.337476 -216.078223) (xy 337.358951 -216.124843) (xy 337.373523 -216.174059) (xy 337.38089 -216.224856)
			(xy 337.381342 -216.25052) (xy 337.380843 -216.277207) (xy 337.372888 -216.329986) (xy 337.357156 -216.380989)
			(xy 337.333998 -216.429078) (xy 337.303931 -216.473178) (xy 337.267627 -216.512305) (xy 337.225897 -216.545583)
			(xy 337.179673 -216.57227) (xy 337.129988 -216.59177) (xy 337.077951 -216.603647) (xy 337.024726 -216.607636)
			(xy 336.971501 -216.603647) (xy 336.919464 -216.59177) (xy 336.869779 -216.57227) (xy 336.823555 -216.545583)
			(xy 336.781825 -216.512305) (xy 336.745521 -216.473178) (xy 336.715454 -216.429078) (xy 336.692296 -216.380989)
			(xy 336.676564 -216.329986) (xy 336.668609 -216.277207) (xy 336.66811 -216.25052) (xy 336.668464 -216.22718)
			(xy 336.674569 -216.180901) (xy 336.686677 -216.135818) (xy 336.695288 -216.114122) (xy 336.70494 -216.090754)
			(xy 336.532982 -215.793574) (xy 336.50809 -215.790272) (xy 336.482701 -215.786479) (xy 336.433314 -215.772475)
			(xy 336.386443 -215.751537) (xy 336.343058 -215.724097) (xy 336.304054 -215.690721) (xy 336.270237 -215.6521)
			(xy 336.242304 -215.60903) (xy 336.220834 -215.562401) (xy 336.206269 -215.513176) (xy 336.198911 -215.462371)
			(xy 336.198464 -215.436704) (xy 135.960612 -215.436704) (xy 135.960115 -215.463315) (xy 135.952182 -215.515943)
			(xy 135.936495 -215.566801) (xy 135.913402 -215.614753) (xy 135.883421 -215.658728) (xy 135.84722 -215.697743)
			(xy 135.805609 -215.730926) (xy 135.759517 -215.757538) (xy 135.709974 -215.776982) (xy 135.658086 -215.788825)
			(xy 135.605012 -215.792803) (xy 135.551938 -215.788825) (xy 135.50005 -215.776982) (xy 135.450507 -215.757538)
			(xy 135.404415 -215.730926) (xy 135.362804 -215.697743) (xy 135.326603 -215.658728) (xy 135.296622 -215.614753)
			(xy 135.273529 -215.566801) (xy 135.257842 -215.515943) (xy 135.249909 -215.463315) (xy 135.249412 -215.436704)
			(xy 135.250046 -215.407259) (xy 135.259738 -215.349172) (xy 135.278859 -215.293472) (xy 135.292338 -215.267286)
			(xy 135.098536 -214.900256) (xy 135.072607 -214.897128) (xy 135.022007 -214.884195) (xy 134.973841 -214.864003)
			(xy 134.929145 -214.836987) (xy 134.888879 -214.803727) (xy 134.853907 -214.764937) (xy 134.824982 -214.721452)
			(xy 134.802725 -214.674205) (xy 134.787614 -214.624212) (xy 134.779974 -214.572547) (xy 134.779512 -214.546434)
			(xy 133.603912 -214.546434) (xy 133.611375 -214.595947) (xy 133.611874 -214.622634) (xy 133.611464 -214.648303)
			(xy 133.604111 -214.699112) (xy 133.589549 -214.748341) (xy 133.568078 -214.794974) (xy 133.540142 -214.838045)
			(xy 133.506318 -214.876665) (xy 133.467305 -214.910036) (xy 133.423911 -214.937468) (xy 133.377031 -214.958393)
			(xy 133.327635 -214.97238) (xy 133.302248 -214.976202) (xy 133.277356 -214.979504) (xy 133.105398 -215.276938)
			(xy 133.11505 -215.300306) (xy 133.123611 -215.322019) (xy 133.135701 -215.367099) (xy 133.141824 -215.413368)
			(xy 133.142228 -215.4367) (xy 133.369281 -215.4367) (xy 133.373259 -215.383622) (xy 133.385103 -215.33173)
			(xy 133.404549 -215.282183) (xy 133.431163 -215.236087) (xy 133.46435 -215.194473) (xy 133.503369 -215.158271)
			(xy 133.547347 -215.128288) (xy 133.595304 -215.105195) (xy 133.646166 -215.089507) (xy 133.698799 -215.081576)
			(xy 133.725412 -215.081104) (xy 133.750357 -215.08153) (xy 133.799759 -215.088493) (xy 133.847702 -215.102295)
			(xy 133.893244 -215.122666) (xy 133.935491 -215.149203) (xy 133.973612 -215.181387) (xy 134.006858 -215.218585)
			(xy 134.021068 -215.239092) (xy 134.369556 -215.239092) (xy 134.383742 -215.218569) (xy 134.416999 -215.181379)
			(xy 134.455127 -215.149202) (xy 134.497378 -215.122668) (xy 134.542921 -215.102299) (xy 134.590864 -215.088494)
			(xy 134.640266 -215.081523) (xy 134.665212 -215.081104) (xy 134.691823 -215.081594) (xy 134.74445 -215.089528)
			(xy 134.795307 -215.105217) (xy 134.843258 -215.12831) (xy 134.887232 -215.158292) (xy 134.926245 -215.194493)
			(xy 134.959428 -215.236104) (xy 134.986039 -215.282196) (xy 135.005483 -215.331739) (xy 135.017325 -215.383627)
			(xy 135.021303 -215.4367) (xy 135.017325 -215.489773) (xy 135.005483 -215.541661) (xy 134.986039 -215.591204)
			(xy 134.959428 -215.637296) (xy 134.926245 -215.678907) (xy 134.887232 -215.715108) (xy 134.843258 -215.74509)
			(xy 134.795307 -215.768183) (xy 134.74445 -215.783872) (xy 134.691823 -215.791806) (xy 134.665212 -215.792304)
			(xy 134.640265 -215.791933) (xy 134.590861 -215.784959) (xy 134.542917 -215.771147) (xy 134.497375 -215.750768)
			(xy 134.455129 -215.724222) (xy 134.417009 -215.69203) (xy 134.383765 -215.654826) (xy 134.369556 -215.634316)
			(xy 134.021068 -215.634316) (xy 134.006869 -215.654829) (xy 133.973614 -215.692019) (xy 133.935488 -215.724197)
			(xy 133.89324 -215.750732) (xy 133.847698 -215.771103) (xy 133.799757 -215.78491) (xy 133.750357 -215.791883)
			(xy 133.725412 -215.792304) (xy 133.698799 -215.791824) (xy 133.646166 -215.783893) (xy 133.595304 -215.768205)
			(xy 133.547347 -215.745112) (xy 133.503369 -215.715129) (xy 133.46435 -215.678927) (xy 133.431163 -215.637313)
			(xy 133.404549 -215.591217) (xy 133.385103 -215.54167) (xy 133.373259 -215.489778) (xy 133.369281 -215.4367)
			(xy 133.142228 -215.4367) (xy 133.142228 -215.436704) (xy 133.141729 -215.463391) (xy 133.133774 -215.51617)
			(xy 133.118042 -215.567173) (xy 133.094884 -215.615262) (xy 133.064817 -215.659362) (xy 133.028513 -215.698489)
			(xy 132.986783 -215.731767) (xy 132.940559 -215.758454) (xy 132.890874 -215.777954) (xy 132.838837 -215.789831)
			(xy 132.785612 -215.79382) (xy 132.732387 -215.789831) (xy 132.68035 -215.777954) (xy 132.630665 -215.758454)
			(xy 132.584441 -215.731767) (xy 132.542711 -215.698489) (xy 132.506407 -215.659362) (xy 132.47634 -215.615262)
			(xy 132.453182 -215.567173) (xy 132.43745 -215.51617) (xy 132.429495 -215.463391) (xy 132.428996 -215.436704)
			(xy 131.262628 -215.436704) (xy 131.262129 -215.463391) (xy 131.254174 -215.51617) (xy 131.238442 -215.567173)
			(xy 131.215284 -215.615262) (xy 131.185217 -215.659362) (xy 131.148913 -215.698489) (xy 131.107183 -215.731767)
			(xy 131.060959 -215.758454) (xy 131.011274 -215.777954) (xy 130.959237 -215.789831) (xy 130.906012 -215.79382)
			(xy 130.852787 -215.789831) (xy 130.80075 -215.777954) (xy 130.751065 -215.758454) (xy 130.704841 -215.731767)
			(xy 130.663111 -215.698489) (xy 130.626807 -215.659362) (xy 130.59674 -215.615262) (xy 130.573582 -215.567173)
			(xy 130.55785 -215.51617) (xy 130.549895 -215.463391) (xy 130.549396 -215.436704) (xy 129.383028 -215.436704)
			(xy 129.382529 -215.463391) (xy 129.374574 -215.51617) (xy 129.358842 -215.567173) (xy 129.335684 -215.615262)
			(xy 129.305617 -215.659362) (xy 129.269313 -215.698489) (xy 129.227583 -215.731767) (xy 129.181359 -215.758454)
			(xy 129.131674 -215.777954) (xy 129.079637 -215.789831) (xy 129.026412 -215.79382) (xy 128.973187 -215.789831)
			(xy 128.92115 -215.777954) (xy 128.871465 -215.758454) (xy 128.825241 -215.731767) (xy 128.783511 -215.698489)
			(xy 128.747207 -215.659362) (xy 128.71714 -215.615262) (xy 128.693982 -215.567173) (xy 128.67825 -215.51617)
			(xy 128.670295 -215.463391) (xy 128.669796 -215.436704) (xy 127.503428 -215.436704) (xy 127.502929 -215.463391)
			(xy 127.494974 -215.51617) (xy 127.479242 -215.567173) (xy 127.456084 -215.615262) (xy 127.426017 -215.659362)
			(xy 127.389713 -215.698489) (xy 127.347983 -215.731767) (xy 127.301759 -215.758454) (xy 127.252074 -215.777954)
			(xy 127.200037 -215.789831) (xy 127.146812 -215.79382) (xy 127.093587 -215.789831) (xy 127.04155 -215.777954)
			(xy 126.991865 -215.758454) (xy 126.945641 -215.731767) (xy 126.903911 -215.698489) (xy 126.867607 -215.659362)
			(xy 126.83754 -215.615262) (xy 126.814382 -215.567173) (xy 126.79865 -215.51617) (xy 126.790695 -215.463391)
			(xy 126.790196 -215.436704) (xy 125.623828 -215.436704) (xy 125.623329 -215.463391) (xy 125.615374 -215.51617)
			(xy 125.599642 -215.567173) (xy 125.576484 -215.615262) (xy 125.546417 -215.659362) (xy 125.510113 -215.698489)
			(xy 125.468383 -215.731767) (xy 125.422159 -215.758454) (xy 125.372474 -215.777954) (xy 125.320437 -215.789831)
			(xy 125.267212 -215.79382) (xy 125.213987 -215.789831) (xy 125.16195 -215.777954) (xy 125.112265 -215.758454)
			(xy 125.066041 -215.731767) (xy 125.024311 -215.698489) (xy 124.988007 -215.659362) (xy 124.95794 -215.615262)
			(xy 124.934782 -215.567173) (xy 124.91905 -215.51617) (xy 124.911095 -215.463391) (xy 124.910596 -215.436704)
			(xy 123.744228 -215.436704) (xy 123.743729 -215.463391) (xy 123.735774 -215.51617) (xy 123.720042 -215.567173)
			(xy 123.696884 -215.615262) (xy 123.666817 -215.659362) (xy 123.630513 -215.698489) (xy 123.588783 -215.731767)
			(xy 123.542559 -215.758454) (xy 123.492874 -215.777954) (xy 123.440837 -215.789831) (xy 123.387612 -215.79382)
			(xy 123.334387 -215.789831) (xy 123.28235 -215.777954) (xy 123.232665 -215.758454) (xy 123.186441 -215.731767)
			(xy 123.144711 -215.698489) (xy 123.108407 -215.659362) (xy 123.07834 -215.615262) (xy 123.055182 -215.567173)
			(xy 123.03945 -215.51617) (xy 123.031495 -215.463391) (xy 123.030996 -215.436704) (xy 121.864628 -215.436704)
			(xy 121.864129 -215.463391) (xy 121.856174 -215.51617) (xy 121.840442 -215.567173) (xy 121.817284 -215.615262)
			(xy 121.787217 -215.659362) (xy 121.750913 -215.698489) (xy 121.709183 -215.731767) (xy 121.662959 -215.758454)
			(xy 121.613274 -215.777954) (xy 121.561237 -215.789831) (xy 121.508012 -215.79382) (xy 121.454787 -215.789831)
			(xy 121.40275 -215.777954) (xy 121.353065 -215.758454) (xy 121.306841 -215.731767) (xy 121.265111 -215.698489)
			(xy 121.228807 -215.659362) (xy 121.19874 -215.615262) (xy 121.175582 -215.567173) (xy 121.15985 -215.51617)
			(xy 121.151895 -215.463391) (xy 121.151396 -215.436704) (xy 119.985028 -215.436704) (xy 119.984529 -215.463391)
			(xy 119.976574 -215.51617) (xy 119.960842 -215.567173) (xy 119.937684 -215.615262) (xy 119.907617 -215.659362)
			(xy 119.871313 -215.698489) (xy 119.829583 -215.731767) (xy 119.783359 -215.758454) (xy 119.733674 -215.777954)
			(xy 119.681637 -215.789831) (xy 119.628412 -215.79382) (xy 119.575187 -215.789831) (xy 119.52315 -215.777954)
			(xy 119.473465 -215.758454) (xy 119.427241 -215.731767) (xy 119.385511 -215.698489) (xy 119.349207 -215.659362)
			(xy 119.31914 -215.615262) (xy 119.295982 -215.567173) (xy 119.28025 -215.51617) (xy 119.272295 -215.463391)
			(xy 119.271796 -215.436704) (xy 118.105428 -215.436704) (xy 118.104929 -215.463391) (xy 118.096974 -215.51617)
			(xy 118.081242 -215.567173) (xy 118.058084 -215.615262) (xy 118.028017 -215.659362) (xy 117.991713 -215.698489)
			(xy 117.949983 -215.731767) (xy 117.903759 -215.758454) (xy 117.854074 -215.777954) (xy 117.802037 -215.789831)
			(xy 117.748812 -215.79382) (xy 117.695587 -215.789831) (xy 117.64355 -215.777954) (xy 117.593865 -215.758454)
			(xy 117.547641 -215.731767) (xy 117.505911 -215.698489) (xy 117.469607 -215.659362) (xy 117.43954 -215.615262)
			(xy 117.416382 -215.567173) (xy 117.40065 -215.51617) (xy 117.392695 -215.463391) (xy 117.392196 -215.436704)
			(xy 116.225828 -215.436704) (xy 116.225329 -215.463391) (xy 116.217374 -215.51617) (xy 116.201642 -215.567173)
			(xy 116.178484 -215.615262) (xy 116.148417 -215.659362) (xy 116.112113 -215.698489) (xy 116.070383 -215.731767)
			(xy 116.024159 -215.758454) (xy 115.974474 -215.777954) (xy 115.922437 -215.789831) (xy 115.869212 -215.79382)
			(xy 115.815987 -215.789831) (xy 115.76395 -215.777954) (xy 115.714265 -215.758454) (xy 115.668041 -215.731767)
			(xy 115.626311 -215.698489) (xy 115.590007 -215.659362) (xy 115.55994 -215.615262) (xy 115.536782 -215.567173)
			(xy 115.52105 -215.51617) (xy 115.513095 -215.463391) (xy 115.512596 -215.436704) (xy 114.346228 -215.436704)
			(xy 114.345729 -215.463391) (xy 114.337774 -215.51617) (xy 114.322042 -215.567173) (xy 114.298884 -215.615262)
			(xy 114.268817 -215.659362) (xy 114.232513 -215.698489) (xy 114.190783 -215.731767) (xy 114.144559 -215.758454)
			(xy 114.094874 -215.777954) (xy 114.042837 -215.789831) (xy 113.989612 -215.79382) (xy 113.936387 -215.789831)
			(xy 113.88435 -215.777954) (xy 113.834665 -215.758454) (xy 113.788441 -215.731767) (xy 113.746711 -215.698489)
			(xy 113.710407 -215.659362) (xy 113.68034 -215.615262) (xy 113.657182 -215.567173) (xy 113.64145 -215.51617)
			(xy 113.633495 -215.463391) (xy 113.632996 -215.436704) (xy 111.526828 -215.436704) (xy 111.526329 -215.463391)
			(xy 111.518374 -215.51617) (xy 111.502642 -215.567173) (xy 111.479484 -215.615262) (xy 111.449417 -215.659362)
			(xy 111.413113 -215.698489) (xy 111.371383 -215.731767) (xy 111.325159 -215.758454) (xy 111.275474 -215.777954)
			(xy 111.223437 -215.789831) (xy 111.170212 -215.79382) (xy 111.116987 -215.789831) (xy 111.06495 -215.777954)
			(xy 111.015265 -215.758454) (xy 110.969041 -215.731767) (xy 110.927311 -215.698489) (xy 110.891007 -215.659362)
			(xy 110.86094 -215.615262) (xy 110.837782 -215.567173) (xy 110.82205 -215.51617) (xy 110.814095 -215.463391)
			(xy 110.813596 -215.436704) (xy 110.813596 -215.43645) (xy 110.814129 -215.408633) (xy 110.822789 -215.353678)
			(xy 110.839876 -215.300734) (xy 110.85195 -215.275668) (xy 110.863888 -215.2523) (xy 110.679992 -214.903558)
			(xy 110.654084 -214.900002) (xy 110.628672 -214.896209) (xy 110.579222 -214.882268) (xy 110.532283 -214.861375)
			(xy 110.488828 -214.833963) (xy 110.449756 -214.800599) (xy 110.415876 -214.761974) (xy 110.38789 -214.718887)
			(xy 110.366375 -214.67223) (xy 110.351778 -214.622969) (xy 110.344401 -214.572123) (xy 110.34395 -214.546434)
			(xy 109.169112 -214.546434) (xy 109.176575 -214.595947) (xy 109.177074 -214.622634) (xy 109.176664 -214.648303)
			(xy 109.169311 -214.699112) (xy 109.154749 -214.748341) (xy 109.133278 -214.794974) (xy 109.105342 -214.838045)
			(xy 109.071518 -214.876665) (xy 109.032505 -214.910036) (xy 108.989111 -214.937468) (xy 108.942231 -214.958393)
			(xy 108.892835 -214.97238) (xy 108.867448 -214.976202) (xy 108.842556 -214.979504) (xy 108.670598 -215.276938)
			(xy 108.68025 -215.300306) (xy 108.688811 -215.322019) (xy 108.700901 -215.367099) (xy 108.707024 -215.413368)
			(xy 108.707428 -215.4367) (xy 108.934481 -215.4367) (xy 108.938459 -215.383622) (xy 108.950303 -215.33173)
			(xy 108.969749 -215.282183) (xy 108.996363 -215.236087) (xy 109.02955 -215.194473) (xy 109.068569 -215.158271)
			(xy 109.112547 -215.128288) (xy 109.160504 -215.105195) (xy 109.211366 -215.089507) (xy 109.263999 -215.081576)
			(xy 109.290612 -215.081104) (xy 109.315557 -215.08153) (xy 109.364959 -215.088493) (xy 109.412902 -215.102295)
			(xy 109.458444 -215.122666) (xy 109.500691 -215.149203) (xy 109.538812 -215.181387) (xy 109.572058 -215.218585)
			(xy 109.586268 -215.239092) (xy 109.934756 -215.239092) (xy 109.948942 -215.218569) (xy 109.982199 -215.181379)
			(xy 110.020327 -215.149202) (xy 110.062578 -215.122668) (xy 110.108121 -215.102299) (xy 110.156064 -215.088494)
			(xy 110.205466 -215.081523) (xy 110.230412 -215.081104) (xy 110.257023 -215.081594) (xy 110.30965 -215.089528)
			(xy 110.360507 -215.105217) (xy 110.408458 -215.12831) (xy 110.452432 -215.158292) (xy 110.491445 -215.194493)
			(xy 110.524628 -215.236104) (xy 110.551239 -215.282196) (xy 110.570683 -215.331739) (xy 110.582525 -215.383627)
			(xy 110.586503 -215.4367) (xy 110.582525 -215.489773) (xy 110.570683 -215.541661) (xy 110.551239 -215.591204)
			(xy 110.524628 -215.637296) (xy 110.491445 -215.678907) (xy 110.452432 -215.715108) (xy 110.408458 -215.74509)
			(xy 110.360507 -215.768183) (xy 110.30965 -215.783872) (xy 110.257023 -215.791806) (xy 110.230412 -215.792304)
			(xy 110.205465 -215.791933) (xy 110.156061 -215.784959) (xy 110.108117 -215.771147) (xy 110.062575 -215.750768)
			(xy 110.020329 -215.724222) (xy 109.982209 -215.69203) (xy 109.948965 -215.654826) (xy 109.934756 -215.634316)
			(xy 109.586268 -215.634316) (xy 109.572069 -215.654829) (xy 109.538814 -215.692019) (xy 109.500688 -215.724197)
			(xy 109.45844 -215.750732) (xy 109.412898 -215.771103) (xy 109.364957 -215.78491) (xy 109.315557 -215.791883)
			(xy 109.290612 -215.792304) (xy 109.263999 -215.791824) (xy 109.211366 -215.783893) (xy 109.160504 -215.768205)
			(xy 109.112547 -215.745112) (xy 109.068569 -215.715129) (xy 109.02955 -215.678927) (xy 108.996363 -215.637313)
			(xy 108.969749 -215.591217) (xy 108.950303 -215.54167) (xy 108.938459 -215.489778) (xy 108.934481 -215.4367)
			(xy 108.707428 -215.4367) (xy 108.707428 -215.436704) (xy 108.706929 -215.463391) (xy 108.698974 -215.51617)
			(xy 108.683242 -215.567173) (xy 108.660084 -215.615262) (xy 108.630017 -215.659362) (xy 108.593713 -215.698489)
			(xy 108.551983 -215.731767) (xy 108.505759 -215.758454) (xy 108.456074 -215.777954) (xy 108.404037 -215.789831)
			(xy 108.350812 -215.79382) (xy 108.297587 -215.789831) (xy 108.24555 -215.777954) (xy 108.195865 -215.758454)
			(xy 108.149641 -215.731767) (xy 108.107911 -215.698489) (xy 108.071607 -215.659362) (xy 108.04154 -215.615262)
			(xy 108.018382 -215.567173) (xy 108.00265 -215.51617) (xy 107.994695 -215.463391) (xy 107.994196 -215.436704)
			(xy 106.827828 -215.436704) (xy 106.827329 -215.463391) (xy 106.819374 -215.51617) (xy 106.803642 -215.567173)
			(xy 106.780484 -215.615262) (xy 106.750417 -215.659362) (xy 106.714113 -215.698489) (xy 106.672383 -215.731767)
			(xy 106.626159 -215.758454) (xy 106.576474 -215.777954) (xy 106.524437 -215.789831) (xy 106.471212 -215.79382)
			(xy 106.417987 -215.789831) (xy 106.36595 -215.777954) (xy 106.316265 -215.758454) (xy 106.270041 -215.731767)
			(xy 106.228311 -215.698489) (xy 106.192007 -215.659362) (xy 106.16194 -215.615262) (xy 106.138782 -215.567173)
			(xy 106.12305 -215.51617) (xy 106.115095 -215.463391) (xy 106.114596 -215.436704) (xy 104.948228 -215.436704)
			(xy 104.947729 -215.463391) (xy 104.939774 -215.51617) (xy 104.924042 -215.567173) (xy 104.900884 -215.615262)
			(xy 104.870817 -215.659362) (xy 104.834513 -215.698489) (xy 104.792783 -215.731767) (xy 104.746559 -215.758454)
			(xy 104.696874 -215.777954) (xy 104.644837 -215.789831) (xy 104.591612 -215.79382) (xy 104.538387 -215.789831)
			(xy 104.48635 -215.777954) (xy 104.436665 -215.758454) (xy 104.390441 -215.731767) (xy 104.348711 -215.698489)
			(xy 104.312407 -215.659362) (xy 104.28234 -215.615262) (xy 104.259182 -215.567173) (xy 104.24345 -215.51617)
			(xy 104.235495 -215.463391) (xy 104.234996 -215.436704) (xy 103.068628 -215.436704) (xy 103.068129 -215.463391)
			(xy 103.060174 -215.51617) (xy 103.044442 -215.567173) (xy 103.021284 -215.615262) (xy 102.991217 -215.659362)
			(xy 102.954913 -215.698489) (xy 102.913183 -215.731767) (xy 102.866959 -215.758454) (xy 102.817274 -215.777954)
			(xy 102.765237 -215.789831) (xy 102.712012 -215.79382) (xy 102.658787 -215.789831) (xy 102.60675 -215.777954)
			(xy 102.557065 -215.758454) (xy 102.510841 -215.731767) (xy 102.469111 -215.698489) (xy 102.432807 -215.659362)
			(xy 102.40274 -215.615262) (xy 102.379582 -215.567173) (xy 102.36385 -215.51617) (xy 102.355895 -215.463391)
			(xy 102.355396 -215.436704) (xy 101.189028 -215.436704) (xy 101.188529 -215.463391) (xy 101.180574 -215.51617)
			(xy 101.164842 -215.567173) (xy 101.141684 -215.615262) (xy 101.111617 -215.659362) (xy 101.075313 -215.698489)
			(xy 101.033583 -215.731767) (xy 100.987359 -215.758454) (xy 100.937674 -215.777954) (xy 100.885637 -215.789831)
			(xy 100.832412 -215.79382) (xy 100.779187 -215.789831) (xy 100.72715 -215.777954) (xy 100.677465 -215.758454)
			(xy 100.631241 -215.731767) (xy 100.589511 -215.698489) (xy 100.553207 -215.659362) (xy 100.52314 -215.615262)
			(xy 100.499982 -215.567173) (xy 100.48425 -215.51617) (xy 100.476295 -215.463391) (xy 100.475796 -215.436704)
			(xy 99.309428 -215.436704) (xy 99.308929 -215.463391) (xy 99.300974 -215.51617) (xy 99.285242 -215.567173)
			(xy 99.262084 -215.615262) (xy 99.232017 -215.659362) (xy 99.195713 -215.698489) (xy 99.153983 -215.731767)
			(xy 99.107759 -215.758454) (xy 99.058074 -215.777954) (xy 99.006037 -215.789831) (xy 98.952812 -215.79382)
			(xy 98.899587 -215.789831) (xy 98.84755 -215.777954) (xy 98.797865 -215.758454) (xy 98.751641 -215.731767)
			(xy 98.709911 -215.698489) (xy 98.673607 -215.659362) (xy 98.64354 -215.615262) (xy 98.620382 -215.567173)
			(xy 98.60465 -215.51617) (xy 98.596695 -215.463391) (xy 98.596196 -215.436704) (xy 97.429828 -215.436704)
			(xy 97.429329 -215.463391) (xy 97.421374 -215.51617) (xy 97.405642 -215.567173) (xy 97.382484 -215.615262)
			(xy 97.352417 -215.659362) (xy 97.316113 -215.698489) (xy 97.274383 -215.731767) (xy 97.228159 -215.758454)
			(xy 97.178474 -215.777954) (xy 97.126437 -215.789831) (xy 97.073212 -215.79382) (xy 97.019987 -215.789831)
			(xy 96.96795 -215.777954) (xy 96.918265 -215.758454) (xy 96.872041 -215.731767) (xy 96.830311 -215.698489)
			(xy 96.794007 -215.659362) (xy 96.76394 -215.615262) (xy 96.740782 -215.567173) (xy 96.72505 -215.51617)
			(xy 96.717095 -215.463391) (xy 96.716596 -215.436704) (xy 95.550228 -215.436704) (xy 95.549729 -215.463391)
			(xy 95.541774 -215.51617) (xy 95.526042 -215.567173) (xy 95.502884 -215.615262) (xy 95.472817 -215.659362)
			(xy 95.436513 -215.698489) (xy 95.394783 -215.731767) (xy 95.348559 -215.758454) (xy 95.298874 -215.777954)
			(xy 95.246837 -215.789831) (xy 95.193612 -215.79382) (xy 95.140387 -215.789831) (xy 95.08835 -215.777954)
			(xy 95.038665 -215.758454) (xy 94.992441 -215.731767) (xy 94.950711 -215.698489) (xy 94.914407 -215.659362)
			(xy 94.88434 -215.615262) (xy 94.861182 -215.567173) (xy 94.84545 -215.51617) (xy 94.837495 -215.463391)
			(xy 94.836996 -215.436704) (xy 93.670628 -215.436704) (xy 93.670129 -215.463391) (xy 93.662174 -215.51617)
			(xy 93.646442 -215.567173) (xy 93.623284 -215.615262) (xy 93.593217 -215.659362) (xy 93.556913 -215.698489)
			(xy 93.515183 -215.731767) (xy 93.468959 -215.758454) (xy 93.419274 -215.777954) (xy 93.367237 -215.789831)
			(xy 93.314012 -215.79382) (xy 93.260787 -215.789831) (xy 93.20875 -215.777954) (xy 93.159065 -215.758454)
			(xy 93.112841 -215.731767) (xy 93.071111 -215.698489) (xy 93.034807 -215.659362) (xy 93.00474 -215.615262)
			(xy 92.981582 -215.567173) (xy 92.96585 -215.51617) (xy 92.957895 -215.463391) (xy 92.957396 -215.436704)
			(xy 91.791028 -215.436704) (xy 91.790529 -215.463391) (xy 91.782574 -215.51617) (xy 91.766842 -215.567173)
			(xy 91.743684 -215.615262) (xy 91.713617 -215.659362) (xy 91.677313 -215.698489) (xy 91.635583 -215.731767)
			(xy 91.589359 -215.758454) (xy 91.539674 -215.777954) (xy 91.487637 -215.789831) (xy 91.434412 -215.79382)
			(xy 91.381187 -215.789831) (xy 91.32915 -215.777954) (xy 91.279465 -215.758454) (xy 91.233241 -215.731767)
			(xy 91.191511 -215.698489) (xy 91.155207 -215.659362) (xy 91.12514 -215.615262) (xy 91.101982 -215.567173)
			(xy 91.08625 -215.51617) (xy 91.078295 -215.463391) (xy 91.077796 -215.436704) (xy 89.911428 -215.436704)
			(xy 89.910929 -215.463391) (xy 89.902974 -215.51617) (xy 89.887242 -215.567173) (xy 89.864084 -215.615262)
			(xy 89.834017 -215.659362) (xy 89.797713 -215.698489) (xy 89.755983 -215.731767) (xy 89.709759 -215.758454)
			(xy 89.660074 -215.777954) (xy 89.608037 -215.789831) (xy 89.554812 -215.79382) (xy 89.501587 -215.789831)
			(xy 89.44955 -215.777954) (xy 89.399865 -215.758454) (xy 89.353641 -215.731767) (xy 89.311911 -215.698489)
			(xy 89.275607 -215.659362) (xy 89.24554 -215.615262) (xy 89.222382 -215.567173) (xy 89.20665 -215.51617)
			(xy 89.198695 -215.463391) (xy 89.198196 -215.436704) (xy 88.971628 -215.436704) (xy 88.971279 -215.460044)
			(xy 88.965172 -215.506323) (xy 88.953062 -215.551406) (xy 88.94445 -215.573102) (xy 88.934798 -215.59647)
			(xy 89.106756 -215.89365) (xy 89.131648 -215.896952) (xy 89.157028 -215.900789) (xy 89.206411 -215.914793)
			(xy 89.253276 -215.93573) (xy 89.296658 -215.963167) (xy 89.335659 -215.996538) (xy 89.369476 -216.035154)
			(xy 89.39741 -216.078217) (xy 89.418884 -216.124839) (xy 89.433455 -216.174057) (xy 89.440822 -216.224855)
			(xy 89.441274 -216.25052) (xy 89.440775 -216.277207) (xy 89.43282 -216.329986) (xy 89.417088 -216.380989)
			(xy 89.39393 -216.429078) (xy 89.363863 -216.473178) (xy 89.327559 -216.512305) (xy 89.285829 -216.545583)
			(xy 89.239605 -216.57227) (xy 89.18992 -216.59177) (xy 89.137883 -216.603647) (xy 89.084658 -216.607636)
			(xy 89.031433 -216.603647) (xy 88.979396 -216.59177) (xy 88.929711 -216.57227) (xy 88.883487 -216.545583)
			(xy 88.841757 -216.512305) (xy 88.805453 -216.473178) (xy 88.775386 -216.429078) (xy 88.752228 -216.380989)
			(xy 88.736496 -216.329986) (xy 88.728541 -216.277207) (xy 88.728042 -216.25052) (xy 88.728401 -216.22718)
			(xy 88.734505 -216.180901) (xy 88.74661 -216.135819) (xy 88.75522 -216.114122) (xy 88.764872 -216.090754)
			(xy 88.592914 -215.793574) (xy 88.568022 -215.790272) (xy 88.542637 -215.786453) (xy 88.49325 -215.772454)
			(xy 88.446379 -215.75152) (xy 88.402994 -215.724083) (xy 88.363989 -215.690711) (xy 88.330171 -215.652092)
			(xy 88.302238 -215.609024) (xy 88.280767 -215.562397) (xy 88.266202 -215.513173) (xy 88.258843 -215.462371)
			(xy 88.258396 -215.436704) (xy 2.509012 -215.436704) (xy 2.509012 -217.878406) (xy 88.72855 -217.878406)
			(xy 88.729049 -217.851719) (xy 88.737004 -217.79894) (xy 88.752736 -217.747937) (xy 88.775894 -217.699848)
			(xy 88.805961 -217.655748) (xy 88.842265 -217.616621) (xy 88.883995 -217.583343) (xy 88.930219 -217.556656)
			(xy 88.979904 -217.537156) (xy 89.031941 -217.525279) (xy 89.085166 -217.52129) (xy 89.138391 -217.525279)
			(xy 89.190428 -217.537156) (xy 89.240113 -217.556656) (xy 89.286337 -217.583343) (xy 89.328067 -217.616621)
			(xy 89.364371 -217.655748) (xy 89.394438 -217.699848) (xy 89.417596 -217.747937) (xy 89.433328 -217.79894)
			(xy 89.441283 -217.851719) (xy 89.441782 -217.878406) (xy 89.66835 -217.878406) (xy 89.668776 -217.852737)
			(xy 89.676124 -217.801928) (xy 89.690682 -217.752698) (xy 89.71215 -217.706064) (xy 89.740084 -217.662992)
			(xy 89.773907 -217.624371) (xy 89.812919 -217.591) (xy 89.856313 -217.563568) (xy 89.903193 -217.542644)
			(xy 89.952589 -217.528659) (xy 89.977976 -217.524838) (xy 90.002868 -217.521536) (xy 90.174826 -217.224102)
			(xy 90.165174 -217.200734) (xy 90.15659 -217.179029) (xy 90.144509 -217.133945) (xy 90.138395 -217.087673)
			(xy 90.137996 -217.064336) (xy 90.138495 -217.037649) (xy 90.14645 -216.98487) (xy 90.162182 -216.933867)
			(xy 90.18534 -216.885778) (xy 90.215407 -216.841678) (xy 90.251711 -216.802551) (xy 90.293441 -216.769273)
			(xy 90.339665 -216.742586) (xy 90.38935 -216.723086) (xy 90.441387 -216.711209) (xy 90.494612 -216.70722)
			(xy 90.547837 -216.711209) (xy 90.599874 -216.723086) (xy 90.649559 -216.742586) (xy 90.695783 -216.769273)
			(xy 90.737513 -216.802551) (xy 90.773817 -216.841678) (xy 90.803884 -216.885778) (xy 90.827042 -216.933867)
			(xy 90.842774 -216.98487) (xy 90.850729 -217.037649) (xy 90.851228 -217.064336) (xy 90.850767 -217.090004)
			(xy 90.843427 -217.140813) (xy 90.828876 -217.190044) (xy 90.807413 -217.236678) (xy 90.779483 -217.279751)
			(xy 90.745664 -217.318373) (xy 90.706654 -217.351745) (xy 90.663262 -217.379177) (xy 90.616383 -217.400101)
			(xy 90.566988 -217.414084) (xy 90.541602 -217.417904) (xy 90.51671 -217.421206) (xy 90.344752 -217.71864)
			(xy 90.354404 -217.742008) (xy 90.362969 -217.76372) (xy 90.375057 -217.8088) (xy 90.381179 -217.85507)
			(xy 90.381582 -217.878406) (xy 90.60815 -217.878406) (xy 90.608649 -217.851719) (xy 90.616604 -217.79894)
			(xy 90.632336 -217.747937) (xy 90.655494 -217.699848) (xy 90.685561 -217.655748) (xy 90.721865 -217.616621)
			(xy 90.763595 -217.583343) (xy 90.809819 -217.556656) (xy 90.859504 -217.537156) (xy 90.911541 -217.525279)
			(xy 90.964766 -217.52129) (xy 91.017991 -217.525279) (xy 91.070028 -217.537156) (xy 91.119713 -217.556656)
			(xy 91.165937 -217.583343) (xy 91.207667 -217.616621) (xy 91.243971 -217.655748) (xy 91.274038 -217.699848)
			(xy 91.297196 -217.747937) (xy 91.312928 -217.79894) (xy 91.320883 -217.851719) (xy 91.321382 -217.878406)
			(xy 91.54795 -217.878406) (xy 91.548376 -217.852737) (xy 91.555724 -217.801928) (xy 91.570282 -217.752698)
			(xy 91.59175 -217.706064) (xy 91.619684 -217.662992) (xy 91.653507 -217.624371) (xy 91.692519 -217.591)
			(xy 91.735913 -217.563568) (xy 91.782793 -217.542644) (xy 91.832189 -217.528659) (xy 91.857576 -217.524838)
			(xy 91.882468 -217.521536) (xy 92.054426 -217.224102) (xy 92.044774 -217.200734) (xy 92.03619 -217.179029)
			(xy 92.024109 -217.133945) (xy 92.017995 -217.087673) (xy 92.017596 -217.064336) (xy 92.018095 -217.037649)
			(xy 92.02605 -216.98487) (xy 92.041782 -216.933867) (xy 92.06494 -216.885778) (xy 92.095007 -216.841678)
			(xy 92.131311 -216.802551) (xy 92.173041 -216.769273) (xy 92.219265 -216.742586) (xy 92.26895 -216.723086)
			(xy 92.320987 -216.711209) (xy 92.374212 -216.70722) (xy 92.427437 -216.711209) (xy 92.479474 -216.723086)
			(xy 92.529159 -216.742586) (xy 92.575383 -216.769273) (xy 92.617113 -216.802551) (xy 92.653417 -216.841678)
			(xy 92.683484 -216.885778) (xy 92.706642 -216.933867) (xy 92.722374 -216.98487) (xy 92.730329 -217.037649)
			(xy 92.730828 -217.064336) (xy 92.730367 -217.090004) (xy 92.723027 -217.140813) (xy 92.708476 -217.190044)
			(xy 92.687013 -217.236678) (xy 92.659083 -217.279751) (xy 92.625264 -217.318373) (xy 92.586254 -217.351745)
			(xy 92.542862 -217.379177) (xy 92.495983 -217.400101) (xy 92.446588 -217.414084) (xy 92.421202 -217.417904)
			(xy 92.39631 -217.421206) (xy 92.224352 -217.71864) (xy 92.234004 -217.742008) (xy 92.242569 -217.76372)
			(xy 92.254657 -217.8088) (xy 92.260779 -217.85507) (xy 92.261182 -217.878406) (xy 92.48775 -217.878406)
			(xy 92.488249 -217.851719) (xy 92.496204 -217.79894) (xy 92.511936 -217.747937) (xy 92.535094 -217.699848)
			(xy 92.565161 -217.655748) (xy 92.601465 -217.616621) (xy 92.643195 -217.583343) (xy 92.689419 -217.556656)
			(xy 92.739104 -217.537156) (xy 92.791141 -217.525279) (xy 92.844366 -217.52129) (xy 92.897591 -217.525279)
			(xy 92.949628 -217.537156) (xy 92.999313 -217.556656) (xy 93.045537 -217.583343) (xy 93.087267 -217.616621)
			(xy 93.123571 -217.655748) (xy 93.153638 -217.699848) (xy 93.176796 -217.747937) (xy 93.192528 -217.79894)
			(xy 93.200483 -217.851719) (xy 93.200982 -217.878406) (xy 93.42755 -217.878406) (xy 93.427976 -217.852737)
			(xy 93.435324 -217.801928) (xy 93.449882 -217.752698) (xy 93.47135 -217.706064) (xy 93.499284 -217.662992)
			(xy 93.533107 -217.624371) (xy 93.572119 -217.591) (xy 93.615513 -217.563568) (xy 93.662393 -217.542644)
			(xy 93.711789 -217.528659) (xy 93.737176 -217.524838) (xy 93.762068 -217.521536) (xy 93.934026 -217.224102)
			(xy 93.924374 -217.200734) (xy 93.91579 -217.179029) (xy 93.903709 -217.133945) (xy 93.897595 -217.087673)
			(xy 93.897196 -217.064336) (xy 93.897695 -217.037649) (xy 93.90565 -216.98487) (xy 93.921382 -216.933867)
			(xy 93.94454 -216.885778) (xy 93.974607 -216.841678) (xy 94.010911 -216.802551) (xy 94.052641 -216.769273)
			(xy 94.098865 -216.742586) (xy 94.14855 -216.723086) (xy 94.200587 -216.711209) (xy 94.253812 -216.70722)
			(xy 94.307037 -216.711209) (xy 94.359074 -216.723086) (xy 94.408759 -216.742586) (xy 94.454983 -216.769273)
			(xy 94.496713 -216.802551) (xy 94.533017 -216.841678) (xy 94.563084 -216.885778) (xy 94.586242 -216.933867)
			(xy 94.601974 -216.98487) (xy 94.609929 -217.037649) (xy 94.610428 -217.064336) (xy 94.609967 -217.090004)
			(xy 94.602627 -217.140813) (xy 94.588076 -217.190044) (xy 94.566613 -217.236678) (xy 94.538683 -217.279751)
			(xy 94.504864 -217.318373) (xy 94.465854 -217.351745) (xy 94.422462 -217.379177) (xy 94.375583 -217.400101)
			(xy 94.326188 -217.414084) (xy 94.300802 -217.417904) (xy 94.27591 -217.421206) (xy 94.103952 -217.71864)
			(xy 94.113604 -217.742008) (xy 94.122169 -217.76372) (xy 94.134257 -217.8088) (xy 94.140379 -217.85507)
			(xy 94.140782 -217.878406) (xy 94.36735 -217.878406) (xy 94.367849 -217.851719) (xy 94.375804 -217.79894)
			(xy 94.391536 -217.747937) (xy 94.414694 -217.699848) (xy 94.444761 -217.655748) (xy 94.481065 -217.616621)
			(xy 94.522795 -217.583343) (xy 94.569019 -217.556656) (xy 94.618704 -217.537156) (xy 94.670741 -217.525279)
			(xy 94.723966 -217.52129) (xy 94.777191 -217.525279) (xy 94.829228 -217.537156) (xy 94.878913 -217.556656)
			(xy 94.925137 -217.583343) (xy 94.966867 -217.616621) (xy 95.003171 -217.655748) (xy 95.033238 -217.699848)
			(xy 95.056396 -217.747937) (xy 95.072128 -217.79894) (xy 95.080083 -217.851719) (xy 95.080582 -217.878406)
			(xy 95.30715 -217.878406) (xy 95.307576 -217.852737) (xy 95.314924 -217.801928) (xy 95.329482 -217.752698)
			(xy 95.35095 -217.706064) (xy 95.378884 -217.662992) (xy 95.412707 -217.624371) (xy 95.451719 -217.591)
			(xy 95.495113 -217.563568) (xy 95.541993 -217.542644) (xy 95.591389 -217.528659) (xy 95.616776 -217.524838)
			(xy 95.641668 -217.521536) (xy 95.813626 -217.224102) (xy 95.803974 -217.200734) (xy 95.79539 -217.179029)
			(xy 95.783309 -217.133945) (xy 95.777195 -217.087673) (xy 95.776796 -217.064336) (xy 95.777295 -217.037649)
			(xy 95.78525 -216.98487) (xy 95.800982 -216.933867) (xy 95.82414 -216.885778) (xy 95.854207 -216.841678)
			(xy 95.890511 -216.802551) (xy 95.932241 -216.769273) (xy 95.978465 -216.742586) (xy 96.02815 -216.723086)
			(xy 96.080187 -216.711209) (xy 96.133412 -216.70722) (xy 96.186637 -216.711209) (xy 96.238674 -216.723086)
			(xy 96.288359 -216.742586) (xy 96.334583 -216.769273) (xy 96.376313 -216.802551) (xy 96.412617 -216.841678)
			(xy 96.442684 -216.885778) (xy 96.465842 -216.933867) (xy 96.481574 -216.98487) (xy 96.489529 -217.037649)
			(xy 96.490028 -217.064336) (xy 96.489567 -217.090004) (xy 96.482227 -217.140813) (xy 96.467676 -217.190044)
			(xy 96.446213 -217.236678) (xy 96.418283 -217.279751) (xy 96.384464 -217.318373) (xy 96.345454 -217.351745)
			(xy 96.302062 -217.379177) (xy 96.255183 -217.400101) (xy 96.205788 -217.414084) (xy 96.180402 -217.417904)
			(xy 96.15551 -217.421206) (xy 95.983552 -217.71864) (xy 95.993204 -217.742008) (xy 96.001769 -217.76372)
			(xy 96.013857 -217.8088) (xy 96.019979 -217.85507) (xy 96.020382 -217.878406) (xy 96.24695 -217.878406)
			(xy 96.247449 -217.851719) (xy 96.255404 -217.79894) (xy 96.271136 -217.747937) (xy 96.294294 -217.699848)
			(xy 96.324361 -217.655748) (xy 96.360665 -217.616621) (xy 96.402395 -217.583343) (xy 96.448619 -217.556656)
			(xy 96.498304 -217.537156) (xy 96.550341 -217.525279) (xy 96.603566 -217.52129) (xy 96.656791 -217.525279)
			(xy 96.708828 -217.537156) (xy 96.758513 -217.556656) (xy 96.804737 -217.583343) (xy 96.846467 -217.616621)
			(xy 96.882771 -217.655748) (xy 96.912838 -217.699848) (xy 96.935996 -217.747937) (xy 96.951728 -217.79894)
			(xy 96.959683 -217.851719) (xy 96.960182 -217.878406) (xy 97.18675 -217.878406) (xy 97.187176 -217.852737)
			(xy 97.194524 -217.801928) (xy 97.209082 -217.752698) (xy 97.23055 -217.706064) (xy 97.258484 -217.662992)
			(xy 97.292307 -217.624371) (xy 97.331319 -217.591) (xy 97.374713 -217.563568) (xy 97.421593 -217.542644)
			(xy 97.470989 -217.528659) (xy 97.496376 -217.524838) (xy 97.521268 -217.521536) (xy 97.693226 -217.224102)
			(xy 97.683574 -217.200734) (xy 97.67499 -217.179029) (xy 97.662909 -217.133945) (xy 97.656795 -217.087673)
			(xy 97.656396 -217.064336) (xy 97.656895 -217.037649) (xy 97.66485 -216.98487) (xy 97.680582 -216.933867)
			(xy 97.70374 -216.885778) (xy 97.733807 -216.841678) (xy 97.770111 -216.802551) (xy 97.811841 -216.769273)
			(xy 97.858065 -216.742586) (xy 97.90775 -216.723086) (xy 97.959787 -216.711209) (xy 98.013012 -216.70722)
			(xy 98.066237 -216.711209) (xy 98.118274 -216.723086) (xy 98.167959 -216.742586) (xy 98.214183 -216.769273)
			(xy 98.255913 -216.802551) (xy 98.292217 -216.841678) (xy 98.322284 -216.885778) (xy 98.345442 -216.933867)
			(xy 98.361174 -216.98487) (xy 98.369129 -217.037649) (xy 98.369628 -217.064336) (xy 98.369167 -217.090004)
			(xy 98.361827 -217.140813) (xy 98.347276 -217.190044) (xy 98.325813 -217.236678) (xy 98.297883 -217.279751)
			(xy 98.264064 -217.318373) (xy 98.225054 -217.351745) (xy 98.181662 -217.379177) (xy 98.134783 -217.400101)
			(xy 98.085388 -217.414084) (xy 98.060002 -217.417904) (xy 98.03511 -217.421206) (xy 97.863152 -217.71864)
			(xy 97.872804 -217.742008) (xy 97.881369 -217.76372) (xy 97.893457 -217.8088) (xy 97.899579 -217.85507)
			(xy 97.899982 -217.878406) (xy 98.12655 -217.878406) (xy 98.127049 -217.851719) (xy 98.135004 -217.79894)
			(xy 98.150736 -217.747937) (xy 98.173894 -217.699848) (xy 98.203961 -217.655748) (xy 98.240265 -217.616621)
			(xy 98.281995 -217.583343) (xy 98.328219 -217.556656) (xy 98.377904 -217.537156) (xy 98.429941 -217.525279)
			(xy 98.483166 -217.52129) (xy 98.536391 -217.525279) (xy 98.588428 -217.537156) (xy 98.638113 -217.556656)
			(xy 98.684337 -217.583343) (xy 98.726067 -217.616621) (xy 98.762371 -217.655748) (xy 98.792438 -217.699848)
			(xy 98.815596 -217.747937) (xy 98.831328 -217.79894) (xy 98.839283 -217.851719) (xy 98.839782 -217.878406)
			(xy 99.06635 -217.878406) (xy 99.066776 -217.852737) (xy 99.074124 -217.801928) (xy 99.088682 -217.752698)
			(xy 99.11015 -217.706064) (xy 99.138084 -217.662992) (xy 99.171907 -217.624371) (xy 99.210919 -217.591)
			(xy 99.254313 -217.563568) (xy 99.301193 -217.542644) (xy 99.350589 -217.528659) (xy 99.375976 -217.524838)
			(xy 99.400868 -217.521536) (xy 99.572826 -217.224102) (xy 99.563174 -217.200734) (xy 99.55459 -217.179029)
			(xy 99.542509 -217.133945) (xy 99.536395 -217.087673) (xy 99.535996 -217.064336) (xy 99.536495 -217.037649)
			(xy 99.54445 -216.98487) (xy 99.560182 -216.933867) (xy 99.58334 -216.885778) (xy 99.613407 -216.841678)
			(xy 99.649711 -216.802551) (xy 99.691441 -216.769273) (xy 99.737665 -216.742586) (xy 99.78735 -216.723086)
			(xy 99.839387 -216.711209) (xy 99.892612 -216.70722) (xy 99.945837 -216.711209) (xy 99.997874 -216.723086)
			(xy 100.047559 -216.742586) (xy 100.093783 -216.769273) (xy 100.135513 -216.802551) (xy 100.171817 -216.841678)
			(xy 100.201884 -216.885778) (xy 100.225042 -216.933867) (xy 100.240774 -216.98487) (xy 100.248729 -217.037649)
			(xy 100.249228 -217.064336) (xy 100.248767 -217.090004) (xy 100.241427 -217.140813) (xy 100.226876 -217.190044)
			(xy 100.205413 -217.236678) (xy 100.177483 -217.279751) (xy 100.143664 -217.318373) (xy 100.104654 -217.351745)
			(xy 100.061262 -217.379177) (xy 100.014383 -217.400101) (xy 99.964988 -217.414084) (xy 99.939602 -217.417904)
			(xy 99.91471 -217.421206) (xy 99.742752 -217.71864) (xy 99.752404 -217.742008) (xy 99.760969 -217.76372)
			(xy 99.773057 -217.8088) (xy 99.779179 -217.85507) (xy 99.779582 -217.878406) (xy 100.00615 -217.878406)
			(xy 100.006649 -217.851719) (xy 100.014604 -217.79894) (xy 100.030336 -217.747937) (xy 100.053494 -217.699848)
			(xy 100.083561 -217.655748) (xy 100.119865 -217.616621) (xy 100.161595 -217.583343) (xy 100.207819 -217.556656)
			(xy 100.257504 -217.537156) (xy 100.309541 -217.525279) (xy 100.362766 -217.52129) (xy 100.415991 -217.525279)
			(xy 100.468028 -217.537156) (xy 100.517713 -217.556656) (xy 100.563937 -217.583343) (xy 100.605667 -217.616621)
			(xy 100.641971 -217.655748) (xy 100.672038 -217.699848) (xy 100.695196 -217.747937) (xy 100.710928 -217.79894)
			(xy 100.718883 -217.851719) (xy 100.719382 -217.878406) (xy 100.94595 -217.878406) (xy 100.946376 -217.852737)
			(xy 100.953724 -217.801928) (xy 100.968282 -217.752698) (xy 100.98975 -217.706064) (xy 101.017684 -217.662992)
			(xy 101.051507 -217.624371) (xy 101.090519 -217.591) (xy 101.133913 -217.563568) (xy 101.180793 -217.542644)
			(xy 101.230189 -217.528659) (xy 101.255576 -217.524838) (xy 101.280468 -217.521536) (xy 101.452426 -217.224102)
			(xy 101.442774 -217.200734) (xy 101.43419 -217.179029) (xy 101.422109 -217.133945) (xy 101.415995 -217.087673)
			(xy 101.415596 -217.064336) (xy 101.416095 -217.037649) (xy 101.42405 -216.98487) (xy 101.439782 -216.933867)
			(xy 101.46294 -216.885778) (xy 101.493007 -216.841678) (xy 101.529311 -216.802551) (xy 101.571041 -216.769273)
			(xy 101.617265 -216.742586) (xy 101.66695 -216.723086) (xy 101.718987 -216.711209) (xy 101.772212 -216.70722)
			(xy 101.825437 -216.711209) (xy 101.877474 -216.723086) (xy 101.927159 -216.742586) (xy 101.973383 -216.769273)
			(xy 102.015113 -216.802551) (xy 102.051417 -216.841678) (xy 102.081484 -216.885778) (xy 102.104642 -216.933867)
			(xy 102.120374 -216.98487) (xy 102.128329 -217.037649) (xy 102.128828 -217.064336) (xy 102.128367 -217.090004)
			(xy 102.121027 -217.140813) (xy 102.106476 -217.190044) (xy 102.085013 -217.236678) (xy 102.057083 -217.279751)
			(xy 102.023264 -217.318373) (xy 101.984254 -217.351745) (xy 101.940862 -217.379177) (xy 101.893983 -217.400101)
			(xy 101.844588 -217.414084) (xy 101.819202 -217.417904) (xy 101.79431 -217.421206) (xy 101.622352 -217.71864)
			(xy 101.632004 -217.742008) (xy 101.640569 -217.76372) (xy 101.652657 -217.8088) (xy 101.658779 -217.85507)
			(xy 101.659182 -217.878406) (xy 101.88575 -217.878406) (xy 101.886249 -217.851719) (xy 101.894204 -217.79894)
			(xy 101.909936 -217.747937) (xy 101.933094 -217.699848) (xy 101.963161 -217.655748) (xy 101.999465 -217.616621)
			(xy 102.041195 -217.583343) (xy 102.087419 -217.556656) (xy 102.137104 -217.537156) (xy 102.189141 -217.525279)
			(xy 102.242366 -217.52129) (xy 102.295591 -217.525279) (xy 102.347628 -217.537156) (xy 102.397313 -217.556656)
			(xy 102.443537 -217.583343) (xy 102.485267 -217.616621) (xy 102.521571 -217.655748) (xy 102.551638 -217.699848)
			(xy 102.574796 -217.747937) (xy 102.590528 -217.79894) (xy 102.598483 -217.851719) (xy 102.598982 -217.878406)
			(xy 102.82555 -217.878406) (xy 102.825976 -217.852737) (xy 102.833324 -217.801928) (xy 102.847882 -217.752698)
			(xy 102.86935 -217.706064) (xy 102.897284 -217.662992) (xy 102.931107 -217.624371) (xy 102.970119 -217.591)
			(xy 103.013513 -217.563568) (xy 103.060393 -217.542644) (xy 103.109789 -217.528659) (xy 103.135176 -217.524838)
			(xy 103.160068 -217.521536) (xy 103.332026 -217.224102) (xy 103.322374 -217.200734) (xy 103.31379 -217.179029)
			(xy 103.301709 -217.133945) (xy 103.295595 -217.087673) (xy 103.295196 -217.064336) (xy 103.295695 -217.037649)
			(xy 103.30365 -216.98487) (xy 103.319382 -216.933867) (xy 103.34254 -216.885778) (xy 103.372607 -216.841678)
			(xy 103.408911 -216.802551) (xy 103.450641 -216.769273) (xy 103.496865 -216.742586) (xy 103.54655 -216.723086)
			(xy 103.598587 -216.711209) (xy 103.651812 -216.70722) (xy 103.705037 -216.711209) (xy 103.757074 -216.723086)
			(xy 103.806759 -216.742586) (xy 103.852983 -216.769273) (xy 103.894713 -216.802551) (xy 103.931017 -216.841678)
			(xy 103.961084 -216.885778) (xy 103.984242 -216.933867) (xy 103.999974 -216.98487) (xy 104.007929 -217.037649)
			(xy 104.008428 -217.064336) (xy 104.007967 -217.090004) (xy 104.000627 -217.140813) (xy 103.986076 -217.190044)
			(xy 103.964613 -217.236678) (xy 103.936683 -217.279751) (xy 103.902864 -217.318373) (xy 103.863854 -217.351745)
			(xy 103.820462 -217.379177) (xy 103.773583 -217.400101) (xy 103.724188 -217.414084) (xy 103.698802 -217.417904)
			(xy 103.67391 -217.421206) (xy 103.501952 -217.71864) (xy 103.511604 -217.742008) (xy 103.520169 -217.76372)
			(xy 103.532257 -217.8088) (xy 103.538379 -217.85507) (xy 103.538782 -217.878406) (xy 103.76535 -217.878406)
			(xy 103.765849 -217.851719) (xy 103.773804 -217.79894) (xy 103.789536 -217.747937) (xy 103.812694 -217.699848)
			(xy 103.842761 -217.655748) (xy 103.879065 -217.616621) (xy 103.920795 -217.583343) (xy 103.967019 -217.556656)
			(xy 104.016704 -217.537156) (xy 104.068741 -217.525279) (xy 104.121966 -217.52129) (xy 104.175191 -217.525279)
			(xy 104.227228 -217.537156) (xy 104.276913 -217.556656) (xy 104.323137 -217.583343) (xy 104.364867 -217.616621)
			(xy 104.401171 -217.655748) (xy 104.431238 -217.699848) (xy 104.454396 -217.747937) (xy 104.470128 -217.79894)
			(xy 104.478083 -217.851719) (xy 104.478582 -217.878406) (xy 104.70515 -217.878406) (xy 104.705576 -217.852737)
			(xy 104.712924 -217.801928) (xy 104.727482 -217.752698) (xy 104.74895 -217.706064) (xy 104.776884 -217.662992)
			(xy 104.810707 -217.624371) (xy 104.849719 -217.591) (xy 104.893113 -217.563568) (xy 104.939993 -217.542644)
			(xy 104.989389 -217.528659) (xy 105.014776 -217.524838) (xy 105.039668 -217.521536) (xy 105.211626 -217.224102)
			(xy 105.201974 -217.200734) (xy 105.19339 -217.179029) (xy 105.181309 -217.133945) (xy 105.175195 -217.087673)
			(xy 105.174796 -217.064336) (xy 105.175295 -217.037649) (xy 105.18325 -216.98487) (xy 105.198982 -216.933867)
			(xy 105.22214 -216.885778) (xy 105.252207 -216.841678) (xy 105.288511 -216.802551) (xy 105.330241 -216.769273)
			(xy 105.376465 -216.742586) (xy 105.42615 -216.723086) (xy 105.478187 -216.711209) (xy 105.531412 -216.70722)
			(xy 105.584637 -216.711209) (xy 105.636674 -216.723086) (xy 105.686359 -216.742586) (xy 105.732583 -216.769273)
			(xy 105.774313 -216.802551) (xy 105.810617 -216.841678) (xy 105.840684 -216.885778) (xy 105.863842 -216.933867)
			(xy 105.879574 -216.98487) (xy 105.887529 -217.037649) (xy 105.888028 -217.064336) (xy 105.887567 -217.090004)
			(xy 105.880227 -217.140813) (xy 105.865676 -217.190044) (xy 105.844213 -217.236678) (xy 105.816283 -217.279751)
			(xy 105.782464 -217.318373) (xy 105.743454 -217.351745) (xy 105.700062 -217.379177) (xy 105.653183 -217.400101)
			(xy 105.603788 -217.414084) (xy 105.578402 -217.417904) (xy 105.55351 -217.421206) (xy 105.381552 -217.71864)
			(xy 105.391204 -217.742008) (xy 105.399769 -217.76372) (xy 105.411857 -217.8088) (xy 105.417979 -217.85507)
			(xy 105.418382 -217.878406) (xy 105.64495 -217.878406) (xy 105.645449 -217.851719) (xy 105.653404 -217.79894)
			(xy 105.669136 -217.747937) (xy 105.692294 -217.699848) (xy 105.722361 -217.655748) (xy 105.758665 -217.616621)
			(xy 105.800395 -217.583343) (xy 105.846619 -217.556656) (xy 105.896304 -217.537156) (xy 105.948341 -217.525279)
			(xy 106.001566 -217.52129) (xy 106.054791 -217.525279) (xy 106.106828 -217.537156) (xy 106.156513 -217.556656)
			(xy 106.202737 -217.583343) (xy 106.244467 -217.616621) (xy 106.280771 -217.655748) (xy 106.310838 -217.699848)
			(xy 106.333996 -217.747937) (xy 106.349728 -217.79894) (xy 106.357683 -217.851719) (xy 106.358182 -217.878406)
			(xy 106.58475 -217.878406) (xy 106.585176 -217.852737) (xy 106.592524 -217.801928) (xy 106.607082 -217.752698)
			(xy 106.62855 -217.706064) (xy 106.656484 -217.662992) (xy 106.690307 -217.624371) (xy 106.729319 -217.591)
			(xy 106.772713 -217.563568) (xy 106.819593 -217.542644) (xy 106.868989 -217.528659) (xy 106.894376 -217.524838)
			(xy 106.919268 -217.521536) (xy 107.091226 -217.224102) (xy 107.081574 -217.200734) (xy 107.07299 -217.179029)
			(xy 107.060909 -217.133945) (xy 107.054795 -217.087673) (xy 107.054396 -217.064336) (xy 107.054895 -217.037649)
			(xy 107.06285 -216.98487) (xy 107.078582 -216.933867) (xy 107.10174 -216.885778) (xy 107.131807 -216.841678)
			(xy 107.168111 -216.802551) (xy 107.209841 -216.769273) (xy 107.256065 -216.742586) (xy 107.30575 -216.723086)
			(xy 107.357787 -216.711209) (xy 107.411012 -216.70722) (xy 107.464237 -216.711209) (xy 107.516274 -216.723086)
			(xy 107.565959 -216.742586) (xy 107.612183 -216.769273) (xy 107.653913 -216.802551) (xy 107.690217 -216.841678)
			(xy 107.720284 -216.885778) (xy 107.743442 -216.933867) (xy 107.759174 -216.98487) (xy 107.767129 -217.037649)
			(xy 107.767628 -217.064336) (xy 107.767167 -217.090004) (xy 107.759827 -217.140813) (xy 107.745276 -217.190044)
			(xy 107.723813 -217.236678) (xy 107.695883 -217.279751) (xy 107.662064 -217.318373) (xy 107.623054 -217.351745)
			(xy 107.579662 -217.379177) (xy 107.532783 -217.400101) (xy 107.483388 -217.414084) (xy 107.458002 -217.417904)
			(xy 107.43311 -217.421206) (xy 107.261152 -217.71864) (xy 107.270804 -217.742008) (xy 107.279369 -217.76372)
			(xy 107.291457 -217.8088) (xy 107.297579 -217.85507) (xy 107.297982 -217.878406) (xy 107.52455 -217.878406)
			(xy 107.525049 -217.851719) (xy 107.533004 -217.79894) (xy 107.548736 -217.747937) (xy 107.571894 -217.699848)
			(xy 107.601961 -217.655748) (xy 107.638265 -217.616621) (xy 107.679995 -217.583343) (xy 107.726219 -217.556656)
			(xy 107.775904 -217.537156) (xy 107.827941 -217.525279) (xy 107.881166 -217.52129) (xy 107.934391 -217.525279)
			(xy 107.986428 -217.537156) (xy 108.036113 -217.556656) (xy 108.082337 -217.583343) (xy 108.124067 -217.616621)
			(xy 108.160371 -217.655748) (xy 108.190438 -217.699848) (xy 108.213596 -217.747937) (xy 108.229328 -217.79894)
			(xy 108.237283 -217.851719) (xy 108.237782 -217.878406) (xy 108.46435 -217.878406) (xy 108.464776 -217.852737)
			(xy 108.472124 -217.801928) (xy 108.486682 -217.752698) (xy 108.50815 -217.706064) (xy 108.536084 -217.662992)
			(xy 108.569907 -217.624371) (xy 108.608919 -217.591) (xy 108.652313 -217.563568) (xy 108.699193 -217.542644)
			(xy 108.748589 -217.528659) (xy 108.773976 -217.524838) (xy 108.798868 -217.521536) (xy 108.970826 -217.224102)
			(xy 108.961174 -217.200734) (xy 108.95259 -217.179029) (xy 108.940509 -217.133945) (xy 108.934395 -217.087673)
			(xy 108.933996 -217.064336) (xy 108.934495 -217.037649) (xy 108.94245 -216.98487) (xy 108.958182 -216.933867)
			(xy 108.98134 -216.885778) (xy 109.011407 -216.841678) (xy 109.047711 -216.802551) (xy 109.089441 -216.769273)
			(xy 109.135665 -216.742586) (xy 109.18535 -216.723086) (xy 109.237387 -216.711209) (xy 109.290612 -216.70722)
			(xy 109.343837 -216.711209) (xy 109.395874 -216.723086) (xy 109.445559 -216.742586) (xy 109.491783 -216.769273)
			(xy 109.533513 -216.802551) (xy 109.569817 -216.841678) (xy 109.599884 -216.885778) (xy 109.623042 -216.933867)
			(xy 109.638774 -216.98487) (xy 109.646729 -217.037649) (xy 109.647228 -217.064336) (xy 109.646767 -217.090004)
			(xy 109.639427 -217.140813) (xy 109.624876 -217.190044) (xy 109.603413 -217.236678) (xy 109.575483 -217.279751)
			(xy 109.541664 -217.318373) (xy 109.502654 -217.351745) (xy 109.459262 -217.379177) (xy 109.412383 -217.400101)
			(xy 109.362988 -217.414084) (xy 109.337602 -217.417904) (xy 109.31271 -217.421206) (xy 109.140752 -217.71864)
			(xy 109.150404 -217.742008) (xy 109.158969 -217.76372) (xy 109.171057 -217.8088) (xy 109.177179 -217.85507)
			(xy 109.177582 -217.878406) (xy 109.40415 -217.878406) (xy 109.404649 -217.851719) (xy 109.412604 -217.79894)
			(xy 109.428336 -217.747937) (xy 109.451494 -217.699848) (xy 109.481561 -217.655748) (xy 109.517865 -217.616621)
			(xy 109.559595 -217.583343) (xy 109.605819 -217.556656) (xy 109.655504 -217.537156) (xy 109.707541 -217.525279)
			(xy 109.760766 -217.52129) (xy 109.813991 -217.525279) (xy 109.866028 -217.537156) (xy 109.915713 -217.556656)
			(xy 109.961937 -217.583343) (xy 110.003667 -217.616621) (xy 110.039971 -217.655748) (xy 110.070038 -217.699848)
			(xy 110.093196 -217.747937) (xy 110.108928 -217.79894) (xy 110.116883 -217.851719) (xy 110.117382 -217.878406)
			(xy 110.34395 -217.878406) (xy 110.344376 -217.852737) (xy 110.351724 -217.801928) (xy 110.366282 -217.752698)
			(xy 110.38775 -217.706064) (xy 110.415684 -217.662992) (xy 110.449507 -217.624371) (xy 110.488519 -217.591)
			(xy 110.531913 -217.563568) (xy 110.578793 -217.542644) (xy 110.628189 -217.528659) (xy 110.653576 -217.524838)
			(xy 110.678468 -217.521536) (xy 110.850426 -217.223594) (xy 110.840774 -217.20048) (xy 110.832281 -217.178884)
			(xy 110.820298 -217.134054) (xy 110.81424 -217.088046) (xy 110.81385 -217.064844) (xy 110.81385 -217.064336)
			(xy 110.814349 -217.037649) (xy 110.822304 -216.98487) (xy 110.838036 -216.933867) (xy 110.861194 -216.885778)
			(xy 110.891261 -216.841678) (xy 110.927565 -216.802551) (xy 110.969295 -216.769273) (xy 111.015519 -216.742586)
			(xy 111.065204 -216.723086) (xy 111.117241 -216.711209) (xy 111.170466 -216.70722) (xy 111.223691 -216.711209)
			(xy 111.275728 -216.723086) (xy 111.325413 -216.742586) (xy 111.371637 -216.769273) (xy 111.413367 -216.802551)
			(xy 111.449671 -216.841678) (xy 111.479738 -216.885778) (xy 111.502896 -216.933867) (xy 111.518628 -216.98487)
			(xy 111.526583 -217.037649) (xy 111.527082 -217.064336) (xy 112.693196 -217.064336) (xy 112.693695 -217.037649)
			(xy 112.70165 -216.98487) (xy 112.717382 -216.933867) (xy 112.74054 -216.885778) (xy 112.770607 -216.841678)
			(xy 112.806911 -216.802551) (xy 112.848641 -216.769273) (xy 112.894865 -216.742586) (xy 112.94455 -216.723086)
			(xy 112.996587 -216.711209) (xy 113.049812 -216.70722) (xy 113.103037 -216.711209) (xy 113.155074 -216.723086)
			(xy 113.204759 -216.742586) (xy 113.250983 -216.769273) (xy 113.292713 -216.802551) (xy 113.329017 -216.841678)
			(xy 113.359084 -216.885778) (xy 113.382242 -216.933867) (xy 113.397974 -216.98487) (xy 113.405929 -217.037649)
			(xy 113.406428 -217.064336) (xy 114.572796 -217.064336) (xy 114.573295 -217.037649) (xy 114.58125 -216.98487)
			(xy 114.596982 -216.933867) (xy 114.62014 -216.885778) (xy 114.650207 -216.841678) (xy 114.686511 -216.802551)
			(xy 114.728241 -216.769273) (xy 114.774465 -216.742586) (xy 114.82415 -216.723086) (xy 114.876187 -216.711209)
			(xy 114.929412 -216.70722) (xy 114.982637 -216.711209) (xy 115.034674 -216.723086) (xy 115.084359 -216.742586)
			(xy 115.130583 -216.769273) (xy 115.172313 -216.802551) (xy 115.208617 -216.841678) (xy 115.238684 -216.885778)
			(xy 115.261842 -216.933867) (xy 115.277574 -216.98487) (xy 115.285529 -217.037649) (xy 115.286028 -217.064336)
			(xy 116.452396 -217.064336) (xy 116.452895 -217.037649) (xy 116.46085 -216.98487) (xy 116.476582 -216.933867)
			(xy 116.49974 -216.885778) (xy 116.529807 -216.841678) (xy 116.566111 -216.802551) (xy 116.607841 -216.769273)
			(xy 116.654065 -216.742586) (xy 116.70375 -216.723086) (xy 116.755787 -216.711209) (xy 116.809012 -216.70722)
			(xy 116.862237 -216.711209) (xy 116.914274 -216.723086) (xy 116.963959 -216.742586) (xy 117.010183 -216.769273)
			(xy 117.051913 -216.802551) (xy 117.088217 -216.841678) (xy 117.118284 -216.885778) (xy 117.141442 -216.933867)
			(xy 117.157174 -216.98487) (xy 117.165129 -217.037649) (xy 117.165628 -217.064336) (xy 118.331996 -217.064336)
			(xy 118.332495 -217.037649) (xy 118.34045 -216.98487) (xy 118.356182 -216.933867) (xy 118.37934 -216.885778)
			(xy 118.409407 -216.841678) (xy 118.445711 -216.802551) (xy 118.487441 -216.769273) (xy 118.533665 -216.742586)
			(xy 118.58335 -216.723086) (xy 118.635387 -216.711209) (xy 118.688612 -216.70722) (xy 118.741837 -216.711209)
			(xy 118.793874 -216.723086) (xy 118.843559 -216.742586) (xy 118.889783 -216.769273) (xy 118.931513 -216.802551)
			(xy 118.967817 -216.841678) (xy 118.997884 -216.885778) (xy 119.021042 -216.933867) (xy 119.036774 -216.98487)
			(xy 119.044729 -217.037649) (xy 119.045228 -217.064336) (xy 120.211596 -217.064336) (xy 120.212095 -217.037649)
			(xy 120.22005 -216.98487) (xy 120.235782 -216.933867) (xy 120.25894 -216.885778) (xy 120.289007 -216.841678)
			(xy 120.325311 -216.802551) (xy 120.367041 -216.769273) (xy 120.413265 -216.742586) (xy 120.46295 -216.723086)
			(xy 120.514987 -216.711209) (xy 120.568212 -216.70722) (xy 120.621437 -216.711209) (xy 120.673474 -216.723086)
			(xy 120.723159 -216.742586) (xy 120.769383 -216.769273) (xy 120.811113 -216.802551) (xy 120.847417 -216.841678)
			(xy 120.877484 -216.885778) (xy 120.900642 -216.933867) (xy 120.916374 -216.98487) (xy 120.924329 -217.037649)
			(xy 120.924828 -217.064336) (xy 122.091196 -217.064336) (xy 122.091695 -217.037649) (xy 122.09965 -216.98487)
			(xy 122.115382 -216.933867) (xy 122.13854 -216.885778) (xy 122.168607 -216.841678) (xy 122.204911 -216.802551)
			(xy 122.246641 -216.769273) (xy 122.292865 -216.742586) (xy 122.34255 -216.723086) (xy 122.394587 -216.711209)
			(xy 122.447812 -216.70722) (xy 122.501037 -216.711209) (xy 122.553074 -216.723086) (xy 122.602759 -216.742586)
			(xy 122.648983 -216.769273) (xy 122.690713 -216.802551) (xy 122.727017 -216.841678) (xy 122.757084 -216.885778)
			(xy 122.780242 -216.933867) (xy 122.795974 -216.98487) (xy 122.803929 -217.037649) (xy 122.804428 -217.064336)
			(xy 123.970796 -217.064336) (xy 123.971295 -217.037649) (xy 123.97925 -216.98487) (xy 123.994982 -216.933867)
			(xy 124.01814 -216.885778) (xy 124.048207 -216.841678) (xy 124.084511 -216.802551) (xy 124.126241 -216.769273)
			(xy 124.172465 -216.742586) (xy 124.22215 -216.723086) (xy 124.274187 -216.711209) (xy 124.327412 -216.70722)
			(xy 124.380637 -216.711209) (xy 124.432674 -216.723086) (xy 124.482359 -216.742586) (xy 124.528583 -216.769273)
			(xy 124.570313 -216.802551) (xy 124.606617 -216.841678) (xy 124.636684 -216.885778) (xy 124.659842 -216.933867)
			(xy 124.675574 -216.98487) (xy 124.683529 -217.037649) (xy 124.684028 -217.064336) (xy 125.850396 -217.064336)
			(xy 125.850895 -217.037649) (xy 125.85885 -216.98487) (xy 125.874582 -216.933867) (xy 125.89774 -216.885778)
			(xy 125.927807 -216.841678) (xy 125.964111 -216.802551) (xy 126.005841 -216.769273) (xy 126.052065 -216.742586)
			(xy 126.10175 -216.723086) (xy 126.153787 -216.711209) (xy 126.207012 -216.70722) (xy 126.260237 -216.711209)
			(xy 126.312274 -216.723086) (xy 126.361959 -216.742586) (xy 126.408183 -216.769273) (xy 126.449913 -216.802551)
			(xy 126.486217 -216.841678) (xy 126.516284 -216.885778) (xy 126.539442 -216.933867) (xy 126.555174 -216.98487)
			(xy 126.563129 -217.037649) (xy 126.563628 -217.064336) (xy 127.729996 -217.064336) (xy 127.730495 -217.037649)
			(xy 127.73845 -216.98487) (xy 127.754182 -216.933867) (xy 127.77734 -216.885778) (xy 127.807407 -216.841678)
			(xy 127.843711 -216.802551) (xy 127.885441 -216.769273) (xy 127.931665 -216.742586) (xy 127.98135 -216.723086)
			(xy 128.033387 -216.711209) (xy 128.086612 -216.70722) (xy 128.139837 -216.711209) (xy 128.191874 -216.723086)
			(xy 128.241559 -216.742586) (xy 128.287783 -216.769273) (xy 128.329513 -216.802551) (xy 128.365817 -216.841678)
			(xy 128.395884 -216.885778) (xy 128.419042 -216.933867) (xy 128.434774 -216.98487) (xy 128.442729 -217.037649)
			(xy 128.443228 -217.064336) (xy 129.609596 -217.064336) (xy 129.610095 -217.037649) (xy 129.61805 -216.98487)
			(xy 129.633782 -216.933867) (xy 129.65694 -216.885778) (xy 129.687007 -216.841678) (xy 129.723311 -216.802551)
			(xy 129.765041 -216.769273) (xy 129.811265 -216.742586) (xy 129.86095 -216.723086) (xy 129.912987 -216.711209)
			(xy 129.966212 -216.70722) (xy 130.019437 -216.711209) (xy 130.071474 -216.723086) (xy 130.121159 -216.742586)
			(xy 130.167383 -216.769273) (xy 130.209113 -216.802551) (xy 130.245417 -216.841678) (xy 130.275484 -216.885778)
			(xy 130.298642 -216.933867) (xy 130.314374 -216.98487) (xy 130.322329 -217.037649) (xy 130.322828 -217.064336)
			(xy 131.489196 -217.064336) (xy 131.489695 -217.037649) (xy 131.49765 -216.98487) (xy 131.513382 -216.933867)
			(xy 131.53654 -216.885778) (xy 131.566607 -216.841678) (xy 131.602911 -216.802551) (xy 131.644641 -216.769273)
			(xy 131.690865 -216.742586) (xy 131.74055 -216.723086) (xy 131.792587 -216.711209) (xy 131.845812 -216.70722)
			(xy 131.899037 -216.711209) (xy 131.951074 -216.723086) (xy 132.000759 -216.742586) (xy 132.046983 -216.769273)
			(xy 132.088713 -216.802551) (xy 132.125017 -216.841678) (xy 132.155084 -216.885778) (xy 132.178242 -216.933867)
			(xy 132.193974 -216.98487) (xy 132.201929 -217.037649) (xy 132.202428 -217.064336) (xy 133.368796 -217.064336)
			(xy 133.369295 -217.037649) (xy 133.37725 -216.98487) (xy 133.392982 -216.933867) (xy 133.41614 -216.885778)
			(xy 133.446207 -216.841678) (xy 133.482511 -216.802551) (xy 133.524241 -216.769273) (xy 133.570465 -216.742586)
			(xy 133.62015 -216.723086) (xy 133.672187 -216.711209) (xy 133.725412 -216.70722) (xy 133.778637 -216.711209)
			(xy 133.830674 -216.723086) (xy 133.880359 -216.742586) (xy 133.926583 -216.769273) (xy 133.968313 -216.802551)
			(xy 134.004617 -216.841678) (xy 134.034684 -216.885778) (xy 134.057842 -216.933867) (xy 134.073574 -216.98487)
			(xy 134.081529 -217.037649) (xy 134.082028 -217.064336) (xy 134.082028 -217.064844) (xy 134.081621 -217.088045)
			(xy 134.075564 -217.134052) (xy 134.063598 -217.178886) (xy 134.055104 -217.20048) (xy 134.045452 -217.223594)
			(xy 134.217664 -217.521536) (xy 134.242556 -217.524838) (xy 134.267935 -217.528682) (xy 134.317316 -217.542687)
			(xy 134.364181 -217.563624) (xy 134.407562 -217.59106) (xy 134.446563 -217.62443) (xy 134.480379 -217.663045)
			(xy 134.508313 -217.706107) (xy 134.529788 -217.752728) (xy 134.54436 -217.801945) (xy 134.551729 -217.852742)
			(xy 134.552182 -217.878406) (xy 336.668618 -217.878406) (xy 336.669117 -217.851719) (xy 336.677072 -217.79894)
			(xy 336.692804 -217.747937) (xy 336.715962 -217.699848) (xy 336.746029 -217.655748) (xy 336.782333 -217.616621)
			(xy 336.824063 -217.583343) (xy 336.870287 -217.556656) (xy 336.919972 -217.537156) (xy 336.972009 -217.525279)
			(xy 337.025234 -217.52129) (xy 337.078459 -217.525279) (xy 337.130496 -217.537156) (xy 337.180181 -217.556656)
			(xy 337.226405 -217.583343) (xy 337.268135 -217.616621) (xy 337.304439 -217.655748) (xy 337.334506 -217.699848)
			(xy 337.357664 -217.747937) (xy 337.373396 -217.79894) (xy 337.381351 -217.851719) (xy 337.38185 -217.878406)
			(xy 337.608418 -217.878406) (xy 337.608872 -217.852738) (xy 337.616219 -217.801932) (xy 337.630775 -217.752704)
			(xy 337.652241 -217.706072) (xy 337.680172 -217.663001) (xy 337.713991 -217.62438) (xy 337.753 -217.591008)
			(xy 337.79639 -217.563576) (xy 337.843266 -217.542649) (xy 337.892659 -217.528661) (xy 337.918044 -217.524838)
			(xy 337.942936 -217.521536) (xy 338.114894 -217.224102) (xy 338.105242 -217.200734) (xy 338.096662 -217.179028)
			(xy 338.084579 -217.133945) (xy 338.078464 -217.087673) (xy 338.078064 -217.064336) (xy 338.078563 -217.037649)
			(xy 338.086518 -216.98487) (xy 338.10225 -216.933867) (xy 338.125408 -216.885778) (xy 338.155475 -216.841678)
			(xy 338.191779 -216.802551) (xy 338.233509 -216.769273) (xy 338.279733 -216.742586) (xy 338.329418 -216.723086)
			(xy 338.381455 -216.711209) (xy 338.43468 -216.70722) (xy 338.487905 -216.711209) (xy 338.539942 -216.723086)
			(xy 338.589627 -216.742586) (xy 338.635851 -216.769273) (xy 338.677581 -216.802551) (xy 338.713885 -216.841678)
			(xy 338.743952 -216.885778) (xy 338.76711 -216.933867) (xy 338.782842 -216.98487) (xy 338.790797 -217.037649)
			(xy 338.791296 -217.064336) (xy 338.790777 -217.090002) (xy 338.783438 -217.140805) (xy 338.76889 -217.190031)
			(xy 338.747432 -217.236662) (xy 338.719508 -217.279733) (xy 338.685696 -217.318354) (xy 338.646695 -217.351726)
			(xy 338.603311 -217.379161) (xy 338.55644 -217.400089) (xy 338.507053 -217.41408) (xy 338.48167 -217.417904)
			(xy 338.456778 -217.421206) (xy 338.28482 -217.71864) (xy 338.294472 -217.742008) (xy 338.303035 -217.76372)
			(xy 338.315124 -217.8088) (xy 338.321246 -217.85507) (xy 338.32165 -217.878406) (xy 338.548218 -217.878406)
			(xy 338.548717 -217.851719) (xy 338.556672 -217.79894) (xy 338.572404 -217.747937) (xy 338.595562 -217.699848)
			(xy 338.625629 -217.655748) (xy 338.661933 -217.616621) (xy 338.703663 -217.583343) (xy 338.749887 -217.556656)
			(xy 338.799572 -217.537156) (xy 338.851609 -217.525279) (xy 338.904834 -217.52129) (xy 338.958059 -217.525279)
			(xy 339.010096 -217.537156) (xy 339.059781 -217.556656) (xy 339.106005 -217.583343) (xy 339.147735 -217.616621)
			(xy 339.184039 -217.655748) (xy 339.214106 -217.699848) (xy 339.237264 -217.747937) (xy 339.252996 -217.79894)
			(xy 339.260951 -217.851719) (xy 339.26145 -217.878406) (xy 339.488018 -217.878406) (xy 339.488472 -217.852738)
			(xy 339.495819 -217.801932) (xy 339.510375 -217.752704) (xy 339.531841 -217.706072) (xy 339.559772 -217.663001)
			(xy 339.593591 -217.62438) (xy 339.6326 -217.591008) (xy 339.67599 -217.563576) (xy 339.722866 -217.542649)
			(xy 339.772259 -217.528661) (xy 339.797644 -217.524838) (xy 339.822536 -217.521536) (xy 339.994494 -217.224102)
			(xy 339.984842 -217.200734) (xy 339.976262 -217.179028) (xy 339.964179 -217.133945) (xy 339.958064 -217.087673)
			(xy 339.957664 -217.064336) (xy 339.958163 -217.037649) (xy 339.966118 -216.98487) (xy 339.98185 -216.933867)
			(xy 340.005008 -216.885778) (xy 340.035075 -216.841678) (xy 340.071379 -216.802551) (xy 340.113109 -216.769273)
			(xy 340.159333 -216.742586) (xy 340.209018 -216.723086) (xy 340.261055 -216.711209) (xy 340.31428 -216.70722)
			(xy 340.367505 -216.711209) (xy 340.419542 -216.723086) (xy 340.469227 -216.742586) (xy 340.515451 -216.769273)
			(xy 340.557181 -216.802551) (xy 340.593485 -216.841678) (xy 340.623552 -216.885778) (xy 340.64671 -216.933867)
			(xy 340.662442 -216.98487) (xy 340.670397 -217.037649) (xy 340.670896 -217.064336) (xy 340.670377 -217.090002)
			(xy 340.663038 -217.140805) (xy 340.64849 -217.190031) (xy 340.627032 -217.236662) (xy 340.599108 -217.279733)
			(xy 340.565296 -217.318354) (xy 340.526295 -217.351726) (xy 340.482911 -217.379161) (xy 340.43604 -217.400089)
			(xy 340.386653 -217.41408) (xy 340.36127 -217.417904) (xy 340.336378 -217.421206) (xy 340.16442 -217.71864)
			(xy 340.174072 -217.742008) (xy 340.182635 -217.76372) (xy 340.194724 -217.8088) (xy 340.200846 -217.85507)
			(xy 340.20125 -217.878406) (xy 340.427818 -217.878406) (xy 340.428317 -217.851719) (xy 340.436272 -217.79894)
			(xy 340.452004 -217.747937) (xy 340.475162 -217.699848) (xy 340.505229 -217.655748) (xy 340.541533 -217.616621)
			(xy 340.583263 -217.583343) (xy 340.629487 -217.556656) (xy 340.679172 -217.537156) (xy 340.731209 -217.525279)
			(xy 340.784434 -217.52129) (xy 340.837659 -217.525279) (xy 340.889696 -217.537156) (xy 340.939381 -217.556656)
			(xy 340.985605 -217.583343) (xy 341.027335 -217.616621) (xy 341.063639 -217.655748) (xy 341.093706 -217.699848)
			(xy 341.116864 -217.747937) (xy 341.132596 -217.79894) (xy 341.140551 -217.851719) (xy 341.14105 -217.878406)
			(xy 341.367618 -217.878406) (xy 341.368072 -217.852738) (xy 341.375419 -217.801932) (xy 341.389975 -217.752704)
			(xy 341.411441 -217.706072) (xy 341.439372 -217.663001) (xy 341.473191 -217.62438) (xy 341.5122 -217.591008)
			(xy 341.55559 -217.563576) (xy 341.602466 -217.542649) (xy 341.651859 -217.528661) (xy 341.677244 -217.524838)
			(xy 341.702136 -217.521536) (xy 341.874094 -217.224102) (xy 341.864442 -217.200734) (xy 341.855862 -217.179028)
			(xy 341.843779 -217.133945) (xy 341.837664 -217.087673) (xy 341.837264 -217.064336) (xy 341.837763 -217.037649)
			(xy 341.845718 -216.98487) (xy 341.86145 -216.933867) (xy 341.884608 -216.885778) (xy 341.914675 -216.841678)
			(xy 341.950979 -216.802551) (xy 341.992709 -216.769273) (xy 342.038933 -216.742586) (xy 342.088618 -216.723086)
			(xy 342.140655 -216.711209) (xy 342.19388 -216.70722) (xy 342.247105 -216.711209) (xy 342.299142 -216.723086)
			(xy 342.348827 -216.742586) (xy 342.395051 -216.769273) (xy 342.436781 -216.802551) (xy 342.473085 -216.841678)
			(xy 342.503152 -216.885778) (xy 342.52631 -216.933867) (xy 342.542042 -216.98487) (xy 342.549997 -217.037649)
			(xy 342.550496 -217.064336) (xy 342.549977 -217.090002) (xy 342.542638 -217.140805) (xy 342.52809 -217.190031)
			(xy 342.506632 -217.236662) (xy 342.478708 -217.279733) (xy 342.444896 -217.318354) (xy 342.405895 -217.351726)
			(xy 342.362511 -217.379161) (xy 342.31564 -217.400089) (xy 342.266253 -217.41408) (xy 342.24087 -217.417904)
			(xy 342.215978 -217.421206) (xy 342.04402 -217.71864) (xy 342.053672 -217.742008) (xy 342.062235 -217.76372)
			(xy 342.074324 -217.8088) (xy 342.080446 -217.85507) (xy 342.08085 -217.878406) (xy 342.307418 -217.878406)
			(xy 342.307917 -217.851719) (xy 342.315872 -217.79894) (xy 342.331604 -217.747937) (xy 342.354762 -217.699848)
			(xy 342.384829 -217.655748) (xy 342.421133 -217.616621) (xy 342.462863 -217.583343) (xy 342.509087 -217.556656)
			(xy 342.558772 -217.537156) (xy 342.610809 -217.525279) (xy 342.664034 -217.52129) (xy 342.717259 -217.525279)
			(xy 342.769296 -217.537156) (xy 342.818981 -217.556656) (xy 342.865205 -217.583343) (xy 342.906935 -217.616621)
			(xy 342.943239 -217.655748) (xy 342.973306 -217.699848) (xy 342.996464 -217.747937) (xy 343.012196 -217.79894)
			(xy 343.020151 -217.851719) (xy 343.02065 -217.878406) (xy 343.247218 -217.878406) (xy 343.247672 -217.852738)
			(xy 343.255019 -217.801932) (xy 343.269575 -217.752704) (xy 343.291041 -217.706072) (xy 343.318972 -217.663001)
			(xy 343.352791 -217.62438) (xy 343.3918 -217.591008) (xy 343.43519 -217.563576) (xy 343.482066 -217.542649)
			(xy 343.531459 -217.528661) (xy 343.556844 -217.524838) (xy 343.581736 -217.521536) (xy 343.753694 -217.224102)
			(xy 343.744042 -217.200734) (xy 343.735462 -217.179028) (xy 343.723379 -217.133945) (xy 343.717264 -217.087673)
			(xy 343.716864 -217.064336) (xy 343.717363 -217.037649) (xy 343.725318 -216.98487) (xy 343.74105 -216.933867)
			(xy 343.764208 -216.885778) (xy 343.794275 -216.841678) (xy 343.830579 -216.802551) (xy 343.872309 -216.769273)
			(xy 343.918533 -216.742586) (xy 343.968218 -216.723086) (xy 344.020255 -216.711209) (xy 344.07348 -216.70722)
			(xy 344.126705 -216.711209) (xy 344.178742 -216.723086) (xy 344.228427 -216.742586) (xy 344.274651 -216.769273)
			(xy 344.316381 -216.802551) (xy 344.352685 -216.841678) (xy 344.382752 -216.885778) (xy 344.40591 -216.933867)
			(xy 344.421642 -216.98487) (xy 344.429597 -217.037649) (xy 344.430096 -217.064336) (xy 344.429577 -217.090002)
			(xy 344.422238 -217.140805) (xy 344.40769 -217.190031) (xy 344.386232 -217.236662) (xy 344.358308 -217.279733)
			(xy 344.324496 -217.318354) (xy 344.285495 -217.351726) (xy 344.242111 -217.379161) (xy 344.19524 -217.400089)
			(xy 344.145853 -217.41408) (xy 344.12047 -217.417904) (xy 344.095578 -217.421206) (xy 343.92362 -217.71864)
			(xy 343.933272 -217.742008) (xy 343.941835 -217.76372) (xy 343.953924 -217.8088) (xy 343.960046 -217.85507)
			(xy 343.96045 -217.878406) (xy 344.187018 -217.878406) (xy 344.187517 -217.851719) (xy 344.195472 -217.79894)
			(xy 344.211204 -217.747937) (xy 344.234362 -217.699848) (xy 344.264429 -217.655748) (xy 344.300733 -217.616621)
			(xy 344.342463 -217.583343) (xy 344.388687 -217.556656) (xy 344.438372 -217.537156) (xy 344.490409 -217.525279)
			(xy 344.543634 -217.52129) (xy 344.596859 -217.525279) (xy 344.648896 -217.537156) (xy 344.698581 -217.556656)
			(xy 344.744805 -217.583343) (xy 344.786535 -217.616621) (xy 344.822839 -217.655748) (xy 344.852906 -217.699848)
			(xy 344.876064 -217.747937) (xy 344.891796 -217.79894) (xy 344.899751 -217.851719) (xy 344.90025 -217.878406)
			(xy 345.126818 -217.878406) (xy 345.127272 -217.852738) (xy 345.134619 -217.801932) (xy 345.149175 -217.752704)
			(xy 345.170641 -217.706072) (xy 345.198572 -217.663001) (xy 345.232391 -217.62438) (xy 345.2714 -217.591008)
			(xy 345.31479 -217.563576) (xy 345.361666 -217.542649) (xy 345.411059 -217.528661) (xy 345.436444 -217.524838)
			(xy 345.461336 -217.521536) (xy 345.633294 -217.224102) (xy 345.623642 -217.200734) (xy 345.615062 -217.179028)
			(xy 345.602979 -217.133945) (xy 345.596864 -217.087673) (xy 345.596464 -217.064336) (xy 345.596963 -217.037649)
			(xy 345.604918 -216.98487) (xy 345.62065 -216.933867) (xy 345.643808 -216.885778) (xy 345.673875 -216.841678)
			(xy 345.710179 -216.802551) (xy 345.751909 -216.769273) (xy 345.798133 -216.742586) (xy 345.847818 -216.723086)
			(xy 345.899855 -216.711209) (xy 345.95308 -216.70722) (xy 346.006305 -216.711209) (xy 346.058342 -216.723086)
			(xy 346.108027 -216.742586) (xy 346.154251 -216.769273) (xy 346.195981 -216.802551) (xy 346.232285 -216.841678)
			(xy 346.262352 -216.885778) (xy 346.28551 -216.933867) (xy 346.301242 -216.98487) (xy 346.309197 -217.037649)
			(xy 346.309696 -217.064336) (xy 346.309177 -217.090002) (xy 346.301838 -217.140805) (xy 346.28729 -217.190031)
			(xy 346.265832 -217.236662) (xy 346.237908 -217.279733) (xy 346.204096 -217.318354) (xy 346.165095 -217.351726)
			(xy 346.121711 -217.379161) (xy 346.07484 -217.400089) (xy 346.025453 -217.41408) (xy 346.00007 -217.417904)
			(xy 345.975178 -217.421206) (xy 345.80322 -217.71864) (xy 345.812872 -217.742008) (xy 345.821435 -217.76372)
			(xy 345.833524 -217.8088) (xy 345.839646 -217.85507) (xy 345.84005 -217.878406) (xy 346.066618 -217.878406)
			(xy 346.067117 -217.851719) (xy 346.075072 -217.79894) (xy 346.090804 -217.747937) (xy 346.113962 -217.699848)
			(xy 346.144029 -217.655748) (xy 346.180333 -217.616621) (xy 346.222063 -217.583343) (xy 346.268287 -217.556656)
			(xy 346.317972 -217.537156) (xy 346.370009 -217.525279) (xy 346.423234 -217.52129) (xy 346.476459 -217.525279)
			(xy 346.528496 -217.537156) (xy 346.578181 -217.556656) (xy 346.624405 -217.583343) (xy 346.666135 -217.616621)
			(xy 346.702439 -217.655748) (xy 346.732506 -217.699848) (xy 346.755664 -217.747937) (xy 346.771396 -217.79894)
			(xy 346.779351 -217.851719) (xy 346.77985 -217.878406) (xy 347.006418 -217.878406) (xy 347.006872 -217.852738)
			(xy 347.014219 -217.801932) (xy 347.028775 -217.752704) (xy 347.050241 -217.706072) (xy 347.078172 -217.663001)
			(xy 347.111991 -217.62438) (xy 347.151 -217.591008) (xy 347.19439 -217.563576) (xy 347.241266 -217.542649)
			(xy 347.290659 -217.528661) (xy 347.316044 -217.524838) (xy 347.340936 -217.521536) (xy 347.512894 -217.224102)
			(xy 347.503242 -217.200734) (xy 347.494662 -217.179028) (xy 347.482579 -217.133945) (xy 347.476464 -217.087673)
			(xy 347.476064 -217.064336) (xy 347.476563 -217.037649) (xy 347.484518 -216.98487) (xy 347.50025 -216.933867)
			(xy 347.523408 -216.885778) (xy 347.553475 -216.841678) (xy 347.589779 -216.802551) (xy 347.631509 -216.769273)
			(xy 347.677733 -216.742586) (xy 347.727418 -216.723086) (xy 347.779455 -216.711209) (xy 347.83268 -216.70722)
			(xy 347.885905 -216.711209) (xy 347.937942 -216.723086) (xy 347.987627 -216.742586) (xy 348.033851 -216.769273)
			(xy 348.075581 -216.802551) (xy 348.111885 -216.841678) (xy 348.141952 -216.885778) (xy 348.16511 -216.933867)
			(xy 348.180842 -216.98487) (xy 348.188797 -217.037649) (xy 348.189296 -217.064336) (xy 348.188777 -217.090002)
			(xy 348.181438 -217.140805) (xy 348.16689 -217.190031) (xy 348.145432 -217.236662) (xy 348.117508 -217.279733)
			(xy 348.083696 -217.318354) (xy 348.044695 -217.351726) (xy 348.001311 -217.379161) (xy 347.95444 -217.400089)
			(xy 347.905053 -217.41408) (xy 347.87967 -217.417904) (xy 347.854778 -217.421206) (xy 347.68282 -217.71864)
			(xy 347.692472 -217.742008) (xy 347.701035 -217.76372) (xy 347.713124 -217.8088) (xy 347.719246 -217.85507)
			(xy 347.71965 -217.878406) (xy 347.946218 -217.878406) (xy 347.946717 -217.851719) (xy 347.954672 -217.79894)
			(xy 347.970404 -217.747937) (xy 347.993562 -217.699848) (xy 348.023629 -217.655748) (xy 348.059933 -217.616621)
			(xy 348.101663 -217.583343) (xy 348.147887 -217.556656) (xy 348.197572 -217.537156) (xy 348.249609 -217.525279)
			(xy 348.302834 -217.52129) (xy 348.356059 -217.525279) (xy 348.408096 -217.537156) (xy 348.457781 -217.556656)
			(xy 348.504005 -217.583343) (xy 348.545735 -217.616621) (xy 348.582039 -217.655748) (xy 348.612106 -217.699848)
			(xy 348.635264 -217.747937) (xy 348.650996 -217.79894) (xy 348.658951 -217.851719) (xy 348.65945 -217.878406)
			(xy 348.886018 -217.878406) (xy 348.886472 -217.852738) (xy 348.893819 -217.801932) (xy 348.908375 -217.752704)
			(xy 348.929841 -217.706072) (xy 348.957772 -217.663001) (xy 348.991591 -217.62438) (xy 349.0306 -217.591008)
			(xy 349.07399 -217.563576) (xy 349.120866 -217.542649) (xy 349.170259 -217.528661) (xy 349.195644 -217.524838)
			(xy 349.220536 -217.521536) (xy 349.392494 -217.224102) (xy 349.382842 -217.200734) (xy 349.374262 -217.179028)
			(xy 349.362179 -217.133945) (xy 349.356064 -217.087673) (xy 349.355664 -217.064336) (xy 349.356163 -217.037649)
			(xy 349.364118 -216.98487) (xy 349.37985 -216.933867) (xy 349.403008 -216.885778) (xy 349.433075 -216.841678)
			(xy 349.469379 -216.802551) (xy 349.511109 -216.769273) (xy 349.557333 -216.742586) (xy 349.607018 -216.723086)
			(xy 349.659055 -216.711209) (xy 349.71228 -216.70722) (xy 349.765505 -216.711209) (xy 349.817542 -216.723086)
			(xy 349.867227 -216.742586) (xy 349.913451 -216.769273) (xy 349.955181 -216.802551) (xy 349.991485 -216.841678)
			(xy 350.021552 -216.885778) (xy 350.04471 -216.933867) (xy 350.060442 -216.98487) (xy 350.068397 -217.037649)
			(xy 350.068896 -217.064336) (xy 350.068377 -217.090002) (xy 350.061038 -217.140805) (xy 350.04649 -217.190031)
			(xy 350.025032 -217.236662) (xy 349.997108 -217.279733) (xy 349.963296 -217.318354) (xy 349.924295 -217.351726)
			(xy 349.880911 -217.379161) (xy 349.83404 -217.400089) (xy 349.784653 -217.41408) (xy 349.75927 -217.417904)
			(xy 349.734378 -217.421206) (xy 349.56242 -217.71864) (xy 349.572072 -217.742008) (xy 349.580635 -217.76372)
			(xy 349.592724 -217.8088) (xy 349.598846 -217.85507) (xy 349.59925 -217.878406) (xy 349.825818 -217.878406)
			(xy 349.826317 -217.851719) (xy 349.834272 -217.79894) (xy 349.850004 -217.747937) (xy 349.873162 -217.699848)
			(xy 349.903229 -217.655748) (xy 349.939533 -217.616621) (xy 349.981263 -217.583343) (xy 350.027487 -217.556656)
			(xy 350.077172 -217.537156) (xy 350.129209 -217.525279) (xy 350.182434 -217.52129) (xy 350.235659 -217.525279)
			(xy 350.287696 -217.537156) (xy 350.337381 -217.556656) (xy 350.383605 -217.583343) (xy 350.425335 -217.616621)
			(xy 350.461639 -217.655748) (xy 350.491706 -217.699848) (xy 350.514864 -217.747937) (xy 350.530596 -217.79894)
			(xy 350.538551 -217.851719) (xy 350.53905 -217.878406) (xy 350.765618 -217.878406) (xy 350.766072 -217.852738)
			(xy 350.773419 -217.801932) (xy 350.787975 -217.752704) (xy 350.809441 -217.706072) (xy 350.837372 -217.663001)
			(xy 350.871191 -217.62438) (xy 350.9102 -217.591008) (xy 350.95359 -217.563576) (xy 351.000466 -217.542649)
			(xy 351.049859 -217.528661) (xy 351.075244 -217.524838) (xy 351.100136 -217.521536) (xy 351.272094 -217.224102)
			(xy 351.262442 -217.200734) (xy 351.253862 -217.179028) (xy 351.241779 -217.133945) (xy 351.235664 -217.087673)
			(xy 351.235264 -217.064336) (xy 351.235763 -217.037649) (xy 351.243718 -216.98487) (xy 351.25945 -216.933867)
			(xy 351.282608 -216.885778) (xy 351.312675 -216.841678) (xy 351.348979 -216.802551) (xy 351.390709 -216.769273)
			(xy 351.436933 -216.742586) (xy 351.486618 -216.723086) (xy 351.538655 -216.711209) (xy 351.59188 -216.70722)
			(xy 351.645105 -216.711209) (xy 351.697142 -216.723086) (xy 351.746827 -216.742586) (xy 351.793051 -216.769273)
			(xy 351.834781 -216.802551) (xy 351.871085 -216.841678) (xy 351.901152 -216.885778) (xy 351.92431 -216.933867)
			(xy 351.940042 -216.98487) (xy 351.947997 -217.037649) (xy 351.948496 -217.064336) (xy 351.947977 -217.090002)
			(xy 351.940638 -217.140805) (xy 351.92609 -217.190031) (xy 351.904632 -217.236662) (xy 351.876708 -217.279733)
			(xy 351.842896 -217.318354) (xy 351.803895 -217.351726) (xy 351.760511 -217.379161) (xy 351.71364 -217.400089)
			(xy 351.664253 -217.41408) (xy 351.63887 -217.417904) (xy 351.613978 -217.421206) (xy 351.44202 -217.71864)
			(xy 351.451672 -217.742008) (xy 351.460235 -217.76372) (xy 351.472324 -217.8088) (xy 351.478446 -217.85507)
			(xy 351.47885 -217.878406) (xy 351.705418 -217.878406) (xy 351.705917 -217.851719) (xy 351.713872 -217.79894)
			(xy 351.729604 -217.747937) (xy 351.752762 -217.699848) (xy 351.782829 -217.655748) (xy 351.819133 -217.616621)
			(xy 351.860863 -217.583343) (xy 351.907087 -217.556656) (xy 351.956772 -217.537156) (xy 352.008809 -217.525279)
			(xy 352.062034 -217.52129) (xy 352.115259 -217.525279) (xy 352.167296 -217.537156) (xy 352.216981 -217.556656)
			(xy 352.263205 -217.583343) (xy 352.304935 -217.616621) (xy 352.341239 -217.655748) (xy 352.371306 -217.699848)
			(xy 352.394464 -217.747937) (xy 352.410196 -217.79894) (xy 352.418151 -217.851719) (xy 352.41865 -217.878406)
			(xy 352.645218 -217.878406) (xy 352.645672 -217.852738) (xy 352.653019 -217.801932) (xy 352.667575 -217.752704)
			(xy 352.689041 -217.706072) (xy 352.716972 -217.663001) (xy 352.750791 -217.62438) (xy 352.7898 -217.591008)
			(xy 352.83319 -217.563576) (xy 352.880066 -217.542649) (xy 352.929459 -217.528661) (xy 352.954844 -217.524838)
			(xy 352.979736 -217.521536) (xy 353.151694 -217.224102) (xy 353.142042 -217.200734) (xy 353.133462 -217.179028)
			(xy 353.121379 -217.133945) (xy 353.115264 -217.087673) (xy 353.114864 -217.064336) (xy 353.115363 -217.037649)
			(xy 353.123318 -216.98487) (xy 353.13905 -216.933867) (xy 353.162208 -216.885778) (xy 353.192275 -216.841678)
			(xy 353.228579 -216.802551) (xy 353.270309 -216.769273) (xy 353.316533 -216.742586) (xy 353.366218 -216.723086)
			(xy 353.418255 -216.711209) (xy 353.47148 -216.70722) (xy 353.524705 -216.711209) (xy 353.576742 -216.723086)
			(xy 353.626427 -216.742586) (xy 353.672651 -216.769273) (xy 353.714381 -216.802551) (xy 353.750685 -216.841678)
			(xy 353.780752 -216.885778) (xy 353.80391 -216.933867) (xy 353.819642 -216.98487) (xy 353.827597 -217.037649)
			(xy 353.828096 -217.064336) (xy 353.827577 -217.090002) (xy 353.820238 -217.140805) (xy 353.80569 -217.190031)
			(xy 353.784232 -217.236662) (xy 353.756308 -217.279733) (xy 353.722496 -217.318354) (xy 353.683495 -217.351726)
			(xy 353.640111 -217.379161) (xy 353.59324 -217.400089) (xy 353.543853 -217.41408) (xy 353.51847 -217.417904)
			(xy 353.493578 -217.421206) (xy 353.32162 -217.71864) (xy 353.331272 -217.742008) (xy 353.339835 -217.76372)
			(xy 353.351924 -217.8088) (xy 353.358046 -217.85507) (xy 353.35845 -217.878406) (xy 353.585018 -217.878406)
			(xy 353.585517 -217.851719) (xy 353.593472 -217.79894) (xy 353.609204 -217.747937) (xy 353.632362 -217.699848)
			(xy 353.662429 -217.655748) (xy 353.698733 -217.616621) (xy 353.740463 -217.583343) (xy 353.786687 -217.556656)
			(xy 353.836372 -217.537156) (xy 353.888409 -217.525279) (xy 353.941634 -217.52129) (xy 353.994859 -217.525279)
			(xy 354.046896 -217.537156) (xy 354.096581 -217.556656) (xy 354.142805 -217.583343) (xy 354.184535 -217.616621)
			(xy 354.220839 -217.655748) (xy 354.250906 -217.699848) (xy 354.274064 -217.747937) (xy 354.289796 -217.79894)
			(xy 354.297751 -217.851719) (xy 354.29825 -217.878406) (xy 354.524818 -217.878406) (xy 354.525272 -217.852738)
			(xy 354.532619 -217.801932) (xy 354.547175 -217.752704) (xy 354.568641 -217.706072) (xy 354.596572 -217.663001)
			(xy 354.630391 -217.62438) (xy 354.6694 -217.591008) (xy 354.71279 -217.563576) (xy 354.759666 -217.542649)
			(xy 354.809059 -217.528661) (xy 354.834444 -217.524838) (xy 354.859336 -217.521536) (xy 355.031294 -217.224102)
			(xy 355.021642 -217.200734) (xy 355.013062 -217.179028) (xy 355.000979 -217.133945) (xy 354.994864 -217.087673)
			(xy 354.994464 -217.064336) (xy 354.994963 -217.037649) (xy 355.002918 -216.98487) (xy 355.01865 -216.933867)
			(xy 355.041808 -216.885778) (xy 355.071875 -216.841678) (xy 355.108179 -216.802551) (xy 355.149909 -216.769273)
			(xy 355.196133 -216.742586) (xy 355.245818 -216.723086) (xy 355.297855 -216.711209) (xy 355.35108 -216.70722)
			(xy 355.404305 -216.711209) (xy 355.456342 -216.723086) (xy 355.506027 -216.742586) (xy 355.552251 -216.769273)
			(xy 355.593981 -216.802551) (xy 355.630285 -216.841678) (xy 355.660352 -216.885778) (xy 355.68351 -216.933867)
			(xy 355.699242 -216.98487) (xy 355.707197 -217.037649) (xy 355.707696 -217.064336) (xy 355.707177 -217.090002)
			(xy 355.699838 -217.140805) (xy 355.68529 -217.190031) (xy 355.663832 -217.236662) (xy 355.635908 -217.279733)
			(xy 355.602096 -217.318354) (xy 355.563095 -217.351726) (xy 355.519711 -217.379161) (xy 355.47284 -217.400089)
			(xy 355.423453 -217.41408) (xy 355.39807 -217.417904) (xy 355.373178 -217.421206) (xy 355.20122 -217.71864)
			(xy 355.210872 -217.742008) (xy 355.219435 -217.76372) (xy 355.231524 -217.8088) (xy 355.237646 -217.85507)
			(xy 355.23805 -217.878406) (xy 355.464618 -217.878406) (xy 355.465117 -217.851719) (xy 355.473072 -217.79894)
			(xy 355.488804 -217.747937) (xy 355.511962 -217.699848) (xy 355.542029 -217.655748) (xy 355.578333 -217.616621)
			(xy 355.620063 -217.583343) (xy 355.666287 -217.556656) (xy 355.715972 -217.537156) (xy 355.768009 -217.525279)
			(xy 355.821234 -217.52129) (xy 355.874459 -217.525279) (xy 355.926496 -217.537156) (xy 355.976181 -217.556656)
			(xy 356.022405 -217.583343) (xy 356.064135 -217.616621) (xy 356.100439 -217.655748) (xy 356.130506 -217.699848)
			(xy 356.153664 -217.747937) (xy 356.169396 -217.79894) (xy 356.177351 -217.851719) (xy 356.17785 -217.878406)
			(xy 356.404418 -217.878406) (xy 356.404872 -217.852738) (xy 356.412219 -217.801932) (xy 356.426775 -217.752704)
			(xy 356.448241 -217.706072) (xy 356.476172 -217.663001) (xy 356.509991 -217.62438) (xy 356.549 -217.591008)
			(xy 356.59239 -217.563576) (xy 356.639266 -217.542649) (xy 356.688659 -217.528661) (xy 356.714044 -217.524838)
			(xy 356.738936 -217.521536) (xy 356.910894 -217.224102) (xy 356.901242 -217.200734) (xy 356.892662 -217.179028)
			(xy 356.880579 -217.133945) (xy 356.874464 -217.087673) (xy 356.874064 -217.064336) (xy 356.874563 -217.037649)
			(xy 356.882518 -216.98487) (xy 356.89825 -216.933867) (xy 356.921408 -216.885778) (xy 356.951475 -216.841678)
			(xy 356.987779 -216.802551) (xy 357.029509 -216.769273) (xy 357.075733 -216.742586) (xy 357.125418 -216.723086)
			(xy 357.177455 -216.711209) (xy 357.23068 -216.70722) (xy 357.283905 -216.711209) (xy 357.335942 -216.723086)
			(xy 357.385627 -216.742586) (xy 357.431851 -216.769273) (xy 357.473581 -216.802551) (xy 357.509885 -216.841678)
			(xy 357.539952 -216.885778) (xy 357.56311 -216.933867) (xy 357.578842 -216.98487) (xy 357.586797 -217.037649)
			(xy 357.587296 -217.064336) (xy 357.586777 -217.090002) (xy 357.579438 -217.140805) (xy 357.56489 -217.190031)
			(xy 357.543432 -217.236662) (xy 357.515508 -217.279733) (xy 357.481696 -217.318354) (xy 357.442695 -217.351726)
			(xy 357.399311 -217.379161) (xy 357.35244 -217.400089) (xy 357.303053 -217.41408) (xy 357.27767 -217.417904)
			(xy 357.252778 -217.421206) (xy 357.08082 -217.71864) (xy 357.090472 -217.742008) (xy 357.099035 -217.76372)
			(xy 357.111124 -217.8088) (xy 357.117246 -217.85507) (xy 357.11765 -217.878406) (xy 357.344218 -217.878406)
			(xy 357.344717 -217.851719) (xy 357.352672 -217.79894) (xy 357.368404 -217.747937) (xy 357.391562 -217.699848)
			(xy 357.421629 -217.655748) (xy 357.457933 -217.616621) (xy 357.499663 -217.583343) (xy 357.545887 -217.556656)
			(xy 357.595572 -217.537156) (xy 357.647609 -217.525279) (xy 357.700834 -217.52129) (xy 357.754059 -217.525279)
			(xy 357.806096 -217.537156) (xy 357.855781 -217.556656) (xy 357.902005 -217.583343) (xy 357.943735 -217.616621)
			(xy 357.980039 -217.655748) (xy 358.010106 -217.699848) (xy 358.033264 -217.747937) (xy 358.048996 -217.79894)
			(xy 358.056951 -217.851719) (xy 358.05745 -217.878406) (xy 358.284018 -217.878406) (xy 358.284472 -217.852738)
			(xy 358.291819 -217.801932) (xy 358.306375 -217.752704) (xy 358.327841 -217.706072) (xy 358.355772 -217.663001)
			(xy 358.389591 -217.62438) (xy 358.4286 -217.591008) (xy 358.47199 -217.563576) (xy 358.518866 -217.542649)
			(xy 358.568259 -217.528661) (xy 358.593644 -217.524838) (xy 358.618536 -217.521536) (xy 358.790494 -217.223594)
			(xy 358.780842 -217.20048) (xy 358.772347 -217.178885) (xy 358.760366 -217.134054) (xy 358.754308 -217.088046)
			(xy 358.753918 -217.064844) (xy 358.753918 -217.064336) (xy 358.754417 -217.037649) (xy 358.762372 -216.98487)
			(xy 358.778104 -216.933867) (xy 358.801262 -216.885778) (xy 358.831329 -216.841678) (xy 358.867633 -216.802551)
			(xy 358.909363 -216.769273) (xy 358.955587 -216.742586) (xy 359.005272 -216.723086) (xy 359.057309 -216.711209)
			(xy 359.110534 -216.70722) (xy 359.163759 -216.711209) (xy 359.215796 -216.723086) (xy 359.265481 -216.742586)
			(xy 359.311705 -216.769273) (xy 359.353435 -216.802551) (xy 359.389739 -216.841678) (xy 359.419806 -216.885778)
			(xy 359.442964 -216.933867) (xy 359.458696 -216.98487) (xy 359.466651 -217.037649) (xy 359.46715 -217.064336)
			(xy 360.633264 -217.064336) (xy 360.633763 -217.037649) (xy 360.641718 -216.98487) (xy 360.65745 -216.933867)
			(xy 360.680608 -216.885778) (xy 360.710675 -216.841678) (xy 360.746979 -216.802551) (xy 360.788709 -216.769273)
			(xy 360.834933 -216.742586) (xy 360.884618 -216.723086) (xy 360.936655 -216.711209) (xy 360.98988 -216.70722)
			(xy 361.043105 -216.711209) (xy 361.095142 -216.723086) (xy 361.144827 -216.742586) (xy 361.191051 -216.769273)
			(xy 361.232781 -216.802551) (xy 361.269085 -216.841678) (xy 361.299152 -216.885778) (xy 361.32231 -216.933867)
			(xy 361.338042 -216.98487) (xy 361.345997 -217.037649) (xy 361.346496 -217.064336) (xy 362.512864 -217.064336)
			(xy 362.513363 -217.037649) (xy 362.521318 -216.98487) (xy 362.53705 -216.933867) (xy 362.560208 -216.885778)
			(xy 362.590275 -216.841678) (xy 362.626579 -216.802551) (xy 362.668309 -216.769273) (xy 362.714533 -216.742586)
			(xy 362.764218 -216.723086) (xy 362.816255 -216.711209) (xy 362.86948 -216.70722) (xy 362.922705 -216.711209)
			(xy 362.974742 -216.723086) (xy 363.024427 -216.742586) (xy 363.070651 -216.769273) (xy 363.112381 -216.802551)
			(xy 363.148685 -216.841678) (xy 363.178752 -216.885778) (xy 363.20191 -216.933867) (xy 363.217642 -216.98487)
			(xy 363.225597 -217.037649) (xy 363.226096 -217.064336) (xy 364.392464 -217.064336) (xy 364.392963 -217.037649)
			(xy 364.400918 -216.98487) (xy 364.41665 -216.933867) (xy 364.439808 -216.885778) (xy 364.469875 -216.841678)
			(xy 364.506179 -216.802551) (xy 364.547909 -216.769273) (xy 364.594133 -216.742586) (xy 364.643818 -216.723086)
			(xy 364.695855 -216.711209) (xy 364.74908 -216.70722) (xy 364.802305 -216.711209) (xy 364.854342 -216.723086)
			(xy 364.904027 -216.742586) (xy 364.950251 -216.769273) (xy 364.991981 -216.802551) (xy 365.028285 -216.841678)
			(xy 365.058352 -216.885778) (xy 365.08151 -216.933867) (xy 365.097242 -216.98487) (xy 365.105197 -217.037649)
			(xy 365.105696 -217.064336) (xy 366.272064 -217.064336) (xy 366.272563 -217.037649) (xy 366.280518 -216.98487)
			(xy 366.29625 -216.933867) (xy 366.319408 -216.885778) (xy 366.349475 -216.841678) (xy 366.385779 -216.802551)
			(xy 366.427509 -216.769273) (xy 366.473733 -216.742586) (xy 366.523418 -216.723086) (xy 366.575455 -216.711209)
			(xy 366.62868 -216.70722) (xy 366.681905 -216.711209) (xy 366.733942 -216.723086) (xy 366.783627 -216.742586)
			(xy 366.829851 -216.769273) (xy 366.871581 -216.802551) (xy 366.907885 -216.841678) (xy 366.937952 -216.885778)
			(xy 366.96111 -216.933867) (xy 366.976842 -216.98487) (xy 366.984797 -217.037649) (xy 366.985296 -217.064336)
			(xy 368.151664 -217.064336) (xy 368.152163 -217.037649) (xy 368.160118 -216.98487) (xy 368.17585 -216.933867)
			(xy 368.199008 -216.885778) (xy 368.229075 -216.841678) (xy 368.265379 -216.802551) (xy 368.307109 -216.769273)
			(xy 368.353333 -216.742586) (xy 368.403018 -216.723086) (xy 368.455055 -216.711209) (xy 368.50828 -216.70722)
			(xy 368.561505 -216.711209) (xy 368.613542 -216.723086) (xy 368.663227 -216.742586) (xy 368.709451 -216.769273)
			(xy 368.751181 -216.802551) (xy 368.787485 -216.841678) (xy 368.817552 -216.885778) (xy 368.84071 -216.933867)
			(xy 368.856442 -216.98487) (xy 368.864397 -217.037649) (xy 368.864896 -217.064336) (xy 370.031264 -217.064336)
			(xy 370.031763 -217.037649) (xy 370.039718 -216.98487) (xy 370.05545 -216.933867) (xy 370.078608 -216.885778)
			(xy 370.108675 -216.841678) (xy 370.144979 -216.802551) (xy 370.186709 -216.769273) (xy 370.232933 -216.742586)
			(xy 370.282618 -216.723086) (xy 370.334655 -216.711209) (xy 370.38788 -216.70722) (xy 370.441105 -216.711209)
			(xy 370.493142 -216.723086) (xy 370.542827 -216.742586) (xy 370.589051 -216.769273) (xy 370.630781 -216.802551)
			(xy 370.667085 -216.841678) (xy 370.697152 -216.885778) (xy 370.72031 -216.933867) (xy 370.736042 -216.98487)
			(xy 370.743997 -217.037649) (xy 370.744496 -217.064336) (xy 371.910864 -217.064336) (xy 371.911363 -217.037649)
			(xy 371.919318 -216.98487) (xy 371.93505 -216.933867) (xy 371.958208 -216.885778) (xy 371.988275 -216.841678)
			(xy 372.024579 -216.802551) (xy 372.066309 -216.769273) (xy 372.112533 -216.742586) (xy 372.162218 -216.723086)
			(xy 372.214255 -216.711209) (xy 372.26748 -216.70722) (xy 372.320705 -216.711209) (xy 372.372742 -216.723086)
			(xy 372.422427 -216.742586) (xy 372.468651 -216.769273) (xy 372.510381 -216.802551) (xy 372.546685 -216.841678)
			(xy 372.576752 -216.885778) (xy 372.59991 -216.933867) (xy 372.615642 -216.98487) (xy 372.623597 -217.037649)
			(xy 372.624096 -217.064336) (xy 373.790464 -217.064336) (xy 373.790963 -217.037649) (xy 373.798918 -216.98487)
			(xy 373.81465 -216.933867) (xy 373.837808 -216.885778) (xy 373.867875 -216.841678) (xy 373.904179 -216.802551)
			(xy 373.945909 -216.769273) (xy 373.992133 -216.742586) (xy 374.041818 -216.723086) (xy 374.093855 -216.711209)
			(xy 374.14708 -216.70722) (xy 374.200305 -216.711209) (xy 374.252342 -216.723086) (xy 374.302027 -216.742586)
			(xy 374.348251 -216.769273) (xy 374.389981 -216.802551) (xy 374.426285 -216.841678) (xy 374.456352 -216.885778)
			(xy 374.47951 -216.933867) (xy 374.495242 -216.98487) (xy 374.503197 -217.037649) (xy 374.503696 -217.064336)
			(xy 375.670064 -217.064336) (xy 375.670563 -217.037649) (xy 375.678518 -216.98487) (xy 375.69425 -216.933867)
			(xy 375.717408 -216.885778) (xy 375.747475 -216.841678) (xy 375.783779 -216.802551) (xy 375.825509 -216.769273)
			(xy 375.871733 -216.742586) (xy 375.921418 -216.723086) (xy 375.973455 -216.711209) (xy 376.02668 -216.70722)
			(xy 376.079905 -216.711209) (xy 376.131942 -216.723086) (xy 376.181627 -216.742586) (xy 376.227851 -216.769273)
			(xy 376.269581 -216.802551) (xy 376.305885 -216.841678) (xy 376.335952 -216.885778) (xy 376.35911 -216.933867)
			(xy 376.374842 -216.98487) (xy 376.382797 -217.037649) (xy 376.383296 -217.064336) (xy 377.549664 -217.064336)
			(xy 377.550163 -217.037649) (xy 377.558118 -216.98487) (xy 377.57385 -216.933867) (xy 377.597008 -216.885778)
			(xy 377.627075 -216.841678) (xy 377.663379 -216.802551) (xy 377.705109 -216.769273) (xy 377.751333 -216.742586)
			(xy 377.801018 -216.723086) (xy 377.853055 -216.711209) (xy 377.90628 -216.70722) (xy 377.959505 -216.711209)
			(xy 378.011542 -216.723086) (xy 378.061227 -216.742586) (xy 378.107451 -216.769273) (xy 378.149181 -216.802551)
			(xy 378.185485 -216.841678) (xy 378.215552 -216.885778) (xy 378.23871 -216.933867) (xy 378.254442 -216.98487)
			(xy 378.262397 -217.037649) (xy 378.262896 -217.064336) (xy 379.429264 -217.064336) (xy 379.429763 -217.037649)
			(xy 379.437718 -216.98487) (xy 379.45345 -216.933867) (xy 379.476608 -216.885778) (xy 379.506675 -216.841678)
			(xy 379.542979 -216.802551) (xy 379.584709 -216.769273) (xy 379.630933 -216.742586) (xy 379.680618 -216.723086)
			(xy 379.732655 -216.711209) (xy 379.78588 -216.70722) (xy 379.839105 -216.711209) (xy 379.891142 -216.723086)
			(xy 379.940827 -216.742586) (xy 379.987051 -216.769273) (xy 380.028781 -216.802551) (xy 380.065085 -216.841678)
			(xy 380.095152 -216.885778) (xy 380.11831 -216.933867) (xy 380.134042 -216.98487) (xy 380.141997 -217.037649)
			(xy 380.142496 -217.064336) (xy 381.308864 -217.064336) (xy 381.309363 -217.037649) (xy 381.317318 -216.98487)
			(xy 381.33305 -216.933867) (xy 381.356208 -216.885778) (xy 381.386275 -216.841678) (xy 381.422579 -216.802551)
			(xy 381.464309 -216.769273) (xy 381.510533 -216.742586) (xy 381.560218 -216.723086) (xy 381.612255 -216.711209)
			(xy 381.66548 -216.70722) (xy 381.718705 -216.711209) (xy 381.770742 -216.723086) (xy 381.820427 -216.742586)
			(xy 381.866651 -216.769273) (xy 381.908381 -216.802551) (xy 381.944685 -216.841678) (xy 381.974752 -216.885778)
			(xy 381.99791 -216.933867) (xy 382.013642 -216.98487) (xy 382.021597 -217.037649) (xy 382.022096 -217.064336)
			(xy 382.022096 -217.064844) (xy 382.021691 -217.088045) (xy 382.015634 -217.134052) (xy 382.003667 -217.178886)
			(xy 381.995172 -217.20048) (xy 381.98552 -217.223594) (xy 382.157732 -217.521536) (xy 382.182624 -217.524838)
			(xy 382.207999 -217.528707) (xy 382.25738 -217.542708) (xy 382.304245 -217.563641) (xy 382.347626 -217.591074)
			(xy 382.386628 -217.624441) (xy 382.420445 -217.663053) (xy 382.44838 -217.706113) (xy 382.469855 -217.752732)
			(xy 382.484428 -217.801947) (xy 382.491797 -217.852742) (xy 382.49225 -217.878406) (xy 382.491751 -217.905093)
			(xy 382.483796 -217.957872) (xy 382.468064 -218.008875) (xy 382.444906 -218.056964) (xy 382.414839 -218.101064)
			(xy 382.378535 -218.140191) (xy 382.336805 -218.173469) (xy 382.290581 -218.200156) (xy 382.240896 -218.219656)
			(xy 382.188859 -218.231533) (xy 382.135634 -218.235522) (xy 382.082409 -218.231533) (xy 382.030372 -218.219656)
			(xy 381.980687 -218.200156) (xy 381.934463 -218.173469) (xy 381.892733 -218.140191) (xy 381.856429 -218.101064)
			(xy 381.826362 -218.056964) (xy 381.803204 -218.008875) (xy 381.787472 -217.957872) (xy 381.779517 -217.905093)
			(xy 381.779018 -217.878406) (xy 381.779374 -217.855066) (xy 381.785479 -217.808787) (xy 381.797586 -217.763705)
			(xy 381.806196 -217.742008) (xy 381.815848 -217.71864) (xy 381.644144 -217.421206) (xy 381.619252 -217.417904)
			(xy 381.593819 -217.414163) (xy 381.544328 -217.400257) (xy 381.497348 -217.379387) (xy 381.453853 -217.351987)
			(xy 381.414743 -217.318623) (xy 381.380831 -217.279989) (xy 381.352818 -217.236884) (xy 381.331287 -217.190204)
			(xy 381.316683 -217.140915) (xy 381.309309 -217.09004) (xy 381.308864 -217.064336) (xy 380.142496 -217.064336)
			(xy 380.142496 -217.064844) (xy 380.142091 -217.088045) (xy 380.136034 -217.134052) (xy 380.124067 -217.178886)
			(xy 380.115572 -217.20048) (xy 380.10592 -217.223594) (xy 380.278132 -217.521536) (xy 380.303024 -217.524838)
			(xy 380.328399 -217.528707) (xy 380.37778 -217.542708) (xy 380.424645 -217.563641) (xy 380.468026 -217.591074)
			(xy 380.507028 -217.624441) (xy 380.540845 -217.663053) (xy 380.56878 -217.706113) (xy 380.590255 -217.752732)
			(xy 380.604828 -217.801947) (xy 380.612197 -217.852742) (xy 380.61265 -217.878406) (xy 380.612151 -217.905093)
			(xy 380.604196 -217.957872) (xy 380.588464 -218.008875) (xy 380.565306 -218.056964) (xy 380.535239 -218.101064)
			(xy 380.498935 -218.140191) (xy 380.457205 -218.173469) (xy 380.410981 -218.200156) (xy 380.361296 -218.219656)
			(xy 380.309259 -218.231533) (xy 380.256034 -218.235522) (xy 380.202809 -218.231533) (xy 380.150772 -218.219656)
			(xy 380.101087 -218.200156) (xy 380.054863 -218.173469) (xy 380.013133 -218.140191) (xy 379.976829 -218.101064)
			(xy 379.946762 -218.056964) (xy 379.923604 -218.008875) (xy 379.907872 -217.957872) (xy 379.899917 -217.905093)
			(xy 379.899418 -217.878406) (xy 379.899774 -217.855066) (xy 379.905879 -217.808787) (xy 379.917986 -217.763705)
			(xy 379.926596 -217.742008) (xy 379.936248 -217.71864) (xy 379.764544 -217.421206) (xy 379.739652 -217.417904)
			(xy 379.714219 -217.414163) (xy 379.664728 -217.400257) (xy 379.617748 -217.379387) (xy 379.574253 -217.351987)
			(xy 379.535143 -217.318623) (xy 379.501231 -217.279989) (xy 379.473218 -217.236884) (xy 379.451687 -217.190204)
			(xy 379.437083 -217.140915) (xy 379.429709 -217.09004) (xy 379.429264 -217.064336) (xy 378.262896 -217.064336)
			(xy 378.262896 -217.064844) (xy 378.262491 -217.088045) (xy 378.256434 -217.134052) (xy 378.244467 -217.178886)
			(xy 378.235972 -217.20048) (xy 378.22632 -217.223594) (xy 378.398532 -217.521536) (xy 378.423424 -217.524838)
			(xy 378.448799 -217.528707) (xy 378.49818 -217.542708) (xy 378.545045 -217.563641) (xy 378.588426 -217.591074)
			(xy 378.627428 -217.624441) (xy 378.661245 -217.663053) (xy 378.68918 -217.706113) (xy 378.710655 -217.752732)
			(xy 378.725228 -217.801947) (xy 378.732597 -217.852742) (xy 378.73305 -217.878406) (xy 378.732551 -217.905093)
			(xy 378.724596 -217.957872) (xy 378.708864 -218.008875) (xy 378.685706 -218.056964) (xy 378.655639 -218.101064)
			(xy 378.619335 -218.140191) (xy 378.577605 -218.173469) (xy 378.531381 -218.200156) (xy 378.481696 -218.219656)
			(xy 378.429659 -218.231533) (xy 378.376434 -218.235522) (xy 378.323209 -218.231533) (xy 378.271172 -218.219656)
			(xy 378.221487 -218.200156) (xy 378.175263 -218.173469) (xy 378.133533 -218.140191) (xy 378.097229 -218.101064)
			(xy 378.067162 -218.056964) (xy 378.044004 -218.008875) (xy 378.028272 -217.957872) (xy 378.020317 -217.905093)
			(xy 378.019818 -217.878406) (xy 378.020174 -217.855066) (xy 378.026279 -217.808787) (xy 378.038386 -217.763705)
			(xy 378.046996 -217.742008) (xy 378.056648 -217.71864) (xy 377.884944 -217.421206) (xy 377.860052 -217.417904)
			(xy 377.834619 -217.414163) (xy 377.785128 -217.400257) (xy 377.738148 -217.379387) (xy 377.694653 -217.351987)
			(xy 377.655543 -217.318623) (xy 377.621631 -217.279989) (xy 377.593618 -217.236884) (xy 377.572087 -217.190204)
			(xy 377.557483 -217.140915) (xy 377.550109 -217.09004) (xy 377.549664 -217.064336) (xy 376.383296 -217.064336)
			(xy 376.383296 -217.064844) (xy 376.382891 -217.088045) (xy 376.376834 -217.134052) (xy 376.364867 -217.178886)
			(xy 376.356372 -217.20048) (xy 376.34672 -217.223594) (xy 376.518932 -217.521536) (xy 376.543824 -217.524838)
			(xy 376.569199 -217.528707) (xy 376.61858 -217.542708) (xy 376.665445 -217.563641) (xy 376.708826 -217.591074)
			(xy 376.747828 -217.624441) (xy 376.781645 -217.663053) (xy 376.80958 -217.706113) (xy 376.831055 -217.752732)
			(xy 376.845628 -217.801947) (xy 376.852997 -217.852742) (xy 376.85345 -217.878406) (xy 376.852951 -217.905093)
			(xy 376.844996 -217.957872) (xy 376.829264 -218.008875) (xy 376.806106 -218.056964) (xy 376.776039 -218.101064)
			(xy 376.739735 -218.140191) (xy 376.698005 -218.173469) (xy 376.651781 -218.200156) (xy 376.602096 -218.219656)
			(xy 376.550059 -218.231533) (xy 376.496834 -218.235522) (xy 376.443609 -218.231533) (xy 376.391572 -218.219656)
			(xy 376.341887 -218.200156) (xy 376.295663 -218.173469) (xy 376.253933 -218.140191) (xy 376.217629 -218.101064)
			(xy 376.187562 -218.056964) (xy 376.164404 -218.008875) (xy 376.148672 -217.957872) (xy 376.140717 -217.905093)
			(xy 376.140218 -217.878406) (xy 376.140574 -217.855066) (xy 376.146679 -217.808787) (xy 376.158786 -217.763705)
			(xy 376.167396 -217.742008) (xy 376.177048 -217.71864) (xy 376.005344 -217.421206) (xy 375.980452 -217.417904)
			(xy 375.955019 -217.414163) (xy 375.905528 -217.400257) (xy 375.858548 -217.379387) (xy 375.815053 -217.351987)
			(xy 375.775943 -217.318623) (xy 375.742031 -217.279989) (xy 375.714018 -217.236884) (xy 375.692487 -217.190204)
			(xy 375.677883 -217.140915) (xy 375.670509 -217.09004) (xy 375.670064 -217.064336) (xy 374.503696 -217.064336)
			(xy 374.503696 -217.064844) (xy 374.503291 -217.088045) (xy 374.497234 -217.134052) (xy 374.485267 -217.178886)
			(xy 374.476772 -217.20048) (xy 374.46712 -217.223594) (xy 374.639332 -217.521536) (xy 374.664224 -217.524838)
			(xy 374.689599 -217.528707) (xy 374.73898 -217.542708) (xy 374.785845 -217.563641) (xy 374.829226 -217.591074)
			(xy 374.868228 -217.624441) (xy 374.902045 -217.663053) (xy 374.92998 -217.706113) (xy 374.951455 -217.752732)
			(xy 374.966028 -217.801947) (xy 374.973397 -217.852742) (xy 374.97385 -217.878406) (xy 374.973351 -217.905093)
			(xy 374.965396 -217.957872) (xy 374.949664 -218.008875) (xy 374.926506 -218.056964) (xy 374.896439 -218.101064)
			(xy 374.860135 -218.140191) (xy 374.818405 -218.173469) (xy 374.772181 -218.200156) (xy 374.722496 -218.219656)
			(xy 374.670459 -218.231533) (xy 374.617234 -218.235522) (xy 374.564009 -218.231533) (xy 374.511972 -218.219656)
			(xy 374.462287 -218.200156) (xy 374.416063 -218.173469) (xy 374.374333 -218.140191) (xy 374.338029 -218.101064)
			(xy 374.307962 -218.056964) (xy 374.284804 -218.008875) (xy 374.269072 -217.957872) (xy 374.261117 -217.905093)
			(xy 374.260618 -217.878406) (xy 374.260974 -217.855066) (xy 374.267079 -217.808787) (xy 374.279186 -217.763705)
			(xy 374.287796 -217.742008) (xy 374.297448 -217.71864) (xy 374.125744 -217.421206) (xy 374.100852 -217.417904)
			(xy 374.075419 -217.414163) (xy 374.025928 -217.400257) (xy 373.978948 -217.379387) (xy 373.935453 -217.351987)
			(xy 373.896343 -217.318623) (xy 373.862431 -217.279989) (xy 373.834418 -217.236884) (xy 373.812887 -217.190204)
			(xy 373.798283 -217.140915) (xy 373.790909 -217.09004) (xy 373.790464 -217.064336) (xy 372.624096 -217.064336)
			(xy 372.624096 -217.064844) (xy 372.623691 -217.088045) (xy 372.617634 -217.134052) (xy 372.605667 -217.178886)
			(xy 372.597172 -217.20048) (xy 372.58752 -217.223594) (xy 372.759732 -217.521536) (xy 372.784624 -217.524838)
			(xy 372.809999 -217.528707) (xy 372.85938 -217.542708) (xy 372.906245 -217.563641) (xy 372.949626 -217.591074)
			(xy 372.988628 -217.624441) (xy 373.022445 -217.663053) (xy 373.05038 -217.706113) (xy 373.071855 -217.752732)
			(xy 373.086428 -217.801947) (xy 373.093797 -217.852742) (xy 373.09425 -217.878406) (xy 373.093751 -217.905093)
			(xy 373.085796 -217.957872) (xy 373.070064 -218.008875) (xy 373.046906 -218.056964) (xy 373.016839 -218.101064)
			(xy 372.980535 -218.140191) (xy 372.938805 -218.173469) (xy 372.892581 -218.200156) (xy 372.842896 -218.219656)
			(xy 372.790859 -218.231533) (xy 372.737634 -218.235522) (xy 372.684409 -218.231533) (xy 372.632372 -218.219656)
			(xy 372.582687 -218.200156) (xy 372.536463 -218.173469) (xy 372.494733 -218.140191) (xy 372.458429 -218.101064)
			(xy 372.428362 -218.056964) (xy 372.405204 -218.008875) (xy 372.389472 -217.957872) (xy 372.381517 -217.905093)
			(xy 372.381018 -217.878406) (xy 372.381374 -217.855066) (xy 372.387479 -217.808787) (xy 372.399586 -217.763705)
			(xy 372.408196 -217.742008) (xy 372.417848 -217.71864) (xy 372.246144 -217.421206) (xy 372.221252 -217.417904)
			(xy 372.195819 -217.414163) (xy 372.146328 -217.400257) (xy 372.099348 -217.379387) (xy 372.055853 -217.351987)
			(xy 372.016743 -217.318623) (xy 371.982831 -217.279989) (xy 371.954818 -217.236884) (xy 371.933287 -217.190204)
			(xy 371.918683 -217.140915) (xy 371.911309 -217.09004) (xy 371.910864 -217.064336) (xy 370.744496 -217.064336)
			(xy 370.744496 -217.064844) (xy 370.744091 -217.088045) (xy 370.738034 -217.134052) (xy 370.726067 -217.178886)
			(xy 370.717572 -217.20048) (xy 370.70792 -217.223594) (xy 370.880132 -217.521536) (xy 370.905024 -217.524838)
			(xy 370.930399 -217.528707) (xy 370.97978 -217.542708) (xy 371.026645 -217.563641) (xy 371.070026 -217.591074)
			(xy 371.109028 -217.624441) (xy 371.142845 -217.663053) (xy 371.17078 -217.706113) (xy 371.192255 -217.752732)
			(xy 371.206828 -217.801947) (xy 371.214197 -217.852742) (xy 371.21465 -217.878406) (xy 371.214151 -217.905093)
			(xy 371.206196 -217.957872) (xy 371.190464 -218.008875) (xy 371.167306 -218.056964) (xy 371.137239 -218.101064)
			(xy 371.100935 -218.140191) (xy 371.059205 -218.173469) (xy 371.012981 -218.200156) (xy 370.963296 -218.219656)
			(xy 370.911259 -218.231533) (xy 370.858034 -218.235522) (xy 370.804809 -218.231533) (xy 370.752772 -218.219656)
			(xy 370.703087 -218.200156) (xy 370.656863 -218.173469) (xy 370.615133 -218.140191) (xy 370.578829 -218.101064)
			(xy 370.548762 -218.056964) (xy 370.525604 -218.008875) (xy 370.509872 -217.957872) (xy 370.501917 -217.905093)
			(xy 370.501418 -217.878406) (xy 370.501774 -217.855066) (xy 370.507879 -217.808787) (xy 370.519986 -217.763705)
			(xy 370.528596 -217.742008) (xy 370.538248 -217.71864) (xy 370.366544 -217.421206) (xy 370.341652 -217.417904)
			(xy 370.316219 -217.414163) (xy 370.266728 -217.400257) (xy 370.219748 -217.379387) (xy 370.176253 -217.351987)
			(xy 370.137143 -217.318623) (xy 370.103231 -217.279989) (xy 370.075218 -217.236884) (xy 370.053687 -217.190204)
			(xy 370.039083 -217.140915) (xy 370.031709 -217.09004) (xy 370.031264 -217.064336) (xy 368.864896 -217.064336)
			(xy 368.864896 -217.064844) (xy 368.864491 -217.088045) (xy 368.858434 -217.134052) (xy 368.846467 -217.178886)
			(xy 368.837972 -217.20048) (xy 368.82832 -217.223594) (xy 369.000532 -217.521536) (xy 369.025424 -217.524838)
			(xy 369.050799 -217.528707) (xy 369.10018 -217.542708) (xy 369.147045 -217.563641) (xy 369.190426 -217.591074)
			(xy 369.229428 -217.624441) (xy 369.263245 -217.663053) (xy 369.29118 -217.706113) (xy 369.312655 -217.752732)
			(xy 369.327228 -217.801947) (xy 369.334597 -217.852742) (xy 369.33505 -217.878406) (xy 369.334551 -217.905093)
			(xy 369.326596 -217.957872) (xy 369.310864 -218.008875) (xy 369.287706 -218.056964) (xy 369.257639 -218.101064)
			(xy 369.221335 -218.140191) (xy 369.179605 -218.173469) (xy 369.133381 -218.200156) (xy 369.083696 -218.219656)
			(xy 369.031659 -218.231533) (xy 368.978434 -218.235522) (xy 368.925209 -218.231533) (xy 368.873172 -218.219656)
			(xy 368.823487 -218.200156) (xy 368.777263 -218.173469) (xy 368.735533 -218.140191) (xy 368.699229 -218.101064)
			(xy 368.669162 -218.056964) (xy 368.646004 -218.008875) (xy 368.630272 -217.957872) (xy 368.622317 -217.905093)
			(xy 368.621818 -217.878406) (xy 368.622174 -217.855066) (xy 368.628279 -217.808787) (xy 368.640386 -217.763705)
			(xy 368.648996 -217.742008) (xy 368.658648 -217.71864) (xy 368.486944 -217.421206) (xy 368.462052 -217.417904)
			(xy 368.436619 -217.414163) (xy 368.387128 -217.400257) (xy 368.340148 -217.379387) (xy 368.296653 -217.351987)
			(xy 368.257543 -217.318623) (xy 368.223631 -217.279989) (xy 368.195618 -217.236884) (xy 368.174087 -217.190204)
			(xy 368.159483 -217.140915) (xy 368.152109 -217.09004) (xy 368.151664 -217.064336) (xy 366.985296 -217.064336)
			(xy 366.985296 -217.064844) (xy 366.984891 -217.088045) (xy 366.978834 -217.134052) (xy 366.966867 -217.178886)
			(xy 366.958372 -217.20048) (xy 366.94872 -217.223594) (xy 367.120932 -217.521536) (xy 367.145824 -217.524838)
			(xy 367.171199 -217.528707) (xy 367.22058 -217.542708) (xy 367.267445 -217.563641) (xy 367.310826 -217.591074)
			(xy 367.349828 -217.624441) (xy 367.383645 -217.663053) (xy 367.41158 -217.706113) (xy 367.433055 -217.752732)
			(xy 367.447628 -217.801947) (xy 367.454997 -217.852742) (xy 367.45545 -217.878406) (xy 367.454951 -217.905093)
			(xy 367.446996 -217.957872) (xy 367.431264 -218.008875) (xy 367.408106 -218.056964) (xy 367.378039 -218.101064)
			(xy 367.341735 -218.140191) (xy 367.300005 -218.173469) (xy 367.253781 -218.200156) (xy 367.204096 -218.219656)
			(xy 367.152059 -218.231533) (xy 367.098834 -218.235522) (xy 367.045609 -218.231533) (xy 366.993572 -218.219656)
			(xy 366.943887 -218.200156) (xy 366.897663 -218.173469) (xy 366.855933 -218.140191) (xy 366.819629 -218.101064)
			(xy 366.789562 -218.056964) (xy 366.766404 -218.008875) (xy 366.750672 -217.957872) (xy 366.742717 -217.905093)
			(xy 366.742218 -217.878406) (xy 366.742574 -217.855066) (xy 366.748679 -217.808787) (xy 366.760786 -217.763705)
			(xy 366.769396 -217.742008) (xy 366.779048 -217.71864) (xy 366.607344 -217.421206) (xy 366.582452 -217.417904)
			(xy 366.557019 -217.414163) (xy 366.507528 -217.400257) (xy 366.460548 -217.379387) (xy 366.417053 -217.351987)
			(xy 366.377943 -217.318623) (xy 366.344031 -217.279989) (xy 366.316018 -217.236884) (xy 366.294487 -217.190204)
			(xy 366.279883 -217.140915) (xy 366.272509 -217.09004) (xy 366.272064 -217.064336) (xy 365.105696 -217.064336)
			(xy 365.105696 -217.064844) (xy 365.105291 -217.088045) (xy 365.099234 -217.134052) (xy 365.087267 -217.178886)
			(xy 365.078772 -217.20048) (xy 365.06912 -217.223594) (xy 365.241332 -217.521536) (xy 365.266224 -217.524838)
			(xy 365.291599 -217.528707) (xy 365.34098 -217.542708) (xy 365.387845 -217.563641) (xy 365.431226 -217.591074)
			(xy 365.470228 -217.624441) (xy 365.504045 -217.663053) (xy 365.53198 -217.706113) (xy 365.553455 -217.752732)
			(xy 365.568028 -217.801947) (xy 365.575397 -217.852742) (xy 365.57585 -217.878406) (xy 365.575351 -217.905093)
			(xy 365.567396 -217.957872) (xy 365.551664 -218.008875) (xy 365.528506 -218.056964) (xy 365.498439 -218.101064)
			(xy 365.462135 -218.140191) (xy 365.420405 -218.173469) (xy 365.374181 -218.200156) (xy 365.324496 -218.219656)
			(xy 365.272459 -218.231533) (xy 365.219234 -218.235522) (xy 365.166009 -218.231533) (xy 365.113972 -218.219656)
			(xy 365.064287 -218.200156) (xy 365.018063 -218.173469) (xy 364.976333 -218.140191) (xy 364.940029 -218.101064)
			(xy 364.909962 -218.056964) (xy 364.886804 -218.008875) (xy 364.871072 -217.957872) (xy 364.863117 -217.905093)
			(xy 364.862618 -217.878406) (xy 364.862974 -217.855066) (xy 364.869079 -217.808787) (xy 364.881186 -217.763705)
			(xy 364.889796 -217.742008) (xy 364.899448 -217.71864) (xy 364.727744 -217.421206) (xy 364.702852 -217.417904)
			(xy 364.677419 -217.414163) (xy 364.627928 -217.400257) (xy 364.580948 -217.379387) (xy 364.537453 -217.351987)
			(xy 364.498343 -217.318623) (xy 364.464431 -217.279989) (xy 364.436418 -217.236884) (xy 364.414887 -217.190204)
			(xy 364.400283 -217.140915) (xy 364.392909 -217.09004) (xy 364.392464 -217.064336) (xy 363.226096 -217.064336)
			(xy 363.226096 -217.064844) (xy 363.225691 -217.088045) (xy 363.219634 -217.134052) (xy 363.207667 -217.178886)
			(xy 363.199172 -217.20048) (xy 363.18952 -217.223594) (xy 363.361732 -217.521536) (xy 363.386624 -217.524838)
			(xy 363.411999 -217.528707) (xy 363.46138 -217.542708) (xy 363.508245 -217.563641) (xy 363.551626 -217.591074)
			(xy 363.590628 -217.624441) (xy 363.624445 -217.663053) (xy 363.65238 -217.706113) (xy 363.673855 -217.752732)
			(xy 363.688428 -217.801947) (xy 363.695797 -217.852742) (xy 363.69625 -217.878406) (xy 363.695751 -217.905093)
			(xy 363.687796 -217.957872) (xy 363.672064 -218.008875) (xy 363.648906 -218.056964) (xy 363.618839 -218.101064)
			(xy 363.582535 -218.140191) (xy 363.540805 -218.173469) (xy 363.494581 -218.200156) (xy 363.444896 -218.219656)
			(xy 363.392859 -218.231533) (xy 363.339634 -218.235522) (xy 363.286409 -218.231533) (xy 363.234372 -218.219656)
			(xy 363.184687 -218.200156) (xy 363.138463 -218.173469) (xy 363.096733 -218.140191) (xy 363.060429 -218.101064)
			(xy 363.030362 -218.056964) (xy 363.007204 -218.008875) (xy 362.991472 -217.957872) (xy 362.983517 -217.905093)
			(xy 362.983018 -217.878406) (xy 362.983374 -217.855066) (xy 362.989479 -217.808787) (xy 363.001586 -217.763705)
			(xy 363.010196 -217.742008) (xy 363.019848 -217.71864) (xy 362.848144 -217.421206) (xy 362.823252 -217.417904)
			(xy 362.797819 -217.414163) (xy 362.748328 -217.400257) (xy 362.701348 -217.379387) (xy 362.657853 -217.351987)
			(xy 362.618743 -217.318623) (xy 362.584831 -217.279989) (xy 362.556818 -217.236884) (xy 362.535287 -217.190204)
			(xy 362.520683 -217.140915) (xy 362.513309 -217.09004) (xy 362.512864 -217.064336) (xy 361.346496 -217.064336)
			(xy 361.346496 -217.064844) (xy 361.346091 -217.088045) (xy 361.340034 -217.134052) (xy 361.328067 -217.178886)
			(xy 361.319572 -217.20048) (xy 361.30992 -217.223594) (xy 361.482132 -217.521536) (xy 361.507024 -217.524838)
			(xy 361.532399 -217.528707) (xy 361.58178 -217.542708) (xy 361.628645 -217.563641) (xy 361.672026 -217.591074)
			(xy 361.711028 -217.624441) (xy 361.744845 -217.663053) (xy 361.77278 -217.706113) (xy 361.794255 -217.752732)
			(xy 361.808828 -217.801947) (xy 361.816197 -217.852742) (xy 361.81665 -217.878406) (xy 361.816151 -217.905093)
			(xy 361.808196 -217.957872) (xy 361.792464 -218.008875) (xy 361.769306 -218.056964) (xy 361.739239 -218.101064)
			(xy 361.702935 -218.140191) (xy 361.661205 -218.173469) (xy 361.614981 -218.200156) (xy 361.565296 -218.219656)
			(xy 361.513259 -218.231533) (xy 361.460034 -218.235522) (xy 361.406809 -218.231533) (xy 361.354772 -218.219656)
			(xy 361.305087 -218.200156) (xy 361.258863 -218.173469) (xy 361.217133 -218.140191) (xy 361.180829 -218.101064)
			(xy 361.150762 -218.056964) (xy 361.127604 -218.008875) (xy 361.111872 -217.957872) (xy 361.103917 -217.905093)
			(xy 361.103418 -217.878406) (xy 361.103774 -217.855066) (xy 361.109879 -217.808787) (xy 361.121986 -217.763705)
			(xy 361.130596 -217.742008) (xy 361.140248 -217.71864) (xy 360.968544 -217.421206) (xy 360.943652 -217.417904)
			(xy 360.918219 -217.414163) (xy 360.868728 -217.400257) (xy 360.821748 -217.379387) (xy 360.778253 -217.351987)
			(xy 360.739143 -217.318623) (xy 360.705231 -217.279989) (xy 360.677218 -217.236884) (xy 360.655687 -217.190204)
			(xy 360.641083 -217.140915) (xy 360.633709 -217.09004) (xy 360.633264 -217.064336) (xy 359.46715 -217.064336)
			(xy 359.466728 -217.090016) (xy 359.459369 -217.140847) (xy 359.444792 -217.190095) (xy 359.4233 -217.236743)
			(xy 359.395338 -217.279824) (xy 359.361485 -217.318448) (xy 359.32244 -217.351815) (xy 359.279011 -217.379235)
			(xy 359.232098 -217.400141) (xy 359.182671 -217.414099) (xy 359.15727 -217.417904) (xy 359.132378 -217.421206)
			(xy 358.96042 -217.71864) (xy 358.970072 -217.742008) (xy 358.978635 -217.76372) (xy 358.990724 -217.8088)
			(xy 358.996846 -217.85507) (xy 358.99725 -217.878406) (xy 358.996751 -217.905093) (xy 358.988796 -217.957872)
			(xy 358.973064 -218.008875) (xy 358.949906 -218.056964) (xy 358.919839 -218.101064) (xy 358.883535 -218.140191)
			(xy 358.841805 -218.173469) (xy 358.795581 -218.200156) (xy 358.745896 -218.219656) (xy 358.693859 -218.231533)
			(xy 358.640634 -218.235522) (xy 358.587409 -218.231533) (xy 358.535372 -218.219656) (xy 358.485687 -218.200156)
			(xy 358.439463 -218.173469) (xy 358.397733 -218.140191) (xy 358.361429 -218.101064) (xy 358.331362 -218.056964)
			(xy 358.308204 -218.008875) (xy 358.292472 -217.957872) (xy 358.284517 -217.905093) (xy 358.284018 -217.878406)
			(xy 358.05745 -217.878406) (xy 358.05745 -217.878914) (xy 358.057063 -217.902116) (xy 358.050998 -217.948123)
			(xy 358.039024 -217.992956) (xy 358.030526 -218.01455) (xy 358.020874 -218.037664) (xy 358.192832 -218.335352)
			(xy 358.217724 -218.338654) (xy 358.243102 -218.342508) (xy 358.292484 -218.356509) (xy 358.33935 -218.377443)
			(xy 358.382732 -218.404878) (xy 358.421734 -218.438247) (xy 358.455551 -218.476861) (xy 358.483485 -218.519923)
			(xy 358.50496 -218.566543) (xy 358.519531 -218.61576) (xy 358.526898 -218.666558) (xy 358.52735 -218.692222)
			(xy 359.693464 -218.692222) (xy 359.693893 -218.666553) (xy 359.701238 -218.615743) (xy 359.715795 -218.566512)
			(xy 359.737263 -218.519878) (xy 359.765196 -218.476805) (xy 359.799019 -218.438184) (xy 359.838031 -218.404813)
			(xy 359.881426 -218.377382) (xy 359.928306 -218.356458) (xy 359.977703 -218.342474) (xy 360.00309 -218.338654)
			(xy 360.027982 -218.335352) (xy 360.200194 -218.037664) (xy 360.190542 -218.01455) (xy 360.182038 -217.992958)
			(xy 360.17006 -217.948125) (xy 360.164006 -217.902117) (xy 360.163618 -217.878914) (xy 360.163618 -217.878406)
			(xy 360.164117 -217.851719) (xy 360.172072 -217.79894) (xy 360.187804 -217.747937) (xy 360.210962 -217.699848)
			(xy 360.241029 -217.655748) (xy 360.277333 -217.616621) (xy 360.319063 -217.583343) (xy 360.365287 -217.556656)
			(xy 360.414972 -217.537156) (xy 360.467009 -217.525279) (xy 360.520234 -217.52129) (xy 360.573459 -217.525279)
			(xy 360.625496 -217.537156) (xy 360.675181 -217.556656) (xy 360.721405 -217.583343) (xy 360.763135 -217.616621)
			(xy 360.799439 -217.655748) (xy 360.829506 -217.699848) (xy 360.852664 -217.747937) (xy 360.868396 -217.79894)
			(xy 360.876351 -217.851719) (xy 360.87685 -217.878406) (xy 360.876397 -217.904117) (xy 360.868996 -217.955005)
			(xy 360.854364 -218.004303) (xy 360.832804 -218.050988) (xy 360.804763 -218.094092) (xy 360.770822 -218.132723)
			(xy 360.731685 -218.166079) (xy 360.688163 -218.193468) (xy 360.641159 -218.214323) (xy 360.591647 -218.228211)
			(xy 360.566208 -218.231974) (xy 360.541316 -218.235276) (xy 360.369866 -218.532456) (xy 360.379518 -218.55557)
			(xy 360.388102 -218.577274) (xy 360.400183 -218.622359) (xy 360.406297 -218.668631) (xy 360.406696 -218.691968)
			(xy 360.406696 -218.692222) (xy 361.573318 -218.692222) (xy 361.573787 -218.666555) (xy 361.581131 -218.615749)
			(xy 361.595686 -218.566521) (xy 361.61715 -218.519889) (xy 361.645079 -218.476818) (xy 361.678897 -218.438197)
			(xy 361.717903 -218.404825) (xy 361.761293 -218.377392) (xy 361.808168 -218.356465) (xy 361.857559 -218.342477)
			(xy 361.882944 -218.338654) (xy 361.907836 -218.335352) (xy 362.079794 -218.037664) (xy 362.070142 -218.01455)
			(xy 362.061638 -217.992958) (xy 362.04966 -217.948125) (xy 362.043606 -217.902117) (xy 362.043218 -217.878914)
			(xy 362.043218 -217.878406) (xy 362.043717 -217.851719) (xy 362.051672 -217.79894) (xy 362.067404 -217.747937)
			(xy 362.090562 -217.699848) (xy 362.120629 -217.655748) (xy 362.156933 -217.616621) (xy 362.198663 -217.583343)
			(xy 362.244887 -217.556656) (xy 362.294572 -217.537156) (xy 362.346609 -217.525279) (xy 362.399834 -217.52129)
			(xy 362.453059 -217.525279) (xy 362.505096 -217.537156) (xy 362.554781 -217.556656) (xy 362.601005 -217.583343)
			(xy 362.642735 -217.616621) (xy 362.679039 -217.655748) (xy 362.709106 -217.699848) (xy 362.732264 -217.747937)
			(xy 362.747996 -217.79894) (xy 362.755951 -217.851719) (xy 362.75645 -217.878406) (xy 362.755972 -217.904094)
			(xy 362.748599 -217.954939) (xy 362.734005 -218.0042) (xy 362.712494 -218.050856) (xy 362.68451 -218.093943)
			(xy 362.650633 -218.132568) (xy 362.611564 -218.165932) (xy 362.568112 -218.193344) (xy 362.521175 -218.214237)
			(xy 362.471726 -218.228179) (xy 362.446316 -218.231974) (xy 362.421424 -218.235276) (xy 362.24972 -218.532456)
			(xy 362.259372 -218.555824) (xy 362.26794 -218.577534) (xy 362.280027 -218.622615) (xy 362.286147 -218.668886)
			(xy 362.28655 -218.692222) (xy 363.452664 -218.692222) (xy 363.453093 -218.666553) (xy 363.460438 -218.615743)
			(xy 363.474995 -218.566512) (xy 363.496463 -218.519878) (xy 363.524396 -218.476805) (xy 363.558219 -218.438184)
			(xy 363.597231 -218.404813) (xy 363.640626 -218.377382) (xy 363.687506 -218.356458) (xy 363.736903 -218.342474)
			(xy 363.76229 -218.338654) (xy 363.787182 -218.335352) (xy 363.959394 -218.037664) (xy 363.949742 -218.01455)
			(xy 363.941238 -217.992958) (xy 363.92926 -217.948125) (xy 363.923206 -217.902117) (xy 363.922818 -217.878914)
			(xy 363.922818 -217.878406) (xy 363.923317 -217.851719) (xy 363.931272 -217.79894) (xy 363.947004 -217.747937)
			(xy 363.970162 -217.699848) (xy 364.000229 -217.655748) (xy 364.036533 -217.616621) (xy 364.078263 -217.583343)
			(xy 364.124487 -217.556656) (xy 364.174172 -217.537156) (xy 364.226209 -217.525279) (xy 364.279434 -217.52129)
			(xy 364.332659 -217.525279) (xy 364.384696 -217.537156) (xy 364.434381 -217.556656) (xy 364.480605 -217.583343)
			(xy 364.522335 -217.616621) (xy 364.558639 -217.655748) (xy 364.588706 -217.699848) (xy 364.611864 -217.747937)
			(xy 364.627596 -217.79894) (xy 364.635551 -217.851719) (xy 364.63605 -217.878406) (xy 364.635597 -217.904117)
			(xy 364.628196 -217.955005) (xy 364.613564 -218.004303) (xy 364.592004 -218.050988) (xy 364.563963 -218.094092)
			(xy 364.530022 -218.132723) (xy 364.490885 -218.166079) (xy 364.447363 -218.193468) (xy 364.400359 -218.214323)
			(xy 364.350847 -218.228211) (xy 364.325408 -218.231974) (xy 364.300516 -218.235276) (xy 364.129066 -218.532456)
			(xy 364.138718 -218.55557) (xy 364.147302 -218.577274) (xy 364.159383 -218.622359) (xy 364.165497 -218.668631)
			(xy 364.165896 -218.691968) (xy 364.165896 -218.692222) (xy 365.332264 -218.692222) (xy 365.332693 -218.666553)
			(xy 365.340038 -218.615743) (xy 365.354595 -218.566512) (xy 365.376063 -218.519878) (xy 365.403996 -218.476805)
			(xy 365.437819 -218.438184) (xy 365.476831 -218.404813) (xy 365.520226 -218.377382) (xy 365.567106 -218.356458)
			(xy 365.616503 -218.342474) (xy 365.64189 -218.338654) (xy 365.666782 -218.335352) (xy 365.838994 -218.037664)
			(xy 365.829342 -218.01455) (xy 365.820838 -217.992958) (xy 365.80886 -217.948125) (xy 365.802806 -217.902117)
			(xy 365.802418 -217.878914) (xy 365.802418 -217.878406) (xy 365.802917 -217.851719) (xy 365.810872 -217.79894)
			(xy 365.826604 -217.747937) (xy 365.849762 -217.699848) (xy 365.879829 -217.655748) (xy 365.916133 -217.616621)
			(xy 365.957863 -217.583343) (xy 366.004087 -217.556656) (xy 366.053772 -217.537156) (xy 366.105809 -217.525279)
			(xy 366.159034 -217.52129) (xy 366.212259 -217.525279) (xy 366.264296 -217.537156) (xy 366.313981 -217.556656)
			(xy 366.360205 -217.583343) (xy 366.401935 -217.616621) (xy 366.438239 -217.655748) (xy 366.468306 -217.699848)
			(xy 366.491464 -217.747937) (xy 366.507196 -217.79894) (xy 366.515151 -217.851719) (xy 366.51565 -217.878406)
			(xy 366.515197 -217.904117) (xy 366.507796 -217.955005) (xy 366.493164 -218.004303) (xy 366.471604 -218.050988)
			(xy 366.443563 -218.094092) (xy 366.409622 -218.132723) (xy 366.370485 -218.166079) (xy 366.326963 -218.193468)
			(xy 366.279959 -218.214323) (xy 366.230447 -218.228211) (xy 366.205008 -218.231974) (xy 366.180116 -218.235276)
			(xy 366.008666 -218.532456) (xy 366.018318 -218.55557) (xy 366.026902 -218.577274) (xy 366.038983 -218.622359)
			(xy 366.045097 -218.668631) (xy 366.045496 -218.691968) (xy 366.045496 -218.692222) (xy 367.211864 -218.692222)
			(xy 367.212293 -218.666553) (xy 367.219638 -218.615743) (xy 367.234195 -218.566512) (xy 367.255663 -218.519878)
			(xy 367.283596 -218.476805) (xy 367.317419 -218.438184) (xy 367.356431 -218.404813) (xy 367.399826 -218.377382)
			(xy 367.446706 -218.356458) (xy 367.496103 -218.342474) (xy 367.52149 -218.338654) (xy 367.546382 -218.335352)
			(xy 367.718594 -218.037664) (xy 367.708942 -218.01455) (xy 367.700438 -217.992958) (xy 367.68846 -217.948125)
			(xy 367.682406 -217.902117) (xy 367.682018 -217.878914) (xy 367.682018 -217.878406) (xy 367.682517 -217.851719)
			(xy 367.690472 -217.79894) (xy 367.706204 -217.747937) (xy 367.729362 -217.699848) (xy 367.759429 -217.655748)
			(xy 367.795733 -217.616621) (xy 367.837463 -217.583343) (xy 367.883687 -217.556656) (xy 367.933372 -217.537156)
			(xy 367.985409 -217.525279) (xy 368.038634 -217.52129) (xy 368.091859 -217.525279) (xy 368.143896 -217.537156)
			(xy 368.193581 -217.556656) (xy 368.239805 -217.583343) (xy 368.281535 -217.616621) (xy 368.317839 -217.655748)
			(xy 368.347906 -217.699848) (xy 368.371064 -217.747937) (xy 368.386796 -217.79894) (xy 368.394751 -217.851719)
			(xy 368.39525 -217.878406) (xy 368.394797 -217.904117) (xy 368.387396 -217.955005) (xy 368.372764 -218.004303)
			(xy 368.351204 -218.050988) (xy 368.323163 -218.094092) (xy 368.289222 -218.132723) (xy 368.250085 -218.166079)
			(xy 368.206563 -218.193468) (xy 368.159559 -218.214323) (xy 368.110047 -218.228211) (xy 368.084608 -218.231974)
			(xy 368.059716 -218.235276) (xy 367.888266 -218.532456) (xy 367.897918 -218.55557) (xy 367.906502 -218.577274)
			(xy 367.918583 -218.622359) (xy 367.924697 -218.668631) (xy 367.925096 -218.691968) (xy 367.925096 -218.692222)
			(xy 369.091464 -218.692222) (xy 369.091893 -218.666553) (xy 369.099238 -218.615743) (xy 369.113795 -218.566512)
			(xy 369.135263 -218.519878) (xy 369.163196 -218.476805) (xy 369.197019 -218.438184) (xy 369.236031 -218.404813)
			(xy 369.279426 -218.377382) (xy 369.326306 -218.356458) (xy 369.375703 -218.342474) (xy 369.40109 -218.338654)
			(xy 369.425982 -218.335352) (xy 369.598194 -218.037664) (xy 369.588542 -218.01455) (xy 369.580038 -217.992958)
			(xy 369.56806 -217.948125) (xy 369.562006 -217.902117) (xy 369.561618 -217.878914) (xy 369.561618 -217.878406)
			(xy 369.562117 -217.851719) (xy 369.570072 -217.79894) (xy 369.585804 -217.747937) (xy 369.608962 -217.699848)
			(xy 369.639029 -217.655748) (xy 369.675333 -217.616621) (xy 369.717063 -217.583343) (xy 369.763287 -217.556656)
			(xy 369.812972 -217.537156) (xy 369.865009 -217.525279) (xy 369.918234 -217.52129) (xy 369.971459 -217.525279)
			(xy 370.023496 -217.537156) (xy 370.073181 -217.556656) (xy 370.119405 -217.583343) (xy 370.161135 -217.616621)
			(xy 370.197439 -217.655748) (xy 370.227506 -217.699848) (xy 370.250664 -217.747937) (xy 370.266396 -217.79894)
			(xy 370.274351 -217.851719) (xy 370.27485 -217.878406) (xy 370.274397 -217.904117) (xy 370.266996 -217.955005)
			(xy 370.252364 -218.004303) (xy 370.230804 -218.050988) (xy 370.202763 -218.094092) (xy 370.168822 -218.132723)
			(xy 370.129685 -218.166079) (xy 370.086163 -218.193468) (xy 370.039159 -218.214323) (xy 369.989647 -218.228211)
			(xy 369.964208 -218.231974) (xy 369.939316 -218.235276) (xy 369.767866 -218.532456) (xy 369.777518 -218.55557)
			(xy 369.786102 -218.577274) (xy 369.798183 -218.622359) (xy 369.804297 -218.668631) (xy 369.804696 -218.691968)
			(xy 369.804696 -218.692222) (xy 370.971064 -218.692222) (xy 370.971493 -218.666553) (xy 370.978838 -218.615743)
			(xy 370.993395 -218.566512) (xy 371.014863 -218.519878) (xy 371.042796 -218.476805) (xy 371.076619 -218.438184)
			(xy 371.115631 -218.404813) (xy 371.159026 -218.377382) (xy 371.205906 -218.356458) (xy 371.255303 -218.342474)
			(xy 371.28069 -218.338654) (xy 371.305582 -218.335352) (xy 371.477794 -218.037664) (xy 371.468142 -218.01455)
			(xy 371.459638 -217.992958) (xy 371.44766 -217.948125) (xy 371.441606 -217.902117) (xy 371.441218 -217.878914)
			(xy 371.441218 -217.878406) (xy 371.441717 -217.851719) (xy 371.449672 -217.79894) (xy 371.465404 -217.747937)
			(xy 371.488562 -217.699848) (xy 371.518629 -217.655748) (xy 371.554933 -217.616621) (xy 371.596663 -217.583343)
			(xy 371.642887 -217.556656) (xy 371.692572 -217.537156) (xy 371.744609 -217.525279) (xy 371.797834 -217.52129)
			(xy 371.851059 -217.525279) (xy 371.903096 -217.537156) (xy 371.952781 -217.556656) (xy 371.999005 -217.583343)
			(xy 372.040735 -217.616621) (xy 372.077039 -217.655748) (xy 372.107106 -217.699848) (xy 372.130264 -217.747937)
			(xy 372.145996 -217.79894) (xy 372.153951 -217.851719) (xy 372.15445 -217.878406) (xy 372.153997 -217.904117)
			(xy 372.146596 -217.955005) (xy 372.131964 -218.004303) (xy 372.110404 -218.050988) (xy 372.082363 -218.094092)
			(xy 372.048422 -218.132723) (xy 372.009285 -218.166079) (xy 371.965763 -218.193468) (xy 371.918759 -218.214323)
			(xy 371.869247 -218.228211) (xy 371.843808 -218.231974) (xy 371.818916 -218.235276) (xy 371.647466 -218.532456)
			(xy 371.657118 -218.55557) (xy 371.665702 -218.577274) (xy 371.677783 -218.622359) (xy 371.683897 -218.668631)
			(xy 371.684296 -218.691968) (xy 371.684296 -218.692222) (xy 372.850664 -218.692222) (xy 372.851093 -218.666553)
			(xy 372.858438 -218.615743) (xy 372.872995 -218.566512) (xy 372.894463 -218.519878) (xy 372.922396 -218.476805)
			(xy 372.956219 -218.438184) (xy 372.995231 -218.404813) (xy 373.038626 -218.377382) (xy 373.085506 -218.356458)
			(xy 373.134903 -218.342474) (xy 373.16029 -218.338654) (xy 373.185182 -218.335352) (xy 373.357394 -218.037664)
			(xy 373.347742 -218.01455) (xy 373.339238 -217.992958) (xy 373.32726 -217.948125) (xy 373.321206 -217.902117)
			(xy 373.320818 -217.878914) (xy 373.320818 -217.878406) (xy 373.321317 -217.851719) (xy 373.329272 -217.79894)
			(xy 373.345004 -217.747937) (xy 373.368162 -217.699848) (xy 373.398229 -217.655748) (xy 373.434533 -217.616621)
			(xy 373.476263 -217.583343) (xy 373.522487 -217.556656) (xy 373.572172 -217.537156) (xy 373.624209 -217.525279)
			(xy 373.677434 -217.52129) (xy 373.730659 -217.525279) (xy 373.782696 -217.537156) (xy 373.832381 -217.556656)
			(xy 373.878605 -217.583343) (xy 373.920335 -217.616621) (xy 373.956639 -217.655748) (xy 373.986706 -217.699848)
			(xy 374.009864 -217.747937) (xy 374.025596 -217.79894) (xy 374.033551 -217.851719) (xy 374.03405 -217.878406)
			(xy 374.033597 -217.904117) (xy 374.026196 -217.955005) (xy 374.011564 -218.004303) (xy 373.990004 -218.050988)
			(xy 373.961963 -218.094092) (xy 373.928022 -218.132723) (xy 373.888885 -218.166079) (xy 373.845363 -218.193468)
			(xy 373.798359 -218.214323) (xy 373.748847 -218.228211) (xy 373.723408 -218.231974) (xy 373.698516 -218.235276)
			(xy 373.527066 -218.532456) (xy 373.536718 -218.55557) (xy 373.545302 -218.577274) (xy 373.557383 -218.622359)
			(xy 373.563497 -218.668631) (xy 373.563896 -218.691968) (xy 373.563896 -218.692222) (xy 374.730264 -218.692222)
			(xy 374.730693 -218.666553) (xy 374.738038 -218.615743) (xy 374.752595 -218.566512) (xy 374.774063 -218.519878)
			(xy 374.801996 -218.476805) (xy 374.835819 -218.438184) (xy 374.874831 -218.404813) (xy 374.918226 -218.377382)
			(xy 374.965106 -218.356458) (xy 375.014503 -218.342474) (xy 375.03989 -218.338654) (xy 375.064782 -218.335352)
			(xy 375.236994 -218.037664) (xy 375.227342 -218.01455) (xy 375.218838 -217.992958) (xy 375.20686 -217.948125)
			(xy 375.200806 -217.902117) (xy 375.200418 -217.878914) (xy 375.200418 -217.878406) (xy 375.200917 -217.851719)
			(xy 375.208872 -217.79894) (xy 375.224604 -217.747937) (xy 375.247762 -217.699848) (xy 375.277829 -217.655748)
			(xy 375.314133 -217.616621) (xy 375.355863 -217.583343) (xy 375.402087 -217.556656) (xy 375.451772 -217.537156)
			(xy 375.503809 -217.525279) (xy 375.557034 -217.52129) (xy 375.610259 -217.525279) (xy 375.662296 -217.537156)
			(xy 375.711981 -217.556656) (xy 375.758205 -217.583343) (xy 375.799935 -217.616621) (xy 375.836239 -217.655748)
			(xy 375.866306 -217.699848) (xy 375.889464 -217.747937) (xy 375.905196 -217.79894) (xy 375.913151 -217.851719)
			(xy 375.91365 -217.878406) (xy 375.913197 -217.904117) (xy 375.905796 -217.955005) (xy 375.891164 -218.004303)
			(xy 375.869604 -218.050988) (xy 375.841563 -218.094092) (xy 375.807622 -218.132723) (xy 375.768485 -218.166079)
			(xy 375.724963 -218.193468) (xy 375.677959 -218.214323) (xy 375.628447 -218.228211) (xy 375.603008 -218.231974)
			(xy 375.578116 -218.235276) (xy 375.406666 -218.532456) (xy 375.416318 -218.55557) (xy 375.424902 -218.577274)
			(xy 375.436983 -218.622359) (xy 375.443097 -218.668631) (xy 375.443496 -218.691968) (xy 375.443496 -218.692222)
			(xy 376.609864 -218.692222) (xy 376.610293 -218.666553) (xy 376.617638 -218.615743) (xy 376.632195 -218.566512)
			(xy 376.653663 -218.519878) (xy 376.681596 -218.476805) (xy 376.715419 -218.438184) (xy 376.754431 -218.404813)
			(xy 376.797826 -218.377382) (xy 376.844706 -218.356458) (xy 376.894103 -218.342474) (xy 376.91949 -218.338654)
			(xy 376.944382 -218.335352) (xy 377.116594 -218.037664) (xy 377.106942 -218.01455) (xy 377.098438 -217.992958)
			(xy 377.08646 -217.948125) (xy 377.080406 -217.902117) (xy 377.080018 -217.878914) (xy 377.080018 -217.878406)
			(xy 377.080517 -217.851719) (xy 377.088472 -217.79894) (xy 377.104204 -217.747937) (xy 377.127362 -217.699848)
			(xy 377.157429 -217.655748) (xy 377.193733 -217.616621) (xy 377.235463 -217.583343) (xy 377.281687 -217.556656)
			(xy 377.331372 -217.537156) (xy 377.383409 -217.525279) (xy 377.436634 -217.52129) (xy 377.489859 -217.525279)
			(xy 377.541896 -217.537156) (xy 377.591581 -217.556656) (xy 377.637805 -217.583343) (xy 377.679535 -217.616621)
			(xy 377.715839 -217.655748) (xy 377.745906 -217.699848) (xy 377.769064 -217.747937) (xy 377.784796 -217.79894)
			(xy 377.792751 -217.851719) (xy 377.79325 -217.878406) (xy 377.792797 -217.904117) (xy 377.785396 -217.955005)
			(xy 377.770764 -218.004303) (xy 377.749204 -218.050988) (xy 377.721163 -218.094092) (xy 377.687222 -218.132723)
			(xy 377.648085 -218.166079) (xy 377.604563 -218.193468) (xy 377.557559 -218.214323) (xy 377.508047 -218.228211)
			(xy 377.482608 -218.231974) (xy 377.457716 -218.235276) (xy 377.286266 -218.532456) (xy 377.295918 -218.55557)
			(xy 377.304502 -218.577274) (xy 377.316583 -218.622359) (xy 377.322697 -218.668631) (xy 377.323096 -218.691968)
			(xy 377.323096 -218.692222) (xy 378.489464 -218.692222) (xy 378.489893 -218.666553) (xy 378.497238 -218.615743)
			(xy 378.511795 -218.566512) (xy 378.533263 -218.519878) (xy 378.561196 -218.476805) (xy 378.595019 -218.438184)
			(xy 378.634031 -218.404813) (xy 378.677426 -218.377382) (xy 378.724306 -218.356458) (xy 378.773703 -218.342474)
			(xy 378.79909 -218.338654) (xy 378.823982 -218.335352) (xy 378.996194 -218.037664) (xy 378.986542 -218.01455)
			(xy 378.978038 -217.992958) (xy 378.96606 -217.948125) (xy 378.960006 -217.902117) (xy 378.959618 -217.878914)
			(xy 378.959618 -217.878406) (xy 378.960117 -217.851719) (xy 378.968072 -217.79894) (xy 378.983804 -217.747937)
			(xy 379.006962 -217.699848) (xy 379.037029 -217.655748) (xy 379.073333 -217.616621) (xy 379.115063 -217.583343)
			(xy 379.161287 -217.556656) (xy 379.210972 -217.537156) (xy 379.263009 -217.525279) (xy 379.316234 -217.52129)
			(xy 379.369459 -217.525279) (xy 379.421496 -217.537156) (xy 379.471181 -217.556656) (xy 379.517405 -217.583343)
			(xy 379.559135 -217.616621) (xy 379.595439 -217.655748) (xy 379.625506 -217.699848) (xy 379.648664 -217.747937)
			(xy 379.664396 -217.79894) (xy 379.672351 -217.851719) (xy 379.67285 -217.878406) (xy 379.672397 -217.904117)
			(xy 379.664996 -217.955005) (xy 379.650364 -218.004303) (xy 379.628804 -218.050988) (xy 379.600763 -218.094092)
			(xy 379.566822 -218.132723) (xy 379.527685 -218.166079) (xy 379.484163 -218.193468) (xy 379.437159 -218.214323)
			(xy 379.387647 -218.228211) (xy 379.362208 -218.231974) (xy 379.337316 -218.235276) (xy 379.165866 -218.532456)
			(xy 379.175518 -218.55557) (xy 379.184102 -218.577274) (xy 379.196183 -218.622359) (xy 379.202297 -218.668631)
			(xy 379.202696 -218.691968) (xy 379.202696 -218.692222) (xy 380.369064 -218.692222) (xy 380.369493 -218.666553)
			(xy 380.376838 -218.615743) (xy 380.391395 -218.566512) (xy 380.412863 -218.519878) (xy 380.440796 -218.476805)
			(xy 380.474619 -218.438184) (xy 380.513631 -218.404813) (xy 380.557026 -218.377382) (xy 380.603906 -218.356458)
			(xy 380.653303 -218.342474) (xy 380.67869 -218.338654) (xy 380.703582 -218.335352) (xy 380.875794 -218.037664)
			(xy 380.866142 -218.01455) (xy 380.857638 -217.992958) (xy 380.84566 -217.948125) (xy 380.839606 -217.902117)
			(xy 380.839218 -217.878914) (xy 380.839218 -217.878406) (xy 380.839717 -217.851719) (xy 380.847672 -217.79894)
			(xy 380.863404 -217.747937) (xy 380.886562 -217.699848) (xy 380.916629 -217.655748) (xy 380.952933 -217.616621)
			(xy 380.994663 -217.583343) (xy 381.040887 -217.556656) (xy 381.090572 -217.537156) (xy 381.142609 -217.525279)
			(xy 381.195834 -217.52129) (xy 381.249059 -217.525279) (xy 381.301096 -217.537156) (xy 381.350781 -217.556656)
			(xy 381.397005 -217.583343) (xy 381.438735 -217.616621) (xy 381.475039 -217.655748) (xy 381.505106 -217.699848)
			(xy 381.528264 -217.747937) (xy 381.543996 -217.79894) (xy 381.551951 -217.851719) (xy 381.55245 -217.878406)
			(xy 381.551997 -217.904117) (xy 381.544596 -217.955005) (xy 381.529964 -218.004303) (xy 381.508404 -218.050988)
			(xy 381.480363 -218.094092) (xy 381.446422 -218.132723) (xy 381.407285 -218.166079) (xy 381.363763 -218.193468)
			(xy 381.316759 -218.214323) (xy 381.267247 -218.228211) (xy 381.241808 -218.231974) (xy 381.216916 -218.235276)
			(xy 381.045466 -218.532456) (xy 381.055118 -218.55557) (xy 381.063702 -218.577274) (xy 381.075783 -218.622359)
			(xy 381.081897 -218.668631) (xy 381.082296 -218.691968) (xy 381.082296 -218.692222) (xy 381.081797 -218.718909)
			(xy 381.073842 -218.771688) (xy 381.05811 -218.822691) (xy 381.034952 -218.87078) (xy 381.004885 -218.91488)
			(xy 380.968581 -218.954007) (xy 380.926851 -218.987285) (xy 380.880627 -219.013972) (xy 380.830942 -219.033472)
			(xy 380.778905 -219.045349) (xy 380.72568 -219.049338) (xy 380.672455 -219.045349) (xy 380.620418 -219.033472)
			(xy 380.570733 -219.013972) (xy 380.524509 -218.987285) (xy 380.482779 -218.954007) (xy 380.446475 -218.91488)
			(xy 380.416408 -218.87078) (xy 380.39325 -218.822691) (xy 380.377518 -218.771688) (xy 380.369563 -218.718909)
			(xy 380.369064 -218.692222) (xy 379.202696 -218.692222) (xy 379.202197 -218.718909) (xy 379.194242 -218.771688)
			(xy 379.17851 -218.822691) (xy 379.155352 -218.87078) (xy 379.125285 -218.91488) (xy 379.088981 -218.954007)
			(xy 379.047251 -218.987285) (xy 379.001027 -219.013972) (xy 378.951342 -219.033472) (xy 378.899305 -219.045349)
			(xy 378.84608 -219.049338) (xy 378.792855 -219.045349) (xy 378.740818 -219.033472) (xy 378.691133 -219.013972)
			(xy 378.644909 -218.987285) (xy 378.603179 -218.954007) (xy 378.566875 -218.91488) (xy 378.536808 -218.87078)
			(xy 378.51365 -218.822691) (xy 378.497918 -218.771688) (xy 378.489963 -218.718909) (xy 378.489464 -218.692222)
			(xy 377.323096 -218.692222) (xy 377.322597 -218.718909) (xy 377.314642 -218.771688) (xy 377.29891 -218.822691)
			(xy 377.275752 -218.87078) (xy 377.245685 -218.91488) (xy 377.209381 -218.954007) (xy 377.167651 -218.987285)
			(xy 377.121427 -219.013972) (xy 377.071742 -219.033472) (xy 377.019705 -219.045349) (xy 376.96648 -219.049338)
			(xy 376.913255 -219.045349) (xy 376.861218 -219.033472) (xy 376.811533 -219.013972) (xy 376.765309 -218.987285)
			(xy 376.723579 -218.954007) (xy 376.687275 -218.91488) (xy 376.657208 -218.87078) (xy 376.63405 -218.822691)
			(xy 376.618318 -218.771688) (xy 376.610363 -218.718909) (xy 376.609864 -218.692222) (xy 375.443496 -218.692222)
			(xy 375.442997 -218.718909) (xy 375.435042 -218.771688) (xy 375.41931 -218.822691) (xy 375.396152 -218.87078)
			(xy 375.366085 -218.91488) (xy 375.329781 -218.954007) (xy 375.288051 -218.987285) (xy 375.241827 -219.013972)
			(xy 375.192142 -219.033472) (xy 375.140105 -219.045349) (xy 375.08688 -219.049338) (xy 375.033655 -219.045349)
			(xy 374.981618 -219.033472) (xy 374.931933 -219.013972) (xy 374.885709 -218.987285) (xy 374.843979 -218.954007)
			(xy 374.807675 -218.91488) (xy 374.777608 -218.87078) (xy 374.75445 -218.822691) (xy 374.738718 -218.771688)
			(xy 374.730763 -218.718909) (xy 374.730264 -218.692222) (xy 373.563896 -218.692222) (xy 373.563397 -218.718909)
			(xy 373.555442 -218.771688) (xy 373.53971 -218.822691) (xy 373.516552 -218.87078) (xy 373.486485 -218.91488)
			(xy 373.450181 -218.954007) (xy 373.408451 -218.987285) (xy 373.362227 -219.013972) (xy 373.312542 -219.033472)
			(xy 373.260505 -219.045349) (xy 373.20728 -219.049338) (xy 373.154055 -219.045349) (xy 373.102018 -219.033472)
			(xy 373.052333 -219.013972) (xy 373.006109 -218.987285) (xy 372.964379 -218.954007) (xy 372.928075 -218.91488)
			(xy 372.898008 -218.87078) (xy 372.87485 -218.822691) (xy 372.859118 -218.771688) (xy 372.851163 -218.718909)
			(xy 372.850664 -218.692222) (xy 371.684296 -218.692222) (xy 371.683797 -218.718909) (xy 371.675842 -218.771688)
			(xy 371.66011 -218.822691) (xy 371.636952 -218.87078) (xy 371.606885 -218.91488) (xy 371.570581 -218.954007)
			(xy 371.528851 -218.987285) (xy 371.482627 -219.013972) (xy 371.432942 -219.033472) (xy 371.380905 -219.045349)
			(xy 371.32768 -219.049338) (xy 371.274455 -219.045349) (xy 371.222418 -219.033472) (xy 371.172733 -219.013972)
			(xy 371.126509 -218.987285) (xy 371.084779 -218.954007) (xy 371.048475 -218.91488) (xy 371.018408 -218.87078)
			(xy 370.99525 -218.822691) (xy 370.979518 -218.771688) (xy 370.971563 -218.718909) (xy 370.971064 -218.692222)
			(xy 369.804696 -218.692222) (xy 369.804197 -218.718909) (xy 369.796242 -218.771688) (xy 369.78051 -218.822691)
			(xy 369.757352 -218.87078) (xy 369.727285 -218.91488) (xy 369.690981 -218.954007) (xy 369.649251 -218.987285)
			(xy 369.603027 -219.013972) (xy 369.553342 -219.033472) (xy 369.501305 -219.045349) (xy 369.44808 -219.049338)
			(xy 369.394855 -219.045349) (xy 369.342818 -219.033472) (xy 369.293133 -219.013972) (xy 369.246909 -218.987285)
			(xy 369.205179 -218.954007) (xy 369.168875 -218.91488) (xy 369.138808 -218.87078) (xy 369.11565 -218.822691)
			(xy 369.099918 -218.771688) (xy 369.091963 -218.718909) (xy 369.091464 -218.692222) (xy 367.925096 -218.692222)
			(xy 367.924597 -218.718909) (xy 367.916642 -218.771688) (xy 367.90091 -218.822691) (xy 367.877752 -218.87078)
			(xy 367.847685 -218.91488) (xy 367.811381 -218.954007) (xy 367.769651 -218.987285) (xy 367.723427 -219.013972)
			(xy 367.673742 -219.033472) (xy 367.621705 -219.045349) (xy 367.56848 -219.049338) (xy 367.515255 -219.045349)
			(xy 367.463218 -219.033472) (xy 367.413533 -219.013972) (xy 367.367309 -218.987285) (xy 367.325579 -218.954007)
			(xy 367.289275 -218.91488) (xy 367.259208 -218.87078) (xy 367.23605 -218.822691) (xy 367.220318 -218.771688)
			(xy 367.212363 -218.718909) (xy 367.211864 -218.692222) (xy 366.045496 -218.692222) (xy 366.044997 -218.718909)
			(xy 366.037042 -218.771688) (xy 366.02131 -218.822691) (xy 365.998152 -218.87078) (xy 365.968085 -218.91488)
			(xy 365.931781 -218.954007) (xy 365.890051 -218.987285) (xy 365.843827 -219.013972) (xy 365.794142 -219.033472)
			(xy 365.742105 -219.045349) (xy 365.68888 -219.049338) (xy 365.635655 -219.045349) (xy 365.583618 -219.033472)
			(xy 365.533933 -219.013972) (xy 365.487709 -218.987285) (xy 365.445979 -218.954007) (xy 365.409675 -218.91488)
			(xy 365.379608 -218.87078) (xy 365.35645 -218.822691) (xy 365.340718 -218.771688) (xy 365.332763 -218.718909)
			(xy 365.332264 -218.692222) (xy 364.165896 -218.692222) (xy 364.165397 -218.718909) (xy 364.157442 -218.771688)
			(xy 364.14171 -218.822691) (xy 364.118552 -218.87078) (xy 364.088485 -218.91488) (xy 364.052181 -218.954007)
			(xy 364.010451 -218.987285) (xy 363.964227 -219.013972) (xy 363.914542 -219.033472) (xy 363.862505 -219.045349)
			(xy 363.80928 -219.049338) (xy 363.756055 -219.045349) (xy 363.704018 -219.033472) (xy 363.654333 -219.013972)
			(xy 363.608109 -218.987285) (xy 363.566379 -218.954007) (xy 363.530075 -218.91488) (xy 363.500008 -218.87078)
			(xy 363.47685 -218.822691) (xy 363.461118 -218.771688) (xy 363.453163 -218.718909) (xy 363.452664 -218.692222)
			(xy 362.28655 -218.692222) (xy 362.286051 -218.718909) (xy 362.278096 -218.771688) (xy 362.262364 -218.822691)
			(xy 362.239206 -218.87078) (xy 362.209139 -218.91488) (xy 362.172835 -218.954007) (xy 362.131105 -218.987285)
			(xy 362.084881 -219.013972) (xy 362.035196 -219.033472) (xy 361.983159 -219.045349) (xy 361.929934 -219.049338)
			(xy 361.876709 -219.045349) (xy 361.824672 -219.033472) (xy 361.774987 -219.013972) (xy 361.728763 -218.987285)
			(xy 361.687033 -218.954007) (xy 361.650729 -218.91488) (xy 361.620662 -218.87078) (xy 361.597504 -218.822691)
			(xy 361.581772 -218.771688) (xy 361.573817 -218.718909) (xy 361.573318 -218.692222) (xy 360.406696 -218.692222)
			(xy 360.406197 -218.718909) (xy 360.398242 -218.771688) (xy 360.38251 -218.822691) (xy 360.359352 -218.87078)
			(xy 360.329285 -218.91488) (xy 360.292981 -218.954007) (xy 360.251251 -218.987285) (xy 360.205027 -219.013972)
			(xy 360.155342 -219.033472) (xy 360.103305 -219.045349) (xy 360.05008 -219.049338) (xy 359.996855 -219.045349)
			(xy 359.944818 -219.033472) (xy 359.895133 -219.013972) (xy 359.848909 -218.987285) (xy 359.807179 -218.954007)
			(xy 359.770875 -218.91488) (xy 359.740808 -218.87078) (xy 359.71765 -218.822691) (xy 359.701918 -218.771688)
			(xy 359.693963 -218.718909) (xy 359.693464 -218.692222) (xy 358.52735 -218.692222) (xy 358.526851 -218.718909)
			(xy 358.518896 -218.771688) (xy 358.503164 -218.822691) (xy 358.480006 -218.87078) (xy 358.449939 -218.91488)
			(xy 358.413635 -218.954007) (xy 358.371905 -218.987285) (xy 358.325681 -219.013972) (xy 358.275996 -219.033472)
			(xy 358.223959 -219.045349) (xy 358.170734 -219.049338) (xy 358.117509 -219.045349) (xy 358.065472 -219.033472)
			(xy 358.015787 -219.013972) (xy 357.969563 -218.987285) (xy 357.927833 -218.954007) (xy 357.891529 -218.91488)
			(xy 357.861462 -218.87078) (xy 357.838304 -218.822691) (xy 357.822572 -218.771688) (xy 357.814617 -218.718909)
			(xy 357.814118 -218.692222) (xy 357.814479 -218.668882) (xy 357.820582 -218.622604) (xy 357.832687 -218.577521)
			(xy 357.841296 -218.555824) (xy 357.850948 -218.532456) (xy 357.67899 -218.235276) (xy 357.654098 -218.231974)
			(xy 357.628697 -218.228185) (xy 357.579277 -218.214213) (xy 357.532372 -218.193298) (xy 357.488951 -218.165872)
			(xy 357.449912 -218.132502) (xy 357.416064 -218.093878) (xy 357.388104 -218.050799) (xy 357.366612 -218.004155)
			(xy 357.352032 -217.954911) (xy 357.344666 -217.904085) (xy 357.344218 -217.878406) (xy 357.11765 -217.878406)
			(xy 357.117151 -217.905093) (xy 357.109196 -217.957872) (xy 357.093464 -218.008875) (xy 357.070306 -218.056964)
			(xy 357.040239 -218.101064) (xy 357.003935 -218.140191) (xy 356.962205 -218.173469) (xy 356.915981 -218.200156)
			(xy 356.866296 -218.219656) (xy 356.814259 -218.231533) (xy 356.761034 -218.235522) (xy 356.707809 -218.231533)
			(xy 356.655772 -218.219656) (xy 356.606087 -218.200156) (xy 356.559863 -218.173469) (xy 356.518133 -218.140191)
			(xy 356.481829 -218.101064) (xy 356.451762 -218.056964) (xy 356.428604 -218.008875) (xy 356.412872 -217.957872)
			(xy 356.404917 -217.905093) (xy 356.404418 -217.878406) (xy 356.17785 -217.878406) (xy 356.177468 -217.901745)
			(xy 356.171374 -217.948023) (xy 356.159278 -217.993106) (xy 356.150672 -218.014804) (xy 356.14102 -218.038172)
			(xy 356.312978 -218.335352) (xy 356.33787 -218.338654) (xy 356.363241 -218.34255) (xy 356.412623 -218.356544)
			(xy 356.459489 -218.377472) (xy 356.502871 -218.404901) (xy 356.541875 -218.438265) (xy 356.575693 -218.476874)
			(xy 356.603629 -218.519932) (xy 356.625104 -218.56655) (xy 356.639677 -218.615764) (xy 356.647044 -218.666559)
			(xy 356.647496 -218.692222) (xy 356.646997 -218.718909) (xy 356.639042 -218.771688) (xy 356.62331 -218.822691)
			(xy 356.600152 -218.87078) (xy 356.570085 -218.91488) (xy 356.533781 -218.954007) (xy 356.492051 -218.987285)
			(xy 356.445827 -219.013972) (xy 356.396142 -219.033472) (xy 356.344105 -219.045349) (xy 356.29088 -219.049338)
			(xy 356.237655 -219.045349) (xy 356.185618 -219.033472) (xy 356.135933 -219.013972) (xy 356.089709 -218.987285)
			(xy 356.047979 -218.954007) (xy 356.011675 -218.91488) (xy 355.981608 -218.87078) (xy 355.95845 -218.822691)
			(xy 355.942718 -218.771688) (xy 355.934763 -218.718909) (xy 355.934264 -218.692222) (xy 355.934622 -218.668882)
			(xy 355.940726 -218.622603) (xy 355.952832 -218.577521) (xy 355.961442 -218.555824) (xy 355.971094 -218.532456)
			(xy 355.799136 -218.235276) (xy 355.774244 -218.231974) (xy 355.74885 -218.228215) (xy 355.699462 -218.214205)
			(xy 355.652592 -218.193262) (xy 355.609208 -218.165817) (xy 355.570205 -218.132437) (xy 355.536388 -218.093812)
			(xy 355.508457 -218.050739) (xy 355.486988 -218.004108) (xy 355.472423 -217.954881) (xy 355.465065 -217.904074)
			(xy 355.464618 -217.878406) (xy 355.23805 -217.878406) (xy 355.237551 -217.905093) (xy 355.229596 -217.957872)
			(xy 355.213864 -218.008875) (xy 355.190706 -218.056964) (xy 355.160639 -218.101064) (xy 355.124335 -218.140191)
			(xy 355.082605 -218.173469) (xy 355.036381 -218.200156) (xy 354.986696 -218.219656) (xy 354.934659 -218.231533)
			(xy 354.881434 -218.235522) (xy 354.828209 -218.231533) (xy 354.776172 -218.219656) (xy 354.726487 -218.200156)
			(xy 354.680263 -218.173469) (xy 354.638533 -218.140191) (xy 354.602229 -218.101064) (xy 354.572162 -218.056964)
			(xy 354.549004 -218.008875) (xy 354.533272 -217.957872) (xy 354.525317 -217.905093) (xy 354.524818 -217.878406)
			(xy 354.29825 -217.878406) (xy 354.297868 -217.901745) (xy 354.291774 -217.948023) (xy 354.279678 -217.993106)
			(xy 354.271072 -218.014804) (xy 354.26142 -218.038172) (xy 354.433378 -218.335352) (xy 354.45827 -218.338654)
			(xy 354.483641 -218.34255) (xy 354.533023 -218.356544) (xy 354.579889 -218.377472) (xy 354.623271 -218.404901)
			(xy 354.662275 -218.438265) (xy 354.696093 -218.476874) (xy 354.724029 -218.519932) (xy 354.745504 -218.56655)
			(xy 354.760077 -218.615764) (xy 354.767444 -218.666559) (xy 354.767896 -218.692222) (xy 354.767397 -218.718909)
			(xy 354.759442 -218.771688) (xy 354.74371 -218.822691) (xy 354.720552 -218.87078) (xy 354.690485 -218.91488)
			(xy 354.654181 -218.954007) (xy 354.612451 -218.987285) (xy 354.566227 -219.013972) (xy 354.516542 -219.033472)
			(xy 354.464505 -219.045349) (xy 354.41128 -219.049338) (xy 354.358055 -219.045349) (xy 354.306018 -219.033472)
			(xy 354.256333 -219.013972) (xy 354.210109 -218.987285) (xy 354.168379 -218.954007) (xy 354.132075 -218.91488)
			(xy 354.102008 -218.87078) (xy 354.07885 -218.822691) (xy 354.063118 -218.771688) (xy 354.055163 -218.718909)
			(xy 354.054664 -218.692222) (xy 354.055022 -218.668882) (xy 354.061126 -218.622603) (xy 354.073232 -218.577521)
			(xy 354.081842 -218.555824) (xy 354.091494 -218.532456) (xy 353.919536 -218.235276) (xy 353.894644 -218.231974)
			(xy 353.86925 -218.228215) (xy 353.819862 -218.214205) (xy 353.772992 -218.193262) (xy 353.729608 -218.165817)
			(xy 353.690605 -218.132437) (xy 353.656788 -218.093812) (xy 353.628857 -218.050739) (xy 353.607388 -218.004108)
			(xy 353.592823 -217.954881) (xy 353.585465 -217.904074) (xy 353.585018 -217.878406) (xy 353.35845 -217.878406)
			(xy 353.357951 -217.905093) (xy 353.349996 -217.957872) (xy 353.334264 -218.008875) (xy 353.311106 -218.056964)
			(xy 353.281039 -218.101064) (xy 353.244735 -218.140191) (xy 353.203005 -218.173469) (xy 353.156781 -218.200156)
			(xy 353.107096 -218.219656) (xy 353.055059 -218.231533) (xy 353.001834 -218.235522) (xy 352.948609 -218.231533)
			(xy 352.896572 -218.219656) (xy 352.846887 -218.200156) (xy 352.800663 -218.173469) (xy 352.758933 -218.140191)
			(xy 352.722629 -218.101064) (xy 352.692562 -218.056964) (xy 352.669404 -218.008875) (xy 352.653672 -217.957872)
			(xy 352.645717 -217.905093) (xy 352.645218 -217.878406) (xy 352.41865 -217.878406) (xy 352.418268 -217.901745)
			(xy 352.412174 -217.948023) (xy 352.400078 -217.993106) (xy 352.391472 -218.014804) (xy 352.38182 -218.038172)
			(xy 352.553778 -218.335352) (xy 352.57867 -218.338654) (xy 352.604041 -218.34255) (xy 352.653423 -218.356544)
			(xy 352.700289 -218.377472) (xy 352.743671 -218.404901) (xy 352.782675 -218.438265) (xy 352.816493 -218.476874)
			(xy 352.844429 -218.519932) (xy 352.865904 -218.56655) (xy 352.880477 -218.615764) (xy 352.887844 -218.666559)
			(xy 352.888296 -218.692222) (xy 352.887797 -218.718909) (xy 352.879842 -218.771688) (xy 352.86411 -218.822691)
			(xy 352.840952 -218.87078) (xy 352.810885 -218.91488) (xy 352.774581 -218.954007) (xy 352.732851 -218.987285)
			(xy 352.686627 -219.013972) (xy 352.636942 -219.033472) (xy 352.584905 -219.045349) (xy 352.53168 -219.049338)
			(xy 352.478455 -219.045349) (xy 352.426418 -219.033472) (xy 352.376733 -219.013972) (xy 352.330509 -218.987285)
			(xy 352.288779 -218.954007) (xy 352.252475 -218.91488) (xy 352.222408 -218.87078) (xy 352.19925 -218.822691)
			(xy 352.183518 -218.771688) (xy 352.175563 -218.718909) (xy 352.175064 -218.692222) (xy 352.175422 -218.668882)
			(xy 352.181526 -218.622603) (xy 352.193632 -218.577521) (xy 352.202242 -218.555824) (xy 352.211894 -218.532456)
			(xy 352.039936 -218.235276) (xy 352.015044 -218.231974) (xy 351.98965 -218.228215) (xy 351.940262 -218.214205)
			(xy 351.893392 -218.193262) (xy 351.850008 -218.165817) (xy 351.811005 -218.132437) (xy 351.777188 -218.093812)
			(xy 351.749257 -218.050739) (xy 351.727788 -218.004108) (xy 351.713223 -217.954881) (xy 351.705865 -217.904074)
			(xy 351.705418 -217.878406) (xy 351.47885 -217.878406) (xy 351.478351 -217.905093) (xy 351.470396 -217.957872)
			(xy 351.454664 -218.008875) (xy 351.431506 -218.056964) (xy 351.401439 -218.101064) (xy 351.365135 -218.140191)
			(xy 351.323405 -218.173469) (xy 351.277181 -218.200156) (xy 351.227496 -218.219656) (xy 351.175459 -218.231533)
			(xy 351.122234 -218.235522) (xy 351.069009 -218.231533) (xy 351.016972 -218.219656) (xy 350.967287 -218.200156)
			(xy 350.921063 -218.173469) (xy 350.879333 -218.140191) (xy 350.843029 -218.101064) (xy 350.812962 -218.056964)
			(xy 350.789804 -218.008875) (xy 350.774072 -217.957872) (xy 350.766117 -217.905093) (xy 350.765618 -217.878406)
			(xy 350.53905 -217.878406) (xy 350.538668 -217.901745) (xy 350.532574 -217.948023) (xy 350.520478 -217.993106)
			(xy 350.511872 -218.014804) (xy 350.50222 -218.038172) (xy 350.674178 -218.335352) (xy 350.69907 -218.338654)
			(xy 350.724441 -218.34255) (xy 350.773823 -218.356544) (xy 350.820689 -218.377472) (xy 350.864071 -218.404901)
			(xy 350.903075 -218.438265) (xy 350.936893 -218.476874) (xy 350.964829 -218.519932) (xy 350.986304 -218.56655)
			(xy 351.000877 -218.615764) (xy 351.008244 -218.666559) (xy 351.008696 -218.692222) (xy 351.008197 -218.718909)
			(xy 351.000242 -218.771688) (xy 350.98451 -218.822691) (xy 350.961352 -218.87078) (xy 350.931285 -218.91488)
			(xy 350.894981 -218.954007) (xy 350.853251 -218.987285) (xy 350.807027 -219.013972) (xy 350.757342 -219.033472)
			(xy 350.705305 -219.045349) (xy 350.65208 -219.049338) (xy 350.598855 -219.045349) (xy 350.546818 -219.033472)
			(xy 350.497133 -219.013972) (xy 350.450909 -218.987285) (xy 350.409179 -218.954007) (xy 350.372875 -218.91488)
			(xy 350.342808 -218.87078) (xy 350.31965 -218.822691) (xy 350.303918 -218.771688) (xy 350.295963 -218.718909)
			(xy 350.295464 -218.692222) (xy 350.295822 -218.668882) (xy 350.301926 -218.622603) (xy 350.314032 -218.577521)
			(xy 350.322642 -218.555824) (xy 350.332294 -218.532456) (xy 350.160336 -218.235276) (xy 350.135444 -218.231974)
			(xy 350.11005 -218.228215) (xy 350.060662 -218.214205) (xy 350.013792 -218.193262) (xy 349.970408 -218.165817)
			(xy 349.931405 -218.132437) (xy 349.897588 -218.093812) (xy 349.869657 -218.050739) (xy 349.848188 -218.004108)
			(xy 349.833623 -217.954881) (xy 349.826265 -217.904074) (xy 349.825818 -217.878406) (xy 349.59925 -217.878406)
			(xy 349.598751 -217.905093) (xy 349.590796 -217.957872) (xy 349.575064 -218.008875) (xy 349.551906 -218.056964)
			(xy 349.521839 -218.101064) (xy 349.485535 -218.140191) (xy 349.443805 -218.173469) (xy 349.397581 -218.200156)
			(xy 349.347896 -218.219656) (xy 349.295859 -218.231533) (xy 349.242634 -218.235522) (xy 349.189409 -218.231533)
			(xy 349.137372 -218.219656) (xy 349.087687 -218.200156) (xy 349.041463 -218.173469) (xy 348.999733 -218.140191)
			(xy 348.963429 -218.101064) (xy 348.933362 -218.056964) (xy 348.910204 -218.008875) (xy 348.894472 -217.957872)
			(xy 348.886517 -217.905093) (xy 348.886018 -217.878406) (xy 348.65945 -217.878406) (xy 348.659068 -217.901745)
			(xy 348.652974 -217.948023) (xy 348.640878 -217.993106) (xy 348.632272 -218.014804) (xy 348.62262 -218.038172)
			(xy 348.794578 -218.335352) (xy 348.81947 -218.338654) (xy 348.844841 -218.34255) (xy 348.894223 -218.356544)
			(xy 348.941089 -218.377472) (xy 348.984471 -218.404901) (xy 349.023475 -218.438265) (xy 349.057293 -218.476874)
			(xy 349.085229 -218.519932) (xy 349.106704 -218.56655) (xy 349.121277 -218.615764) (xy 349.128644 -218.666559)
			(xy 349.129096 -218.692222) (xy 349.128597 -218.718909) (xy 349.120642 -218.771688) (xy 349.10491 -218.822691)
			(xy 349.081752 -218.87078) (xy 349.051685 -218.91488) (xy 349.015381 -218.954007) (xy 348.973651 -218.987285)
			(xy 348.927427 -219.013972) (xy 348.877742 -219.033472) (xy 348.825705 -219.045349) (xy 348.77248 -219.049338)
			(xy 348.719255 -219.045349) (xy 348.667218 -219.033472) (xy 348.617533 -219.013972) (xy 348.571309 -218.987285)
			(xy 348.529579 -218.954007) (xy 348.493275 -218.91488) (xy 348.463208 -218.87078) (xy 348.44005 -218.822691)
			(xy 348.424318 -218.771688) (xy 348.416363 -218.718909) (xy 348.415864 -218.692222) (xy 348.416222 -218.668882)
			(xy 348.422326 -218.622603) (xy 348.434432 -218.577521) (xy 348.443042 -218.555824) (xy 348.452694 -218.532456)
			(xy 348.280736 -218.235276) (xy 348.255844 -218.231974) (xy 348.23045 -218.228215) (xy 348.181062 -218.214205)
			(xy 348.134192 -218.193262) (xy 348.090808 -218.165817) (xy 348.051805 -218.132437) (xy 348.017988 -218.093812)
			(xy 347.990057 -218.050739) (xy 347.968588 -218.004108) (xy 347.954023 -217.954881) (xy 347.946665 -217.904074)
			(xy 347.946218 -217.878406) (xy 347.71965 -217.878406) (xy 347.719151 -217.905093) (xy 347.711196 -217.957872)
			(xy 347.695464 -218.008875) (xy 347.672306 -218.056964) (xy 347.642239 -218.101064) (xy 347.605935 -218.140191)
			(xy 347.564205 -218.173469) (xy 347.517981 -218.200156) (xy 347.468296 -218.219656) (xy 347.416259 -218.231533)
			(xy 347.363034 -218.235522) (xy 347.309809 -218.231533) (xy 347.257772 -218.219656) (xy 347.208087 -218.200156)
			(xy 347.161863 -218.173469) (xy 347.120133 -218.140191) (xy 347.083829 -218.101064) (xy 347.053762 -218.056964)
			(xy 347.030604 -218.008875) (xy 347.014872 -217.957872) (xy 347.006917 -217.905093) (xy 347.006418 -217.878406)
			(xy 346.77985 -217.878406) (xy 346.779468 -217.901745) (xy 346.773374 -217.948023) (xy 346.761278 -217.993106)
			(xy 346.752672 -218.014804) (xy 346.74302 -218.038172) (xy 346.914978 -218.335352) (xy 346.93987 -218.338654)
			(xy 346.965241 -218.34255) (xy 347.014623 -218.356544) (xy 347.061489 -218.377472) (xy 347.104871 -218.404901)
			(xy 347.143875 -218.438265) (xy 347.177693 -218.476874) (xy 347.205629 -218.519932) (xy 347.227104 -218.56655)
			(xy 347.241677 -218.615764) (xy 347.249044 -218.666559) (xy 347.249496 -218.692222) (xy 347.248997 -218.718909)
			(xy 347.241042 -218.771688) (xy 347.22531 -218.822691) (xy 347.202152 -218.87078) (xy 347.172085 -218.91488)
			(xy 347.135781 -218.954007) (xy 347.094051 -218.987285) (xy 347.047827 -219.013972) (xy 346.998142 -219.033472)
			(xy 346.946105 -219.045349) (xy 346.89288 -219.049338) (xy 346.839655 -219.045349) (xy 346.787618 -219.033472)
			(xy 346.737933 -219.013972) (xy 346.691709 -218.987285) (xy 346.649979 -218.954007) (xy 346.613675 -218.91488)
			(xy 346.583608 -218.87078) (xy 346.56045 -218.822691) (xy 346.544718 -218.771688) (xy 346.536763 -218.718909)
			(xy 346.536264 -218.692222) (xy 346.536622 -218.668882) (xy 346.542726 -218.622603) (xy 346.554832 -218.577521)
			(xy 346.563442 -218.555824) (xy 346.573094 -218.532456) (xy 346.401136 -218.235276) (xy 346.376244 -218.231974)
			(xy 346.35085 -218.228215) (xy 346.301462 -218.214205) (xy 346.254592 -218.193262) (xy 346.211208 -218.165817)
			(xy 346.172205 -218.132437) (xy 346.138388 -218.093812) (xy 346.110457 -218.050739) (xy 346.088988 -218.004108)
			(xy 346.074423 -217.954881) (xy 346.067065 -217.904074) (xy 346.066618 -217.878406) (xy 345.84005 -217.878406)
			(xy 345.839551 -217.905093) (xy 345.831596 -217.957872) (xy 345.815864 -218.008875) (xy 345.792706 -218.056964)
			(xy 345.762639 -218.101064) (xy 345.726335 -218.140191) (xy 345.684605 -218.173469) (xy 345.638381 -218.200156)
			(xy 345.588696 -218.219656) (xy 345.536659 -218.231533) (xy 345.483434 -218.235522) (xy 345.430209 -218.231533)
			(xy 345.378172 -218.219656) (xy 345.328487 -218.200156) (xy 345.282263 -218.173469) (xy 345.240533 -218.140191)
			(xy 345.204229 -218.101064) (xy 345.174162 -218.056964) (xy 345.151004 -218.008875) (xy 345.135272 -217.957872)
			(xy 345.127317 -217.905093) (xy 345.126818 -217.878406) (xy 344.90025 -217.878406) (xy 344.899868 -217.901745)
			(xy 344.893774 -217.948023) (xy 344.881678 -217.993106) (xy 344.873072 -218.014804) (xy 344.86342 -218.038172)
			(xy 345.035378 -218.335352) (xy 345.06027 -218.338654) (xy 345.085641 -218.34255) (xy 345.135023 -218.356544)
			(xy 345.181889 -218.377472) (xy 345.225271 -218.404901) (xy 345.264275 -218.438265) (xy 345.298093 -218.476874)
			(xy 345.326029 -218.519932) (xy 345.347504 -218.56655) (xy 345.362077 -218.615764) (xy 345.369444 -218.666559)
			(xy 345.369896 -218.692222) (xy 345.369397 -218.718909) (xy 345.361442 -218.771688) (xy 345.34571 -218.822691)
			(xy 345.322552 -218.87078) (xy 345.292485 -218.91488) (xy 345.256181 -218.954007) (xy 345.214451 -218.987285)
			(xy 345.168227 -219.013972) (xy 345.118542 -219.033472) (xy 345.066505 -219.045349) (xy 345.01328 -219.049338)
			(xy 344.960055 -219.045349) (xy 344.908018 -219.033472) (xy 344.858333 -219.013972) (xy 344.812109 -218.987285)
			(xy 344.770379 -218.954007) (xy 344.734075 -218.91488) (xy 344.704008 -218.87078) (xy 344.68085 -218.822691)
			(xy 344.665118 -218.771688) (xy 344.657163 -218.718909) (xy 344.656664 -218.692222) (xy 344.657022 -218.668882)
			(xy 344.663126 -218.622603) (xy 344.675232 -218.577521) (xy 344.683842 -218.555824) (xy 344.693494 -218.532456)
			(xy 344.521536 -218.235276) (xy 344.496644 -218.231974) (xy 344.47125 -218.228215) (xy 344.421862 -218.214205)
			(xy 344.374992 -218.193262) (xy 344.331608 -218.165817) (xy 344.292605 -218.132437) (xy 344.258788 -218.093812)
			(xy 344.230857 -218.050739) (xy 344.209388 -218.004108) (xy 344.194823 -217.954881) (xy 344.187465 -217.904074)
			(xy 344.187018 -217.878406) (xy 343.96045 -217.878406) (xy 343.959951 -217.905093) (xy 343.951996 -217.957872)
			(xy 343.936264 -218.008875) (xy 343.913106 -218.056964) (xy 343.883039 -218.101064) (xy 343.846735 -218.140191)
			(xy 343.805005 -218.173469) (xy 343.758781 -218.200156) (xy 343.709096 -218.219656) (xy 343.657059 -218.231533)
			(xy 343.603834 -218.235522) (xy 343.550609 -218.231533) (xy 343.498572 -218.219656) (xy 343.448887 -218.200156)
			(xy 343.402663 -218.173469) (xy 343.360933 -218.140191) (xy 343.324629 -218.101064) (xy 343.294562 -218.056964)
			(xy 343.271404 -218.008875) (xy 343.255672 -217.957872) (xy 343.247717 -217.905093) (xy 343.247218 -217.878406)
			(xy 343.02065 -217.878406) (xy 343.020268 -217.901745) (xy 343.014174 -217.948023) (xy 343.002078 -217.993106)
			(xy 342.993472 -218.014804) (xy 342.98382 -218.038172) (xy 343.155778 -218.335352) (xy 343.18067 -218.338654)
			(xy 343.206041 -218.34255) (xy 343.255423 -218.356544) (xy 343.302289 -218.377472) (xy 343.345671 -218.404901)
			(xy 343.384675 -218.438265) (xy 343.418493 -218.476874) (xy 343.446429 -218.519932) (xy 343.467904 -218.56655)
			(xy 343.482477 -218.615764) (xy 343.489844 -218.666559) (xy 343.490296 -218.692222) (xy 343.489797 -218.718909)
			(xy 343.481842 -218.771688) (xy 343.46611 -218.822691) (xy 343.442952 -218.87078) (xy 343.412885 -218.91488)
			(xy 343.376581 -218.954007) (xy 343.334851 -218.987285) (xy 343.288627 -219.013972) (xy 343.238942 -219.033472)
			(xy 343.186905 -219.045349) (xy 343.13368 -219.049338) (xy 343.080455 -219.045349) (xy 343.028418 -219.033472)
			(xy 342.978733 -219.013972) (xy 342.932509 -218.987285) (xy 342.890779 -218.954007) (xy 342.854475 -218.91488)
			(xy 342.824408 -218.87078) (xy 342.80125 -218.822691) (xy 342.785518 -218.771688) (xy 342.777563 -218.718909)
			(xy 342.777064 -218.692222) (xy 342.777422 -218.668882) (xy 342.783526 -218.622603) (xy 342.795632 -218.577521)
			(xy 342.804242 -218.555824) (xy 342.813894 -218.532456) (xy 342.641936 -218.235276) (xy 342.617044 -218.231974)
			(xy 342.59165 -218.228215) (xy 342.542262 -218.214205) (xy 342.495392 -218.193262) (xy 342.452008 -218.165817)
			(xy 342.413005 -218.132437) (xy 342.379188 -218.093812) (xy 342.351257 -218.050739) (xy 342.329788 -218.004108)
			(xy 342.315223 -217.954881) (xy 342.307865 -217.904074) (xy 342.307418 -217.878406) (xy 342.08085 -217.878406)
			(xy 342.080351 -217.905093) (xy 342.072396 -217.957872) (xy 342.056664 -218.008875) (xy 342.033506 -218.056964)
			(xy 342.003439 -218.101064) (xy 341.967135 -218.140191) (xy 341.925405 -218.173469) (xy 341.879181 -218.200156)
			(xy 341.829496 -218.219656) (xy 341.777459 -218.231533) (xy 341.724234 -218.235522) (xy 341.671009 -218.231533)
			(xy 341.618972 -218.219656) (xy 341.569287 -218.200156) (xy 341.523063 -218.173469) (xy 341.481333 -218.140191)
			(xy 341.445029 -218.101064) (xy 341.414962 -218.056964) (xy 341.391804 -218.008875) (xy 341.376072 -217.957872)
			(xy 341.368117 -217.905093) (xy 341.367618 -217.878406) (xy 341.14105 -217.878406) (xy 341.140668 -217.901745)
			(xy 341.134574 -217.948023) (xy 341.122478 -217.993106) (xy 341.113872 -218.014804) (xy 341.10422 -218.038172)
			(xy 341.276178 -218.335352) (xy 341.30107 -218.338654) (xy 341.326441 -218.34255) (xy 341.375823 -218.356544)
			(xy 341.422689 -218.377472) (xy 341.466071 -218.404901) (xy 341.505075 -218.438265) (xy 341.538893 -218.476874)
			(xy 341.566829 -218.519932) (xy 341.588304 -218.56655) (xy 341.602877 -218.615764) (xy 341.610244 -218.666559)
			(xy 341.610696 -218.692222) (xy 341.610197 -218.718909) (xy 341.602242 -218.771688) (xy 341.58651 -218.822691)
			(xy 341.563352 -218.87078) (xy 341.533285 -218.91488) (xy 341.496981 -218.954007) (xy 341.455251 -218.987285)
			(xy 341.409027 -219.013972) (xy 341.359342 -219.033472) (xy 341.307305 -219.045349) (xy 341.25408 -219.049338)
			(xy 341.200855 -219.045349) (xy 341.148818 -219.033472) (xy 341.099133 -219.013972) (xy 341.052909 -218.987285)
			(xy 341.011179 -218.954007) (xy 340.974875 -218.91488) (xy 340.944808 -218.87078) (xy 340.92165 -218.822691)
			(xy 340.905918 -218.771688) (xy 340.897963 -218.718909) (xy 340.897464 -218.692222) (xy 340.897822 -218.668882)
			(xy 340.903926 -218.622603) (xy 340.916032 -218.577521) (xy 340.924642 -218.555824) (xy 340.934294 -218.532456)
			(xy 340.762336 -218.235276) (xy 340.737444 -218.231974) (xy 340.71205 -218.228215) (xy 340.662662 -218.214205)
			(xy 340.615792 -218.193262) (xy 340.572408 -218.165817) (xy 340.533405 -218.132437) (xy 340.499588 -218.093812)
			(xy 340.471657 -218.050739) (xy 340.450188 -218.004108) (xy 340.435623 -217.954881) (xy 340.428265 -217.904074)
			(xy 340.427818 -217.878406) (xy 340.20125 -217.878406) (xy 340.200751 -217.905093) (xy 340.192796 -217.957872)
			(xy 340.177064 -218.008875) (xy 340.153906 -218.056964) (xy 340.123839 -218.101064) (xy 340.087535 -218.140191)
			(xy 340.045805 -218.173469) (xy 339.999581 -218.200156) (xy 339.949896 -218.219656) (xy 339.897859 -218.231533)
			(xy 339.844634 -218.235522) (xy 339.791409 -218.231533) (xy 339.739372 -218.219656) (xy 339.689687 -218.200156)
			(xy 339.643463 -218.173469) (xy 339.601733 -218.140191) (xy 339.565429 -218.101064) (xy 339.535362 -218.056964)
			(xy 339.512204 -218.008875) (xy 339.496472 -217.957872) (xy 339.488517 -217.905093) (xy 339.488018 -217.878406)
			(xy 339.26145 -217.878406) (xy 339.261068 -217.901745) (xy 339.254974 -217.948023) (xy 339.242878 -217.993106)
			(xy 339.234272 -218.014804) (xy 339.22462 -218.038172) (xy 339.396578 -218.335352) (xy 339.42147 -218.338654)
			(xy 339.446841 -218.34255) (xy 339.496223 -218.356544) (xy 339.543089 -218.377472) (xy 339.586471 -218.404901)
			(xy 339.625475 -218.438265) (xy 339.659293 -218.476874) (xy 339.687229 -218.519932) (xy 339.708704 -218.56655)
			(xy 339.723277 -218.615764) (xy 339.730644 -218.666559) (xy 339.731096 -218.692222) (xy 339.730597 -218.718909)
			(xy 339.722642 -218.771688) (xy 339.70691 -218.822691) (xy 339.683752 -218.87078) (xy 339.653685 -218.91488)
			(xy 339.617381 -218.954007) (xy 339.575651 -218.987285) (xy 339.529427 -219.013972) (xy 339.479742 -219.033472)
			(xy 339.427705 -219.045349) (xy 339.37448 -219.049338) (xy 339.321255 -219.045349) (xy 339.269218 -219.033472)
			(xy 339.219533 -219.013972) (xy 339.173309 -218.987285) (xy 339.131579 -218.954007) (xy 339.095275 -218.91488)
			(xy 339.065208 -218.87078) (xy 339.04205 -218.822691) (xy 339.026318 -218.771688) (xy 339.018363 -218.718909)
			(xy 339.017864 -218.692222) (xy 339.018222 -218.668882) (xy 339.024326 -218.622603) (xy 339.036432 -218.577521)
			(xy 339.045042 -218.555824) (xy 339.054694 -218.532456) (xy 338.882736 -218.235276) (xy 338.857844 -218.231974)
			(xy 338.83245 -218.228215) (xy 338.783062 -218.214205) (xy 338.736192 -218.193262) (xy 338.692808 -218.165817)
			(xy 338.653805 -218.132437) (xy 338.619988 -218.093812) (xy 338.592057 -218.050739) (xy 338.570588 -218.004108)
			(xy 338.556023 -217.954881) (xy 338.548665 -217.904074) (xy 338.548218 -217.878406) (xy 338.32165 -217.878406)
			(xy 338.321151 -217.905093) (xy 338.313196 -217.957872) (xy 338.297464 -218.008875) (xy 338.274306 -218.056964)
			(xy 338.244239 -218.101064) (xy 338.207935 -218.140191) (xy 338.166205 -218.173469) (xy 338.119981 -218.200156)
			(xy 338.070296 -218.219656) (xy 338.018259 -218.231533) (xy 337.965034 -218.235522) (xy 337.911809 -218.231533)
			(xy 337.859772 -218.219656) (xy 337.810087 -218.200156) (xy 337.763863 -218.173469) (xy 337.722133 -218.140191)
			(xy 337.685829 -218.101064) (xy 337.655762 -218.056964) (xy 337.632604 -218.008875) (xy 337.616872 -217.957872)
			(xy 337.608917 -217.905093) (xy 337.608418 -217.878406) (xy 337.38185 -217.878406) (xy 337.381468 -217.901745)
			(xy 337.375374 -217.948023) (xy 337.363278 -217.993106) (xy 337.354672 -218.014804) (xy 337.34502 -218.038172)
			(xy 337.516978 -218.335352) (xy 337.54187 -218.338654) (xy 337.567241 -218.34255) (xy 337.616623 -218.356544)
			(xy 337.663489 -218.377472) (xy 337.706871 -218.404901) (xy 337.745875 -218.438265) (xy 337.779693 -218.476874)
			(xy 337.807629 -218.519932) (xy 337.829104 -218.56655) (xy 337.843677 -218.615764) (xy 337.851044 -218.666559)
			(xy 337.851496 -218.692222) (xy 337.850997 -218.718909) (xy 337.843042 -218.771688) (xy 337.82731 -218.822691)
			(xy 337.804152 -218.87078) (xy 337.774085 -218.91488) (xy 337.737781 -218.954007) (xy 337.696051 -218.987285)
			(xy 337.649827 -219.013972) (xy 337.600142 -219.033472) (xy 337.548105 -219.045349) (xy 337.49488 -219.049338)
			(xy 337.441655 -219.045349) (xy 337.389618 -219.033472) (xy 337.339933 -219.013972) (xy 337.293709 -218.987285)
			(xy 337.251979 -218.954007) (xy 337.215675 -218.91488) (xy 337.185608 -218.87078) (xy 337.16245 -218.822691)
			(xy 337.146718 -218.771688) (xy 337.138763 -218.718909) (xy 337.138264 -218.692222) (xy 337.138622 -218.668882)
			(xy 337.144726 -218.622603) (xy 337.156832 -218.577521) (xy 337.165442 -218.555824) (xy 337.175094 -218.532456)
			(xy 337.003136 -218.235276) (xy 336.978244 -218.231974) (xy 336.95285 -218.228215) (xy 336.903462 -218.214205)
			(xy 336.856592 -218.193262) (xy 336.813208 -218.165817) (xy 336.774205 -218.132437) (xy 336.740388 -218.093812)
			(xy 336.712457 -218.050739) (xy 336.690988 -218.004108) (xy 336.676423 -217.954881) (xy 336.669065 -217.904074)
			(xy 336.668618 -217.878406) (xy 134.552182 -217.878406) (xy 134.551683 -217.905093) (xy 134.543728 -217.957872)
			(xy 134.527996 -218.008875) (xy 134.504838 -218.056964) (xy 134.474771 -218.101064) (xy 134.438467 -218.140191)
			(xy 134.396737 -218.173469) (xy 134.350513 -218.200156) (xy 134.300828 -218.219656) (xy 134.248791 -218.231533)
			(xy 134.195566 -218.235522) (xy 134.142341 -218.231533) (xy 134.090304 -218.219656) (xy 134.040619 -218.200156)
			(xy 133.994395 -218.173469) (xy 133.952665 -218.140191) (xy 133.916361 -218.101064) (xy 133.886294 -218.056964)
			(xy 133.863136 -218.008875) (xy 133.847404 -217.957872) (xy 133.839449 -217.905093) (xy 133.83895 -217.878406)
			(xy 133.839304 -217.855066) (xy 133.84541 -217.808787) (xy 133.857517 -217.763705) (xy 133.866128 -217.742008)
			(xy 133.87578 -217.71864) (xy 133.704076 -217.421206) (xy 133.679184 -217.417904) (xy 133.653755 -217.414138)
			(xy 133.604265 -217.400236) (xy 133.557284 -217.37937) (xy 133.513788 -217.351973) (xy 133.474678 -217.318613)
			(xy 133.440765 -217.279981) (xy 133.412752 -217.236879) (xy 133.391219 -217.1902) (xy 133.376615 -217.140913)
			(xy 133.369241 -217.090039) (xy 133.368796 -217.064336) (xy 132.202428 -217.064336) (xy 132.202428 -217.064844)
			(xy 132.202021 -217.088045) (xy 132.195964 -217.134052) (xy 132.183998 -217.178886) (xy 132.175504 -217.20048)
			(xy 132.165852 -217.223594) (xy 132.338064 -217.521536) (xy 132.362956 -217.524838) (xy 132.388335 -217.528682)
			(xy 132.437716 -217.542687) (xy 132.484581 -217.563624) (xy 132.527962 -217.59106) (xy 132.566963 -217.62443)
			(xy 132.600779 -217.663045) (xy 132.628713 -217.706107) (xy 132.650188 -217.752728) (xy 132.66476 -217.801945)
			(xy 132.672129 -217.852742) (xy 132.672582 -217.878406) (xy 132.672083 -217.905093) (xy 132.664128 -217.957872)
			(xy 132.648396 -218.008875) (xy 132.625238 -218.056964) (xy 132.595171 -218.101064) (xy 132.558867 -218.140191)
			(xy 132.517137 -218.173469) (xy 132.470913 -218.200156) (xy 132.421228 -218.219656) (xy 132.369191 -218.231533)
			(xy 132.315966 -218.235522) (xy 132.262741 -218.231533) (xy 132.210704 -218.219656) (xy 132.161019 -218.200156)
			(xy 132.114795 -218.173469) (xy 132.073065 -218.140191) (xy 132.036761 -218.101064) (xy 132.006694 -218.056964)
			(xy 131.983536 -218.008875) (xy 131.967804 -217.957872) (xy 131.959849 -217.905093) (xy 131.95935 -217.878406)
			(xy 131.959704 -217.855066) (xy 131.96581 -217.808787) (xy 131.977917 -217.763705) (xy 131.986528 -217.742008)
			(xy 131.99618 -217.71864) (xy 131.824476 -217.421206) (xy 131.799584 -217.417904) (xy 131.774155 -217.414138)
			(xy 131.724665 -217.400236) (xy 131.677684 -217.37937) (xy 131.634188 -217.351973) (xy 131.595078 -217.318613)
			(xy 131.561165 -217.279981) (xy 131.533152 -217.236879) (xy 131.511619 -217.1902) (xy 131.497015 -217.140913)
			(xy 131.489641 -217.090039) (xy 131.489196 -217.064336) (xy 130.322828 -217.064336) (xy 130.322828 -217.064844)
			(xy 130.322421 -217.088045) (xy 130.316364 -217.134052) (xy 130.304398 -217.178886) (xy 130.295904 -217.20048)
			(xy 130.286252 -217.223594) (xy 130.458464 -217.521536) (xy 130.483356 -217.524838) (xy 130.508735 -217.528682)
			(xy 130.558116 -217.542687) (xy 130.604981 -217.563624) (xy 130.648362 -217.59106) (xy 130.687363 -217.62443)
			(xy 130.721179 -217.663045) (xy 130.749113 -217.706107) (xy 130.770588 -217.752728) (xy 130.78516 -217.801945)
			(xy 130.792529 -217.852742) (xy 130.792982 -217.878406) (xy 130.792483 -217.905093) (xy 130.784528 -217.957872)
			(xy 130.768796 -218.008875) (xy 130.745638 -218.056964) (xy 130.715571 -218.101064) (xy 130.679267 -218.140191)
			(xy 130.637537 -218.173469) (xy 130.591313 -218.200156) (xy 130.541628 -218.219656) (xy 130.489591 -218.231533)
			(xy 130.436366 -218.235522) (xy 130.383141 -218.231533) (xy 130.331104 -218.219656) (xy 130.281419 -218.200156)
			(xy 130.235195 -218.173469) (xy 130.193465 -218.140191) (xy 130.157161 -218.101064) (xy 130.127094 -218.056964)
			(xy 130.103936 -218.008875) (xy 130.088204 -217.957872) (xy 130.080249 -217.905093) (xy 130.07975 -217.878406)
			(xy 130.080104 -217.855066) (xy 130.08621 -217.808787) (xy 130.098317 -217.763705) (xy 130.106928 -217.742008)
			(xy 130.11658 -217.71864) (xy 129.944876 -217.421206) (xy 129.919984 -217.417904) (xy 129.894555 -217.414138)
			(xy 129.845065 -217.400236) (xy 129.798084 -217.37937) (xy 129.754588 -217.351973) (xy 129.715478 -217.318613)
			(xy 129.681565 -217.279981) (xy 129.653552 -217.236879) (xy 129.632019 -217.1902) (xy 129.617415 -217.140913)
			(xy 129.610041 -217.090039) (xy 129.609596 -217.064336) (xy 128.443228 -217.064336) (xy 128.443228 -217.064844)
			(xy 128.442821 -217.088045) (xy 128.436764 -217.134052) (xy 128.424798 -217.178886) (xy 128.416304 -217.20048)
			(xy 128.406652 -217.223594) (xy 128.578864 -217.521536) (xy 128.603756 -217.524838) (xy 128.629135 -217.528682)
			(xy 128.678516 -217.542687) (xy 128.725381 -217.563624) (xy 128.768762 -217.59106) (xy 128.807763 -217.62443)
			(xy 128.841579 -217.663045) (xy 128.869513 -217.706107) (xy 128.890988 -217.752728) (xy 128.90556 -217.801945)
			(xy 128.912929 -217.852742) (xy 128.913382 -217.878406) (xy 128.912883 -217.905093) (xy 128.904928 -217.957872)
			(xy 128.889196 -218.008875) (xy 128.866038 -218.056964) (xy 128.835971 -218.101064) (xy 128.799667 -218.140191)
			(xy 128.757937 -218.173469) (xy 128.711713 -218.200156) (xy 128.662028 -218.219656) (xy 128.609991 -218.231533)
			(xy 128.556766 -218.235522) (xy 128.503541 -218.231533) (xy 128.451504 -218.219656) (xy 128.401819 -218.200156)
			(xy 128.355595 -218.173469) (xy 128.313865 -218.140191) (xy 128.277561 -218.101064) (xy 128.247494 -218.056964)
			(xy 128.224336 -218.008875) (xy 128.208604 -217.957872) (xy 128.200649 -217.905093) (xy 128.20015 -217.878406)
			(xy 128.200504 -217.855066) (xy 128.20661 -217.808787) (xy 128.218717 -217.763705) (xy 128.227328 -217.742008)
			(xy 128.23698 -217.71864) (xy 128.065276 -217.421206) (xy 128.040384 -217.417904) (xy 128.014955 -217.414138)
			(xy 127.965465 -217.400236) (xy 127.918484 -217.37937) (xy 127.874988 -217.351973) (xy 127.835878 -217.318613)
			(xy 127.801965 -217.279981) (xy 127.773952 -217.236879) (xy 127.752419 -217.1902) (xy 127.737815 -217.140913)
			(xy 127.730441 -217.090039) (xy 127.729996 -217.064336) (xy 126.563628 -217.064336) (xy 126.563628 -217.064844)
			(xy 126.563221 -217.088045) (xy 126.557164 -217.134052) (xy 126.545198 -217.178886) (xy 126.536704 -217.20048)
			(xy 126.527052 -217.223594) (xy 126.699264 -217.521536) (xy 126.724156 -217.524838) (xy 126.749535 -217.528682)
			(xy 126.798916 -217.542687) (xy 126.845781 -217.563624) (xy 126.889162 -217.59106) (xy 126.928163 -217.62443)
			(xy 126.961979 -217.663045) (xy 126.989913 -217.706107) (xy 127.011388 -217.752728) (xy 127.02596 -217.801945)
			(xy 127.033329 -217.852742) (xy 127.033782 -217.878406) (xy 127.033283 -217.905093) (xy 127.025328 -217.957872)
			(xy 127.009596 -218.008875) (xy 126.986438 -218.056964) (xy 126.956371 -218.101064) (xy 126.920067 -218.140191)
			(xy 126.878337 -218.173469) (xy 126.832113 -218.200156) (xy 126.782428 -218.219656) (xy 126.730391 -218.231533)
			(xy 126.677166 -218.235522) (xy 126.623941 -218.231533) (xy 126.571904 -218.219656) (xy 126.522219 -218.200156)
			(xy 126.475995 -218.173469) (xy 126.434265 -218.140191) (xy 126.397961 -218.101064) (xy 126.367894 -218.056964)
			(xy 126.344736 -218.008875) (xy 126.329004 -217.957872) (xy 126.321049 -217.905093) (xy 126.32055 -217.878406)
			(xy 126.320904 -217.855066) (xy 126.32701 -217.808787) (xy 126.339117 -217.763705) (xy 126.347728 -217.742008)
			(xy 126.35738 -217.71864) (xy 126.185676 -217.421206) (xy 126.160784 -217.417904) (xy 126.135355 -217.414138)
			(xy 126.085865 -217.400236) (xy 126.038884 -217.37937) (xy 125.995388 -217.351973) (xy 125.956278 -217.318613)
			(xy 125.922365 -217.279981) (xy 125.894352 -217.236879) (xy 125.872819 -217.1902) (xy 125.858215 -217.140913)
			(xy 125.850841 -217.090039) (xy 125.850396 -217.064336) (xy 124.684028 -217.064336) (xy 124.684028 -217.064844)
			(xy 124.683621 -217.088045) (xy 124.677564 -217.134052) (xy 124.665598 -217.178886) (xy 124.657104 -217.20048)
			(xy 124.647452 -217.223594) (xy 124.819664 -217.521536) (xy 124.844556 -217.524838) (xy 124.869935 -217.528682)
			(xy 124.919316 -217.542687) (xy 124.966181 -217.563624) (xy 125.009562 -217.59106) (xy 125.048563 -217.62443)
			(xy 125.082379 -217.663045) (xy 125.110313 -217.706107) (xy 125.131788 -217.752728) (xy 125.14636 -217.801945)
			(xy 125.153729 -217.852742) (xy 125.154182 -217.878406) (xy 125.153683 -217.905093) (xy 125.145728 -217.957872)
			(xy 125.129996 -218.008875) (xy 125.106838 -218.056964) (xy 125.076771 -218.101064) (xy 125.040467 -218.140191)
			(xy 124.998737 -218.173469) (xy 124.952513 -218.200156) (xy 124.902828 -218.219656) (xy 124.850791 -218.231533)
			(xy 124.797566 -218.235522) (xy 124.744341 -218.231533) (xy 124.692304 -218.219656) (xy 124.642619 -218.200156)
			(xy 124.596395 -218.173469) (xy 124.554665 -218.140191) (xy 124.518361 -218.101064) (xy 124.488294 -218.056964)
			(xy 124.465136 -218.008875) (xy 124.449404 -217.957872) (xy 124.441449 -217.905093) (xy 124.44095 -217.878406)
			(xy 124.441304 -217.855066) (xy 124.44741 -217.808787) (xy 124.459517 -217.763705) (xy 124.468128 -217.742008)
			(xy 124.47778 -217.71864) (xy 124.306076 -217.421206) (xy 124.281184 -217.417904) (xy 124.255755 -217.414138)
			(xy 124.206265 -217.400236) (xy 124.159284 -217.37937) (xy 124.115788 -217.351973) (xy 124.076678 -217.318613)
			(xy 124.042765 -217.279981) (xy 124.014752 -217.236879) (xy 123.993219 -217.1902) (xy 123.978615 -217.140913)
			(xy 123.971241 -217.090039) (xy 123.970796 -217.064336) (xy 122.804428 -217.064336) (xy 122.804428 -217.064844)
			(xy 122.804021 -217.088045) (xy 122.797964 -217.134052) (xy 122.785998 -217.178886) (xy 122.777504 -217.20048)
			(xy 122.767852 -217.223594) (xy 122.940064 -217.521536) (xy 122.964956 -217.524838) (xy 122.990335 -217.528682)
			(xy 123.039716 -217.542687) (xy 123.086581 -217.563624) (xy 123.129962 -217.59106) (xy 123.168963 -217.62443)
			(xy 123.202779 -217.663045) (xy 123.230713 -217.706107) (xy 123.252188 -217.752728) (xy 123.26676 -217.801945)
			(xy 123.274129 -217.852742) (xy 123.274582 -217.878406) (xy 123.274083 -217.905093) (xy 123.266128 -217.957872)
			(xy 123.250396 -218.008875) (xy 123.227238 -218.056964) (xy 123.197171 -218.101064) (xy 123.160867 -218.140191)
			(xy 123.119137 -218.173469) (xy 123.072913 -218.200156) (xy 123.023228 -218.219656) (xy 122.971191 -218.231533)
			(xy 122.917966 -218.235522) (xy 122.864741 -218.231533) (xy 122.812704 -218.219656) (xy 122.763019 -218.200156)
			(xy 122.716795 -218.173469) (xy 122.675065 -218.140191) (xy 122.638761 -218.101064) (xy 122.608694 -218.056964)
			(xy 122.585536 -218.008875) (xy 122.569804 -217.957872) (xy 122.561849 -217.905093) (xy 122.56135 -217.878406)
			(xy 122.561704 -217.855066) (xy 122.56781 -217.808787) (xy 122.579917 -217.763705) (xy 122.588528 -217.742008)
			(xy 122.59818 -217.71864) (xy 122.426476 -217.421206) (xy 122.401584 -217.417904) (xy 122.376155 -217.414138)
			(xy 122.326665 -217.400236) (xy 122.279684 -217.37937) (xy 122.236188 -217.351973) (xy 122.197078 -217.318613)
			(xy 122.163165 -217.279981) (xy 122.135152 -217.236879) (xy 122.113619 -217.1902) (xy 122.099015 -217.140913)
			(xy 122.091641 -217.090039) (xy 122.091196 -217.064336) (xy 120.924828 -217.064336) (xy 120.924828 -217.064844)
			(xy 120.924421 -217.088045) (xy 120.918364 -217.134052) (xy 120.906398 -217.178886) (xy 120.897904 -217.20048)
			(xy 120.888252 -217.223594) (xy 121.060464 -217.521536) (xy 121.085356 -217.524838) (xy 121.110735 -217.528682)
			(xy 121.160116 -217.542687) (xy 121.206981 -217.563624) (xy 121.250362 -217.59106) (xy 121.289363 -217.62443)
			(xy 121.323179 -217.663045) (xy 121.351113 -217.706107) (xy 121.372588 -217.752728) (xy 121.38716 -217.801945)
			(xy 121.394529 -217.852742) (xy 121.394982 -217.878406) (xy 121.394483 -217.905093) (xy 121.386528 -217.957872)
			(xy 121.370796 -218.008875) (xy 121.347638 -218.056964) (xy 121.317571 -218.101064) (xy 121.281267 -218.140191)
			(xy 121.239537 -218.173469) (xy 121.193313 -218.200156) (xy 121.143628 -218.219656) (xy 121.091591 -218.231533)
			(xy 121.038366 -218.235522) (xy 120.985141 -218.231533) (xy 120.933104 -218.219656) (xy 120.883419 -218.200156)
			(xy 120.837195 -218.173469) (xy 120.795465 -218.140191) (xy 120.759161 -218.101064) (xy 120.729094 -218.056964)
			(xy 120.705936 -218.008875) (xy 120.690204 -217.957872) (xy 120.682249 -217.905093) (xy 120.68175 -217.878406)
			(xy 120.682104 -217.855066) (xy 120.68821 -217.808787) (xy 120.700317 -217.763705) (xy 120.708928 -217.742008)
			(xy 120.71858 -217.71864) (xy 120.546876 -217.421206) (xy 120.521984 -217.417904) (xy 120.496555 -217.414138)
			(xy 120.447065 -217.400236) (xy 120.400084 -217.37937) (xy 120.356588 -217.351973) (xy 120.317478 -217.318613)
			(xy 120.283565 -217.279981) (xy 120.255552 -217.236879) (xy 120.234019 -217.1902) (xy 120.219415 -217.140913)
			(xy 120.212041 -217.090039) (xy 120.211596 -217.064336) (xy 119.045228 -217.064336) (xy 119.045228 -217.064844)
			(xy 119.044821 -217.088045) (xy 119.038764 -217.134052) (xy 119.026798 -217.178886) (xy 119.018304 -217.20048)
			(xy 119.008652 -217.223594) (xy 119.180864 -217.521536) (xy 119.205756 -217.524838) (xy 119.231135 -217.528682)
			(xy 119.280516 -217.542687) (xy 119.327381 -217.563624) (xy 119.370762 -217.59106) (xy 119.409763 -217.62443)
			(xy 119.443579 -217.663045) (xy 119.471513 -217.706107) (xy 119.492988 -217.752728) (xy 119.50756 -217.801945)
			(xy 119.514929 -217.852742) (xy 119.515382 -217.878406) (xy 119.514883 -217.905093) (xy 119.506928 -217.957872)
			(xy 119.491196 -218.008875) (xy 119.468038 -218.056964) (xy 119.437971 -218.101064) (xy 119.401667 -218.140191)
			(xy 119.359937 -218.173469) (xy 119.313713 -218.200156) (xy 119.264028 -218.219656) (xy 119.211991 -218.231533)
			(xy 119.158766 -218.235522) (xy 119.105541 -218.231533) (xy 119.053504 -218.219656) (xy 119.003819 -218.200156)
			(xy 118.957595 -218.173469) (xy 118.915865 -218.140191) (xy 118.879561 -218.101064) (xy 118.849494 -218.056964)
			(xy 118.826336 -218.008875) (xy 118.810604 -217.957872) (xy 118.802649 -217.905093) (xy 118.80215 -217.878406)
			(xy 118.802504 -217.855066) (xy 118.80861 -217.808787) (xy 118.820717 -217.763705) (xy 118.829328 -217.742008)
			(xy 118.83898 -217.71864) (xy 118.667276 -217.421206) (xy 118.642384 -217.417904) (xy 118.616955 -217.414138)
			(xy 118.567465 -217.400236) (xy 118.520484 -217.37937) (xy 118.476988 -217.351973) (xy 118.437878 -217.318613)
			(xy 118.403965 -217.279981) (xy 118.375952 -217.236879) (xy 118.354419 -217.1902) (xy 118.339815 -217.140913)
			(xy 118.332441 -217.090039) (xy 118.331996 -217.064336) (xy 117.165628 -217.064336) (xy 117.165628 -217.064844)
			(xy 117.165221 -217.088045) (xy 117.159164 -217.134052) (xy 117.147198 -217.178886) (xy 117.138704 -217.20048)
			(xy 117.129052 -217.223594) (xy 117.301264 -217.521536) (xy 117.326156 -217.524838) (xy 117.351535 -217.528682)
			(xy 117.400916 -217.542687) (xy 117.447781 -217.563624) (xy 117.491162 -217.59106) (xy 117.530163 -217.62443)
			(xy 117.563979 -217.663045) (xy 117.591913 -217.706107) (xy 117.613388 -217.752728) (xy 117.62796 -217.801945)
			(xy 117.635329 -217.852742) (xy 117.635782 -217.878406) (xy 117.635283 -217.905093) (xy 117.627328 -217.957872)
			(xy 117.611596 -218.008875) (xy 117.588438 -218.056964) (xy 117.558371 -218.101064) (xy 117.522067 -218.140191)
			(xy 117.480337 -218.173469) (xy 117.434113 -218.200156) (xy 117.384428 -218.219656) (xy 117.332391 -218.231533)
			(xy 117.279166 -218.235522) (xy 117.225941 -218.231533) (xy 117.173904 -218.219656) (xy 117.124219 -218.200156)
			(xy 117.077995 -218.173469) (xy 117.036265 -218.140191) (xy 116.999961 -218.101064) (xy 116.969894 -218.056964)
			(xy 116.946736 -218.008875) (xy 116.931004 -217.957872) (xy 116.923049 -217.905093) (xy 116.92255 -217.878406)
			(xy 116.922904 -217.855066) (xy 116.92901 -217.808787) (xy 116.941117 -217.763705) (xy 116.949728 -217.742008)
			(xy 116.95938 -217.71864) (xy 116.787676 -217.421206) (xy 116.762784 -217.417904) (xy 116.737355 -217.414138)
			(xy 116.687865 -217.400236) (xy 116.640884 -217.37937) (xy 116.597388 -217.351973) (xy 116.558278 -217.318613)
			(xy 116.524365 -217.279981) (xy 116.496352 -217.236879) (xy 116.474819 -217.1902) (xy 116.460215 -217.140913)
			(xy 116.452841 -217.090039) (xy 116.452396 -217.064336) (xy 115.286028 -217.064336) (xy 115.286028 -217.064844)
			(xy 115.285621 -217.088045) (xy 115.279564 -217.134052) (xy 115.267598 -217.178886) (xy 115.259104 -217.20048)
			(xy 115.249452 -217.223594) (xy 115.421664 -217.521536) (xy 115.446556 -217.524838) (xy 115.471935 -217.528682)
			(xy 115.521316 -217.542687) (xy 115.568181 -217.563624) (xy 115.611562 -217.59106) (xy 115.650563 -217.62443)
			(xy 115.684379 -217.663045) (xy 115.712313 -217.706107) (xy 115.733788 -217.752728) (xy 115.74836 -217.801945)
			(xy 115.755729 -217.852742) (xy 115.756182 -217.878406) (xy 115.755683 -217.905093) (xy 115.747728 -217.957872)
			(xy 115.731996 -218.008875) (xy 115.708838 -218.056964) (xy 115.678771 -218.101064) (xy 115.642467 -218.140191)
			(xy 115.600737 -218.173469) (xy 115.554513 -218.200156) (xy 115.504828 -218.219656) (xy 115.452791 -218.231533)
			(xy 115.399566 -218.235522) (xy 115.346341 -218.231533) (xy 115.294304 -218.219656) (xy 115.244619 -218.200156)
			(xy 115.198395 -218.173469) (xy 115.156665 -218.140191) (xy 115.120361 -218.101064) (xy 115.090294 -218.056964)
			(xy 115.067136 -218.008875) (xy 115.051404 -217.957872) (xy 115.043449 -217.905093) (xy 115.04295 -217.878406)
			(xy 115.043304 -217.855066) (xy 115.04941 -217.808787) (xy 115.061517 -217.763705) (xy 115.070128 -217.742008)
			(xy 115.07978 -217.71864) (xy 114.908076 -217.421206) (xy 114.883184 -217.417904) (xy 114.857755 -217.414138)
			(xy 114.808265 -217.400236) (xy 114.761284 -217.37937) (xy 114.717788 -217.351973) (xy 114.678678 -217.318613)
			(xy 114.644765 -217.279981) (xy 114.616752 -217.236879) (xy 114.595219 -217.1902) (xy 114.580615 -217.140913)
			(xy 114.573241 -217.090039) (xy 114.572796 -217.064336) (xy 113.406428 -217.064336) (xy 113.406428 -217.064844)
			(xy 113.406021 -217.088045) (xy 113.399964 -217.134052) (xy 113.387998 -217.178886) (xy 113.379504 -217.20048)
			(xy 113.369852 -217.223594) (xy 113.542064 -217.521536) (xy 113.566956 -217.524838) (xy 113.592335 -217.528682)
			(xy 113.641716 -217.542687) (xy 113.688581 -217.563624) (xy 113.731962 -217.59106) (xy 113.770963 -217.62443)
			(xy 113.804779 -217.663045) (xy 113.832713 -217.706107) (xy 113.854188 -217.752728) (xy 113.86876 -217.801945)
			(xy 113.876129 -217.852742) (xy 113.876582 -217.878406) (xy 113.876083 -217.905093) (xy 113.868128 -217.957872)
			(xy 113.852396 -218.008875) (xy 113.829238 -218.056964) (xy 113.799171 -218.101064) (xy 113.762867 -218.140191)
			(xy 113.721137 -218.173469) (xy 113.674913 -218.200156) (xy 113.625228 -218.219656) (xy 113.573191 -218.231533)
			(xy 113.519966 -218.235522) (xy 113.466741 -218.231533) (xy 113.414704 -218.219656) (xy 113.365019 -218.200156)
			(xy 113.318795 -218.173469) (xy 113.277065 -218.140191) (xy 113.240761 -218.101064) (xy 113.210694 -218.056964)
			(xy 113.187536 -218.008875) (xy 113.171804 -217.957872) (xy 113.163849 -217.905093) (xy 113.16335 -217.878406)
			(xy 113.163704 -217.855066) (xy 113.16981 -217.808787) (xy 113.181917 -217.763705) (xy 113.190528 -217.742008)
			(xy 113.20018 -217.71864) (xy 113.028476 -217.421206) (xy 113.003584 -217.417904) (xy 112.978155 -217.414138)
			(xy 112.928665 -217.400236) (xy 112.881684 -217.37937) (xy 112.838188 -217.351973) (xy 112.799078 -217.318613)
			(xy 112.765165 -217.279981) (xy 112.737152 -217.236879) (xy 112.715619 -217.1902) (xy 112.701015 -217.140913)
			(xy 112.693641 -217.090039) (xy 112.693196 -217.064336) (xy 111.527082 -217.064336) (xy 111.526633 -217.090015)
			(xy 111.519274 -217.140843) (xy 111.504699 -217.190089) (xy 111.483209 -217.236735) (xy 111.45525 -217.279815)
			(xy 111.4214 -217.318439) (xy 111.382359 -217.351806) (xy 111.338934 -217.379228) (xy 111.292025 -217.400135)
			(xy 111.242601 -217.414097) (xy 111.217202 -217.417904) (xy 111.19231 -217.421206) (xy 111.020352 -217.71864)
			(xy 111.030004 -217.742008) (xy 111.038569 -217.76372) (xy 111.050657 -217.8088) (xy 111.056779 -217.85507)
			(xy 111.057182 -217.878406) (xy 111.056683 -217.905093) (xy 111.048728 -217.957872) (xy 111.032996 -218.008875)
			(xy 111.009838 -218.056964) (xy 110.979771 -218.101064) (xy 110.943467 -218.140191) (xy 110.901737 -218.173469)
			(xy 110.855513 -218.200156) (xy 110.805828 -218.219656) (xy 110.753791 -218.231533) (xy 110.700566 -218.235522)
			(xy 110.647341 -218.231533) (xy 110.595304 -218.219656) (xy 110.545619 -218.200156) (xy 110.499395 -218.173469)
			(xy 110.457665 -218.140191) (xy 110.421361 -218.101064) (xy 110.391294 -218.056964) (xy 110.368136 -218.008875)
			(xy 110.352404 -217.957872) (xy 110.344449 -217.905093) (xy 110.34395 -217.878406) (xy 110.117382 -217.878406)
			(xy 110.117382 -217.878914) (xy 110.116993 -217.902116) (xy 110.110928 -217.948123) (xy 110.098955 -217.992956)
			(xy 110.090458 -218.01455) (xy 110.080806 -218.037664) (xy 110.252764 -218.335352) (xy 110.277656 -218.338654)
			(xy 110.303038 -218.342483) (xy 110.35242 -218.356488) (xy 110.399286 -218.377426) (xy 110.442667 -218.404865)
			(xy 110.481669 -218.438236) (xy 110.515485 -218.476853) (xy 110.543419 -218.519917) (xy 110.564892 -218.566539)
			(xy 110.579463 -218.615758) (xy 110.58683 -218.666557) (xy 110.587282 -218.692222) (xy 111.753396 -218.692222)
			(xy 111.753797 -218.666552) (xy 111.761144 -218.615739) (xy 111.775702 -218.566506) (xy 111.797172 -218.519871)
			(xy 111.825108 -218.476796) (xy 111.858934 -218.438175) (xy 111.89795 -218.404804) (xy 111.941349 -218.377374)
			(xy 111.988233 -218.356453) (xy 112.037633 -218.342472) (xy 112.063022 -218.338654) (xy 112.087914 -218.335352)
			(xy 112.260126 -218.037664) (xy 112.250474 -218.01455) (xy 112.241972 -217.992958) (xy 112.229993 -217.948125)
			(xy 112.223938 -217.902116) (xy 112.22355 -217.878914) (xy 112.22355 -217.878406) (xy 112.224049 -217.851719)
			(xy 112.232004 -217.79894) (xy 112.247736 -217.747937) (xy 112.270894 -217.699848) (xy 112.300961 -217.655748)
			(xy 112.337265 -217.616621) (xy 112.378995 -217.583343) (xy 112.425219 -217.556656) (xy 112.474904 -217.537156)
			(xy 112.526941 -217.525279) (xy 112.580166 -217.52129) (xy 112.633391 -217.525279) (xy 112.685428 -217.537156)
			(xy 112.735113 -217.556656) (xy 112.781337 -217.583343) (xy 112.823067 -217.616621) (xy 112.859371 -217.655748)
			(xy 112.889438 -217.699848) (xy 112.912596 -217.747937) (xy 112.928328 -217.79894) (xy 112.936283 -217.851719)
			(xy 112.936782 -217.878406) (xy 112.936301 -217.904116) (xy 112.928901 -217.955001) (xy 112.914271 -218.004297)
			(xy 112.892713 -218.05098) (xy 112.864675 -218.094083) (xy 112.830737 -218.132714) (xy 112.791604 -218.16607)
			(xy 112.748086 -218.193461) (xy 112.701086 -218.214318) (xy 112.651577 -218.228209) (xy 112.62614 -218.231974)
			(xy 112.601248 -218.235276) (xy 112.429798 -218.532456) (xy 112.43945 -218.55557) (xy 112.448031 -218.577276)
			(xy 112.460113 -218.622359) (xy 112.466228 -218.668631) (xy 112.466628 -218.691968) (xy 112.466628 -218.692222)
			(xy 113.63325 -218.692222) (xy 113.633691 -218.666553) (xy 113.641036 -218.615745) (xy 113.655592 -218.566515)
			(xy 113.677059 -218.519882) (xy 113.704991 -218.476809) (xy 113.738812 -218.438188) (xy 113.777822 -218.404816)
			(xy 113.821216 -218.377385) (xy 113.868095 -218.35646) (xy 113.91749 -218.342475) (xy 113.942876 -218.338654)
			(xy 113.967768 -218.335352) (xy 114.139726 -218.037664) (xy 114.130074 -218.01455) (xy 114.121572 -217.992958)
			(xy 114.109593 -217.948125) (xy 114.103538 -217.902116) (xy 114.10315 -217.878914) (xy 114.10315 -217.878406)
			(xy 114.103649 -217.851719) (xy 114.111604 -217.79894) (xy 114.127336 -217.747937) (xy 114.150494 -217.699848)
			(xy 114.180561 -217.655748) (xy 114.216865 -217.616621) (xy 114.258595 -217.583343) (xy 114.304819 -217.556656)
			(xy 114.354504 -217.537156) (xy 114.406541 -217.525279) (xy 114.459766 -217.52129) (xy 114.512991 -217.525279)
			(xy 114.565028 -217.537156) (xy 114.614713 -217.556656) (xy 114.660937 -217.583343) (xy 114.702667 -217.616621)
			(xy 114.738971 -217.655748) (xy 114.769038 -217.699848) (xy 114.792196 -217.747937) (xy 114.807928 -217.79894)
			(xy 114.815883 -217.851719) (xy 114.816382 -217.878406) (xy 114.815963 -217.904097) (xy 114.808588 -217.954947)
			(xy 114.793991 -218.004212) (xy 114.772475 -218.050872) (xy 114.744485 -218.093962) (xy 114.710601 -218.132588)
			(xy 114.671524 -218.165951) (xy 114.628063 -218.19336) (xy 114.581118 -218.214249) (xy 114.531662 -218.228183)
			(xy 114.506248 -218.231974) (xy 114.481356 -218.235276) (xy 114.309652 -218.532456) (xy 114.319304 -218.555824)
			(xy 114.327873 -218.577534) (xy 114.33996 -218.622615) (xy 114.34608 -218.668886) (xy 114.346482 -218.692222)
			(xy 115.512596 -218.692222) (xy 115.512997 -218.666552) (xy 115.520344 -218.615739) (xy 115.534902 -218.566506)
			(xy 115.556372 -218.519871) (xy 115.584308 -218.476796) (xy 115.618134 -218.438175) (xy 115.65715 -218.404804)
			(xy 115.700549 -218.377374) (xy 115.747433 -218.356453) (xy 115.796833 -218.342472) (xy 115.822222 -218.338654)
			(xy 115.847114 -218.335352) (xy 116.019326 -218.037664) (xy 116.009674 -218.01455) (xy 116.001172 -217.992958)
			(xy 115.989193 -217.948125) (xy 115.983138 -217.902116) (xy 115.98275 -217.878914) (xy 115.98275 -217.878406)
			(xy 115.983249 -217.851719) (xy 115.991204 -217.79894) (xy 116.006936 -217.747937) (xy 116.030094 -217.699848)
			(xy 116.060161 -217.655748) (xy 116.096465 -217.616621) (xy 116.138195 -217.583343) (xy 116.184419 -217.556656)
			(xy 116.234104 -217.537156) (xy 116.286141 -217.525279) (xy 116.339366 -217.52129) (xy 116.392591 -217.525279)
			(xy 116.444628 -217.537156) (xy 116.494313 -217.556656) (xy 116.540537 -217.583343) (xy 116.582267 -217.616621)
			(xy 116.618571 -217.655748) (xy 116.648638 -217.699848) (xy 116.671796 -217.747937) (xy 116.687528 -217.79894)
			(xy 116.695483 -217.851719) (xy 116.695982 -217.878406) (xy 116.695501 -217.904116) (xy 116.688101 -217.955001)
			(xy 116.673471 -218.004297) (xy 116.651913 -218.05098) (xy 116.623875 -218.094083) (xy 116.589937 -218.132714)
			(xy 116.550804 -218.16607) (xy 116.507286 -218.193461) (xy 116.460286 -218.214318) (xy 116.410777 -218.228209)
			(xy 116.38534 -218.231974) (xy 116.360448 -218.235276) (xy 116.188998 -218.532456) (xy 116.19865 -218.55557)
			(xy 116.207231 -218.577276) (xy 116.219313 -218.622359) (xy 116.225428 -218.668631) (xy 116.225828 -218.691968)
			(xy 116.225828 -218.692222) (xy 117.392196 -218.692222) (xy 117.392597 -218.666552) (xy 117.399944 -218.615739)
			(xy 117.414502 -218.566506) (xy 117.435972 -218.519871) (xy 117.463908 -218.476796) (xy 117.497734 -218.438175)
			(xy 117.53675 -218.404804) (xy 117.580149 -218.377374) (xy 117.627033 -218.356453) (xy 117.676433 -218.342472)
			(xy 117.701822 -218.338654) (xy 117.726714 -218.335352) (xy 117.898926 -218.037664) (xy 117.889274 -218.01455)
			(xy 117.880772 -217.992958) (xy 117.868793 -217.948125) (xy 117.862738 -217.902116) (xy 117.86235 -217.878914)
			(xy 117.86235 -217.878406) (xy 117.862849 -217.851719) (xy 117.870804 -217.79894) (xy 117.886536 -217.747937)
			(xy 117.909694 -217.699848) (xy 117.939761 -217.655748) (xy 117.976065 -217.616621) (xy 118.017795 -217.583343)
			(xy 118.064019 -217.556656) (xy 118.113704 -217.537156) (xy 118.165741 -217.525279) (xy 118.218966 -217.52129)
			(xy 118.272191 -217.525279) (xy 118.324228 -217.537156) (xy 118.373913 -217.556656) (xy 118.420137 -217.583343)
			(xy 118.461867 -217.616621) (xy 118.498171 -217.655748) (xy 118.528238 -217.699848) (xy 118.551396 -217.747937)
			(xy 118.567128 -217.79894) (xy 118.575083 -217.851719) (xy 118.575582 -217.878406) (xy 118.575101 -217.904116)
			(xy 118.567701 -217.955001) (xy 118.553071 -218.004297) (xy 118.531513 -218.05098) (xy 118.503475 -218.094083)
			(xy 118.469537 -218.132714) (xy 118.430404 -218.16607) (xy 118.386886 -218.193461) (xy 118.339886 -218.214318)
			(xy 118.290377 -218.228209) (xy 118.26494 -218.231974) (xy 118.240048 -218.235276) (xy 118.068598 -218.532456)
			(xy 118.07825 -218.55557) (xy 118.086831 -218.577276) (xy 118.098913 -218.622359) (xy 118.105028 -218.668631)
			(xy 118.105428 -218.691968) (xy 118.105428 -218.692222) (xy 119.271796 -218.692222) (xy 119.272197 -218.666552)
			(xy 119.279544 -218.615739) (xy 119.294102 -218.566506) (xy 119.315572 -218.519871) (xy 119.343508 -218.476796)
			(xy 119.377334 -218.438175) (xy 119.41635 -218.404804) (xy 119.459749 -218.377374) (xy 119.506633 -218.356453)
			(xy 119.556033 -218.342472) (xy 119.581422 -218.338654) (xy 119.606314 -218.335352) (xy 119.778526 -218.037664)
			(xy 119.768874 -218.01455) (xy 119.760372 -217.992958) (xy 119.748393 -217.948125) (xy 119.742338 -217.902116)
			(xy 119.74195 -217.878914) (xy 119.74195 -217.878406) (xy 119.742449 -217.851719) (xy 119.750404 -217.79894)
			(xy 119.766136 -217.747937) (xy 119.789294 -217.699848) (xy 119.819361 -217.655748) (xy 119.855665 -217.616621)
			(xy 119.897395 -217.583343) (xy 119.943619 -217.556656) (xy 119.993304 -217.537156) (xy 120.045341 -217.525279)
			(xy 120.098566 -217.52129) (xy 120.151791 -217.525279) (xy 120.203828 -217.537156) (xy 120.253513 -217.556656)
			(xy 120.299737 -217.583343) (xy 120.341467 -217.616621) (xy 120.377771 -217.655748) (xy 120.407838 -217.699848)
			(xy 120.430996 -217.747937) (xy 120.446728 -217.79894) (xy 120.454683 -217.851719) (xy 120.455182 -217.878406)
			(xy 120.454701 -217.904116) (xy 120.447301 -217.955001) (xy 120.432671 -218.004297) (xy 120.411113 -218.05098)
			(xy 120.383075 -218.094083) (xy 120.349137 -218.132714) (xy 120.310004 -218.16607) (xy 120.266486 -218.193461)
			(xy 120.219486 -218.214318) (xy 120.169977 -218.228209) (xy 120.14454 -218.231974) (xy 120.119648 -218.235276)
			(xy 119.948198 -218.532456) (xy 119.95785 -218.55557) (xy 119.966431 -218.577276) (xy 119.978513 -218.622359)
			(xy 119.984628 -218.668631) (xy 119.985028 -218.691968) (xy 119.985028 -218.692222) (xy 121.151396 -218.692222)
			(xy 121.151797 -218.666552) (xy 121.159144 -218.615739) (xy 121.173702 -218.566506) (xy 121.195172 -218.519871)
			(xy 121.223108 -218.476796) (xy 121.256934 -218.438175) (xy 121.29595 -218.404804) (xy 121.339349 -218.377374)
			(xy 121.386233 -218.356453) (xy 121.435633 -218.342472) (xy 121.461022 -218.338654) (xy 121.485914 -218.335352)
			(xy 121.658126 -218.037664) (xy 121.648474 -218.01455) (xy 121.639972 -217.992958) (xy 121.627993 -217.948125)
			(xy 121.621938 -217.902116) (xy 121.62155 -217.878914) (xy 121.62155 -217.878406) (xy 121.622049 -217.851719)
			(xy 121.630004 -217.79894) (xy 121.645736 -217.747937) (xy 121.668894 -217.699848) (xy 121.698961 -217.655748)
			(xy 121.735265 -217.616621) (xy 121.776995 -217.583343) (xy 121.823219 -217.556656) (xy 121.872904 -217.537156)
			(xy 121.924941 -217.525279) (xy 121.978166 -217.52129) (xy 122.031391 -217.525279) (xy 122.083428 -217.537156)
			(xy 122.133113 -217.556656) (xy 122.179337 -217.583343) (xy 122.221067 -217.616621) (xy 122.257371 -217.655748)
			(xy 122.287438 -217.699848) (xy 122.310596 -217.747937) (xy 122.326328 -217.79894) (xy 122.334283 -217.851719)
			(xy 122.334782 -217.878406) (xy 122.334301 -217.904116) (xy 122.326901 -217.955001) (xy 122.312271 -218.004297)
			(xy 122.290713 -218.05098) (xy 122.262675 -218.094083) (xy 122.228737 -218.132714) (xy 122.189604 -218.16607)
			(xy 122.146086 -218.193461) (xy 122.099086 -218.214318) (xy 122.049577 -218.228209) (xy 122.02414 -218.231974)
			(xy 121.999248 -218.235276) (xy 121.827798 -218.532456) (xy 121.83745 -218.55557) (xy 121.846031 -218.577276)
			(xy 121.858113 -218.622359) (xy 121.864228 -218.668631) (xy 121.864628 -218.691968) (xy 121.864628 -218.692222)
			(xy 123.030996 -218.692222) (xy 123.031397 -218.666552) (xy 123.038744 -218.615739) (xy 123.053302 -218.566506)
			(xy 123.074772 -218.519871) (xy 123.102708 -218.476796) (xy 123.136534 -218.438175) (xy 123.17555 -218.404804)
			(xy 123.218949 -218.377374) (xy 123.265833 -218.356453) (xy 123.315233 -218.342472) (xy 123.340622 -218.338654)
			(xy 123.365514 -218.335352) (xy 123.537726 -218.037664) (xy 123.528074 -218.01455) (xy 123.519572 -217.992958)
			(xy 123.507593 -217.948125) (xy 123.501538 -217.902116) (xy 123.50115 -217.878914) (xy 123.50115 -217.878406)
			(xy 123.501649 -217.851719) (xy 123.509604 -217.79894) (xy 123.525336 -217.747937) (xy 123.548494 -217.699848)
			(xy 123.578561 -217.655748) (xy 123.614865 -217.616621) (xy 123.656595 -217.583343) (xy 123.702819 -217.556656)
			(xy 123.752504 -217.537156) (xy 123.804541 -217.525279) (xy 123.857766 -217.52129) (xy 123.910991 -217.525279)
			(xy 123.963028 -217.537156) (xy 124.012713 -217.556656) (xy 124.058937 -217.583343) (xy 124.100667 -217.616621)
			(xy 124.136971 -217.655748) (xy 124.167038 -217.699848) (xy 124.190196 -217.747937) (xy 124.205928 -217.79894)
			(xy 124.213883 -217.851719) (xy 124.214382 -217.878406) (xy 124.213901 -217.904116) (xy 124.206501 -217.955001)
			(xy 124.191871 -218.004297) (xy 124.170313 -218.05098) (xy 124.142275 -218.094083) (xy 124.108337 -218.132714)
			(xy 124.069204 -218.16607) (xy 124.025686 -218.193461) (xy 123.978686 -218.214318) (xy 123.929177 -218.228209)
			(xy 123.90374 -218.231974) (xy 123.878848 -218.235276) (xy 123.707398 -218.532456) (xy 123.71705 -218.55557)
			(xy 123.725631 -218.577276) (xy 123.737713 -218.622359) (xy 123.743828 -218.668631) (xy 123.744228 -218.691968)
			(xy 123.744228 -218.692222) (xy 124.910596 -218.692222) (xy 124.910997 -218.666552) (xy 124.918344 -218.615739)
			(xy 124.932902 -218.566506) (xy 124.954372 -218.519871) (xy 124.982308 -218.476796) (xy 125.016134 -218.438175)
			(xy 125.05515 -218.404804) (xy 125.098549 -218.377374) (xy 125.145433 -218.356453) (xy 125.194833 -218.342472)
			(xy 125.220222 -218.338654) (xy 125.245114 -218.335352) (xy 125.417326 -218.037664) (xy 125.407674 -218.01455)
			(xy 125.399172 -217.992958) (xy 125.387193 -217.948125) (xy 125.381138 -217.902116) (xy 125.38075 -217.878914)
			(xy 125.38075 -217.878406) (xy 125.381249 -217.851719) (xy 125.389204 -217.79894) (xy 125.404936 -217.747937)
			(xy 125.428094 -217.699848) (xy 125.458161 -217.655748) (xy 125.494465 -217.616621) (xy 125.536195 -217.583343)
			(xy 125.582419 -217.556656) (xy 125.632104 -217.537156) (xy 125.684141 -217.525279) (xy 125.737366 -217.52129)
			(xy 125.790591 -217.525279) (xy 125.842628 -217.537156) (xy 125.892313 -217.556656) (xy 125.938537 -217.583343)
			(xy 125.980267 -217.616621) (xy 126.016571 -217.655748) (xy 126.046638 -217.699848) (xy 126.069796 -217.747937)
			(xy 126.085528 -217.79894) (xy 126.093483 -217.851719) (xy 126.093982 -217.878406) (xy 126.093501 -217.904116)
			(xy 126.086101 -217.955001) (xy 126.071471 -218.004297) (xy 126.049913 -218.05098) (xy 126.021875 -218.094083)
			(xy 125.987937 -218.132714) (xy 125.948804 -218.16607) (xy 125.905286 -218.193461) (xy 125.858286 -218.214318)
			(xy 125.808777 -218.228209) (xy 125.78334 -218.231974) (xy 125.758448 -218.235276) (xy 125.586998 -218.532456)
			(xy 125.59665 -218.55557) (xy 125.605231 -218.577276) (xy 125.617313 -218.622359) (xy 125.623428 -218.668631)
			(xy 125.623828 -218.691968) (xy 125.623828 -218.692222) (xy 126.790196 -218.692222) (xy 126.790597 -218.666552)
			(xy 126.797944 -218.615739) (xy 126.812502 -218.566506) (xy 126.833972 -218.519871) (xy 126.861908 -218.476796)
			(xy 126.895734 -218.438175) (xy 126.93475 -218.404804) (xy 126.978149 -218.377374) (xy 127.025033 -218.356453)
			(xy 127.074433 -218.342472) (xy 127.099822 -218.338654) (xy 127.124714 -218.335352) (xy 127.296926 -218.037664)
			(xy 127.287274 -218.01455) (xy 127.278772 -217.992958) (xy 127.266793 -217.948125) (xy 127.260738 -217.902116)
			(xy 127.26035 -217.878914) (xy 127.26035 -217.878406) (xy 127.260849 -217.851719) (xy 127.268804 -217.79894)
			(xy 127.284536 -217.747937) (xy 127.307694 -217.699848) (xy 127.337761 -217.655748) (xy 127.374065 -217.616621)
			(xy 127.415795 -217.583343) (xy 127.462019 -217.556656) (xy 127.511704 -217.537156) (xy 127.563741 -217.525279)
			(xy 127.616966 -217.52129) (xy 127.670191 -217.525279) (xy 127.722228 -217.537156) (xy 127.771913 -217.556656)
			(xy 127.818137 -217.583343) (xy 127.859867 -217.616621) (xy 127.896171 -217.655748) (xy 127.926238 -217.699848)
			(xy 127.949396 -217.747937) (xy 127.965128 -217.79894) (xy 127.973083 -217.851719) (xy 127.973582 -217.878406)
			(xy 127.973101 -217.904116) (xy 127.965701 -217.955001) (xy 127.951071 -218.004297) (xy 127.929513 -218.05098)
			(xy 127.901475 -218.094083) (xy 127.867537 -218.132714) (xy 127.828404 -218.16607) (xy 127.784886 -218.193461)
			(xy 127.737886 -218.214318) (xy 127.688377 -218.228209) (xy 127.66294 -218.231974) (xy 127.638048 -218.235276)
			(xy 127.466598 -218.532456) (xy 127.47625 -218.55557) (xy 127.484831 -218.577276) (xy 127.496913 -218.622359)
			(xy 127.503028 -218.668631) (xy 127.503428 -218.691968) (xy 127.503428 -218.692222) (xy 128.669796 -218.692222)
			(xy 128.670197 -218.666552) (xy 128.677544 -218.615739) (xy 128.692102 -218.566506) (xy 128.713572 -218.519871)
			(xy 128.741508 -218.476796) (xy 128.775334 -218.438175) (xy 128.81435 -218.404804) (xy 128.857749 -218.377374)
			(xy 128.904633 -218.356453) (xy 128.954033 -218.342472) (xy 128.979422 -218.338654) (xy 129.004314 -218.335352)
			(xy 129.176526 -218.037664) (xy 129.166874 -218.01455) (xy 129.158372 -217.992958) (xy 129.146393 -217.948125)
			(xy 129.140338 -217.902116) (xy 129.13995 -217.878914) (xy 129.13995 -217.878406) (xy 129.140449 -217.851719)
			(xy 129.148404 -217.79894) (xy 129.164136 -217.747937) (xy 129.187294 -217.699848) (xy 129.217361 -217.655748)
			(xy 129.253665 -217.616621) (xy 129.295395 -217.583343) (xy 129.341619 -217.556656) (xy 129.391304 -217.537156)
			(xy 129.443341 -217.525279) (xy 129.496566 -217.52129) (xy 129.549791 -217.525279) (xy 129.601828 -217.537156)
			(xy 129.651513 -217.556656) (xy 129.697737 -217.583343) (xy 129.739467 -217.616621) (xy 129.775771 -217.655748)
			(xy 129.805838 -217.699848) (xy 129.828996 -217.747937) (xy 129.844728 -217.79894) (xy 129.852683 -217.851719)
			(xy 129.853182 -217.878406) (xy 129.852701 -217.904116) (xy 129.845301 -217.955001) (xy 129.830671 -218.004297)
			(xy 129.809113 -218.05098) (xy 129.781075 -218.094083) (xy 129.747137 -218.132714) (xy 129.708004 -218.16607)
			(xy 129.664486 -218.193461) (xy 129.617486 -218.214318) (xy 129.567977 -218.228209) (xy 129.54254 -218.231974)
			(xy 129.517648 -218.235276) (xy 129.346198 -218.532456) (xy 129.35585 -218.55557) (xy 129.364431 -218.577276)
			(xy 129.376513 -218.622359) (xy 129.382628 -218.668631) (xy 129.383028 -218.691968) (xy 129.383028 -218.692222)
			(xy 130.549396 -218.692222) (xy 130.549797 -218.666552) (xy 130.557144 -218.615739) (xy 130.571702 -218.566506)
			(xy 130.593172 -218.519871) (xy 130.621108 -218.476796) (xy 130.654934 -218.438175) (xy 130.69395 -218.404804)
			(xy 130.737349 -218.377374) (xy 130.784233 -218.356453) (xy 130.833633 -218.342472) (xy 130.859022 -218.338654)
			(xy 130.883914 -218.335352) (xy 131.056126 -218.037664) (xy 131.046474 -218.01455) (xy 131.037972 -217.992958)
			(xy 131.025993 -217.948125) (xy 131.019938 -217.902116) (xy 131.01955 -217.878914) (xy 131.01955 -217.878406)
			(xy 131.020049 -217.851719) (xy 131.028004 -217.79894) (xy 131.043736 -217.747937) (xy 131.066894 -217.699848)
			(xy 131.096961 -217.655748) (xy 131.133265 -217.616621) (xy 131.174995 -217.583343) (xy 131.221219 -217.556656)
			(xy 131.270904 -217.537156) (xy 131.322941 -217.525279) (xy 131.376166 -217.52129) (xy 131.429391 -217.525279)
			(xy 131.481428 -217.537156) (xy 131.531113 -217.556656) (xy 131.577337 -217.583343) (xy 131.619067 -217.616621)
			(xy 131.655371 -217.655748) (xy 131.685438 -217.699848) (xy 131.708596 -217.747937) (xy 131.724328 -217.79894)
			(xy 131.732283 -217.851719) (xy 131.732782 -217.878406) (xy 131.732301 -217.904116) (xy 131.724901 -217.955001)
			(xy 131.710271 -218.004297) (xy 131.688713 -218.05098) (xy 131.660675 -218.094083) (xy 131.626737 -218.132714)
			(xy 131.587604 -218.16607) (xy 131.544086 -218.193461) (xy 131.497086 -218.214318) (xy 131.447577 -218.228209)
			(xy 131.42214 -218.231974) (xy 131.397248 -218.235276) (xy 131.225798 -218.532456) (xy 131.23545 -218.55557)
			(xy 131.244031 -218.577276) (xy 131.256113 -218.622359) (xy 131.262228 -218.668631) (xy 131.262628 -218.691968)
			(xy 131.262628 -218.692222) (xy 132.428996 -218.692222) (xy 132.429397 -218.666552) (xy 132.436744 -218.615739)
			(xy 132.451302 -218.566506) (xy 132.472772 -218.519871) (xy 132.500708 -218.476796) (xy 132.534534 -218.438175)
			(xy 132.57355 -218.404804) (xy 132.616949 -218.377374) (xy 132.663833 -218.356453) (xy 132.713233 -218.342472)
			(xy 132.738622 -218.338654) (xy 132.763514 -218.335352) (xy 132.935726 -218.037664) (xy 132.926074 -218.01455)
			(xy 132.917572 -217.992958) (xy 132.905593 -217.948125) (xy 132.899538 -217.902116) (xy 132.89915 -217.878914)
			(xy 132.89915 -217.878406) (xy 132.899649 -217.851719) (xy 132.907604 -217.79894) (xy 132.923336 -217.747937)
			(xy 132.946494 -217.699848) (xy 132.976561 -217.655748) (xy 133.012865 -217.616621) (xy 133.054595 -217.583343)
			(xy 133.100819 -217.556656) (xy 133.150504 -217.537156) (xy 133.202541 -217.525279) (xy 133.255766 -217.52129)
			(xy 133.308991 -217.525279) (xy 133.361028 -217.537156) (xy 133.410713 -217.556656) (xy 133.456937 -217.583343)
			(xy 133.498667 -217.616621) (xy 133.534971 -217.655748) (xy 133.565038 -217.699848) (xy 133.588196 -217.747937)
			(xy 133.603928 -217.79894) (xy 133.611883 -217.851719) (xy 133.612382 -217.878406) (xy 133.611901 -217.904116)
			(xy 133.604501 -217.955001) (xy 133.589871 -218.004297) (xy 133.568313 -218.05098) (xy 133.540275 -218.094083)
			(xy 133.506337 -218.132714) (xy 133.467204 -218.16607) (xy 133.423686 -218.193461) (xy 133.376686 -218.214318)
			(xy 133.327177 -218.228209) (xy 133.30174 -218.231974) (xy 133.276848 -218.235276) (xy 133.105398 -218.532456)
			(xy 133.11505 -218.55557) (xy 133.123631 -218.577276) (xy 133.135713 -218.622359) (xy 133.141828 -218.668631)
			(xy 133.142228 -218.691968) (xy 133.142228 -218.692222) (xy 133.141729 -218.718909) (xy 133.133774 -218.771688)
			(xy 133.118042 -218.822691) (xy 133.094884 -218.87078) (xy 133.064817 -218.91488) (xy 133.028513 -218.954007)
			(xy 132.986783 -218.987285) (xy 132.940559 -219.013972) (xy 132.890874 -219.033472) (xy 132.838837 -219.045349)
			(xy 132.785612 -219.049338) (xy 132.732387 -219.045349) (xy 132.68035 -219.033472) (xy 132.630665 -219.013972)
			(xy 132.584441 -218.987285) (xy 132.542711 -218.954007) (xy 132.506407 -218.91488) (xy 132.47634 -218.87078)
			(xy 132.453182 -218.822691) (xy 132.43745 -218.771688) (xy 132.429495 -218.718909) (xy 132.428996 -218.692222)
			(xy 131.262628 -218.692222) (xy 131.262129 -218.718909) (xy 131.254174 -218.771688) (xy 131.238442 -218.822691)
			(xy 131.215284 -218.87078) (xy 131.185217 -218.91488) (xy 131.148913 -218.954007) (xy 131.107183 -218.987285)
			(xy 131.060959 -219.013972) (xy 131.011274 -219.033472) (xy 130.959237 -219.045349) (xy 130.906012 -219.049338)
			(xy 130.852787 -219.045349) (xy 130.80075 -219.033472) (xy 130.751065 -219.013972) (xy 130.704841 -218.987285)
			(xy 130.663111 -218.954007) (xy 130.626807 -218.91488) (xy 130.59674 -218.87078) (xy 130.573582 -218.822691)
			(xy 130.55785 -218.771688) (xy 130.549895 -218.718909) (xy 130.549396 -218.692222) (xy 129.383028 -218.692222)
			(xy 129.382529 -218.718909) (xy 129.374574 -218.771688) (xy 129.358842 -218.822691) (xy 129.335684 -218.87078)
			(xy 129.305617 -218.91488) (xy 129.269313 -218.954007) (xy 129.227583 -218.987285) (xy 129.181359 -219.013972)
			(xy 129.131674 -219.033472) (xy 129.079637 -219.045349) (xy 129.026412 -219.049338) (xy 128.973187 -219.045349)
			(xy 128.92115 -219.033472) (xy 128.871465 -219.013972) (xy 128.825241 -218.987285) (xy 128.783511 -218.954007)
			(xy 128.747207 -218.91488) (xy 128.71714 -218.87078) (xy 128.693982 -218.822691) (xy 128.67825 -218.771688)
			(xy 128.670295 -218.718909) (xy 128.669796 -218.692222) (xy 127.503428 -218.692222) (xy 127.502929 -218.718909)
			(xy 127.494974 -218.771688) (xy 127.479242 -218.822691) (xy 127.456084 -218.87078) (xy 127.426017 -218.91488)
			(xy 127.389713 -218.954007) (xy 127.347983 -218.987285) (xy 127.301759 -219.013972) (xy 127.252074 -219.033472)
			(xy 127.200037 -219.045349) (xy 127.146812 -219.049338) (xy 127.093587 -219.045349) (xy 127.04155 -219.033472)
			(xy 126.991865 -219.013972) (xy 126.945641 -218.987285) (xy 126.903911 -218.954007) (xy 126.867607 -218.91488)
			(xy 126.83754 -218.87078) (xy 126.814382 -218.822691) (xy 126.79865 -218.771688) (xy 126.790695 -218.718909)
			(xy 126.790196 -218.692222) (xy 125.623828 -218.692222) (xy 125.623329 -218.718909) (xy 125.615374 -218.771688)
			(xy 125.599642 -218.822691) (xy 125.576484 -218.87078) (xy 125.546417 -218.91488) (xy 125.510113 -218.954007)
			(xy 125.468383 -218.987285) (xy 125.422159 -219.013972) (xy 125.372474 -219.033472) (xy 125.320437 -219.045349)
			(xy 125.267212 -219.049338) (xy 125.213987 -219.045349) (xy 125.16195 -219.033472) (xy 125.112265 -219.013972)
			(xy 125.066041 -218.987285) (xy 125.024311 -218.954007) (xy 124.988007 -218.91488) (xy 124.95794 -218.87078)
			(xy 124.934782 -218.822691) (xy 124.91905 -218.771688) (xy 124.911095 -218.718909) (xy 124.910596 -218.692222)
			(xy 123.744228 -218.692222) (xy 123.743729 -218.718909) (xy 123.735774 -218.771688) (xy 123.720042 -218.822691)
			(xy 123.696884 -218.87078) (xy 123.666817 -218.91488) (xy 123.630513 -218.954007) (xy 123.588783 -218.987285)
			(xy 123.542559 -219.013972) (xy 123.492874 -219.033472) (xy 123.440837 -219.045349) (xy 123.387612 -219.049338)
			(xy 123.334387 -219.045349) (xy 123.28235 -219.033472) (xy 123.232665 -219.013972) (xy 123.186441 -218.987285)
			(xy 123.144711 -218.954007) (xy 123.108407 -218.91488) (xy 123.07834 -218.87078) (xy 123.055182 -218.822691)
			(xy 123.03945 -218.771688) (xy 123.031495 -218.718909) (xy 123.030996 -218.692222) (xy 121.864628 -218.692222)
			(xy 121.864129 -218.718909) (xy 121.856174 -218.771688) (xy 121.840442 -218.822691) (xy 121.817284 -218.87078)
			(xy 121.787217 -218.91488) (xy 121.750913 -218.954007) (xy 121.709183 -218.987285) (xy 121.662959 -219.013972)
			(xy 121.613274 -219.033472) (xy 121.561237 -219.045349) (xy 121.508012 -219.049338) (xy 121.454787 -219.045349)
			(xy 121.40275 -219.033472) (xy 121.353065 -219.013972) (xy 121.306841 -218.987285) (xy 121.265111 -218.954007)
			(xy 121.228807 -218.91488) (xy 121.19874 -218.87078) (xy 121.175582 -218.822691) (xy 121.15985 -218.771688)
			(xy 121.151895 -218.718909) (xy 121.151396 -218.692222) (xy 119.985028 -218.692222) (xy 119.984529 -218.718909)
			(xy 119.976574 -218.771688) (xy 119.960842 -218.822691) (xy 119.937684 -218.87078) (xy 119.907617 -218.91488)
			(xy 119.871313 -218.954007) (xy 119.829583 -218.987285) (xy 119.783359 -219.013972) (xy 119.733674 -219.033472)
			(xy 119.681637 -219.045349) (xy 119.628412 -219.049338) (xy 119.575187 -219.045349) (xy 119.52315 -219.033472)
			(xy 119.473465 -219.013972) (xy 119.427241 -218.987285) (xy 119.385511 -218.954007) (xy 119.349207 -218.91488)
			(xy 119.31914 -218.87078) (xy 119.295982 -218.822691) (xy 119.28025 -218.771688) (xy 119.272295 -218.718909)
			(xy 119.271796 -218.692222) (xy 118.105428 -218.692222) (xy 118.104929 -218.718909) (xy 118.096974 -218.771688)
			(xy 118.081242 -218.822691) (xy 118.058084 -218.87078) (xy 118.028017 -218.91488) (xy 117.991713 -218.954007)
			(xy 117.949983 -218.987285) (xy 117.903759 -219.013972) (xy 117.854074 -219.033472) (xy 117.802037 -219.045349)
			(xy 117.748812 -219.049338) (xy 117.695587 -219.045349) (xy 117.64355 -219.033472) (xy 117.593865 -219.013972)
			(xy 117.547641 -218.987285) (xy 117.505911 -218.954007) (xy 117.469607 -218.91488) (xy 117.43954 -218.87078)
			(xy 117.416382 -218.822691) (xy 117.40065 -218.771688) (xy 117.392695 -218.718909) (xy 117.392196 -218.692222)
			(xy 116.225828 -218.692222) (xy 116.225329 -218.718909) (xy 116.217374 -218.771688) (xy 116.201642 -218.822691)
			(xy 116.178484 -218.87078) (xy 116.148417 -218.91488) (xy 116.112113 -218.954007) (xy 116.070383 -218.987285)
			(xy 116.024159 -219.013972) (xy 115.974474 -219.033472) (xy 115.922437 -219.045349) (xy 115.869212 -219.049338)
			(xy 115.815987 -219.045349) (xy 115.76395 -219.033472) (xy 115.714265 -219.013972) (xy 115.668041 -218.987285)
			(xy 115.626311 -218.954007) (xy 115.590007 -218.91488) (xy 115.55994 -218.87078) (xy 115.536782 -218.822691)
			(xy 115.52105 -218.771688) (xy 115.513095 -218.718909) (xy 115.512596 -218.692222) (xy 114.346482 -218.692222)
			(xy 114.345983 -218.718909) (xy 114.338028 -218.771688) (xy 114.322296 -218.822691) (xy 114.299138 -218.87078)
			(xy 114.269071 -218.91488) (xy 114.232767 -218.954007) (xy 114.191037 -218.987285) (xy 114.144813 -219.013972)
			(xy 114.095128 -219.033472) (xy 114.043091 -219.045349) (xy 113.989866 -219.049338) (xy 113.936641 -219.045349)
			(xy 113.884604 -219.033472) (xy 113.834919 -219.013972) (xy 113.788695 -218.987285) (xy 113.746965 -218.954007)
			(xy 113.710661 -218.91488) (xy 113.680594 -218.87078) (xy 113.657436 -218.822691) (xy 113.641704 -218.771688)
			(xy 113.633749 -218.718909) (xy 113.63325 -218.692222) (xy 112.466628 -218.692222) (xy 112.466129 -218.718909)
			(xy 112.458174 -218.771688) (xy 112.442442 -218.822691) (xy 112.419284 -218.87078) (xy 112.389217 -218.91488)
			(xy 112.352913 -218.954007) (xy 112.311183 -218.987285) (xy 112.264959 -219.013972) (xy 112.215274 -219.033472)
			(xy 112.163237 -219.045349) (xy 112.110012 -219.049338) (xy 112.056787 -219.045349) (xy 112.00475 -219.033472)
			(xy 111.955065 -219.013972) (xy 111.908841 -218.987285) (xy 111.867111 -218.954007) (xy 111.830807 -218.91488)
			(xy 111.80074 -218.87078) (xy 111.777582 -218.822691) (xy 111.76185 -218.771688) (xy 111.753895 -218.718909)
			(xy 111.753396 -218.692222) (xy 110.587282 -218.692222) (xy 110.586783 -218.718909) (xy 110.578828 -218.771688)
			(xy 110.563096 -218.822691) (xy 110.539938 -218.87078) (xy 110.509871 -218.91488) (xy 110.473567 -218.954007)
			(xy 110.431837 -218.987285) (xy 110.385613 -219.013972) (xy 110.335928 -219.033472) (xy 110.283891 -219.045349)
			(xy 110.230666 -219.049338) (xy 110.177441 -219.045349) (xy 110.125404 -219.033472) (xy 110.075719 -219.013972)
			(xy 110.029495 -218.987285) (xy 109.987765 -218.954007) (xy 109.951461 -218.91488) (xy 109.921394 -218.87078)
			(xy 109.898236 -218.822691) (xy 109.882504 -218.771688) (xy 109.874549 -218.718909) (xy 109.87405 -218.692222)
			(xy 109.874409 -218.668882) (xy 109.880513 -218.622603) (xy 109.892618 -218.577521) (xy 109.901228 -218.555824)
			(xy 109.91088 -218.532456) (xy 109.738922 -218.235276) (xy 109.71403 -218.231974) (xy 109.688633 -218.228159)
			(xy 109.639213 -218.214192) (xy 109.592308 -218.193281) (xy 109.548886 -218.165858) (xy 109.509847 -218.132491)
			(xy 109.475998 -218.09387) (xy 109.448037 -218.050793) (xy 109.426545 -218.004151) (xy 109.411965 -217.954908)
			(xy 109.404598 -217.904084) (xy 109.40415 -217.878406) (xy 109.177582 -217.878406) (xy 109.177083 -217.905093)
			(xy 109.169128 -217.957872) (xy 109.153396 -218.008875) (xy 109.130238 -218.056964) (xy 109.100171 -218.101064)
			(xy 109.063867 -218.140191) (xy 109.022137 -218.173469) (xy 108.975913 -218.200156) (xy 108.926228 -218.219656)
			(xy 108.874191 -218.231533) (xy 108.820966 -218.235522) (xy 108.767741 -218.231533) (xy 108.715704 -218.219656)
			(xy 108.666019 -218.200156) (xy 108.619795 -218.173469) (xy 108.578065 -218.140191) (xy 108.541761 -218.101064)
			(xy 108.511694 -218.056964) (xy 108.488536 -218.008875) (xy 108.472804 -217.957872) (xy 108.464849 -217.905093)
			(xy 108.46435 -217.878406) (xy 108.237782 -217.878406) (xy 108.237398 -217.901745) (xy 108.231304 -217.948023)
			(xy 108.219209 -217.993106) (xy 108.210604 -218.014804) (xy 108.200952 -218.038172) (xy 108.37291 -218.335352)
			(xy 108.397802 -218.338654) (xy 108.423177 -218.342525) (xy 108.472559 -218.356524) (xy 108.519425 -218.377455)
			(xy 108.562807 -218.404887) (xy 108.60181 -218.438254) (xy 108.635628 -218.476866) (xy 108.663562 -218.519927)
			(xy 108.685037 -218.566546) (xy 108.699609 -218.615762) (xy 108.706976 -218.666558) (xy 108.707428 -218.692222)
			(xy 108.706929 -218.718909) (xy 108.698974 -218.771688) (xy 108.683242 -218.822691) (xy 108.660084 -218.87078)
			(xy 108.630017 -218.91488) (xy 108.593713 -218.954007) (xy 108.551983 -218.987285) (xy 108.505759 -219.013972)
			(xy 108.456074 -219.033472) (xy 108.404037 -219.045349) (xy 108.350812 -219.049338) (xy 108.297587 -219.045349)
			(xy 108.24555 -219.033472) (xy 108.195865 -219.013972) (xy 108.149641 -218.987285) (xy 108.107911 -218.954007)
			(xy 108.071607 -218.91488) (xy 108.04154 -218.87078) (xy 108.018382 -218.822691) (xy 108.00265 -218.771688)
			(xy 107.994695 -218.718909) (xy 107.994196 -218.692222) (xy 107.994551 -218.668882) (xy 108.000656 -218.622603)
			(xy 108.012763 -218.577521) (xy 108.021374 -218.555824) (xy 108.031026 -218.532456) (xy 107.859068 -218.235276)
			(xy 107.834176 -218.231974) (xy 107.808786 -218.22819) (xy 107.759398 -218.214184) (xy 107.712528 -218.193245)
			(xy 107.669143 -218.165803) (xy 107.63014 -218.132427) (xy 107.596323 -218.093804) (xy 107.568391 -218.050733)
			(xy 107.54692 -218.004104) (xy 107.532356 -217.954878) (xy 107.524997 -217.904074) (xy 107.52455 -217.878406)
			(xy 107.297982 -217.878406) (xy 107.297483 -217.905093) (xy 107.289528 -217.957872) (xy 107.273796 -218.008875)
			(xy 107.250638 -218.056964) (xy 107.220571 -218.101064) (xy 107.184267 -218.140191) (xy 107.142537 -218.173469)
			(xy 107.096313 -218.200156) (xy 107.046628 -218.219656) (xy 106.994591 -218.231533) (xy 106.941366 -218.235522)
			(xy 106.888141 -218.231533) (xy 106.836104 -218.219656) (xy 106.786419 -218.200156) (xy 106.740195 -218.173469)
			(xy 106.698465 -218.140191) (xy 106.662161 -218.101064) (xy 106.632094 -218.056964) (xy 106.608936 -218.008875)
			(xy 106.593204 -217.957872) (xy 106.585249 -217.905093) (xy 106.58475 -217.878406) (xy 106.358182 -217.878406)
			(xy 106.357798 -217.901745) (xy 106.351704 -217.948023) (xy 106.339609 -217.993106) (xy 106.331004 -218.014804)
			(xy 106.321352 -218.038172) (xy 106.49331 -218.335352) (xy 106.518202 -218.338654) (xy 106.543577 -218.342525)
			(xy 106.592959 -218.356524) (xy 106.639825 -218.377455) (xy 106.683207 -218.404887) (xy 106.72221 -218.438254)
			(xy 106.756028 -218.476866) (xy 106.783962 -218.519927) (xy 106.805437 -218.566546) (xy 106.820009 -218.615762)
			(xy 106.827376 -218.666558) (xy 106.827828 -218.692222) (xy 106.827329 -218.718909) (xy 106.819374 -218.771688)
			(xy 106.803642 -218.822691) (xy 106.780484 -218.87078) (xy 106.750417 -218.91488) (xy 106.714113 -218.954007)
			(xy 106.672383 -218.987285) (xy 106.626159 -219.013972) (xy 106.576474 -219.033472) (xy 106.524437 -219.045349)
			(xy 106.471212 -219.049338) (xy 106.417987 -219.045349) (xy 106.36595 -219.033472) (xy 106.316265 -219.013972)
			(xy 106.270041 -218.987285) (xy 106.228311 -218.954007) (xy 106.192007 -218.91488) (xy 106.16194 -218.87078)
			(xy 106.138782 -218.822691) (xy 106.12305 -218.771688) (xy 106.115095 -218.718909) (xy 106.114596 -218.692222)
			(xy 106.114951 -218.668882) (xy 106.121056 -218.622603) (xy 106.133163 -218.577521) (xy 106.141774 -218.555824)
			(xy 106.151426 -218.532456) (xy 105.979468 -218.235276) (xy 105.954576 -218.231974) (xy 105.929186 -218.22819)
			(xy 105.879798 -218.214184) (xy 105.832928 -218.193245) (xy 105.789543 -218.165803) (xy 105.75054 -218.132427)
			(xy 105.716723 -218.093804) (xy 105.688791 -218.050733) (xy 105.66732 -218.004104) (xy 105.652756 -217.954878)
			(xy 105.645397 -217.904074) (xy 105.64495 -217.878406) (xy 105.418382 -217.878406) (xy 105.417883 -217.905093)
			(xy 105.409928 -217.957872) (xy 105.394196 -218.008875) (xy 105.371038 -218.056964) (xy 105.340971 -218.101064)
			(xy 105.304667 -218.140191) (xy 105.262937 -218.173469) (xy 105.216713 -218.200156) (xy 105.167028 -218.219656)
			(xy 105.114991 -218.231533) (xy 105.061766 -218.235522) (xy 105.008541 -218.231533) (xy 104.956504 -218.219656)
			(xy 104.906819 -218.200156) (xy 104.860595 -218.173469) (xy 104.818865 -218.140191) (xy 104.782561 -218.101064)
			(xy 104.752494 -218.056964) (xy 104.729336 -218.008875) (xy 104.713604 -217.957872) (xy 104.705649 -217.905093)
			(xy 104.70515 -217.878406) (xy 104.478582 -217.878406) (xy 104.478198 -217.901745) (xy 104.472104 -217.948023)
			(xy 104.460009 -217.993106) (xy 104.451404 -218.014804) (xy 104.441752 -218.038172) (xy 104.61371 -218.335352)
			(xy 104.638602 -218.338654) (xy 104.663977 -218.342525) (xy 104.713359 -218.356524) (xy 104.760225 -218.377455)
			(xy 104.803607 -218.404887) (xy 104.84261 -218.438254) (xy 104.876428 -218.476866) (xy 104.904362 -218.519927)
			(xy 104.925837 -218.566546) (xy 104.940409 -218.615762) (xy 104.947776 -218.666558) (xy 104.948228 -218.692222)
			(xy 104.947729 -218.718909) (xy 104.939774 -218.771688) (xy 104.924042 -218.822691) (xy 104.900884 -218.87078)
			(xy 104.870817 -218.91488) (xy 104.834513 -218.954007) (xy 104.792783 -218.987285) (xy 104.746559 -219.013972)
			(xy 104.696874 -219.033472) (xy 104.644837 -219.045349) (xy 104.591612 -219.049338) (xy 104.538387 -219.045349)
			(xy 104.48635 -219.033472) (xy 104.436665 -219.013972) (xy 104.390441 -218.987285) (xy 104.348711 -218.954007)
			(xy 104.312407 -218.91488) (xy 104.28234 -218.87078) (xy 104.259182 -218.822691) (xy 104.24345 -218.771688)
			(xy 104.235495 -218.718909) (xy 104.234996 -218.692222) (xy 104.235351 -218.668882) (xy 104.241456 -218.622603)
			(xy 104.253563 -218.577521) (xy 104.262174 -218.555824) (xy 104.271826 -218.532456) (xy 104.099868 -218.235276)
			(xy 104.074976 -218.231974) (xy 104.049586 -218.22819) (xy 104.000198 -218.214184) (xy 103.953328 -218.193245)
			(xy 103.909943 -218.165803) (xy 103.87094 -218.132427) (xy 103.837123 -218.093804) (xy 103.809191 -218.050733)
			(xy 103.78772 -218.004104) (xy 103.773156 -217.954878) (xy 103.765797 -217.904074) (xy 103.76535 -217.878406)
			(xy 103.538782 -217.878406) (xy 103.538283 -217.905093) (xy 103.530328 -217.957872) (xy 103.514596 -218.008875)
			(xy 103.491438 -218.056964) (xy 103.461371 -218.101064) (xy 103.425067 -218.140191) (xy 103.383337 -218.173469)
			(xy 103.337113 -218.200156) (xy 103.287428 -218.219656) (xy 103.235391 -218.231533) (xy 103.182166 -218.235522)
			(xy 103.128941 -218.231533) (xy 103.076904 -218.219656) (xy 103.027219 -218.200156) (xy 102.980995 -218.173469)
			(xy 102.939265 -218.140191) (xy 102.902961 -218.101064) (xy 102.872894 -218.056964) (xy 102.849736 -218.008875)
			(xy 102.834004 -217.957872) (xy 102.826049 -217.905093) (xy 102.82555 -217.878406) (xy 102.598982 -217.878406)
			(xy 102.598598 -217.901745) (xy 102.592504 -217.948023) (xy 102.580409 -217.993106) (xy 102.571804 -218.014804)
			(xy 102.562152 -218.038172) (xy 102.73411 -218.335352) (xy 102.759002 -218.338654) (xy 102.784377 -218.342525)
			(xy 102.833759 -218.356524) (xy 102.880625 -218.377455) (xy 102.924007 -218.404887) (xy 102.96301 -218.438254)
			(xy 102.996828 -218.476866) (xy 103.024762 -218.519927) (xy 103.046237 -218.566546) (xy 103.060809 -218.615762)
			(xy 103.068176 -218.666558) (xy 103.068628 -218.692222) (xy 103.068129 -218.718909) (xy 103.060174 -218.771688)
			(xy 103.044442 -218.822691) (xy 103.021284 -218.87078) (xy 102.991217 -218.91488) (xy 102.954913 -218.954007)
			(xy 102.913183 -218.987285) (xy 102.866959 -219.013972) (xy 102.817274 -219.033472) (xy 102.765237 -219.045349)
			(xy 102.712012 -219.049338) (xy 102.658787 -219.045349) (xy 102.60675 -219.033472) (xy 102.557065 -219.013972)
			(xy 102.510841 -218.987285) (xy 102.469111 -218.954007) (xy 102.432807 -218.91488) (xy 102.40274 -218.87078)
			(xy 102.379582 -218.822691) (xy 102.36385 -218.771688) (xy 102.355895 -218.718909) (xy 102.355396 -218.692222)
			(xy 102.355751 -218.668882) (xy 102.361856 -218.622603) (xy 102.373963 -218.577521) (xy 102.382574 -218.555824)
			(xy 102.392226 -218.532456) (xy 102.220268 -218.235276) (xy 102.195376 -218.231974) (xy 102.169986 -218.22819)
			(xy 102.120598 -218.214184) (xy 102.073728 -218.193245) (xy 102.030343 -218.165803) (xy 101.99134 -218.132427)
			(xy 101.957523 -218.093804) (xy 101.929591 -218.050733) (xy 101.90812 -218.004104) (xy 101.893556 -217.954878)
			(xy 101.886197 -217.904074) (xy 101.88575 -217.878406) (xy 101.659182 -217.878406) (xy 101.658683 -217.905093)
			(xy 101.650728 -217.957872) (xy 101.634996 -218.008875) (xy 101.611838 -218.056964) (xy 101.581771 -218.101064)
			(xy 101.545467 -218.140191) (xy 101.503737 -218.173469) (xy 101.457513 -218.200156) (xy 101.407828 -218.219656)
			(xy 101.355791 -218.231533) (xy 101.302566 -218.235522) (xy 101.249341 -218.231533) (xy 101.197304 -218.219656)
			(xy 101.147619 -218.200156) (xy 101.101395 -218.173469) (xy 101.059665 -218.140191) (xy 101.023361 -218.101064)
			(xy 100.993294 -218.056964) (xy 100.970136 -218.008875) (xy 100.954404 -217.957872) (xy 100.946449 -217.905093)
			(xy 100.94595 -217.878406) (xy 100.719382 -217.878406) (xy 100.718998 -217.901745) (xy 100.712904 -217.948023)
			(xy 100.700809 -217.993106) (xy 100.692204 -218.014804) (xy 100.682552 -218.038172) (xy 100.85451 -218.335352)
			(xy 100.879402 -218.338654) (xy 100.904777 -218.342525) (xy 100.954159 -218.356524) (xy 101.001025 -218.377455)
			(xy 101.044407 -218.404887) (xy 101.08341 -218.438254) (xy 101.117228 -218.476866) (xy 101.145162 -218.519927)
			(xy 101.166637 -218.566546) (xy 101.181209 -218.615762) (xy 101.188576 -218.666558) (xy 101.189028 -218.692222)
			(xy 101.188529 -218.718909) (xy 101.180574 -218.771688) (xy 101.164842 -218.822691) (xy 101.141684 -218.87078)
			(xy 101.111617 -218.91488) (xy 101.075313 -218.954007) (xy 101.033583 -218.987285) (xy 100.987359 -219.013972)
			(xy 100.937674 -219.033472) (xy 100.885637 -219.045349) (xy 100.832412 -219.049338) (xy 100.779187 -219.045349)
			(xy 100.72715 -219.033472) (xy 100.677465 -219.013972) (xy 100.631241 -218.987285) (xy 100.589511 -218.954007)
			(xy 100.553207 -218.91488) (xy 100.52314 -218.87078) (xy 100.499982 -218.822691) (xy 100.48425 -218.771688)
			(xy 100.476295 -218.718909) (xy 100.475796 -218.692222) (xy 100.476151 -218.668882) (xy 100.482256 -218.622603)
			(xy 100.494363 -218.577521) (xy 100.502974 -218.555824) (xy 100.512626 -218.532456) (xy 100.340668 -218.235276)
			(xy 100.315776 -218.231974) (xy 100.290386 -218.22819) (xy 100.240998 -218.214184) (xy 100.194128 -218.193245)
			(xy 100.150743 -218.165803) (xy 100.11174 -218.132427) (xy 100.077923 -218.093804) (xy 100.049991 -218.050733)
			(xy 100.02852 -218.004104) (xy 100.013956 -217.954878) (xy 100.006597 -217.904074) (xy 100.00615 -217.878406)
			(xy 99.779582 -217.878406) (xy 99.779083 -217.905093) (xy 99.771128 -217.957872) (xy 99.755396 -218.008875)
			(xy 99.732238 -218.056964) (xy 99.702171 -218.101064) (xy 99.665867 -218.140191) (xy 99.624137 -218.173469)
			(xy 99.577913 -218.200156) (xy 99.528228 -218.219656) (xy 99.476191 -218.231533) (xy 99.422966 -218.235522)
			(xy 99.369741 -218.231533) (xy 99.317704 -218.219656) (xy 99.268019 -218.200156) (xy 99.221795 -218.173469)
			(xy 99.180065 -218.140191) (xy 99.143761 -218.101064) (xy 99.113694 -218.056964) (xy 99.090536 -218.008875)
			(xy 99.074804 -217.957872) (xy 99.066849 -217.905093) (xy 99.06635 -217.878406) (xy 98.839782 -217.878406)
			(xy 98.839398 -217.901745) (xy 98.833304 -217.948023) (xy 98.821209 -217.993106) (xy 98.812604 -218.014804)
			(xy 98.802952 -218.038172) (xy 98.97491 -218.335352) (xy 98.999802 -218.338654) (xy 99.025177 -218.342525)
			(xy 99.074559 -218.356524) (xy 99.121425 -218.377455) (xy 99.164807 -218.404887) (xy 99.20381 -218.438254)
			(xy 99.237628 -218.476866) (xy 99.265562 -218.519927) (xy 99.287037 -218.566546) (xy 99.301609 -218.615762)
			(xy 99.308976 -218.666558) (xy 99.309428 -218.692222) (xy 99.308929 -218.718909) (xy 99.300974 -218.771688)
			(xy 99.285242 -218.822691) (xy 99.262084 -218.87078) (xy 99.232017 -218.91488) (xy 99.195713 -218.954007)
			(xy 99.153983 -218.987285) (xy 99.107759 -219.013972) (xy 99.058074 -219.033472) (xy 99.006037 -219.045349)
			(xy 98.952812 -219.049338) (xy 98.899587 -219.045349) (xy 98.84755 -219.033472) (xy 98.797865 -219.013972)
			(xy 98.751641 -218.987285) (xy 98.709911 -218.954007) (xy 98.673607 -218.91488) (xy 98.64354 -218.87078)
			(xy 98.620382 -218.822691) (xy 98.60465 -218.771688) (xy 98.596695 -218.718909) (xy 98.596196 -218.692222)
			(xy 98.596551 -218.668882) (xy 98.602656 -218.622603) (xy 98.614763 -218.577521) (xy 98.623374 -218.555824)
			(xy 98.633026 -218.532456) (xy 98.461068 -218.235276) (xy 98.436176 -218.231974) (xy 98.410786 -218.22819)
			(xy 98.361398 -218.214184) (xy 98.314528 -218.193245) (xy 98.271143 -218.165803) (xy 98.23214 -218.132427)
			(xy 98.198323 -218.093804) (xy 98.170391 -218.050733) (xy 98.14892 -218.004104) (xy 98.134356 -217.954878)
			(xy 98.126997 -217.904074) (xy 98.12655 -217.878406) (xy 97.899982 -217.878406) (xy 97.899483 -217.905093)
			(xy 97.891528 -217.957872) (xy 97.875796 -218.008875) (xy 97.852638 -218.056964) (xy 97.822571 -218.101064)
			(xy 97.786267 -218.140191) (xy 97.744537 -218.173469) (xy 97.698313 -218.200156) (xy 97.648628 -218.219656)
			(xy 97.596591 -218.231533) (xy 97.543366 -218.235522) (xy 97.490141 -218.231533) (xy 97.438104 -218.219656)
			(xy 97.388419 -218.200156) (xy 97.342195 -218.173469) (xy 97.300465 -218.140191) (xy 97.264161 -218.101064)
			(xy 97.234094 -218.056964) (xy 97.210936 -218.008875) (xy 97.195204 -217.957872) (xy 97.187249 -217.905093)
			(xy 97.18675 -217.878406) (xy 96.960182 -217.878406) (xy 96.959798 -217.901745) (xy 96.953704 -217.948023)
			(xy 96.941609 -217.993106) (xy 96.933004 -218.014804) (xy 96.923352 -218.038172) (xy 97.09531 -218.335352)
			(xy 97.120202 -218.338654) (xy 97.145577 -218.342525) (xy 97.194959 -218.356524) (xy 97.241825 -218.377455)
			(xy 97.285207 -218.404887) (xy 97.32421 -218.438254) (xy 97.358028 -218.476866) (xy 97.385962 -218.519927)
			(xy 97.407437 -218.566546) (xy 97.422009 -218.615762) (xy 97.429376 -218.666558) (xy 97.429828 -218.692222)
			(xy 97.429329 -218.718909) (xy 97.421374 -218.771688) (xy 97.405642 -218.822691) (xy 97.382484 -218.87078)
			(xy 97.352417 -218.91488) (xy 97.316113 -218.954007) (xy 97.274383 -218.987285) (xy 97.228159 -219.013972)
			(xy 97.178474 -219.033472) (xy 97.126437 -219.045349) (xy 97.073212 -219.049338) (xy 97.019987 -219.045349)
			(xy 96.96795 -219.033472) (xy 96.918265 -219.013972) (xy 96.872041 -218.987285) (xy 96.830311 -218.954007)
			(xy 96.794007 -218.91488) (xy 96.76394 -218.87078) (xy 96.740782 -218.822691) (xy 96.72505 -218.771688)
			(xy 96.717095 -218.718909) (xy 96.716596 -218.692222) (xy 96.716951 -218.668882) (xy 96.723056 -218.622603)
			(xy 96.735163 -218.577521) (xy 96.743774 -218.555824) (xy 96.753426 -218.532456) (xy 96.581468 -218.235276)
			(xy 96.556576 -218.231974) (xy 96.531186 -218.22819) (xy 96.481798 -218.214184) (xy 96.434928 -218.193245)
			(xy 96.391543 -218.165803) (xy 96.35254 -218.132427) (xy 96.318723 -218.093804) (xy 96.290791 -218.050733)
			(xy 96.26932 -218.004104) (xy 96.254756 -217.954878) (xy 96.247397 -217.904074) (xy 96.24695 -217.878406)
			(xy 96.020382 -217.878406) (xy 96.019883 -217.905093) (xy 96.011928 -217.957872) (xy 95.996196 -218.008875)
			(xy 95.973038 -218.056964) (xy 95.942971 -218.101064) (xy 95.906667 -218.140191) (xy 95.864937 -218.173469)
			(xy 95.818713 -218.200156) (xy 95.769028 -218.219656) (xy 95.716991 -218.231533) (xy 95.663766 -218.235522)
			(xy 95.610541 -218.231533) (xy 95.558504 -218.219656) (xy 95.508819 -218.200156) (xy 95.462595 -218.173469)
			(xy 95.420865 -218.140191) (xy 95.384561 -218.101064) (xy 95.354494 -218.056964) (xy 95.331336 -218.008875)
			(xy 95.315604 -217.957872) (xy 95.307649 -217.905093) (xy 95.30715 -217.878406) (xy 95.080582 -217.878406)
			(xy 95.080198 -217.901745) (xy 95.074104 -217.948023) (xy 95.062009 -217.993106) (xy 95.053404 -218.014804)
			(xy 95.043752 -218.038172) (xy 95.21571 -218.335352) (xy 95.240602 -218.338654) (xy 95.265977 -218.342525)
			(xy 95.315359 -218.356524) (xy 95.362225 -218.377455) (xy 95.405607 -218.404887) (xy 95.44461 -218.438254)
			(xy 95.478428 -218.476866) (xy 95.506362 -218.519927) (xy 95.527837 -218.566546) (xy 95.542409 -218.615762)
			(xy 95.549776 -218.666558) (xy 95.550228 -218.692222) (xy 95.549729 -218.718909) (xy 95.541774 -218.771688)
			(xy 95.526042 -218.822691) (xy 95.502884 -218.87078) (xy 95.472817 -218.91488) (xy 95.436513 -218.954007)
			(xy 95.394783 -218.987285) (xy 95.348559 -219.013972) (xy 95.298874 -219.033472) (xy 95.246837 -219.045349)
			(xy 95.193612 -219.049338) (xy 95.140387 -219.045349) (xy 95.08835 -219.033472) (xy 95.038665 -219.013972)
			(xy 94.992441 -218.987285) (xy 94.950711 -218.954007) (xy 94.914407 -218.91488) (xy 94.88434 -218.87078)
			(xy 94.861182 -218.822691) (xy 94.84545 -218.771688) (xy 94.837495 -218.718909) (xy 94.836996 -218.692222)
			(xy 94.837351 -218.668882) (xy 94.843456 -218.622603) (xy 94.855563 -218.577521) (xy 94.864174 -218.555824)
			(xy 94.873826 -218.532456) (xy 94.701868 -218.235276) (xy 94.676976 -218.231974) (xy 94.651586 -218.22819)
			(xy 94.602198 -218.214184) (xy 94.555328 -218.193245) (xy 94.511943 -218.165803) (xy 94.47294 -218.132427)
			(xy 94.439123 -218.093804) (xy 94.411191 -218.050733) (xy 94.38972 -218.004104) (xy 94.375156 -217.954878)
			(xy 94.367797 -217.904074) (xy 94.36735 -217.878406) (xy 94.140782 -217.878406) (xy 94.140283 -217.905093)
			(xy 94.132328 -217.957872) (xy 94.116596 -218.008875) (xy 94.093438 -218.056964) (xy 94.063371 -218.101064)
			(xy 94.027067 -218.140191) (xy 93.985337 -218.173469) (xy 93.939113 -218.200156) (xy 93.889428 -218.219656)
			(xy 93.837391 -218.231533) (xy 93.784166 -218.235522) (xy 93.730941 -218.231533) (xy 93.678904 -218.219656)
			(xy 93.629219 -218.200156) (xy 93.582995 -218.173469) (xy 93.541265 -218.140191) (xy 93.504961 -218.101064)
			(xy 93.474894 -218.056964) (xy 93.451736 -218.008875) (xy 93.436004 -217.957872) (xy 93.428049 -217.905093)
			(xy 93.42755 -217.878406) (xy 93.200982 -217.878406) (xy 93.200598 -217.901745) (xy 93.194504 -217.948023)
			(xy 93.182409 -217.993106) (xy 93.173804 -218.014804) (xy 93.164152 -218.038172) (xy 93.33611 -218.335352)
			(xy 93.361002 -218.338654) (xy 93.386377 -218.342525) (xy 93.435759 -218.356524) (xy 93.482625 -218.377455)
			(xy 93.526007 -218.404887) (xy 93.56501 -218.438254) (xy 93.598828 -218.476866) (xy 93.626762 -218.519927)
			(xy 93.648237 -218.566546) (xy 93.662809 -218.615762) (xy 93.670176 -218.666558) (xy 93.670628 -218.692222)
			(xy 93.670129 -218.718909) (xy 93.662174 -218.771688) (xy 93.646442 -218.822691) (xy 93.623284 -218.87078)
			(xy 93.593217 -218.91488) (xy 93.556913 -218.954007) (xy 93.515183 -218.987285) (xy 93.468959 -219.013972)
			(xy 93.419274 -219.033472) (xy 93.367237 -219.045349) (xy 93.314012 -219.049338) (xy 93.260787 -219.045349)
			(xy 93.20875 -219.033472) (xy 93.159065 -219.013972) (xy 93.112841 -218.987285) (xy 93.071111 -218.954007)
			(xy 93.034807 -218.91488) (xy 93.00474 -218.87078) (xy 92.981582 -218.822691) (xy 92.96585 -218.771688)
			(xy 92.957895 -218.718909) (xy 92.957396 -218.692222) (xy 92.957751 -218.668882) (xy 92.963856 -218.622603)
			(xy 92.975963 -218.577521) (xy 92.984574 -218.555824) (xy 92.994226 -218.532456) (xy 92.822268 -218.235276)
			(xy 92.797376 -218.231974) (xy 92.771986 -218.22819) (xy 92.722598 -218.214184) (xy 92.675728 -218.193245)
			(xy 92.632343 -218.165803) (xy 92.59334 -218.132427) (xy 92.559523 -218.093804) (xy 92.531591 -218.050733)
			(xy 92.51012 -218.004104) (xy 92.495556 -217.954878) (xy 92.488197 -217.904074) (xy 92.48775 -217.878406)
			(xy 92.261182 -217.878406) (xy 92.260683 -217.905093) (xy 92.252728 -217.957872) (xy 92.236996 -218.008875)
			(xy 92.213838 -218.056964) (xy 92.183771 -218.101064) (xy 92.147467 -218.140191) (xy 92.105737 -218.173469)
			(xy 92.059513 -218.200156) (xy 92.009828 -218.219656) (xy 91.957791 -218.231533) (xy 91.904566 -218.235522)
			(xy 91.851341 -218.231533) (xy 91.799304 -218.219656) (xy 91.749619 -218.200156) (xy 91.703395 -218.173469)
			(xy 91.661665 -218.140191) (xy 91.625361 -218.101064) (xy 91.595294 -218.056964) (xy 91.572136 -218.008875)
			(xy 91.556404 -217.957872) (xy 91.548449 -217.905093) (xy 91.54795 -217.878406) (xy 91.321382 -217.878406)
			(xy 91.320998 -217.901745) (xy 91.314904 -217.948023) (xy 91.302809 -217.993106) (xy 91.294204 -218.014804)
			(xy 91.284552 -218.038172) (xy 91.45651 -218.335352) (xy 91.481402 -218.338654) (xy 91.506777 -218.342525)
			(xy 91.556159 -218.356524) (xy 91.603025 -218.377455) (xy 91.646407 -218.404887) (xy 91.68541 -218.438254)
			(xy 91.719228 -218.476866) (xy 91.747162 -218.519927) (xy 91.768637 -218.566546) (xy 91.783209 -218.615762)
			(xy 91.790576 -218.666558) (xy 91.791028 -218.692222) (xy 91.790529 -218.718909) (xy 91.782574 -218.771688)
			(xy 91.766842 -218.822691) (xy 91.743684 -218.87078) (xy 91.713617 -218.91488) (xy 91.677313 -218.954007)
			(xy 91.635583 -218.987285) (xy 91.589359 -219.013972) (xy 91.539674 -219.033472) (xy 91.487637 -219.045349)
			(xy 91.434412 -219.049338) (xy 91.381187 -219.045349) (xy 91.32915 -219.033472) (xy 91.279465 -219.013972)
			(xy 91.233241 -218.987285) (xy 91.191511 -218.954007) (xy 91.155207 -218.91488) (xy 91.12514 -218.87078)
			(xy 91.101982 -218.822691) (xy 91.08625 -218.771688) (xy 91.078295 -218.718909) (xy 91.077796 -218.692222)
			(xy 91.078151 -218.668882) (xy 91.084256 -218.622603) (xy 91.096363 -218.577521) (xy 91.104974 -218.555824)
			(xy 91.114626 -218.532456) (xy 90.942668 -218.235276) (xy 90.917776 -218.231974) (xy 90.892386 -218.22819)
			(xy 90.842998 -218.214184) (xy 90.796128 -218.193245) (xy 90.752743 -218.165803) (xy 90.71374 -218.132427)
			(xy 90.679923 -218.093804) (xy 90.651991 -218.050733) (xy 90.63052 -218.004104) (xy 90.615956 -217.954878)
			(xy 90.608597 -217.904074) (xy 90.60815 -217.878406) (xy 90.381582 -217.878406) (xy 90.381083 -217.905093)
			(xy 90.373128 -217.957872) (xy 90.357396 -218.008875) (xy 90.334238 -218.056964) (xy 90.304171 -218.101064)
			(xy 90.267867 -218.140191) (xy 90.226137 -218.173469) (xy 90.179913 -218.200156) (xy 90.130228 -218.219656)
			(xy 90.078191 -218.231533) (xy 90.024966 -218.235522) (xy 89.971741 -218.231533) (xy 89.919704 -218.219656)
			(xy 89.870019 -218.200156) (xy 89.823795 -218.173469) (xy 89.782065 -218.140191) (xy 89.745761 -218.101064)
			(xy 89.715694 -218.056964) (xy 89.692536 -218.008875) (xy 89.676804 -217.957872) (xy 89.668849 -217.905093)
			(xy 89.66835 -217.878406) (xy 89.441782 -217.878406) (xy 89.441398 -217.901745) (xy 89.435304 -217.948023)
			(xy 89.423209 -217.993106) (xy 89.414604 -218.014804) (xy 89.404952 -218.038172) (xy 89.57691 -218.335352)
			(xy 89.601802 -218.338654) (xy 89.627177 -218.342525) (xy 89.676559 -218.356524) (xy 89.723425 -218.377455)
			(xy 89.766807 -218.404887) (xy 89.80581 -218.438254) (xy 89.839628 -218.476866) (xy 89.867562 -218.519927)
			(xy 89.889037 -218.566546) (xy 89.903609 -218.615762) (xy 89.910976 -218.666558) (xy 89.911428 -218.692222)
			(xy 89.910929 -218.718909) (xy 89.902974 -218.771688) (xy 89.887242 -218.822691) (xy 89.864084 -218.87078)
			(xy 89.834017 -218.91488) (xy 89.797713 -218.954007) (xy 89.755983 -218.987285) (xy 89.709759 -219.013972)
			(xy 89.660074 -219.033472) (xy 89.608037 -219.045349) (xy 89.554812 -219.049338) (xy 89.501587 -219.045349)
			(xy 89.44955 -219.033472) (xy 89.399865 -219.013972) (xy 89.353641 -218.987285) (xy 89.311911 -218.954007)
			(xy 89.275607 -218.91488) (xy 89.24554 -218.87078) (xy 89.222382 -218.822691) (xy 89.20665 -218.771688)
			(xy 89.198695 -218.718909) (xy 89.198196 -218.692222) (xy 89.198551 -218.668882) (xy 89.204656 -218.622603)
			(xy 89.216763 -218.577521) (xy 89.225374 -218.555824) (xy 89.235026 -218.532456) (xy 89.063068 -218.235276)
			(xy 89.038176 -218.231974) (xy 89.012786 -218.22819) (xy 88.963398 -218.214184) (xy 88.916528 -218.193245)
			(xy 88.873143 -218.165803) (xy 88.83414 -218.132427) (xy 88.800323 -218.093804) (xy 88.772391 -218.050733)
			(xy 88.75092 -218.004104) (xy 88.736356 -217.954878) (xy 88.728997 -217.904074) (xy 88.72855 -217.878406)
			(xy 2.509012 -217.878406) (xy 2.509012 -221.133924) (xy 88.755728 -221.133924) (xy 88.756236 -221.108037)
			(xy 88.764335 -221.056899) (xy 88.780334 -221.007659) (xy 88.80384 -220.961527) (xy 88.834272 -220.91964)
			(xy 88.870882 -220.88303) (xy 88.912769 -220.852598) (xy 88.958901 -220.829092) (xy 89.008141 -220.813093)
			(xy 89.059279 -220.804994) (xy 89.111053 -220.804994) (xy 89.162191 -220.813093) (xy 89.211431 -220.829092)
			(xy 89.257563 -220.852598) (xy 89.29945 -220.88303) (xy 89.33606 -220.91964) (xy 89.366492 -220.961527)
			(xy 89.389998 -221.007659) (xy 89.405997 -221.056899) (xy 89.414096 -221.108037) (xy 89.414604 -221.133924)
			(xy 89.695528 -221.133924) (xy 89.69601 -221.108589) (xy 89.70376 -221.058515) (xy 89.71908 -221.010217)
			(xy 89.741611 -220.964832) (xy 89.770821 -220.923429) (xy 89.806022 -220.886984) (xy 89.846386 -220.856354)
			(xy 89.890961 -220.83226) (xy 89.938698 -220.815272) (xy 89.963498 -220.810074) (xy 89.986358 -220.805756)
			(xy 90.191336 -220.450664) (xy 90.183462 -220.42882) (xy 90.174829 -220.402408) (xy 90.1655 -220.347635)
			(xy 90.16492 -220.319854) (xy 90.165428 -220.293947) (xy 90.173534 -220.24277) (xy 90.189546 -220.193491)
			(xy 90.213069 -220.147324) (xy 90.243525 -220.105405) (xy 90.280163 -220.068767) (xy 90.322082 -220.038311)
			(xy 90.368249 -220.014788) (xy 90.417528 -219.998776) (xy 90.468705 -219.99067) (xy 90.520519 -219.99067)
			(xy 90.571696 -219.998776) (xy 90.620975 -220.014788) (xy 90.667142 -220.038311) (xy 90.709061 -220.068767)
			(xy 90.745699 -220.105405) (xy 90.776155 -220.147324) (xy 90.799678 -220.193491) (xy 90.81569 -220.24277)
			(xy 90.823796 -220.293947) (xy 90.824304 -220.319854) (xy 90.823828 -220.345199) (xy 90.816049 -220.395289)
			(xy 90.800697 -220.443599) (xy 90.778134 -220.48899) (xy 90.748891 -220.530396) (xy 90.713657 -220.566839)
			(xy 90.673262 -220.597461) (xy 90.628657 -220.621543) (xy 90.580893 -220.638516) (xy 90.55608 -220.643704)
			(xy 90.53322 -220.648022) (xy 90.328242 -221.003114) (xy 90.336116 -221.024958) (xy 90.34471 -221.051373)
			(xy 90.353897 -221.106151) (xy 90.354404 -221.133924) (xy 90.635328 -221.133924) (xy 90.635836 -221.108037)
			(xy 90.643935 -221.056899) (xy 90.659934 -221.007659) (xy 90.68344 -220.961527) (xy 90.713872 -220.91964)
			(xy 90.750482 -220.88303) (xy 90.792369 -220.852598) (xy 90.838501 -220.829092) (xy 90.887741 -220.813093)
			(xy 90.938879 -220.804994) (xy 90.990653 -220.804994) (xy 91.041791 -220.813093) (xy 91.091031 -220.829092)
			(xy 91.137163 -220.852598) (xy 91.17905 -220.88303) (xy 91.21566 -220.91964) (xy 91.246092 -220.961527)
			(xy 91.269598 -221.007659) (xy 91.285597 -221.056899) (xy 91.293696 -221.108037) (xy 91.294204 -221.133924)
			(xy 91.575128 -221.133924) (xy 91.57561 -221.108589) (xy 91.58336 -221.058515) (xy 91.59868 -221.010217)
			(xy 91.621211 -220.964832) (xy 91.650421 -220.923429) (xy 91.685622 -220.886984) (xy 91.725986 -220.856354)
			(xy 91.770561 -220.83226) (xy 91.818298 -220.815272) (xy 91.843098 -220.810074) (xy 91.865958 -220.805756)
			(xy 92.070936 -220.450664) (xy 92.063062 -220.42882) (xy 92.054429 -220.402408) (xy 92.0451 -220.347635)
			(xy 92.04452 -220.319854) (xy 92.045028 -220.293947) (xy 92.053134 -220.24277) (xy 92.069146 -220.193491)
			(xy 92.092669 -220.147324) (xy 92.123125 -220.105405) (xy 92.159763 -220.068767) (xy 92.201682 -220.038311)
			(xy 92.247849 -220.014788) (xy 92.297128 -219.998776) (xy 92.348305 -219.99067) (xy 92.400119 -219.99067)
			(xy 92.451296 -219.998776) (xy 92.500575 -220.014788) (xy 92.546742 -220.038311) (xy 92.588661 -220.068767)
			(xy 92.625299 -220.105405) (xy 92.655755 -220.147324) (xy 92.679278 -220.193491) (xy 92.69529 -220.24277)
			(xy 92.703396 -220.293947) (xy 92.703904 -220.319854) (xy 92.703428 -220.345199) (xy 92.695649 -220.395289)
			(xy 92.680297 -220.443599) (xy 92.657734 -220.48899) (xy 92.628491 -220.530396) (xy 92.593257 -220.566839)
			(xy 92.552862 -220.597461) (xy 92.508257 -220.621543) (xy 92.460493 -220.638516) (xy 92.43568 -220.643704)
			(xy 92.41282 -220.648022) (xy 92.207842 -221.003114) (xy 92.215716 -221.024958) (xy 92.22431 -221.051373)
			(xy 92.233497 -221.106151) (xy 92.234004 -221.133924) (xy 92.514928 -221.133924) (xy 92.515436 -221.108037)
			(xy 92.523535 -221.056899) (xy 92.539534 -221.007659) (xy 92.56304 -220.961527) (xy 92.593472 -220.91964)
			(xy 92.630082 -220.88303) (xy 92.671969 -220.852598) (xy 92.718101 -220.829092) (xy 92.767341 -220.813093)
			(xy 92.818479 -220.804994) (xy 92.870253 -220.804994) (xy 92.921391 -220.813093) (xy 92.970631 -220.829092)
			(xy 93.016763 -220.852598) (xy 93.05865 -220.88303) (xy 93.09526 -220.91964) (xy 93.125692 -220.961527)
			(xy 93.149198 -221.007659) (xy 93.165197 -221.056899) (xy 93.173296 -221.108037) (xy 93.173804 -221.133924)
			(xy 93.454728 -221.133924) (xy 93.45521 -221.108589) (xy 93.46296 -221.058515) (xy 93.47828 -221.010217)
			(xy 93.500811 -220.964832) (xy 93.530021 -220.923429) (xy 93.565222 -220.886984) (xy 93.605586 -220.856354)
			(xy 93.650161 -220.83226) (xy 93.697898 -220.815272) (xy 93.722698 -220.810074) (xy 93.745558 -220.805756)
			(xy 93.950536 -220.450664) (xy 93.942662 -220.42882) (xy 93.934029 -220.402408) (xy 93.9247 -220.347635)
			(xy 93.92412 -220.319854) (xy 93.924628 -220.293947) (xy 93.932734 -220.24277) (xy 93.948746 -220.193491)
			(xy 93.972269 -220.147324) (xy 94.002725 -220.105405) (xy 94.039363 -220.068767) (xy 94.081282 -220.038311)
			(xy 94.127449 -220.014788) (xy 94.176728 -219.998776) (xy 94.227905 -219.99067) (xy 94.279719 -219.99067)
			(xy 94.330896 -219.998776) (xy 94.380175 -220.014788) (xy 94.426342 -220.038311) (xy 94.468261 -220.068767)
			(xy 94.504899 -220.105405) (xy 94.535355 -220.147324) (xy 94.558878 -220.193491) (xy 94.57489 -220.24277)
			(xy 94.582996 -220.293947) (xy 94.583504 -220.319854) (xy 94.583028 -220.345199) (xy 94.575249 -220.395289)
			(xy 94.559897 -220.443599) (xy 94.537334 -220.48899) (xy 94.508091 -220.530396) (xy 94.472857 -220.566839)
			(xy 94.432462 -220.597461) (xy 94.387857 -220.621543) (xy 94.340093 -220.638516) (xy 94.31528 -220.643704)
			(xy 94.29242 -220.648022) (xy 94.087442 -221.003114) (xy 94.095316 -221.024958) (xy 94.10391 -221.051373)
			(xy 94.113097 -221.106151) (xy 94.113604 -221.133924) (xy 94.394528 -221.133924) (xy 94.395036 -221.108037)
			(xy 94.403135 -221.056899) (xy 94.419134 -221.007659) (xy 94.44264 -220.961527) (xy 94.473072 -220.91964)
			(xy 94.509682 -220.88303) (xy 94.551569 -220.852598) (xy 94.597701 -220.829092) (xy 94.646941 -220.813093)
			(xy 94.698079 -220.804994) (xy 94.749853 -220.804994) (xy 94.800991 -220.813093) (xy 94.850231 -220.829092)
			(xy 94.896363 -220.852598) (xy 94.93825 -220.88303) (xy 94.97486 -220.91964) (xy 95.005292 -220.961527)
			(xy 95.028798 -221.007659) (xy 95.044797 -221.056899) (xy 95.052896 -221.108037) (xy 95.053404 -221.133924)
			(xy 95.334328 -221.133924) (xy 95.33481 -221.108589) (xy 95.34256 -221.058515) (xy 95.35788 -221.010217)
			(xy 95.380411 -220.964832) (xy 95.409621 -220.923429) (xy 95.444822 -220.886984) (xy 95.485186 -220.856354)
			(xy 95.529761 -220.83226) (xy 95.577498 -220.815272) (xy 95.602298 -220.810074) (xy 95.625158 -220.805756)
			(xy 95.830136 -220.450664) (xy 95.822262 -220.42882) (xy 95.813629 -220.402408) (xy 95.8043 -220.347635)
			(xy 95.80372 -220.319854) (xy 95.804228 -220.293947) (xy 95.812334 -220.24277) (xy 95.828346 -220.193491)
			(xy 95.851869 -220.147324) (xy 95.882325 -220.105405) (xy 95.918963 -220.068767) (xy 95.960882 -220.038311)
			(xy 96.007049 -220.014788) (xy 96.056328 -219.998776) (xy 96.107505 -219.99067) (xy 96.159319 -219.99067)
			(xy 96.210496 -219.998776) (xy 96.259775 -220.014788) (xy 96.305942 -220.038311) (xy 96.347861 -220.068767)
			(xy 96.384499 -220.105405) (xy 96.414955 -220.147324) (xy 96.438478 -220.193491) (xy 96.45449 -220.24277)
			(xy 96.462596 -220.293947) (xy 96.463104 -220.319854) (xy 96.462628 -220.345199) (xy 96.454849 -220.395289)
			(xy 96.439497 -220.443599) (xy 96.416934 -220.48899) (xy 96.387691 -220.530396) (xy 96.352457 -220.566839)
			(xy 96.312062 -220.597461) (xy 96.267457 -220.621543) (xy 96.219693 -220.638516) (xy 96.19488 -220.643704)
			(xy 96.17202 -220.648022) (xy 95.967042 -221.003114) (xy 95.974916 -221.024958) (xy 95.98351 -221.051373)
			(xy 95.992697 -221.106151) (xy 95.993204 -221.133924) (xy 96.274128 -221.133924) (xy 96.274636 -221.108037)
			(xy 96.282735 -221.056899) (xy 96.298734 -221.007659) (xy 96.32224 -220.961527) (xy 96.352672 -220.91964)
			(xy 96.389282 -220.88303) (xy 96.431169 -220.852598) (xy 96.477301 -220.829092) (xy 96.526541 -220.813093)
			(xy 96.577679 -220.804994) (xy 96.629453 -220.804994) (xy 96.680591 -220.813093) (xy 96.729831 -220.829092)
			(xy 96.775963 -220.852598) (xy 96.81785 -220.88303) (xy 96.85446 -220.91964) (xy 96.884892 -220.961527)
			(xy 96.908398 -221.007659) (xy 96.924397 -221.056899) (xy 96.932496 -221.108037) (xy 96.933004 -221.133924)
			(xy 97.213928 -221.133924) (xy 97.21441 -221.108589) (xy 97.22216 -221.058515) (xy 97.23748 -221.010217)
			(xy 97.260011 -220.964832) (xy 97.289221 -220.923429) (xy 97.324422 -220.886984) (xy 97.364786 -220.856354)
			(xy 97.409361 -220.83226) (xy 97.457098 -220.815272) (xy 97.481898 -220.810074) (xy 97.504758 -220.805756)
			(xy 97.709736 -220.450664) (xy 97.701862 -220.42882) (xy 97.693229 -220.402408) (xy 97.6839 -220.347635)
			(xy 97.68332 -220.319854) (xy 97.683828 -220.293947) (xy 97.691934 -220.24277) (xy 97.707946 -220.193491)
			(xy 97.731469 -220.147324) (xy 97.761925 -220.105405) (xy 97.798563 -220.068767) (xy 97.840482 -220.038311)
			(xy 97.886649 -220.014788) (xy 97.935928 -219.998776) (xy 97.987105 -219.99067) (xy 98.038919 -219.99067)
			(xy 98.090096 -219.998776) (xy 98.139375 -220.014788) (xy 98.185542 -220.038311) (xy 98.227461 -220.068767)
			(xy 98.264099 -220.105405) (xy 98.294555 -220.147324) (xy 98.318078 -220.193491) (xy 98.33409 -220.24277)
			(xy 98.342196 -220.293947) (xy 98.342704 -220.319854) (xy 98.342228 -220.345199) (xy 98.334449 -220.395289)
			(xy 98.319097 -220.443599) (xy 98.296534 -220.48899) (xy 98.267291 -220.530396) (xy 98.232057 -220.566839)
			(xy 98.191662 -220.597461) (xy 98.147057 -220.621543) (xy 98.099293 -220.638516) (xy 98.07448 -220.643704)
			(xy 98.05162 -220.648022) (xy 97.846642 -221.003114) (xy 97.854516 -221.024958) (xy 97.86311 -221.051373)
			(xy 97.872297 -221.106151) (xy 97.872804 -221.133924) (xy 98.153728 -221.133924) (xy 98.154236 -221.108037)
			(xy 98.162335 -221.056899) (xy 98.178334 -221.007659) (xy 98.20184 -220.961527) (xy 98.232272 -220.91964)
			(xy 98.268882 -220.88303) (xy 98.310769 -220.852598) (xy 98.356901 -220.829092) (xy 98.406141 -220.813093)
			(xy 98.457279 -220.804994) (xy 98.509053 -220.804994) (xy 98.560191 -220.813093) (xy 98.609431 -220.829092)
			(xy 98.655563 -220.852598) (xy 98.69745 -220.88303) (xy 98.73406 -220.91964) (xy 98.764492 -220.961527)
			(xy 98.787998 -221.007659) (xy 98.803997 -221.056899) (xy 98.812096 -221.108037) (xy 98.812604 -221.133924)
			(xy 99.093528 -221.133924) (xy 99.09401 -221.108589) (xy 99.10176 -221.058515) (xy 99.11708 -221.010217)
			(xy 99.139611 -220.964832) (xy 99.168821 -220.923429) (xy 99.204022 -220.886984) (xy 99.244386 -220.856354)
			(xy 99.288961 -220.83226) (xy 99.336698 -220.815272) (xy 99.361498 -220.810074) (xy 99.384358 -220.805756)
			(xy 99.589336 -220.450664) (xy 99.581462 -220.42882) (xy 99.572829 -220.402408) (xy 99.5635 -220.347635)
			(xy 99.56292 -220.319854) (xy 99.563428 -220.293947) (xy 99.571534 -220.24277) (xy 99.587546 -220.193491)
			(xy 99.611069 -220.147324) (xy 99.641525 -220.105405) (xy 99.678163 -220.068767) (xy 99.720082 -220.038311)
			(xy 99.766249 -220.014788) (xy 99.815528 -219.998776) (xy 99.866705 -219.99067) (xy 99.918519 -219.99067)
			(xy 99.969696 -219.998776) (xy 100.018975 -220.014788) (xy 100.065142 -220.038311) (xy 100.107061 -220.068767)
			(xy 100.143699 -220.105405) (xy 100.174155 -220.147324) (xy 100.197678 -220.193491) (xy 100.21369 -220.24277)
			(xy 100.221796 -220.293947) (xy 100.222304 -220.319854) (xy 100.221828 -220.345199) (xy 100.214049 -220.395289)
			(xy 100.198697 -220.443599) (xy 100.176134 -220.48899) (xy 100.146891 -220.530396) (xy 100.111657 -220.566839)
			(xy 100.071262 -220.597461) (xy 100.026657 -220.621543) (xy 99.978893 -220.638516) (xy 99.95408 -220.643704)
			(xy 99.93122 -220.648022) (xy 99.726242 -221.003114) (xy 99.734116 -221.024958) (xy 99.74271 -221.051373)
			(xy 99.751897 -221.106151) (xy 99.752404 -221.133924) (xy 100.033328 -221.133924) (xy 100.033836 -221.108037)
			(xy 100.041935 -221.056899) (xy 100.057934 -221.007659) (xy 100.08144 -220.961527) (xy 100.111872 -220.91964)
			(xy 100.148482 -220.88303) (xy 100.190369 -220.852598) (xy 100.236501 -220.829092) (xy 100.285741 -220.813093)
			(xy 100.336879 -220.804994) (xy 100.388653 -220.804994) (xy 100.439791 -220.813093) (xy 100.489031 -220.829092)
			(xy 100.535163 -220.852598) (xy 100.57705 -220.88303) (xy 100.61366 -220.91964) (xy 100.644092 -220.961527)
			(xy 100.667598 -221.007659) (xy 100.683597 -221.056899) (xy 100.691696 -221.108037) (xy 100.692204 -221.133924)
			(xy 100.973128 -221.133924) (xy 100.97361 -221.108589) (xy 100.98136 -221.058515) (xy 100.99668 -221.010217)
			(xy 101.019211 -220.964832) (xy 101.048421 -220.923429) (xy 101.083622 -220.886984) (xy 101.123986 -220.856354)
			(xy 101.168561 -220.83226) (xy 101.216298 -220.815272) (xy 101.241098 -220.810074) (xy 101.263958 -220.805756)
			(xy 101.468936 -220.450664) (xy 101.461062 -220.42882) (xy 101.452429 -220.402408) (xy 101.4431 -220.347635)
			(xy 101.44252 -220.319854) (xy 101.443028 -220.293947) (xy 101.451134 -220.24277) (xy 101.467146 -220.193491)
			(xy 101.490669 -220.147324) (xy 101.521125 -220.105405) (xy 101.557763 -220.068767) (xy 101.599682 -220.038311)
			(xy 101.645849 -220.014788) (xy 101.695128 -219.998776) (xy 101.746305 -219.99067) (xy 101.798119 -219.99067)
			(xy 101.849296 -219.998776) (xy 101.898575 -220.014788) (xy 101.944742 -220.038311) (xy 101.986661 -220.068767)
			(xy 102.023299 -220.105405) (xy 102.053755 -220.147324) (xy 102.077278 -220.193491) (xy 102.09329 -220.24277)
			(xy 102.101396 -220.293947) (xy 102.101904 -220.319854) (xy 102.101428 -220.345199) (xy 102.093649 -220.395289)
			(xy 102.078297 -220.443599) (xy 102.055734 -220.48899) (xy 102.026491 -220.530396) (xy 101.991257 -220.566839)
			(xy 101.950862 -220.597461) (xy 101.906257 -220.621543) (xy 101.858493 -220.638516) (xy 101.83368 -220.643704)
			(xy 101.81082 -220.648022) (xy 101.605842 -221.003114) (xy 101.613716 -221.024958) (xy 101.62231 -221.051373)
			(xy 101.631497 -221.106151) (xy 101.632004 -221.133924) (xy 101.912928 -221.133924) (xy 101.913436 -221.108037)
			(xy 101.921535 -221.056899) (xy 101.937534 -221.007659) (xy 101.96104 -220.961527) (xy 101.991472 -220.91964)
			(xy 102.028082 -220.88303) (xy 102.069969 -220.852598) (xy 102.116101 -220.829092) (xy 102.165341 -220.813093)
			(xy 102.216479 -220.804994) (xy 102.268253 -220.804994) (xy 102.319391 -220.813093) (xy 102.368631 -220.829092)
			(xy 102.414763 -220.852598) (xy 102.45665 -220.88303) (xy 102.49326 -220.91964) (xy 102.523692 -220.961527)
			(xy 102.547198 -221.007659) (xy 102.563197 -221.056899) (xy 102.571296 -221.108037) (xy 102.571804 -221.133924)
			(xy 102.852728 -221.133924) (xy 102.85321 -221.108589) (xy 102.86096 -221.058515) (xy 102.87628 -221.010217)
			(xy 102.898811 -220.964832) (xy 102.928021 -220.923429) (xy 102.963222 -220.886984) (xy 103.003586 -220.856354)
			(xy 103.048161 -220.83226) (xy 103.095898 -220.815272) (xy 103.120698 -220.810074) (xy 103.143558 -220.805756)
			(xy 103.348536 -220.450664) (xy 103.340662 -220.42882) (xy 103.332029 -220.402408) (xy 103.3227 -220.347635)
			(xy 103.32212 -220.319854) (xy 103.322628 -220.293947) (xy 103.330734 -220.24277) (xy 103.346746 -220.193491)
			(xy 103.370269 -220.147324) (xy 103.400725 -220.105405) (xy 103.437363 -220.068767) (xy 103.479282 -220.038311)
			(xy 103.525449 -220.014788) (xy 103.574728 -219.998776) (xy 103.625905 -219.99067) (xy 103.677719 -219.99067)
			(xy 103.728896 -219.998776) (xy 103.778175 -220.014788) (xy 103.824342 -220.038311) (xy 103.866261 -220.068767)
			(xy 103.902899 -220.105405) (xy 103.933355 -220.147324) (xy 103.956878 -220.193491) (xy 103.97289 -220.24277)
			(xy 103.980996 -220.293947) (xy 103.981504 -220.319854) (xy 105.20172 -220.319854) (xy 105.202228 -220.293947)
			(xy 105.210334 -220.24277) (xy 105.226346 -220.193491) (xy 105.249869 -220.147324) (xy 105.280325 -220.105405)
			(xy 105.316963 -220.068767) (xy 105.358882 -220.038311) (xy 105.405049 -220.014788) (xy 105.454328 -219.998776)
			(xy 105.505505 -219.99067) (xy 105.557319 -219.99067) (xy 105.608496 -219.998776) (xy 105.657775 -220.014788)
			(xy 105.703942 -220.038311) (xy 105.745861 -220.068767) (xy 105.782499 -220.105405) (xy 105.812955 -220.147324)
			(xy 105.836478 -220.193491) (xy 105.85249 -220.24277) (xy 105.860596 -220.293947) (xy 105.861104 -220.319854)
			(xy 107.08132 -220.319854) (xy 107.081828 -220.293947) (xy 107.089934 -220.24277) (xy 107.105946 -220.193491)
			(xy 107.129469 -220.147324) (xy 107.159925 -220.105405) (xy 107.196563 -220.068767) (xy 107.238482 -220.038311)
			(xy 107.284649 -220.014788) (xy 107.333928 -219.998776) (xy 107.385105 -219.99067) (xy 107.436919 -219.99067)
			(xy 107.488096 -219.998776) (xy 107.537375 -220.014788) (xy 107.583542 -220.038311) (xy 107.625461 -220.068767)
			(xy 107.662099 -220.105405) (xy 107.692555 -220.147324) (xy 107.716078 -220.193491) (xy 107.73209 -220.24277)
			(xy 107.740196 -220.293947) (xy 107.740704 -220.319854) (xy 108.96092 -220.319854) (xy 108.961428 -220.293947)
			(xy 108.969534 -220.24277) (xy 108.985546 -220.193491) (xy 109.009069 -220.147324) (xy 109.039525 -220.105405)
			(xy 109.076163 -220.068767) (xy 109.118082 -220.038311) (xy 109.164249 -220.014788) (xy 109.213528 -219.998776)
			(xy 109.264705 -219.99067) (xy 109.316519 -219.99067) (xy 109.367696 -219.998776) (xy 109.416975 -220.014788)
			(xy 109.463142 -220.038311) (xy 109.505061 -220.068767) (xy 109.541699 -220.105405) (xy 109.572155 -220.147324)
			(xy 109.595678 -220.193491) (xy 109.61169 -220.24277) (xy 109.619796 -220.293947) (xy 109.620304 -220.319854)
			(xy 110.84052 -220.319854) (xy 110.841028 -220.293947) (xy 110.849134 -220.24277) (xy 110.865146 -220.193491)
			(xy 110.888669 -220.147324) (xy 110.919125 -220.105405) (xy 110.955763 -220.068767) (xy 110.997682 -220.038311)
			(xy 111.043849 -220.014788) (xy 111.093128 -219.998776) (xy 111.144305 -219.99067) (xy 111.196119 -219.99067)
			(xy 111.247296 -219.998776) (xy 111.296575 -220.014788) (xy 111.342742 -220.038311) (xy 111.384661 -220.068767)
			(xy 111.421299 -220.105405) (xy 111.451755 -220.147324) (xy 111.475278 -220.193491) (xy 111.49129 -220.24277)
			(xy 111.499396 -220.293947) (xy 111.499904 -220.319854) (xy 112.72012 -220.319854) (xy 112.720628 -220.293947)
			(xy 112.728734 -220.24277) (xy 112.744746 -220.193491) (xy 112.768269 -220.147324) (xy 112.798725 -220.105405)
			(xy 112.835363 -220.068767) (xy 112.877282 -220.038311) (xy 112.923449 -220.014788) (xy 112.972728 -219.998776)
			(xy 113.023905 -219.99067) (xy 113.075719 -219.99067) (xy 113.126896 -219.998776) (xy 113.176175 -220.014788)
			(xy 113.222342 -220.038311) (xy 113.264261 -220.068767) (xy 113.300899 -220.105405) (xy 113.331355 -220.147324)
			(xy 113.354878 -220.193491) (xy 113.37089 -220.24277) (xy 113.378996 -220.293947) (xy 113.379504 -220.319854)
			(xy 114.59972 -220.319854) (xy 114.600228 -220.293947) (xy 114.608334 -220.24277) (xy 114.624346 -220.193491)
			(xy 114.647869 -220.147324) (xy 114.678325 -220.105405) (xy 114.714963 -220.068767) (xy 114.756882 -220.038311)
			(xy 114.803049 -220.014788) (xy 114.852328 -219.998776) (xy 114.903505 -219.99067) (xy 114.955319 -219.99067)
			(xy 115.006496 -219.998776) (xy 115.055775 -220.014788) (xy 115.101942 -220.038311) (xy 115.143861 -220.068767)
			(xy 115.180499 -220.105405) (xy 115.210955 -220.147324) (xy 115.234478 -220.193491) (xy 115.25049 -220.24277)
			(xy 115.258596 -220.293947) (xy 115.259104 -220.319854) (xy 116.47932 -220.319854) (xy 116.479828 -220.293947)
			(xy 116.487934 -220.24277) (xy 116.503946 -220.193491) (xy 116.527469 -220.147324) (xy 116.557925 -220.105405)
			(xy 116.594563 -220.068767) (xy 116.636482 -220.038311) (xy 116.682649 -220.014788) (xy 116.731928 -219.998776)
			(xy 116.783105 -219.99067) (xy 116.834919 -219.99067) (xy 116.886096 -219.998776) (xy 116.935375 -220.014788)
			(xy 116.981542 -220.038311) (xy 117.023461 -220.068767) (xy 117.060099 -220.105405) (xy 117.090555 -220.147324)
			(xy 117.114078 -220.193491) (xy 117.13009 -220.24277) (xy 117.138196 -220.293947) (xy 117.138704 -220.319854)
			(xy 118.35892 -220.319854) (xy 118.359428 -220.293947) (xy 118.367534 -220.24277) (xy 118.383546 -220.193491)
			(xy 118.407069 -220.147324) (xy 118.437525 -220.105405) (xy 118.474163 -220.068767) (xy 118.516082 -220.038311)
			(xy 118.562249 -220.014788) (xy 118.611528 -219.998776) (xy 118.662705 -219.99067) (xy 118.714519 -219.99067)
			(xy 118.765696 -219.998776) (xy 118.814975 -220.014788) (xy 118.861142 -220.038311) (xy 118.903061 -220.068767)
			(xy 118.939699 -220.105405) (xy 118.970155 -220.147324) (xy 118.993678 -220.193491) (xy 119.00969 -220.24277)
			(xy 119.017796 -220.293947) (xy 119.018304 -220.319854) (xy 120.23852 -220.319854) (xy 120.239028 -220.293947)
			(xy 120.247134 -220.24277) (xy 120.263146 -220.193491) (xy 120.286669 -220.147324) (xy 120.317125 -220.105405)
			(xy 120.353763 -220.068767) (xy 120.395682 -220.038311) (xy 120.441849 -220.014788) (xy 120.491128 -219.998776)
			(xy 120.542305 -219.99067) (xy 120.594119 -219.99067) (xy 120.645296 -219.998776) (xy 120.694575 -220.014788)
			(xy 120.740742 -220.038311) (xy 120.782661 -220.068767) (xy 120.819299 -220.105405) (xy 120.849755 -220.147324)
			(xy 120.873278 -220.193491) (xy 120.88929 -220.24277) (xy 120.897396 -220.293947) (xy 120.897904 -220.319854)
			(xy 122.11812 -220.319854) (xy 122.118628 -220.293947) (xy 122.126734 -220.24277) (xy 122.142746 -220.193491)
			(xy 122.166269 -220.147324) (xy 122.196725 -220.105405) (xy 122.233363 -220.068767) (xy 122.275282 -220.038311)
			(xy 122.321449 -220.014788) (xy 122.370728 -219.998776) (xy 122.421905 -219.99067) (xy 122.473719 -219.99067)
			(xy 122.524896 -219.998776) (xy 122.574175 -220.014788) (xy 122.620342 -220.038311) (xy 122.662261 -220.068767)
			(xy 122.698899 -220.105405) (xy 122.729355 -220.147324) (xy 122.752878 -220.193491) (xy 122.76889 -220.24277)
			(xy 122.776996 -220.293947) (xy 122.777504 -220.319854) (xy 123.99772 -220.319854) (xy 123.998228 -220.293947)
			(xy 124.006334 -220.24277) (xy 124.022346 -220.193491) (xy 124.045869 -220.147324) (xy 124.076325 -220.105405)
			(xy 124.112963 -220.068767) (xy 124.154882 -220.038311) (xy 124.201049 -220.014788) (xy 124.250328 -219.998776)
			(xy 124.301505 -219.99067) (xy 124.353319 -219.99067) (xy 124.404496 -219.998776) (xy 124.453775 -220.014788)
			(xy 124.499942 -220.038311) (xy 124.541861 -220.068767) (xy 124.578499 -220.105405) (xy 124.608955 -220.147324)
			(xy 124.632478 -220.193491) (xy 124.64849 -220.24277) (xy 124.656596 -220.293947) (xy 124.657104 -220.319854)
			(xy 125.87732 -220.319854) (xy 125.877828 -220.293947) (xy 125.885934 -220.24277) (xy 125.901946 -220.193491)
			(xy 125.925469 -220.147324) (xy 125.955925 -220.105405) (xy 125.992563 -220.068767) (xy 126.034482 -220.038311)
			(xy 126.080649 -220.014788) (xy 126.129928 -219.998776) (xy 126.181105 -219.99067) (xy 126.232919 -219.99067)
			(xy 126.284096 -219.998776) (xy 126.333375 -220.014788) (xy 126.379542 -220.038311) (xy 126.421461 -220.068767)
			(xy 126.458099 -220.105405) (xy 126.488555 -220.147324) (xy 126.512078 -220.193491) (xy 126.52809 -220.24277)
			(xy 126.536196 -220.293947) (xy 126.536704 -220.319854) (xy 127.75692 -220.319854) (xy 127.757428 -220.293947)
			(xy 127.765534 -220.24277) (xy 127.781546 -220.193491) (xy 127.805069 -220.147324) (xy 127.835525 -220.105405)
			(xy 127.872163 -220.068767) (xy 127.914082 -220.038311) (xy 127.960249 -220.014788) (xy 128.009528 -219.998776)
			(xy 128.060705 -219.99067) (xy 128.112519 -219.99067) (xy 128.163696 -219.998776) (xy 128.212975 -220.014788)
			(xy 128.259142 -220.038311) (xy 128.301061 -220.068767) (xy 128.337699 -220.105405) (xy 128.368155 -220.147324)
			(xy 128.391678 -220.193491) (xy 128.40769 -220.24277) (xy 128.415796 -220.293947) (xy 128.416304 -220.319854)
			(xy 129.63652 -220.319854) (xy 129.637028 -220.293947) (xy 129.645134 -220.24277) (xy 129.661146 -220.193491)
			(xy 129.684669 -220.147324) (xy 129.715125 -220.105405) (xy 129.751763 -220.068767) (xy 129.793682 -220.038311)
			(xy 129.839849 -220.014788) (xy 129.889128 -219.998776) (xy 129.940305 -219.99067) (xy 129.992119 -219.99067)
			(xy 130.043296 -219.998776) (xy 130.092575 -220.014788) (xy 130.138742 -220.038311) (xy 130.180661 -220.068767)
			(xy 130.217299 -220.105405) (xy 130.247755 -220.147324) (xy 130.271278 -220.193491) (xy 130.28729 -220.24277)
			(xy 130.295396 -220.293947) (xy 130.295904 -220.319854) (xy 131.51612 -220.319854) (xy 131.516628 -220.293947)
			(xy 131.524734 -220.24277) (xy 131.540746 -220.193491) (xy 131.564269 -220.147324) (xy 131.594725 -220.105405)
			(xy 131.631363 -220.068767) (xy 131.673282 -220.038311) (xy 131.719449 -220.014788) (xy 131.768728 -219.998776)
			(xy 131.819905 -219.99067) (xy 131.871719 -219.99067) (xy 131.922896 -219.998776) (xy 131.972175 -220.014788)
			(xy 132.018342 -220.038311) (xy 132.060261 -220.068767) (xy 132.096899 -220.105405) (xy 132.127355 -220.147324)
			(xy 132.150878 -220.193491) (xy 132.16689 -220.24277) (xy 132.174996 -220.293947) (xy 132.175504 -220.319854)
			(xy 133.396228 -220.319854) (xy 133.396736 -220.293967) (xy 133.404835 -220.242829) (xy 133.420834 -220.193589)
			(xy 133.44434 -220.147457) (xy 133.474772 -220.10557) (xy 133.511382 -220.06896) (xy 133.553269 -220.038528)
			(xy 133.599401 -220.015022) (xy 133.648641 -219.999023) (xy 133.699779 -219.990924) (xy 133.751553 -219.990924)
			(xy 133.802691 -219.999023) (xy 133.851931 -220.015022) (xy 133.898063 -220.038528) (xy 133.93995 -220.06896)
			(xy 133.97656 -220.10557) (xy 134.006992 -220.147457) (xy 134.030498 -220.193589) (xy 134.046497 -220.242829)
			(xy 134.054596 -220.293967) (xy 134.055104 -220.319854) (xy 134.054563 -220.347562) (xy 134.045375 -220.402208)
			(xy 134.036816 -220.428566) (xy 134.029196 -220.450664) (xy 134.234174 -220.805756) (xy 134.257034 -220.810074)
			(xy 134.281845 -220.815229) (xy 134.329584 -220.832223) (xy 134.374162 -220.856322) (xy 134.414527 -220.886957)
			(xy 134.44973 -220.923408) (xy 134.47894 -220.964816) (xy 134.501472 -221.010206) (xy 134.516792 -221.058509)
			(xy 134.524542 -221.108587) (xy 134.525004 -221.133924) (xy 134.524496 -221.159811) (xy 134.516397 -221.210949)
			(xy 134.500398 -221.260189) (xy 134.476892 -221.306321) (xy 134.44646 -221.348208) (xy 134.40985 -221.384818)
			(xy 134.367963 -221.41525) (xy 134.321831 -221.438756) (xy 134.272591 -221.454755) (xy 134.221453 -221.462854)
			(xy 134.169679 -221.462854) (xy 134.118541 -221.454755) (xy 134.069301 -221.438756) (xy 134.023169 -221.41525)
			(xy 133.981282 -221.384818) (xy 133.944672 -221.348208) (xy 133.91424 -221.306321) (xy 133.890734 -221.260189)
			(xy 133.874735 -221.210949) (xy 133.866636 -221.159811) (xy 133.866128 -221.133924) (xy 133.866667 -221.106216)
			(xy 133.875856 -221.05157) (xy 133.884416 -221.025212) (xy 133.89229 -221.003114) (xy 133.687312 -220.648022)
			(xy 133.664452 -220.643704) (xy 133.639631 -220.638536) (xy 133.591852 -220.621582) (xy 133.547233 -220.59751)
			(xy 133.506826 -220.56689) (xy 133.471585 -220.530444) (xy 133.442341 -220.48903) (xy 133.419784 -220.443627)
			(xy 133.404447 -220.395304) (xy 133.39669 -220.345203) (xy 133.396228 -220.319854) (xy 132.175504 -220.319854)
			(xy 132.174894 -220.347507) (xy 132.165571 -220.402025) (xy 132.156962 -220.428312) (xy 132.149342 -220.45041)
			(xy 132.354574 -220.805756) (xy 132.377434 -220.810074) (xy 132.402245 -220.815229) (xy 132.449984 -220.832223)
			(xy 132.494562 -220.856322) (xy 132.534927 -220.886957) (xy 132.57013 -220.923408) (xy 132.59934 -220.964816)
			(xy 132.621872 -221.010206) (xy 132.637192 -221.058509) (xy 132.644942 -221.108587) (xy 132.645404 -221.133924)
			(xy 132.644896 -221.159811) (xy 132.636797 -221.210949) (xy 132.620798 -221.260189) (xy 132.597292 -221.306321)
			(xy 132.56686 -221.348208) (xy 132.53025 -221.384818) (xy 132.488363 -221.41525) (xy 132.442231 -221.438756)
			(xy 132.392991 -221.454755) (xy 132.341853 -221.462854) (xy 132.290079 -221.462854) (xy 132.238941 -221.454755)
			(xy 132.189701 -221.438756) (xy 132.143569 -221.41525) (xy 132.101682 -221.384818) (xy 132.065072 -221.348208)
			(xy 132.03464 -221.306321) (xy 132.011134 -221.260189) (xy 131.995135 -221.210949) (xy 131.987036 -221.159811)
			(xy 131.986528 -221.133924) (xy 131.987067 -221.106216) (xy 131.996256 -221.05157) (xy 132.004816 -221.025212)
			(xy 132.01269 -221.003114) (xy 131.807712 -220.648022) (xy 131.784852 -220.643704) (xy 131.76 -220.63857)
			(xy 131.712153 -220.621668) (xy 131.667462 -220.597632) (xy 131.626984 -220.567029) (xy 131.591674 -220.530584)
			(xy 131.562368 -220.489157) (xy 131.539757 -220.443728) (xy 131.524377 -220.39537) (xy 131.516591 -220.345226)
			(xy 131.51612 -220.319854) (xy 130.295904 -220.319854) (xy 130.295294 -220.347507) (xy 130.285971 -220.402025)
			(xy 130.277362 -220.428312) (xy 130.269742 -220.45041) (xy 130.474974 -220.805756) (xy 130.497834 -220.810074)
			(xy 130.522645 -220.815229) (xy 130.570384 -220.832223) (xy 130.614962 -220.856322) (xy 130.655327 -220.886957)
			(xy 130.69053 -220.923408) (xy 130.71974 -220.964816) (xy 130.742272 -221.010206) (xy 130.757592 -221.058509)
			(xy 130.765342 -221.108587) (xy 130.765804 -221.133924) (xy 130.765296 -221.159811) (xy 130.757197 -221.210949)
			(xy 130.741198 -221.260189) (xy 130.717692 -221.306321) (xy 130.68726 -221.348208) (xy 130.65065 -221.384818)
			(xy 130.608763 -221.41525) (xy 130.562631 -221.438756) (xy 130.513391 -221.454755) (xy 130.462253 -221.462854)
			(xy 130.410479 -221.462854) (xy 130.359341 -221.454755) (xy 130.310101 -221.438756) (xy 130.263969 -221.41525)
			(xy 130.222082 -221.384818) (xy 130.185472 -221.348208) (xy 130.15504 -221.306321) (xy 130.131534 -221.260189)
			(xy 130.115535 -221.210949) (xy 130.107436 -221.159811) (xy 130.106928 -221.133924) (xy 130.107467 -221.106216)
			(xy 130.116656 -221.05157) (xy 130.125216 -221.025212) (xy 130.13309 -221.003114) (xy 129.928112 -220.648022)
			(xy 129.905252 -220.643704) (xy 129.8804 -220.63857) (xy 129.832553 -220.621668) (xy 129.787862 -220.597632)
			(xy 129.747384 -220.567029) (xy 129.712074 -220.530584) (xy 129.682768 -220.489157) (xy 129.660157 -220.443728)
			(xy 129.644777 -220.39537) (xy 129.636991 -220.345226) (xy 129.63652 -220.319854) (xy 128.416304 -220.319854)
			(xy 128.415694 -220.347507) (xy 128.406371 -220.402025) (xy 128.397762 -220.428312) (xy 128.390142 -220.45041)
			(xy 128.595374 -220.805756) (xy 128.618234 -220.810074) (xy 128.643045 -220.815229) (xy 128.690784 -220.832223)
			(xy 128.735362 -220.856322) (xy 128.775727 -220.886957) (xy 128.81093 -220.923408) (xy 128.84014 -220.964816)
			(xy 128.862672 -221.010206) (xy 128.877992 -221.058509) (xy 128.885742 -221.108587) (xy 128.886204 -221.133924)
			(xy 128.885696 -221.159811) (xy 128.877597 -221.210949) (xy 128.861598 -221.260189) (xy 128.838092 -221.306321)
			(xy 128.80766 -221.348208) (xy 128.77105 -221.384818) (xy 128.729163 -221.41525) (xy 128.683031 -221.438756)
			(xy 128.633791 -221.454755) (xy 128.582653 -221.462854) (xy 128.530879 -221.462854) (xy 128.479741 -221.454755)
			(xy 128.430501 -221.438756) (xy 128.384369 -221.41525) (xy 128.342482 -221.384818) (xy 128.305872 -221.348208)
			(xy 128.27544 -221.306321) (xy 128.251934 -221.260189) (xy 128.235935 -221.210949) (xy 128.227836 -221.159811)
			(xy 128.227328 -221.133924) (xy 128.227867 -221.106216) (xy 128.237056 -221.05157) (xy 128.245616 -221.025212)
			(xy 128.25349 -221.003114) (xy 128.048512 -220.648022) (xy 128.025652 -220.643704) (xy 128.0008 -220.63857)
			(xy 127.952953 -220.621668) (xy 127.908262 -220.597632) (xy 127.867784 -220.567029) (xy 127.832474 -220.530584)
			(xy 127.803168 -220.489157) (xy 127.780557 -220.443728) (xy 127.765177 -220.39537) (xy 127.757391 -220.345226)
			(xy 127.75692 -220.319854) (xy 126.536704 -220.319854) (xy 126.536094 -220.347507) (xy 126.526771 -220.402025)
			(xy 126.518162 -220.428312) (xy 126.510542 -220.45041) (xy 126.715774 -220.805756) (xy 126.738634 -220.810074)
			(xy 126.763445 -220.815229) (xy 126.811184 -220.832223) (xy 126.855762 -220.856322) (xy 126.896127 -220.886957)
			(xy 126.93133 -220.923408) (xy 126.96054 -220.964816) (xy 126.983072 -221.010206) (xy 126.998392 -221.058509)
			(xy 127.006142 -221.108587) (xy 127.006604 -221.133924) (xy 127.006096 -221.159811) (xy 126.997997 -221.210949)
			(xy 126.981998 -221.260189) (xy 126.958492 -221.306321) (xy 126.92806 -221.348208) (xy 126.89145 -221.384818)
			(xy 126.849563 -221.41525) (xy 126.803431 -221.438756) (xy 126.754191 -221.454755) (xy 126.703053 -221.462854)
			(xy 126.651279 -221.462854) (xy 126.600141 -221.454755) (xy 126.550901 -221.438756) (xy 126.504769 -221.41525)
			(xy 126.462882 -221.384818) (xy 126.426272 -221.348208) (xy 126.39584 -221.306321) (xy 126.372334 -221.260189)
			(xy 126.356335 -221.210949) (xy 126.348236 -221.159811) (xy 126.347728 -221.133924) (xy 126.348267 -221.106216)
			(xy 126.357456 -221.05157) (xy 126.366016 -221.025212) (xy 126.37389 -221.003114) (xy 126.168912 -220.648022)
			(xy 126.146052 -220.643704) (xy 126.1212 -220.63857) (xy 126.073353 -220.621668) (xy 126.028662 -220.597632)
			(xy 125.988184 -220.567029) (xy 125.952874 -220.530584) (xy 125.923568 -220.489157) (xy 125.900957 -220.443728)
			(xy 125.885577 -220.39537) (xy 125.877791 -220.345226) (xy 125.87732 -220.319854) (xy 124.657104 -220.319854)
			(xy 124.656494 -220.347507) (xy 124.647171 -220.402025) (xy 124.638562 -220.428312) (xy 124.630942 -220.45041)
			(xy 124.836174 -220.805756) (xy 124.859034 -220.810074) (xy 124.883845 -220.815229) (xy 124.931584 -220.832223)
			(xy 124.976162 -220.856322) (xy 125.016527 -220.886957) (xy 125.05173 -220.923408) (xy 125.08094 -220.964816)
			(xy 125.103472 -221.010206) (xy 125.118792 -221.058509) (xy 125.126542 -221.108587) (xy 125.127004 -221.133924)
			(xy 125.126496 -221.159811) (xy 125.118397 -221.210949) (xy 125.102398 -221.260189) (xy 125.078892 -221.306321)
			(xy 125.04846 -221.348208) (xy 125.01185 -221.384818) (xy 124.969963 -221.41525) (xy 124.923831 -221.438756)
			(xy 124.874591 -221.454755) (xy 124.823453 -221.462854) (xy 124.771679 -221.462854) (xy 124.720541 -221.454755)
			(xy 124.671301 -221.438756) (xy 124.625169 -221.41525) (xy 124.583282 -221.384818) (xy 124.546672 -221.348208)
			(xy 124.51624 -221.306321) (xy 124.492734 -221.260189) (xy 124.476735 -221.210949) (xy 124.468636 -221.159811)
			(xy 124.468128 -221.133924) (xy 124.468667 -221.106216) (xy 124.477856 -221.05157) (xy 124.486416 -221.025212)
			(xy 124.49429 -221.003114) (xy 124.289312 -220.648022) (xy 124.266452 -220.643704) (xy 124.2416 -220.63857)
			(xy 124.193753 -220.621668) (xy 124.149062 -220.597632) (xy 124.108584 -220.567029) (xy 124.073274 -220.530584)
			(xy 124.043968 -220.489157) (xy 124.021357 -220.443728) (xy 124.005977 -220.39537) (xy 123.998191 -220.345226)
			(xy 123.99772 -220.319854) (xy 122.777504 -220.319854) (xy 122.776894 -220.347507) (xy 122.767571 -220.402025)
			(xy 122.758962 -220.428312) (xy 122.751342 -220.45041) (xy 122.956574 -220.805756) (xy 122.979434 -220.810074)
			(xy 123.004245 -220.815229) (xy 123.051984 -220.832223) (xy 123.096562 -220.856322) (xy 123.136927 -220.886957)
			(xy 123.17213 -220.923408) (xy 123.20134 -220.964816) (xy 123.223872 -221.010206) (xy 123.239192 -221.058509)
			(xy 123.246942 -221.108587) (xy 123.247404 -221.133924) (xy 123.246896 -221.159811) (xy 123.238797 -221.210949)
			(xy 123.222798 -221.260189) (xy 123.199292 -221.306321) (xy 123.16886 -221.348208) (xy 123.13225 -221.384818)
			(xy 123.090363 -221.41525) (xy 123.044231 -221.438756) (xy 122.994991 -221.454755) (xy 122.943853 -221.462854)
			(xy 122.892079 -221.462854) (xy 122.840941 -221.454755) (xy 122.791701 -221.438756) (xy 122.745569 -221.41525)
			(xy 122.703682 -221.384818) (xy 122.667072 -221.348208) (xy 122.63664 -221.306321) (xy 122.613134 -221.260189)
			(xy 122.597135 -221.210949) (xy 122.589036 -221.159811) (xy 122.588528 -221.133924) (xy 122.589067 -221.106216)
			(xy 122.598256 -221.05157) (xy 122.606816 -221.025212) (xy 122.61469 -221.003114) (xy 122.409712 -220.648022)
			(xy 122.386852 -220.643704) (xy 122.362 -220.63857) (xy 122.314153 -220.621668) (xy 122.269462 -220.597632)
			(xy 122.228984 -220.567029) (xy 122.193674 -220.530584) (xy 122.164368 -220.489157) (xy 122.141757 -220.443728)
			(xy 122.126377 -220.39537) (xy 122.118591 -220.345226) (xy 122.11812 -220.319854) (xy 120.897904 -220.319854)
			(xy 120.897294 -220.347507) (xy 120.887971 -220.402025) (xy 120.879362 -220.428312) (xy 120.871742 -220.45041)
			(xy 121.076974 -220.805756) (xy 121.099834 -220.810074) (xy 121.124645 -220.815229) (xy 121.172384 -220.832223)
			(xy 121.216962 -220.856322) (xy 121.257327 -220.886957) (xy 121.29253 -220.923408) (xy 121.32174 -220.964816)
			(xy 121.344272 -221.010206) (xy 121.359592 -221.058509) (xy 121.367342 -221.108587) (xy 121.367804 -221.133924)
			(xy 121.367296 -221.159811) (xy 121.359197 -221.210949) (xy 121.343198 -221.260189) (xy 121.319692 -221.306321)
			(xy 121.28926 -221.348208) (xy 121.25265 -221.384818) (xy 121.210763 -221.41525) (xy 121.164631 -221.438756)
			(xy 121.115391 -221.454755) (xy 121.064253 -221.462854) (xy 121.012479 -221.462854) (xy 120.961341 -221.454755)
			(xy 120.912101 -221.438756) (xy 120.865969 -221.41525) (xy 120.824082 -221.384818) (xy 120.787472 -221.348208)
			(xy 120.75704 -221.306321) (xy 120.733534 -221.260189) (xy 120.717535 -221.210949) (xy 120.709436 -221.159811)
			(xy 120.708928 -221.133924) (xy 120.709467 -221.106216) (xy 120.718656 -221.05157) (xy 120.727216 -221.025212)
			(xy 120.73509 -221.003114) (xy 120.530112 -220.648022) (xy 120.507252 -220.643704) (xy 120.4824 -220.63857)
			(xy 120.434553 -220.621668) (xy 120.389862 -220.597632) (xy 120.349384 -220.567029) (xy 120.314074 -220.530584)
			(xy 120.284768 -220.489157) (xy 120.262157 -220.443728) (xy 120.246777 -220.39537) (xy 120.238991 -220.345226)
			(xy 120.23852 -220.319854) (xy 119.018304 -220.319854) (xy 119.017694 -220.347507) (xy 119.008371 -220.402025)
			(xy 118.999762 -220.428312) (xy 118.992142 -220.45041) (xy 119.197374 -220.805756) (xy 119.220234 -220.810074)
			(xy 119.245045 -220.815229) (xy 119.292784 -220.832223) (xy 119.337362 -220.856322) (xy 119.377727 -220.886957)
			(xy 119.41293 -220.923408) (xy 119.44214 -220.964816) (xy 119.464672 -221.010206) (xy 119.479992 -221.058509)
			(xy 119.487742 -221.108587) (xy 119.488204 -221.133924) (xy 119.487696 -221.159811) (xy 119.479597 -221.210949)
			(xy 119.463598 -221.260189) (xy 119.440092 -221.306321) (xy 119.40966 -221.348208) (xy 119.37305 -221.384818)
			(xy 119.331163 -221.41525) (xy 119.285031 -221.438756) (xy 119.235791 -221.454755) (xy 119.184653 -221.462854)
			(xy 119.132879 -221.462854) (xy 119.081741 -221.454755) (xy 119.032501 -221.438756) (xy 118.986369 -221.41525)
			(xy 118.944482 -221.384818) (xy 118.907872 -221.348208) (xy 118.87744 -221.306321) (xy 118.853934 -221.260189)
			(xy 118.837935 -221.210949) (xy 118.829836 -221.159811) (xy 118.829328 -221.133924) (xy 118.829867 -221.106216)
			(xy 118.839056 -221.05157) (xy 118.847616 -221.025212) (xy 118.85549 -221.003114) (xy 118.650512 -220.648022)
			(xy 118.627652 -220.643704) (xy 118.6028 -220.63857) (xy 118.554953 -220.621668) (xy 118.510262 -220.597632)
			(xy 118.469784 -220.567029) (xy 118.434474 -220.530584) (xy 118.405168 -220.489157) (xy 118.382557 -220.443728)
			(xy 118.367177 -220.39537) (xy 118.359391 -220.345226) (xy 118.35892 -220.319854) (xy 117.138704 -220.319854)
			(xy 117.138094 -220.347507) (xy 117.128771 -220.402025) (xy 117.120162 -220.428312) (xy 117.112542 -220.45041)
			(xy 117.317774 -220.805756) (xy 117.340634 -220.810074) (xy 117.365445 -220.815229) (xy 117.413184 -220.832223)
			(xy 117.457762 -220.856322) (xy 117.498127 -220.886957) (xy 117.53333 -220.923408) (xy 117.56254 -220.964816)
			(xy 117.585072 -221.010206) (xy 117.600392 -221.058509) (xy 117.608142 -221.108587) (xy 117.608604 -221.133924)
			(xy 117.608096 -221.159811) (xy 117.599997 -221.210949) (xy 117.583998 -221.260189) (xy 117.560492 -221.306321)
			(xy 117.53006 -221.348208) (xy 117.49345 -221.384818) (xy 117.451563 -221.41525) (xy 117.405431 -221.438756)
			(xy 117.356191 -221.454755) (xy 117.305053 -221.462854) (xy 117.253279 -221.462854) (xy 117.202141 -221.454755)
			(xy 117.152901 -221.438756) (xy 117.106769 -221.41525) (xy 117.064882 -221.384818) (xy 117.028272 -221.348208)
			(xy 116.99784 -221.306321) (xy 116.974334 -221.260189) (xy 116.958335 -221.210949) (xy 116.950236 -221.159811)
			(xy 116.949728 -221.133924) (xy 116.950267 -221.106216) (xy 116.959456 -221.05157) (xy 116.968016 -221.025212)
			(xy 116.97589 -221.003114) (xy 116.770912 -220.648022) (xy 116.748052 -220.643704) (xy 116.7232 -220.63857)
			(xy 116.675353 -220.621668) (xy 116.630662 -220.597632) (xy 116.590184 -220.567029) (xy 116.554874 -220.530584)
			(xy 116.525568 -220.489157) (xy 116.502957 -220.443728) (xy 116.487577 -220.39537) (xy 116.479791 -220.345226)
			(xy 116.47932 -220.319854) (xy 115.259104 -220.319854) (xy 115.258494 -220.347507) (xy 115.249171 -220.402025)
			(xy 115.240562 -220.428312) (xy 115.232942 -220.45041) (xy 115.438174 -220.805756) (xy 115.461034 -220.810074)
			(xy 115.485845 -220.815229) (xy 115.533584 -220.832223) (xy 115.578162 -220.856322) (xy 115.618527 -220.886957)
			(xy 115.65373 -220.923408) (xy 115.68294 -220.964816) (xy 115.705472 -221.010206) (xy 115.720792 -221.058509)
			(xy 115.728542 -221.108587) (xy 115.729004 -221.133924) (xy 115.728496 -221.159811) (xy 115.720397 -221.210949)
			(xy 115.704398 -221.260189) (xy 115.680892 -221.306321) (xy 115.65046 -221.348208) (xy 115.61385 -221.384818)
			(xy 115.571963 -221.41525) (xy 115.525831 -221.438756) (xy 115.476591 -221.454755) (xy 115.425453 -221.462854)
			(xy 115.373679 -221.462854) (xy 115.322541 -221.454755) (xy 115.273301 -221.438756) (xy 115.227169 -221.41525)
			(xy 115.185282 -221.384818) (xy 115.148672 -221.348208) (xy 115.11824 -221.306321) (xy 115.094734 -221.260189)
			(xy 115.078735 -221.210949) (xy 115.070636 -221.159811) (xy 115.070128 -221.133924) (xy 115.070667 -221.106216)
			(xy 115.079856 -221.05157) (xy 115.088416 -221.025212) (xy 115.09629 -221.003114) (xy 114.891312 -220.648022)
			(xy 114.868452 -220.643704) (xy 114.8436 -220.63857) (xy 114.795753 -220.621668) (xy 114.751062 -220.597632)
			(xy 114.710584 -220.567029) (xy 114.675274 -220.530584) (xy 114.645968 -220.489157) (xy 114.623357 -220.443728)
			(xy 114.607977 -220.39537) (xy 114.600191 -220.345226) (xy 114.59972 -220.319854) (xy 113.379504 -220.319854)
			(xy 113.378894 -220.347507) (xy 113.369571 -220.402025) (xy 113.360962 -220.428312) (xy 113.353342 -220.45041)
			(xy 113.558574 -220.805756) (xy 113.581434 -220.810074) (xy 113.606245 -220.815229) (xy 113.653984 -220.832223)
			(xy 113.698562 -220.856322) (xy 113.738927 -220.886957) (xy 113.77413 -220.923408) (xy 113.80334 -220.964816)
			(xy 113.825872 -221.010206) (xy 113.841192 -221.058509) (xy 113.848942 -221.108587) (xy 113.849404 -221.133924)
			(xy 113.848896 -221.159811) (xy 113.840797 -221.210949) (xy 113.824798 -221.260189) (xy 113.801292 -221.306321)
			(xy 113.77086 -221.348208) (xy 113.73425 -221.384818) (xy 113.692363 -221.41525) (xy 113.646231 -221.438756)
			(xy 113.596991 -221.454755) (xy 113.545853 -221.462854) (xy 113.494079 -221.462854) (xy 113.442941 -221.454755)
			(xy 113.393701 -221.438756) (xy 113.347569 -221.41525) (xy 113.305682 -221.384818) (xy 113.269072 -221.348208)
			(xy 113.23864 -221.306321) (xy 113.215134 -221.260189) (xy 113.199135 -221.210949) (xy 113.191036 -221.159811)
			(xy 113.190528 -221.133924) (xy 113.191067 -221.106216) (xy 113.200256 -221.05157) (xy 113.208816 -221.025212)
			(xy 113.21669 -221.003114) (xy 113.011712 -220.648022) (xy 112.988852 -220.643704) (xy 112.964 -220.63857)
			(xy 112.916153 -220.621668) (xy 112.871462 -220.597632) (xy 112.830984 -220.567029) (xy 112.795674 -220.530584)
			(xy 112.766368 -220.489157) (xy 112.743757 -220.443728) (xy 112.728377 -220.39537) (xy 112.720591 -220.345226)
			(xy 112.72012 -220.319854) (xy 111.499904 -220.319854) (xy 111.499294 -220.347507) (xy 111.489971 -220.402025)
			(xy 111.481362 -220.428312) (xy 111.473742 -220.45041) (xy 111.678974 -220.805756) (xy 111.701834 -220.810074)
			(xy 111.726645 -220.815229) (xy 111.774384 -220.832223) (xy 111.818962 -220.856322) (xy 111.859327 -220.886957)
			(xy 111.89453 -220.923408) (xy 111.92374 -220.964816) (xy 111.946272 -221.010206) (xy 111.961592 -221.058509)
			(xy 111.969342 -221.108587) (xy 111.969804 -221.133924) (xy 111.969296 -221.159811) (xy 111.961197 -221.210949)
			(xy 111.945198 -221.260189) (xy 111.921692 -221.306321) (xy 111.89126 -221.348208) (xy 111.85465 -221.384818)
			(xy 111.812763 -221.41525) (xy 111.766631 -221.438756) (xy 111.717391 -221.454755) (xy 111.666253 -221.462854)
			(xy 111.614479 -221.462854) (xy 111.563341 -221.454755) (xy 111.514101 -221.438756) (xy 111.467969 -221.41525)
			(xy 111.426082 -221.384818) (xy 111.389472 -221.348208) (xy 111.35904 -221.306321) (xy 111.335534 -221.260189)
			(xy 111.319535 -221.210949) (xy 111.311436 -221.159811) (xy 111.310928 -221.133924) (xy 111.311467 -221.106216)
			(xy 111.320656 -221.05157) (xy 111.329216 -221.025212) (xy 111.33709 -221.003114) (xy 111.132112 -220.648022)
			(xy 111.109252 -220.643704) (xy 111.0844 -220.63857) (xy 111.036553 -220.621668) (xy 110.991862 -220.597632)
			(xy 110.951384 -220.567029) (xy 110.916074 -220.530584) (xy 110.886768 -220.489157) (xy 110.864157 -220.443728)
			(xy 110.848777 -220.39537) (xy 110.840991 -220.345226) (xy 110.84052 -220.319854) (xy 109.620304 -220.319854)
			(xy 109.619694 -220.347507) (xy 109.610371 -220.402025) (xy 109.601762 -220.428312) (xy 109.594142 -220.45041)
			(xy 109.799374 -220.805756) (xy 109.822234 -220.810074) (xy 109.847045 -220.815229) (xy 109.894784 -220.832223)
			(xy 109.939362 -220.856322) (xy 109.979727 -220.886957) (xy 110.01493 -220.923408) (xy 110.04414 -220.964816)
			(xy 110.066672 -221.010206) (xy 110.081992 -221.058509) (xy 110.089742 -221.108587) (xy 110.090204 -221.133924)
			(xy 110.089696 -221.159811) (xy 110.081597 -221.210949) (xy 110.065598 -221.260189) (xy 110.042092 -221.306321)
			(xy 110.01166 -221.348208) (xy 109.97505 -221.384818) (xy 109.933163 -221.41525) (xy 109.887031 -221.438756)
			(xy 109.837791 -221.454755) (xy 109.786653 -221.462854) (xy 109.734879 -221.462854) (xy 109.683741 -221.454755)
			(xy 109.634501 -221.438756) (xy 109.588369 -221.41525) (xy 109.546482 -221.384818) (xy 109.509872 -221.348208)
			(xy 109.47944 -221.306321) (xy 109.455934 -221.260189) (xy 109.439935 -221.210949) (xy 109.431836 -221.159811)
			(xy 109.431328 -221.133924) (xy 109.431867 -221.106216) (xy 109.441056 -221.05157) (xy 109.449616 -221.025212)
			(xy 109.45749 -221.003114) (xy 109.252512 -220.648022) (xy 109.229652 -220.643704) (xy 109.2048 -220.63857)
			(xy 109.156953 -220.621668) (xy 109.112262 -220.597632) (xy 109.071784 -220.567029) (xy 109.036474 -220.530584)
			(xy 109.007168 -220.489157) (xy 108.984557 -220.443728) (xy 108.969177 -220.39537) (xy 108.961391 -220.345226)
			(xy 108.96092 -220.319854) (xy 107.740704 -220.319854) (xy 107.740094 -220.347507) (xy 107.730771 -220.402025)
			(xy 107.722162 -220.428312) (xy 107.714542 -220.45041) (xy 107.919774 -220.805756) (xy 107.942634 -220.810074)
			(xy 107.967445 -220.815229) (xy 108.015184 -220.832223) (xy 108.059762 -220.856322) (xy 108.100127 -220.886957)
			(xy 108.13533 -220.923408) (xy 108.16454 -220.964816) (xy 108.187072 -221.010206) (xy 108.202392 -221.058509)
			(xy 108.210142 -221.108587) (xy 108.210604 -221.133924) (xy 108.210096 -221.159811) (xy 108.201997 -221.210949)
			(xy 108.185998 -221.260189) (xy 108.162492 -221.306321) (xy 108.13206 -221.348208) (xy 108.09545 -221.384818)
			(xy 108.053563 -221.41525) (xy 108.007431 -221.438756) (xy 107.958191 -221.454755) (xy 107.907053 -221.462854)
			(xy 107.855279 -221.462854) (xy 107.804141 -221.454755) (xy 107.754901 -221.438756) (xy 107.708769 -221.41525)
			(xy 107.666882 -221.384818) (xy 107.630272 -221.348208) (xy 107.59984 -221.306321) (xy 107.576334 -221.260189)
			(xy 107.560335 -221.210949) (xy 107.552236 -221.159811) (xy 107.551728 -221.133924) (xy 107.552267 -221.106216)
			(xy 107.561456 -221.05157) (xy 107.570016 -221.025212) (xy 107.57789 -221.003114) (xy 107.372912 -220.648022)
			(xy 107.350052 -220.643704) (xy 107.3252 -220.63857) (xy 107.277353 -220.621668) (xy 107.232662 -220.597632)
			(xy 107.192184 -220.567029) (xy 107.156874 -220.530584) (xy 107.127568 -220.489157) (xy 107.104957 -220.443728)
			(xy 107.089577 -220.39537) (xy 107.081791 -220.345226) (xy 107.08132 -220.319854) (xy 105.861104 -220.319854)
			(xy 105.860494 -220.347507) (xy 105.851171 -220.402025) (xy 105.842562 -220.428312) (xy 105.834942 -220.45041)
			(xy 106.040174 -220.805756) (xy 106.063034 -220.810074) (xy 106.087845 -220.815229) (xy 106.135584 -220.832223)
			(xy 106.180162 -220.856322) (xy 106.220527 -220.886957) (xy 106.25573 -220.923408) (xy 106.28494 -220.964816)
			(xy 106.307472 -221.010206) (xy 106.322792 -221.058509) (xy 106.330542 -221.108587) (xy 106.331004 -221.133924)
			(xy 106.330496 -221.159811) (xy 106.322397 -221.210949) (xy 106.306398 -221.260189) (xy 106.282892 -221.306321)
			(xy 106.25246 -221.348208) (xy 106.21585 -221.384818) (xy 106.173963 -221.41525) (xy 106.127831 -221.438756)
			(xy 106.078591 -221.454755) (xy 106.027453 -221.462854) (xy 105.975679 -221.462854) (xy 105.924541 -221.454755)
			(xy 105.875301 -221.438756) (xy 105.829169 -221.41525) (xy 105.787282 -221.384818) (xy 105.750672 -221.348208)
			(xy 105.72024 -221.306321) (xy 105.696734 -221.260189) (xy 105.680735 -221.210949) (xy 105.672636 -221.159811)
			(xy 105.672128 -221.133924) (xy 105.672667 -221.106216) (xy 105.681856 -221.05157) (xy 105.690416 -221.025212)
			(xy 105.69829 -221.003114) (xy 105.493312 -220.648022) (xy 105.470452 -220.643704) (xy 105.4456 -220.63857)
			(xy 105.397753 -220.621668) (xy 105.353062 -220.597632) (xy 105.312584 -220.567029) (xy 105.277274 -220.530584)
			(xy 105.247968 -220.489157) (xy 105.225357 -220.443728) (xy 105.209977 -220.39537) (xy 105.202191 -220.345226)
			(xy 105.20172 -220.319854) (xy 103.981504 -220.319854) (xy 103.981028 -220.345199) (xy 103.973249 -220.395289)
			(xy 103.957897 -220.443599) (xy 103.935334 -220.48899) (xy 103.906091 -220.530396) (xy 103.870857 -220.566839)
			(xy 103.830462 -220.597461) (xy 103.785857 -220.621543) (xy 103.738093 -220.638516) (xy 103.71328 -220.643704)
			(xy 103.69042 -220.648022) (xy 103.485442 -221.003114) (xy 103.493316 -221.024958) (xy 103.50191 -221.051373)
			(xy 103.511097 -221.106151) (xy 103.511604 -221.133924) (xy 103.511096 -221.159811) (xy 103.502997 -221.210949)
			(xy 103.486998 -221.260189) (xy 103.463492 -221.306321) (xy 103.43306 -221.348208) (xy 103.39645 -221.384818)
			(xy 103.354563 -221.41525) (xy 103.308431 -221.438756) (xy 103.259191 -221.454755) (xy 103.208053 -221.462854)
			(xy 103.156279 -221.462854) (xy 103.105141 -221.454755) (xy 103.055901 -221.438756) (xy 103.009769 -221.41525)
			(xy 102.967882 -221.384818) (xy 102.931272 -221.348208) (xy 102.90084 -221.306321) (xy 102.877334 -221.260189)
			(xy 102.861335 -221.210949) (xy 102.853236 -221.159811) (xy 102.852728 -221.133924) (xy 102.571804 -221.133924)
			(xy 102.57128 -221.161632) (xy 102.562081 -221.216279) (xy 102.553516 -221.242636) (xy 102.545642 -221.264734)
			(xy 102.75062 -221.619572) (xy 102.77348 -221.62389) (xy 102.798305 -221.629041) (xy 102.846083 -221.645999)
			(xy 102.890702 -221.670074) (xy 102.931107 -221.700696) (xy 102.966347 -221.737145) (xy 102.99559 -221.778561)
			(xy 103.018147 -221.823965) (xy 103.033485 -221.872289) (xy 103.041242 -221.92239) (xy 103.041704 -221.94774)
			(xy 104.26192 -221.94774) (xy 104.262371 -221.922394) (xy 104.270152 -221.872302) (xy 104.285506 -221.82399)
			(xy 104.308072 -221.778597) (xy 104.337318 -221.737192) (xy 104.372555 -221.700749) (xy 104.412954 -221.670127)
			(xy 104.457562 -221.646047) (xy 104.50533 -221.629076) (xy 104.530144 -221.62389) (xy 104.553004 -221.619572)
			(xy 104.758236 -221.264226) (xy 104.750362 -221.242128) (xy 104.741898 -221.215883) (xy 104.732825 -221.161495)
			(xy 104.732328 -221.133924) (xy 104.732836 -221.108037) (xy 104.740935 -221.056899) (xy 104.756934 -221.007659)
			(xy 104.78044 -220.961527) (xy 104.810872 -220.91964) (xy 104.847482 -220.88303) (xy 104.889369 -220.852598)
			(xy 104.935501 -220.829092) (xy 104.984741 -220.813093) (xy 105.035879 -220.804994) (xy 105.087653 -220.804994)
			(xy 105.138791 -220.813093) (xy 105.188031 -220.829092) (xy 105.234163 -220.852598) (xy 105.27605 -220.88303)
			(xy 105.31266 -220.91964) (xy 105.343092 -220.961527) (xy 105.366598 -221.007659) (xy 105.382597 -221.056899)
			(xy 105.390696 -221.108037) (xy 105.391204 -221.133924) (xy 105.390748 -221.159299) (xy 105.382976 -221.20945)
			(xy 105.367604 -221.257815) (xy 105.344997 -221.303251) (xy 105.315689 -221.344682) (xy 105.280373 -221.381128)
			(xy 105.239885 -221.411727) (xy 105.195184 -221.435754) (xy 105.147326 -221.452641) (xy 105.122472 -221.457774)
			(xy 105.099612 -221.462092) (xy 104.894888 -221.81693) (xy 104.902762 -221.838774) (xy 104.911419 -221.865179)
			(xy 104.920732 -221.919958) (xy 104.921304 -221.94774) (xy 106.14152 -221.94774) (xy 106.141971 -221.922394)
			(xy 106.149752 -221.872302) (xy 106.165106 -221.82399) (xy 106.187672 -221.778597) (xy 106.216918 -221.737192)
			(xy 106.252155 -221.700749) (xy 106.292554 -221.670127) (xy 106.337162 -221.646047) (xy 106.38493 -221.629076)
			(xy 106.409744 -221.62389) (xy 106.432604 -221.619572) (xy 106.637836 -221.264226) (xy 106.629962 -221.242128)
			(xy 106.621498 -221.215883) (xy 106.612425 -221.161495) (xy 106.611928 -221.133924) (xy 106.612436 -221.108037)
			(xy 106.620535 -221.056899) (xy 106.636534 -221.007659) (xy 106.66004 -220.961527) (xy 106.690472 -220.91964)
			(xy 106.727082 -220.88303) (xy 106.768969 -220.852598) (xy 106.815101 -220.829092) (xy 106.864341 -220.813093)
			(xy 106.915479 -220.804994) (xy 106.967253 -220.804994) (xy 107.018391 -220.813093) (xy 107.067631 -220.829092)
			(xy 107.113763 -220.852598) (xy 107.15565 -220.88303) (xy 107.19226 -220.91964) (xy 107.222692 -220.961527)
			(xy 107.246198 -221.007659) (xy 107.262197 -221.056899) (xy 107.270296 -221.108037) (xy 107.270804 -221.133924)
			(xy 107.270348 -221.159299) (xy 107.262576 -221.20945) (xy 107.247204 -221.257815) (xy 107.224597 -221.303251)
			(xy 107.195289 -221.344682) (xy 107.159973 -221.381128) (xy 107.119485 -221.411727) (xy 107.074784 -221.435754)
			(xy 107.026926 -221.452641) (xy 107.002072 -221.457774) (xy 106.979212 -221.462092) (xy 106.774488 -221.81693)
			(xy 106.782362 -221.838774) (xy 106.791019 -221.865179) (xy 106.800332 -221.919958) (xy 106.800904 -221.94774)
			(xy 108.02112 -221.94774) (xy 108.021571 -221.922394) (xy 108.029352 -221.872302) (xy 108.044706 -221.82399)
			(xy 108.067272 -221.778597) (xy 108.096518 -221.737192) (xy 108.131755 -221.700749) (xy 108.172154 -221.670127)
			(xy 108.216762 -221.646047) (xy 108.26453 -221.629076) (xy 108.289344 -221.62389) (xy 108.312204 -221.619572)
			(xy 108.517436 -221.264226) (xy 108.509562 -221.242128) (xy 108.501098 -221.215883) (xy 108.492025 -221.161495)
			(xy 108.491528 -221.133924) (xy 108.492036 -221.108037) (xy 108.500135 -221.056899) (xy 108.516134 -221.007659)
			(xy 108.53964 -220.961527) (xy 108.570072 -220.91964) (xy 108.606682 -220.88303) (xy 108.648569 -220.852598)
			(xy 108.694701 -220.829092) (xy 108.743941 -220.813093) (xy 108.795079 -220.804994) (xy 108.846853 -220.804994)
			(xy 108.897991 -220.813093) (xy 108.947231 -220.829092) (xy 108.993363 -220.852598) (xy 109.03525 -220.88303)
			(xy 109.07186 -220.91964) (xy 109.102292 -220.961527) (xy 109.125798 -221.007659) (xy 109.141797 -221.056899)
			(xy 109.149896 -221.108037) (xy 109.150404 -221.133924) (xy 109.149948 -221.159299) (xy 109.142176 -221.20945)
			(xy 109.126804 -221.257815) (xy 109.104197 -221.303251) (xy 109.074889 -221.344682) (xy 109.039573 -221.381128)
			(xy 108.999085 -221.411727) (xy 108.954384 -221.435754) (xy 108.906526 -221.452641) (xy 108.881672 -221.457774)
			(xy 108.858812 -221.462092) (xy 108.654088 -221.81693) (xy 108.661962 -221.838774) (xy 108.670619 -221.865179)
			(xy 108.679932 -221.919958) (xy 108.680504 -221.94774) (xy 109.901228 -221.94774) (xy 109.901634 -221.922403)
			(xy 109.909396 -221.872326) (xy 109.924728 -221.824026) (xy 109.947269 -221.77864) (xy 109.976489 -221.737238)
			(xy 110.011699 -221.700794) (xy 110.05207 -221.670165) (xy 110.096652 -221.646074) (xy 110.144395 -221.629087)
			(xy 110.169198 -221.62389) (xy 110.192058 -221.619572) (xy 110.397036 -221.26448) (xy 110.389416 -221.242382)
			(xy 110.380897 -221.216211) (xy 110.371703 -221.161949) (xy 110.371128 -221.134432) (xy 110.371128 -221.133924)
			(xy 110.371636 -221.108037) (xy 110.379735 -221.056899) (xy 110.395734 -221.007659) (xy 110.41924 -220.961527)
			(xy 110.449672 -220.91964) (xy 110.486282 -220.88303) (xy 110.528169 -220.852598) (xy 110.574301 -220.829092)
			(xy 110.623541 -220.813093) (xy 110.674679 -220.804994) (xy 110.726453 -220.804994) (xy 110.777591 -220.813093)
			(xy 110.826831 -220.829092) (xy 110.872963 -220.852598) (xy 110.91485 -220.88303) (xy 110.95146 -220.91964)
			(xy 110.981892 -220.961527) (xy 111.005398 -221.007659) (xy 111.021397 -221.056899) (xy 111.029496 -221.108037)
			(xy 111.030004 -221.133924) (xy 111.029585 -221.15929) (xy 111.021833 -221.209425) (xy 111.006484 -221.257778)
			(xy 110.983902 -221.303206) (xy 110.954621 -221.344633) (xy 110.919333 -221.381081) (xy 110.878874 -221.411686)
			(xy 110.8342 -221.435725) (xy 110.786369 -221.45263) (xy 110.761526 -221.457774) (xy 110.738666 -221.462092)
			(xy 110.533942 -221.81693) (xy 110.541816 -221.838774) (xy 110.550414 -221.865187) (xy 110.559598 -221.919967)
			(xy 110.560104 -221.94774) (xy 111.78032 -221.94774) (xy 111.780771 -221.922394) (xy 111.788552 -221.872302)
			(xy 111.803906 -221.82399) (xy 111.826472 -221.778597) (xy 111.855718 -221.737192) (xy 111.890955 -221.700749)
			(xy 111.931354 -221.670127) (xy 111.975962 -221.646047) (xy 112.02373 -221.629076) (xy 112.048544 -221.62389)
			(xy 112.071404 -221.619572) (xy 112.276636 -221.264226) (xy 112.268762 -221.242128) (xy 112.260298 -221.215883)
			(xy 112.251225 -221.161495) (xy 112.250728 -221.133924) (xy 112.251236 -221.108037) (xy 112.259335 -221.056899)
			(xy 112.275334 -221.007659) (xy 112.29884 -220.961527) (xy 112.329272 -220.91964) (xy 112.365882 -220.88303)
			(xy 112.407769 -220.852598) (xy 112.453901 -220.829092) (xy 112.503141 -220.813093) (xy 112.554279 -220.804994)
			(xy 112.606053 -220.804994) (xy 112.657191 -220.813093) (xy 112.706431 -220.829092) (xy 112.752563 -220.852598)
			(xy 112.79445 -220.88303) (xy 112.83106 -220.91964) (xy 112.861492 -220.961527) (xy 112.884998 -221.007659)
			(xy 112.900997 -221.056899) (xy 112.909096 -221.108037) (xy 112.909604 -221.133924) (xy 112.909148 -221.159299)
			(xy 112.901376 -221.20945) (xy 112.886004 -221.257815) (xy 112.863397 -221.303251) (xy 112.834089 -221.344682)
			(xy 112.798773 -221.381128) (xy 112.758285 -221.411727) (xy 112.713584 -221.435754) (xy 112.665726 -221.452641)
			(xy 112.640872 -221.457774) (xy 112.618012 -221.462092) (xy 112.413288 -221.81693) (xy 112.421162 -221.838774)
			(xy 112.429819 -221.865179) (xy 112.439132 -221.919958) (xy 112.439704 -221.94774) (xy 113.660428 -221.94774)
			(xy 113.660834 -221.922403) (xy 113.668596 -221.872326) (xy 113.683928 -221.824026) (xy 113.706469 -221.77864)
			(xy 113.735689 -221.737238) (xy 113.770899 -221.700794) (xy 113.81127 -221.670165) (xy 113.855852 -221.646074)
			(xy 113.903595 -221.629087) (xy 113.928398 -221.62389) (xy 113.951258 -221.619572) (xy 114.156236 -221.26448)
			(xy 114.148616 -221.242382) (xy 114.140097 -221.216211) (xy 114.130903 -221.161949) (xy 114.130328 -221.134432)
			(xy 114.130328 -221.133924) (xy 114.130836 -221.108037) (xy 114.138935 -221.056899) (xy 114.154934 -221.007659)
			(xy 114.17844 -220.961527) (xy 114.208872 -220.91964) (xy 114.245482 -220.88303) (xy 114.287369 -220.852598)
			(xy 114.333501 -220.829092) (xy 114.382741 -220.813093) (xy 114.433879 -220.804994) (xy 114.485653 -220.804994)
			(xy 114.536791 -220.813093) (xy 114.586031 -220.829092) (xy 114.632163 -220.852598) (xy 114.67405 -220.88303)
			(xy 114.71066 -220.91964) (xy 114.741092 -220.961527) (xy 114.764598 -221.007659) (xy 114.780597 -221.056899)
			(xy 114.788696 -221.108037) (xy 114.789204 -221.133924) (xy 114.788785 -221.15929) (xy 114.781033 -221.209425)
			(xy 114.765684 -221.257778) (xy 114.743102 -221.303206) (xy 114.713821 -221.344633) (xy 114.678533 -221.381081)
			(xy 114.638074 -221.411686) (xy 114.5934 -221.435725) (xy 114.545569 -221.45263) (xy 114.520726 -221.457774)
			(xy 114.497866 -221.462092) (xy 114.293142 -221.81693) (xy 114.301016 -221.838774) (xy 114.309614 -221.865187)
			(xy 114.318798 -221.919967) (xy 114.319304 -221.94774) (xy 115.53952 -221.94774) (xy 115.539971 -221.922394)
			(xy 115.547752 -221.872302) (xy 115.563106 -221.82399) (xy 115.585672 -221.778597) (xy 115.614918 -221.737192)
			(xy 115.650155 -221.700749) (xy 115.690554 -221.670127) (xy 115.735162 -221.646047) (xy 115.78293 -221.629076)
			(xy 115.807744 -221.62389) (xy 115.830604 -221.619572) (xy 116.035836 -221.264226) (xy 116.027962 -221.242128)
			(xy 116.019498 -221.215883) (xy 116.010425 -221.161495) (xy 116.009928 -221.133924) (xy 116.010436 -221.108037)
			(xy 116.018535 -221.056899) (xy 116.034534 -221.007659) (xy 116.05804 -220.961527) (xy 116.088472 -220.91964)
			(xy 116.125082 -220.88303) (xy 116.166969 -220.852598) (xy 116.213101 -220.829092) (xy 116.262341 -220.813093)
			(xy 116.313479 -220.804994) (xy 116.365253 -220.804994) (xy 116.416391 -220.813093) (xy 116.465631 -220.829092)
			(xy 116.511763 -220.852598) (xy 116.55365 -220.88303) (xy 116.59026 -220.91964) (xy 116.620692 -220.961527)
			(xy 116.644198 -221.007659) (xy 116.660197 -221.056899) (xy 116.668296 -221.108037) (xy 116.668804 -221.133924)
			(xy 116.668348 -221.159299) (xy 116.660576 -221.20945) (xy 116.645204 -221.257815) (xy 116.622597 -221.303251)
			(xy 116.593289 -221.344682) (xy 116.557973 -221.381128) (xy 116.517485 -221.411727) (xy 116.472784 -221.435754)
			(xy 116.424926 -221.452641) (xy 116.400072 -221.457774) (xy 116.377212 -221.462092) (xy 116.172488 -221.81693)
			(xy 116.180362 -221.838774) (xy 116.189019 -221.865179) (xy 116.198332 -221.919958) (xy 116.198904 -221.94774)
			(xy 117.41912 -221.94774) (xy 117.419571 -221.922394) (xy 117.427352 -221.872302) (xy 117.442706 -221.82399)
			(xy 117.465272 -221.778597) (xy 117.494518 -221.737192) (xy 117.529755 -221.700749) (xy 117.570154 -221.670127)
			(xy 117.614762 -221.646047) (xy 117.66253 -221.629076) (xy 117.687344 -221.62389) (xy 117.710204 -221.619572)
			(xy 117.915436 -221.264226) (xy 117.907562 -221.242128) (xy 117.899098 -221.215883) (xy 117.890025 -221.161495)
			(xy 117.889528 -221.133924) (xy 117.890036 -221.108037) (xy 117.898135 -221.056899) (xy 117.914134 -221.007659)
			(xy 117.93764 -220.961527) (xy 117.968072 -220.91964) (xy 118.004682 -220.88303) (xy 118.046569 -220.852598)
			(xy 118.092701 -220.829092) (xy 118.141941 -220.813093) (xy 118.193079 -220.804994) (xy 118.244853 -220.804994)
			(xy 118.295991 -220.813093) (xy 118.345231 -220.829092) (xy 118.391363 -220.852598) (xy 118.43325 -220.88303)
			(xy 118.46986 -220.91964) (xy 118.500292 -220.961527) (xy 118.523798 -221.007659) (xy 118.539797 -221.056899)
			(xy 118.547896 -221.108037) (xy 118.548404 -221.133924) (xy 118.547948 -221.159299) (xy 118.540176 -221.20945)
			(xy 118.524804 -221.257815) (xy 118.502197 -221.303251) (xy 118.472889 -221.344682) (xy 118.437573 -221.381128)
			(xy 118.397085 -221.411727) (xy 118.352384 -221.435754) (xy 118.304526 -221.452641) (xy 118.279672 -221.457774)
			(xy 118.256812 -221.462092) (xy 118.052088 -221.81693) (xy 118.059962 -221.838774) (xy 118.068619 -221.865179)
			(xy 118.077932 -221.919958) (xy 118.078504 -221.94774) (xy 121.17832 -221.94774) (xy 121.178771 -221.922394)
			(xy 121.186552 -221.872302) (xy 121.201906 -221.82399) (xy 121.224472 -221.778597) (xy 121.253718 -221.737192)
			(xy 121.288955 -221.700749) (xy 121.329354 -221.670127) (xy 121.373962 -221.646047) (xy 121.42173 -221.629076)
			(xy 121.446544 -221.62389) (xy 121.469404 -221.619572) (xy 121.674636 -221.264226) (xy 121.666762 -221.242128)
			(xy 121.658298 -221.215883) (xy 121.649225 -221.161495) (xy 121.648728 -221.133924) (xy 121.649236 -221.108037)
			(xy 121.657335 -221.056899) (xy 121.673334 -221.007659) (xy 121.69684 -220.961527) (xy 121.727272 -220.91964)
			(xy 121.763882 -220.88303) (xy 121.805769 -220.852598) (xy 121.851901 -220.829092) (xy 121.901141 -220.813093)
			(xy 121.952279 -220.804994) (xy 122.004053 -220.804994) (xy 122.055191 -220.813093) (xy 122.104431 -220.829092)
			(xy 122.150563 -220.852598) (xy 122.19245 -220.88303) (xy 122.22906 -220.91964) (xy 122.259492 -220.961527)
			(xy 122.282998 -221.007659) (xy 122.298997 -221.056899) (xy 122.307096 -221.108037) (xy 122.307604 -221.133924)
			(xy 122.307148 -221.159299) (xy 122.299376 -221.20945) (xy 122.284004 -221.257815) (xy 122.261397 -221.303251)
			(xy 122.232089 -221.344682) (xy 122.196773 -221.381128) (xy 122.156285 -221.411727) (xy 122.111584 -221.435754)
			(xy 122.063726 -221.452641) (xy 122.038872 -221.457774) (xy 122.016012 -221.462092) (xy 121.811288 -221.81693)
			(xy 121.819162 -221.838774) (xy 121.827819 -221.865179) (xy 121.837132 -221.919958) (xy 121.837704 -221.94774)
			(xy 123.05792 -221.94774) (xy 123.058371 -221.922394) (xy 123.066152 -221.872302) (xy 123.081506 -221.82399)
			(xy 123.104072 -221.778597) (xy 123.133318 -221.737192) (xy 123.168555 -221.700749) (xy 123.208954 -221.670127)
			(xy 123.253562 -221.646047) (xy 123.30133 -221.629076) (xy 123.326144 -221.62389) (xy 123.349004 -221.619572)
			(xy 123.554236 -221.264226) (xy 123.546362 -221.242128) (xy 123.537898 -221.215883) (xy 123.528825 -221.161495)
			(xy 123.528328 -221.133924) (xy 123.528836 -221.108037) (xy 123.536935 -221.056899) (xy 123.552934 -221.007659)
			(xy 123.57644 -220.961527) (xy 123.606872 -220.91964) (xy 123.643482 -220.88303) (xy 123.685369 -220.852598)
			(xy 123.731501 -220.829092) (xy 123.780741 -220.813093) (xy 123.831879 -220.804994) (xy 123.883653 -220.804994)
			(xy 123.934791 -220.813093) (xy 123.984031 -220.829092) (xy 124.030163 -220.852598) (xy 124.07205 -220.88303)
			(xy 124.10866 -220.91964) (xy 124.139092 -220.961527) (xy 124.162598 -221.007659) (xy 124.178597 -221.056899)
			(xy 124.186696 -221.108037) (xy 124.187204 -221.133924) (xy 124.186748 -221.159299) (xy 124.178976 -221.20945)
			(xy 124.163604 -221.257815) (xy 124.140997 -221.303251) (xy 124.111689 -221.344682) (xy 124.076373 -221.381128)
			(xy 124.035885 -221.411727) (xy 123.991184 -221.435754) (xy 123.943326 -221.452641) (xy 123.918472 -221.457774)
			(xy 123.895612 -221.462092) (xy 123.690888 -221.81693) (xy 123.698762 -221.838774) (xy 123.707419 -221.865179)
			(xy 123.716732 -221.919958) (xy 123.717304 -221.94774) (xy 124.93752 -221.94774) (xy 124.937971 -221.922394)
			(xy 124.945752 -221.872302) (xy 124.961106 -221.82399) (xy 124.983672 -221.778597) (xy 125.012918 -221.737192)
			(xy 125.048155 -221.700749) (xy 125.088554 -221.670127) (xy 125.133162 -221.646047) (xy 125.18093 -221.629076)
			(xy 125.205744 -221.62389) (xy 125.228604 -221.619572) (xy 125.433836 -221.264226) (xy 125.425962 -221.242128)
			(xy 125.417498 -221.215883) (xy 125.408425 -221.161495) (xy 125.407928 -221.133924) (xy 125.408436 -221.108037)
			(xy 125.416535 -221.056899) (xy 125.432534 -221.007659) (xy 125.45604 -220.961527) (xy 125.486472 -220.91964)
			(xy 125.523082 -220.88303) (xy 125.564969 -220.852598) (xy 125.611101 -220.829092) (xy 125.660341 -220.813093)
			(xy 125.711479 -220.804994) (xy 125.763253 -220.804994) (xy 125.814391 -220.813093) (xy 125.863631 -220.829092)
			(xy 125.909763 -220.852598) (xy 125.95165 -220.88303) (xy 125.98826 -220.91964) (xy 126.018692 -220.961527)
			(xy 126.042198 -221.007659) (xy 126.058197 -221.056899) (xy 126.066296 -221.108037) (xy 126.066804 -221.133924)
			(xy 126.066348 -221.159299) (xy 126.058576 -221.20945) (xy 126.043204 -221.257815) (xy 126.020597 -221.303251)
			(xy 125.991289 -221.344682) (xy 125.955973 -221.381128) (xy 125.915485 -221.411727) (xy 125.870784 -221.435754)
			(xy 125.822926 -221.452641) (xy 125.798072 -221.457774) (xy 125.775212 -221.462092) (xy 125.570488 -221.81693)
			(xy 125.578362 -221.838774) (xy 125.587019 -221.865179) (xy 125.596332 -221.919958) (xy 125.596904 -221.94774)
			(xy 126.81712 -221.94774) (xy 126.817571 -221.922394) (xy 126.825352 -221.872302) (xy 126.840706 -221.82399)
			(xy 126.863272 -221.778597) (xy 126.892518 -221.737192) (xy 126.927755 -221.700749) (xy 126.968154 -221.670127)
			(xy 127.012762 -221.646047) (xy 127.06053 -221.629076) (xy 127.085344 -221.62389) (xy 127.108204 -221.619572)
			(xy 127.313436 -221.264226) (xy 127.305562 -221.242128) (xy 127.297098 -221.215883) (xy 127.288025 -221.161495)
			(xy 127.287528 -221.133924) (xy 127.288036 -221.108037) (xy 127.296135 -221.056899) (xy 127.312134 -221.007659)
			(xy 127.33564 -220.961527) (xy 127.366072 -220.91964) (xy 127.402682 -220.88303) (xy 127.444569 -220.852598)
			(xy 127.490701 -220.829092) (xy 127.539941 -220.813093) (xy 127.591079 -220.804994) (xy 127.642853 -220.804994)
			(xy 127.693991 -220.813093) (xy 127.743231 -220.829092) (xy 127.789363 -220.852598) (xy 127.83125 -220.88303)
			(xy 127.86786 -220.91964) (xy 127.898292 -220.961527) (xy 127.921798 -221.007659) (xy 127.937797 -221.056899)
			(xy 127.945896 -221.108037) (xy 127.946404 -221.133924) (xy 127.945948 -221.159299) (xy 127.938176 -221.20945)
			(xy 127.922804 -221.257815) (xy 127.900197 -221.303251) (xy 127.870889 -221.344682) (xy 127.835573 -221.381128)
			(xy 127.795085 -221.411727) (xy 127.750384 -221.435754) (xy 127.702526 -221.452641) (xy 127.677672 -221.457774)
			(xy 127.654812 -221.462092) (xy 127.450088 -221.81693) (xy 127.457962 -221.838774) (xy 127.466619 -221.865179)
			(xy 127.475932 -221.919958) (xy 127.476504 -221.94774) (xy 128.69672 -221.94774) (xy 128.697171 -221.922394)
			(xy 128.704952 -221.872302) (xy 128.720306 -221.82399) (xy 128.742872 -221.778597) (xy 128.772118 -221.737192)
			(xy 128.807355 -221.700749) (xy 128.847754 -221.670127) (xy 128.892362 -221.646047) (xy 128.94013 -221.629076)
			(xy 128.964944 -221.62389) (xy 128.987804 -221.619572) (xy 129.193036 -221.264226) (xy 129.185162 -221.242128)
			(xy 129.176698 -221.215883) (xy 129.167625 -221.161495) (xy 129.167128 -221.133924) (xy 129.167636 -221.108037)
			(xy 129.175735 -221.056899) (xy 129.191734 -221.007659) (xy 129.21524 -220.961527) (xy 129.245672 -220.91964)
			(xy 129.282282 -220.88303) (xy 129.324169 -220.852598) (xy 129.370301 -220.829092) (xy 129.419541 -220.813093)
			(xy 129.470679 -220.804994) (xy 129.522453 -220.804994) (xy 129.573591 -220.813093) (xy 129.622831 -220.829092)
			(xy 129.668963 -220.852598) (xy 129.71085 -220.88303) (xy 129.74746 -220.91964) (xy 129.777892 -220.961527)
			(xy 129.801398 -221.007659) (xy 129.817397 -221.056899) (xy 129.825496 -221.108037) (xy 129.826004 -221.133924)
			(xy 129.825548 -221.159299) (xy 129.817776 -221.20945) (xy 129.802404 -221.257815) (xy 129.779797 -221.303251)
			(xy 129.750489 -221.344682) (xy 129.715173 -221.381128) (xy 129.674685 -221.411727) (xy 129.629984 -221.435754)
			(xy 129.582126 -221.452641) (xy 129.557272 -221.457774) (xy 129.534412 -221.462092) (xy 129.329688 -221.81693)
			(xy 129.337562 -221.838774) (xy 129.346219 -221.865179) (xy 129.355532 -221.919958) (xy 129.356104 -221.94774)
			(xy 130.57632 -221.94774) (xy 130.576771 -221.922394) (xy 130.584552 -221.872302) (xy 130.599906 -221.82399)
			(xy 130.622472 -221.778597) (xy 130.651718 -221.737192) (xy 130.686955 -221.700749) (xy 130.727354 -221.670127)
			(xy 130.771962 -221.646047) (xy 130.81973 -221.629076) (xy 130.844544 -221.62389) (xy 130.867404 -221.619572)
			(xy 131.072636 -221.264226) (xy 131.064762 -221.242128) (xy 131.056298 -221.215883) (xy 131.047225 -221.161495)
			(xy 131.046728 -221.133924) (xy 131.047236 -221.108037) (xy 131.055335 -221.056899) (xy 131.071334 -221.007659)
			(xy 131.09484 -220.961527) (xy 131.125272 -220.91964) (xy 131.161882 -220.88303) (xy 131.203769 -220.852598)
			(xy 131.249901 -220.829092) (xy 131.299141 -220.813093) (xy 131.350279 -220.804994) (xy 131.402053 -220.804994)
			(xy 131.453191 -220.813093) (xy 131.502431 -220.829092) (xy 131.548563 -220.852598) (xy 131.59045 -220.88303)
			(xy 131.62706 -220.91964) (xy 131.657492 -220.961527) (xy 131.680998 -221.007659) (xy 131.696997 -221.056899)
			(xy 131.705096 -221.108037) (xy 131.705604 -221.133924) (xy 131.705148 -221.159299) (xy 131.697376 -221.20945)
			(xy 131.682004 -221.257815) (xy 131.659397 -221.303251) (xy 131.630089 -221.344682) (xy 131.594773 -221.381128)
			(xy 131.554285 -221.411727) (xy 131.509584 -221.435754) (xy 131.461726 -221.452641) (xy 131.436872 -221.457774)
			(xy 131.414012 -221.462092) (xy 131.209288 -221.81693) (xy 131.217162 -221.838774) (xy 131.225819 -221.865179)
			(xy 131.235132 -221.919958) (xy 131.235704 -221.94774) (xy 132.45592 -221.94774) (xy 132.456371 -221.922394)
			(xy 132.464152 -221.872302) (xy 132.479506 -221.82399) (xy 132.502072 -221.778597) (xy 132.531318 -221.737192)
			(xy 132.566555 -221.700749) (xy 132.606954 -221.670127) (xy 132.651562 -221.646047) (xy 132.69933 -221.629076)
			(xy 132.724144 -221.62389) (xy 132.747004 -221.619572) (xy 132.951982 -221.263972) (xy 132.944362 -221.242128)
			(xy 132.935911 -221.215946) (xy 132.92684 -221.161685) (xy 132.926328 -221.134178) (xy 132.926328 -221.133924)
			(xy 132.926836 -221.108037) (xy 132.934935 -221.056899) (xy 132.950934 -221.007659) (xy 132.97444 -220.961527)
			(xy 133.004872 -220.91964) (xy 133.041482 -220.88303) (xy 133.083369 -220.852598) (xy 133.129501 -220.829092)
			(xy 133.178741 -220.813093) (xy 133.229879 -220.804994) (xy 133.281653 -220.804994) (xy 133.332791 -220.813093)
			(xy 133.382031 -220.829092) (xy 133.428163 -220.852598) (xy 133.47005 -220.88303) (xy 133.50666 -220.91964)
			(xy 133.537092 -220.961527) (xy 133.560598 -221.007659) (xy 133.576597 -221.056899) (xy 133.584696 -221.108037)
			(xy 133.585204 -221.133924) (xy 133.584785 -221.15929) (xy 133.577033 -221.209425) (xy 133.561684 -221.257778)
			(xy 133.539102 -221.303206) (xy 133.509821 -221.344633) (xy 133.474533 -221.381081) (xy 133.434074 -221.411686)
			(xy 133.3894 -221.435725) (xy 133.341569 -221.45263) (xy 133.316726 -221.457774) (xy 133.293866 -221.462092)
			(xy 133.089142 -221.81693) (xy 133.096762 -221.838774) (xy 133.105377 -221.865059) (xy 133.114698 -221.919578)
			(xy 133.115304 -221.947232) (xy 133.115304 -221.94774) (xy 134.33552 -221.94774) (xy 134.335971 -221.922394)
			(xy 134.343752 -221.872302) (xy 134.359106 -221.82399) (xy 134.381672 -221.778597) (xy 134.410918 -221.737192)
			(xy 134.446155 -221.700749) (xy 134.486554 -221.670127) (xy 134.531162 -221.646047) (xy 134.57893 -221.629076)
			(xy 134.603744 -221.62389) (xy 134.626604 -221.619572) (xy 134.831582 -221.263972) (xy 134.823962 -221.242128)
			(xy 134.815511 -221.215946) (xy 134.80644 -221.161685) (xy 134.805928 -221.134178) (xy 134.805928 -221.133924)
			(xy 134.806436 -221.108037) (xy 134.814535 -221.056899) (xy 134.830534 -221.007659) (xy 134.85404 -220.961527)
			(xy 134.884472 -220.91964) (xy 134.921082 -220.88303) (xy 134.962969 -220.852598) (xy 135.009101 -220.829092)
			(xy 135.058341 -220.813093) (xy 135.109479 -220.804994) (xy 135.161253 -220.804994) (xy 135.212391 -220.813093)
			(xy 135.261631 -220.829092) (xy 135.307763 -220.852598) (xy 135.34965 -220.88303) (xy 135.38626 -220.91964)
			(xy 135.416692 -220.961527) (xy 135.440198 -221.007659) (xy 135.456197 -221.056899) (xy 135.464296 -221.108037)
			(xy 135.464804 -221.133924) (xy 336.695796 -221.133924) (xy 336.696304 -221.108037) (xy 336.704403 -221.056899)
			(xy 336.720402 -221.007659) (xy 336.743908 -220.961527) (xy 336.77434 -220.91964) (xy 336.81095 -220.88303)
			(xy 336.852837 -220.852598) (xy 336.898969 -220.829092) (xy 336.948209 -220.813093) (xy 336.999347 -220.804994)
			(xy 337.051121 -220.804994) (xy 337.102259 -220.813093) (xy 337.151499 -220.829092) (xy 337.197631 -220.852598)
			(xy 337.239518 -220.88303) (xy 337.276128 -220.91964) (xy 337.30656 -220.961527) (xy 337.330066 -221.007659)
			(xy 337.346065 -221.056899) (xy 337.354164 -221.108037) (xy 337.354672 -221.133924) (xy 337.635596 -221.133924)
			(xy 337.636104 -221.10859) (xy 337.643853 -221.058519) (xy 337.659172 -221.010223) (xy 337.6817 -220.96484)
			(xy 337.710906 -220.923438) (xy 337.746104 -220.886992) (xy 337.786463 -220.856361) (xy 337.831034 -220.832266)
			(xy 337.878767 -220.815274) (xy 337.903566 -220.810074) (xy 337.926426 -220.805756) (xy 338.131404 -220.450664)
			(xy 338.12353 -220.42882) (xy 338.114896 -220.402408) (xy 338.105568 -220.347635) (xy 338.104988 -220.319854)
			(xy 338.105496 -220.293947) (xy 338.113602 -220.24277) (xy 338.129614 -220.193491) (xy 338.153137 -220.147324)
			(xy 338.183593 -220.105405) (xy 338.220231 -220.068767) (xy 338.26215 -220.038311) (xy 338.308317 -220.014788)
			(xy 338.357596 -219.998776) (xy 338.408773 -219.99067) (xy 338.460587 -219.99067) (xy 338.511764 -219.998776)
			(xy 338.561043 -220.014788) (xy 338.60721 -220.038311) (xy 338.649129 -220.068767) (xy 338.685767 -220.105405)
			(xy 338.716223 -220.147324) (xy 338.739746 -220.193491) (xy 338.755758 -220.24277) (xy 338.763864 -220.293947)
			(xy 338.764372 -220.319854) (xy 338.763922 -220.3452) (xy 338.756142 -220.395293) (xy 338.740788 -220.443604)
			(xy 338.718222 -220.488998) (xy 338.688976 -220.530404) (xy 338.653739 -220.566847) (xy 338.61334 -220.597469)
			(xy 338.568731 -220.621548) (xy 338.520963 -220.638518) (xy 338.496148 -220.643704) (xy 338.473288 -220.648022)
			(xy 338.26831 -221.003114) (xy 338.276184 -221.024958) (xy 338.284777 -221.051373) (xy 338.293965 -221.106151)
			(xy 338.294472 -221.133924) (xy 338.575396 -221.133924) (xy 338.575904 -221.108037) (xy 338.584003 -221.056899)
			(xy 338.600002 -221.007659) (xy 338.623508 -220.961527) (xy 338.65394 -220.91964) (xy 338.69055 -220.88303)
			(xy 338.732437 -220.852598) (xy 338.778569 -220.829092) (xy 338.827809 -220.813093) (xy 338.878947 -220.804994)
			(xy 338.930721 -220.804994) (xy 338.981859 -220.813093) (xy 339.031099 -220.829092) (xy 339.077231 -220.852598)
			(xy 339.119118 -220.88303) (xy 339.155728 -220.91964) (xy 339.18616 -220.961527) (xy 339.209666 -221.007659)
			(xy 339.225665 -221.056899) (xy 339.233764 -221.108037) (xy 339.234272 -221.133924) (xy 339.515196 -221.133924)
			(xy 339.515704 -221.10859) (xy 339.523453 -221.058519) (xy 339.538772 -221.010223) (xy 339.5613 -220.96484)
			(xy 339.590506 -220.923438) (xy 339.625704 -220.886992) (xy 339.666063 -220.856361) (xy 339.710634 -220.832266)
			(xy 339.758367 -220.815274) (xy 339.783166 -220.810074) (xy 339.806026 -220.805756) (xy 340.011004 -220.450664)
			(xy 340.00313 -220.42882) (xy 339.994496 -220.402408) (xy 339.985168 -220.347635) (xy 339.984588 -220.319854)
			(xy 339.985096 -220.293947) (xy 339.993202 -220.24277) (xy 340.009214 -220.193491) (xy 340.032737 -220.147324)
			(xy 340.063193 -220.105405) (xy 340.099831 -220.068767) (xy 340.14175 -220.038311) (xy 340.187917 -220.014788)
			(xy 340.237196 -219.998776) (xy 340.288373 -219.99067) (xy 340.340187 -219.99067) (xy 340.391364 -219.998776)
			(xy 340.440643 -220.014788) (xy 340.48681 -220.038311) (xy 340.528729 -220.068767) (xy 340.565367 -220.105405)
			(xy 340.595823 -220.147324) (xy 340.619346 -220.193491) (xy 340.635358 -220.24277) (xy 340.643464 -220.293947)
			(xy 340.643972 -220.319854) (xy 340.643522 -220.3452) (xy 340.635742 -220.395293) (xy 340.620388 -220.443604)
			(xy 340.597822 -220.488998) (xy 340.568576 -220.530404) (xy 340.533339 -220.566847) (xy 340.49294 -220.597469)
			(xy 340.448331 -220.621548) (xy 340.400563 -220.638518) (xy 340.375748 -220.643704) (xy 340.352888 -220.648022)
			(xy 340.14791 -221.003114) (xy 340.155784 -221.024958) (xy 340.164377 -221.051373) (xy 340.173565 -221.106151)
			(xy 340.174072 -221.133924) (xy 340.454996 -221.133924) (xy 340.455504 -221.108037) (xy 340.463603 -221.056899)
			(xy 340.479602 -221.007659) (xy 340.503108 -220.961527) (xy 340.53354 -220.91964) (xy 340.57015 -220.88303)
			(xy 340.612037 -220.852598) (xy 340.658169 -220.829092) (xy 340.707409 -220.813093) (xy 340.758547 -220.804994)
			(xy 340.810321 -220.804994) (xy 340.861459 -220.813093) (xy 340.910699 -220.829092) (xy 340.956831 -220.852598)
			(xy 340.998718 -220.88303) (xy 341.035328 -220.91964) (xy 341.06576 -220.961527) (xy 341.089266 -221.007659)
			(xy 341.105265 -221.056899) (xy 341.113364 -221.108037) (xy 341.113872 -221.133924) (xy 341.394796 -221.133924)
			(xy 341.395304 -221.10859) (xy 341.403053 -221.058519) (xy 341.418372 -221.010223) (xy 341.4409 -220.96484)
			(xy 341.470106 -220.923438) (xy 341.505304 -220.886992) (xy 341.545663 -220.856361) (xy 341.590234 -220.832266)
			(xy 341.637967 -220.815274) (xy 341.662766 -220.810074) (xy 341.685626 -220.805756) (xy 341.890604 -220.450664)
			(xy 341.88273 -220.42882) (xy 341.874096 -220.402408) (xy 341.864768 -220.347635) (xy 341.864188 -220.319854)
			(xy 341.864696 -220.293947) (xy 341.872802 -220.24277) (xy 341.888814 -220.193491) (xy 341.912337 -220.147324)
			(xy 341.942793 -220.105405) (xy 341.979431 -220.068767) (xy 342.02135 -220.038311) (xy 342.067517 -220.014788)
			(xy 342.116796 -219.998776) (xy 342.167973 -219.99067) (xy 342.219787 -219.99067) (xy 342.270964 -219.998776)
			(xy 342.320243 -220.014788) (xy 342.36641 -220.038311) (xy 342.408329 -220.068767) (xy 342.444967 -220.105405)
			(xy 342.475423 -220.147324) (xy 342.498946 -220.193491) (xy 342.514958 -220.24277) (xy 342.523064 -220.293947)
			(xy 342.523572 -220.319854) (xy 342.523122 -220.3452) (xy 342.515342 -220.395293) (xy 342.499988 -220.443604)
			(xy 342.477422 -220.488998) (xy 342.448176 -220.530404) (xy 342.412939 -220.566847) (xy 342.37254 -220.597469)
			(xy 342.327931 -220.621548) (xy 342.280163 -220.638518) (xy 342.255348 -220.643704) (xy 342.232488 -220.648022)
			(xy 342.02751 -221.003114) (xy 342.035384 -221.024958) (xy 342.043977 -221.051373) (xy 342.053165 -221.106151)
			(xy 342.053672 -221.133924) (xy 342.334596 -221.133924) (xy 342.335104 -221.108037) (xy 342.343203 -221.056899)
			(xy 342.359202 -221.007659) (xy 342.382708 -220.961527) (xy 342.41314 -220.91964) (xy 342.44975 -220.88303)
			(xy 342.491637 -220.852598) (xy 342.537769 -220.829092) (xy 342.587009 -220.813093) (xy 342.638147 -220.804994)
			(xy 342.689921 -220.804994) (xy 342.741059 -220.813093) (xy 342.790299 -220.829092) (xy 342.836431 -220.852598)
			(xy 342.878318 -220.88303) (xy 342.914928 -220.91964) (xy 342.94536 -220.961527) (xy 342.968866 -221.007659)
			(xy 342.984865 -221.056899) (xy 342.992964 -221.108037) (xy 342.993472 -221.133924) (xy 343.274396 -221.133924)
			(xy 343.274904 -221.10859) (xy 343.282653 -221.058519) (xy 343.297972 -221.010223) (xy 343.3205 -220.96484)
			(xy 343.349706 -220.923438) (xy 343.384904 -220.886992) (xy 343.425263 -220.856361) (xy 343.469834 -220.832266)
			(xy 343.517567 -220.815274) (xy 343.542366 -220.810074) (xy 343.565226 -220.805756) (xy 343.770204 -220.450664)
			(xy 343.76233 -220.42882) (xy 343.753696 -220.402408) (xy 343.744368 -220.347635) (xy 343.743788 -220.319854)
			(xy 343.744296 -220.293947) (xy 343.752402 -220.24277) (xy 343.768414 -220.193491) (xy 343.791937 -220.147324)
			(xy 343.822393 -220.105405) (xy 343.859031 -220.068767) (xy 343.90095 -220.038311) (xy 343.947117 -220.014788)
			(xy 343.996396 -219.998776) (xy 344.047573 -219.99067) (xy 344.099387 -219.99067) (xy 344.150564 -219.998776)
			(xy 344.199843 -220.014788) (xy 344.24601 -220.038311) (xy 344.287929 -220.068767) (xy 344.324567 -220.105405)
			(xy 344.355023 -220.147324) (xy 344.378546 -220.193491) (xy 344.394558 -220.24277) (xy 344.402664 -220.293947)
			(xy 344.403172 -220.319854) (xy 344.402722 -220.3452) (xy 344.394942 -220.395293) (xy 344.379588 -220.443604)
			(xy 344.357022 -220.488998) (xy 344.327776 -220.530404) (xy 344.292539 -220.566847) (xy 344.25214 -220.597469)
			(xy 344.207531 -220.621548) (xy 344.159763 -220.638518) (xy 344.134948 -220.643704) (xy 344.112088 -220.648022)
			(xy 343.90711 -221.003114) (xy 343.914984 -221.024958) (xy 343.923577 -221.051373) (xy 343.932765 -221.106151)
			(xy 343.933272 -221.133924) (xy 344.214196 -221.133924) (xy 344.214704 -221.108037) (xy 344.222803 -221.056899)
			(xy 344.238802 -221.007659) (xy 344.262308 -220.961527) (xy 344.29274 -220.91964) (xy 344.32935 -220.88303)
			(xy 344.371237 -220.852598) (xy 344.417369 -220.829092) (xy 344.466609 -220.813093) (xy 344.517747 -220.804994)
			(xy 344.569521 -220.804994) (xy 344.620659 -220.813093) (xy 344.669899 -220.829092) (xy 344.716031 -220.852598)
			(xy 344.757918 -220.88303) (xy 344.794528 -220.91964) (xy 344.82496 -220.961527) (xy 344.848466 -221.007659)
			(xy 344.864465 -221.056899) (xy 344.872564 -221.108037) (xy 344.873072 -221.133924) (xy 345.153996 -221.133924)
			(xy 345.154504 -221.10859) (xy 345.162253 -221.058519) (xy 345.177572 -221.010223) (xy 345.2001 -220.96484)
			(xy 345.229306 -220.923438) (xy 345.264504 -220.886992) (xy 345.304863 -220.856361) (xy 345.349434 -220.832266)
			(xy 345.397167 -220.815274) (xy 345.421966 -220.810074) (xy 345.444826 -220.805756) (xy 345.649804 -220.450664)
			(xy 345.64193 -220.42882) (xy 345.633296 -220.402408) (xy 345.623968 -220.347635) (xy 345.623388 -220.319854)
			(xy 345.623896 -220.293947) (xy 345.632002 -220.24277) (xy 345.648014 -220.193491) (xy 345.671537 -220.147324)
			(xy 345.701993 -220.105405) (xy 345.738631 -220.068767) (xy 345.78055 -220.038311) (xy 345.826717 -220.014788)
			(xy 345.875996 -219.998776) (xy 345.927173 -219.99067) (xy 345.978987 -219.99067) (xy 346.030164 -219.998776)
			(xy 346.079443 -220.014788) (xy 346.12561 -220.038311) (xy 346.167529 -220.068767) (xy 346.204167 -220.105405)
			(xy 346.234623 -220.147324) (xy 346.258146 -220.193491) (xy 346.274158 -220.24277) (xy 346.282264 -220.293947)
			(xy 346.282772 -220.319854) (xy 346.282322 -220.3452) (xy 346.274542 -220.395293) (xy 346.259188 -220.443604)
			(xy 346.236622 -220.488998) (xy 346.207376 -220.530404) (xy 346.172139 -220.566847) (xy 346.13174 -220.597469)
			(xy 346.087131 -220.621548) (xy 346.039363 -220.638518) (xy 346.014548 -220.643704) (xy 345.991688 -220.648022)
			(xy 345.78671 -221.003114) (xy 345.794584 -221.024958) (xy 345.803177 -221.051373) (xy 345.812365 -221.106151)
			(xy 345.812872 -221.133924) (xy 346.093796 -221.133924) (xy 346.094304 -221.108037) (xy 346.102403 -221.056899)
			(xy 346.118402 -221.007659) (xy 346.141908 -220.961527) (xy 346.17234 -220.91964) (xy 346.20895 -220.88303)
			(xy 346.250837 -220.852598) (xy 346.296969 -220.829092) (xy 346.346209 -220.813093) (xy 346.397347 -220.804994)
			(xy 346.449121 -220.804994) (xy 346.500259 -220.813093) (xy 346.549499 -220.829092) (xy 346.595631 -220.852598)
			(xy 346.637518 -220.88303) (xy 346.674128 -220.91964) (xy 346.70456 -220.961527) (xy 346.728066 -221.007659)
			(xy 346.744065 -221.056899) (xy 346.752164 -221.108037) (xy 346.752672 -221.133924) (xy 347.033596 -221.133924)
			(xy 347.034104 -221.10859) (xy 347.041853 -221.058519) (xy 347.057172 -221.010223) (xy 347.0797 -220.96484)
			(xy 347.108906 -220.923438) (xy 347.144104 -220.886992) (xy 347.184463 -220.856361) (xy 347.229034 -220.832266)
			(xy 347.276767 -220.815274) (xy 347.301566 -220.810074) (xy 347.324426 -220.805756) (xy 347.529404 -220.450664)
			(xy 347.52153 -220.42882) (xy 347.512896 -220.402408) (xy 347.503568 -220.347635) (xy 347.502988 -220.319854)
			(xy 347.503496 -220.293947) (xy 347.511602 -220.24277) (xy 347.527614 -220.193491) (xy 347.551137 -220.147324)
			(xy 347.581593 -220.105405) (xy 347.618231 -220.068767) (xy 347.66015 -220.038311) (xy 347.706317 -220.014788)
			(xy 347.755596 -219.998776) (xy 347.806773 -219.99067) (xy 347.858587 -219.99067) (xy 347.909764 -219.998776)
			(xy 347.959043 -220.014788) (xy 348.00521 -220.038311) (xy 348.047129 -220.068767) (xy 348.083767 -220.105405)
			(xy 348.114223 -220.147324) (xy 348.137746 -220.193491) (xy 348.153758 -220.24277) (xy 348.161864 -220.293947)
			(xy 348.162372 -220.319854) (xy 348.161922 -220.3452) (xy 348.154142 -220.395293) (xy 348.138788 -220.443604)
			(xy 348.116222 -220.488998) (xy 348.086976 -220.530404) (xy 348.051739 -220.566847) (xy 348.01134 -220.597469)
			(xy 347.966731 -220.621548) (xy 347.918963 -220.638518) (xy 347.894148 -220.643704) (xy 347.871288 -220.648022)
			(xy 347.66631 -221.003114) (xy 347.674184 -221.024958) (xy 347.682777 -221.051373) (xy 347.691965 -221.106151)
			(xy 347.692472 -221.133924) (xy 347.973396 -221.133924) (xy 347.973904 -221.108037) (xy 347.982003 -221.056899)
			(xy 347.998002 -221.007659) (xy 348.021508 -220.961527) (xy 348.05194 -220.91964) (xy 348.08855 -220.88303)
			(xy 348.130437 -220.852598) (xy 348.176569 -220.829092) (xy 348.225809 -220.813093) (xy 348.276947 -220.804994)
			(xy 348.328721 -220.804994) (xy 348.379859 -220.813093) (xy 348.429099 -220.829092) (xy 348.475231 -220.852598)
			(xy 348.517118 -220.88303) (xy 348.553728 -220.91964) (xy 348.58416 -220.961527) (xy 348.607666 -221.007659)
			(xy 348.623665 -221.056899) (xy 348.631764 -221.108037) (xy 348.632272 -221.133924) (xy 348.913196 -221.133924)
			(xy 348.913704 -221.10859) (xy 348.921453 -221.058519) (xy 348.936772 -221.010223) (xy 348.9593 -220.96484)
			(xy 348.988506 -220.923438) (xy 349.023704 -220.886992) (xy 349.064063 -220.856361) (xy 349.108634 -220.832266)
			(xy 349.156367 -220.815274) (xy 349.181166 -220.810074) (xy 349.204026 -220.805756) (xy 349.409004 -220.450664)
			(xy 349.40113 -220.42882) (xy 349.392496 -220.402408) (xy 349.383168 -220.347635) (xy 349.382588 -220.319854)
			(xy 349.383096 -220.293947) (xy 349.391202 -220.24277) (xy 349.407214 -220.193491) (xy 349.430737 -220.147324)
			(xy 349.461193 -220.105405) (xy 349.497831 -220.068767) (xy 349.53975 -220.038311) (xy 349.585917 -220.014788)
			(xy 349.635196 -219.998776) (xy 349.686373 -219.99067) (xy 349.738187 -219.99067) (xy 349.789364 -219.998776)
			(xy 349.838643 -220.014788) (xy 349.88481 -220.038311) (xy 349.926729 -220.068767) (xy 349.963367 -220.105405)
			(xy 349.993823 -220.147324) (xy 350.017346 -220.193491) (xy 350.033358 -220.24277) (xy 350.041464 -220.293947)
			(xy 350.041972 -220.319854) (xy 350.041522 -220.3452) (xy 350.033742 -220.395293) (xy 350.018388 -220.443604)
			(xy 349.995822 -220.488998) (xy 349.966576 -220.530404) (xy 349.931339 -220.566847) (xy 349.89094 -220.597469)
			(xy 349.846331 -220.621548) (xy 349.798563 -220.638518) (xy 349.773748 -220.643704) (xy 349.750888 -220.648022)
			(xy 349.54591 -221.003114) (xy 349.553784 -221.024958) (xy 349.562377 -221.051373) (xy 349.571565 -221.106151)
			(xy 349.572072 -221.133924) (xy 349.852996 -221.133924) (xy 349.853504 -221.108037) (xy 349.861603 -221.056899)
			(xy 349.877602 -221.007659) (xy 349.901108 -220.961527) (xy 349.93154 -220.91964) (xy 349.96815 -220.88303)
			(xy 350.010037 -220.852598) (xy 350.056169 -220.829092) (xy 350.105409 -220.813093) (xy 350.156547 -220.804994)
			(xy 350.208321 -220.804994) (xy 350.259459 -220.813093) (xy 350.308699 -220.829092) (xy 350.354831 -220.852598)
			(xy 350.396718 -220.88303) (xy 350.433328 -220.91964) (xy 350.46376 -220.961527) (xy 350.487266 -221.007659)
			(xy 350.503265 -221.056899) (xy 350.511364 -221.108037) (xy 350.511872 -221.133924) (xy 350.792796 -221.133924)
			(xy 350.793304 -221.10859) (xy 350.801053 -221.058519) (xy 350.816372 -221.010223) (xy 350.8389 -220.96484)
			(xy 350.868106 -220.923438) (xy 350.903304 -220.886992) (xy 350.943663 -220.856361) (xy 350.988234 -220.832266)
			(xy 351.035967 -220.815274) (xy 351.060766 -220.810074) (xy 351.083626 -220.805756) (xy 351.288604 -220.450664)
			(xy 351.28073 -220.42882) (xy 351.272096 -220.402408) (xy 351.262768 -220.347635) (xy 351.262188 -220.319854)
			(xy 351.262696 -220.293947) (xy 351.270802 -220.24277) (xy 351.286814 -220.193491) (xy 351.310337 -220.147324)
			(xy 351.340793 -220.105405) (xy 351.377431 -220.068767) (xy 351.41935 -220.038311) (xy 351.465517 -220.014788)
			(xy 351.514796 -219.998776) (xy 351.565973 -219.99067) (xy 351.617787 -219.99067) (xy 351.668964 -219.998776)
			(xy 351.718243 -220.014788) (xy 351.76441 -220.038311) (xy 351.806329 -220.068767) (xy 351.842967 -220.105405)
			(xy 351.873423 -220.147324) (xy 351.896946 -220.193491) (xy 351.912958 -220.24277) (xy 351.921064 -220.293947)
			(xy 351.921572 -220.319854) (xy 353.141788 -220.319854) (xy 353.142296 -220.293947) (xy 353.150402 -220.24277)
			(xy 353.166414 -220.193491) (xy 353.189937 -220.147324) (xy 353.220393 -220.105405) (xy 353.257031 -220.068767)
			(xy 353.29895 -220.038311) (xy 353.345117 -220.014788) (xy 353.394396 -219.998776) (xy 353.445573 -219.99067)
			(xy 353.497387 -219.99067) (xy 353.548564 -219.998776) (xy 353.597843 -220.014788) (xy 353.64401 -220.038311)
			(xy 353.685929 -220.068767) (xy 353.722567 -220.105405) (xy 353.753023 -220.147324) (xy 353.776546 -220.193491)
			(xy 353.792558 -220.24277) (xy 353.800664 -220.293947) (xy 353.801172 -220.319854) (xy 355.021388 -220.319854)
			(xy 355.021896 -220.293947) (xy 355.030002 -220.24277) (xy 355.046014 -220.193491) (xy 355.069537 -220.147324)
			(xy 355.099993 -220.105405) (xy 355.136631 -220.068767) (xy 355.17855 -220.038311) (xy 355.224717 -220.014788)
			(xy 355.273996 -219.998776) (xy 355.325173 -219.99067) (xy 355.376987 -219.99067) (xy 355.428164 -219.998776)
			(xy 355.477443 -220.014788) (xy 355.52361 -220.038311) (xy 355.565529 -220.068767) (xy 355.602167 -220.105405)
			(xy 355.632623 -220.147324) (xy 355.656146 -220.193491) (xy 355.672158 -220.24277) (xy 355.680264 -220.293947)
			(xy 355.680772 -220.319854) (xy 356.900988 -220.319854) (xy 356.901496 -220.293947) (xy 356.909602 -220.24277)
			(xy 356.925614 -220.193491) (xy 356.949137 -220.147324) (xy 356.979593 -220.105405) (xy 357.016231 -220.068767)
			(xy 357.05815 -220.038311) (xy 357.104317 -220.014788) (xy 357.153596 -219.998776) (xy 357.204773 -219.99067)
			(xy 357.256587 -219.99067) (xy 357.307764 -219.998776) (xy 357.357043 -220.014788) (xy 357.40321 -220.038311)
			(xy 357.445129 -220.068767) (xy 357.481767 -220.105405) (xy 357.512223 -220.147324) (xy 357.535746 -220.193491)
			(xy 357.551758 -220.24277) (xy 357.559864 -220.293947) (xy 357.560372 -220.319854) (xy 358.780588 -220.319854)
			(xy 358.781096 -220.293947) (xy 358.789202 -220.24277) (xy 358.805214 -220.193491) (xy 358.828737 -220.147324)
			(xy 358.859193 -220.105405) (xy 358.895831 -220.068767) (xy 358.93775 -220.038311) (xy 358.983917 -220.014788)
			(xy 359.033196 -219.998776) (xy 359.084373 -219.99067) (xy 359.136187 -219.99067) (xy 359.187364 -219.998776)
			(xy 359.236643 -220.014788) (xy 359.28281 -220.038311) (xy 359.324729 -220.068767) (xy 359.361367 -220.105405)
			(xy 359.391823 -220.147324) (xy 359.415346 -220.193491) (xy 359.431358 -220.24277) (xy 359.439464 -220.293947)
			(xy 359.439972 -220.319854) (xy 360.660188 -220.319854) (xy 360.660696 -220.293947) (xy 360.668802 -220.24277)
			(xy 360.684814 -220.193491) (xy 360.708337 -220.147324) (xy 360.738793 -220.105405) (xy 360.775431 -220.068767)
			(xy 360.81735 -220.038311) (xy 360.863517 -220.014788) (xy 360.912796 -219.998776) (xy 360.963973 -219.99067)
			(xy 361.015787 -219.99067) (xy 361.066964 -219.998776) (xy 361.116243 -220.014788) (xy 361.16241 -220.038311)
			(xy 361.204329 -220.068767) (xy 361.240967 -220.105405) (xy 361.271423 -220.147324) (xy 361.294946 -220.193491)
			(xy 361.310958 -220.24277) (xy 361.319064 -220.293947) (xy 361.319572 -220.319854) (xy 362.539788 -220.319854)
			(xy 362.540296 -220.293947) (xy 362.548402 -220.24277) (xy 362.564414 -220.193491) (xy 362.587937 -220.147324)
			(xy 362.618393 -220.105405) (xy 362.655031 -220.068767) (xy 362.69695 -220.038311) (xy 362.743117 -220.014788)
			(xy 362.792396 -219.998776) (xy 362.843573 -219.99067) (xy 362.895387 -219.99067) (xy 362.946564 -219.998776)
			(xy 362.995843 -220.014788) (xy 363.04201 -220.038311) (xy 363.083929 -220.068767) (xy 363.120567 -220.105405)
			(xy 363.151023 -220.147324) (xy 363.174546 -220.193491) (xy 363.190558 -220.24277) (xy 363.198664 -220.293947)
			(xy 363.199172 -220.319854) (xy 364.419388 -220.319854) (xy 364.419896 -220.293947) (xy 364.428002 -220.24277)
			(xy 364.444014 -220.193491) (xy 364.467537 -220.147324) (xy 364.497993 -220.105405) (xy 364.534631 -220.068767)
			(xy 364.57655 -220.038311) (xy 364.622717 -220.014788) (xy 364.671996 -219.998776) (xy 364.723173 -219.99067)
			(xy 364.774987 -219.99067) (xy 364.826164 -219.998776) (xy 364.875443 -220.014788) (xy 364.92161 -220.038311)
			(xy 364.963529 -220.068767) (xy 365.000167 -220.105405) (xy 365.030623 -220.147324) (xy 365.054146 -220.193491)
			(xy 365.070158 -220.24277) (xy 365.078264 -220.293947) (xy 365.078772 -220.319854) (xy 366.298988 -220.319854)
			(xy 366.299496 -220.293947) (xy 366.307602 -220.24277) (xy 366.323614 -220.193491) (xy 366.347137 -220.147324)
			(xy 366.377593 -220.105405) (xy 366.414231 -220.068767) (xy 366.45615 -220.038311) (xy 366.502317 -220.014788)
			(xy 366.551596 -219.998776) (xy 366.602773 -219.99067) (xy 366.654587 -219.99067) (xy 366.705764 -219.998776)
			(xy 366.755043 -220.014788) (xy 366.80121 -220.038311) (xy 366.843129 -220.068767) (xy 366.879767 -220.105405)
			(xy 366.910223 -220.147324) (xy 366.933746 -220.193491) (xy 366.949758 -220.24277) (xy 366.957864 -220.293947)
			(xy 366.958372 -220.319854) (xy 368.178588 -220.319854) (xy 368.179096 -220.293947) (xy 368.187202 -220.24277)
			(xy 368.203214 -220.193491) (xy 368.226737 -220.147324) (xy 368.257193 -220.105405) (xy 368.293831 -220.068767)
			(xy 368.33575 -220.038311) (xy 368.381917 -220.014788) (xy 368.431196 -219.998776) (xy 368.482373 -219.99067)
			(xy 368.534187 -219.99067) (xy 368.585364 -219.998776) (xy 368.634643 -220.014788) (xy 368.68081 -220.038311)
			(xy 368.722729 -220.068767) (xy 368.759367 -220.105405) (xy 368.789823 -220.147324) (xy 368.813346 -220.193491)
			(xy 368.829358 -220.24277) (xy 368.837464 -220.293947) (xy 368.837972 -220.319854) (xy 370.058188 -220.319854)
			(xy 370.058696 -220.293947) (xy 370.066802 -220.24277) (xy 370.082814 -220.193491) (xy 370.106337 -220.147324)
			(xy 370.136793 -220.105405) (xy 370.173431 -220.068767) (xy 370.21535 -220.038311) (xy 370.261517 -220.014788)
			(xy 370.310796 -219.998776) (xy 370.361973 -219.99067) (xy 370.413787 -219.99067) (xy 370.464964 -219.998776)
			(xy 370.514243 -220.014788) (xy 370.56041 -220.038311) (xy 370.602329 -220.068767) (xy 370.638967 -220.105405)
			(xy 370.669423 -220.147324) (xy 370.692946 -220.193491) (xy 370.708958 -220.24277) (xy 370.717064 -220.293947)
			(xy 370.717572 -220.319854) (xy 371.937788 -220.319854) (xy 371.938296 -220.293947) (xy 371.946402 -220.24277)
			(xy 371.962414 -220.193491) (xy 371.985937 -220.147324) (xy 372.016393 -220.105405) (xy 372.053031 -220.068767)
			(xy 372.09495 -220.038311) (xy 372.141117 -220.014788) (xy 372.190396 -219.998776) (xy 372.241573 -219.99067)
			(xy 372.293387 -219.99067) (xy 372.344564 -219.998776) (xy 372.393843 -220.014788) (xy 372.44001 -220.038311)
			(xy 372.481929 -220.068767) (xy 372.518567 -220.105405) (xy 372.549023 -220.147324) (xy 372.572546 -220.193491)
			(xy 372.588558 -220.24277) (xy 372.596664 -220.293947) (xy 372.597172 -220.319854) (xy 373.817388 -220.319854)
			(xy 373.817896 -220.293947) (xy 373.826002 -220.24277) (xy 373.842014 -220.193491) (xy 373.865537 -220.147324)
			(xy 373.895993 -220.105405) (xy 373.932631 -220.068767) (xy 373.97455 -220.038311) (xy 374.020717 -220.014788)
			(xy 374.069996 -219.998776) (xy 374.121173 -219.99067) (xy 374.172987 -219.99067) (xy 374.224164 -219.998776)
			(xy 374.273443 -220.014788) (xy 374.31961 -220.038311) (xy 374.361529 -220.068767) (xy 374.398167 -220.105405)
			(xy 374.428623 -220.147324) (xy 374.452146 -220.193491) (xy 374.468158 -220.24277) (xy 374.476264 -220.293947)
			(xy 374.476772 -220.319854) (xy 375.696988 -220.319854) (xy 375.697496 -220.293947) (xy 375.705602 -220.24277)
			(xy 375.721614 -220.193491) (xy 375.745137 -220.147324) (xy 375.775593 -220.105405) (xy 375.812231 -220.068767)
			(xy 375.85415 -220.038311) (xy 375.900317 -220.014788) (xy 375.949596 -219.998776) (xy 376.000773 -219.99067)
			(xy 376.052587 -219.99067) (xy 376.103764 -219.998776) (xy 376.153043 -220.014788) (xy 376.19921 -220.038311)
			(xy 376.241129 -220.068767) (xy 376.277767 -220.105405) (xy 376.308223 -220.147324) (xy 376.331746 -220.193491)
			(xy 376.347758 -220.24277) (xy 376.355864 -220.293947) (xy 376.356372 -220.319854) (xy 377.576588 -220.319854)
			(xy 377.577096 -220.293947) (xy 377.585202 -220.24277) (xy 377.601214 -220.193491) (xy 377.624737 -220.147324)
			(xy 377.655193 -220.105405) (xy 377.691831 -220.068767) (xy 377.73375 -220.038311) (xy 377.779917 -220.014788)
			(xy 377.829196 -219.998776) (xy 377.880373 -219.99067) (xy 377.932187 -219.99067) (xy 377.983364 -219.998776)
			(xy 378.032643 -220.014788) (xy 378.07881 -220.038311) (xy 378.120729 -220.068767) (xy 378.157367 -220.105405)
			(xy 378.187823 -220.147324) (xy 378.211346 -220.193491) (xy 378.227358 -220.24277) (xy 378.235464 -220.293947)
			(xy 378.235972 -220.319854) (xy 379.456188 -220.319854) (xy 379.456696 -220.293947) (xy 379.464802 -220.24277)
			(xy 379.480814 -220.193491) (xy 379.504337 -220.147324) (xy 379.534793 -220.105405) (xy 379.571431 -220.068767)
			(xy 379.61335 -220.038311) (xy 379.659517 -220.014788) (xy 379.708796 -219.998776) (xy 379.759973 -219.99067)
			(xy 379.811787 -219.99067) (xy 379.862964 -219.998776) (xy 379.912243 -220.014788) (xy 379.95841 -220.038311)
			(xy 380.000329 -220.068767) (xy 380.036967 -220.105405) (xy 380.067423 -220.147324) (xy 380.090946 -220.193491)
			(xy 380.106958 -220.24277) (xy 380.115064 -220.293947) (xy 380.115572 -220.319854) (xy 381.336296 -220.319854)
			(xy 381.336804 -220.293967) (xy 381.344903 -220.242829) (xy 381.360902 -220.193589) (xy 381.384408 -220.147457)
			(xy 381.41484 -220.10557) (xy 381.45145 -220.06896) (xy 381.493337 -220.038528) (xy 381.539469 -220.015022)
			(xy 381.588709 -219.999023) (xy 381.639847 -219.990924) (xy 381.691621 -219.990924) (xy 381.742759 -219.999023)
			(xy 381.791999 -220.015022) (xy 381.838131 -220.038528) (xy 381.880018 -220.06896) (xy 381.916628 -220.10557)
			(xy 381.94706 -220.147457) (xy 381.970566 -220.193589) (xy 381.986565 -220.242829) (xy 381.994664 -220.293967)
			(xy 381.995172 -220.319854) (xy 381.994628 -220.347561) (xy 381.985442 -220.402208) (xy 381.976884 -220.428566)
			(xy 381.969264 -220.450664) (xy 382.174242 -220.805756) (xy 382.197102 -220.810074) (xy 382.221908 -220.815252)
			(xy 382.269647 -220.832242) (xy 382.314225 -220.856337) (xy 382.354591 -220.886969) (xy 382.389795 -220.923417)
			(xy 382.419006 -220.964822) (xy 382.441538 -221.01021) (xy 382.45686 -221.058511) (xy 382.46461 -221.108588)
			(xy 382.465072 -221.133924) (xy 382.464564 -221.159811) (xy 382.456465 -221.210949) (xy 382.440466 -221.260189)
			(xy 382.41696 -221.306321) (xy 382.386528 -221.348208) (xy 382.349918 -221.384818) (xy 382.308031 -221.41525)
			(xy 382.261899 -221.438756) (xy 382.212659 -221.454755) (xy 382.161521 -221.462854) (xy 382.109747 -221.462854)
			(xy 382.058609 -221.454755) (xy 382.009369 -221.438756) (xy 381.963237 -221.41525) (xy 381.92135 -221.384818)
			(xy 381.88474 -221.348208) (xy 381.854308 -221.306321) (xy 381.830802 -221.260189) (xy 381.814803 -221.210949)
			(xy 381.806704 -221.159811) (xy 381.806196 -221.133924) (xy 381.806732 -221.106216) (xy 381.815923 -221.051569)
			(xy 381.824484 -221.025212) (xy 381.832358 -221.003114) (xy 381.62738 -220.648022) (xy 381.60452 -220.643704)
			(xy 381.579694 -220.638559) (xy 381.531915 -220.6216) (xy 381.487296 -220.597525) (xy 381.446891 -220.566902)
			(xy 381.41165 -220.530452) (xy 381.382408 -220.489036) (xy 381.359851 -220.44363) (xy 381.344514 -220.395306)
			(xy 381.336758 -220.345204) (xy 381.336296 -220.319854) (xy 380.115572 -220.319854) (xy 380.114963 -220.347508)
			(xy 380.105639 -220.402026) (xy 380.09703 -220.428312) (xy 380.08941 -220.45041) (xy 380.294642 -220.805756)
			(xy 380.317502 -220.810074) (xy 380.342308 -220.815252) (xy 380.390047 -220.832242) (xy 380.434625 -220.856337)
			(xy 380.474991 -220.886969) (xy 380.510195 -220.923417) (xy 380.539406 -220.964822) (xy 380.561938 -221.01021)
			(xy 380.57726 -221.058511) (xy 380.58501 -221.108588) (xy 380.585472 -221.133924) (xy 380.584964 -221.159811)
			(xy 380.576865 -221.210949) (xy 380.560866 -221.260189) (xy 380.53736 -221.306321) (xy 380.506928 -221.348208)
			(xy 380.470318 -221.384818) (xy 380.428431 -221.41525) (xy 380.382299 -221.438756) (xy 380.333059 -221.454755)
			(xy 380.281921 -221.462854) (xy 380.230147 -221.462854) (xy 380.179009 -221.454755) (xy 380.129769 -221.438756)
			(xy 380.083637 -221.41525) (xy 380.04175 -221.384818) (xy 380.00514 -221.348208) (xy 379.974708 -221.306321)
			(xy 379.951202 -221.260189) (xy 379.935203 -221.210949) (xy 379.927104 -221.159811) (xy 379.926596 -221.133924)
			(xy 379.927132 -221.106216) (xy 379.936323 -221.051569) (xy 379.944884 -221.025212) (xy 379.952758 -221.003114)
			(xy 379.74778 -220.648022) (xy 379.72492 -220.643704) (xy 379.700079 -220.638521) (xy 379.652232 -220.621628)
			(xy 379.60754 -220.5976) (xy 379.567059 -220.567005) (xy 379.531748 -220.530566) (xy 379.502439 -220.489145)
			(xy 379.479827 -220.44372) (xy 379.464446 -220.395365) (xy 379.456659 -220.345225) (xy 379.456188 -220.319854)
			(xy 378.235972 -220.319854) (xy 378.235363 -220.347508) (xy 378.226039 -220.402026) (xy 378.21743 -220.428312)
			(xy 378.20981 -220.45041) (xy 378.415042 -220.805756) (xy 378.437902 -220.810074) (xy 378.462708 -220.815252)
			(xy 378.510447 -220.832242) (xy 378.555025 -220.856337) (xy 378.595391 -220.886969) (xy 378.630595 -220.923417)
			(xy 378.659806 -220.964822) (xy 378.682338 -221.01021) (xy 378.69766 -221.058511) (xy 378.70541 -221.108588)
			(xy 378.705872 -221.133924) (xy 378.705364 -221.159811) (xy 378.697265 -221.210949) (xy 378.681266 -221.260189)
			(xy 378.65776 -221.306321) (xy 378.627328 -221.348208) (xy 378.590718 -221.384818) (xy 378.548831 -221.41525)
			(xy 378.502699 -221.438756) (xy 378.453459 -221.454755) (xy 378.402321 -221.462854) (xy 378.350547 -221.462854)
			(xy 378.299409 -221.454755) (xy 378.250169 -221.438756) (xy 378.204037 -221.41525) (xy 378.16215 -221.384818)
			(xy 378.12554 -221.348208) (xy 378.095108 -221.306321) (xy 378.071602 -221.260189) (xy 378.055603 -221.210949)
			(xy 378.047504 -221.159811) (xy 378.046996 -221.133924) (xy 378.047532 -221.106216) (xy 378.056723 -221.051569)
			(xy 378.065284 -221.025212) (xy 378.073158 -221.003114) (xy 377.86818 -220.648022) (xy 377.84532 -220.643704)
			(xy 377.820479 -220.638521) (xy 377.772632 -220.621628) (xy 377.72794 -220.5976) (xy 377.687459 -220.567005)
			(xy 377.652148 -220.530566) (xy 377.622839 -220.489145) (xy 377.600227 -220.44372) (xy 377.584846 -220.395365)
			(xy 377.577059 -220.345225) (xy 377.576588 -220.319854) (xy 376.356372 -220.319854) (xy 376.355763 -220.347508)
			(xy 376.346439 -220.402026) (xy 376.33783 -220.428312) (xy 376.33021 -220.45041) (xy 376.535442 -220.805756)
			(xy 376.558302 -220.810074) (xy 376.583108 -220.815252) (xy 376.630847 -220.832242) (xy 376.675425 -220.856337)
			(xy 376.715791 -220.886969) (xy 376.750995 -220.923417) (xy 376.780206 -220.964822) (xy 376.802738 -221.01021)
			(xy 376.81806 -221.058511) (xy 376.82581 -221.108588) (xy 376.826272 -221.133924) (xy 376.825764 -221.159811)
			(xy 376.817665 -221.210949) (xy 376.801666 -221.260189) (xy 376.77816 -221.306321) (xy 376.747728 -221.348208)
			(xy 376.711118 -221.384818) (xy 376.669231 -221.41525) (xy 376.623099 -221.438756) (xy 376.573859 -221.454755)
			(xy 376.522721 -221.462854) (xy 376.470947 -221.462854) (xy 376.419809 -221.454755) (xy 376.370569 -221.438756)
			(xy 376.324437 -221.41525) (xy 376.28255 -221.384818) (xy 376.24594 -221.348208) (xy 376.215508 -221.306321)
			(xy 376.192002 -221.260189) (xy 376.176003 -221.210949) (xy 376.167904 -221.159811) (xy 376.167396 -221.133924)
			(xy 376.167932 -221.106216) (xy 376.177123 -221.051569) (xy 376.185684 -221.025212) (xy 376.193558 -221.003114)
			(xy 375.98858 -220.648022) (xy 375.96572 -220.643704) (xy 375.940879 -220.638521) (xy 375.893032 -220.621628)
			(xy 375.84834 -220.5976) (xy 375.807859 -220.567005) (xy 375.772548 -220.530566) (xy 375.743239 -220.489145)
			(xy 375.720627 -220.44372) (xy 375.705246 -220.395365) (xy 375.697459 -220.345225) (xy 375.696988 -220.319854)
			(xy 374.476772 -220.319854) (xy 374.476163 -220.347508) (xy 374.466839 -220.402026) (xy 374.45823 -220.428312)
			(xy 374.45061 -220.45041) (xy 374.655842 -220.805756) (xy 374.678702 -220.810074) (xy 374.703508 -220.815252)
			(xy 374.751247 -220.832242) (xy 374.795825 -220.856337) (xy 374.836191 -220.886969) (xy 374.871395 -220.923417)
			(xy 374.900606 -220.964822) (xy 374.923138 -221.01021) (xy 374.93846 -221.058511) (xy 374.94621 -221.108588)
			(xy 374.946672 -221.133924) (xy 374.946164 -221.159811) (xy 374.938065 -221.210949) (xy 374.922066 -221.260189)
			(xy 374.89856 -221.306321) (xy 374.868128 -221.348208) (xy 374.831518 -221.384818) (xy 374.789631 -221.41525)
			(xy 374.743499 -221.438756) (xy 374.694259 -221.454755) (xy 374.643121 -221.462854) (xy 374.591347 -221.462854)
			(xy 374.540209 -221.454755) (xy 374.490969 -221.438756) (xy 374.444837 -221.41525) (xy 374.40295 -221.384818)
			(xy 374.36634 -221.348208) (xy 374.335908 -221.306321) (xy 374.312402 -221.260189) (xy 374.296403 -221.210949)
			(xy 374.288304 -221.159811) (xy 374.287796 -221.133924) (xy 374.288332 -221.106216) (xy 374.297523 -221.051569)
			(xy 374.306084 -221.025212) (xy 374.313958 -221.003114) (xy 374.10898 -220.648022) (xy 374.08612 -220.643704)
			(xy 374.061279 -220.638521) (xy 374.013432 -220.621628) (xy 373.96874 -220.5976) (xy 373.928259 -220.567005)
			(xy 373.892948 -220.530566) (xy 373.863639 -220.489145) (xy 373.841027 -220.44372) (xy 373.825646 -220.395365)
			(xy 373.817859 -220.345225) (xy 373.817388 -220.319854) (xy 372.597172 -220.319854) (xy 372.596563 -220.347508)
			(xy 372.587239 -220.402026) (xy 372.57863 -220.428312) (xy 372.57101 -220.45041) (xy 372.776242 -220.805756)
			(xy 372.799102 -220.810074) (xy 372.823908 -220.815252) (xy 372.871647 -220.832242) (xy 372.916225 -220.856337)
			(xy 372.956591 -220.886969) (xy 372.991795 -220.923417) (xy 373.021006 -220.964822) (xy 373.043538 -221.01021)
			(xy 373.05886 -221.058511) (xy 373.06661 -221.108588) (xy 373.067072 -221.133924) (xy 373.066564 -221.159811)
			(xy 373.058465 -221.210949) (xy 373.042466 -221.260189) (xy 373.01896 -221.306321) (xy 372.988528 -221.348208)
			(xy 372.951918 -221.384818) (xy 372.910031 -221.41525) (xy 372.863899 -221.438756) (xy 372.814659 -221.454755)
			(xy 372.763521 -221.462854) (xy 372.711747 -221.462854) (xy 372.660609 -221.454755) (xy 372.611369 -221.438756)
			(xy 372.565237 -221.41525) (xy 372.52335 -221.384818) (xy 372.48674 -221.348208) (xy 372.456308 -221.306321)
			(xy 372.432802 -221.260189) (xy 372.416803 -221.210949) (xy 372.408704 -221.159811) (xy 372.408196 -221.133924)
			(xy 372.408732 -221.106216) (xy 372.417923 -221.051569) (xy 372.426484 -221.025212) (xy 372.434358 -221.003114)
			(xy 372.22938 -220.648022) (xy 372.20652 -220.643704) (xy 372.181679 -220.638521) (xy 372.133832 -220.621628)
			(xy 372.08914 -220.5976) (xy 372.048659 -220.567005) (xy 372.013348 -220.530566) (xy 371.984039 -220.489145)
			(xy 371.961427 -220.44372) (xy 371.946046 -220.395365) (xy 371.938259 -220.345225) (xy 371.937788 -220.319854)
			(xy 370.717572 -220.319854) (xy 370.716963 -220.347508) (xy 370.707639 -220.402026) (xy 370.69903 -220.428312)
			(xy 370.69141 -220.45041) (xy 370.896642 -220.805756) (xy 370.919502 -220.810074) (xy 370.944308 -220.815252)
			(xy 370.992047 -220.832242) (xy 371.036625 -220.856337) (xy 371.076991 -220.886969) (xy 371.112195 -220.923417)
			(xy 371.141406 -220.964822) (xy 371.163938 -221.01021) (xy 371.17926 -221.058511) (xy 371.18701 -221.108588)
			(xy 371.187472 -221.133924) (xy 371.186964 -221.159811) (xy 371.178865 -221.210949) (xy 371.162866 -221.260189)
			(xy 371.13936 -221.306321) (xy 371.108928 -221.348208) (xy 371.072318 -221.384818) (xy 371.030431 -221.41525)
			(xy 370.984299 -221.438756) (xy 370.935059 -221.454755) (xy 370.883921 -221.462854) (xy 370.832147 -221.462854)
			(xy 370.781009 -221.454755) (xy 370.731769 -221.438756) (xy 370.685637 -221.41525) (xy 370.64375 -221.384818)
			(xy 370.60714 -221.348208) (xy 370.576708 -221.306321) (xy 370.553202 -221.260189) (xy 370.537203 -221.210949)
			(xy 370.529104 -221.159811) (xy 370.528596 -221.133924) (xy 370.529132 -221.106216) (xy 370.538323 -221.051569)
			(xy 370.546884 -221.025212) (xy 370.554758 -221.003114) (xy 370.34978 -220.648022) (xy 370.32692 -220.643704)
			(xy 370.302079 -220.638521) (xy 370.254232 -220.621628) (xy 370.20954 -220.5976) (xy 370.169059 -220.567005)
			(xy 370.133748 -220.530566) (xy 370.104439 -220.489145) (xy 370.081827 -220.44372) (xy 370.066446 -220.395365)
			(xy 370.058659 -220.345225) (xy 370.058188 -220.319854) (xy 368.837972 -220.319854) (xy 368.837363 -220.347508)
			(xy 368.828039 -220.402026) (xy 368.81943 -220.428312) (xy 368.81181 -220.45041) (xy 369.017042 -220.805756)
			(xy 369.039902 -220.810074) (xy 369.064708 -220.815252) (xy 369.112447 -220.832242) (xy 369.157025 -220.856337)
			(xy 369.197391 -220.886969) (xy 369.232595 -220.923417) (xy 369.261806 -220.964822) (xy 369.284338 -221.01021)
			(xy 369.29966 -221.058511) (xy 369.30741 -221.108588) (xy 369.307872 -221.133924) (xy 369.307364 -221.159811)
			(xy 369.299265 -221.210949) (xy 369.283266 -221.260189) (xy 369.25976 -221.306321) (xy 369.229328 -221.348208)
			(xy 369.192718 -221.384818) (xy 369.150831 -221.41525) (xy 369.104699 -221.438756) (xy 369.055459 -221.454755)
			(xy 369.004321 -221.462854) (xy 368.952547 -221.462854) (xy 368.901409 -221.454755) (xy 368.852169 -221.438756)
			(xy 368.806037 -221.41525) (xy 368.76415 -221.384818) (xy 368.72754 -221.348208) (xy 368.697108 -221.306321)
			(xy 368.673602 -221.260189) (xy 368.657603 -221.210949) (xy 368.649504 -221.159811) (xy 368.648996 -221.133924)
			(xy 368.649532 -221.106216) (xy 368.658723 -221.051569) (xy 368.667284 -221.025212) (xy 368.675158 -221.003114)
			(xy 368.47018 -220.648022) (xy 368.44732 -220.643704) (xy 368.422479 -220.638521) (xy 368.374632 -220.621628)
			(xy 368.32994 -220.5976) (xy 368.289459 -220.567005) (xy 368.254148 -220.530566) (xy 368.224839 -220.489145)
			(xy 368.202227 -220.44372) (xy 368.186846 -220.395365) (xy 368.179059 -220.345225) (xy 368.178588 -220.319854)
			(xy 366.958372 -220.319854) (xy 366.957763 -220.347508) (xy 366.948439 -220.402026) (xy 366.93983 -220.428312)
			(xy 366.93221 -220.45041) (xy 367.137442 -220.805756) (xy 367.160302 -220.810074) (xy 367.185108 -220.815252)
			(xy 367.232847 -220.832242) (xy 367.277425 -220.856337) (xy 367.317791 -220.886969) (xy 367.352995 -220.923417)
			(xy 367.382206 -220.964822) (xy 367.404738 -221.01021) (xy 367.42006 -221.058511) (xy 367.42781 -221.108588)
			(xy 367.428272 -221.133924) (xy 367.427764 -221.159811) (xy 367.419665 -221.210949) (xy 367.403666 -221.260189)
			(xy 367.38016 -221.306321) (xy 367.349728 -221.348208) (xy 367.313118 -221.384818) (xy 367.271231 -221.41525)
			(xy 367.225099 -221.438756) (xy 367.175859 -221.454755) (xy 367.124721 -221.462854) (xy 367.072947 -221.462854)
			(xy 367.021809 -221.454755) (xy 366.972569 -221.438756) (xy 366.926437 -221.41525) (xy 366.88455 -221.384818)
			(xy 366.84794 -221.348208) (xy 366.817508 -221.306321) (xy 366.794002 -221.260189) (xy 366.778003 -221.210949)
			(xy 366.769904 -221.159811) (xy 366.769396 -221.133924) (xy 366.769932 -221.106216) (xy 366.779123 -221.051569)
			(xy 366.787684 -221.025212) (xy 366.795558 -221.003114) (xy 366.59058 -220.648022) (xy 366.56772 -220.643704)
			(xy 366.542879 -220.638521) (xy 366.495032 -220.621628) (xy 366.45034 -220.5976) (xy 366.409859 -220.567005)
			(xy 366.374548 -220.530566) (xy 366.345239 -220.489145) (xy 366.322627 -220.44372) (xy 366.307246 -220.395365)
			(xy 366.299459 -220.345225) (xy 366.298988 -220.319854) (xy 365.078772 -220.319854) (xy 365.078163 -220.347508)
			(xy 365.068839 -220.402026) (xy 365.06023 -220.428312) (xy 365.05261 -220.45041) (xy 365.257842 -220.805756)
			(xy 365.280702 -220.810074) (xy 365.305508 -220.815252) (xy 365.353247 -220.832242) (xy 365.397825 -220.856337)
			(xy 365.438191 -220.886969) (xy 365.473395 -220.923417) (xy 365.502606 -220.964822) (xy 365.525138 -221.01021)
			(xy 365.54046 -221.058511) (xy 365.54821 -221.108588) (xy 365.548672 -221.133924) (xy 365.548164 -221.159811)
			(xy 365.540065 -221.210949) (xy 365.524066 -221.260189) (xy 365.50056 -221.306321) (xy 365.470128 -221.348208)
			(xy 365.433518 -221.384818) (xy 365.391631 -221.41525) (xy 365.345499 -221.438756) (xy 365.296259 -221.454755)
			(xy 365.245121 -221.462854) (xy 365.193347 -221.462854) (xy 365.142209 -221.454755) (xy 365.092969 -221.438756)
			(xy 365.046837 -221.41525) (xy 365.00495 -221.384818) (xy 364.96834 -221.348208) (xy 364.937908 -221.306321)
			(xy 364.914402 -221.260189) (xy 364.898403 -221.210949) (xy 364.890304 -221.159811) (xy 364.889796 -221.133924)
			(xy 364.890332 -221.106216) (xy 364.899523 -221.051569) (xy 364.908084 -221.025212) (xy 364.915958 -221.003114)
			(xy 364.71098 -220.648022) (xy 364.68812 -220.643704) (xy 364.663279 -220.638521) (xy 364.615432 -220.621628)
			(xy 364.57074 -220.5976) (xy 364.530259 -220.567005) (xy 364.494948 -220.530566) (xy 364.465639 -220.489145)
			(xy 364.443027 -220.44372) (xy 364.427646 -220.395365) (xy 364.419859 -220.345225) (xy 364.419388 -220.319854)
			(xy 363.199172 -220.319854) (xy 363.198563 -220.347508) (xy 363.189239 -220.402026) (xy 363.18063 -220.428312)
			(xy 363.17301 -220.45041) (xy 363.378242 -220.805756) (xy 363.401102 -220.810074) (xy 363.425908 -220.815252)
			(xy 363.473647 -220.832242) (xy 363.518225 -220.856337) (xy 363.558591 -220.886969) (xy 363.593795 -220.923417)
			(xy 363.623006 -220.964822) (xy 363.645538 -221.01021) (xy 363.66086 -221.058511) (xy 363.66861 -221.108588)
			(xy 363.669072 -221.133924) (xy 363.668564 -221.159811) (xy 363.660465 -221.210949) (xy 363.644466 -221.260189)
			(xy 363.62096 -221.306321) (xy 363.590528 -221.348208) (xy 363.553918 -221.384818) (xy 363.512031 -221.41525)
			(xy 363.465899 -221.438756) (xy 363.416659 -221.454755) (xy 363.365521 -221.462854) (xy 363.313747 -221.462854)
			(xy 363.262609 -221.454755) (xy 363.213369 -221.438756) (xy 363.167237 -221.41525) (xy 363.12535 -221.384818)
			(xy 363.08874 -221.348208) (xy 363.058308 -221.306321) (xy 363.034802 -221.260189) (xy 363.018803 -221.210949)
			(xy 363.010704 -221.159811) (xy 363.010196 -221.133924) (xy 363.010732 -221.106216) (xy 363.019923 -221.051569)
			(xy 363.028484 -221.025212) (xy 363.036358 -221.003114) (xy 362.83138 -220.648022) (xy 362.80852 -220.643704)
			(xy 362.783679 -220.638521) (xy 362.735832 -220.621628) (xy 362.69114 -220.5976) (xy 362.650659 -220.567005)
			(xy 362.615348 -220.530566) (xy 362.586039 -220.489145) (xy 362.563427 -220.44372) (xy 362.548046 -220.395365)
			(xy 362.540259 -220.345225) (xy 362.539788 -220.319854) (xy 361.319572 -220.319854) (xy 361.318963 -220.347508)
			(xy 361.309639 -220.402026) (xy 361.30103 -220.428312) (xy 361.29341 -220.45041) (xy 361.498642 -220.805756)
			(xy 361.521502 -220.810074) (xy 361.546308 -220.815252) (xy 361.594047 -220.832242) (xy 361.638625 -220.856337)
			(xy 361.678991 -220.886969) (xy 361.714195 -220.923417) (xy 361.743406 -220.964822) (xy 361.765938 -221.01021)
			(xy 361.78126 -221.058511) (xy 361.78901 -221.108588) (xy 361.789472 -221.133924) (xy 361.788964 -221.159811)
			(xy 361.780865 -221.210949) (xy 361.764866 -221.260189) (xy 361.74136 -221.306321) (xy 361.710928 -221.348208)
			(xy 361.674318 -221.384818) (xy 361.632431 -221.41525) (xy 361.586299 -221.438756) (xy 361.537059 -221.454755)
			(xy 361.485921 -221.462854) (xy 361.434147 -221.462854) (xy 361.383009 -221.454755) (xy 361.333769 -221.438756)
			(xy 361.287637 -221.41525) (xy 361.24575 -221.384818) (xy 361.20914 -221.348208) (xy 361.178708 -221.306321)
			(xy 361.155202 -221.260189) (xy 361.139203 -221.210949) (xy 361.131104 -221.159811) (xy 361.130596 -221.133924)
			(xy 361.131132 -221.106216) (xy 361.140323 -221.051569) (xy 361.148884 -221.025212) (xy 361.156758 -221.003114)
			(xy 360.95178 -220.648022) (xy 360.92892 -220.643704) (xy 360.904079 -220.638521) (xy 360.856232 -220.621628)
			(xy 360.81154 -220.5976) (xy 360.771059 -220.567005) (xy 360.735748 -220.530566) (xy 360.706439 -220.489145)
			(xy 360.683827 -220.44372) (xy 360.668446 -220.395365) (xy 360.660659 -220.345225) (xy 360.660188 -220.319854)
			(xy 359.439972 -220.319854) (xy 359.439363 -220.347508) (xy 359.430039 -220.402026) (xy 359.42143 -220.428312)
			(xy 359.41381 -220.45041) (xy 359.619042 -220.805756) (xy 359.641902 -220.810074) (xy 359.666708 -220.815252)
			(xy 359.714447 -220.832242) (xy 359.759025 -220.856337) (xy 359.799391 -220.886969) (xy 359.834595 -220.923417)
			(xy 359.863806 -220.964822) (xy 359.886338 -221.01021) (xy 359.90166 -221.058511) (xy 359.90941 -221.108588)
			(xy 359.909872 -221.133924) (xy 359.909364 -221.159811) (xy 359.901265 -221.210949) (xy 359.885266 -221.260189)
			(xy 359.86176 -221.306321) (xy 359.831328 -221.348208) (xy 359.794718 -221.384818) (xy 359.752831 -221.41525)
			(xy 359.706699 -221.438756) (xy 359.657459 -221.454755) (xy 359.606321 -221.462854) (xy 359.554547 -221.462854)
			(xy 359.503409 -221.454755) (xy 359.454169 -221.438756) (xy 359.408037 -221.41525) (xy 359.36615 -221.384818)
			(xy 359.32954 -221.348208) (xy 359.299108 -221.306321) (xy 359.275602 -221.260189) (xy 359.259603 -221.210949)
			(xy 359.251504 -221.159811) (xy 359.250996 -221.133924) (xy 359.251532 -221.106216) (xy 359.260723 -221.051569)
			(xy 359.269284 -221.025212) (xy 359.277158 -221.003114) (xy 359.07218 -220.648022) (xy 359.04932 -220.643704)
			(xy 359.024479 -220.638521) (xy 358.976632 -220.621628) (xy 358.93194 -220.5976) (xy 358.891459 -220.567005)
			(xy 358.856148 -220.530566) (xy 358.826839 -220.489145) (xy 358.804227 -220.44372) (xy 358.788846 -220.395365)
			(xy 358.781059 -220.345225) (xy 358.780588 -220.319854) (xy 357.560372 -220.319854) (xy 357.559763 -220.347508)
			(xy 357.550439 -220.402026) (xy 357.54183 -220.428312) (xy 357.53421 -220.45041) (xy 357.739442 -220.805756)
			(xy 357.762302 -220.810074) (xy 357.787108 -220.815252) (xy 357.834847 -220.832242) (xy 357.879425 -220.856337)
			(xy 357.919791 -220.886969) (xy 357.954995 -220.923417) (xy 357.984206 -220.964822) (xy 358.006738 -221.01021)
			(xy 358.02206 -221.058511) (xy 358.02981 -221.108588) (xy 358.030272 -221.133924) (xy 358.029764 -221.159811)
			(xy 358.021665 -221.210949) (xy 358.005666 -221.260189) (xy 357.98216 -221.306321) (xy 357.951728 -221.348208)
			(xy 357.915118 -221.384818) (xy 357.873231 -221.41525) (xy 357.827099 -221.438756) (xy 357.777859 -221.454755)
			(xy 357.726721 -221.462854) (xy 357.674947 -221.462854) (xy 357.623809 -221.454755) (xy 357.574569 -221.438756)
			(xy 357.528437 -221.41525) (xy 357.48655 -221.384818) (xy 357.44994 -221.348208) (xy 357.419508 -221.306321)
			(xy 357.396002 -221.260189) (xy 357.380003 -221.210949) (xy 357.371904 -221.159811) (xy 357.371396 -221.133924)
			(xy 357.371932 -221.106216) (xy 357.381123 -221.051569) (xy 357.389684 -221.025212) (xy 357.397558 -221.003114)
			(xy 357.19258 -220.648022) (xy 357.16972 -220.643704) (xy 357.144879 -220.638521) (xy 357.097032 -220.621628)
			(xy 357.05234 -220.5976) (xy 357.011859 -220.567005) (xy 356.976548 -220.530566) (xy 356.947239 -220.489145)
			(xy 356.924627 -220.44372) (xy 356.909246 -220.395365) (xy 356.901459 -220.345225) (xy 356.900988 -220.319854)
			(xy 355.680772 -220.319854) (xy 355.680163 -220.347508) (xy 355.670839 -220.402026) (xy 355.66223 -220.428312)
			(xy 355.65461 -220.45041) (xy 355.859842 -220.805756) (xy 355.882702 -220.810074) (xy 355.907508 -220.815252)
			(xy 355.955247 -220.832242) (xy 355.999825 -220.856337) (xy 356.040191 -220.886969) (xy 356.075395 -220.923417)
			(xy 356.104606 -220.964822) (xy 356.127138 -221.01021) (xy 356.14246 -221.058511) (xy 356.15021 -221.108588)
			(xy 356.150672 -221.133924) (xy 356.150164 -221.159811) (xy 356.142065 -221.210949) (xy 356.126066 -221.260189)
			(xy 356.10256 -221.306321) (xy 356.072128 -221.348208) (xy 356.035518 -221.384818) (xy 355.993631 -221.41525)
			(xy 355.947499 -221.438756) (xy 355.898259 -221.454755) (xy 355.847121 -221.462854) (xy 355.795347 -221.462854)
			(xy 355.744209 -221.454755) (xy 355.694969 -221.438756) (xy 355.648837 -221.41525) (xy 355.60695 -221.384818)
			(xy 355.57034 -221.348208) (xy 355.539908 -221.306321) (xy 355.516402 -221.260189) (xy 355.500403 -221.210949)
			(xy 355.492304 -221.159811) (xy 355.491796 -221.133924) (xy 355.492332 -221.106216) (xy 355.501523 -221.051569)
			(xy 355.510084 -221.025212) (xy 355.517958 -221.003114) (xy 355.31298 -220.648022) (xy 355.29012 -220.643704)
			(xy 355.265279 -220.638521) (xy 355.217432 -220.621628) (xy 355.17274 -220.5976) (xy 355.132259 -220.567005)
			(xy 355.096948 -220.530566) (xy 355.067639 -220.489145) (xy 355.045027 -220.44372) (xy 355.029646 -220.395365)
			(xy 355.021859 -220.345225) (xy 355.021388 -220.319854) (xy 353.801172 -220.319854) (xy 353.800563 -220.347508)
			(xy 353.791239 -220.402026) (xy 353.78263 -220.428312) (xy 353.77501 -220.45041) (xy 353.980242 -220.805756)
			(xy 354.003102 -220.810074) (xy 354.027908 -220.815252) (xy 354.075647 -220.832242) (xy 354.120225 -220.856337)
			(xy 354.160591 -220.886969) (xy 354.195795 -220.923417) (xy 354.225006 -220.964822) (xy 354.247538 -221.01021)
			(xy 354.26286 -221.058511) (xy 354.27061 -221.108588) (xy 354.271072 -221.133924) (xy 354.270564 -221.159811)
			(xy 354.262465 -221.210949) (xy 354.246466 -221.260189) (xy 354.22296 -221.306321) (xy 354.192528 -221.348208)
			(xy 354.155918 -221.384818) (xy 354.114031 -221.41525) (xy 354.067899 -221.438756) (xy 354.018659 -221.454755)
			(xy 353.967521 -221.462854) (xy 353.915747 -221.462854) (xy 353.864609 -221.454755) (xy 353.815369 -221.438756)
			(xy 353.769237 -221.41525) (xy 353.72735 -221.384818) (xy 353.69074 -221.348208) (xy 353.660308 -221.306321)
			(xy 353.636802 -221.260189) (xy 353.620803 -221.210949) (xy 353.612704 -221.159811) (xy 353.612196 -221.133924)
			(xy 353.612732 -221.106216) (xy 353.621923 -221.051569) (xy 353.630484 -221.025212) (xy 353.638358 -221.003114)
			(xy 353.43338 -220.648022) (xy 353.41052 -220.643704) (xy 353.385679 -220.638521) (xy 353.337832 -220.621628)
			(xy 353.29314 -220.5976) (xy 353.252659 -220.567005) (xy 353.217348 -220.530566) (xy 353.188039 -220.489145)
			(xy 353.165427 -220.44372) (xy 353.150046 -220.395365) (xy 353.142259 -220.345225) (xy 353.141788 -220.319854)
			(xy 351.921572 -220.319854) (xy 351.921122 -220.3452) (xy 351.913342 -220.395293) (xy 351.897988 -220.443604)
			(xy 351.875422 -220.488998) (xy 351.846176 -220.530404) (xy 351.810939 -220.566847) (xy 351.77054 -220.597469)
			(xy 351.725931 -220.621548) (xy 351.678163 -220.638518) (xy 351.653348 -220.643704) (xy 351.630488 -220.648022)
			(xy 351.42551 -221.003114) (xy 351.433384 -221.024958) (xy 351.441977 -221.051373) (xy 351.451165 -221.106151)
			(xy 351.451672 -221.133924) (xy 351.451164 -221.159811) (xy 351.443065 -221.210949) (xy 351.427066 -221.260189)
			(xy 351.40356 -221.306321) (xy 351.373128 -221.348208) (xy 351.336518 -221.384818) (xy 351.294631 -221.41525)
			(xy 351.248499 -221.438756) (xy 351.199259 -221.454755) (xy 351.148121 -221.462854) (xy 351.096347 -221.462854)
			(xy 351.045209 -221.454755) (xy 350.995969 -221.438756) (xy 350.949837 -221.41525) (xy 350.90795 -221.384818)
			(xy 350.87134 -221.348208) (xy 350.840908 -221.306321) (xy 350.817402 -221.260189) (xy 350.801403 -221.210949)
			(xy 350.793304 -221.159811) (xy 350.792796 -221.133924) (xy 350.511872 -221.133924) (xy 350.511345 -221.161632)
			(xy 350.502148 -221.216279) (xy 350.493584 -221.242636) (xy 350.48571 -221.264734) (xy 350.690688 -221.619572)
			(xy 350.713548 -221.62389) (xy 350.738367 -221.629064) (xy 350.786146 -221.646018) (xy 350.830765 -221.670088)
			(xy 350.871172 -221.700708) (xy 350.906413 -221.737154) (xy 350.935657 -221.778566) (xy 350.958214 -221.823969)
			(xy 350.973552 -221.872291) (xy 350.98131 -221.922391) (xy 350.981772 -221.94774) (xy 352.201988 -221.94774)
			(xy 352.202465 -221.922395) (xy 352.210245 -221.872306) (xy 352.225597 -221.823996) (xy 352.24816 -221.778605)
			(xy 352.277403 -221.7372) (xy 352.312637 -221.700757) (xy 352.353031 -221.670134) (xy 352.397636 -221.646052)
			(xy 352.445399 -221.629078) (xy 352.470212 -221.62389) (xy 352.493072 -221.619572) (xy 352.698304 -221.264226)
			(xy 352.69043 -221.242128) (xy 352.681965 -221.215883) (xy 352.672893 -221.161495) (xy 352.672396 -221.133924)
			(xy 352.672904 -221.108037) (xy 352.681003 -221.056899) (xy 352.697002 -221.007659) (xy 352.720508 -220.961527)
			(xy 352.75094 -220.91964) (xy 352.78755 -220.88303) (xy 352.829437 -220.852598) (xy 352.875569 -220.829092)
			(xy 352.924809 -220.813093) (xy 352.975947 -220.804994) (xy 353.027721 -220.804994) (xy 353.078859 -220.813093)
			(xy 353.128099 -220.829092) (xy 353.174231 -220.852598) (xy 353.216118 -220.88303) (xy 353.252728 -220.91964)
			(xy 353.28316 -220.961527) (xy 353.306666 -221.007659) (xy 353.322665 -221.056899) (xy 353.330764 -221.108037)
			(xy 353.331272 -221.133924) (xy 353.330842 -221.1593) (xy 353.323069 -221.209454) (xy 353.307696 -221.257821)
			(xy 353.285086 -221.303259) (xy 353.255774 -221.344691) (xy 353.220455 -221.381137) (xy 353.179963 -221.411734)
			(xy 353.135258 -221.435759) (xy 353.087396 -221.452643) (xy 353.06254 -221.457774) (xy 353.03968 -221.462092)
			(xy 352.834956 -221.81693) (xy 352.84283 -221.838774) (xy 352.851486 -221.865179) (xy 352.8608 -221.919958)
			(xy 352.861372 -221.94774) (xy 354.081588 -221.94774) (xy 354.082065 -221.922395) (xy 354.089845 -221.872306)
			(xy 354.105197 -221.823996) (xy 354.12776 -221.778605) (xy 354.157003 -221.7372) (xy 354.192237 -221.700757)
			(xy 354.232631 -221.670134) (xy 354.277236 -221.646052) (xy 354.324999 -221.629078) (xy 354.349812 -221.62389)
			(xy 354.372672 -221.619572) (xy 354.577904 -221.264226) (xy 354.57003 -221.242128) (xy 354.561565 -221.215883)
			(xy 354.552493 -221.161495) (xy 354.551996 -221.133924) (xy 354.552504 -221.108037) (xy 354.560603 -221.056899)
			(xy 354.576602 -221.007659) (xy 354.600108 -220.961527) (xy 354.63054 -220.91964) (xy 354.66715 -220.88303)
			(xy 354.709037 -220.852598) (xy 354.755169 -220.829092) (xy 354.804409 -220.813093) (xy 354.855547 -220.804994)
			(xy 354.907321 -220.804994) (xy 354.958459 -220.813093) (xy 355.007699 -220.829092) (xy 355.053831 -220.852598)
			(xy 355.095718 -220.88303) (xy 355.132328 -220.91964) (xy 355.16276 -220.961527) (xy 355.186266 -221.007659)
			(xy 355.202265 -221.056899) (xy 355.210364 -221.108037) (xy 355.210872 -221.133924) (xy 355.210442 -221.1593)
			(xy 355.202669 -221.209454) (xy 355.187296 -221.257821) (xy 355.164686 -221.303259) (xy 355.135374 -221.344691)
			(xy 355.100055 -221.381137) (xy 355.059563 -221.411734) (xy 355.014858 -221.435759) (xy 354.966996 -221.452643)
			(xy 354.94214 -221.457774) (xy 354.91928 -221.462092) (xy 354.714556 -221.81693) (xy 354.72243 -221.838774)
			(xy 354.731086 -221.865179) (xy 354.7404 -221.919958) (xy 354.740972 -221.94774) (xy 355.961188 -221.94774)
			(xy 355.961665 -221.922395) (xy 355.969445 -221.872306) (xy 355.984797 -221.823996) (xy 356.00736 -221.778605)
			(xy 356.036603 -221.7372) (xy 356.071837 -221.700757) (xy 356.112231 -221.670134) (xy 356.156836 -221.646052)
			(xy 356.204599 -221.629078) (xy 356.229412 -221.62389) (xy 356.252272 -221.619572) (xy 356.457504 -221.264226)
			(xy 356.44963 -221.242128) (xy 356.441165 -221.215883) (xy 356.432093 -221.161495) (xy 356.431596 -221.133924)
			(xy 356.432104 -221.108037) (xy 356.440203 -221.056899) (xy 356.456202 -221.007659) (xy 356.479708 -220.961527)
			(xy 356.51014 -220.91964) (xy 356.54675 -220.88303) (xy 356.588637 -220.852598) (xy 356.634769 -220.829092)
			(xy 356.684009 -220.813093) (xy 356.735147 -220.804994) (xy 356.786921 -220.804994) (xy 356.838059 -220.813093)
			(xy 356.887299 -220.829092) (xy 356.933431 -220.852598) (xy 356.975318 -220.88303) (xy 357.011928 -220.91964)
			(xy 357.04236 -220.961527) (xy 357.065866 -221.007659) (xy 357.081865 -221.056899) (xy 357.089964 -221.108037)
			(xy 357.090472 -221.133924) (xy 357.090042 -221.1593) (xy 357.082269 -221.209454) (xy 357.066896 -221.257821)
			(xy 357.044286 -221.303259) (xy 357.014974 -221.344691) (xy 356.979655 -221.381137) (xy 356.939163 -221.411734)
			(xy 356.894458 -221.435759) (xy 356.846596 -221.452643) (xy 356.82174 -221.457774) (xy 356.79888 -221.462092)
			(xy 356.594156 -221.81693) (xy 356.60203 -221.838774) (xy 356.610686 -221.865179) (xy 356.62 -221.919958)
			(xy 356.620572 -221.94774) (xy 357.841296 -221.94774) (xy 357.841727 -221.922404) (xy 357.849489 -221.872329)
			(xy 357.864819 -221.824032) (xy 357.887358 -221.778648) (xy 357.916574 -221.737246) (xy 357.95178 -221.700802)
			(xy 357.992148 -221.670172) (xy 358.036725 -221.646079) (xy 358.084465 -221.629089) (xy 358.109266 -221.62389)
			(xy 358.132126 -221.619572) (xy 358.337104 -221.26448) (xy 358.329484 -221.242382) (xy 358.320964 -221.216211)
			(xy 358.311771 -221.161949) (xy 358.311196 -221.134432) (xy 358.311196 -221.133924) (xy 358.311704 -221.108037)
			(xy 358.319803 -221.056899) (xy 358.335802 -221.007659) (xy 358.359308 -220.961527) (xy 358.38974 -220.91964)
			(xy 358.42635 -220.88303) (xy 358.468237 -220.852598) (xy 358.514369 -220.829092) (xy 358.563609 -220.813093)
			(xy 358.614747 -220.804994) (xy 358.666521 -220.804994) (xy 358.717659 -220.813093) (xy 358.766899 -220.829092)
			(xy 358.813031 -220.852598) (xy 358.854918 -220.88303) (xy 358.891528 -220.91964) (xy 358.92196 -220.961527)
			(xy 358.945466 -221.007659) (xy 358.961465 -221.056899) (xy 358.969564 -221.108037) (xy 358.970072 -221.133924)
			(xy 358.969679 -221.159291) (xy 358.961926 -221.209429) (xy 358.946575 -221.257784) (xy 358.923991 -221.303213)
			(xy 358.894706 -221.344642) (xy 358.859415 -221.381089) (xy 358.818952 -221.411694) (xy 358.774274 -221.435731)
			(xy 358.726438 -221.452632) (xy 358.701594 -221.457774) (xy 358.678734 -221.462092) (xy 358.47401 -221.81693)
			(xy 358.481884 -221.838774) (xy 358.490481 -221.865188) (xy 358.499666 -221.919967) (xy 358.500172 -221.94774)
			(xy 359.720388 -221.94774) (xy 359.720865 -221.922395) (xy 359.728645 -221.872306) (xy 359.743997 -221.823996)
			(xy 359.76656 -221.778605) (xy 359.795803 -221.7372) (xy 359.831037 -221.700757) (xy 359.871431 -221.670134)
			(xy 359.916036 -221.646052) (xy 359.963799 -221.629078) (xy 359.988612 -221.62389) (xy 360.011472 -221.619572)
			(xy 360.216704 -221.264226) (xy 360.20883 -221.242128) (xy 360.200365 -221.215883) (xy 360.191293 -221.161495)
			(xy 360.190796 -221.133924) (xy 360.191304 -221.108037) (xy 360.199403 -221.056899) (xy 360.215402 -221.007659)
			(xy 360.238908 -220.961527) (xy 360.26934 -220.91964) (xy 360.30595 -220.88303) (xy 360.347837 -220.852598)
			(xy 360.393969 -220.829092) (xy 360.443209 -220.813093) (xy 360.494347 -220.804994) (xy 360.546121 -220.804994)
			(xy 360.597259 -220.813093) (xy 360.646499 -220.829092) (xy 360.692631 -220.852598) (xy 360.734518 -220.88303)
			(xy 360.771128 -220.91964) (xy 360.80156 -220.961527) (xy 360.825066 -221.007659) (xy 360.841065 -221.056899)
			(xy 360.849164 -221.108037) (xy 360.849672 -221.133924) (xy 360.849242 -221.1593) (xy 360.841469 -221.209454)
			(xy 360.826096 -221.257821) (xy 360.803486 -221.303259) (xy 360.774174 -221.344691) (xy 360.738855 -221.381137)
			(xy 360.698363 -221.411734) (xy 360.653658 -221.435759) (xy 360.605796 -221.452643) (xy 360.58094 -221.457774)
			(xy 360.55808 -221.462092) (xy 360.353356 -221.81693) (xy 360.36123 -221.838774) (xy 360.369886 -221.865179)
			(xy 360.3792 -221.919958) (xy 360.379772 -221.94774) (xy 361.600496 -221.94774) (xy 361.600927 -221.922404)
			(xy 361.608689 -221.872329) (xy 361.624019 -221.824032) (xy 361.646558 -221.778648) (xy 361.675774 -221.737246)
			(xy 361.71098 -221.700802) (xy 361.751348 -221.670172) (xy 361.795925 -221.646079) (xy 361.843665 -221.629089)
			(xy 361.868466 -221.62389) (xy 361.891326 -221.619572) (xy 362.096304 -221.26448) (xy 362.088684 -221.242382)
			(xy 362.080164 -221.216211) (xy 362.070971 -221.161949) (xy 362.070396 -221.134432) (xy 362.070396 -221.133924)
			(xy 362.070904 -221.108037) (xy 362.079003 -221.056899) (xy 362.095002 -221.007659) (xy 362.118508 -220.961527)
			(xy 362.14894 -220.91964) (xy 362.18555 -220.88303) (xy 362.227437 -220.852598) (xy 362.273569 -220.829092)
			(xy 362.322809 -220.813093) (xy 362.373947 -220.804994) (xy 362.425721 -220.804994) (xy 362.476859 -220.813093)
			(xy 362.526099 -220.829092) (xy 362.572231 -220.852598) (xy 362.614118 -220.88303) (xy 362.650728 -220.91964)
			(xy 362.68116 -220.961527) (xy 362.704666 -221.007659) (xy 362.720665 -221.056899) (xy 362.728764 -221.108037)
			(xy 362.729272 -221.133924) (xy 362.728879 -221.159291) (xy 362.721126 -221.209429) (xy 362.705775 -221.257784)
			(xy 362.683191 -221.303213) (xy 362.653906 -221.344642) (xy 362.618615 -221.381089) (xy 362.578152 -221.411694)
			(xy 362.533474 -221.435731) (xy 362.485638 -221.452632) (xy 362.460794 -221.457774) (xy 362.437934 -221.462092)
			(xy 362.23321 -221.81693) (xy 362.241084 -221.838774) (xy 362.249681 -221.865188) (xy 362.258866 -221.919967)
			(xy 362.259372 -221.94774) (xy 363.479588 -221.94774) (xy 363.480065 -221.922395) (xy 363.487845 -221.872306)
			(xy 363.503197 -221.823996) (xy 363.52576 -221.778605) (xy 363.555003 -221.7372) (xy 363.590237 -221.700757)
			(xy 363.630631 -221.670134) (xy 363.675236 -221.646052) (xy 363.722999 -221.629078) (xy 363.747812 -221.62389)
			(xy 363.770672 -221.619572) (xy 363.975904 -221.264226) (xy 363.96803 -221.242128) (xy 363.959565 -221.215883)
			(xy 363.950493 -221.161495) (xy 363.949996 -221.133924) (xy 363.950504 -221.108037) (xy 363.958603 -221.056899)
			(xy 363.974602 -221.007659) (xy 363.998108 -220.961527) (xy 364.02854 -220.91964) (xy 364.06515 -220.88303)
			(xy 364.107037 -220.852598) (xy 364.153169 -220.829092) (xy 364.202409 -220.813093) (xy 364.253547 -220.804994)
			(xy 364.305321 -220.804994) (xy 364.356459 -220.813093) (xy 364.405699 -220.829092) (xy 364.451831 -220.852598)
			(xy 364.493718 -220.88303) (xy 364.530328 -220.91964) (xy 364.56076 -220.961527) (xy 364.584266 -221.007659)
			(xy 364.600265 -221.056899) (xy 364.608364 -221.108037) (xy 364.608872 -221.133924) (xy 364.608442 -221.1593)
			(xy 364.600669 -221.209454) (xy 364.585296 -221.257821) (xy 364.562686 -221.303259) (xy 364.533374 -221.344691)
			(xy 364.498055 -221.381137) (xy 364.457563 -221.411734) (xy 364.412858 -221.435759) (xy 364.364996 -221.452643)
			(xy 364.34014 -221.457774) (xy 364.31728 -221.462092) (xy 364.112556 -221.81693) (xy 364.12043 -221.838774)
			(xy 364.129086 -221.865179) (xy 364.1384 -221.919958) (xy 364.138972 -221.94774) (xy 365.359188 -221.94774)
			(xy 365.359665 -221.922395) (xy 365.367445 -221.872306) (xy 365.382797 -221.823996) (xy 365.40536 -221.778605)
			(xy 365.434603 -221.7372) (xy 365.469837 -221.700757) (xy 365.510231 -221.670134) (xy 365.554836 -221.646052)
			(xy 365.602599 -221.629078) (xy 365.627412 -221.62389) (xy 365.650272 -221.619572) (xy 365.855504 -221.264226)
			(xy 365.84763 -221.242128) (xy 365.839165 -221.215883) (xy 365.830093 -221.161495) (xy 365.829596 -221.133924)
			(xy 365.830104 -221.108037) (xy 365.838203 -221.056899) (xy 365.854202 -221.007659) (xy 365.877708 -220.961527)
			(xy 365.90814 -220.91964) (xy 365.94475 -220.88303) (xy 365.986637 -220.852598) (xy 366.032769 -220.829092)
			(xy 366.082009 -220.813093) (xy 366.133147 -220.804994) (xy 366.184921 -220.804994) (xy 366.236059 -220.813093)
			(xy 366.285299 -220.829092) (xy 366.331431 -220.852598) (xy 366.373318 -220.88303) (xy 366.409928 -220.91964)
			(xy 366.44036 -220.961527) (xy 366.463866 -221.007659) (xy 366.479865 -221.056899) (xy 366.487964 -221.108037)
			(xy 366.488472 -221.133924) (xy 366.488042 -221.1593) (xy 366.480269 -221.209454) (xy 366.464896 -221.257821)
			(xy 366.442286 -221.303259) (xy 366.412974 -221.344691) (xy 366.377655 -221.381137) (xy 366.337163 -221.411734)
			(xy 366.292458 -221.435759) (xy 366.244596 -221.452643) (xy 366.21974 -221.457774) (xy 366.19688 -221.462092)
			(xy 365.992156 -221.81693) (xy 366.00003 -221.838774) (xy 366.008686 -221.865179) (xy 366.018 -221.919958)
			(xy 366.018572 -221.94774) (xy 369.118388 -221.94774) (xy 369.118865 -221.922395) (xy 369.126645 -221.872306)
			(xy 369.141997 -221.823996) (xy 369.16456 -221.778605) (xy 369.193803 -221.7372) (xy 369.229037 -221.700757)
			(xy 369.269431 -221.670134) (xy 369.314036 -221.646052) (xy 369.361799 -221.629078) (xy 369.386612 -221.62389)
			(xy 369.409472 -221.619572) (xy 369.614704 -221.264226) (xy 369.60683 -221.242128) (xy 369.598365 -221.215883)
			(xy 369.589293 -221.161495) (xy 369.588796 -221.133924) (xy 369.589304 -221.108037) (xy 369.597403 -221.056899)
			(xy 369.613402 -221.007659) (xy 369.636908 -220.961527) (xy 369.66734 -220.91964) (xy 369.70395 -220.88303)
			(xy 369.745837 -220.852598) (xy 369.791969 -220.829092) (xy 369.841209 -220.813093) (xy 369.892347 -220.804994)
			(xy 369.944121 -220.804994) (xy 369.995259 -220.813093) (xy 370.044499 -220.829092) (xy 370.090631 -220.852598)
			(xy 370.132518 -220.88303) (xy 370.169128 -220.91964) (xy 370.19956 -220.961527) (xy 370.223066 -221.007659)
			(xy 370.239065 -221.056899) (xy 370.247164 -221.108037) (xy 370.247672 -221.133924) (xy 370.247242 -221.1593)
			(xy 370.239469 -221.209454) (xy 370.224096 -221.257821) (xy 370.201486 -221.303259) (xy 370.172174 -221.344691)
			(xy 370.136855 -221.381137) (xy 370.096363 -221.411734) (xy 370.051658 -221.435759) (xy 370.003796 -221.452643)
			(xy 369.97894 -221.457774) (xy 369.95608 -221.462092) (xy 369.751356 -221.81693) (xy 369.75923 -221.838774)
			(xy 369.767886 -221.865179) (xy 369.7772 -221.919958) (xy 369.777772 -221.94774) (xy 370.997988 -221.94774)
			(xy 370.998465 -221.922395) (xy 371.006245 -221.872306) (xy 371.021597 -221.823996) (xy 371.04416 -221.778605)
			(xy 371.073403 -221.7372) (xy 371.108637 -221.700757) (xy 371.149031 -221.670134) (xy 371.193636 -221.646052)
			(xy 371.241399 -221.629078) (xy 371.266212 -221.62389) (xy 371.289072 -221.619572) (xy 371.494304 -221.264226)
			(xy 371.48643 -221.242128) (xy 371.477965 -221.215883) (xy 371.468893 -221.161495) (xy 371.468396 -221.133924)
			(xy 371.468904 -221.108037) (xy 371.477003 -221.056899) (xy 371.493002 -221.007659) (xy 371.516508 -220.961527)
			(xy 371.54694 -220.91964) (xy 371.58355 -220.88303) (xy 371.625437 -220.852598) (xy 371.671569 -220.829092)
			(xy 371.720809 -220.813093) (xy 371.771947 -220.804994) (xy 371.823721 -220.804994) (xy 371.874859 -220.813093)
			(xy 371.924099 -220.829092) (xy 371.970231 -220.852598) (xy 372.012118 -220.88303) (xy 372.048728 -220.91964)
			(xy 372.07916 -220.961527) (xy 372.102666 -221.007659) (xy 372.118665 -221.056899) (xy 372.126764 -221.108037)
			(xy 372.127272 -221.133924) (xy 372.126842 -221.1593) (xy 372.119069 -221.209454) (xy 372.103696 -221.257821)
			(xy 372.081086 -221.303259) (xy 372.051774 -221.344691) (xy 372.016455 -221.381137) (xy 371.975963 -221.411734)
			(xy 371.931258 -221.435759) (xy 371.883396 -221.452643) (xy 371.85854 -221.457774) (xy 371.83568 -221.462092)
			(xy 371.630956 -221.81693) (xy 371.63883 -221.838774) (xy 371.647486 -221.865179) (xy 371.6568 -221.919958)
			(xy 371.657372 -221.94774) (xy 372.877588 -221.94774) (xy 372.878065 -221.922395) (xy 372.885845 -221.872306)
			(xy 372.901197 -221.823996) (xy 372.92376 -221.778605) (xy 372.953003 -221.7372) (xy 372.988237 -221.700757)
			(xy 373.028631 -221.670134) (xy 373.073236 -221.646052) (xy 373.120999 -221.629078) (xy 373.145812 -221.62389)
			(xy 373.168672 -221.619572) (xy 373.373904 -221.264226) (xy 373.36603 -221.242128) (xy 373.357565 -221.215883)
			(xy 373.348493 -221.161495) (xy 373.347996 -221.133924) (xy 373.348504 -221.108037) (xy 373.356603 -221.056899)
			(xy 373.372602 -221.007659) (xy 373.396108 -220.961527) (xy 373.42654 -220.91964) (xy 373.46315 -220.88303)
			(xy 373.505037 -220.852598) (xy 373.551169 -220.829092) (xy 373.600409 -220.813093) (xy 373.651547 -220.804994)
			(xy 373.703321 -220.804994) (xy 373.754459 -220.813093) (xy 373.803699 -220.829092) (xy 373.849831 -220.852598)
			(xy 373.891718 -220.88303) (xy 373.928328 -220.91964) (xy 373.95876 -220.961527) (xy 373.982266 -221.007659)
			(xy 373.998265 -221.056899) (xy 374.006364 -221.108037) (xy 374.006872 -221.133924) (xy 374.006442 -221.1593)
			(xy 373.998669 -221.209454) (xy 373.983296 -221.257821) (xy 373.960686 -221.303259) (xy 373.931374 -221.344691)
			(xy 373.896055 -221.381137) (xy 373.855563 -221.411734) (xy 373.810858 -221.435759) (xy 373.762996 -221.452643)
			(xy 373.73814 -221.457774) (xy 373.71528 -221.462092) (xy 373.510556 -221.81693) (xy 373.51843 -221.838774)
			(xy 373.527086 -221.865179) (xy 373.5364 -221.919958) (xy 373.536972 -221.94774) (xy 374.757188 -221.94774)
			(xy 374.757665 -221.922395) (xy 374.765445 -221.872306) (xy 374.780797 -221.823996) (xy 374.80336 -221.778605)
			(xy 374.832603 -221.7372) (xy 374.867837 -221.700757) (xy 374.908231 -221.670134) (xy 374.952836 -221.646052)
			(xy 375.000599 -221.629078) (xy 375.025412 -221.62389) (xy 375.048272 -221.619572) (xy 375.253504 -221.264226)
			(xy 375.24563 -221.242128) (xy 375.237165 -221.215883) (xy 375.228093 -221.161495) (xy 375.227596 -221.133924)
			(xy 375.228104 -221.108037) (xy 375.236203 -221.056899) (xy 375.252202 -221.007659) (xy 375.275708 -220.961527)
			(xy 375.30614 -220.91964) (xy 375.34275 -220.88303) (xy 375.384637 -220.852598) (xy 375.430769 -220.829092)
			(xy 375.480009 -220.813093) (xy 375.531147 -220.804994) (xy 375.582921 -220.804994) (xy 375.634059 -220.813093)
			(xy 375.683299 -220.829092) (xy 375.729431 -220.852598) (xy 375.771318 -220.88303) (xy 375.807928 -220.91964)
			(xy 375.83836 -220.961527) (xy 375.861866 -221.007659) (xy 375.877865 -221.056899) (xy 375.885964 -221.108037)
			(xy 375.886472 -221.133924) (xy 375.886042 -221.1593) (xy 375.878269 -221.209454) (xy 375.862896 -221.257821)
			(xy 375.840286 -221.303259) (xy 375.810974 -221.344691) (xy 375.775655 -221.381137) (xy 375.735163 -221.411734)
			(xy 375.690458 -221.435759) (xy 375.642596 -221.452643) (xy 375.61774 -221.457774) (xy 375.59488 -221.462092)
			(xy 375.390156 -221.81693) (xy 375.39803 -221.838774) (xy 375.406686 -221.865179) (xy 375.416 -221.919958)
			(xy 375.416572 -221.94774) (xy 376.636788 -221.94774) (xy 376.637265 -221.922395) (xy 376.645045 -221.872306)
			(xy 376.660397 -221.823996) (xy 376.68296 -221.778605) (xy 376.712203 -221.7372) (xy 376.747437 -221.700757)
			(xy 376.787831 -221.670134) (xy 376.832436 -221.646052) (xy 376.880199 -221.629078) (xy 376.905012 -221.62389)
			(xy 376.927872 -221.619572) (xy 377.133104 -221.264226) (xy 377.12523 -221.242128) (xy 377.116765 -221.215883)
			(xy 377.107693 -221.161495) (xy 377.107196 -221.133924) (xy 377.107704 -221.108037) (xy 377.115803 -221.056899)
			(xy 377.131802 -221.007659) (xy 377.155308 -220.961527) (xy 377.18574 -220.91964) (xy 377.22235 -220.88303)
			(xy 377.264237 -220.852598) (xy 377.310369 -220.829092) (xy 377.359609 -220.813093) (xy 377.410747 -220.804994)
			(xy 377.462521 -220.804994) (xy 377.513659 -220.813093) (xy 377.562899 -220.829092) (xy 377.609031 -220.852598)
			(xy 377.650918 -220.88303) (xy 377.687528 -220.91964) (xy 377.71796 -220.961527) (xy 377.741466 -221.007659)
			(xy 377.757465 -221.056899) (xy 377.765564 -221.108037) (xy 377.766072 -221.133924) (xy 377.765642 -221.1593)
			(xy 377.757869 -221.209454) (xy 377.742496 -221.257821) (xy 377.719886 -221.303259) (xy 377.690574 -221.344691)
			(xy 377.655255 -221.381137) (xy 377.614763 -221.411734) (xy 377.570058 -221.435759) (xy 377.522196 -221.452643)
			(xy 377.49734 -221.457774) (xy 377.47448 -221.462092) (xy 377.269756 -221.81693) (xy 377.27763 -221.838774)
			(xy 377.286286 -221.865179) (xy 377.2956 -221.919958) (xy 377.296172 -221.94774) (xy 378.516388 -221.94774)
			(xy 378.516865 -221.922395) (xy 378.524645 -221.872306) (xy 378.539997 -221.823996) (xy 378.56256 -221.778605)
			(xy 378.591803 -221.7372) (xy 378.627037 -221.700757) (xy 378.667431 -221.670134) (xy 378.712036 -221.646052)
			(xy 378.759799 -221.629078) (xy 378.784612 -221.62389) (xy 378.807472 -221.619572) (xy 379.012704 -221.264226)
			(xy 379.00483 -221.242128) (xy 378.996365 -221.215883) (xy 378.987293 -221.161495) (xy 378.986796 -221.133924)
			(xy 378.987304 -221.108037) (xy 378.995403 -221.056899) (xy 379.011402 -221.007659) (xy 379.034908 -220.961527)
			(xy 379.06534 -220.91964) (xy 379.10195 -220.88303) (xy 379.143837 -220.852598) (xy 379.189969 -220.829092)
			(xy 379.239209 -220.813093) (xy 379.290347 -220.804994) (xy 379.342121 -220.804994) (xy 379.393259 -220.813093)
			(xy 379.442499 -220.829092) (xy 379.488631 -220.852598) (xy 379.530518 -220.88303) (xy 379.567128 -220.91964)
			(xy 379.59756 -220.961527) (xy 379.621066 -221.007659) (xy 379.637065 -221.056899) (xy 379.645164 -221.108037)
			(xy 379.645672 -221.133924) (xy 379.645242 -221.1593) (xy 379.637469 -221.209454) (xy 379.622096 -221.257821)
			(xy 379.599486 -221.303259) (xy 379.570174 -221.344691) (xy 379.534855 -221.381137) (xy 379.494363 -221.411734)
			(xy 379.449658 -221.435759) (xy 379.401796 -221.452643) (xy 379.37694 -221.457774) (xy 379.35408 -221.462092)
			(xy 379.149356 -221.81693) (xy 379.15723 -221.838774) (xy 379.165886 -221.865179) (xy 379.1752 -221.919958)
			(xy 379.175772 -221.94774) (xy 380.395988 -221.94774) (xy 380.396465 -221.922395) (xy 380.404245 -221.872306)
			(xy 380.419597 -221.823996) (xy 380.44216 -221.778605) (xy 380.471403 -221.7372) (xy 380.506637 -221.700757)
			(xy 380.547031 -221.670134) (xy 380.591636 -221.646052) (xy 380.639399 -221.629078) (xy 380.664212 -221.62389)
			(xy 380.687072 -221.619572) (xy 380.89205 -221.263972) (xy 380.88443 -221.242128) (xy 380.875981 -221.215945)
			(xy 380.866909 -221.161685) (xy 380.866396 -221.134178) (xy 380.866396 -221.133924) (xy 380.866904 -221.108037)
			(xy 380.875003 -221.056899) (xy 380.891002 -221.007659) (xy 380.914508 -220.961527) (xy 380.94494 -220.91964)
			(xy 380.98155 -220.88303) (xy 381.023437 -220.852598) (xy 381.069569 -220.829092) (xy 381.118809 -220.813093)
			(xy 381.169947 -220.804994) (xy 381.221721 -220.804994) (xy 381.272859 -220.813093) (xy 381.322099 -220.829092)
			(xy 381.368231 -220.852598) (xy 381.410118 -220.88303) (xy 381.446728 -220.91964) (xy 381.47716 -220.961527)
			(xy 381.500666 -221.007659) (xy 381.516665 -221.056899) (xy 381.524764 -221.108037) (xy 381.525272 -221.133924)
			(xy 381.524879 -221.159291) (xy 381.517126 -221.209429) (xy 381.501775 -221.257784) (xy 381.479191 -221.303213)
			(xy 381.449906 -221.344642) (xy 381.414615 -221.381089) (xy 381.374152 -221.411694) (xy 381.329474 -221.435731)
			(xy 381.281638 -221.452632) (xy 381.256794 -221.457774) (xy 381.233934 -221.462092) (xy 381.02921 -221.81693)
			(xy 381.03683 -221.838774) (xy 381.045444 -221.865059) (xy 381.054766 -221.919578) (xy 381.055372 -221.947232)
			(xy 381.055372 -221.94774) (xy 382.275588 -221.94774) (xy 382.276065 -221.922395) (xy 382.283845 -221.872306)
			(xy 382.299197 -221.823996) (xy 382.32176 -221.778605) (xy 382.351003 -221.7372) (xy 382.386237 -221.700757)
			(xy 382.426631 -221.670134) (xy 382.471236 -221.646052) (xy 382.518999 -221.629078) (xy 382.543812 -221.62389)
			(xy 382.566672 -221.619572) (xy 382.77165 -221.263972) (xy 382.76403 -221.242128) (xy 382.755581 -221.215945)
			(xy 382.746509 -221.161685) (xy 382.745996 -221.134178) (xy 382.745996 -221.133924) (xy 382.746504 -221.108037)
			(xy 382.754603 -221.056899) (xy 382.770602 -221.007659) (xy 382.794108 -220.961527) (xy 382.82454 -220.91964)
			(xy 382.86115 -220.88303) (xy 382.903037 -220.852598) (xy 382.949169 -220.829092) (xy 382.998409 -220.813093)
			(xy 383.049547 -220.804994) (xy 383.101321 -220.804994) (xy 383.152459 -220.813093) (xy 383.201699 -220.829092)
			(xy 383.247831 -220.852598) (xy 383.289718 -220.88303) (xy 383.326328 -220.91964) (xy 383.35676 -220.961527)
			(xy 383.380266 -221.007659) (xy 383.396265 -221.056899) (xy 383.404364 -221.108037) (xy 383.404872 -221.133924)
			(xy 383.404479 -221.159291) (xy 383.396726 -221.209429) (xy 383.381375 -221.257784) (xy 383.358791 -221.303213)
			(xy 383.329506 -221.344642) (xy 383.294215 -221.381089) (xy 383.253752 -221.411694) (xy 383.209074 -221.435731)
			(xy 383.161238 -221.452632) (xy 383.136394 -221.457774) (xy 383.113534 -221.462092) (xy 382.90881 -221.81693)
			(xy 382.91643 -221.838774) (xy 382.925044 -221.865059) (xy 382.934366 -221.919578) (xy 382.934972 -221.947232)
			(xy 382.934972 -221.94774) (xy 382.934464 -221.973647) (xy 382.926358 -222.024824) (xy 382.910346 -222.074103)
			(xy 382.886823 -222.12027) (xy 382.856367 -222.162189) (xy 382.819729 -222.198827) (xy 382.77781 -222.229283)
			(xy 382.731643 -222.252806) (xy 382.682364 -222.268818) (xy 382.631187 -222.276924) (xy 382.579373 -222.276924)
			(xy 382.528196 -222.268818) (xy 382.478917 -222.252806) (xy 382.43275 -222.229283) (xy 382.390831 -222.198827)
			(xy 382.354193 -222.162189) (xy 382.323737 -222.12027) (xy 382.300214 -222.074103) (xy 382.284202 -222.024824)
			(xy 382.276096 -221.973647) (xy 382.275588 -221.94774) (xy 381.055372 -221.94774) (xy 381.054864 -221.973647)
			(xy 381.046758 -222.024824) (xy 381.030746 -222.074103) (xy 381.007223 -222.12027) (xy 380.976767 -222.162189)
			(xy 380.940129 -222.198827) (xy 380.89821 -222.229283) (xy 380.852043 -222.252806) (xy 380.802764 -222.268818)
			(xy 380.751587 -222.276924) (xy 380.699773 -222.276924) (xy 380.648596 -222.268818) (xy 380.599317 -222.252806)
			(xy 380.55315 -222.229283) (xy 380.511231 -222.198827) (xy 380.474593 -222.162189) (xy 380.444137 -222.12027)
			(xy 380.420614 -222.074103) (xy 380.404602 -222.024824) (xy 380.396496 -221.973647) (xy 380.395988 -221.94774)
			(xy 379.175772 -221.94774) (xy 379.175264 -221.973647) (xy 379.167158 -222.024824) (xy 379.151146 -222.074103)
			(xy 379.127623 -222.12027) (xy 379.097167 -222.162189) (xy 379.060529 -222.198827) (xy 379.01861 -222.229283)
			(xy 378.972443 -222.252806) (xy 378.923164 -222.268818) (xy 378.871987 -222.276924) (xy 378.820173 -222.276924)
			(xy 378.768996 -222.268818) (xy 378.719717 -222.252806) (xy 378.67355 -222.229283) (xy 378.631631 -222.198827)
			(xy 378.594993 -222.162189) (xy 378.564537 -222.12027) (xy 378.541014 -222.074103) (xy 378.525002 -222.024824)
			(xy 378.516896 -221.973647) (xy 378.516388 -221.94774) (xy 377.296172 -221.94774) (xy 377.295664 -221.973647)
			(xy 377.287558 -222.024824) (xy 377.271546 -222.074103) (xy 377.248023 -222.12027) (xy 377.217567 -222.162189)
			(xy 377.180929 -222.198827) (xy 377.13901 -222.229283) (xy 377.092843 -222.252806) (xy 377.043564 -222.268818)
			(xy 376.992387 -222.276924) (xy 376.940573 -222.276924) (xy 376.889396 -222.268818) (xy 376.840117 -222.252806)
			(xy 376.79395 -222.229283) (xy 376.752031 -222.198827) (xy 376.715393 -222.162189) (xy 376.684937 -222.12027)
			(xy 376.661414 -222.074103) (xy 376.645402 -222.024824) (xy 376.637296 -221.973647) (xy 376.636788 -221.94774)
			(xy 375.416572 -221.94774) (xy 375.416064 -221.973647) (xy 375.407958 -222.024824) (xy 375.391946 -222.074103)
			(xy 375.368423 -222.12027) (xy 375.337967 -222.162189) (xy 375.301329 -222.198827) (xy 375.25941 -222.229283)
			(xy 375.213243 -222.252806) (xy 375.163964 -222.268818) (xy 375.112787 -222.276924) (xy 375.060973 -222.276924)
			(xy 375.009796 -222.268818) (xy 374.960517 -222.252806) (xy 374.91435 -222.229283) (xy 374.872431 -222.198827)
			(xy 374.835793 -222.162189) (xy 374.805337 -222.12027) (xy 374.781814 -222.074103) (xy 374.765802 -222.024824)
			(xy 374.757696 -221.973647) (xy 374.757188 -221.94774) (xy 373.536972 -221.94774) (xy 373.536464 -221.973647)
			(xy 373.528358 -222.024824) (xy 373.512346 -222.074103) (xy 373.488823 -222.12027) (xy 373.458367 -222.162189)
			(xy 373.421729 -222.198827) (xy 373.37981 -222.229283) (xy 373.333643 -222.252806) (xy 373.284364 -222.268818)
			(xy 373.233187 -222.276924) (xy 373.181373 -222.276924) (xy 373.130196 -222.268818) (xy 373.080917 -222.252806)
			(xy 373.03475 -222.229283) (xy 372.992831 -222.198827) (xy 372.956193 -222.162189) (xy 372.925737 -222.12027)
			(xy 372.902214 -222.074103) (xy 372.886202 -222.024824) (xy 372.878096 -221.973647) (xy 372.877588 -221.94774)
			(xy 371.657372 -221.94774) (xy 371.656864 -221.973647) (xy 371.648758 -222.024824) (xy 371.632746 -222.074103)
			(xy 371.609223 -222.12027) (xy 371.578767 -222.162189) (xy 371.542129 -222.198827) (xy 371.50021 -222.229283)
			(xy 371.454043 -222.252806) (xy 371.404764 -222.268818) (xy 371.353587 -222.276924) (xy 371.301773 -222.276924)
			(xy 371.250596 -222.268818) (xy 371.201317 -222.252806) (xy 371.15515 -222.229283) (xy 371.113231 -222.198827)
			(xy 371.076593 -222.162189) (xy 371.046137 -222.12027) (xy 371.022614 -222.074103) (xy 371.006602 -222.024824)
			(xy 370.998496 -221.973647) (xy 370.997988 -221.94774) (xy 369.777772 -221.94774) (xy 369.777264 -221.973647)
			(xy 369.769158 -222.024824) (xy 369.753146 -222.074103) (xy 369.729623 -222.12027) (xy 369.699167 -222.162189)
			(xy 369.662529 -222.198827) (xy 369.62061 -222.229283) (xy 369.574443 -222.252806) (xy 369.525164 -222.268818)
			(xy 369.473987 -222.276924) (xy 369.422173 -222.276924) (xy 369.370996 -222.268818) (xy 369.321717 -222.252806)
			(xy 369.27555 -222.229283) (xy 369.233631 -222.198827) (xy 369.196993 -222.162189) (xy 369.166537 -222.12027)
			(xy 369.143014 -222.074103) (xy 369.127002 -222.024824) (xy 369.118896 -221.973647) (xy 369.118388 -221.94774)
			(xy 366.018572 -221.94774) (xy 366.018064 -221.973647) (xy 366.009958 -222.024824) (xy 365.993946 -222.074103)
			(xy 365.970423 -222.12027) (xy 365.939967 -222.162189) (xy 365.903329 -222.198827) (xy 365.86141 -222.229283)
			(xy 365.815243 -222.252806) (xy 365.765964 -222.268818) (xy 365.714787 -222.276924) (xy 365.662973 -222.276924)
			(xy 365.611796 -222.268818) (xy 365.562517 -222.252806) (xy 365.51635 -222.229283) (xy 365.474431 -222.198827)
			(xy 365.437793 -222.162189) (xy 365.407337 -222.12027) (xy 365.383814 -222.074103) (xy 365.367802 -222.024824)
			(xy 365.359696 -221.973647) (xy 365.359188 -221.94774) (xy 364.138972 -221.94774) (xy 364.138464 -221.973647)
			(xy 364.130358 -222.024824) (xy 364.114346 -222.074103) (xy 364.090823 -222.12027) (xy 364.060367 -222.162189)
			(xy 364.023729 -222.198827) (xy 363.98181 -222.229283) (xy 363.935643 -222.252806) (xy 363.886364 -222.268818)
			(xy 363.835187 -222.276924) (xy 363.783373 -222.276924) (xy 363.732196 -222.268818) (xy 363.682917 -222.252806)
			(xy 363.63675 -222.229283) (xy 363.594831 -222.198827) (xy 363.558193 -222.162189) (xy 363.527737 -222.12027)
			(xy 363.504214 -222.074103) (xy 363.488202 -222.024824) (xy 363.480096 -221.973647) (xy 363.479588 -221.94774)
			(xy 362.259372 -221.94774) (xy 362.258864 -221.973627) (xy 362.250765 -222.024765) (xy 362.234766 -222.074005)
			(xy 362.21126 -222.120137) (xy 362.180828 -222.162024) (xy 362.144218 -222.198634) (xy 362.102331 -222.229066)
			(xy 362.056199 -222.252572) (xy 362.006959 -222.268571) (xy 361.955821 -222.27667) (xy 361.904047 -222.27667)
			(xy 361.852909 -222.268571) (xy 361.803669 -222.252572) (xy 361.757537 -222.229066) (xy 361.71565 -222.198634)
			(xy 361.67904 -222.162024) (xy 361.648608 -222.120137) (xy 361.625102 -222.074005) (xy 361.609103 -222.024765)
			(xy 361.601004 -221.973627) (xy 361.600496 -221.94774) (xy 360.379772 -221.94774) (xy 360.379264 -221.973647)
			(xy 360.371158 -222.024824) (xy 360.355146 -222.074103) (xy 360.331623 -222.12027) (xy 360.301167 -222.162189)
			(xy 360.264529 -222.198827) (xy 360.22261 -222.229283) (xy 360.176443 -222.252806) (xy 360.127164 -222.268818)
			(xy 360.075987 -222.276924) (xy 360.024173 -222.276924) (xy 359.972996 -222.268818) (xy 359.923717 -222.252806)
			(xy 359.87755 -222.229283) (xy 359.835631 -222.198827) (xy 359.798993 -222.162189) (xy 359.768537 -222.12027)
			(xy 359.745014 -222.074103) (xy 359.729002 -222.024824) (xy 359.720896 -221.973647) (xy 359.720388 -221.94774)
			(xy 358.500172 -221.94774) (xy 358.499664 -221.973627) (xy 358.491565 -222.024765) (xy 358.475566 -222.074005)
			(xy 358.45206 -222.120137) (xy 358.421628 -222.162024) (xy 358.385018 -222.198634) (xy 358.343131 -222.229066)
			(xy 358.296999 -222.252572) (xy 358.247759 -222.268571) (xy 358.196621 -222.27667) (xy 358.144847 -222.27667)
			(xy 358.093709 -222.268571) (xy 358.044469 -222.252572) (xy 357.998337 -222.229066) (xy 357.95645 -222.198634)
			(xy 357.91984 -222.162024) (xy 357.889408 -222.120137) (xy 357.865902 -222.074005) (xy 357.849903 -222.024765)
			(xy 357.841804 -221.973627) (xy 357.841296 -221.94774) (xy 356.620572 -221.94774) (xy 356.620064 -221.973647)
			(xy 356.611958 -222.024824) (xy 356.595946 -222.074103) (xy 356.572423 -222.12027) (xy 356.541967 -222.162189)
			(xy 356.505329 -222.198827) (xy 356.46341 -222.229283) (xy 356.417243 -222.252806) (xy 356.367964 -222.268818)
			(xy 356.316787 -222.276924) (xy 356.264973 -222.276924) (xy 356.213796 -222.268818) (xy 356.164517 -222.252806)
			(xy 356.11835 -222.229283) (xy 356.076431 -222.198827) (xy 356.039793 -222.162189) (xy 356.009337 -222.12027)
			(xy 355.985814 -222.074103) (xy 355.969802 -222.024824) (xy 355.961696 -221.973647) (xy 355.961188 -221.94774)
			(xy 354.740972 -221.94774) (xy 354.740464 -221.973647) (xy 354.732358 -222.024824) (xy 354.716346 -222.074103)
			(xy 354.692823 -222.12027) (xy 354.662367 -222.162189) (xy 354.625729 -222.198827) (xy 354.58381 -222.229283)
			(xy 354.537643 -222.252806) (xy 354.488364 -222.268818) (xy 354.437187 -222.276924) (xy 354.385373 -222.276924)
			(xy 354.334196 -222.268818) (xy 354.284917 -222.252806) (xy 354.23875 -222.229283) (xy 354.196831 -222.198827)
			(xy 354.160193 -222.162189) (xy 354.129737 -222.12027) (xy 354.106214 -222.074103) (xy 354.090202 -222.024824)
			(xy 354.082096 -221.973647) (xy 354.081588 -221.94774) (xy 352.861372 -221.94774) (xy 352.860864 -221.973647)
			(xy 352.852758 -222.024824) (xy 352.836746 -222.074103) (xy 352.813223 -222.12027) (xy 352.782767 -222.162189)
			(xy 352.746129 -222.198827) (xy 352.70421 -222.229283) (xy 352.658043 -222.252806) (xy 352.608764 -222.268818)
			(xy 352.557587 -222.276924) (xy 352.505773 -222.276924) (xy 352.454596 -222.268818) (xy 352.405317 -222.252806)
			(xy 352.35915 -222.229283) (xy 352.317231 -222.198827) (xy 352.280593 -222.162189) (xy 352.250137 -222.12027)
			(xy 352.226614 -222.074103) (xy 352.210602 -222.024824) (xy 352.202496 -221.973647) (xy 352.201988 -221.94774)
			(xy 350.981772 -221.94774) (xy 350.981264 -221.973647) (xy 350.973158 -222.024824) (xy 350.957146 -222.074103)
			(xy 350.933623 -222.12027) (xy 350.903167 -222.162189) (xy 350.866529 -222.198827) (xy 350.82461 -222.229283)
			(xy 350.778443 -222.252806) (xy 350.729164 -222.268818) (xy 350.677987 -222.276924) (xy 350.626173 -222.276924)
			(xy 350.574996 -222.268818) (xy 350.525717 -222.252806) (xy 350.47955 -222.229283) (xy 350.437631 -222.198827)
			(xy 350.400993 -222.162189) (xy 350.370537 -222.12027) (xy 350.347014 -222.074103) (xy 350.331002 -222.024824)
			(xy 350.322896 -221.973647) (xy 350.322388 -221.94774) (xy 350.322992 -221.920023) (xy 350.332309 -221.865377)
			(xy 350.34093 -221.839028) (xy 350.348804 -221.81693) (xy 350.143826 -221.462092) (xy 350.120966 -221.457774)
			(xy 350.096166 -221.452574) (xy 350.04843 -221.435583) (xy 350.003855 -221.411489) (xy 349.963491 -221.380859)
			(xy 349.928289 -221.344414) (xy 349.899076 -221.303012) (xy 349.876542 -221.257629) (xy 349.861217 -221.209332)
			(xy 349.853461 -221.159259) (xy 349.852996 -221.133924) (xy 349.572072 -221.133924) (xy 349.571564 -221.159811)
			(xy 349.563465 -221.210949) (xy 349.547466 -221.260189) (xy 349.52396 -221.306321) (xy 349.493528 -221.348208)
			(xy 349.456918 -221.384818) (xy 349.415031 -221.41525) (xy 349.368899 -221.438756) (xy 349.319659 -221.454755)
			(xy 349.268521 -221.462854) (xy 349.216747 -221.462854) (xy 349.165609 -221.454755) (xy 349.116369 -221.438756)
			(xy 349.070237 -221.41525) (xy 349.02835 -221.384818) (xy 348.99174 -221.348208) (xy 348.961308 -221.306321)
			(xy 348.937802 -221.260189) (xy 348.921803 -221.210949) (xy 348.913704 -221.159811) (xy 348.913196 -221.133924)
			(xy 348.632272 -221.133924) (xy 348.631745 -221.161632) (xy 348.622548 -221.216279) (xy 348.613984 -221.242636)
			(xy 348.60611 -221.264734) (xy 348.811088 -221.619572) (xy 348.833948 -221.62389) (xy 348.858767 -221.629064)
			(xy 348.906546 -221.646018) (xy 348.951165 -221.670088) (xy 348.991572 -221.700708) (xy 349.026813 -221.737154)
			(xy 349.056057 -221.778566) (xy 349.078614 -221.823969) (xy 349.093952 -221.872291) (xy 349.10171 -221.922391)
			(xy 349.102172 -221.94774) (xy 349.101664 -221.973647) (xy 349.093558 -222.024824) (xy 349.077546 -222.074103)
			(xy 349.054023 -222.12027) (xy 349.023567 -222.162189) (xy 348.986929 -222.198827) (xy 348.94501 -222.229283)
			(xy 348.898843 -222.252806) (xy 348.849564 -222.268818) (xy 348.798387 -222.276924) (xy 348.746573 -222.276924)
			(xy 348.695396 -222.268818) (xy 348.646117 -222.252806) (xy 348.59995 -222.229283) (xy 348.558031 -222.198827)
			(xy 348.521393 -222.162189) (xy 348.490937 -222.12027) (xy 348.467414 -222.074103) (xy 348.451402 -222.024824)
			(xy 348.443296 -221.973647) (xy 348.442788 -221.94774) (xy 348.443392 -221.920023) (xy 348.452709 -221.865377)
			(xy 348.46133 -221.839028) (xy 348.469204 -221.81693) (xy 348.264226 -221.462092) (xy 348.241366 -221.457774)
			(xy 348.216566 -221.452574) (xy 348.16883 -221.435583) (xy 348.124255 -221.411489) (xy 348.083891 -221.380859)
			(xy 348.048689 -221.344414) (xy 348.019476 -221.303012) (xy 347.996942 -221.257629) (xy 347.981617 -221.209332)
			(xy 347.973861 -221.159259) (xy 347.973396 -221.133924) (xy 347.692472 -221.133924) (xy 347.691964 -221.159811)
			(xy 347.683865 -221.210949) (xy 347.667866 -221.260189) (xy 347.64436 -221.306321) (xy 347.613928 -221.348208)
			(xy 347.577318 -221.384818) (xy 347.535431 -221.41525) (xy 347.489299 -221.438756) (xy 347.440059 -221.454755)
			(xy 347.388921 -221.462854) (xy 347.337147 -221.462854) (xy 347.286009 -221.454755) (xy 347.236769 -221.438756)
			(xy 347.190637 -221.41525) (xy 347.14875 -221.384818) (xy 347.11214 -221.348208) (xy 347.081708 -221.306321)
			(xy 347.058202 -221.260189) (xy 347.042203 -221.210949) (xy 347.034104 -221.159811) (xy 347.033596 -221.133924)
			(xy 346.752672 -221.133924) (xy 346.752145 -221.161632) (xy 346.742948 -221.216279) (xy 346.734384 -221.242636)
			(xy 346.72651 -221.264734) (xy 346.931488 -221.619572) (xy 346.954348 -221.62389) (xy 346.979167 -221.629064)
			(xy 347.026946 -221.646018) (xy 347.071565 -221.670088) (xy 347.111972 -221.700708) (xy 347.147213 -221.737154)
			(xy 347.176457 -221.778566) (xy 347.199014 -221.823969) (xy 347.214352 -221.872291) (xy 347.22211 -221.922391)
			(xy 347.222572 -221.94774) (xy 347.222064 -221.973647) (xy 347.213958 -222.024824) (xy 347.197946 -222.074103)
			(xy 347.174423 -222.12027) (xy 347.143967 -222.162189) (xy 347.107329 -222.198827) (xy 347.06541 -222.229283)
			(xy 347.019243 -222.252806) (xy 346.969964 -222.268818) (xy 346.918787 -222.276924) (xy 346.866973 -222.276924)
			(xy 346.815796 -222.268818) (xy 346.766517 -222.252806) (xy 346.72035 -222.229283) (xy 346.678431 -222.198827)
			(xy 346.641793 -222.162189) (xy 346.611337 -222.12027) (xy 346.587814 -222.074103) (xy 346.571802 -222.024824)
			(xy 346.563696 -221.973647) (xy 346.563188 -221.94774) (xy 346.563792 -221.920023) (xy 346.573109 -221.865377)
			(xy 346.58173 -221.839028) (xy 346.589604 -221.81693) (xy 346.384626 -221.462092) (xy 346.361766 -221.457774)
			(xy 346.336966 -221.452574) (xy 346.28923 -221.435583) (xy 346.244655 -221.411489) (xy 346.204291 -221.380859)
			(xy 346.169089 -221.344414) (xy 346.139876 -221.303012) (xy 346.117342 -221.257629) (xy 346.102017 -221.209332)
			(xy 346.094261 -221.159259) (xy 346.093796 -221.133924) (xy 345.812872 -221.133924) (xy 345.812364 -221.159811)
			(xy 345.804265 -221.210949) (xy 345.788266 -221.260189) (xy 345.76476 -221.306321) (xy 345.734328 -221.348208)
			(xy 345.697718 -221.384818) (xy 345.655831 -221.41525) (xy 345.609699 -221.438756) (xy 345.560459 -221.454755)
			(xy 345.509321 -221.462854) (xy 345.457547 -221.462854) (xy 345.406409 -221.454755) (xy 345.357169 -221.438756)
			(xy 345.311037 -221.41525) (xy 345.26915 -221.384818) (xy 345.23254 -221.348208) (xy 345.202108 -221.306321)
			(xy 345.178602 -221.260189) (xy 345.162603 -221.210949) (xy 345.154504 -221.159811) (xy 345.153996 -221.133924)
			(xy 344.873072 -221.133924) (xy 344.872545 -221.161632) (xy 344.863348 -221.216279) (xy 344.854784 -221.242636)
			(xy 344.84691 -221.264734) (xy 345.051888 -221.619572) (xy 345.074748 -221.62389) (xy 345.099567 -221.629064)
			(xy 345.147346 -221.646018) (xy 345.191965 -221.670088) (xy 345.232372 -221.700708) (xy 345.267613 -221.737154)
			(xy 345.296857 -221.778566) (xy 345.319414 -221.823969) (xy 345.334752 -221.872291) (xy 345.34251 -221.922391)
			(xy 345.342972 -221.94774) (xy 345.342464 -221.973647) (xy 345.334358 -222.024824) (xy 345.318346 -222.074103)
			(xy 345.294823 -222.12027) (xy 345.264367 -222.162189) (xy 345.227729 -222.198827) (xy 345.18581 -222.229283)
			(xy 345.139643 -222.252806) (xy 345.090364 -222.268818) (xy 345.039187 -222.276924) (xy 344.987373 -222.276924)
			(xy 344.936196 -222.268818) (xy 344.886917 -222.252806) (xy 344.84075 -222.229283) (xy 344.798831 -222.198827)
			(xy 344.762193 -222.162189) (xy 344.731737 -222.12027) (xy 344.708214 -222.074103) (xy 344.692202 -222.024824)
			(xy 344.684096 -221.973647) (xy 344.683588 -221.94774) (xy 344.684192 -221.920023) (xy 344.693509 -221.865377)
			(xy 344.70213 -221.839028) (xy 344.710004 -221.81693) (xy 344.505026 -221.462092) (xy 344.482166 -221.457774)
			(xy 344.457366 -221.452574) (xy 344.40963 -221.435583) (xy 344.365055 -221.411489) (xy 344.324691 -221.380859)
			(xy 344.289489 -221.344414) (xy 344.260276 -221.303012) (xy 344.237742 -221.257629) (xy 344.222417 -221.209332)
			(xy 344.214661 -221.159259) (xy 344.214196 -221.133924) (xy 343.933272 -221.133924) (xy 343.932764 -221.159811)
			(xy 343.924665 -221.210949) (xy 343.908666 -221.260189) (xy 343.88516 -221.306321) (xy 343.854728 -221.348208)
			(xy 343.818118 -221.384818) (xy 343.776231 -221.41525) (xy 343.730099 -221.438756) (xy 343.680859 -221.454755)
			(xy 343.629721 -221.462854) (xy 343.577947 -221.462854) (xy 343.526809 -221.454755) (xy 343.477569 -221.438756)
			(xy 343.431437 -221.41525) (xy 343.38955 -221.384818) (xy 343.35294 -221.348208) (xy 343.322508 -221.306321)
			(xy 343.299002 -221.260189) (xy 343.283003 -221.210949) (xy 343.274904 -221.159811) (xy 343.274396 -221.133924)
			(xy 342.993472 -221.133924) (xy 342.992945 -221.161632) (xy 342.983748 -221.216279) (xy 342.975184 -221.242636)
			(xy 342.96731 -221.264734) (xy 343.172288 -221.619572) (xy 343.195148 -221.62389) (xy 343.219967 -221.629064)
			(xy 343.267746 -221.646018) (xy 343.312365 -221.670088) (xy 343.352772 -221.700708) (xy 343.388013 -221.737154)
			(xy 343.417257 -221.778566) (xy 343.439814 -221.823969) (xy 343.455152 -221.872291) (xy 343.46291 -221.922391)
			(xy 343.463372 -221.94774) (xy 343.462864 -221.973647) (xy 343.454758 -222.024824) (xy 343.438746 -222.074103)
			(xy 343.415223 -222.12027) (xy 343.384767 -222.162189) (xy 343.348129 -222.198827) (xy 343.30621 -222.229283)
			(xy 343.260043 -222.252806) (xy 343.210764 -222.268818) (xy 343.159587 -222.276924) (xy 343.107773 -222.276924)
			(xy 343.056596 -222.268818) (xy 343.007317 -222.252806) (xy 342.96115 -222.229283) (xy 342.919231 -222.198827)
			(xy 342.882593 -222.162189) (xy 342.852137 -222.12027) (xy 342.828614 -222.074103) (xy 342.812602 -222.024824)
			(xy 342.804496 -221.973647) (xy 342.803988 -221.94774) (xy 342.804592 -221.920023) (xy 342.813909 -221.865377)
			(xy 342.82253 -221.839028) (xy 342.830404 -221.81693) (xy 342.625426 -221.462092) (xy 342.602566 -221.457774)
			(xy 342.577766 -221.452574) (xy 342.53003 -221.435583) (xy 342.485455 -221.411489) (xy 342.445091 -221.380859)
			(xy 342.409889 -221.344414) (xy 342.380676 -221.303012) (xy 342.358142 -221.257629) (xy 342.342817 -221.209332)
			(xy 342.335061 -221.159259) (xy 342.334596 -221.133924) (xy 342.053672 -221.133924) (xy 342.053164 -221.159811)
			(xy 342.045065 -221.210949) (xy 342.029066 -221.260189) (xy 342.00556 -221.306321) (xy 341.975128 -221.348208)
			(xy 341.938518 -221.384818) (xy 341.896631 -221.41525) (xy 341.850499 -221.438756) (xy 341.801259 -221.454755)
			(xy 341.750121 -221.462854) (xy 341.698347 -221.462854) (xy 341.647209 -221.454755) (xy 341.597969 -221.438756)
			(xy 341.551837 -221.41525) (xy 341.50995 -221.384818) (xy 341.47334 -221.348208) (xy 341.442908 -221.306321)
			(xy 341.419402 -221.260189) (xy 341.403403 -221.210949) (xy 341.395304 -221.159811) (xy 341.394796 -221.133924)
			(xy 341.113872 -221.133924) (xy 341.113345 -221.161632) (xy 341.104148 -221.216279) (xy 341.095584 -221.242636)
			(xy 341.08771 -221.264734) (xy 341.292688 -221.619572) (xy 341.315548 -221.62389) (xy 341.340367 -221.629064)
			(xy 341.388146 -221.646018) (xy 341.432765 -221.670088) (xy 341.473172 -221.700708) (xy 341.508413 -221.737154)
			(xy 341.537657 -221.778566) (xy 341.560214 -221.823969) (xy 341.575552 -221.872291) (xy 341.58331 -221.922391)
			(xy 341.583772 -221.94774) (xy 341.583264 -221.973647) (xy 341.575158 -222.024824) (xy 341.559146 -222.074103)
			(xy 341.535623 -222.12027) (xy 341.505167 -222.162189) (xy 341.468529 -222.198827) (xy 341.42661 -222.229283)
			(xy 341.380443 -222.252806) (xy 341.331164 -222.268818) (xy 341.279987 -222.276924) (xy 341.228173 -222.276924)
			(xy 341.176996 -222.268818) (xy 341.127717 -222.252806) (xy 341.08155 -222.229283) (xy 341.039631 -222.198827)
			(xy 341.002993 -222.162189) (xy 340.972537 -222.12027) (xy 340.949014 -222.074103) (xy 340.933002 -222.024824)
			(xy 340.924896 -221.973647) (xy 340.924388 -221.94774) (xy 340.924992 -221.920023) (xy 340.934309 -221.865377)
			(xy 340.94293 -221.839028) (xy 340.950804 -221.81693) (xy 340.745826 -221.462092) (xy 340.722966 -221.457774)
			(xy 340.698166 -221.452574) (xy 340.65043 -221.435583) (xy 340.605855 -221.411489) (xy 340.565491 -221.380859)
			(xy 340.530289 -221.344414) (xy 340.501076 -221.303012) (xy 340.478542 -221.257629) (xy 340.463217 -221.209332)
			(xy 340.455461 -221.159259) (xy 340.454996 -221.133924) (xy 340.174072 -221.133924) (xy 340.173564 -221.159811)
			(xy 340.165465 -221.210949) (xy 340.149466 -221.260189) (xy 340.12596 -221.306321) (xy 340.095528 -221.348208)
			(xy 340.058918 -221.384818) (xy 340.017031 -221.41525) (xy 339.970899 -221.438756) (xy 339.921659 -221.454755)
			(xy 339.870521 -221.462854) (xy 339.818747 -221.462854) (xy 339.767609 -221.454755) (xy 339.718369 -221.438756)
			(xy 339.672237 -221.41525) (xy 339.63035 -221.384818) (xy 339.59374 -221.348208) (xy 339.563308 -221.306321)
			(xy 339.539802 -221.260189) (xy 339.523803 -221.210949) (xy 339.515704 -221.159811) (xy 339.515196 -221.133924)
			(xy 339.234272 -221.133924) (xy 339.233745 -221.161632) (xy 339.224548 -221.216279) (xy 339.215984 -221.242636)
			(xy 339.20811 -221.264734) (xy 339.413088 -221.619572) (xy 339.435948 -221.62389) (xy 339.460767 -221.629064)
			(xy 339.508546 -221.646018) (xy 339.553165 -221.670088) (xy 339.593572 -221.700708) (xy 339.628813 -221.737154)
			(xy 339.658057 -221.778566) (xy 339.680614 -221.823969) (xy 339.695952 -221.872291) (xy 339.70371 -221.922391)
			(xy 339.704172 -221.94774) (xy 339.703664 -221.973647) (xy 339.695558 -222.024824) (xy 339.679546 -222.074103)
			(xy 339.656023 -222.12027) (xy 339.625567 -222.162189) (xy 339.588929 -222.198827) (xy 339.54701 -222.229283)
			(xy 339.500843 -222.252806) (xy 339.451564 -222.268818) (xy 339.400387 -222.276924) (xy 339.348573 -222.276924)
			(xy 339.297396 -222.268818) (xy 339.248117 -222.252806) (xy 339.20195 -222.229283) (xy 339.160031 -222.198827)
			(xy 339.123393 -222.162189) (xy 339.092937 -222.12027) (xy 339.069414 -222.074103) (xy 339.053402 -222.024824)
			(xy 339.045296 -221.973647) (xy 339.044788 -221.94774) (xy 339.045392 -221.920023) (xy 339.054709 -221.865377)
			(xy 339.06333 -221.839028) (xy 339.071204 -221.81693) (xy 338.866226 -221.462092) (xy 338.843366 -221.457774)
			(xy 338.818566 -221.452574) (xy 338.77083 -221.435583) (xy 338.726255 -221.411489) (xy 338.685891 -221.380859)
			(xy 338.650689 -221.344414) (xy 338.621476 -221.303012) (xy 338.598942 -221.257629) (xy 338.583617 -221.209332)
			(xy 338.575861 -221.159259) (xy 338.575396 -221.133924) (xy 338.294472 -221.133924) (xy 338.293964 -221.159811)
			(xy 338.285865 -221.210949) (xy 338.269866 -221.260189) (xy 338.24636 -221.306321) (xy 338.215928 -221.348208)
			(xy 338.179318 -221.384818) (xy 338.137431 -221.41525) (xy 338.091299 -221.438756) (xy 338.042059 -221.454755)
			(xy 337.990921 -221.462854) (xy 337.939147 -221.462854) (xy 337.888009 -221.454755) (xy 337.838769 -221.438756)
			(xy 337.792637 -221.41525) (xy 337.75075 -221.384818) (xy 337.71414 -221.348208) (xy 337.683708 -221.306321)
			(xy 337.660202 -221.260189) (xy 337.644203 -221.210949) (xy 337.636104 -221.159811) (xy 337.635596 -221.133924)
			(xy 337.354672 -221.133924) (xy 337.354145 -221.161632) (xy 337.344948 -221.216279) (xy 337.336384 -221.242636)
			(xy 337.32851 -221.264734) (xy 337.533488 -221.619572) (xy 337.556348 -221.62389) (xy 337.581167 -221.629064)
			(xy 337.628946 -221.646018) (xy 337.673565 -221.670088) (xy 337.713972 -221.700708) (xy 337.749213 -221.737154)
			(xy 337.778457 -221.778566) (xy 337.801014 -221.823969) (xy 337.816352 -221.872291) (xy 337.82411 -221.922391)
			(xy 337.824572 -221.94774) (xy 337.824064 -221.973647) (xy 337.815958 -222.024824) (xy 337.799946 -222.074103)
			(xy 337.776423 -222.12027) (xy 337.745967 -222.162189) (xy 337.709329 -222.198827) (xy 337.66741 -222.229283)
			(xy 337.621243 -222.252806) (xy 337.571964 -222.268818) (xy 337.520787 -222.276924) (xy 337.468973 -222.276924)
			(xy 337.417796 -222.268818) (xy 337.368517 -222.252806) (xy 337.32235 -222.229283) (xy 337.280431 -222.198827)
			(xy 337.243793 -222.162189) (xy 337.213337 -222.12027) (xy 337.189814 -222.074103) (xy 337.173802 -222.024824)
			(xy 337.165696 -221.973647) (xy 337.165188 -221.94774) (xy 337.165792 -221.920023) (xy 337.175109 -221.865377)
			(xy 337.18373 -221.839028) (xy 337.191604 -221.81693) (xy 336.986626 -221.462092) (xy 336.963766 -221.457774)
			(xy 336.938966 -221.452574) (xy 336.89123 -221.435583) (xy 336.846655 -221.411489) (xy 336.806291 -221.380859)
			(xy 336.771089 -221.344414) (xy 336.741876 -221.303012) (xy 336.719342 -221.257629) (xy 336.704017 -221.209332)
			(xy 336.696261 -221.159259) (xy 336.695796 -221.133924) (xy 135.464804 -221.133924) (xy 135.464385 -221.15929)
			(xy 135.456633 -221.209425) (xy 135.441284 -221.257778) (xy 135.418702 -221.303206) (xy 135.389421 -221.344633)
			(xy 135.354133 -221.381081) (xy 135.313674 -221.411686) (xy 135.269 -221.435725) (xy 135.221169 -221.45263)
			(xy 135.196326 -221.457774) (xy 135.173466 -221.462092) (xy 134.968742 -221.81693) (xy 134.976362 -221.838774)
			(xy 134.984977 -221.865059) (xy 134.994298 -221.919578) (xy 134.994904 -221.947232) (xy 134.994904 -221.94774)
			(xy 134.994396 -221.973647) (xy 134.98629 -222.024824) (xy 134.970278 -222.074103) (xy 134.946755 -222.12027)
			(xy 134.916299 -222.162189) (xy 134.879661 -222.198827) (xy 134.837742 -222.229283) (xy 134.791575 -222.252806)
			(xy 134.742296 -222.268818) (xy 134.691119 -222.276924) (xy 134.639305 -222.276924) (xy 134.588128 -222.268818)
			(xy 134.538849 -222.252806) (xy 134.492682 -222.229283) (xy 134.450763 -222.198827) (xy 134.414125 -222.162189)
			(xy 134.383669 -222.12027) (xy 134.360146 -222.074103) (xy 134.344134 -222.024824) (xy 134.336028 -221.973647)
			(xy 134.33552 -221.94774) (xy 133.115304 -221.94774) (xy 133.114796 -221.973647) (xy 133.10669 -222.024824)
			(xy 133.090678 -222.074103) (xy 133.067155 -222.12027) (xy 133.036699 -222.162189) (xy 133.000061 -222.198827)
			(xy 132.958142 -222.229283) (xy 132.911975 -222.252806) (xy 132.862696 -222.268818) (xy 132.811519 -222.276924)
			(xy 132.759705 -222.276924) (xy 132.708528 -222.268818) (xy 132.659249 -222.252806) (xy 132.613082 -222.229283)
			(xy 132.571163 -222.198827) (xy 132.534525 -222.162189) (xy 132.504069 -222.12027) (xy 132.480546 -222.074103)
			(xy 132.464534 -222.024824) (xy 132.456428 -221.973647) (xy 132.45592 -221.94774) (xy 131.235704 -221.94774)
			(xy 131.235196 -221.973647) (xy 131.22709 -222.024824) (xy 131.211078 -222.074103) (xy 131.187555 -222.12027)
			(xy 131.157099 -222.162189) (xy 131.120461 -222.198827) (xy 131.078542 -222.229283) (xy 131.032375 -222.252806)
			(xy 130.983096 -222.268818) (xy 130.931919 -222.276924) (xy 130.880105 -222.276924) (xy 130.828928 -222.268818)
			(xy 130.779649 -222.252806) (xy 130.733482 -222.229283) (xy 130.691563 -222.198827) (xy 130.654925 -222.162189)
			(xy 130.624469 -222.12027) (xy 130.600946 -222.074103) (xy 130.584934 -222.024824) (xy 130.576828 -221.973647)
			(xy 130.57632 -221.94774) (xy 129.356104 -221.94774) (xy 129.355596 -221.973647) (xy 129.34749 -222.024824)
			(xy 129.331478 -222.074103) (xy 129.307955 -222.12027) (xy 129.277499 -222.162189) (xy 129.240861 -222.198827)
			(xy 129.198942 -222.229283) (xy 129.152775 -222.252806) (xy 129.103496 -222.268818) (xy 129.052319 -222.276924)
			(xy 129.000505 -222.276924) (xy 128.949328 -222.268818) (xy 128.900049 -222.252806) (xy 128.853882 -222.229283)
			(xy 128.811963 -222.198827) (xy 128.775325 -222.162189) (xy 128.744869 -222.12027) (xy 128.721346 -222.074103)
			(xy 128.705334 -222.024824) (xy 128.697228 -221.973647) (xy 128.69672 -221.94774) (xy 127.476504 -221.94774)
			(xy 127.475996 -221.973647) (xy 127.46789 -222.024824) (xy 127.451878 -222.074103) (xy 127.428355 -222.12027)
			(xy 127.397899 -222.162189) (xy 127.361261 -222.198827) (xy 127.319342 -222.229283) (xy 127.273175 -222.252806)
			(xy 127.223896 -222.268818) (xy 127.172719 -222.276924) (xy 127.120905 -222.276924) (xy 127.069728 -222.268818)
			(xy 127.020449 -222.252806) (xy 126.974282 -222.229283) (xy 126.932363 -222.198827) (xy 126.895725 -222.162189)
			(xy 126.865269 -222.12027) (xy 126.841746 -222.074103) (xy 126.825734 -222.024824) (xy 126.817628 -221.973647)
			(xy 126.81712 -221.94774) (xy 125.596904 -221.94774) (xy 125.596396 -221.973647) (xy 125.58829 -222.024824)
			(xy 125.572278 -222.074103) (xy 125.548755 -222.12027) (xy 125.518299 -222.162189) (xy 125.481661 -222.198827)
			(xy 125.439742 -222.229283) (xy 125.393575 -222.252806) (xy 125.344296 -222.268818) (xy 125.293119 -222.276924)
			(xy 125.241305 -222.276924) (xy 125.190128 -222.268818) (xy 125.140849 -222.252806) (xy 125.094682 -222.229283)
			(xy 125.052763 -222.198827) (xy 125.016125 -222.162189) (xy 124.985669 -222.12027) (xy 124.962146 -222.074103)
			(xy 124.946134 -222.024824) (xy 124.938028 -221.973647) (xy 124.93752 -221.94774) (xy 123.717304 -221.94774)
			(xy 123.716796 -221.973647) (xy 123.70869 -222.024824) (xy 123.692678 -222.074103) (xy 123.669155 -222.12027)
			(xy 123.638699 -222.162189) (xy 123.602061 -222.198827) (xy 123.560142 -222.229283) (xy 123.513975 -222.252806)
			(xy 123.464696 -222.268818) (xy 123.413519 -222.276924) (xy 123.361705 -222.276924) (xy 123.310528 -222.268818)
			(xy 123.261249 -222.252806) (xy 123.215082 -222.229283) (xy 123.173163 -222.198827) (xy 123.136525 -222.162189)
			(xy 123.106069 -222.12027) (xy 123.082546 -222.074103) (xy 123.066534 -222.024824) (xy 123.058428 -221.973647)
			(xy 123.05792 -221.94774) (xy 121.837704 -221.94774) (xy 121.837196 -221.973647) (xy 121.82909 -222.024824)
			(xy 121.813078 -222.074103) (xy 121.789555 -222.12027) (xy 121.759099 -222.162189) (xy 121.722461 -222.198827)
			(xy 121.680542 -222.229283) (xy 121.634375 -222.252806) (xy 121.585096 -222.268818) (xy 121.533919 -222.276924)
			(xy 121.482105 -222.276924) (xy 121.430928 -222.268818) (xy 121.381649 -222.252806) (xy 121.335482 -222.229283)
			(xy 121.293563 -222.198827) (xy 121.256925 -222.162189) (xy 121.226469 -222.12027) (xy 121.202946 -222.074103)
			(xy 121.186934 -222.024824) (xy 121.178828 -221.973647) (xy 121.17832 -221.94774) (xy 118.078504 -221.94774)
			(xy 118.077996 -221.973647) (xy 118.06989 -222.024824) (xy 118.053878 -222.074103) (xy 118.030355 -222.12027)
			(xy 117.999899 -222.162189) (xy 117.963261 -222.198827) (xy 117.921342 -222.229283) (xy 117.875175 -222.252806)
			(xy 117.825896 -222.268818) (xy 117.774719 -222.276924) (xy 117.722905 -222.276924) (xy 117.671728 -222.268818)
			(xy 117.622449 -222.252806) (xy 117.576282 -222.229283) (xy 117.534363 -222.198827) (xy 117.497725 -222.162189)
			(xy 117.467269 -222.12027) (xy 117.443746 -222.074103) (xy 117.427734 -222.024824) (xy 117.419628 -221.973647)
			(xy 117.41912 -221.94774) (xy 116.198904 -221.94774) (xy 116.198396 -221.973647) (xy 116.19029 -222.024824)
			(xy 116.174278 -222.074103) (xy 116.150755 -222.12027) (xy 116.120299 -222.162189) (xy 116.083661 -222.198827)
			(xy 116.041742 -222.229283) (xy 115.995575 -222.252806) (xy 115.946296 -222.268818) (xy 115.895119 -222.276924)
			(xy 115.843305 -222.276924) (xy 115.792128 -222.268818) (xy 115.742849 -222.252806) (xy 115.696682 -222.229283)
			(xy 115.654763 -222.198827) (xy 115.618125 -222.162189) (xy 115.587669 -222.12027) (xy 115.564146 -222.074103)
			(xy 115.548134 -222.024824) (xy 115.540028 -221.973647) (xy 115.53952 -221.94774) (xy 114.319304 -221.94774)
			(xy 114.318796 -221.973627) (xy 114.310697 -222.024765) (xy 114.294698 -222.074005) (xy 114.271192 -222.120137)
			(xy 114.24076 -222.162024) (xy 114.20415 -222.198634) (xy 114.162263 -222.229066) (xy 114.116131 -222.252572)
			(xy 114.066891 -222.268571) (xy 114.015753 -222.27667) (xy 113.963979 -222.27667) (xy 113.912841 -222.268571)
			(xy 113.863601 -222.252572) (xy 113.817469 -222.229066) (xy 113.775582 -222.198634) (xy 113.738972 -222.162024)
			(xy 113.70854 -222.120137) (xy 113.685034 -222.074005) (xy 113.669035 -222.024765) (xy 113.660936 -221.973627)
			(xy 113.660428 -221.94774) (xy 112.439704 -221.94774) (xy 112.439196 -221.973647) (xy 112.43109 -222.024824)
			(xy 112.415078 -222.074103) (xy 112.391555 -222.12027) (xy 112.361099 -222.162189) (xy 112.324461 -222.198827)
			(xy 112.282542 -222.229283) (xy 112.236375 -222.252806) (xy 112.187096 -222.268818) (xy 112.135919 -222.276924)
			(xy 112.084105 -222.276924) (xy 112.032928 -222.268818) (xy 111.983649 -222.252806) (xy 111.937482 -222.229283)
			(xy 111.895563 -222.198827) (xy 111.858925 -222.162189) (xy 111.828469 -222.12027) (xy 111.804946 -222.074103)
			(xy 111.788934 -222.024824) (xy 111.780828 -221.973647) (xy 111.78032 -221.94774) (xy 110.560104 -221.94774)
			(xy 110.559596 -221.973627) (xy 110.551497 -222.024765) (xy 110.535498 -222.074005) (xy 110.511992 -222.120137)
			(xy 110.48156 -222.162024) (xy 110.44495 -222.198634) (xy 110.403063 -222.229066) (xy 110.356931 -222.252572)
			(xy 110.307691 -222.268571) (xy 110.256553 -222.27667) (xy 110.204779 -222.27667) (xy 110.153641 -222.268571)
			(xy 110.104401 -222.252572) (xy 110.058269 -222.229066) (xy 110.016382 -222.198634) (xy 109.979772 -222.162024)
			(xy 109.94934 -222.120137) (xy 109.925834 -222.074005) (xy 109.909835 -222.024765) (xy 109.901736 -221.973627)
			(xy 109.901228 -221.94774) (xy 108.680504 -221.94774) (xy 108.679996 -221.973647) (xy 108.67189 -222.024824)
			(xy 108.655878 -222.074103) (xy 108.632355 -222.12027) (xy 108.601899 -222.162189) (xy 108.565261 -222.198827)
			(xy 108.523342 -222.229283) (xy 108.477175 -222.252806) (xy 108.427896 -222.268818) (xy 108.376719 -222.276924)
			(xy 108.324905 -222.276924) (xy 108.273728 -222.268818) (xy 108.224449 -222.252806) (xy 108.178282 -222.229283)
			(xy 108.136363 -222.198827) (xy 108.099725 -222.162189) (xy 108.069269 -222.12027) (xy 108.045746 -222.074103)
			(xy 108.029734 -222.024824) (xy 108.021628 -221.973647) (xy 108.02112 -221.94774) (xy 106.800904 -221.94774)
			(xy 106.800396 -221.973647) (xy 106.79229 -222.024824) (xy 106.776278 -222.074103) (xy 106.752755 -222.12027)
			(xy 106.722299 -222.162189) (xy 106.685661 -222.198827) (xy 106.643742 -222.229283) (xy 106.597575 -222.252806)
			(xy 106.548296 -222.268818) (xy 106.497119 -222.276924) (xy 106.445305 -222.276924) (xy 106.394128 -222.268818)
			(xy 106.344849 -222.252806) (xy 106.298682 -222.229283) (xy 106.256763 -222.198827) (xy 106.220125 -222.162189)
			(xy 106.189669 -222.12027) (xy 106.166146 -222.074103) (xy 106.150134 -222.024824) (xy 106.142028 -221.973647)
			(xy 106.14152 -221.94774) (xy 104.921304 -221.94774) (xy 104.920796 -221.973647) (xy 104.91269 -222.024824)
			(xy 104.896678 -222.074103) (xy 104.873155 -222.12027) (xy 104.842699 -222.162189) (xy 104.806061 -222.198827)
			(xy 104.764142 -222.229283) (xy 104.717975 -222.252806) (xy 104.668696 -222.268818) (xy 104.617519 -222.276924)
			(xy 104.565705 -222.276924) (xy 104.514528 -222.268818) (xy 104.465249 -222.252806) (xy 104.419082 -222.229283)
			(xy 104.377163 -222.198827) (xy 104.340525 -222.162189) (xy 104.310069 -222.12027) (xy 104.286546 -222.074103)
			(xy 104.270534 -222.024824) (xy 104.262428 -221.973647) (xy 104.26192 -221.94774) (xy 103.041704 -221.94774)
			(xy 103.041196 -221.973647) (xy 103.03309 -222.024824) (xy 103.017078 -222.074103) (xy 102.993555 -222.12027)
			(xy 102.963099 -222.162189) (xy 102.926461 -222.198827) (xy 102.884542 -222.229283) (xy 102.838375 -222.252806)
			(xy 102.789096 -222.268818) (xy 102.737919 -222.276924) (xy 102.686105 -222.276924) (xy 102.634928 -222.268818)
			(xy 102.585649 -222.252806) (xy 102.539482 -222.229283) (xy 102.497563 -222.198827) (xy 102.460925 -222.162189)
			(xy 102.430469 -222.12027) (xy 102.406946 -222.074103) (xy 102.390934 -222.024824) (xy 102.382828 -221.973647)
			(xy 102.38232 -221.94774) (xy 102.382923 -221.920023) (xy 102.39224 -221.865377) (xy 102.400862 -221.839028)
			(xy 102.408736 -221.81693) (xy 102.203758 -221.462092) (xy 102.180898 -221.457774) (xy 102.156103 -221.45255)
			(xy 102.108367 -221.435564) (xy 102.063792 -221.411474) (xy 102.023427 -221.380847) (xy 101.988224 -221.344405)
			(xy 101.959011 -221.303006) (xy 101.936476 -221.257625) (xy 101.92115 -221.20933) (xy 101.913394 -221.159258)
			(xy 101.912928 -221.133924) (xy 101.632004 -221.133924) (xy 101.631496 -221.159811) (xy 101.623397 -221.210949)
			(xy 101.607398 -221.260189) (xy 101.583892 -221.306321) (xy 101.55346 -221.348208) (xy 101.51685 -221.384818)
			(xy 101.474963 -221.41525) (xy 101.428831 -221.438756) (xy 101.379591 -221.454755) (xy 101.328453 -221.462854)
			(xy 101.276679 -221.462854) (xy 101.225541 -221.454755) (xy 101.176301 -221.438756) (xy 101.130169 -221.41525)
			(xy 101.088282 -221.384818) (xy 101.051672 -221.348208) (xy 101.02124 -221.306321) (xy 100.997734 -221.260189)
			(xy 100.981735 -221.210949) (xy 100.973636 -221.159811) (xy 100.973128 -221.133924) (xy 100.692204 -221.133924)
			(xy 100.69168 -221.161632) (xy 100.682481 -221.216279) (xy 100.673916 -221.242636) (xy 100.666042 -221.264734)
			(xy 100.87102 -221.619572) (xy 100.89388 -221.62389) (xy 100.918705 -221.629041) (xy 100.966483 -221.645999)
			(xy 101.011102 -221.670074) (xy 101.051507 -221.700696) (xy 101.086747 -221.737145) (xy 101.11599 -221.778561)
			(xy 101.138547 -221.823965) (xy 101.153885 -221.872289) (xy 101.161642 -221.92239) (xy 101.162104 -221.94774)
			(xy 101.161596 -221.973647) (xy 101.15349 -222.024824) (xy 101.137478 -222.074103) (xy 101.113955 -222.12027)
			(xy 101.083499 -222.162189) (xy 101.046861 -222.198827) (xy 101.004942 -222.229283) (xy 100.958775 -222.252806)
			(xy 100.909496 -222.268818) (xy 100.858319 -222.276924) (xy 100.806505 -222.276924) (xy 100.755328 -222.268818)
			(xy 100.706049 -222.252806) (xy 100.659882 -222.229283) (xy 100.617963 -222.198827) (xy 100.581325 -222.162189)
			(xy 100.550869 -222.12027) (xy 100.527346 -222.074103) (xy 100.511334 -222.024824) (xy 100.503228 -221.973647)
			(xy 100.50272 -221.94774) (xy 100.503323 -221.920023) (xy 100.51264 -221.865377) (xy 100.521262 -221.839028)
			(xy 100.529136 -221.81693) (xy 100.324158 -221.462092) (xy 100.301298 -221.457774) (xy 100.276503 -221.45255)
			(xy 100.228767 -221.435564) (xy 100.184192 -221.411474) (xy 100.143827 -221.380847) (xy 100.108624 -221.344405)
			(xy 100.079411 -221.303006) (xy 100.056876 -221.257625) (xy 100.04155 -221.20933) (xy 100.033794 -221.159258)
			(xy 100.033328 -221.133924) (xy 99.752404 -221.133924) (xy 99.751896 -221.159811) (xy 99.743797 -221.210949)
			(xy 99.727798 -221.260189) (xy 99.704292 -221.306321) (xy 99.67386 -221.348208) (xy 99.63725 -221.384818)
			(xy 99.595363 -221.41525) (xy 99.549231 -221.438756) (xy 99.499991 -221.454755) (xy 99.448853 -221.462854)
			(xy 99.397079 -221.462854) (xy 99.345941 -221.454755) (xy 99.296701 -221.438756) (xy 99.250569 -221.41525)
			(xy 99.208682 -221.384818) (xy 99.172072 -221.348208) (xy 99.14164 -221.306321) (xy 99.118134 -221.260189)
			(xy 99.102135 -221.210949) (xy 99.094036 -221.159811) (xy 99.093528 -221.133924) (xy 98.812604 -221.133924)
			(xy 98.81208 -221.161632) (xy 98.802881 -221.216279) (xy 98.794316 -221.242636) (xy 98.786442 -221.264734)
			(xy 98.99142 -221.619572) (xy 99.01428 -221.62389) (xy 99.039105 -221.629041) (xy 99.086883 -221.645999)
			(xy 99.131502 -221.670074) (xy 99.171907 -221.700696) (xy 99.207147 -221.737145) (xy 99.23639 -221.778561)
			(xy 99.258947 -221.823965) (xy 99.274285 -221.872289) (xy 99.282042 -221.92239) (xy 99.282504 -221.94774)
			(xy 99.281996 -221.973647) (xy 99.27389 -222.024824) (xy 99.257878 -222.074103) (xy 99.234355 -222.12027)
			(xy 99.203899 -222.162189) (xy 99.167261 -222.198827) (xy 99.125342 -222.229283) (xy 99.079175 -222.252806)
			(xy 99.029896 -222.268818) (xy 98.978719 -222.276924) (xy 98.926905 -222.276924) (xy 98.875728 -222.268818)
			(xy 98.826449 -222.252806) (xy 98.780282 -222.229283) (xy 98.738363 -222.198827) (xy 98.701725 -222.162189)
			(xy 98.671269 -222.12027) (xy 98.647746 -222.074103) (xy 98.631734 -222.024824) (xy 98.623628 -221.973647)
			(xy 98.62312 -221.94774) (xy 98.623723 -221.920023) (xy 98.63304 -221.865377) (xy 98.641662 -221.839028)
			(xy 98.649536 -221.81693) (xy 98.444558 -221.462092) (xy 98.421698 -221.457774) (xy 98.396903 -221.45255)
			(xy 98.349167 -221.435564) (xy 98.304592 -221.411474) (xy 98.264227 -221.380847) (xy 98.229024 -221.344405)
			(xy 98.199811 -221.303006) (xy 98.177276 -221.257625) (xy 98.16195 -221.20933) (xy 98.154194 -221.159258)
			(xy 98.153728 -221.133924) (xy 97.872804 -221.133924) (xy 97.872296 -221.159811) (xy 97.864197 -221.210949)
			(xy 97.848198 -221.260189) (xy 97.824692 -221.306321) (xy 97.79426 -221.348208) (xy 97.75765 -221.384818)
			(xy 97.715763 -221.41525) (xy 97.669631 -221.438756) (xy 97.620391 -221.454755) (xy 97.569253 -221.462854)
			(xy 97.517479 -221.462854) (xy 97.466341 -221.454755) (xy 97.417101 -221.438756) (xy 97.370969 -221.41525)
			(xy 97.329082 -221.384818) (xy 97.292472 -221.348208) (xy 97.26204 -221.306321) (xy 97.238534 -221.260189)
			(xy 97.222535 -221.210949) (xy 97.214436 -221.159811) (xy 97.213928 -221.133924) (xy 96.933004 -221.133924)
			(xy 96.93248 -221.161632) (xy 96.923281 -221.216279) (xy 96.914716 -221.242636) (xy 96.906842 -221.264734)
			(xy 97.11182 -221.619572) (xy 97.13468 -221.62389) (xy 97.159505 -221.629041) (xy 97.207283 -221.645999)
			(xy 97.251902 -221.670074) (xy 97.292307 -221.700696) (xy 97.327547 -221.737145) (xy 97.35679 -221.778561)
			(xy 97.379347 -221.823965) (xy 97.394685 -221.872289) (xy 97.402442 -221.92239) (xy 97.402904 -221.94774)
			(xy 97.402396 -221.973647) (xy 97.39429 -222.024824) (xy 97.378278 -222.074103) (xy 97.354755 -222.12027)
			(xy 97.324299 -222.162189) (xy 97.287661 -222.198827) (xy 97.245742 -222.229283) (xy 97.199575 -222.252806)
			(xy 97.150296 -222.268818) (xy 97.099119 -222.276924) (xy 97.047305 -222.276924) (xy 96.996128 -222.268818)
			(xy 96.946849 -222.252806) (xy 96.900682 -222.229283) (xy 96.858763 -222.198827) (xy 96.822125 -222.162189)
			(xy 96.791669 -222.12027) (xy 96.768146 -222.074103) (xy 96.752134 -222.024824) (xy 96.744028 -221.973647)
			(xy 96.74352 -221.94774) (xy 96.744123 -221.920023) (xy 96.75344 -221.865377) (xy 96.762062 -221.839028)
			(xy 96.769936 -221.81693) (xy 96.564958 -221.462092) (xy 96.542098 -221.457774) (xy 96.517303 -221.45255)
			(xy 96.469567 -221.435564) (xy 96.424992 -221.411474) (xy 96.384627 -221.380847) (xy 96.349424 -221.344405)
			(xy 96.320211 -221.303006) (xy 96.297676 -221.257625) (xy 96.28235 -221.20933) (xy 96.274594 -221.159258)
			(xy 96.274128 -221.133924) (xy 95.993204 -221.133924) (xy 95.992696 -221.159811) (xy 95.984597 -221.210949)
			(xy 95.968598 -221.260189) (xy 95.945092 -221.306321) (xy 95.91466 -221.348208) (xy 95.87805 -221.384818)
			(xy 95.836163 -221.41525) (xy 95.790031 -221.438756) (xy 95.740791 -221.454755) (xy 95.689653 -221.462854)
			(xy 95.637879 -221.462854) (xy 95.586741 -221.454755) (xy 95.537501 -221.438756) (xy 95.491369 -221.41525)
			(xy 95.449482 -221.384818) (xy 95.412872 -221.348208) (xy 95.38244 -221.306321) (xy 95.358934 -221.260189)
			(xy 95.342935 -221.210949) (xy 95.334836 -221.159811) (xy 95.334328 -221.133924) (xy 95.053404 -221.133924)
			(xy 95.05288 -221.161632) (xy 95.043681 -221.216279) (xy 95.035116 -221.242636) (xy 95.027242 -221.264734)
			(xy 95.23222 -221.619572) (xy 95.25508 -221.62389) (xy 95.279905 -221.629041) (xy 95.327683 -221.645999)
			(xy 95.372302 -221.670074) (xy 95.412707 -221.700696) (xy 95.447947 -221.737145) (xy 95.47719 -221.778561)
			(xy 95.499747 -221.823965) (xy 95.515085 -221.872289) (xy 95.522842 -221.92239) (xy 95.523304 -221.94774)
			(xy 95.522796 -221.973647) (xy 95.51469 -222.024824) (xy 95.498678 -222.074103) (xy 95.475155 -222.12027)
			(xy 95.444699 -222.162189) (xy 95.408061 -222.198827) (xy 95.366142 -222.229283) (xy 95.319975 -222.252806)
			(xy 95.270696 -222.268818) (xy 95.219519 -222.276924) (xy 95.167705 -222.276924) (xy 95.116528 -222.268818)
			(xy 95.067249 -222.252806) (xy 95.021082 -222.229283) (xy 94.979163 -222.198827) (xy 94.942525 -222.162189)
			(xy 94.912069 -222.12027) (xy 94.888546 -222.074103) (xy 94.872534 -222.024824) (xy 94.864428 -221.973647)
			(xy 94.86392 -221.94774) (xy 94.864523 -221.920023) (xy 94.87384 -221.865377) (xy 94.882462 -221.839028)
			(xy 94.890336 -221.81693) (xy 94.685358 -221.462092) (xy 94.662498 -221.457774) (xy 94.637703 -221.45255)
			(xy 94.589967 -221.435564) (xy 94.545392 -221.411474) (xy 94.505027 -221.380847) (xy 94.469824 -221.344405)
			(xy 94.440611 -221.303006) (xy 94.418076 -221.257625) (xy 94.40275 -221.20933) (xy 94.394994 -221.159258)
			(xy 94.394528 -221.133924) (xy 94.113604 -221.133924) (xy 94.113096 -221.159811) (xy 94.104997 -221.210949)
			(xy 94.088998 -221.260189) (xy 94.065492 -221.306321) (xy 94.03506 -221.348208) (xy 93.99845 -221.384818)
			(xy 93.956563 -221.41525) (xy 93.910431 -221.438756) (xy 93.861191 -221.454755) (xy 93.810053 -221.462854)
			(xy 93.758279 -221.462854) (xy 93.707141 -221.454755) (xy 93.657901 -221.438756) (xy 93.611769 -221.41525)
			(xy 93.569882 -221.384818) (xy 93.533272 -221.348208) (xy 93.50284 -221.306321) (xy 93.479334 -221.260189)
			(xy 93.463335 -221.210949) (xy 93.455236 -221.159811) (xy 93.454728 -221.133924) (xy 93.173804 -221.133924)
			(xy 93.17328 -221.161632) (xy 93.164081 -221.216279) (xy 93.155516 -221.242636) (xy 93.147642 -221.264734)
			(xy 93.35262 -221.619572) (xy 93.37548 -221.62389) (xy 93.400305 -221.629041) (xy 93.448083 -221.645999)
			(xy 93.492702 -221.670074) (xy 93.533107 -221.700696) (xy 93.568347 -221.737145) (xy 93.59759 -221.778561)
			(xy 93.620147 -221.823965) (xy 93.635485 -221.872289) (xy 93.643242 -221.92239) (xy 93.643704 -221.94774)
			(xy 93.643196 -221.973647) (xy 93.63509 -222.024824) (xy 93.619078 -222.074103) (xy 93.595555 -222.12027)
			(xy 93.565099 -222.162189) (xy 93.528461 -222.198827) (xy 93.486542 -222.229283) (xy 93.440375 -222.252806)
			(xy 93.391096 -222.268818) (xy 93.339919 -222.276924) (xy 93.288105 -222.276924) (xy 93.236928 -222.268818)
			(xy 93.187649 -222.252806) (xy 93.141482 -222.229283) (xy 93.099563 -222.198827) (xy 93.062925 -222.162189)
			(xy 93.032469 -222.12027) (xy 93.008946 -222.074103) (xy 92.992934 -222.024824) (xy 92.984828 -221.973647)
			(xy 92.98432 -221.94774) (xy 92.984923 -221.920023) (xy 92.99424 -221.865377) (xy 93.002862 -221.839028)
			(xy 93.010736 -221.81693) (xy 92.805758 -221.462092) (xy 92.782898 -221.457774) (xy 92.758103 -221.45255)
			(xy 92.710367 -221.435564) (xy 92.665792 -221.411474) (xy 92.625427 -221.380847) (xy 92.590224 -221.344405)
			(xy 92.561011 -221.303006) (xy 92.538476 -221.257625) (xy 92.52315 -221.20933) (xy 92.515394 -221.159258)
			(xy 92.514928 -221.133924) (xy 92.234004 -221.133924) (xy 92.233496 -221.159811) (xy 92.225397 -221.210949)
			(xy 92.209398 -221.260189) (xy 92.185892 -221.306321) (xy 92.15546 -221.348208) (xy 92.11885 -221.384818)
			(xy 92.076963 -221.41525) (xy 92.030831 -221.438756) (xy 91.981591 -221.454755) (xy 91.930453 -221.462854)
			(xy 91.878679 -221.462854) (xy 91.827541 -221.454755) (xy 91.778301 -221.438756) (xy 91.732169 -221.41525)
			(xy 91.690282 -221.384818) (xy 91.653672 -221.348208) (xy 91.62324 -221.306321) (xy 91.599734 -221.260189)
			(xy 91.583735 -221.210949) (xy 91.575636 -221.159811) (xy 91.575128 -221.133924) (xy 91.294204 -221.133924)
			(xy 91.29368 -221.161632) (xy 91.284481 -221.216279) (xy 91.275916 -221.242636) (xy 91.268042 -221.264734)
			(xy 91.47302 -221.619572) (xy 91.49588 -221.62389) (xy 91.520705 -221.629041) (xy 91.568483 -221.645999)
			(xy 91.613102 -221.670074) (xy 91.653507 -221.700696) (xy 91.688747 -221.737145) (xy 91.71799 -221.778561)
			(xy 91.740547 -221.823965) (xy 91.755885 -221.872289) (xy 91.763642 -221.92239) (xy 91.764104 -221.94774)
			(xy 91.763596 -221.973647) (xy 91.75549 -222.024824) (xy 91.739478 -222.074103) (xy 91.715955 -222.12027)
			(xy 91.685499 -222.162189) (xy 91.648861 -222.198827) (xy 91.606942 -222.229283) (xy 91.560775 -222.252806)
			(xy 91.511496 -222.268818) (xy 91.460319 -222.276924) (xy 91.408505 -222.276924) (xy 91.357328 -222.268818)
			(xy 91.308049 -222.252806) (xy 91.261882 -222.229283) (xy 91.219963 -222.198827) (xy 91.183325 -222.162189)
			(xy 91.152869 -222.12027) (xy 91.129346 -222.074103) (xy 91.113334 -222.024824) (xy 91.105228 -221.973647)
			(xy 91.10472 -221.94774) (xy 91.105323 -221.920023) (xy 91.11464 -221.865377) (xy 91.123262 -221.839028)
			(xy 91.131136 -221.81693) (xy 90.926158 -221.462092) (xy 90.903298 -221.457774) (xy 90.878503 -221.45255)
			(xy 90.830767 -221.435564) (xy 90.786192 -221.411474) (xy 90.745827 -221.380847) (xy 90.710624 -221.344405)
			(xy 90.681411 -221.303006) (xy 90.658876 -221.257625) (xy 90.64355 -221.20933) (xy 90.635794 -221.159258)
			(xy 90.635328 -221.133924) (xy 90.354404 -221.133924) (xy 90.353896 -221.159811) (xy 90.345797 -221.210949)
			(xy 90.329798 -221.260189) (xy 90.306292 -221.306321) (xy 90.27586 -221.348208) (xy 90.23925 -221.384818)
			(xy 90.197363 -221.41525) (xy 90.151231 -221.438756) (xy 90.101991 -221.454755) (xy 90.050853 -221.462854)
			(xy 89.999079 -221.462854) (xy 89.947941 -221.454755) (xy 89.898701 -221.438756) (xy 89.852569 -221.41525)
			(xy 89.810682 -221.384818) (xy 89.774072 -221.348208) (xy 89.74364 -221.306321) (xy 89.720134 -221.260189)
			(xy 89.704135 -221.210949) (xy 89.696036 -221.159811) (xy 89.695528 -221.133924) (xy 89.414604 -221.133924)
			(xy 89.41408 -221.161632) (xy 89.404881 -221.216279) (xy 89.396316 -221.242636) (xy 89.388442 -221.264734)
			(xy 89.59342 -221.619572) (xy 89.61628 -221.62389) (xy 89.641105 -221.629041) (xy 89.688883 -221.645999)
			(xy 89.733502 -221.670074) (xy 89.773907 -221.700696) (xy 89.809147 -221.737145) (xy 89.83839 -221.778561)
			(xy 89.860947 -221.823965) (xy 89.876285 -221.872289) (xy 89.884042 -221.92239) (xy 89.884504 -221.94774)
			(xy 89.883996 -221.973647) (xy 89.87589 -222.024824) (xy 89.859878 -222.074103) (xy 89.836355 -222.12027)
			(xy 89.805899 -222.162189) (xy 89.769261 -222.198827) (xy 89.727342 -222.229283) (xy 89.681175 -222.252806)
			(xy 89.631896 -222.268818) (xy 89.580719 -222.276924) (xy 89.528905 -222.276924) (xy 89.477728 -222.268818)
			(xy 89.428449 -222.252806) (xy 89.382282 -222.229283) (xy 89.340363 -222.198827) (xy 89.303725 -222.162189)
			(xy 89.273269 -222.12027) (xy 89.249746 -222.074103) (xy 89.233734 -222.024824) (xy 89.225628 -221.973647)
			(xy 89.22512 -221.94774) (xy 89.225723 -221.920023) (xy 89.23504 -221.865377) (xy 89.243662 -221.839028)
			(xy 89.251536 -221.81693) (xy 89.046558 -221.462092) (xy 89.023698 -221.457774) (xy 88.998903 -221.45255)
			(xy 88.951167 -221.435564) (xy 88.906592 -221.411474) (xy 88.866227 -221.380847) (xy 88.831024 -221.344405)
			(xy 88.801811 -221.303006) (xy 88.779276 -221.257625) (xy 88.76395 -221.20933) (xy 88.756194 -221.159258)
			(xy 88.755728 -221.133924) (xy 2.509012 -221.133924) (xy 2.509012 -224.389442) (xy 89.695528 -224.389442)
			(xy 89.695935 -224.364105) (xy 89.703697 -224.314028) (xy 89.719029 -224.265728) (xy 89.74157 -224.220343)
			(xy 89.770789 -224.17894) (xy 89.805999 -224.142496) (xy 89.84637 -224.111867) (xy 89.890952 -224.087776)
			(xy 89.938695 -224.070789) (xy 89.963498 -224.065592) (xy 89.986358 -224.061274) (xy 90.191082 -223.706182)
			(xy 90.183462 -223.684338) (xy 90.174817 -223.657995) (xy 90.165504 -223.603345) (xy 90.16492 -223.575626)
			(xy 90.165428 -223.549719) (xy 90.173534 -223.498542) (xy 90.189546 -223.449263) (xy 90.213069 -223.403096)
			(xy 90.243525 -223.361177) (xy 90.280163 -223.324539) (xy 90.322082 -223.294083) (xy 90.368249 -223.27056)
			(xy 90.417528 -223.254548) (xy 90.468705 -223.246442) (xy 90.520519 -223.246442) (xy 90.571696 -223.254548)
			(xy 90.620975 -223.27056) (xy 90.667142 -223.294083) (xy 90.709061 -223.324539) (xy 90.745699 -223.361177)
			(xy 90.776155 -223.403096) (xy 90.799678 -223.449263) (xy 90.81569 -223.498542) (xy 90.823796 -223.549719)
			(xy 90.824304 -223.575626) (xy 90.823803 -223.60097) (xy 90.816028 -223.651059) (xy 90.800679 -223.699368)
			(xy 90.77812 -223.74476) (xy 90.74888 -223.786165) (xy 90.713649 -223.822609) (xy 90.673257 -223.853232)
			(xy 90.628654 -223.877314) (xy 90.580892 -223.894288) (xy 90.55608 -223.899476) (xy 90.53322 -223.903794)
			(xy 90.328496 -224.258632) (xy 90.336116 -224.280476) (xy 90.344672 -224.306769) (xy 90.353865 -224.361289)
			(xy 90.354404 -224.388934) (xy 90.354404 -224.389442) (xy 90.635328 -224.389442) (xy 90.635836 -224.363555)
			(xy 90.643935 -224.312417) (xy 90.659934 -224.263177) (xy 90.68344 -224.217045) (xy 90.713872 -224.175158)
			(xy 90.750482 -224.138548) (xy 90.792369 -224.108116) (xy 90.838501 -224.08461) (xy 90.887741 -224.068611)
			(xy 90.938879 -224.060512) (xy 90.990653 -224.060512) (xy 91.041791 -224.068611) (xy 91.091031 -224.08461)
			(xy 91.137163 -224.108116) (xy 91.17905 -224.138548) (xy 91.21566 -224.175158) (xy 91.246092 -224.217045)
			(xy 91.269598 -224.263177) (xy 91.285597 -224.312417) (xy 91.293696 -224.363555) (xy 91.294204 -224.389442)
			(xy 91.575128 -224.389442) (xy 91.575535 -224.364105) (xy 91.583297 -224.314028) (xy 91.598629 -224.265728)
			(xy 91.62117 -224.220343) (xy 91.650389 -224.17894) (xy 91.685599 -224.142496) (xy 91.72597 -224.111867)
			(xy 91.770552 -224.087776) (xy 91.818295 -224.070789) (xy 91.843098 -224.065592) (xy 91.865958 -224.061274)
			(xy 92.070682 -223.706182) (xy 92.063062 -223.684338) (xy 92.054417 -223.657995) (xy 92.045104 -223.603345)
			(xy 92.04452 -223.575626) (xy 92.045028 -223.549719) (xy 92.053134 -223.498542) (xy 92.069146 -223.449263)
			(xy 92.092669 -223.403096) (xy 92.123125 -223.361177) (xy 92.159763 -223.324539) (xy 92.201682 -223.294083)
			(xy 92.247849 -223.27056) (xy 92.297128 -223.254548) (xy 92.348305 -223.246442) (xy 92.400119 -223.246442)
			(xy 92.451296 -223.254548) (xy 92.500575 -223.27056) (xy 92.546742 -223.294083) (xy 92.588661 -223.324539)
			(xy 92.625299 -223.361177) (xy 92.655755 -223.403096) (xy 92.679278 -223.449263) (xy 92.69529 -223.498542)
			(xy 92.703396 -223.549719) (xy 92.703904 -223.575626) (xy 92.703403 -223.60097) (xy 92.695628 -223.651059)
			(xy 92.680279 -223.699368) (xy 92.65772 -223.74476) (xy 92.62848 -223.786165) (xy 92.593249 -223.822609)
			(xy 92.552857 -223.853232) (xy 92.508254 -223.877314) (xy 92.460492 -223.894288) (xy 92.43568 -223.899476)
			(xy 92.41282 -223.903794) (xy 92.208096 -224.258632) (xy 92.215716 -224.280476) (xy 92.224272 -224.306769)
			(xy 92.233465 -224.361289) (xy 92.234004 -224.388934) (xy 92.234004 -224.389442) (xy 92.514928 -224.389442)
			(xy 92.515436 -224.363555) (xy 92.523535 -224.312417) (xy 92.539534 -224.263177) (xy 92.56304 -224.217045)
			(xy 92.593472 -224.175158) (xy 92.630082 -224.138548) (xy 92.671969 -224.108116) (xy 92.718101 -224.08461)
			(xy 92.767341 -224.068611) (xy 92.818479 -224.060512) (xy 92.870253 -224.060512) (xy 92.921391 -224.068611)
			(xy 92.970631 -224.08461) (xy 93.016763 -224.108116) (xy 93.05865 -224.138548) (xy 93.09526 -224.175158)
			(xy 93.125692 -224.217045) (xy 93.149198 -224.263177) (xy 93.165197 -224.312417) (xy 93.173296 -224.363555)
			(xy 93.173804 -224.389442) (xy 93.454728 -224.389442) (xy 93.455135 -224.364105) (xy 93.462897 -224.314028)
			(xy 93.478229 -224.265728) (xy 93.50077 -224.220343) (xy 93.529989 -224.17894) (xy 93.565199 -224.142496)
			(xy 93.60557 -224.111867) (xy 93.650152 -224.087776) (xy 93.697895 -224.070789) (xy 93.722698 -224.065592)
			(xy 93.745558 -224.061274) (xy 93.950282 -223.706436) (xy 93.942662 -223.684338) (xy 93.934031 -223.657991)
			(xy 93.92471 -223.603344) (xy 93.92412 -223.575626) (xy 93.924628 -223.549719) (xy 93.932734 -223.498542)
			(xy 93.948746 -223.449263) (xy 93.972269 -223.403096) (xy 94.002725 -223.361177) (xy 94.039363 -223.324539)
			(xy 94.081282 -223.294083) (xy 94.127449 -223.27056) (xy 94.176728 -223.254548) (xy 94.227905 -223.246442)
			(xy 94.279719 -223.246442) (xy 94.330896 -223.254548) (xy 94.380175 -223.27056) (xy 94.426342 -223.294083)
			(xy 94.468261 -223.324539) (xy 94.504899 -223.361177) (xy 94.535355 -223.403096) (xy 94.558878 -223.449263)
			(xy 94.57489 -223.498542) (xy 94.582996 -223.549719) (xy 94.583504 -223.575626) (xy 94.583087 -223.600992)
			(xy 94.575334 -223.651127) (xy 94.559985 -223.69948) (xy 94.537403 -223.744908) (xy 94.508122 -223.786336)
			(xy 94.472834 -223.822783) (xy 94.432375 -223.853388) (xy 94.387701 -223.877427) (xy 94.339869 -223.894332)
			(xy 94.315026 -223.899476) (xy 94.292166 -223.903794) (xy 94.087442 -224.258632) (xy 94.095316 -224.280476)
			(xy 94.10389 -224.306896) (xy 94.11309 -224.36167) (xy 94.113604 -224.389442) (xy 94.394528 -224.389442)
			(xy 94.395036 -224.363555) (xy 94.403135 -224.312417) (xy 94.419134 -224.263177) (xy 94.44264 -224.217045)
			(xy 94.473072 -224.175158) (xy 94.509682 -224.138548) (xy 94.551569 -224.108116) (xy 94.597701 -224.08461)
			(xy 94.646941 -224.068611) (xy 94.698079 -224.060512) (xy 94.749853 -224.060512) (xy 94.800991 -224.068611)
			(xy 94.850231 -224.08461) (xy 94.896363 -224.108116) (xy 94.93825 -224.138548) (xy 94.97486 -224.175158)
			(xy 95.005292 -224.217045) (xy 95.028798 -224.263177) (xy 95.044797 -224.312417) (xy 95.052896 -224.363555)
			(xy 95.053404 -224.389442) (xy 95.334328 -224.389442) (xy 95.334735 -224.364105) (xy 95.342497 -224.314028)
			(xy 95.357829 -224.265728) (xy 95.38037 -224.220343) (xy 95.409589 -224.17894) (xy 95.444799 -224.142496)
			(xy 95.48517 -224.111867) (xy 95.529752 -224.087776) (xy 95.577495 -224.070789) (xy 95.602298 -224.065592)
			(xy 95.625158 -224.061274) (xy 95.829882 -223.706436) (xy 95.822262 -223.684338) (xy 95.813631 -223.657991)
			(xy 95.80431 -223.603344) (xy 95.80372 -223.575626) (xy 95.804228 -223.549719) (xy 95.812334 -223.498542)
			(xy 95.828346 -223.449263) (xy 95.851869 -223.403096) (xy 95.882325 -223.361177) (xy 95.918963 -223.324539)
			(xy 95.960882 -223.294083) (xy 96.007049 -223.27056) (xy 96.056328 -223.254548) (xy 96.107505 -223.246442)
			(xy 96.159319 -223.246442) (xy 96.210496 -223.254548) (xy 96.259775 -223.27056) (xy 96.305942 -223.294083)
			(xy 96.347861 -223.324539) (xy 96.384499 -223.361177) (xy 96.414955 -223.403096) (xy 96.438478 -223.449263)
			(xy 96.45449 -223.498542) (xy 96.462596 -223.549719) (xy 96.463104 -223.575626) (xy 96.462687 -223.600992)
			(xy 96.454934 -223.651127) (xy 96.439585 -223.69948) (xy 96.417003 -223.744908) (xy 96.387722 -223.786336)
			(xy 96.352434 -223.822783) (xy 96.311975 -223.853388) (xy 96.267301 -223.877427) (xy 96.219469 -223.894332)
			(xy 96.194626 -223.899476) (xy 96.171766 -223.903794) (xy 95.967042 -224.258632) (xy 95.974916 -224.280476)
			(xy 95.98349 -224.306896) (xy 95.99269 -224.36167) (xy 95.993204 -224.389442) (xy 96.274128 -224.389442)
			(xy 96.274636 -224.363555) (xy 96.282735 -224.312417) (xy 96.298734 -224.263177) (xy 96.32224 -224.217045)
			(xy 96.352672 -224.175158) (xy 96.389282 -224.138548) (xy 96.431169 -224.108116) (xy 96.477301 -224.08461)
			(xy 96.526541 -224.068611) (xy 96.577679 -224.060512) (xy 96.629453 -224.060512) (xy 96.680591 -224.068611)
			(xy 96.729831 -224.08461) (xy 96.775963 -224.108116) (xy 96.81785 -224.138548) (xy 96.85446 -224.175158)
			(xy 96.884892 -224.217045) (xy 96.908398 -224.263177) (xy 96.924397 -224.312417) (xy 96.932496 -224.363555)
			(xy 96.933004 -224.389442) (xy 97.213928 -224.389442) (xy 97.214335 -224.364105) (xy 97.222097 -224.314028)
			(xy 97.237429 -224.265728) (xy 97.25997 -224.220343) (xy 97.289189 -224.17894) (xy 97.324399 -224.142496)
			(xy 97.36477 -224.111867) (xy 97.409352 -224.087776) (xy 97.457095 -224.070789) (xy 97.481898 -224.065592)
			(xy 97.504758 -224.061274) (xy 97.709482 -223.706436) (xy 97.701862 -223.684338) (xy 97.693231 -223.657991)
			(xy 97.68391 -223.603344) (xy 97.68332 -223.575626) (xy 97.683828 -223.549719) (xy 97.691934 -223.498542)
			(xy 97.707946 -223.449263) (xy 97.731469 -223.403096) (xy 97.761925 -223.361177) (xy 97.798563 -223.324539)
			(xy 97.840482 -223.294083) (xy 97.886649 -223.27056) (xy 97.935928 -223.254548) (xy 97.987105 -223.246442)
			(xy 98.038919 -223.246442) (xy 98.090096 -223.254548) (xy 98.139375 -223.27056) (xy 98.185542 -223.294083)
			(xy 98.227461 -223.324539) (xy 98.264099 -223.361177) (xy 98.294555 -223.403096) (xy 98.318078 -223.449263)
			(xy 98.33409 -223.498542) (xy 98.342196 -223.549719) (xy 98.342704 -223.575626) (xy 98.342287 -223.600992)
			(xy 98.334534 -223.651127) (xy 98.319185 -223.69948) (xy 98.296603 -223.744908) (xy 98.267322 -223.786336)
			(xy 98.232034 -223.822783) (xy 98.191575 -223.853388) (xy 98.146901 -223.877427) (xy 98.099069 -223.894332)
			(xy 98.074226 -223.899476) (xy 98.051366 -223.903794) (xy 97.846642 -224.258632) (xy 97.854516 -224.280476)
			(xy 97.86309 -224.306896) (xy 97.87229 -224.36167) (xy 97.872804 -224.389442) (xy 98.153728 -224.389442)
			(xy 98.154236 -224.363555) (xy 98.162335 -224.312417) (xy 98.178334 -224.263177) (xy 98.20184 -224.217045)
			(xy 98.232272 -224.175158) (xy 98.268882 -224.138548) (xy 98.310769 -224.108116) (xy 98.356901 -224.08461)
			(xy 98.406141 -224.068611) (xy 98.457279 -224.060512) (xy 98.509053 -224.060512) (xy 98.560191 -224.068611)
			(xy 98.609431 -224.08461) (xy 98.655563 -224.108116) (xy 98.69745 -224.138548) (xy 98.73406 -224.175158)
			(xy 98.764492 -224.217045) (xy 98.787998 -224.263177) (xy 98.803997 -224.312417) (xy 98.812096 -224.363555)
			(xy 98.812604 -224.389442) (xy 99.093528 -224.389442) (xy 99.093935 -224.364105) (xy 99.101697 -224.314028)
			(xy 99.117029 -224.265728) (xy 99.13957 -224.220343) (xy 99.168789 -224.17894) (xy 99.203999 -224.142496)
			(xy 99.24437 -224.111867) (xy 99.288952 -224.087776) (xy 99.336695 -224.070789) (xy 99.361498 -224.065592)
			(xy 99.384358 -224.061274) (xy 99.589082 -223.706436) (xy 99.581462 -223.684338) (xy 99.572831 -223.657991)
			(xy 99.56351 -223.603344) (xy 99.56292 -223.575626) (xy 99.563428 -223.549719) (xy 99.571534 -223.498542)
			(xy 99.587546 -223.449263) (xy 99.611069 -223.403096) (xy 99.641525 -223.361177) (xy 99.678163 -223.324539)
			(xy 99.720082 -223.294083) (xy 99.766249 -223.27056) (xy 99.815528 -223.254548) (xy 99.866705 -223.246442)
			(xy 99.918519 -223.246442) (xy 99.969696 -223.254548) (xy 100.018975 -223.27056) (xy 100.065142 -223.294083)
			(xy 100.107061 -223.324539) (xy 100.143699 -223.361177) (xy 100.174155 -223.403096) (xy 100.197678 -223.449263)
			(xy 100.21369 -223.498542) (xy 100.221796 -223.549719) (xy 100.222304 -223.575626) (xy 100.221887 -223.600992)
			(xy 100.214134 -223.651127) (xy 100.198785 -223.69948) (xy 100.176203 -223.744908) (xy 100.146922 -223.786336)
			(xy 100.111634 -223.822783) (xy 100.071175 -223.853388) (xy 100.026501 -223.877427) (xy 99.978669 -223.894332)
			(xy 99.953826 -223.899476) (xy 99.930966 -223.903794) (xy 99.726242 -224.258632) (xy 99.734116 -224.280476)
			(xy 99.74269 -224.306896) (xy 99.75189 -224.36167) (xy 99.752404 -224.389442) (xy 100.033328 -224.389442)
			(xy 100.033836 -224.363555) (xy 100.041935 -224.312417) (xy 100.057934 -224.263177) (xy 100.08144 -224.217045)
			(xy 100.111872 -224.175158) (xy 100.148482 -224.138548) (xy 100.190369 -224.108116) (xy 100.236501 -224.08461)
			(xy 100.285741 -224.068611) (xy 100.336879 -224.060512) (xy 100.388653 -224.060512) (xy 100.439791 -224.068611)
			(xy 100.489031 -224.08461) (xy 100.535163 -224.108116) (xy 100.57705 -224.138548) (xy 100.61366 -224.175158)
			(xy 100.644092 -224.217045) (xy 100.667598 -224.263177) (xy 100.683597 -224.312417) (xy 100.691696 -224.363555)
			(xy 100.692204 -224.389442) (xy 100.973128 -224.389442) (xy 100.973535 -224.364105) (xy 100.981297 -224.314028)
			(xy 100.996629 -224.265728) (xy 101.01917 -224.220343) (xy 101.048389 -224.17894) (xy 101.083599 -224.142496)
			(xy 101.12397 -224.111867) (xy 101.168552 -224.087776) (xy 101.216295 -224.070789) (xy 101.241098 -224.065592)
			(xy 101.263958 -224.061274) (xy 101.468682 -223.706436) (xy 101.461062 -223.684338) (xy 101.452431 -223.657991)
			(xy 101.44311 -223.603344) (xy 101.44252 -223.575626) (xy 101.443028 -223.549719) (xy 101.451134 -223.498542)
			(xy 101.467146 -223.449263) (xy 101.490669 -223.403096) (xy 101.521125 -223.361177) (xy 101.557763 -223.324539)
			(xy 101.599682 -223.294083) (xy 101.645849 -223.27056) (xy 101.695128 -223.254548) (xy 101.746305 -223.246442)
			(xy 101.798119 -223.246442) (xy 101.849296 -223.254548) (xy 101.898575 -223.27056) (xy 101.944742 -223.294083)
			(xy 101.986661 -223.324539) (xy 102.023299 -223.361177) (xy 102.053755 -223.403096) (xy 102.077278 -223.449263)
			(xy 102.09329 -223.498542) (xy 102.101396 -223.549719) (xy 102.101904 -223.575626) (xy 102.101487 -223.600992)
			(xy 102.093734 -223.651127) (xy 102.078385 -223.69948) (xy 102.055803 -223.744908) (xy 102.026522 -223.786336)
			(xy 101.991234 -223.822783) (xy 101.950775 -223.853388) (xy 101.906101 -223.877427) (xy 101.858269 -223.894332)
			(xy 101.833426 -223.899476) (xy 101.810566 -223.903794) (xy 101.605842 -224.258632) (xy 101.613716 -224.280476)
			(xy 101.62229 -224.306896) (xy 101.63149 -224.36167) (xy 101.632004 -224.389442) (xy 101.912928 -224.389442)
			(xy 101.913436 -224.363555) (xy 101.921535 -224.312417) (xy 101.937534 -224.263177) (xy 101.96104 -224.217045)
			(xy 101.991472 -224.175158) (xy 102.028082 -224.138548) (xy 102.069969 -224.108116) (xy 102.116101 -224.08461)
			(xy 102.165341 -224.068611) (xy 102.216479 -224.060512) (xy 102.268253 -224.060512) (xy 102.319391 -224.068611)
			(xy 102.368631 -224.08461) (xy 102.414763 -224.108116) (xy 102.45665 -224.138548) (xy 102.49326 -224.175158)
			(xy 102.523692 -224.217045) (xy 102.547198 -224.263177) (xy 102.563197 -224.312417) (xy 102.571296 -224.363555)
			(xy 102.571804 -224.389442) (xy 102.852728 -224.389442) (xy 102.853135 -224.364105) (xy 102.860897 -224.314028)
			(xy 102.876229 -224.265728) (xy 102.89877 -224.220343) (xy 102.927989 -224.17894) (xy 102.963199 -224.142496)
			(xy 103.00357 -224.111867) (xy 103.048152 -224.087776) (xy 103.095895 -224.070789) (xy 103.120698 -224.065592)
			(xy 103.143558 -224.061274) (xy 103.348282 -223.706436) (xy 103.340662 -223.684338) (xy 103.332031 -223.657991)
			(xy 103.32271 -223.603344) (xy 103.32212 -223.575626) (xy 103.322628 -223.549719) (xy 103.330734 -223.498542)
			(xy 103.346746 -223.449263) (xy 103.370269 -223.403096) (xy 103.400725 -223.361177) (xy 103.437363 -223.324539)
			(xy 103.479282 -223.294083) (xy 103.525449 -223.27056) (xy 103.574728 -223.254548) (xy 103.625905 -223.246442)
			(xy 103.677719 -223.246442) (xy 103.728896 -223.254548) (xy 103.778175 -223.27056) (xy 103.824342 -223.294083)
			(xy 103.866261 -223.324539) (xy 103.902899 -223.361177) (xy 103.933355 -223.403096) (xy 103.956878 -223.449263)
			(xy 103.97289 -223.498542) (xy 103.980996 -223.549719) (xy 103.981504 -223.575626) (xy 103.981087 -223.600992)
			(xy 103.973334 -223.651127) (xy 103.957985 -223.69948) (xy 103.935403 -223.744908) (xy 103.906122 -223.786336)
			(xy 103.870834 -223.822783) (xy 103.830375 -223.853388) (xy 103.785701 -223.877427) (xy 103.737869 -223.894332)
			(xy 103.713026 -223.899476) (xy 103.690166 -223.903794) (xy 103.485442 -224.258632) (xy 103.493316 -224.280476)
			(xy 103.50189 -224.306896) (xy 103.51109 -224.36167) (xy 103.511604 -224.389442) (xy 103.792528 -224.389442)
			(xy 103.793036 -224.363555) (xy 103.801135 -224.312417) (xy 103.817134 -224.263177) (xy 103.84064 -224.217045)
			(xy 103.871072 -224.175158) (xy 103.907682 -224.138548) (xy 103.949569 -224.108116) (xy 103.995701 -224.08461)
			(xy 104.044941 -224.068611) (xy 104.096079 -224.060512) (xy 104.147853 -224.060512) (xy 104.198991 -224.068611)
			(xy 104.248231 -224.08461) (xy 104.294363 -224.108116) (xy 104.33625 -224.138548) (xy 104.37286 -224.175158)
			(xy 104.403292 -224.217045) (xy 104.426798 -224.263177) (xy 104.442797 -224.312417) (xy 104.450896 -224.363555)
			(xy 104.451404 -224.389442) (xy 104.732328 -224.389442) (xy 104.732735 -224.364105) (xy 104.740497 -224.314028)
			(xy 104.755829 -224.265728) (xy 104.77837 -224.220343) (xy 104.807589 -224.17894) (xy 104.842799 -224.142496)
			(xy 104.88317 -224.111867) (xy 104.927752 -224.087776) (xy 104.975495 -224.070789) (xy 105.000298 -224.065592)
			(xy 105.023158 -224.061274) (xy 105.227882 -223.706436) (xy 105.220262 -223.684338) (xy 105.211631 -223.657991)
			(xy 105.20231 -223.603344) (xy 105.20172 -223.575626) (xy 105.202228 -223.549719) (xy 105.210334 -223.498542)
			(xy 105.226346 -223.449263) (xy 105.249869 -223.403096) (xy 105.280325 -223.361177) (xy 105.316963 -223.324539)
			(xy 105.358882 -223.294083) (xy 105.405049 -223.27056) (xy 105.454328 -223.254548) (xy 105.505505 -223.246442)
			(xy 105.557319 -223.246442) (xy 105.608496 -223.254548) (xy 105.657775 -223.27056) (xy 105.703942 -223.294083)
			(xy 105.745861 -223.324539) (xy 105.782499 -223.361177) (xy 105.812955 -223.403096) (xy 105.836478 -223.449263)
			(xy 105.85249 -223.498542) (xy 105.860596 -223.549719) (xy 105.861104 -223.575626) (xy 105.860687 -223.600992)
			(xy 105.852934 -223.651127) (xy 105.837585 -223.69948) (xy 105.815003 -223.744908) (xy 105.785722 -223.786336)
			(xy 105.750434 -223.822783) (xy 105.709975 -223.853388) (xy 105.665301 -223.877427) (xy 105.617469 -223.894332)
			(xy 105.592626 -223.899476) (xy 105.569766 -223.903794) (xy 105.365042 -224.258632) (xy 105.372916 -224.280476)
			(xy 105.38149 -224.306896) (xy 105.39069 -224.36167) (xy 105.391204 -224.389442) (xy 105.672128 -224.389442)
			(xy 105.672636 -224.363555) (xy 105.680735 -224.312417) (xy 105.696734 -224.263177) (xy 105.72024 -224.217045)
			(xy 105.750672 -224.175158) (xy 105.787282 -224.138548) (xy 105.829169 -224.108116) (xy 105.875301 -224.08461)
			(xy 105.924541 -224.068611) (xy 105.975679 -224.060512) (xy 106.027453 -224.060512) (xy 106.078591 -224.068611)
			(xy 106.127831 -224.08461) (xy 106.173963 -224.108116) (xy 106.21585 -224.138548) (xy 106.25246 -224.175158)
			(xy 106.282892 -224.217045) (xy 106.306398 -224.263177) (xy 106.322397 -224.312417) (xy 106.330496 -224.363555)
			(xy 106.331004 -224.389442) (xy 106.611928 -224.389442) (xy 106.612335 -224.364105) (xy 106.620097 -224.314028)
			(xy 106.635429 -224.265728) (xy 106.65797 -224.220343) (xy 106.687189 -224.17894) (xy 106.722399 -224.142496)
			(xy 106.76277 -224.111867) (xy 106.807352 -224.087776) (xy 106.855095 -224.070789) (xy 106.879898 -224.065592)
			(xy 106.902758 -224.061274) (xy 107.107482 -223.706436) (xy 107.099862 -223.684338) (xy 107.091231 -223.657991)
			(xy 107.08191 -223.603344) (xy 107.08132 -223.575626) (xy 107.081828 -223.549719) (xy 107.089934 -223.498542)
			(xy 107.105946 -223.449263) (xy 107.129469 -223.403096) (xy 107.159925 -223.361177) (xy 107.196563 -223.324539)
			(xy 107.238482 -223.294083) (xy 107.284649 -223.27056) (xy 107.333928 -223.254548) (xy 107.385105 -223.246442)
			(xy 107.436919 -223.246442) (xy 107.488096 -223.254548) (xy 107.537375 -223.27056) (xy 107.583542 -223.294083)
			(xy 107.625461 -223.324539) (xy 107.662099 -223.361177) (xy 107.692555 -223.403096) (xy 107.716078 -223.449263)
			(xy 107.73209 -223.498542) (xy 107.740196 -223.549719) (xy 107.740704 -223.575626) (xy 107.740287 -223.600992)
			(xy 107.732534 -223.651127) (xy 107.717185 -223.69948) (xy 107.694603 -223.744908) (xy 107.665322 -223.786336)
			(xy 107.630034 -223.822783) (xy 107.589575 -223.853388) (xy 107.544901 -223.877427) (xy 107.497069 -223.894332)
			(xy 107.472226 -223.899476) (xy 107.449366 -223.903794) (xy 107.244642 -224.258632) (xy 107.252516 -224.280476)
			(xy 107.26109 -224.306896) (xy 107.27029 -224.36167) (xy 107.270804 -224.389442) (xy 107.551728 -224.389442)
			(xy 107.552236 -224.363555) (xy 107.560335 -224.312417) (xy 107.576334 -224.263177) (xy 107.59984 -224.217045)
			(xy 107.630272 -224.175158) (xy 107.666882 -224.138548) (xy 107.708769 -224.108116) (xy 107.754901 -224.08461)
			(xy 107.804141 -224.068611) (xy 107.855279 -224.060512) (xy 107.907053 -224.060512) (xy 107.958191 -224.068611)
			(xy 108.007431 -224.08461) (xy 108.053563 -224.108116) (xy 108.09545 -224.138548) (xy 108.13206 -224.175158)
			(xy 108.162492 -224.217045) (xy 108.185998 -224.263177) (xy 108.201997 -224.312417) (xy 108.210096 -224.363555)
			(xy 108.210604 -224.389442) (xy 108.491528 -224.389442) (xy 108.491935 -224.364105) (xy 108.499697 -224.314028)
			(xy 108.515029 -224.265728) (xy 108.53757 -224.220343) (xy 108.566789 -224.17894) (xy 108.601999 -224.142496)
			(xy 108.64237 -224.111867) (xy 108.686952 -224.087776) (xy 108.734695 -224.070789) (xy 108.759498 -224.065592)
			(xy 108.782358 -224.061274) (xy 108.987082 -223.706436) (xy 108.979462 -223.684338) (xy 108.970831 -223.657991)
			(xy 108.96151 -223.603344) (xy 108.96092 -223.575626) (xy 108.961428 -223.549719) (xy 108.969534 -223.498542)
			(xy 108.985546 -223.449263) (xy 109.009069 -223.403096) (xy 109.039525 -223.361177) (xy 109.076163 -223.324539)
			(xy 109.118082 -223.294083) (xy 109.164249 -223.27056) (xy 109.213528 -223.254548) (xy 109.264705 -223.246442)
			(xy 109.316519 -223.246442) (xy 109.367696 -223.254548) (xy 109.416975 -223.27056) (xy 109.463142 -223.294083)
			(xy 109.505061 -223.324539) (xy 109.541699 -223.361177) (xy 109.572155 -223.403096) (xy 109.595678 -223.449263)
			(xy 109.61169 -223.498542) (xy 109.619796 -223.549719) (xy 109.620304 -223.575626) (xy 109.619887 -223.600992)
			(xy 109.612134 -223.651127) (xy 109.596785 -223.69948) (xy 109.574203 -223.744908) (xy 109.544922 -223.786336)
			(xy 109.509634 -223.822783) (xy 109.469175 -223.853388) (xy 109.424501 -223.877427) (xy 109.376669 -223.894332)
			(xy 109.351826 -223.899476) (xy 109.328966 -223.903794) (xy 109.124242 -224.258632) (xy 109.132116 -224.280476)
			(xy 109.14069 -224.306896) (xy 109.14989 -224.36167) (xy 109.150404 -224.389442) (xy 109.431328 -224.389442)
			(xy 109.431836 -224.363555) (xy 109.439935 -224.312417) (xy 109.455934 -224.263177) (xy 109.47944 -224.217045)
			(xy 109.509872 -224.175158) (xy 109.546482 -224.138548) (xy 109.588369 -224.108116) (xy 109.634501 -224.08461)
			(xy 109.683741 -224.068611) (xy 109.734879 -224.060512) (xy 109.786653 -224.060512) (xy 109.837791 -224.068611)
			(xy 109.887031 -224.08461) (xy 109.933163 -224.108116) (xy 109.97505 -224.138548) (xy 110.01166 -224.175158)
			(xy 110.042092 -224.217045) (xy 110.065598 -224.263177) (xy 110.081597 -224.312417) (xy 110.089696 -224.363555)
			(xy 110.090204 -224.389442) (xy 110.371128 -224.389442) (xy 110.371535 -224.364105) (xy 110.379297 -224.314028)
			(xy 110.394629 -224.265728) (xy 110.41717 -224.220343) (xy 110.446389 -224.17894) (xy 110.481599 -224.142496)
			(xy 110.52197 -224.111867) (xy 110.566552 -224.087776) (xy 110.614295 -224.070789) (xy 110.639098 -224.065592)
			(xy 110.661958 -224.061274) (xy 110.866682 -223.706436) (xy 110.859062 -223.684338) (xy 110.850431 -223.657991)
			(xy 110.84111 -223.603344) (xy 110.84052 -223.575626) (xy 110.841028 -223.549719) (xy 110.849134 -223.498542)
			(xy 110.865146 -223.449263) (xy 110.888669 -223.403096) (xy 110.919125 -223.361177) (xy 110.955763 -223.324539)
			(xy 110.997682 -223.294083) (xy 111.043849 -223.27056) (xy 111.093128 -223.254548) (xy 111.144305 -223.246442)
			(xy 111.196119 -223.246442) (xy 111.247296 -223.254548) (xy 111.296575 -223.27056) (xy 111.342742 -223.294083)
			(xy 111.384661 -223.324539) (xy 111.421299 -223.361177) (xy 111.451755 -223.403096) (xy 111.475278 -223.449263)
			(xy 111.49129 -223.498542) (xy 111.499396 -223.549719) (xy 111.499904 -223.575626) (xy 111.499487 -223.600992)
			(xy 111.491734 -223.651127) (xy 111.476385 -223.69948) (xy 111.453803 -223.744908) (xy 111.424522 -223.786336)
			(xy 111.389234 -223.822783) (xy 111.348775 -223.853388) (xy 111.304101 -223.877427) (xy 111.256269 -223.894332)
			(xy 111.231426 -223.899476) (xy 111.208566 -223.903794) (xy 111.003842 -224.258632) (xy 111.011716 -224.280476)
			(xy 111.02029 -224.306896) (xy 111.02949 -224.36167) (xy 111.030004 -224.389442) (xy 111.310928 -224.389442)
			(xy 111.311436 -224.363555) (xy 111.319535 -224.312417) (xy 111.335534 -224.263177) (xy 111.35904 -224.217045)
			(xy 111.389472 -224.175158) (xy 111.426082 -224.138548) (xy 111.467969 -224.108116) (xy 111.514101 -224.08461)
			(xy 111.563341 -224.068611) (xy 111.614479 -224.060512) (xy 111.666253 -224.060512) (xy 111.717391 -224.068611)
			(xy 111.766631 -224.08461) (xy 111.812763 -224.108116) (xy 111.85465 -224.138548) (xy 111.89126 -224.175158)
			(xy 111.921692 -224.217045) (xy 111.945198 -224.263177) (xy 111.961197 -224.312417) (xy 111.969296 -224.363555)
			(xy 111.969804 -224.389442) (xy 112.250728 -224.389442) (xy 112.251135 -224.364105) (xy 112.258897 -224.314028)
			(xy 112.274229 -224.265728) (xy 112.29677 -224.220343) (xy 112.325989 -224.17894) (xy 112.361199 -224.142496)
			(xy 112.40157 -224.111867) (xy 112.446152 -224.087776) (xy 112.493895 -224.070789) (xy 112.518698 -224.065592)
			(xy 112.541558 -224.061274) (xy 112.746282 -223.706436) (xy 112.738662 -223.684338) (xy 112.730031 -223.657991)
			(xy 112.72071 -223.603344) (xy 112.72012 -223.575626) (xy 112.720628 -223.549719) (xy 112.728734 -223.498542)
			(xy 112.744746 -223.449263) (xy 112.768269 -223.403096) (xy 112.798725 -223.361177) (xy 112.835363 -223.324539)
			(xy 112.877282 -223.294083) (xy 112.923449 -223.27056) (xy 112.972728 -223.254548) (xy 113.023905 -223.246442)
			(xy 113.075719 -223.246442) (xy 113.126896 -223.254548) (xy 113.176175 -223.27056) (xy 113.222342 -223.294083)
			(xy 113.264261 -223.324539) (xy 113.300899 -223.361177) (xy 113.331355 -223.403096) (xy 113.354878 -223.449263)
			(xy 113.37089 -223.498542) (xy 113.378996 -223.549719) (xy 113.379504 -223.575626) (xy 113.379087 -223.600992)
			(xy 113.371334 -223.651127) (xy 113.355985 -223.69948) (xy 113.333403 -223.744908) (xy 113.304122 -223.786336)
			(xy 113.268834 -223.822783) (xy 113.228375 -223.853388) (xy 113.183701 -223.877427) (xy 113.135869 -223.894332)
			(xy 113.111026 -223.899476) (xy 113.088166 -223.903794) (xy 112.883442 -224.258632) (xy 112.891316 -224.280476)
			(xy 112.89989 -224.306896) (xy 112.90909 -224.36167) (xy 112.909604 -224.389442) (xy 113.190528 -224.389442)
			(xy 113.191036 -224.363555) (xy 113.199135 -224.312417) (xy 113.215134 -224.263177) (xy 113.23864 -224.217045)
			(xy 113.269072 -224.175158) (xy 113.305682 -224.138548) (xy 113.347569 -224.108116) (xy 113.393701 -224.08461)
			(xy 113.442941 -224.068611) (xy 113.494079 -224.060512) (xy 113.545853 -224.060512) (xy 113.596991 -224.068611)
			(xy 113.646231 -224.08461) (xy 113.692363 -224.108116) (xy 113.73425 -224.138548) (xy 113.77086 -224.175158)
			(xy 113.801292 -224.217045) (xy 113.824798 -224.263177) (xy 113.840797 -224.312417) (xy 113.848896 -224.363555)
			(xy 113.849404 -224.389442) (xy 114.130328 -224.389442) (xy 114.130735 -224.364105) (xy 114.138497 -224.314028)
			(xy 114.153829 -224.265728) (xy 114.17637 -224.220343) (xy 114.205589 -224.17894) (xy 114.240799 -224.142496)
			(xy 114.28117 -224.111867) (xy 114.325752 -224.087776) (xy 114.373495 -224.070789) (xy 114.398298 -224.065592)
			(xy 114.421158 -224.061274) (xy 114.626136 -223.706182) (xy 114.618516 -223.684084) (xy 114.609997 -223.657912)
			(xy 114.600803 -223.603651) (xy 114.600228 -223.576134) (xy 114.600228 -223.575626) (xy 114.600736 -223.549739)
			(xy 114.608835 -223.498601) (xy 114.624834 -223.449361) (xy 114.64834 -223.403229) (xy 114.678772 -223.361342)
			(xy 114.715382 -223.324732) (xy 114.757269 -223.2943) (xy 114.803401 -223.270794) (xy 114.852641 -223.254795)
			(xy 114.903779 -223.246696) (xy 114.955553 -223.246696) (xy 115.006691 -223.254795) (xy 115.055931 -223.270794)
			(xy 115.102063 -223.2943) (xy 115.14395 -223.324732) (xy 115.18056 -223.361342) (xy 115.210992 -223.403229)
			(xy 115.234498 -223.449361) (xy 115.250497 -223.498601) (xy 115.258596 -223.549739) (xy 115.259104 -223.575626)
			(xy 115.258687 -223.600992) (xy 115.250934 -223.651127) (xy 115.235585 -223.69948) (xy 115.213003 -223.744908)
			(xy 115.183722 -223.786336) (xy 115.148434 -223.822783) (xy 115.107975 -223.853388) (xy 115.063301 -223.877427)
			(xy 115.015469 -223.894332) (xy 114.990626 -223.899476) (xy 114.967766 -223.903794) (xy 114.763042 -224.258632)
			(xy 114.770916 -224.280476) (xy 114.77949 -224.306896) (xy 114.78869 -224.36167) (xy 114.789204 -224.389442)
			(xy 115.070128 -224.389442) (xy 115.070636 -224.363555) (xy 115.078735 -224.312417) (xy 115.094734 -224.263177)
			(xy 115.11824 -224.217045) (xy 115.148672 -224.175158) (xy 115.185282 -224.138548) (xy 115.227169 -224.108116)
			(xy 115.273301 -224.08461) (xy 115.322541 -224.068611) (xy 115.373679 -224.060512) (xy 115.425453 -224.060512)
			(xy 115.476591 -224.068611) (xy 115.525831 -224.08461) (xy 115.571963 -224.108116) (xy 115.61385 -224.138548)
			(xy 115.65046 -224.175158) (xy 115.680892 -224.217045) (xy 115.704398 -224.263177) (xy 115.720397 -224.312417)
			(xy 115.728496 -224.363555) (xy 115.729004 -224.389442) (xy 116.009928 -224.389442) (xy 116.010335 -224.364105)
			(xy 116.018097 -224.314028) (xy 116.033429 -224.265728) (xy 116.05597 -224.220343) (xy 116.085189 -224.17894)
			(xy 116.120399 -224.142496) (xy 116.16077 -224.111867) (xy 116.205352 -224.087776) (xy 116.253095 -224.070789)
			(xy 116.277898 -224.065592) (xy 116.300758 -224.061274) (xy 116.505482 -223.706436) (xy 116.497862 -223.684338)
			(xy 116.489231 -223.657991) (xy 116.47991 -223.603344) (xy 116.47932 -223.575626) (xy 116.479828 -223.549719)
			(xy 116.487934 -223.498542) (xy 116.503946 -223.449263) (xy 116.527469 -223.403096) (xy 116.557925 -223.361177)
			(xy 116.594563 -223.324539) (xy 116.636482 -223.294083) (xy 116.682649 -223.27056) (xy 116.731928 -223.254548)
			(xy 116.783105 -223.246442) (xy 116.834919 -223.246442) (xy 116.886096 -223.254548) (xy 116.935375 -223.27056)
			(xy 116.981542 -223.294083) (xy 117.023461 -223.324539) (xy 117.060099 -223.361177) (xy 117.090555 -223.403096)
			(xy 117.114078 -223.449263) (xy 117.13009 -223.498542) (xy 117.138196 -223.549719) (xy 117.138704 -223.575626)
			(xy 117.138287 -223.600992) (xy 117.130534 -223.651127) (xy 117.115185 -223.69948) (xy 117.092603 -223.744908)
			(xy 117.063322 -223.786336) (xy 117.028034 -223.822783) (xy 116.987575 -223.853388) (xy 116.942901 -223.877427)
			(xy 116.895069 -223.894332) (xy 116.870226 -223.899476) (xy 116.847366 -223.903794) (xy 116.642642 -224.258632)
			(xy 116.650516 -224.280476) (xy 116.65909 -224.306896) (xy 116.66829 -224.36167) (xy 116.668804 -224.389442)
			(xy 116.949728 -224.389442) (xy 116.950236 -224.363555) (xy 116.958335 -224.312417) (xy 116.974334 -224.263177)
			(xy 116.99784 -224.217045) (xy 117.028272 -224.175158) (xy 117.064882 -224.138548) (xy 117.106769 -224.108116)
			(xy 117.152901 -224.08461) (xy 117.202141 -224.068611) (xy 117.253279 -224.060512) (xy 117.305053 -224.060512)
			(xy 117.356191 -224.068611) (xy 117.405431 -224.08461) (xy 117.451563 -224.108116) (xy 117.49345 -224.138548)
			(xy 117.53006 -224.175158) (xy 117.560492 -224.217045) (xy 117.583998 -224.263177) (xy 117.599997 -224.312417)
			(xy 117.608096 -224.363555) (xy 117.608604 -224.389442) (xy 117.889528 -224.389442) (xy 117.889935 -224.364105)
			(xy 117.897697 -224.314028) (xy 117.913029 -224.265728) (xy 117.93557 -224.220343) (xy 117.964789 -224.17894)
			(xy 117.999999 -224.142496) (xy 118.04037 -224.111867) (xy 118.084952 -224.087776) (xy 118.132695 -224.070789)
			(xy 118.157498 -224.065592) (xy 118.180358 -224.061274) (xy 118.385082 -223.706436) (xy 118.377462 -223.684338)
			(xy 118.368831 -223.657991) (xy 118.35951 -223.603344) (xy 118.35892 -223.575626) (xy 118.359428 -223.549719)
			(xy 118.367534 -223.498542) (xy 118.383546 -223.449263) (xy 118.407069 -223.403096) (xy 118.437525 -223.361177)
			(xy 118.474163 -223.324539) (xy 118.516082 -223.294083) (xy 118.562249 -223.27056) (xy 118.611528 -223.254548)
			(xy 118.662705 -223.246442) (xy 118.714519 -223.246442) (xy 118.765696 -223.254548) (xy 118.814975 -223.27056)
			(xy 118.861142 -223.294083) (xy 118.903061 -223.324539) (xy 118.939699 -223.361177) (xy 118.970155 -223.403096)
			(xy 118.993678 -223.449263) (xy 119.00969 -223.498542) (xy 119.017796 -223.549719) (xy 119.018304 -223.575626)
			(xy 119.017887 -223.600992) (xy 119.010134 -223.651127) (xy 118.994785 -223.69948) (xy 118.972203 -223.744908)
			(xy 118.942922 -223.786336) (xy 118.907634 -223.822783) (xy 118.867175 -223.853388) (xy 118.822501 -223.877427)
			(xy 118.774669 -223.894332) (xy 118.749826 -223.899476) (xy 118.726966 -223.903794) (xy 118.522242 -224.258632)
			(xy 118.530116 -224.280476) (xy 118.53869 -224.306896) (xy 118.54789 -224.36167) (xy 118.548404 -224.389442)
			(xy 118.829328 -224.389442) (xy 118.829836 -224.363555) (xy 118.837935 -224.312417) (xy 118.853934 -224.263177)
			(xy 118.87744 -224.217045) (xy 118.907872 -224.175158) (xy 118.944482 -224.138548) (xy 118.986369 -224.108116)
			(xy 119.032501 -224.08461) (xy 119.081741 -224.068611) (xy 119.132879 -224.060512) (xy 119.184653 -224.060512)
			(xy 119.235791 -224.068611) (xy 119.285031 -224.08461) (xy 119.331163 -224.108116) (xy 119.37305 -224.138548)
			(xy 119.40966 -224.175158) (xy 119.440092 -224.217045) (xy 119.463598 -224.263177) (xy 119.479597 -224.312417)
			(xy 119.487696 -224.363555) (xy 119.488204 -224.389442) (xy 119.769128 -224.389442) (xy 119.769535 -224.364105)
			(xy 119.777297 -224.314028) (xy 119.792629 -224.265728) (xy 119.81517 -224.220343) (xy 119.844389 -224.17894)
			(xy 119.879599 -224.142496) (xy 119.91997 -224.111867) (xy 119.964552 -224.087776) (xy 120.012295 -224.070789)
			(xy 120.037098 -224.065592) (xy 120.059958 -224.061274) (xy 120.264682 -223.706436) (xy 120.257062 -223.684338)
			(xy 120.248431 -223.657991) (xy 120.23911 -223.603344) (xy 120.23852 -223.575626) (xy 120.239028 -223.549719)
			(xy 120.247134 -223.498542) (xy 120.263146 -223.449263) (xy 120.286669 -223.403096) (xy 120.317125 -223.361177)
			(xy 120.353763 -223.324539) (xy 120.395682 -223.294083) (xy 120.441849 -223.27056) (xy 120.491128 -223.254548)
			(xy 120.542305 -223.246442) (xy 120.594119 -223.246442) (xy 120.645296 -223.254548) (xy 120.694575 -223.27056)
			(xy 120.740742 -223.294083) (xy 120.782661 -223.324539) (xy 120.819299 -223.361177) (xy 120.849755 -223.403096)
			(xy 120.873278 -223.449263) (xy 120.88929 -223.498542) (xy 120.897396 -223.549719) (xy 120.897904 -223.575626)
			(xy 120.897487 -223.600992) (xy 120.889734 -223.651127) (xy 120.874385 -223.69948) (xy 120.851803 -223.744908)
			(xy 120.822522 -223.786336) (xy 120.787234 -223.822783) (xy 120.746775 -223.853388) (xy 120.702101 -223.877427)
			(xy 120.654269 -223.894332) (xy 120.629426 -223.899476) (xy 120.606566 -223.903794) (xy 120.401842 -224.258632)
			(xy 120.409716 -224.280476) (xy 120.41829 -224.306896) (xy 120.42749 -224.36167) (xy 120.428004 -224.389442)
			(xy 120.708928 -224.389442) (xy 120.709436 -224.363555) (xy 120.717535 -224.312417) (xy 120.733534 -224.263177)
			(xy 120.75704 -224.217045) (xy 120.787472 -224.175158) (xy 120.824082 -224.138548) (xy 120.865969 -224.108116)
			(xy 120.912101 -224.08461) (xy 120.961341 -224.068611) (xy 121.012479 -224.060512) (xy 121.064253 -224.060512)
			(xy 121.115391 -224.068611) (xy 121.164631 -224.08461) (xy 121.210763 -224.108116) (xy 121.25265 -224.138548)
			(xy 121.28926 -224.175158) (xy 121.319692 -224.217045) (xy 121.343198 -224.263177) (xy 121.359197 -224.312417)
			(xy 121.367296 -224.363555) (xy 121.367804 -224.389442) (xy 121.648728 -224.389442) (xy 121.649135 -224.364105)
			(xy 121.656897 -224.314028) (xy 121.672229 -224.265728) (xy 121.69477 -224.220343) (xy 121.723989 -224.17894)
			(xy 121.759199 -224.142496) (xy 121.79957 -224.111867) (xy 121.844152 -224.087776) (xy 121.891895 -224.070789)
			(xy 121.916698 -224.065592) (xy 121.939558 -224.061274) (xy 122.144282 -223.706436) (xy 122.136662 -223.684338)
			(xy 122.128031 -223.657991) (xy 122.11871 -223.603344) (xy 122.11812 -223.575626) (xy 122.118628 -223.549719)
			(xy 122.126734 -223.498542) (xy 122.142746 -223.449263) (xy 122.166269 -223.403096) (xy 122.196725 -223.361177)
			(xy 122.233363 -223.324539) (xy 122.275282 -223.294083) (xy 122.321449 -223.27056) (xy 122.370728 -223.254548)
			(xy 122.421905 -223.246442) (xy 122.473719 -223.246442) (xy 122.524896 -223.254548) (xy 122.574175 -223.27056)
			(xy 122.620342 -223.294083) (xy 122.662261 -223.324539) (xy 122.698899 -223.361177) (xy 122.729355 -223.403096)
			(xy 122.752878 -223.449263) (xy 122.76889 -223.498542) (xy 122.776996 -223.549719) (xy 122.777504 -223.575626)
			(xy 122.777087 -223.600992) (xy 122.769334 -223.651127) (xy 122.753985 -223.69948) (xy 122.731403 -223.744908)
			(xy 122.702122 -223.786336) (xy 122.666834 -223.822783) (xy 122.626375 -223.853388) (xy 122.581701 -223.877427)
			(xy 122.533869 -223.894332) (xy 122.509026 -223.899476) (xy 122.486166 -223.903794) (xy 122.281442 -224.258632)
			(xy 122.289316 -224.280476) (xy 122.29789 -224.306896) (xy 122.30709 -224.36167) (xy 122.307604 -224.389442)
			(xy 122.588528 -224.389442) (xy 122.589036 -224.363555) (xy 122.597135 -224.312417) (xy 122.613134 -224.263177)
			(xy 122.63664 -224.217045) (xy 122.667072 -224.175158) (xy 122.703682 -224.138548) (xy 122.745569 -224.108116)
			(xy 122.791701 -224.08461) (xy 122.840941 -224.068611) (xy 122.892079 -224.060512) (xy 122.943853 -224.060512)
			(xy 122.994991 -224.068611) (xy 123.044231 -224.08461) (xy 123.090363 -224.108116) (xy 123.13225 -224.138548)
			(xy 123.16886 -224.175158) (xy 123.199292 -224.217045) (xy 123.222798 -224.263177) (xy 123.238797 -224.312417)
			(xy 123.246896 -224.363555) (xy 123.247404 -224.389442) (xy 123.528328 -224.389442) (xy 123.528735 -224.364105)
			(xy 123.536497 -224.314028) (xy 123.551829 -224.265728) (xy 123.57437 -224.220343) (xy 123.603589 -224.17894)
			(xy 123.638799 -224.142496) (xy 123.67917 -224.111867) (xy 123.723752 -224.087776) (xy 123.771495 -224.070789)
			(xy 123.796298 -224.065592) (xy 123.819158 -224.061274) (xy 124.023882 -223.706436) (xy 124.016262 -223.684338)
			(xy 124.007631 -223.657991) (xy 123.99831 -223.603344) (xy 123.99772 -223.575626) (xy 123.998228 -223.549719)
			(xy 124.006334 -223.498542) (xy 124.022346 -223.449263) (xy 124.045869 -223.403096) (xy 124.076325 -223.361177)
			(xy 124.112963 -223.324539) (xy 124.154882 -223.294083) (xy 124.201049 -223.27056) (xy 124.250328 -223.254548)
			(xy 124.301505 -223.246442) (xy 124.353319 -223.246442) (xy 124.404496 -223.254548) (xy 124.453775 -223.27056)
			(xy 124.499942 -223.294083) (xy 124.541861 -223.324539) (xy 124.578499 -223.361177) (xy 124.608955 -223.403096)
			(xy 124.632478 -223.449263) (xy 124.64849 -223.498542) (xy 124.656596 -223.549719) (xy 124.657104 -223.575626)
			(xy 124.656687 -223.600992) (xy 124.648934 -223.651127) (xy 124.633585 -223.69948) (xy 124.611003 -223.744908)
			(xy 124.581722 -223.786336) (xy 124.546434 -223.822783) (xy 124.505975 -223.853388) (xy 124.461301 -223.877427)
			(xy 124.413469 -223.894332) (xy 124.388626 -223.899476) (xy 124.365766 -223.903794) (xy 124.161042 -224.258632)
			(xy 124.168916 -224.280476) (xy 124.17749 -224.306896) (xy 124.18669 -224.36167) (xy 124.187204 -224.389442)
			(xy 124.468128 -224.389442) (xy 124.468636 -224.363555) (xy 124.476735 -224.312417) (xy 124.492734 -224.263177)
			(xy 124.51624 -224.217045) (xy 124.546672 -224.175158) (xy 124.583282 -224.138548) (xy 124.625169 -224.108116)
			(xy 124.671301 -224.08461) (xy 124.720541 -224.068611) (xy 124.771679 -224.060512) (xy 124.823453 -224.060512)
			(xy 124.874591 -224.068611) (xy 124.923831 -224.08461) (xy 124.969963 -224.108116) (xy 125.01185 -224.138548)
			(xy 125.04846 -224.175158) (xy 125.078892 -224.217045) (xy 125.102398 -224.263177) (xy 125.118397 -224.312417)
			(xy 125.126496 -224.363555) (xy 125.127004 -224.389442) (xy 125.407928 -224.389442) (xy 125.408335 -224.364105)
			(xy 125.416097 -224.314028) (xy 125.431429 -224.265728) (xy 125.45397 -224.220343) (xy 125.483189 -224.17894)
			(xy 125.518399 -224.142496) (xy 125.55877 -224.111867) (xy 125.603352 -224.087776) (xy 125.651095 -224.070789)
			(xy 125.675898 -224.065592) (xy 125.698758 -224.061274) (xy 125.903482 -223.706436) (xy 125.895862 -223.684338)
			(xy 125.887231 -223.657991) (xy 125.87791 -223.603344) (xy 125.87732 -223.575626) (xy 125.877828 -223.549719)
			(xy 125.885934 -223.498542) (xy 125.901946 -223.449263) (xy 125.925469 -223.403096) (xy 125.955925 -223.361177)
			(xy 125.992563 -223.324539) (xy 126.034482 -223.294083) (xy 126.080649 -223.27056) (xy 126.129928 -223.254548)
			(xy 126.181105 -223.246442) (xy 126.232919 -223.246442) (xy 126.284096 -223.254548) (xy 126.333375 -223.27056)
			(xy 126.379542 -223.294083) (xy 126.421461 -223.324539) (xy 126.458099 -223.361177) (xy 126.488555 -223.403096)
			(xy 126.512078 -223.449263) (xy 126.52809 -223.498542) (xy 126.536196 -223.549719) (xy 126.536704 -223.575626)
			(xy 126.536287 -223.600992) (xy 126.528534 -223.651127) (xy 126.513185 -223.69948) (xy 126.490603 -223.744908)
			(xy 126.461322 -223.786336) (xy 126.426034 -223.822783) (xy 126.385575 -223.853388) (xy 126.340901 -223.877427)
			(xy 126.293069 -223.894332) (xy 126.268226 -223.899476) (xy 126.245366 -223.903794) (xy 126.040642 -224.258632)
			(xy 126.048516 -224.280476) (xy 126.05709 -224.306896) (xy 126.06629 -224.36167) (xy 126.066804 -224.389442)
			(xy 126.347728 -224.389442) (xy 126.348236 -224.363555) (xy 126.356335 -224.312417) (xy 126.372334 -224.263177)
			(xy 126.39584 -224.217045) (xy 126.426272 -224.175158) (xy 126.462882 -224.138548) (xy 126.504769 -224.108116)
			(xy 126.550901 -224.08461) (xy 126.600141 -224.068611) (xy 126.651279 -224.060512) (xy 126.703053 -224.060512)
			(xy 126.754191 -224.068611) (xy 126.803431 -224.08461) (xy 126.849563 -224.108116) (xy 126.89145 -224.138548)
			(xy 126.92806 -224.175158) (xy 126.958492 -224.217045) (xy 126.981998 -224.263177) (xy 126.997997 -224.312417)
			(xy 127.006096 -224.363555) (xy 127.006604 -224.389442) (xy 127.287528 -224.389442) (xy 127.287935 -224.364105)
			(xy 127.295697 -224.314028) (xy 127.311029 -224.265728) (xy 127.33357 -224.220343) (xy 127.362789 -224.17894)
			(xy 127.397999 -224.142496) (xy 127.43837 -224.111867) (xy 127.482952 -224.087776) (xy 127.530695 -224.070789)
			(xy 127.555498 -224.065592) (xy 127.578358 -224.061274) (xy 127.783082 -223.706436) (xy 127.775462 -223.684338)
			(xy 127.766831 -223.657991) (xy 127.75751 -223.603344) (xy 127.75692 -223.575626) (xy 127.757428 -223.549719)
			(xy 127.765534 -223.498542) (xy 127.781546 -223.449263) (xy 127.805069 -223.403096) (xy 127.835525 -223.361177)
			(xy 127.872163 -223.324539) (xy 127.914082 -223.294083) (xy 127.960249 -223.27056) (xy 128.009528 -223.254548)
			(xy 128.060705 -223.246442) (xy 128.112519 -223.246442) (xy 128.163696 -223.254548) (xy 128.212975 -223.27056)
			(xy 128.259142 -223.294083) (xy 128.301061 -223.324539) (xy 128.337699 -223.361177) (xy 128.368155 -223.403096)
			(xy 128.391678 -223.449263) (xy 128.40769 -223.498542) (xy 128.415796 -223.549719) (xy 128.416304 -223.575626)
			(xy 128.415887 -223.600992) (xy 128.408134 -223.651127) (xy 128.392785 -223.69948) (xy 128.370203 -223.744908)
			(xy 128.340922 -223.786336) (xy 128.305634 -223.822783) (xy 128.265175 -223.853388) (xy 128.220501 -223.877427)
			(xy 128.172669 -223.894332) (xy 128.147826 -223.899476) (xy 128.124966 -223.903794) (xy 127.920242 -224.258632)
			(xy 127.928116 -224.280476) (xy 127.93669 -224.306896) (xy 127.94589 -224.36167) (xy 127.946404 -224.389442)
			(xy 128.227328 -224.389442) (xy 128.227836 -224.363555) (xy 128.235935 -224.312417) (xy 128.251934 -224.263177)
			(xy 128.27544 -224.217045) (xy 128.305872 -224.175158) (xy 128.342482 -224.138548) (xy 128.384369 -224.108116)
			(xy 128.430501 -224.08461) (xy 128.479741 -224.068611) (xy 128.530879 -224.060512) (xy 128.582653 -224.060512)
			(xy 128.633791 -224.068611) (xy 128.683031 -224.08461) (xy 128.729163 -224.108116) (xy 128.77105 -224.138548)
			(xy 128.80766 -224.175158) (xy 128.838092 -224.217045) (xy 128.861598 -224.263177) (xy 128.877597 -224.312417)
			(xy 128.885696 -224.363555) (xy 128.886204 -224.389442) (xy 129.167128 -224.389442) (xy 129.167535 -224.364105)
			(xy 129.175297 -224.314028) (xy 129.190629 -224.265728) (xy 129.21317 -224.220343) (xy 129.242389 -224.17894)
			(xy 129.277599 -224.142496) (xy 129.31797 -224.111867) (xy 129.362552 -224.087776) (xy 129.410295 -224.070789)
			(xy 129.435098 -224.065592) (xy 129.457958 -224.061274) (xy 129.662682 -223.706436) (xy 129.655062 -223.684338)
			(xy 129.646431 -223.657991) (xy 129.63711 -223.603344) (xy 129.63652 -223.575626) (xy 129.637028 -223.549719)
			(xy 129.645134 -223.498542) (xy 129.661146 -223.449263) (xy 129.684669 -223.403096) (xy 129.715125 -223.361177)
			(xy 129.751763 -223.324539) (xy 129.793682 -223.294083) (xy 129.839849 -223.27056) (xy 129.889128 -223.254548)
			(xy 129.940305 -223.246442) (xy 129.992119 -223.246442) (xy 130.043296 -223.254548) (xy 130.092575 -223.27056)
			(xy 130.138742 -223.294083) (xy 130.180661 -223.324539) (xy 130.217299 -223.361177) (xy 130.247755 -223.403096)
			(xy 130.271278 -223.449263) (xy 130.28729 -223.498542) (xy 130.295396 -223.549719) (xy 130.295904 -223.575626)
			(xy 130.295487 -223.600992) (xy 130.287734 -223.651127) (xy 130.272385 -223.69948) (xy 130.249803 -223.744908)
			(xy 130.220522 -223.786336) (xy 130.185234 -223.822783) (xy 130.144775 -223.853388) (xy 130.100101 -223.877427)
			(xy 130.052269 -223.894332) (xy 130.027426 -223.899476) (xy 130.004566 -223.903794) (xy 129.799842 -224.258632)
			(xy 129.807716 -224.280476) (xy 129.81629 -224.306896) (xy 129.82549 -224.36167) (xy 129.826004 -224.389442)
			(xy 130.106928 -224.389442) (xy 130.107436 -224.363555) (xy 130.115535 -224.312417) (xy 130.131534 -224.263177)
			(xy 130.15504 -224.217045) (xy 130.185472 -224.175158) (xy 130.222082 -224.138548) (xy 130.263969 -224.108116)
			(xy 130.310101 -224.08461) (xy 130.359341 -224.068611) (xy 130.410479 -224.060512) (xy 130.462253 -224.060512)
			(xy 130.513391 -224.068611) (xy 130.562631 -224.08461) (xy 130.608763 -224.108116) (xy 130.65065 -224.138548)
			(xy 130.68726 -224.175158) (xy 130.717692 -224.217045) (xy 130.741198 -224.263177) (xy 130.757197 -224.312417)
			(xy 130.765296 -224.363555) (xy 130.765804 -224.389442) (xy 131.046728 -224.389442) (xy 131.047135 -224.364105)
			(xy 131.054897 -224.314028) (xy 131.070229 -224.265728) (xy 131.09277 -224.220343) (xy 131.121989 -224.17894)
			(xy 131.157199 -224.142496) (xy 131.19757 -224.111867) (xy 131.242152 -224.087776) (xy 131.289895 -224.070789)
			(xy 131.314698 -224.065592) (xy 131.337558 -224.061274) (xy 131.542282 -223.706182) (xy 131.534662 -223.684338)
			(xy 131.526017 -223.657995) (xy 131.516704 -223.603345) (xy 131.51612 -223.575626) (xy 131.516628 -223.549719)
			(xy 131.524734 -223.498542) (xy 131.540746 -223.449263) (xy 131.564269 -223.403096) (xy 131.594725 -223.361177)
			(xy 131.631363 -223.324539) (xy 131.673282 -223.294083) (xy 131.719449 -223.27056) (xy 131.768728 -223.254548)
			(xy 131.819905 -223.246442) (xy 131.871719 -223.246442) (xy 131.922896 -223.254548) (xy 131.972175 -223.27056)
			(xy 132.018342 -223.294083) (xy 132.060261 -223.324539) (xy 132.096899 -223.361177) (xy 132.127355 -223.403096)
			(xy 132.150878 -223.449263) (xy 132.16689 -223.498542) (xy 132.174996 -223.549719) (xy 132.175504 -223.575626)
			(xy 132.175003 -223.60097) (xy 132.167228 -223.651059) (xy 132.151879 -223.699368) (xy 132.12932 -223.74476)
			(xy 132.10008 -223.786165) (xy 132.064849 -223.822609) (xy 132.024457 -223.853232) (xy 131.979854 -223.877314)
			(xy 131.932092 -223.894288) (xy 131.90728 -223.899476) (xy 131.88442 -223.903794) (xy 131.679696 -224.258632)
			(xy 131.687316 -224.280476) (xy 131.695872 -224.306769) (xy 131.705065 -224.361289) (xy 131.705604 -224.388934)
			(xy 131.705604 -224.389442) (xy 131.986528 -224.389442) (xy 131.987036 -224.363555) (xy 131.995135 -224.312417)
			(xy 132.011134 -224.263177) (xy 132.03464 -224.217045) (xy 132.065072 -224.175158) (xy 132.101682 -224.138548)
			(xy 132.143569 -224.108116) (xy 132.189701 -224.08461) (xy 132.238941 -224.068611) (xy 132.290079 -224.060512)
			(xy 132.341853 -224.060512) (xy 132.392991 -224.068611) (xy 132.442231 -224.08461) (xy 132.488363 -224.108116)
			(xy 132.53025 -224.138548) (xy 132.56686 -224.175158) (xy 132.597292 -224.217045) (xy 132.620798 -224.263177)
			(xy 132.636797 -224.312417) (xy 132.644896 -224.363555) (xy 132.645404 -224.389442) (xy 132.926328 -224.389442)
			(xy 132.926735 -224.364105) (xy 132.934497 -224.314028) (xy 132.949829 -224.265728) (xy 132.97237 -224.220343)
			(xy 133.001589 -224.17894) (xy 133.036799 -224.142496) (xy 133.07717 -224.111867) (xy 133.121752 -224.087776)
			(xy 133.169495 -224.070789) (xy 133.194298 -224.065592) (xy 133.217158 -224.061274) (xy 133.422136 -223.705928)
			(xy 133.414516 -223.684084) (xy 133.405997 -223.657912) (xy 133.396803 -223.603651) (xy 133.396228 -223.576134)
			(xy 133.396228 -223.575626) (xy 133.396736 -223.549739) (xy 133.404835 -223.498601) (xy 133.420834 -223.449361)
			(xy 133.44434 -223.403229) (xy 133.474772 -223.361342) (xy 133.511382 -223.324732) (xy 133.553269 -223.2943)
			(xy 133.599401 -223.270794) (xy 133.648641 -223.254795) (xy 133.699779 -223.246696) (xy 133.751553 -223.246696)
			(xy 133.802691 -223.254795) (xy 133.851931 -223.270794) (xy 133.898063 -223.2943) (xy 133.93995 -223.324732)
			(xy 133.97656 -223.361342) (xy 134.006992 -223.403229) (xy 134.030498 -223.449361) (xy 134.046497 -223.498601)
			(xy 134.054596 -223.549739) (xy 134.055104 -223.575626) (xy 134.054603 -223.60097) (xy 134.046828 -223.651059)
			(xy 134.031479 -223.699368) (xy 134.00892 -223.74476) (xy 133.97968 -223.786165) (xy 133.944449 -223.822609)
			(xy 133.904057 -223.853232) (xy 133.859454 -223.877314) (xy 133.811692 -223.894288) (xy 133.78688 -223.899476)
			(xy 133.76402 -223.903794) (xy 133.559296 -224.258632) (xy 133.566916 -224.280476) (xy 133.575472 -224.306769)
			(xy 133.584665 -224.361289) (xy 133.585204 -224.388934) (xy 133.585204 -224.389442) (xy 133.866128 -224.389442)
			(xy 133.866636 -224.363555) (xy 133.874735 -224.312417) (xy 133.890734 -224.263177) (xy 133.91424 -224.217045)
			(xy 133.944672 -224.175158) (xy 133.981282 -224.138548) (xy 134.023169 -224.108116) (xy 134.069301 -224.08461)
			(xy 134.118541 -224.068611) (xy 134.169679 -224.060512) (xy 134.221453 -224.060512) (xy 134.272591 -224.068611)
			(xy 134.321831 -224.08461) (xy 134.367963 -224.108116) (xy 134.40985 -224.138548) (xy 134.44646 -224.175158)
			(xy 134.476892 -224.217045) (xy 134.500398 -224.263177) (xy 134.516397 -224.312417) (xy 134.524496 -224.363555)
			(xy 134.525004 -224.389442) (xy 337.635596 -224.389442) (xy 337.636029 -224.364106) (xy 337.64379 -224.314032)
			(xy 337.65912 -224.265734) (xy 337.681659 -224.22035) (xy 337.710875 -224.178949) (xy 337.746081 -224.142504)
			(xy 337.786448 -224.111874) (xy 337.831026 -224.087781) (xy 337.878765 -224.070791) (xy 337.903566 -224.065592)
			(xy 337.926426 -224.061274) (xy 338.13115 -223.706182) (xy 338.12353 -223.684338) (xy 338.114887 -223.657995)
			(xy 338.105572 -223.603345) (xy 338.104988 -223.575626) (xy 338.105496 -223.549719) (xy 338.113602 -223.498542)
			(xy 338.129614 -223.449263) (xy 338.153137 -223.403096) (xy 338.183593 -223.361177) (xy 338.220231 -223.324539)
			(xy 338.26215 -223.294083) (xy 338.308317 -223.27056) (xy 338.357596 -223.254548) (xy 338.408773 -223.246442)
			(xy 338.460587 -223.246442) (xy 338.511764 -223.254548) (xy 338.561043 -223.27056) (xy 338.60721 -223.294083)
			(xy 338.649129 -223.324539) (xy 338.685767 -223.361177) (xy 338.716223 -223.403096) (xy 338.739746 -223.449263)
			(xy 338.755758 -223.498542) (xy 338.763864 -223.549719) (xy 338.764372 -223.575626) (xy 338.763897 -223.600971)
			(xy 338.756121 -223.651063) (xy 338.740771 -223.699374) (xy 338.718208 -223.744767) (xy 338.688966 -223.786173)
			(xy 338.653731 -223.822617) (xy 338.613335 -223.853239) (xy 338.568728 -223.877319) (xy 338.520962 -223.89429)
			(xy 338.496148 -223.899476) (xy 338.473288 -223.903794) (xy 338.268564 -224.258632) (xy 338.276184 -224.280476)
			(xy 338.284739 -224.306769) (xy 338.293932 -224.361289) (xy 338.294472 -224.388934) (xy 338.294472 -224.389442)
			(xy 338.575396 -224.389442) (xy 338.575904 -224.363555) (xy 338.584003 -224.312417) (xy 338.600002 -224.263177)
			(xy 338.623508 -224.217045) (xy 338.65394 -224.175158) (xy 338.69055 -224.138548) (xy 338.732437 -224.108116)
			(xy 338.778569 -224.08461) (xy 338.827809 -224.068611) (xy 338.878947 -224.060512) (xy 338.930721 -224.060512)
			(xy 338.981859 -224.068611) (xy 339.031099 -224.08461) (xy 339.077231 -224.108116) (xy 339.119118 -224.138548)
			(xy 339.155728 -224.175158) (xy 339.18616 -224.217045) (xy 339.209666 -224.263177) (xy 339.225665 -224.312417)
			(xy 339.233764 -224.363555) (xy 339.234272 -224.389442) (xy 339.515196 -224.389442) (xy 339.515629 -224.364106)
			(xy 339.52339 -224.314032) (xy 339.53872 -224.265734) (xy 339.561259 -224.22035) (xy 339.590475 -224.178949)
			(xy 339.625681 -224.142504) (xy 339.666048 -224.111874) (xy 339.710626 -224.087781) (xy 339.758365 -224.070791)
			(xy 339.783166 -224.065592) (xy 339.806026 -224.061274) (xy 340.01075 -223.706182) (xy 340.00313 -223.684338)
			(xy 339.994487 -223.657995) (xy 339.985172 -223.603345) (xy 339.984588 -223.575626) (xy 339.985096 -223.549719)
			(xy 339.993202 -223.498542) (xy 340.009214 -223.449263) (xy 340.032737 -223.403096) (xy 340.063193 -223.361177)
			(xy 340.099831 -223.324539) (xy 340.14175 -223.294083) (xy 340.187917 -223.27056) (xy 340.237196 -223.254548)
			(xy 340.288373 -223.246442) (xy 340.340187 -223.246442) (xy 340.391364 -223.254548) (xy 340.440643 -223.27056)
			(xy 340.48681 -223.294083) (xy 340.528729 -223.324539) (xy 340.565367 -223.361177) (xy 340.595823 -223.403096)
			(xy 340.619346 -223.449263) (xy 340.635358 -223.498542) (xy 340.643464 -223.549719) (xy 340.643972 -223.575626)
			(xy 340.643497 -223.600971) (xy 340.635721 -223.651063) (xy 340.620371 -223.699374) (xy 340.597808 -223.744767)
			(xy 340.568566 -223.786173) (xy 340.533331 -223.822617) (xy 340.492935 -223.853239) (xy 340.448328 -223.877319)
			(xy 340.400562 -223.89429) (xy 340.375748 -223.899476) (xy 340.352888 -223.903794) (xy 340.148164 -224.258632)
			(xy 340.155784 -224.280476) (xy 340.164339 -224.306769) (xy 340.173532 -224.361289) (xy 340.174072 -224.388934)
			(xy 340.174072 -224.389442) (xy 340.454996 -224.389442) (xy 340.455504 -224.363555) (xy 340.463603 -224.312417)
			(xy 340.479602 -224.263177) (xy 340.503108 -224.217045) (xy 340.53354 -224.175158) (xy 340.57015 -224.138548)
			(xy 340.612037 -224.108116) (xy 340.658169 -224.08461) (xy 340.707409 -224.068611) (xy 340.758547 -224.060512)
			(xy 340.810321 -224.060512) (xy 340.861459 -224.068611) (xy 340.910699 -224.08461) (xy 340.956831 -224.108116)
			(xy 340.998718 -224.138548) (xy 341.035328 -224.175158) (xy 341.06576 -224.217045) (xy 341.089266 -224.263177)
			(xy 341.105265 -224.312417) (xy 341.113364 -224.363555) (xy 341.113872 -224.389442) (xy 341.394796 -224.389442)
			(xy 341.395229 -224.364106) (xy 341.40299 -224.314032) (xy 341.41832 -224.265734) (xy 341.440859 -224.22035)
			(xy 341.470075 -224.178949) (xy 341.505281 -224.142504) (xy 341.545648 -224.111874) (xy 341.590226 -224.087781)
			(xy 341.637965 -224.070791) (xy 341.662766 -224.065592) (xy 341.685626 -224.061274) (xy 341.89035 -223.706436)
			(xy 341.88273 -223.684338) (xy 341.874102 -223.657991) (xy 341.864779 -223.603344) (xy 341.864188 -223.575626)
			(xy 341.864696 -223.549719) (xy 341.872802 -223.498542) (xy 341.888814 -223.449263) (xy 341.912337 -223.403096)
			(xy 341.942793 -223.361177) (xy 341.979431 -223.324539) (xy 342.02135 -223.294083) (xy 342.067517 -223.27056)
			(xy 342.116796 -223.254548) (xy 342.167973 -223.246442) (xy 342.219787 -223.246442) (xy 342.270964 -223.254548)
			(xy 342.320243 -223.27056) (xy 342.36641 -223.294083) (xy 342.408329 -223.324539) (xy 342.444967 -223.361177)
			(xy 342.475423 -223.403096) (xy 342.498946 -223.449263) (xy 342.514958 -223.498542) (xy 342.523064 -223.549719)
			(xy 342.523572 -223.575626) (xy 342.523181 -223.600993) (xy 342.515428 -223.651131) (xy 342.500077 -223.699486)
			(xy 342.477492 -223.744915) (xy 342.448207 -223.786344) (xy 342.412916 -223.822791) (xy 342.372452 -223.853396)
			(xy 342.327774 -223.877433) (xy 342.279939 -223.894334) (xy 342.255094 -223.899476) (xy 342.232234 -223.903794)
			(xy 342.02751 -224.258632) (xy 342.035384 -224.280476) (xy 342.043957 -224.306897) (xy 342.053158 -224.36167)
			(xy 342.053672 -224.389442) (xy 342.334596 -224.389442) (xy 342.335104 -224.363555) (xy 342.343203 -224.312417)
			(xy 342.359202 -224.263177) (xy 342.382708 -224.217045) (xy 342.41314 -224.175158) (xy 342.44975 -224.138548)
			(xy 342.491637 -224.108116) (xy 342.537769 -224.08461) (xy 342.587009 -224.068611) (xy 342.638147 -224.060512)
			(xy 342.689921 -224.060512) (xy 342.741059 -224.068611) (xy 342.790299 -224.08461) (xy 342.836431 -224.108116)
			(xy 342.878318 -224.138548) (xy 342.914928 -224.175158) (xy 342.94536 -224.217045) (xy 342.968866 -224.263177)
			(xy 342.984865 -224.312417) (xy 342.992964 -224.363555) (xy 342.993472 -224.389442) (xy 343.274396 -224.389442)
			(xy 343.274829 -224.364106) (xy 343.28259 -224.314032) (xy 343.29792 -224.265734) (xy 343.320459 -224.22035)
			(xy 343.349675 -224.178949) (xy 343.384881 -224.142504) (xy 343.425248 -224.111874) (xy 343.469826 -224.087781)
			(xy 343.517565 -224.070791) (xy 343.542366 -224.065592) (xy 343.565226 -224.061274) (xy 343.76995 -223.706436)
			(xy 343.76233 -223.684338) (xy 343.753702 -223.657991) (xy 343.744379 -223.603344) (xy 343.743788 -223.575626)
			(xy 343.744296 -223.549719) (xy 343.752402 -223.498542) (xy 343.768414 -223.449263) (xy 343.791937 -223.403096)
			(xy 343.822393 -223.361177) (xy 343.859031 -223.324539) (xy 343.90095 -223.294083) (xy 343.947117 -223.27056)
			(xy 343.996396 -223.254548) (xy 344.047573 -223.246442) (xy 344.099387 -223.246442) (xy 344.150564 -223.254548)
			(xy 344.199843 -223.27056) (xy 344.24601 -223.294083) (xy 344.287929 -223.324539) (xy 344.324567 -223.361177)
			(xy 344.355023 -223.403096) (xy 344.378546 -223.449263) (xy 344.394558 -223.498542) (xy 344.402664 -223.549719)
			(xy 344.403172 -223.575626) (xy 344.402781 -223.600993) (xy 344.395028 -223.651131) (xy 344.379677 -223.699486)
			(xy 344.357092 -223.744915) (xy 344.327807 -223.786344) (xy 344.292516 -223.822791) (xy 344.252052 -223.853396)
			(xy 344.207374 -223.877433) (xy 344.159539 -223.894334) (xy 344.134694 -223.899476) (xy 344.111834 -223.903794)
			(xy 343.90711 -224.258632) (xy 343.914984 -224.280476) (xy 343.923557 -224.306897) (xy 343.932758 -224.36167)
			(xy 343.933272 -224.389442) (xy 344.214196 -224.389442) (xy 344.214704 -224.363555) (xy 344.222803 -224.312417)
			(xy 344.238802 -224.263177) (xy 344.262308 -224.217045) (xy 344.29274 -224.175158) (xy 344.32935 -224.138548)
			(xy 344.371237 -224.108116) (xy 344.417369 -224.08461) (xy 344.466609 -224.068611) (xy 344.517747 -224.060512)
			(xy 344.569521 -224.060512) (xy 344.620659 -224.068611) (xy 344.669899 -224.08461) (xy 344.716031 -224.108116)
			(xy 344.757918 -224.138548) (xy 344.794528 -224.175158) (xy 344.82496 -224.217045) (xy 344.848466 -224.263177)
			(xy 344.864465 -224.312417) (xy 344.872564 -224.363555) (xy 344.873072 -224.389442) (xy 345.153996 -224.389442)
			(xy 345.154429 -224.364106) (xy 345.16219 -224.314032) (xy 345.17752 -224.265734) (xy 345.200059 -224.22035)
			(xy 345.229275 -224.178949) (xy 345.264481 -224.142504) (xy 345.304848 -224.111874) (xy 345.349426 -224.087781)
			(xy 345.397165 -224.070791) (xy 345.421966 -224.065592) (xy 345.444826 -224.061274) (xy 345.64955 -223.706436)
			(xy 345.64193 -223.684338) (xy 345.633302 -223.657991) (xy 345.623979 -223.603344) (xy 345.623388 -223.575626)
			(xy 345.623896 -223.549719) (xy 345.632002 -223.498542) (xy 345.648014 -223.449263) (xy 345.671537 -223.403096)
			(xy 345.701993 -223.361177) (xy 345.738631 -223.324539) (xy 345.78055 -223.294083) (xy 345.826717 -223.27056)
			(xy 345.875996 -223.254548) (xy 345.927173 -223.246442) (xy 345.978987 -223.246442) (xy 346.030164 -223.254548)
			(xy 346.079443 -223.27056) (xy 346.12561 -223.294083) (xy 346.167529 -223.324539) (xy 346.204167 -223.361177)
			(xy 346.234623 -223.403096) (xy 346.258146 -223.449263) (xy 346.274158 -223.498542) (xy 346.282264 -223.549719)
			(xy 346.282772 -223.575626) (xy 346.282381 -223.600993) (xy 346.274628 -223.651131) (xy 346.259277 -223.699486)
			(xy 346.236692 -223.744915) (xy 346.207407 -223.786344) (xy 346.172116 -223.822791) (xy 346.131652 -223.853396)
			(xy 346.086974 -223.877433) (xy 346.039139 -223.894334) (xy 346.014294 -223.899476) (xy 345.991434 -223.903794)
			(xy 345.78671 -224.258632) (xy 345.794584 -224.280476) (xy 345.803157 -224.306897) (xy 345.812358 -224.36167)
			(xy 345.812872 -224.389442) (xy 346.093796 -224.389442) (xy 346.094304 -224.363555) (xy 346.102403 -224.312417)
			(xy 346.118402 -224.263177) (xy 346.141908 -224.217045) (xy 346.17234 -224.175158) (xy 346.20895 -224.138548)
			(xy 346.250837 -224.108116) (xy 346.296969 -224.08461) (xy 346.346209 -224.068611) (xy 346.397347 -224.060512)
			(xy 346.449121 -224.060512) (xy 346.500259 -224.068611) (xy 346.549499 -224.08461) (xy 346.595631 -224.108116)
			(xy 346.637518 -224.138548) (xy 346.674128 -224.175158) (xy 346.70456 -224.217045) (xy 346.728066 -224.263177)
			(xy 346.744065 -224.312417) (xy 346.752164 -224.363555) (xy 346.752672 -224.389442) (xy 347.033596 -224.389442)
			(xy 347.034029 -224.364106) (xy 347.04179 -224.314032) (xy 347.05712 -224.265734) (xy 347.079659 -224.22035)
			(xy 347.108875 -224.178949) (xy 347.144081 -224.142504) (xy 347.184448 -224.111874) (xy 347.229026 -224.087781)
			(xy 347.276765 -224.070791) (xy 347.301566 -224.065592) (xy 347.324426 -224.061274) (xy 347.52915 -223.706436)
			(xy 347.52153 -223.684338) (xy 347.512902 -223.657991) (xy 347.503579 -223.603344) (xy 347.502988 -223.575626)
			(xy 347.503496 -223.549719) (xy 347.511602 -223.498542) (xy 347.527614 -223.449263) (xy 347.551137 -223.403096)
			(xy 347.581593 -223.361177) (xy 347.618231 -223.324539) (xy 347.66015 -223.294083) (xy 347.706317 -223.27056)
			(xy 347.755596 -223.254548) (xy 347.806773 -223.246442) (xy 347.858587 -223.246442) (xy 347.909764 -223.254548)
			(xy 347.959043 -223.27056) (xy 348.00521 -223.294083) (xy 348.047129 -223.324539) (xy 348.083767 -223.361177)
			(xy 348.114223 -223.403096) (xy 348.137746 -223.449263) (xy 348.153758 -223.498542) (xy 348.161864 -223.549719)
			(xy 348.162372 -223.575626) (xy 348.161981 -223.600993) (xy 348.154228 -223.651131) (xy 348.138877 -223.699486)
			(xy 348.116292 -223.744915) (xy 348.087007 -223.786344) (xy 348.051716 -223.822791) (xy 348.011252 -223.853396)
			(xy 347.966574 -223.877433) (xy 347.918739 -223.894334) (xy 347.893894 -223.899476) (xy 347.871034 -223.903794)
			(xy 347.66631 -224.258632) (xy 347.674184 -224.280476) (xy 347.682757 -224.306897) (xy 347.691958 -224.36167)
			(xy 347.692472 -224.389442) (xy 347.973396 -224.389442) (xy 347.973904 -224.363555) (xy 347.982003 -224.312417)
			(xy 347.998002 -224.263177) (xy 348.021508 -224.217045) (xy 348.05194 -224.175158) (xy 348.08855 -224.138548)
			(xy 348.130437 -224.108116) (xy 348.176569 -224.08461) (xy 348.225809 -224.068611) (xy 348.276947 -224.060512)
			(xy 348.328721 -224.060512) (xy 348.379859 -224.068611) (xy 348.429099 -224.08461) (xy 348.475231 -224.108116)
			(xy 348.517118 -224.138548) (xy 348.553728 -224.175158) (xy 348.58416 -224.217045) (xy 348.607666 -224.263177)
			(xy 348.623665 -224.312417) (xy 348.631764 -224.363555) (xy 348.632272 -224.389442) (xy 348.913196 -224.389442)
			(xy 348.913629 -224.364106) (xy 348.92139 -224.314032) (xy 348.93672 -224.265734) (xy 348.959259 -224.22035)
			(xy 348.988475 -224.178949) (xy 349.023681 -224.142504) (xy 349.064048 -224.111874) (xy 349.108626 -224.087781)
			(xy 349.156365 -224.070791) (xy 349.181166 -224.065592) (xy 349.204026 -224.061274) (xy 349.40875 -223.706436)
			(xy 349.40113 -223.684338) (xy 349.392502 -223.657991) (xy 349.383179 -223.603344) (xy 349.382588 -223.575626)
			(xy 349.383096 -223.549719) (xy 349.391202 -223.498542) (xy 349.407214 -223.449263) (xy 349.430737 -223.403096)
			(xy 349.461193 -223.361177) (xy 349.497831 -223.324539) (xy 349.53975 -223.294083) (xy 349.585917 -223.27056)
			(xy 349.635196 -223.254548) (xy 349.686373 -223.246442) (xy 349.738187 -223.246442) (xy 349.789364 -223.254548)
			(xy 349.838643 -223.27056) (xy 349.88481 -223.294083) (xy 349.926729 -223.324539) (xy 349.963367 -223.361177)
			(xy 349.993823 -223.403096) (xy 350.017346 -223.449263) (xy 350.033358 -223.498542) (xy 350.041464 -223.549719)
			(xy 350.041972 -223.575626) (xy 350.041581 -223.600993) (xy 350.033828 -223.651131) (xy 350.018477 -223.699486)
			(xy 349.995892 -223.744915) (xy 349.966607 -223.786344) (xy 349.931316 -223.822791) (xy 349.890852 -223.853396)
			(xy 349.846174 -223.877433) (xy 349.798339 -223.894334) (xy 349.773494 -223.899476) (xy 349.750634 -223.903794)
			(xy 349.54591 -224.258632) (xy 349.553784 -224.280476) (xy 349.562357 -224.306897) (xy 349.571558 -224.36167)
			(xy 349.572072 -224.389442) (xy 349.852996 -224.389442) (xy 349.853504 -224.363555) (xy 349.861603 -224.312417)
			(xy 349.877602 -224.263177) (xy 349.901108 -224.217045) (xy 349.93154 -224.175158) (xy 349.96815 -224.138548)
			(xy 350.010037 -224.108116) (xy 350.056169 -224.08461) (xy 350.105409 -224.068611) (xy 350.156547 -224.060512)
			(xy 350.208321 -224.060512) (xy 350.259459 -224.068611) (xy 350.308699 -224.08461) (xy 350.354831 -224.108116)
			(xy 350.396718 -224.138548) (xy 350.433328 -224.175158) (xy 350.46376 -224.217045) (xy 350.487266 -224.263177)
			(xy 350.503265 -224.312417) (xy 350.511364 -224.363555) (xy 350.511872 -224.389442) (xy 350.792796 -224.389442)
			(xy 350.793229 -224.364106) (xy 350.80099 -224.314032) (xy 350.81632 -224.265734) (xy 350.838859 -224.22035)
			(xy 350.868075 -224.178949) (xy 350.903281 -224.142504) (xy 350.943648 -224.111874) (xy 350.988226 -224.087781)
			(xy 351.035965 -224.070791) (xy 351.060766 -224.065592) (xy 351.083626 -224.061274) (xy 351.28835 -223.706436)
			(xy 351.28073 -223.684338) (xy 351.272102 -223.657991) (xy 351.262779 -223.603344) (xy 351.262188 -223.575626)
			(xy 351.262696 -223.549719) (xy 351.270802 -223.498542) (xy 351.286814 -223.449263) (xy 351.310337 -223.403096)
			(xy 351.340793 -223.361177) (xy 351.377431 -223.324539) (xy 351.41935 -223.294083) (xy 351.465517 -223.27056)
			(xy 351.514796 -223.254548) (xy 351.565973 -223.246442) (xy 351.617787 -223.246442) (xy 351.668964 -223.254548)
			(xy 351.718243 -223.27056) (xy 351.76441 -223.294083) (xy 351.806329 -223.324539) (xy 351.842967 -223.361177)
			(xy 351.873423 -223.403096) (xy 351.896946 -223.449263) (xy 351.912958 -223.498542) (xy 351.921064 -223.549719)
			(xy 351.921572 -223.575626) (xy 351.921181 -223.600993) (xy 351.913428 -223.651131) (xy 351.898077 -223.699486)
			(xy 351.875492 -223.744915) (xy 351.846207 -223.786344) (xy 351.810916 -223.822791) (xy 351.770452 -223.853396)
			(xy 351.725774 -223.877433) (xy 351.677939 -223.894334) (xy 351.653094 -223.899476) (xy 351.630234 -223.903794)
			(xy 351.42551 -224.258632) (xy 351.433384 -224.280476) (xy 351.441957 -224.306897) (xy 351.451158 -224.36167)
			(xy 351.451672 -224.389442) (xy 351.732596 -224.389442) (xy 351.733104 -224.363555) (xy 351.741203 -224.312417)
			(xy 351.757202 -224.263177) (xy 351.780708 -224.217045) (xy 351.81114 -224.175158) (xy 351.84775 -224.138548)
			(xy 351.889637 -224.108116) (xy 351.935769 -224.08461) (xy 351.985009 -224.068611) (xy 352.036147 -224.060512)
			(xy 352.087921 -224.060512) (xy 352.139059 -224.068611) (xy 352.188299 -224.08461) (xy 352.234431 -224.108116)
			(xy 352.276318 -224.138548) (xy 352.312928 -224.175158) (xy 352.34336 -224.217045) (xy 352.366866 -224.263177)
			(xy 352.382865 -224.312417) (xy 352.390964 -224.363555) (xy 352.391472 -224.389442) (xy 352.672396 -224.389442)
			(xy 352.672829 -224.364106) (xy 352.68059 -224.314032) (xy 352.69592 -224.265734) (xy 352.718459 -224.22035)
			(xy 352.747675 -224.178949) (xy 352.782881 -224.142504) (xy 352.823248 -224.111874) (xy 352.867826 -224.087781)
			(xy 352.915565 -224.070791) (xy 352.940366 -224.065592) (xy 352.963226 -224.061274) (xy 353.16795 -223.706436)
			(xy 353.16033 -223.684338) (xy 353.151702 -223.657991) (xy 353.142379 -223.603344) (xy 353.141788 -223.575626)
			(xy 353.142296 -223.549719) (xy 353.150402 -223.498542) (xy 353.166414 -223.449263) (xy 353.189937 -223.403096)
			(xy 353.220393 -223.361177) (xy 353.257031 -223.324539) (xy 353.29895 -223.294083) (xy 353.345117 -223.27056)
			(xy 353.394396 -223.254548) (xy 353.445573 -223.246442) (xy 353.497387 -223.246442) (xy 353.548564 -223.254548)
			(xy 353.597843 -223.27056) (xy 353.64401 -223.294083) (xy 353.685929 -223.324539) (xy 353.722567 -223.361177)
			(xy 353.753023 -223.403096) (xy 353.776546 -223.449263) (xy 353.792558 -223.498542) (xy 353.800664 -223.549719)
			(xy 353.801172 -223.575626) (xy 353.800781 -223.600993) (xy 353.793028 -223.651131) (xy 353.777677 -223.699486)
			(xy 353.755092 -223.744915) (xy 353.725807 -223.786344) (xy 353.690516 -223.822791) (xy 353.650052 -223.853396)
			(xy 353.605374 -223.877433) (xy 353.557539 -223.894334) (xy 353.532694 -223.899476) (xy 353.509834 -223.903794)
			(xy 353.30511 -224.258632) (xy 353.312984 -224.280476) (xy 353.321557 -224.306897) (xy 353.330758 -224.36167)
			(xy 353.331272 -224.389442) (xy 353.612196 -224.389442) (xy 353.612704 -224.363555) (xy 353.620803 -224.312417)
			(xy 353.636802 -224.263177) (xy 353.660308 -224.217045) (xy 353.69074 -224.175158) (xy 353.72735 -224.138548)
			(xy 353.769237 -224.108116) (xy 353.815369 -224.08461) (xy 353.864609 -224.068611) (xy 353.915747 -224.060512)
			(xy 353.967521 -224.060512) (xy 354.018659 -224.068611) (xy 354.067899 -224.08461) (xy 354.114031 -224.108116)
			(xy 354.155918 -224.138548) (xy 354.192528 -224.175158) (xy 354.22296 -224.217045) (xy 354.246466 -224.263177)
			(xy 354.262465 -224.312417) (xy 354.270564 -224.363555) (xy 354.271072 -224.389442) (xy 354.551996 -224.389442)
			(xy 354.552429 -224.364106) (xy 354.56019 -224.314032) (xy 354.57552 -224.265734) (xy 354.598059 -224.22035)
			(xy 354.627275 -224.178949) (xy 354.662481 -224.142504) (xy 354.702848 -224.111874) (xy 354.747426 -224.087781)
			(xy 354.795165 -224.070791) (xy 354.819966 -224.065592) (xy 354.842826 -224.061274) (xy 355.04755 -223.706436)
			(xy 355.03993 -223.684338) (xy 355.031302 -223.657991) (xy 355.021979 -223.603344) (xy 355.021388 -223.575626)
			(xy 355.021896 -223.549719) (xy 355.030002 -223.498542) (xy 355.046014 -223.449263) (xy 355.069537 -223.403096)
			(xy 355.099993 -223.361177) (xy 355.136631 -223.324539) (xy 355.17855 -223.294083) (xy 355.224717 -223.27056)
			(xy 355.273996 -223.254548) (xy 355.325173 -223.246442) (xy 355.376987 -223.246442) (xy 355.428164 -223.254548)
			(xy 355.477443 -223.27056) (xy 355.52361 -223.294083) (xy 355.565529 -223.324539) (xy 355.602167 -223.361177)
			(xy 355.632623 -223.403096) (xy 355.656146 -223.449263) (xy 355.672158 -223.498542) (xy 355.680264 -223.549719)
			(xy 355.680772 -223.575626) (xy 355.680381 -223.600993) (xy 355.672628 -223.651131) (xy 355.657277 -223.699486)
			(xy 355.634692 -223.744915) (xy 355.605407 -223.786344) (xy 355.570116 -223.822791) (xy 355.529652 -223.853396)
			(xy 355.484974 -223.877433) (xy 355.437139 -223.894334) (xy 355.412294 -223.899476) (xy 355.389434 -223.903794)
			(xy 355.18471 -224.258632) (xy 355.192584 -224.280476) (xy 355.201157 -224.306897) (xy 355.210358 -224.36167)
			(xy 355.210872 -224.389442) (xy 355.491796 -224.389442) (xy 355.492304 -224.363555) (xy 355.500403 -224.312417)
			(xy 355.516402 -224.263177) (xy 355.539908 -224.217045) (xy 355.57034 -224.175158) (xy 355.60695 -224.138548)
			(xy 355.648837 -224.108116) (xy 355.694969 -224.08461) (xy 355.744209 -224.068611) (xy 355.795347 -224.060512)
			(xy 355.847121 -224.060512) (xy 355.898259 -224.068611) (xy 355.947499 -224.08461) (xy 355.993631 -224.108116)
			(xy 356.035518 -224.138548) (xy 356.072128 -224.175158) (xy 356.10256 -224.217045) (xy 356.126066 -224.263177)
			(xy 356.142065 -224.312417) (xy 356.150164 -224.363555) (xy 356.150672 -224.389442) (xy 356.431596 -224.389442)
			(xy 356.432029 -224.364106) (xy 356.43979 -224.314032) (xy 356.45512 -224.265734) (xy 356.477659 -224.22035)
			(xy 356.506875 -224.178949) (xy 356.542081 -224.142504) (xy 356.582448 -224.111874) (xy 356.627026 -224.087781)
			(xy 356.674765 -224.070791) (xy 356.699566 -224.065592) (xy 356.722426 -224.061274) (xy 356.92715 -223.706436)
			(xy 356.91953 -223.684338) (xy 356.910902 -223.657991) (xy 356.901579 -223.603344) (xy 356.900988 -223.575626)
			(xy 356.901496 -223.549719) (xy 356.909602 -223.498542) (xy 356.925614 -223.449263) (xy 356.949137 -223.403096)
			(xy 356.979593 -223.361177) (xy 357.016231 -223.324539) (xy 357.05815 -223.294083) (xy 357.104317 -223.27056)
			(xy 357.153596 -223.254548) (xy 357.204773 -223.246442) (xy 357.256587 -223.246442) (xy 357.307764 -223.254548)
			(xy 357.357043 -223.27056) (xy 357.40321 -223.294083) (xy 357.445129 -223.324539) (xy 357.481767 -223.361177)
			(xy 357.512223 -223.403096) (xy 357.535746 -223.449263) (xy 357.551758 -223.498542) (xy 357.559864 -223.549719)
			(xy 357.560372 -223.575626) (xy 357.559981 -223.600993) (xy 357.552228 -223.651131) (xy 357.536877 -223.699486)
			(xy 357.514292 -223.744915) (xy 357.485007 -223.786344) (xy 357.449716 -223.822791) (xy 357.409252 -223.853396)
			(xy 357.364574 -223.877433) (xy 357.316739 -223.894334) (xy 357.291894 -223.899476) (xy 357.269034 -223.903794)
			(xy 357.06431 -224.258632) (xy 357.072184 -224.280476) (xy 357.080757 -224.306897) (xy 357.089958 -224.36167)
			(xy 357.090472 -224.389442) (xy 357.371396 -224.389442) (xy 357.371904 -224.363555) (xy 357.380003 -224.312417)
			(xy 357.396002 -224.263177) (xy 357.419508 -224.217045) (xy 357.44994 -224.175158) (xy 357.48655 -224.138548)
			(xy 357.528437 -224.108116) (xy 357.574569 -224.08461) (xy 357.623809 -224.068611) (xy 357.674947 -224.060512)
			(xy 357.726721 -224.060512) (xy 357.777859 -224.068611) (xy 357.827099 -224.08461) (xy 357.873231 -224.108116)
			(xy 357.915118 -224.138548) (xy 357.951728 -224.175158) (xy 357.98216 -224.217045) (xy 358.005666 -224.263177)
			(xy 358.021665 -224.312417) (xy 358.029764 -224.363555) (xy 358.030272 -224.389442) (xy 358.311196 -224.389442)
			(xy 358.311629 -224.364106) (xy 358.31939 -224.314032) (xy 358.33472 -224.265734) (xy 358.357259 -224.22035)
			(xy 358.386475 -224.178949) (xy 358.421681 -224.142504) (xy 358.462048 -224.111874) (xy 358.506626 -224.087781)
			(xy 358.554365 -224.070791) (xy 358.579166 -224.065592) (xy 358.602026 -224.061274) (xy 358.80675 -223.706436)
			(xy 358.79913 -223.684338) (xy 358.790502 -223.657991) (xy 358.781179 -223.603344) (xy 358.780588 -223.575626)
			(xy 358.781096 -223.549719) (xy 358.789202 -223.498542) (xy 358.805214 -223.449263) (xy 358.828737 -223.403096)
			(xy 358.859193 -223.361177) (xy 358.895831 -223.324539) (xy 358.93775 -223.294083) (xy 358.983917 -223.27056)
			(xy 359.033196 -223.254548) (xy 359.084373 -223.246442) (xy 359.136187 -223.246442) (xy 359.187364 -223.254548)
			(xy 359.236643 -223.27056) (xy 359.28281 -223.294083) (xy 359.324729 -223.324539) (xy 359.361367 -223.361177)
			(xy 359.391823 -223.403096) (xy 359.415346 -223.449263) (xy 359.431358 -223.498542) (xy 359.439464 -223.549719)
			(xy 359.439972 -223.575626) (xy 359.439581 -223.600993) (xy 359.431828 -223.651131) (xy 359.416477 -223.699486)
			(xy 359.393892 -223.744915) (xy 359.364607 -223.786344) (xy 359.329316 -223.822791) (xy 359.288852 -223.853396)
			(xy 359.244174 -223.877433) (xy 359.196339 -223.894334) (xy 359.171494 -223.899476) (xy 359.148634 -223.903794)
			(xy 358.94391 -224.258632) (xy 358.951784 -224.280476) (xy 358.960357 -224.306897) (xy 358.969558 -224.36167)
			(xy 358.970072 -224.389442) (xy 359.250996 -224.389442) (xy 359.251504 -224.363555) (xy 359.259603 -224.312417)
			(xy 359.275602 -224.263177) (xy 359.299108 -224.217045) (xy 359.32954 -224.175158) (xy 359.36615 -224.138548)
			(xy 359.408037 -224.108116) (xy 359.454169 -224.08461) (xy 359.503409 -224.068611) (xy 359.554547 -224.060512)
			(xy 359.606321 -224.060512) (xy 359.657459 -224.068611) (xy 359.706699 -224.08461) (xy 359.752831 -224.108116)
			(xy 359.794718 -224.138548) (xy 359.831328 -224.175158) (xy 359.86176 -224.217045) (xy 359.885266 -224.263177)
			(xy 359.901265 -224.312417) (xy 359.909364 -224.363555) (xy 359.909872 -224.389442) (xy 360.190796 -224.389442)
			(xy 360.191229 -224.364106) (xy 360.19899 -224.314032) (xy 360.21432 -224.265734) (xy 360.236859 -224.22035)
			(xy 360.266075 -224.178949) (xy 360.301281 -224.142504) (xy 360.341648 -224.111874) (xy 360.386226 -224.087781)
			(xy 360.433965 -224.070791) (xy 360.458766 -224.065592) (xy 360.481626 -224.061274) (xy 360.68635 -223.706436)
			(xy 360.67873 -223.684338) (xy 360.670102 -223.657991) (xy 360.660779 -223.603344) (xy 360.660188 -223.575626)
			(xy 360.660696 -223.549719) (xy 360.668802 -223.498542) (xy 360.684814 -223.449263) (xy 360.708337 -223.403096)
			(xy 360.738793 -223.361177) (xy 360.775431 -223.324539) (xy 360.81735 -223.294083) (xy 360.863517 -223.27056)
			(xy 360.912796 -223.254548) (xy 360.963973 -223.246442) (xy 361.015787 -223.246442) (xy 361.066964 -223.254548)
			(xy 361.116243 -223.27056) (xy 361.16241 -223.294083) (xy 361.204329 -223.324539) (xy 361.240967 -223.361177)
			(xy 361.271423 -223.403096) (xy 361.294946 -223.449263) (xy 361.310958 -223.498542) (xy 361.319064 -223.549719)
			(xy 361.319572 -223.575626) (xy 361.319181 -223.600993) (xy 361.311428 -223.651131) (xy 361.296077 -223.699486)
			(xy 361.273492 -223.744915) (xy 361.244207 -223.786344) (xy 361.208916 -223.822791) (xy 361.168452 -223.853396)
			(xy 361.123774 -223.877433) (xy 361.075939 -223.894334) (xy 361.051094 -223.899476) (xy 361.028234 -223.903794)
			(xy 360.82351 -224.258632) (xy 360.831384 -224.280476) (xy 360.839957 -224.306897) (xy 360.849158 -224.36167)
			(xy 360.849672 -224.389442) (xy 361.130596 -224.389442) (xy 361.131104 -224.363555) (xy 361.139203 -224.312417)
			(xy 361.155202 -224.263177) (xy 361.178708 -224.217045) (xy 361.20914 -224.175158) (xy 361.24575 -224.138548)
			(xy 361.287637 -224.108116) (xy 361.333769 -224.08461) (xy 361.383009 -224.068611) (xy 361.434147 -224.060512)
			(xy 361.485921 -224.060512) (xy 361.537059 -224.068611) (xy 361.586299 -224.08461) (xy 361.632431 -224.108116)
			(xy 361.674318 -224.138548) (xy 361.710928 -224.175158) (xy 361.74136 -224.217045) (xy 361.764866 -224.263177)
			(xy 361.780865 -224.312417) (xy 361.788964 -224.363555) (xy 361.789472 -224.389442) (xy 362.070396 -224.389442)
			(xy 362.070829 -224.364106) (xy 362.07859 -224.314032) (xy 362.09392 -224.265734) (xy 362.116459 -224.22035)
			(xy 362.145675 -224.178949) (xy 362.180881 -224.142504) (xy 362.221248 -224.111874) (xy 362.265826 -224.087781)
			(xy 362.313565 -224.070791) (xy 362.338366 -224.065592) (xy 362.361226 -224.061274) (xy 362.566204 -223.706182)
			(xy 362.558584 -223.684084) (xy 362.550064 -223.657913) (xy 362.540871 -223.603651) (xy 362.540296 -223.576134)
			(xy 362.540296 -223.575626) (xy 362.540804 -223.549739) (xy 362.548903 -223.498601) (xy 362.564902 -223.449361)
			(xy 362.588408 -223.403229) (xy 362.61884 -223.361342) (xy 362.65545 -223.324732) (xy 362.697337 -223.2943)
			(xy 362.743469 -223.270794) (xy 362.792709 -223.254795) (xy 362.843847 -223.246696) (xy 362.895621 -223.246696)
			(xy 362.946759 -223.254795) (xy 362.995999 -223.270794) (xy 363.042131 -223.2943) (xy 363.084018 -223.324732)
			(xy 363.120628 -223.361342) (xy 363.15106 -223.403229) (xy 363.174566 -223.449361) (xy 363.190565 -223.498601)
			(xy 363.198664 -223.549739) (xy 363.199172 -223.575626) (xy 363.198781 -223.600993) (xy 363.191028 -223.651131)
			(xy 363.175677 -223.699486) (xy 363.153092 -223.744915) (xy 363.123807 -223.786344) (xy 363.088516 -223.822791)
			(xy 363.048052 -223.853396) (xy 363.003374 -223.877433) (xy 362.955539 -223.894334) (xy 362.930694 -223.899476)
			(xy 362.907834 -223.903794) (xy 362.70311 -224.258632) (xy 362.710984 -224.280476) (xy 362.719557 -224.306897)
			(xy 362.728758 -224.36167) (xy 362.729272 -224.389442) (xy 363.010196 -224.389442) (xy 363.010704 -224.363555)
			(xy 363.018803 -224.312417) (xy 363.034802 -224.263177) (xy 363.058308 -224.217045) (xy 363.08874 -224.175158)
			(xy 363.12535 -224.138548) (xy 363.167237 -224.108116) (xy 363.213369 -224.08461) (xy 363.262609 -224.068611)
			(xy 363.313747 -224.060512) (xy 363.365521 -224.060512) (xy 363.416659 -224.068611) (xy 363.465899 -224.08461)
			(xy 363.512031 -224.108116) (xy 363.553918 -224.138548) (xy 363.590528 -224.175158) (xy 363.62096 -224.217045)
			(xy 363.644466 -224.263177) (xy 363.660465 -224.312417) (xy 363.668564 -224.363555) (xy 363.669072 -224.389442)
			(xy 363.949996 -224.389442) (xy 363.950429 -224.364106) (xy 363.95819 -224.314032) (xy 363.97352 -224.265734)
			(xy 363.996059 -224.22035) (xy 364.025275 -224.178949) (xy 364.060481 -224.142504) (xy 364.100848 -224.111874)
			(xy 364.145426 -224.087781) (xy 364.193165 -224.070791) (xy 364.217966 -224.065592) (xy 364.240826 -224.061274)
			(xy 364.44555 -223.706436) (xy 364.43793 -223.684338) (xy 364.429302 -223.657991) (xy 364.419979 -223.603344)
			(xy 364.419388 -223.575626) (xy 364.419896 -223.549719) (xy 364.428002 -223.498542) (xy 364.444014 -223.449263)
			(xy 364.467537 -223.403096) (xy 364.497993 -223.361177) (xy 364.534631 -223.324539) (xy 364.57655 -223.294083)
			(xy 364.622717 -223.27056) (xy 364.671996 -223.254548) (xy 364.723173 -223.246442) (xy 364.774987 -223.246442)
			(xy 364.826164 -223.254548) (xy 364.875443 -223.27056) (xy 364.92161 -223.294083) (xy 364.963529 -223.324539)
			(xy 365.000167 -223.361177) (xy 365.030623 -223.403096) (xy 365.054146 -223.449263) (xy 365.070158 -223.498542)
			(xy 365.078264 -223.549719) (xy 365.078772 -223.575626) (xy 365.078381 -223.600993) (xy 365.070628 -223.651131)
			(xy 365.055277 -223.699486) (xy 365.032692 -223.744915) (xy 365.003407 -223.786344) (xy 364.968116 -223.822791)
			(xy 364.927652 -223.853396) (xy 364.882974 -223.877433) (xy 364.835139 -223.894334) (xy 364.810294 -223.899476)
			(xy 364.787434 -223.903794) (xy 364.58271 -224.258632) (xy 364.590584 -224.280476) (xy 364.599157 -224.306897)
			(xy 364.608358 -224.36167) (xy 364.608872 -224.389442) (xy 364.889796 -224.389442) (xy 364.890304 -224.363555)
			(xy 364.898403 -224.312417) (xy 364.914402 -224.263177) (xy 364.937908 -224.217045) (xy 364.96834 -224.175158)
			(xy 365.00495 -224.138548) (xy 365.046837 -224.108116) (xy 365.092969 -224.08461) (xy 365.142209 -224.068611)
			(xy 365.193347 -224.060512) (xy 365.245121 -224.060512) (xy 365.296259 -224.068611) (xy 365.345499 -224.08461)
			(xy 365.391631 -224.108116) (xy 365.433518 -224.138548) (xy 365.470128 -224.175158) (xy 365.50056 -224.217045)
			(xy 365.524066 -224.263177) (xy 365.540065 -224.312417) (xy 365.548164 -224.363555) (xy 365.548672 -224.389442)
			(xy 365.829596 -224.389442) (xy 365.830029 -224.364106) (xy 365.83779 -224.314032) (xy 365.85312 -224.265734)
			(xy 365.875659 -224.22035) (xy 365.904875 -224.178949) (xy 365.940081 -224.142504) (xy 365.980448 -224.111874)
			(xy 366.025026 -224.087781) (xy 366.072765 -224.070791) (xy 366.097566 -224.065592) (xy 366.120426 -224.061274)
			(xy 366.32515 -223.706436) (xy 366.31753 -223.684338) (xy 366.308902 -223.657991) (xy 366.299579 -223.603344)
			(xy 366.298988 -223.575626) (xy 366.299496 -223.549719) (xy 366.307602 -223.498542) (xy 366.323614 -223.449263)
			(xy 366.347137 -223.403096) (xy 366.377593 -223.361177) (xy 366.414231 -223.324539) (xy 366.45615 -223.294083)
			(xy 366.502317 -223.27056) (xy 366.551596 -223.254548) (xy 366.602773 -223.246442) (xy 366.654587 -223.246442)
			(xy 366.705764 -223.254548) (xy 366.755043 -223.27056) (xy 366.80121 -223.294083) (xy 366.843129 -223.324539)
			(xy 366.879767 -223.361177) (xy 366.910223 -223.403096) (xy 366.933746 -223.449263) (xy 366.949758 -223.498542)
			(xy 366.957864 -223.549719) (xy 366.958372 -223.575626) (xy 366.957981 -223.600993) (xy 366.950228 -223.651131)
			(xy 366.934877 -223.699486) (xy 366.912292 -223.744915) (xy 366.883007 -223.786344) (xy 366.847716 -223.822791)
			(xy 366.807252 -223.853396) (xy 366.762574 -223.877433) (xy 366.714739 -223.894334) (xy 366.689894 -223.899476)
			(xy 366.667034 -223.903794) (xy 366.46231 -224.258632) (xy 366.470184 -224.280476) (xy 366.478757 -224.306897)
			(xy 366.487958 -224.36167) (xy 366.488472 -224.389442) (xy 366.769396 -224.389442) (xy 366.769904 -224.363555)
			(xy 366.778003 -224.312417) (xy 366.794002 -224.263177) (xy 366.817508 -224.217045) (xy 366.84794 -224.175158)
			(xy 366.88455 -224.138548) (xy 366.926437 -224.108116) (xy 366.972569 -224.08461) (xy 367.021809 -224.068611)
			(xy 367.072947 -224.060512) (xy 367.124721 -224.060512) (xy 367.175859 -224.068611) (xy 367.225099 -224.08461)
			(xy 367.271231 -224.108116) (xy 367.313118 -224.138548) (xy 367.349728 -224.175158) (xy 367.38016 -224.217045)
			(xy 367.403666 -224.263177) (xy 367.419665 -224.312417) (xy 367.427764 -224.363555) (xy 367.428272 -224.389442)
			(xy 367.709196 -224.389442) (xy 367.709629 -224.364106) (xy 367.71739 -224.314032) (xy 367.73272 -224.265734)
			(xy 367.755259 -224.22035) (xy 367.784475 -224.178949) (xy 367.819681 -224.142504) (xy 367.860048 -224.111874)
			(xy 367.904626 -224.087781) (xy 367.952365 -224.070791) (xy 367.977166 -224.065592) (xy 368.000026 -224.061274)
			(xy 368.20475 -223.706436) (xy 368.19713 -223.684338) (xy 368.188502 -223.657991) (xy 368.179179 -223.603344)
			(xy 368.178588 -223.575626) (xy 368.179096 -223.549719) (xy 368.187202 -223.498542) (xy 368.203214 -223.449263)
			(xy 368.226737 -223.403096) (xy 368.257193 -223.361177) (xy 368.293831 -223.324539) (xy 368.33575 -223.294083)
			(xy 368.381917 -223.27056) (xy 368.431196 -223.254548) (xy 368.482373 -223.246442) (xy 368.534187 -223.246442)
			(xy 368.585364 -223.254548) (xy 368.634643 -223.27056) (xy 368.68081 -223.294083) (xy 368.722729 -223.324539)
			(xy 368.759367 -223.361177) (xy 368.789823 -223.403096) (xy 368.813346 -223.449263) (xy 368.829358 -223.498542)
			(xy 368.837464 -223.549719) (xy 368.837972 -223.575626) (xy 368.837581 -223.600993) (xy 368.829828 -223.651131)
			(xy 368.814477 -223.699486) (xy 368.791892 -223.744915) (xy 368.762607 -223.786344) (xy 368.727316 -223.822791)
			(xy 368.686852 -223.853396) (xy 368.642174 -223.877433) (xy 368.594339 -223.894334) (xy 368.569494 -223.899476)
			(xy 368.546634 -223.903794) (xy 368.34191 -224.258632) (xy 368.349784 -224.280476) (xy 368.358357 -224.306897)
			(xy 368.367558 -224.36167) (xy 368.368072 -224.389442) (xy 368.648996 -224.389442) (xy 368.649504 -224.363555)
			(xy 368.657603 -224.312417) (xy 368.673602 -224.263177) (xy 368.697108 -224.217045) (xy 368.72754 -224.175158)
			(xy 368.76415 -224.138548) (xy 368.806037 -224.108116) (xy 368.852169 -224.08461) (xy 368.901409 -224.068611)
			(xy 368.952547 -224.060512) (xy 369.004321 -224.060512) (xy 369.055459 -224.068611) (xy 369.104699 -224.08461)
			(xy 369.150831 -224.108116) (xy 369.192718 -224.138548) (xy 369.229328 -224.175158) (xy 369.25976 -224.217045)
			(xy 369.283266 -224.263177) (xy 369.299265 -224.312417) (xy 369.307364 -224.363555) (xy 369.307872 -224.389442)
			(xy 369.588796 -224.389442) (xy 369.589229 -224.364106) (xy 369.59699 -224.314032) (xy 369.61232 -224.265734)
			(xy 369.634859 -224.22035) (xy 369.664075 -224.178949) (xy 369.699281 -224.142504) (xy 369.739648 -224.111874)
			(xy 369.784226 -224.087781) (xy 369.831965 -224.070791) (xy 369.856766 -224.065592) (xy 369.879626 -224.061274)
			(xy 370.08435 -223.706436) (xy 370.07673 -223.684338) (xy 370.068102 -223.657991) (xy 370.058779 -223.603344)
			(xy 370.058188 -223.575626) (xy 370.058696 -223.549719) (xy 370.066802 -223.498542) (xy 370.082814 -223.449263)
			(xy 370.106337 -223.403096) (xy 370.136793 -223.361177) (xy 370.173431 -223.324539) (xy 370.21535 -223.294083)
			(xy 370.261517 -223.27056) (xy 370.310796 -223.254548) (xy 370.361973 -223.246442) (xy 370.413787 -223.246442)
			(xy 370.464964 -223.254548) (xy 370.514243 -223.27056) (xy 370.56041 -223.294083) (xy 370.602329 -223.324539)
			(xy 370.638967 -223.361177) (xy 370.669423 -223.403096) (xy 370.692946 -223.449263) (xy 370.708958 -223.498542)
			(xy 370.717064 -223.549719) (xy 370.717572 -223.575626) (xy 370.717181 -223.600993) (xy 370.709428 -223.651131)
			(xy 370.694077 -223.699486) (xy 370.671492 -223.744915) (xy 370.642207 -223.786344) (xy 370.606916 -223.822791)
			(xy 370.566452 -223.853396) (xy 370.521774 -223.877433) (xy 370.473939 -223.894334) (xy 370.449094 -223.899476)
			(xy 370.426234 -223.903794) (xy 370.22151 -224.258632) (xy 370.229384 -224.280476) (xy 370.237957 -224.306897)
			(xy 370.247158 -224.36167) (xy 370.247672 -224.389442) (xy 370.528596 -224.389442) (xy 370.529104 -224.363555)
			(xy 370.537203 -224.312417) (xy 370.553202 -224.263177) (xy 370.576708 -224.217045) (xy 370.60714 -224.175158)
			(xy 370.64375 -224.138548) (xy 370.685637 -224.108116) (xy 370.731769 -224.08461) (xy 370.781009 -224.068611)
			(xy 370.832147 -224.060512) (xy 370.883921 -224.060512) (xy 370.935059 -224.068611) (xy 370.984299 -224.08461)
			(xy 371.030431 -224.108116) (xy 371.072318 -224.138548) (xy 371.108928 -224.175158) (xy 371.13936 -224.217045)
			(xy 371.162866 -224.263177) (xy 371.178865 -224.312417) (xy 371.186964 -224.363555) (xy 371.187472 -224.389442)
			(xy 371.468396 -224.389442) (xy 371.468829 -224.364106) (xy 371.47659 -224.314032) (xy 371.49192 -224.265734)
			(xy 371.514459 -224.22035) (xy 371.543675 -224.178949) (xy 371.578881 -224.142504) (xy 371.619248 -224.111874)
			(xy 371.663826 -224.087781) (xy 371.711565 -224.070791) (xy 371.736366 -224.065592) (xy 371.759226 -224.061274)
			(xy 371.96395 -223.706436) (xy 371.95633 -223.684338) (xy 371.947702 -223.657991) (xy 371.938379 -223.603344)
			(xy 371.937788 -223.575626) (xy 371.938296 -223.549719) (xy 371.946402 -223.498542) (xy 371.962414 -223.449263)
			(xy 371.985937 -223.403096) (xy 372.016393 -223.361177) (xy 372.053031 -223.324539) (xy 372.09495 -223.294083)
			(xy 372.141117 -223.27056) (xy 372.190396 -223.254548) (xy 372.241573 -223.246442) (xy 372.293387 -223.246442)
			(xy 372.344564 -223.254548) (xy 372.393843 -223.27056) (xy 372.44001 -223.294083) (xy 372.481929 -223.324539)
			(xy 372.518567 -223.361177) (xy 372.549023 -223.403096) (xy 372.572546 -223.449263) (xy 372.588558 -223.498542)
			(xy 372.596664 -223.549719) (xy 372.597172 -223.575626) (xy 372.596781 -223.600993) (xy 372.589028 -223.651131)
			(xy 372.573677 -223.699486) (xy 372.551092 -223.744915) (xy 372.521807 -223.786344) (xy 372.486516 -223.822791)
			(xy 372.446052 -223.853396) (xy 372.401374 -223.877433) (xy 372.353539 -223.894334) (xy 372.328694 -223.899476)
			(xy 372.305834 -223.903794) (xy 372.10111 -224.258632) (xy 372.108984 -224.280476) (xy 372.117557 -224.306897)
			(xy 372.126758 -224.36167) (xy 372.127272 -224.389442) (xy 372.408196 -224.389442) (xy 372.408704 -224.363555)
			(xy 372.416803 -224.312417) (xy 372.432802 -224.263177) (xy 372.456308 -224.217045) (xy 372.48674 -224.175158)
			(xy 372.52335 -224.138548) (xy 372.565237 -224.108116) (xy 372.611369 -224.08461) (xy 372.660609 -224.068611)
			(xy 372.711747 -224.060512) (xy 372.763521 -224.060512) (xy 372.814659 -224.068611) (xy 372.863899 -224.08461)
			(xy 372.910031 -224.108116) (xy 372.951918 -224.138548) (xy 372.988528 -224.175158) (xy 373.01896 -224.217045)
			(xy 373.042466 -224.263177) (xy 373.058465 -224.312417) (xy 373.066564 -224.363555) (xy 373.067072 -224.389442)
			(xy 373.347996 -224.389442) (xy 373.348429 -224.364106) (xy 373.35619 -224.314032) (xy 373.37152 -224.265734)
			(xy 373.394059 -224.22035) (xy 373.423275 -224.178949) (xy 373.458481 -224.142504) (xy 373.498848 -224.111874)
			(xy 373.543426 -224.087781) (xy 373.591165 -224.070791) (xy 373.615966 -224.065592) (xy 373.638826 -224.061274)
			(xy 373.84355 -223.706436) (xy 373.83593 -223.684338) (xy 373.827302 -223.657991) (xy 373.817979 -223.603344)
			(xy 373.817388 -223.575626) (xy 373.817896 -223.549719) (xy 373.826002 -223.498542) (xy 373.842014 -223.449263)
			(xy 373.865537 -223.403096) (xy 373.895993 -223.361177) (xy 373.932631 -223.324539) (xy 373.97455 -223.294083)
			(xy 374.020717 -223.27056) (xy 374.069996 -223.254548) (xy 374.121173 -223.246442) (xy 374.172987 -223.246442)
			(xy 374.224164 -223.254548) (xy 374.273443 -223.27056) (xy 374.31961 -223.294083) (xy 374.361529 -223.324539)
			(xy 374.398167 -223.361177) (xy 374.428623 -223.403096) (xy 374.452146 -223.449263) (xy 374.468158 -223.498542)
			(xy 374.476264 -223.549719) (xy 374.476772 -223.575626) (xy 374.476381 -223.600993) (xy 374.468628 -223.651131)
			(xy 374.453277 -223.699486) (xy 374.430692 -223.744915) (xy 374.401407 -223.786344) (xy 374.366116 -223.822791)
			(xy 374.325652 -223.853396) (xy 374.280974 -223.877433) (xy 374.233139 -223.894334) (xy 374.208294 -223.899476)
			(xy 374.185434 -223.903794) (xy 373.98071 -224.258632) (xy 373.988584 -224.280476) (xy 373.997157 -224.306897)
			(xy 374.006358 -224.36167) (xy 374.006872 -224.389442) (xy 374.287796 -224.389442) (xy 374.288304 -224.363555)
			(xy 374.296403 -224.312417) (xy 374.312402 -224.263177) (xy 374.335908 -224.217045) (xy 374.36634 -224.175158)
			(xy 374.40295 -224.138548) (xy 374.444837 -224.108116) (xy 374.490969 -224.08461) (xy 374.540209 -224.068611)
			(xy 374.591347 -224.060512) (xy 374.643121 -224.060512) (xy 374.694259 -224.068611) (xy 374.743499 -224.08461)
			(xy 374.789631 -224.108116) (xy 374.831518 -224.138548) (xy 374.868128 -224.175158) (xy 374.89856 -224.217045)
			(xy 374.922066 -224.263177) (xy 374.938065 -224.312417) (xy 374.946164 -224.363555) (xy 374.946672 -224.389442)
			(xy 375.227596 -224.389442) (xy 375.228029 -224.364106) (xy 375.23579 -224.314032) (xy 375.25112 -224.265734)
			(xy 375.273659 -224.22035) (xy 375.302875 -224.178949) (xy 375.338081 -224.142504) (xy 375.378448 -224.111874)
			(xy 375.423026 -224.087781) (xy 375.470765 -224.070791) (xy 375.495566 -224.065592) (xy 375.518426 -224.061274)
			(xy 375.72315 -223.706436) (xy 375.71553 -223.684338) (xy 375.706902 -223.657991) (xy 375.697579 -223.603344)
			(xy 375.696988 -223.575626) (xy 375.697496 -223.549719) (xy 375.705602 -223.498542) (xy 375.721614 -223.449263)
			(xy 375.745137 -223.403096) (xy 375.775593 -223.361177) (xy 375.812231 -223.324539) (xy 375.85415 -223.294083)
			(xy 375.900317 -223.27056) (xy 375.949596 -223.254548) (xy 376.000773 -223.246442) (xy 376.052587 -223.246442)
			(xy 376.103764 -223.254548) (xy 376.153043 -223.27056) (xy 376.19921 -223.294083) (xy 376.241129 -223.324539)
			(xy 376.277767 -223.361177) (xy 376.308223 -223.403096) (xy 376.331746 -223.449263) (xy 376.347758 -223.498542)
			(xy 376.355864 -223.549719) (xy 376.356372 -223.575626) (xy 376.355981 -223.600993) (xy 376.348228 -223.651131)
			(xy 376.332877 -223.699486) (xy 376.310292 -223.744915) (xy 376.281007 -223.786344) (xy 376.245716 -223.822791)
			(xy 376.205252 -223.853396) (xy 376.160574 -223.877433) (xy 376.112739 -223.894334) (xy 376.087894 -223.899476)
			(xy 376.065034 -223.903794) (xy 375.86031 -224.258632) (xy 375.868184 -224.280476) (xy 375.876757 -224.306897)
			(xy 375.885958 -224.36167) (xy 375.886472 -224.389442) (xy 376.167396 -224.389442) (xy 376.167904 -224.363555)
			(xy 376.176003 -224.312417) (xy 376.192002 -224.263177) (xy 376.215508 -224.217045) (xy 376.24594 -224.175158)
			(xy 376.28255 -224.138548) (xy 376.324437 -224.108116) (xy 376.370569 -224.08461) (xy 376.419809 -224.068611)
			(xy 376.470947 -224.060512) (xy 376.522721 -224.060512) (xy 376.573859 -224.068611) (xy 376.623099 -224.08461)
			(xy 376.669231 -224.108116) (xy 376.711118 -224.138548) (xy 376.747728 -224.175158) (xy 376.77816 -224.217045)
			(xy 376.801666 -224.263177) (xy 376.817665 -224.312417) (xy 376.825764 -224.363555) (xy 376.826272 -224.389442)
			(xy 377.107196 -224.389442) (xy 377.107629 -224.364106) (xy 377.11539 -224.314032) (xy 377.13072 -224.265734)
			(xy 377.153259 -224.22035) (xy 377.182475 -224.178949) (xy 377.217681 -224.142504) (xy 377.258048 -224.111874)
			(xy 377.302626 -224.087781) (xy 377.350365 -224.070791) (xy 377.375166 -224.065592) (xy 377.398026 -224.061274)
			(xy 377.60275 -223.706436) (xy 377.59513 -223.684338) (xy 377.586502 -223.657991) (xy 377.577179 -223.603344)
			(xy 377.576588 -223.575626) (xy 377.577096 -223.549719) (xy 377.585202 -223.498542) (xy 377.601214 -223.449263)
			(xy 377.624737 -223.403096) (xy 377.655193 -223.361177) (xy 377.691831 -223.324539) (xy 377.73375 -223.294083)
			(xy 377.779917 -223.27056) (xy 377.829196 -223.254548) (xy 377.880373 -223.246442) (xy 377.932187 -223.246442)
			(xy 377.983364 -223.254548) (xy 378.032643 -223.27056) (xy 378.07881 -223.294083) (xy 378.120729 -223.324539)
			(xy 378.157367 -223.361177) (xy 378.187823 -223.403096) (xy 378.211346 -223.449263) (xy 378.227358 -223.498542)
			(xy 378.235464 -223.549719) (xy 378.235972 -223.575626) (xy 378.235581 -223.600993) (xy 378.227828 -223.651131)
			(xy 378.212477 -223.699486) (xy 378.189892 -223.744915) (xy 378.160607 -223.786344) (xy 378.125316 -223.822791)
			(xy 378.084852 -223.853396) (xy 378.040174 -223.877433) (xy 377.992339 -223.894334) (xy 377.967494 -223.899476)
			(xy 377.944634 -223.903794) (xy 377.73991 -224.258632) (xy 377.747784 -224.280476) (xy 377.756357 -224.306897)
			(xy 377.765558 -224.36167) (xy 377.766072 -224.389442) (xy 378.046996 -224.389442) (xy 378.047504 -224.363555)
			(xy 378.055603 -224.312417) (xy 378.071602 -224.263177) (xy 378.095108 -224.217045) (xy 378.12554 -224.175158)
			(xy 378.16215 -224.138548) (xy 378.204037 -224.108116) (xy 378.250169 -224.08461) (xy 378.299409 -224.068611)
			(xy 378.350547 -224.060512) (xy 378.402321 -224.060512) (xy 378.453459 -224.068611) (xy 378.502699 -224.08461)
			(xy 378.548831 -224.108116) (xy 378.590718 -224.138548) (xy 378.627328 -224.175158) (xy 378.65776 -224.217045)
			(xy 378.681266 -224.263177) (xy 378.697265 -224.312417) (xy 378.705364 -224.363555) (xy 378.705872 -224.389442)
			(xy 378.986796 -224.389442) (xy 378.987229 -224.364106) (xy 378.99499 -224.314032) (xy 379.01032 -224.265734)
			(xy 379.032859 -224.22035) (xy 379.062075 -224.178949) (xy 379.097281 -224.142504) (xy 379.137648 -224.111874)
			(xy 379.182226 -224.087781) (xy 379.229965 -224.070791) (xy 379.254766 -224.065592) (xy 379.277626 -224.061274)
			(xy 379.48235 -223.706182) (xy 379.47473 -223.684338) (xy 379.466087 -223.657995) (xy 379.456772 -223.603345)
			(xy 379.456188 -223.575626) (xy 379.456696 -223.549719) (xy 379.464802 -223.498542) (xy 379.480814 -223.449263)
			(xy 379.504337 -223.403096) (xy 379.534793 -223.361177) (xy 379.571431 -223.324539) (xy 379.61335 -223.294083)
			(xy 379.659517 -223.27056) (xy 379.708796 -223.254548) (xy 379.759973 -223.246442) (xy 379.811787 -223.246442)
			(xy 379.862964 -223.254548) (xy 379.912243 -223.27056) (xy 379.95841 -223.294083) (xy 380.000329 -223.324539)
			(xy 380.036967 -223.361177) (xy 380.067423 -223.403096) (xy 380.090946 -223.449263) (xy 380.106958 -223.498542)
			(xy 380.115064 -223.549719) (xy 380.115572 -223.575626) (xy 380.115097 -223.600971) (xy 380.107321 -223.651063)
			(xy 380.091971 -223.699374) (xy 380.069408 -223.744767) (xy 380.040166 -223.786173) (xy 380.004931 -223.822617)
			(xy 379.964535 -223.853239) (xy 379.919928 -223.877319) (xy 379.872162 -223.89429) (xy 379.847348 -223.899476)
			(xy 379.824488 -223.903794) (xy 379.619764 -224.258632) (xy 379.627384 -224.280476) (xy 379.635939 -224.306769)
			(xy 379.645132 -224.361289) (xy 379.645672 -224.388934) (xy 379.645672 -224.389442) (xy 379.926596 -224.389442)
			(xy 379.927104 -224.363555) (xy 379.935203 -224.312417) (xy 379.951202 -224.263177) (xy 379.974708 -224.217045)
			(xy 380.00514 -224.175158) (xy 380.04175 -224.138548) (xy 380.083637 -224.108116) (xy 380.129769 -224.08461)
			(xy 380.179009 -224.068611) (xy 380.230147 -224.060512) (xy 380.281921 -224.060512) (xy 380.333059 -224.068611)
			(xy 380.382299 -224.08461) (xy 380.428431 -224.108116) (xy 380.470318 -224.138548) (xy 380.506928 -224.175158)
			(xy 380.53736 -224.217045) (xy 380.560866 -224.263177) (xy 380.576865 -224.312417) (xy 380.584964 -224.363555)
			(xy 380.585472 -224.389442) (xy 380.866396 -224.389442) (xy 380.866829 -224.364106) (xy 380.87459 -224.314032)
			(xy 380.88992 -224.265734) (xy 380.912459 -224.22035) (xy 380.941675 -224.178949) (xy 380.976881 -224.142504)
			(xy 381.017248 -224.111874) (xy 381.061826 -224.087781) (xy 381.109565 -224.070791) (xy 381.134366 -224.065592)
			(xy 381.157226 -224.061274) (xy 381.362204 -223.705928) (xy 381.354584 -223.684084) (xy 381.346064 -223.657913)
			(xy 381.336871 -223.603651) (xy 381.336296 -223.576134) (xy 381.336296 -223.575626) (xy 381.336804 -223.549739)
			(xy 381.344903 -223.498601) (xy 381.360902 -223.449361) (xy 381.384408 -223.403229) (xy 381.41484 -223.361342)
			(xy 381.45145 -223.324732) (xy 381.493337 -223.2943) (xy 381.539469 -223.270794) (xy 381.588709 -223.254795)
			(xy 381.639847 -223.246696) (xy 381.691621 -223.246696) (xy 381.742759 -223.254795) (xy 381.791999 -223.270794)
			(xy 381.838131 -223.2943) (xy 381.880018 -223.324732) (xy 381.916628 -223.361342) (xy 381.94706 -223.403229)
			(xy 381.970566 -223.449361) (xy 381.986565 -223.498601) (xy 381.994664 -223.549739) (xy 381.995172 -223.575626)
			(xy 381.994697 -223.600971) (xy 381.986921 -223.651063) (xy 381.971571 -223.699374) (xy 381.949008 -223.744767)
			(xy 381.919766 -223.786173) (xy 381.884531 -223.822617) (xy 381.844135 -223.853239) (xy 381.799528 -223.877319)
			(xy 381.751762 -223.89429) (xy 381.726948 -223.899476) (xy 381.704088 -223.903794) (xy 381.499364 -224.258632)
			(xy 381.506984 -224.280476) (xy 381.515539 -224.306769) (xy 381.524732 -224.361289) (xy 381.525272 -224.388934)
			(xy 381.525272 -224.389442) (xy 381.806196 -224.389442) (xy 381.806704 -224.363555) (xy 381.814803 -224.312417)
			(xy 381.830802 -224.263177) (xy 381.854308 -224.217045) (xy 381.88474 -224.175158) (xy 381.92135 -224.138548)
			(xy 381.963237 -224.108116) (xy 382.009369 -224.08461) (xy 382.058609 -224.068611) (xy 382.109747 -224.060512)
			(xy 382.161521 -224.060512) (xy 382.212659 -224.068611) (xy 382.261899 -224.08461) (xy 382.308031 -224.108116)
			(xy 382.349918 -224.138548) (xy 382.386528 -224.175158) (xy 382.41696 -224.217045) (xy 382.440466 -224.263177)
			(xy 382.456465 -224.312417) (xy 382.464564 -224.363555) (xy 382.465072 -224.389442) (xy 382.464539 -224.41715)
			(xy 382.455342 -224.471795) (xy 382.446784 -224.498154) (xy 382.439164 -224.519998) (xy 382.644142 -224.87509)
			(xy 382.667002 -224.879408) (xy 382.691815 -224.884555) (xy 382.739557 -224.901547) (xy 382.784137 -224.925644)
			(xy 382.824504 -224.95628) (xy 382.859707 -224.992732) (xy 382.888918 -225.034142) (xy 382.911448 -225.079534)
			(xy 382.926766 -225.12784) (xy 382.934512 -225.17792) (xy 382.934972 -225.203258) (xy 382.934464 -225.229145)
			(xy 382.926365 -225.280283) (xy 382.910366 -225.329523) (xy 382.88686 -225.375655) (xy 382.856428 -225.417542)
			(xy 382.819818 -225.454152) (xy 382.777931 -225.484584) (xy 382.731799 -225.50809) (xy 382.682559 -225.524089)
			(xy 382.631421 -225.532188) (xy 382.579647 -225.532188) (xy 382.528509 -225.524089) (xy 382.479269 -225.50809)
			(xy 382.433137 -225.484584) (xy 382.39125 -225.454152) (xy 382.35464 -225.417542) (xy 382.324208 -225.375655)
			(xy 382.300702 -225.329523) (xy 382.284703 -225.280283) (xy 382.276604 -225.229145) (xy 382.276096 -225.203258)
			(xy 382.276096 -225.20275) (xy 382.276653 -225.175107) (xy 382.285844 -225.120589) (xy 382.294384 -225.094292)
			(xy 382.302004 -225.072448) (xy 382.09728 -224.71761) (xy 382.07442 -224.713292) (xy 382.049591 -224.708158)
			(xy 382.001812 -224.691199) (xy 381.957192 -224.667122) (xy 381.916786 -224.636498) (xy 381.881546 -224.600046)
			(xy 381.852303 -224.558629) (xy 381.829748 -224.513222) (xy 381.814412 -224.464896) (xy 381.806657 -224.414792)
			(xy 381.806196 -224.389442) (xy 381.525272 -224.389442) (xy 381.524764 -224.415329) (xy 381.516665 -224.466467)
			(xy 381.500666 -224.515707) (xy 381.47716 -224.561839) (xy 381.446728 -224.603726) (xy 381.410118 -224.640336)
			(xy 381.368231 -224.670768) (xy 381.322099 -224.694274) (xy 381.272859 -224.710273) (xy 381.221721 -224.718372)
			(xy 381.169947 -224.718372) (xy 381.118809 -224.710273) (xy 381.069569 -224.694274) (xy 381.023437 -224.670768)
			(xy 380.98155 -224.640336) (xy 380.94494 -224.603726) (xy 380.914508 -224.561839) (xy 380.891002 -224.515707)
			(xy 380.875003 -224.466467) (xy 380.866904 -224.415329) (xy 380.866396 -224.389442) (xy 380.585472 -224.389442)
			(xy 380.584925 -224.417149) (xy 380.575741 -224.471796) (xy 380.567184 -224.498154) (xy 380.55931 -224.520252)
			(xy 380.764288 -224.87509) (xy 380.787148 -224.879408) (xy 380.811971 -224.884565) (xy 380.859751 -224.90152)
			(xy 380.904371 -224.925592) (xy 380.944778 -224.956214) (xy 380.980019 -224.992662) (xy 381.009263 -225.034077)
			(xy 381.031819 -225.079482) (xy 381.047156 -225.127806) (xy 381.054911 -225.177908) (xy 381.055372 -225.203258)
			(xy 381.054864 -225.229165) (xy 381.046758 -225.280342) (xy 381.030746 -225.329621) (xy 381.007223 -225.375788)
			(xy 380.976767 -225.417707) (xy 380.940129 -225.454345) (xy 380.89821 -225.484801) (xy 380.852043 -225.508324)
			(xy 380.802764 -225.524336) (xy 380.751587 -225.532442) (xy 380.699773 -225.532442) (xy 380.648596 -225.524336)
			(xy 380.599317 -225.508324) (xy 380.55315 -225.484801) (xy 380.511231 -225.454345) (xy 380.474593 -225.417707)
			(xy 380.444137 -225.375788) (xy 380.420614 -225.329621) (xy 380.404602 -225.280342) (xy 380.396496 -225.229165)
			(xy 380.395988 -225.203258) (xy 380.396597 -225.175541) (xy 380.40591 -225.120895) (xy 380.41453 -225.094546)
			(xy 380.422404 -225.072448) (xy 380.217426 -224.71761) (xy 380.194566 -224.713292) (xy 380.169748 -224.708169)
			(xy 380.122005 -224.691172) (xy 380.077426 -224.667071) (xy 380.03706 -224.636431) (xy 380.001857 -224.599976)
			(xy 379.972648 -224.558564) (xy 379.950119 -224.51317) (xy 379.934801 -224.464863) (xy 379.927055 -224.414781)
			(xy 379.926596 -224.389442) (xy 379.645672 -224.389442) (xy 379.645164 -224.415329) (xy 379.637065 -224.466467)
			(xy 379.621066 -224.515707) (xy 379.59756 -224.561839) (xy 379.567128 -224.603726) (xy 379.530518 -224.640336)
			(xy 379.488631 -224.670768) (xy 379.442499 -224.694274) (xy 379.393259 -224.710273) (xy 379.342121 -224.718372)
			(xy 379.290347 -224.718372) (xy 379.239209 -224.710273) (xy 379.189969 -224.694274) (xy 379.143837 -224.670768)
			(xy 379.10195 -224.640336) (xy 379.06534 -224.603726) (xy 379.034908 -224.561839) (xy 379.011402 -224.515707)
			(xy 378.995403 -224.466467) (xy 378.987304 -224.415329) (xy 378.986796 -224.389442) (xy 378.705872 -224.389442)
			(xy 378.705325 -224.417149) (xy 378.696141 -224.471796) (xy 378.687584 -224.498154) (xy 378.67971 -224.520252)
			(xy 378.884688 -224.87509) (xy 378.907548 -224.879408) (xy 378.932371 -224.884565) (xy 378.980151 -224.90152)
			(xy 379.024771 -224.925592) (xy 379.065178 -224.956214) (xy 379.100419 -224.992662) (xy 379.129663 -225.034077)
			(xy 379.152219 -225.079482) (xy 379.167556 -225.127806) (xy 379.175311 -225.177908) (xy 379.175772 -225.203258)
			(xy 379.175264 -225.229165) (xy 379.167158 -225.280342) (xy 379.151146 -225.329621) (xy 379.127623 -225.375788)
			(xy 379.097167 -225.417707) (xy 379.060529 -225.454345) (xy 379.01861 -225.484801) (xy 378.972443 -225.508324)
			(xy 378.923164 -225.524336) (xy 378.871987 -225.532442) (xy 378.820173 -225.532442) (xy 378.768996 -225.524336)
			(xy 378.719717 -225.508324) (xy 378.67355 -225.484801) (xy 378.631631 -225.454345) (xy 378.594993 -225.417707)
			(xy 378.564537 -225.375788) (xy 378.541014 -225.329621) (xy 378.525002 -225.280342) (xy 378.516896 -225.229165)
			(xy 378.516388 -225.203258) (xy 378.516997 -225.175541) (xy 378.52631 -225.120895) (xy 378.53493 -225.094546)
			(xy 378.542804 -225.072448) (xy 378.337826 -224.71761) (xy 378.314966 -224.713292) (xy 378.290148 -224.708169)
			(xy 378.242405 -224.691172) (xy 378.197826 -224.667071) (xy 378.15746 -224.636431) (xy 378.122257 -224.599976)
			(xy 378.093048 -224.558564) (xy 378.070519 -224.51317) (xy 378.055201 -224.464863) (xy 378.047455 -224.414781)
			(xy 378.046996 -224.389442) (xy 377.766072 -224.389442) (xy 377.765564 -224.415329) (xy 377.757465 -224.466467)
			(xy 377.741466 -224.515707) (xy 377.71796 -224.561839) (xy 377.687528 -224.603726) (xy 377.650918 -224.640336)
			(xy 377.609031 -224.670768) (xy 377.562899 -224.694274) (xy 377.513659 -224.710273) (xy 377.462521 -224.718372)
			(xy 377.410747 -224.718372) (xy 377.359609 -224.710273) (xy 377.310369 -224.694274) (xy 377.264237 -224.670768)
			(xy 377.22235 -224.640336) (xy 377.18574 -224.603726) (xy 377.155308 -224.561839) (xy 377.131802 -224.515707)
			(xy 377.115803 -224.466467) (xy 377.107704 -224.415329) (xy 377.107196 -224.389442) (xy 376.826272 -224.389442)
			(xy 376.825725 -224.417149) (xy 376.816541 -224.471796) (xy 376.807984 -224.498154) (xy 376.80011 -224.520252)
			(xy 377.005088 -224.87509) (xy 377.027948 -224.879408) (xy 377.052771 -224.884565) (xy 377.100551 -224.90152)
			(xy 377.145171 -224.925592) (xy 377.185578 -224.956214) (xy 377.220819 -224.992662) (xy 377.250063 -225.034077)
			(xy 377.272619 -225.079482) (xy 377.287956 -225.127806) (xy 377.295711 -225.177908) (xy 377.296172 -225.203258)
			(xy 377.295664 -225.229165) (xy 377.287558 -225.280342) (xy 377.271546 -225.329621) (xy 377.248023 -225.375788)
			(xy 377.217567 -225.417707) (xy 377.180929 -225.454345) (xy 377.13901 -225.484801) (xy 377.092843 -225.508324)
			(xy 377.043564 -225.524336) (xy 376.992387 -225.532442) (xy 376.940573 -225.532442) (xy 376.889396 -225.524336)
			(xy 376.840117 -225.508324) (xy 376.79395 -225.484801) (xy 376.752031 -225.454345) (xy 376.715393 -225.417707)
			(xy 376.684937 -225.375788) (xy 376.661414 -225.329621) (xy 376.645402 -225.280342) (xy 376.637296 -225.229165)
			(xy 376.636788 -225.203258) (xy 376.637397 -225.175541) (xy 376.64671 -225.120895) (xy 376.65533 -225.094546)
			(xy 376.663204 -225.072448) (xy 376.458226 -224.71761) (xy 376.435366 -224.713292) (xy 376.410548 -224.708169)
			(xy 376.362805 -224.691172) (xy 376.318226 -224.667071) (xy 376.27786 -224.636431) (xy 376.242657 -224.599976)
			(xy 376.213448 -224.558564) (xy 376.190919 -224.51317) (xy 376.175601 -224.464863) (xy 376.167855 -224.414781)
			(xy 376.167396 -224.389442) (xy 375.886472 -224.389442) (xy 375.885964 -224.415329) (xy 375.877865 -224.466467)
			(xy 375.861866 -224.515707) (xy 375.83836 -224.561839) (xy 375.807928 -224.603726) (xy 375.771318 -224.640336)
			(xy 375.729431 -224.670768) (xy 375.683299 -224.694274) (xy 375.634059 -224.710273) (xy 375.582921 -224.718372)
			(xy 375.531147 -224.718372) (xy 375.480009 -224.710273) (xy 375.430769 -224.694274) (xy 375.384637 -224.670768)
			(xy 375.34275 -224.640336) (xy 375.30614 -224.603726) (xy 375.275708 -224.561839) (xy 375.252202 -224.515707)
			(xy 375.236203 -224.466467) (xy 375.228104 -224.415329) (xy 375.227596 -224.389442) (xy 374.946672 -224.389442)
			(xy 374.946125 -224.417149) (xy 374.936941 -224.471796) (xy 374.928384 -224.498154) (xy 374.92051 -224.520252)
			(xy 375.125488 -224.87509) (xy 375.148348 -224.879408) (xy 375.173171 -224.884565) (xy 375.220951 -224.90152)
			(xy 375.265571 -224.925592) (xy 375.305978 -224.956214) (xy 375.341219 -224.992662) (xy 375.370463 -225.034077)
			(xy 375.393019 -225.079482) (xy 375.408356 -225.127806) (xy 375.416111 -225.177908) (xy 375.416572 -225.203258)
			(xy 375.416064 -225.229165) (xy 375.407958 -225.280342) (xy 375.391946 -225.329621) (xy 375.368423 -225.375788)
			(xy 375.337967 -225.417707) (xy 375.301329 -225.454345) (xy 375.25941 -225.484801) (xy 375.213243 -225.508324)
			(xy 375.163964 -225.524336) (xy 375.112787 -225.532442) (xy 375.060973 -225.532442) (xy 375.009796 -225.524336)
			(xy 374.960517 -225.508324) (xy 374.91435 -225.484801) (xy 374.872431 -225.454345) (xy 374.835793 -225.417707)
			(xy 374.805337 -225.375788) (xy 374.781814 -225.329621) (xy 374.765802 -225.280342) (xy 374.757696 -225.229165)
			(xy 374.757188 -225.203258) (xy 374.757797 -225.175541) (xy 374.76711 -225.120895) (xy 374.77573 -225.094546)
			(xy 374.783604 -225.072448) (xy 374.578626 -224.71761) (xy 374.555766 -224.713292) (xy 374.530948 -224.708169)
			(xy 374.483205 -224.691172) (xy 374.438626 -224.667071) (xy 374.39826 -224.636431) (xy 374.363057 -224.599976)
			(xy 374.333848 -224.558564) (xy 374.311319 -224.51317) (xy 374.296001 -224.464863) (xy 374.288255 -224.414781)
			(xy 374.287796 -224.389442) (xy 374.006872 -224.389442) (xy 374.006364 -224.415329) (xy 373.998265 -224.466467)
			(xy 373.982266 -224.515707) (xy 373.95876 -224.561839) (xy 373.928328 -224.603726) (xy 373.891718 -224.640336)
			(xy 373.849831 -224.670768) (xy 373.803699 -224.694274) (xy 373.754459 -224.710273) (xy 373.703321 -224.718372)
			(xy 373.651547 -224.718372) (xy 373.600409 -224.710273) (xy 373.551169 -224.694274) (xy 373.505037 -224.670768)
			(xy 373.46315 -224.640336) (xy 373.42654 -224.603726) (xy 373.396108 -224.561839) (xy 373.372602 -224.515707)
			(xy 373.356603 -224.466467) (xy 373.348504 -224.415329) (xy 373.347996 -224.389442) (xy 373.067072 -224.389442)
			(xy 373.066525 -224.417149) (xy 373.057341 -224.471796) (xy 373.048784 -224.498154) (xy 373.04091 -224.520252)
			(xy 373.245888 -224.87509) (xy 373.268748 -224.879408) (xy 373.293571 -224.884565) (xy 373.341351 -224.90152)
			(xy 373.385971 -224.925592) (xy 373.426378 -224.956214) (xy 373.461619 -224.992662) (xy 373.490863 -225.034077)
			(xy 373.513419 -225.079482) (xy 373.528756 -225.127806) (xy 373.536511 -225.177908) (xy 373.536972 -225.203258)
			(xy 373.536464 -225.229165) (xy 373.528358 -225.280342) (xy 373.512346 -225.329621) (xy 373.488823 -225.375788)
			(xy 373.458367 -225.417707) (xy 373.421729 -225.454345) (xy 373.37981 -225.484801) (xy 373.333643 -225.508324)
			(xy 373.284364 -225.524336) (xy 373.233187 -225.532442) (xy 373.181373 -225.532442) (xy 373.130196 -225.524336)
			(xy 373.080917 -225.508324) (xy 373.03475 -225.484801) (xy 372.992831 -225.454345) (xy 372.956193 -225.417707)
			(xy 372.925737 -225.375788) (xy 372.902214 -225.329621) (xy 372.886202 -225.280342) (xy 372.878096 -225.229165)
			(xy 372.877588 -225.203258) (xy 372.878197 -225.175541) (xy 372.88751 -225.120895) (xy 372.89613 -225.094546)
			(xy 372.904004 -225.072448) (xy 372.699026 -224.71761) (xy 372.676166 -224.713292) (xy 372.651348 -224.708169)
			(xy 372.603605 -224.691172) (xy 372.559026 -224.667071) (xy 372.51866 -224.636431) (xy 372.483457 -224.599976)
			(xy 372.454248 -224.558564) (xy 372.431719 -224.51317) (xy 372.416401 -224.464863) (xy 372.408655 -224.414781)
			(xy 372.408196 -224.389442) (xy 372.127272 -224.389442) (xy 372.126764 -224.415329) (xy 372.118665 -224.466467)
			(xy 372.102666 -224.515707) (xy 372.07916 -224.561839) (xy 372.048728 -224.603726) (xy 372.012118 -224.640336)
			(xy 371.970231 -224.670768) (xy 371.924099 -224.694274) (xy 371.874859 -224.710273) (xy 371.823721 -224.718372)
			(xy 371.771947 -224.718372) (xy 371.720809 -224.710273) (xy 371.671569 -224.694274) (xy 371.625437 -224.670768)
			(xy 371.58355 -224.640336) (xy 371.54694 -224.603726) (xy 371.516508 -224.561839) (xy 371.493002 -224.515707)
			(xy 371.477003 -224.466467) (xy 371.468904 -224.415329) (xy 371.468396 -224.389442) (xy 371.187472 -224.389442)
			(xy 371.186925 -224.417149) (xy 371.177741 -224.471796) (xy 371.169184 -224.498154) (xy 371.16131 -224.520252)
			(xy 371.366288 -224.87509) (xy 371.389148 -224.879408) (xy 371.413971 -224.884565) (xy 371.461751 -224.90152)
			(xy 371.506371 -224.925592) (xy 371.546778 -224.956214) (xy 371.582019 -224.992662) (xy 371.611263 -225.034077)
			(xy 371.633819 -225.079482) (xy 371.649156 -225.127806) (xy 371.656911 -225.177908) (xy 371.657372 -225.203258)
			(xy 371.656864 -225.229165) (xy 371.648758 -225.280342) (xy 371.632746 -225.329621) (xy 371.609223 -225.375788)
			(xy 371.578767 -225.417707) (xy 371.542129 -225.454345) (xy 371.50021 -225.484801) (xy 371.454043 -225.508324)
			(xy 371.404764 -225.524336) (xy 371.353587 -225.532442) (xy 371.301773 -225.532442) (xy 371.250596 -225.524336)
			(xy 371.201317 -225.508324) (xy 371.15515 -225.484801) (xy 371.113231 -225.454345) (xy 371.076593 -225.417707)
			(xy 371.046137 -225.375788) (xy 371.022614 -225.329621) (xy 371.006602 -225.280342) (xy 370.998496 -225.229165)
			(xy 370.997988 -225.203258) (xy 370.998597 -225.175541) (xy 371.00791 -225.120895) (xy 371.01653 -225.094546)
			(xy 371.024404 -225.072448) (xy 370.819426 -224.71761) (xy 370.796566 -224.713292) (xy 370.771748 -224.708169)
			(xy 370.724005 -224.691172) (xy 370.679426 -224.667071) (xy 370.63906 -224.636431) (xy 370.603857 -224.599976)
			(xy 370.574648 -224.558564) (xy 370.552119 -224.51317) (xy 370.536801 -224.464863) (xy 370.529055 -224.414781)
			(xy 370.528596 -224.389442) (xy 370.247672 -224.389442) (xy 370.247164 -224.415329) (xy 370.239065 -224.466467)
			(xy 370.223066 -224.515707) (xy 370.19956 -224.561839) (xy 370.169128 -224.603726) (xy 370.132518 -224.640336)
			(xy 370.090631 -224.670768) (xy 370.044499 -224.694274) (xy 369.995259 -224.710273) (xy 369.944121 -224.718372)
			(xy 369.892347 -224.718372) (xy 369.841209 -224.710273) (xy 369.791969 -224.694274) (xy 369.745837 -224.670768)
			(xy 369.70395 -224.640336) (xy 369.66734 -224.603726) (xy 369.636908 -224.561839) (xy 369.613402 -224.515707)
			(xy 369.597403 -224.466467) (xy 369.589304 -224.415329) (xy 369.588796 -224.389442) (xy 369.307872 -224.389442)
			(xy 369.307325 -224.417149) (xy 369.298141 -224.471796) (xy 369.289584 -224.498154) (xy 369.28171 -224.520252)
			(xy 369.486688 -224.87509) (xy 369.509548 -224.879408) (xy 369.534371 -224.884565) (xy 369.582151 -224.90152)
			(xy 369.626771 -224.925592) (xy 369.667178 -224.956214) (xy 369.702419 -224.992662) (xy 369.731663 -225.034077)
			(xy 369.754219 -225.079482) (xy 369.769556 -225.127806) (xy 369.777311 -225.177908) (xy 369.777772 -225.203258)
			(xy 369.777264 -225.229165) (xy 369.769158 -225.280342) (xy 369.753146 -225.329621) (xy 369.729623 -225.375788)
			(xy 369.699167 -225.417707) (xy 369.662529 -225.454345) (xy 369.62061 -225.484801) (xy 369.574443 -225.508324)
			(xy 369.525164 -225.524336) (xy 369.473987 -225.532442) (xy 369.422173 -225.532442) (xy 369.370996 -225.524336)
			(xy 369.321717 -225.508324) (xy 369.27555 -225.484801) (xy 369.233631 -225.454345) (xy 369.196993 -225.417707)
			(xy 369.166537 -225.375788) (xy 369.143014 -225.329621) (xy 369.127002 -225.280342) (xy 369.118896 -225.229165)
			(xy 369.118388 -225.203258) (xy 369.118997 -225.175541) (xy 369.12831 -225.120895) (xy 369.13693 -225.094546)
			(xy 369.144804 -225.072448) (xy 368.939826 -224.71761) (xy 368.916966 -224.713292) (xy 368.892148 -224.708169)
			(xy 368.844405 -224.691172) (xy 368.799826 -224.667071) (xy 368.75946 -224.636431) (xy 368.724257 -224.599976)
			(xy 368.695048 -224.558564) (xy 368.672519 -224.51317) (xy 368.657201 -224.464863) (xy 368.649455 -224.414781)
			(xy 368.648996 -224.389442) (xy 368.368072 -224.389442) (xy 368.367564 -224.415329) (xy 368.359465 -224.466467)
			(xy 368.343466 -224.515707) (xy 368.31996 -224.561839) (xy 368.289528 -224.603726) (xy 368.252918 -224.640336)
			(xy 368.211031 -224.670768) (xy 368.164899 -224.694274) (xy 368.115659 -224.710273) (xy 368.064521 -224.718372)
			(xy 368.012747 -224.718372) (xy 367.961609 -224.710273) (xy 367.912369 -224.694274) (xy 367.866237 -224.670768)
			(xy 367.82435 -224.640336) (xy 367.78774 -224.603726) (xy 367.757308 -224.561839) (xy 367.733802 -224.515707)
			(xy 367.717803 -224.466467) (xy 367.709704 -224.415329) (xy 367.709196 -224.389442) (xy 367.428272 -224.389442)
			(xy 367.427725 -224.417149) (xy 367.418541 -224.471796) (xy 367.409984 -224.498154) (xy 367.40211 -224.520252)
			(xy 367.607088 -224.87509) (xy 367.629948 -224.879408) (xy 367.654771 -224.884565) (xy 367.702551 -224.90152)
			(xy 367.747171 -224.925592) (xy 367.787578 -224.956214) (xy 367.822819 -224.992662) (xy 367.852063 -225.034077)
			(xy 367.874619 -225.079482) (xy 367.889956 -225.127806) (xy 367.897711 -225.177908) (xy 367.898172 -225.203258)
			(xy 367.897664 -225.229165) (xy 367.889558 -225.280342) (xy 367.873546 -225.329621) (xy 367.850023 -225.375788)
			(xy 367.819567 -225.417707) (xy 367.782929 -225.454345) (xy 367.74101 -225.484801) (xy 367.694843 -225.508324)
			(xy 367.645564 -225.524336) (xy 367.594387 -225.532442) (xy 367.542573 -225.532442) (xy 367.491396 -225.524336)
			(xy 367.442117 -225.508324) (xy 367.39595 -225.484801) (xy 367.354031 -225.454345) (xy 367.317393 -225.417707)
			(xy 367.286937 -225.375788) (xy 367.263414 -225.329621) (xy 367.247402 -225.280342) (xy 367.239296 -225.229165)
			(xy 367.238788 -225.203258) (xy 367.239397 -225.175541) (xy 367.24871 -225.120895) (xy 367.25733 -225.094546)
			(xy 367.265204 -225.072448) (xy 367.060226 -224.71761) (xy 367.037366 -224.713292) (xy 367.012548 -224.708169)
			(xy 366.964805 -224.691172) (xy 366.920226 -224.667071) (xy 366.87986 -224.636431) (xy 366.844657 -224.599976)
			(xy 366.815448 -224.558564) (xy 366.792919 -224.51317) (xy 366.777601 -224.464863) (xy 366.769855 -224.414781)
			(xy 366.769396 -224.389442) (xy 366.488472 -224.389442) (xy 366.487964 -224.415329) (xy 366.479865 -224.466467)
			(xy 366.463866 -224.515707) (xy 366.44036 -224.561839) (xy 366.409928 -224.603726) (xy 366.373318 -224.640336)
			(xy 366.331431 -224.670768) (xy 366.285299 -224.694274) (xy 366.236059 -224.710273) (xy 366.184921 -224.718372)
			(xy 366.133147 -224.718372) (xy 366.082009 -224.710273) (xy 366.032769 -224.694274) (xy 365.986637 -224.670768)
			(xy 365.94475 -224.640336) (xy 365.90814 -224.603726) (xy 365.877708 -224.561839) (xy 365.854202 -224.515707)
			(xy 365.838203 -224.466467) (xy 365.830104 -224.415329) (xy 365.829596 -224.389442) (xy 365.548672 -224.389442)
			(xy 365.548125 -224.417149) (xy 365.538941 -224.471796) (xy 365.530384 -224.498154) (xy 365.52251 -224.520252)
			(xy 365.727488 -224.87509) (xy 365.750348 -224.879408) (xy 365.775171 -224.884565) (xy 365.822951 -224.90152)
			(xy 365.867571 -224.925592) (xy 365.907978 -224.956214) (xy 365.943219 -224.992662) (xy 365.972463 -225.034077)
			(xy 365.995019 -225.079482) (xy 366.010356 -225.127806) (xy 366.018111 -225.177908) (xy 366.018572 -225.203258)
			(xy 366.018064 -225.229165) (xy 366.009958 -225.280342) (xy 365.993946 -225.329621) (xy 365.970423 -225.375788)
			(xy 365.939967 -225.417707) (xy 365.903329 -225.454345) (xy 365.86141 -225.484801) (xy 365.815243 -225.508324)
			(xy 365.765964 -225.524336) (xy 365.714787 -225.532442) (xy 365.662973 -225.532442) (xy 365.611796 -225.524336)
			(xy 365.562517 -225.508324) (xy 365.51635 -225.484801) (xy 365.474431 -225.454345) (xy 365.437793 -225.417707)
			(xy 365.407337 -225.375788) (xy 365.383814 -225.329621) (xy 365.367802 -225.280342) (xy 365.359696 -225.229165)
			(xy 365.359188 -225.203258) (xy 365.359797 -225.175541) (xy 365.36911 -225.120895) (xy 365.37773 -225.094546)
			(xy 365.385604 -225.072448) (xy 365.180626 -224.71761) (xy 365.157766 -224.713292) (xy 365.132948 -224.708169)
			(xy 365.085205 -224.691172) (xy 365.040626 -224.667071) (xy 365.00026 -224.636431) (xy 364.965057 -224.599976)
			(xy 364.935848 -224.558564) (xy 364.913319 -224.51317) (xy 364.898001 -224.464863) (xy 364.890255 -224.414781)
			(xy 364.889796 -224.389442) (xy 364.608872 -224.389442) (xy 364.608364 -224.415329) (xy 364.600265 -224.466467)
			(xy 364.584266 -224.515707) (xy 364.56076 -224.561839) (xy 364.530328 -224.603726) (xy 364.493718 -224.640336)
			(xy 364.451831 -224.670768) (xy 364.405699 -224.694274) (xy 364.356459 -224.710273) (xy 364.305321 -224.718372)
			(xy 364.253547 -224.718372) (xy 364.202409 -224.710273) (xy 364.153169 -224.694274) (xy 364.107037 -224.670768)
			(xy 364.06515 -224.640336) (xy 364.02854 -224.603726) (xy 363.998108 -224.561839) (xy 363.974602 -224.515707)
			(xy 363.958603 -224.466467) (xy 363.950504 -224.415329) (xy 363.949996 -224.389442) (xy 363.669072 -224.389442)
			(xy 363.668525 -224.417149) (xy 363.659341 -224.471796) (xy 363.650784 -224.498154) (xy 363.64291 -224.520252)
			(xy 363.847888 -224.87509) (xy 363.870748 -224.879408) (xy 363.895571 -224.884565) (xy 363.943351 -224.90152)
			(xy 363.987971 -224.925592) (xy 364.028378 -224.956214) (xy 364.063619 -224.992662) (xy 364.092863 -225.034077)
			(xy 364.115419 -225.079482) (xy 364.130756 -225.127806) (xy 364.138511 -225.177908) (xy 364.138972 -225.203258)
			(xy 364.138464 -225.229165) (xy 364.130358 -225.280342) (xy 364.114346 -225.329621) (xy 364.090823 -225.375788)
			(xy 364.060367 -225.417707) (xy 364.023729 -225.454345) (xy 363.98181 -225.484801) (xy 363.935643 -225.508324)
			(xy 363.886364 -225.524336) (xy 363.835187 -225.532442) (xy 363.783373 -225.532442) (xy 363.732196 -225.524336)
			(xy 363.682917 -225.508324) (xy 363.63675 -225.484801) (xy 363.594831 -225.454345) (xy 363.558193 -225.417707)
			(xy 363.527737 -225.375788) (xy 363.504214 -225.329621) (xy 363.488202 -225.280342) (xy 363.480096 -225.229165)
			(xy 363.479588 -225.203258) (xy 363.480197 -225.175541) (xy 363.48951 -225.120895) (xy 363.49813 -225.094546)
			(xy 363.506004 -225.072448) (xy 363.301026 -224.71761) (xy 363.278166 -224.713292) (xy 363.253348 -224.708169)
			(xy 363.205605 -224.691172) (xy 363.161026 -224.667071) (xy 363.12066 -224.636431) (xy 363.085457 -224.599976)
			(xy 363.056248 -224.558564) (xy 363.033719 -224.51317) (xy 363.018401 -224.464863) (xy 363.010655 -224.414781)
			(xy 363.010196 -224.389442) (xy 362.729272 -224.389442) (xy 362.728764 -224.415329) (xy 362.720665 -224.466467)
			(xy 362.704666 -224.515707) (xy 362.68116 -224.561839) (xy 362.650728 -224.603726) (xy 362.614118 -224.640336)
			(xy 362.572231 -224.670768) (xy 362.526099 -224.694274) (xy 362.476859 -224.710273) (xy 362.425721 -224.718372)
			(xy 362.373947 -224.718372) (xy 362.322809 -224.710273) (xy 362.273569 -224.694274) (xy 362.227437 -224.670768)
			(xy 362.18555 -224.640336) (xy 362.14894 -224.603726) (xy 362.118508 -224.561839) (xy 362.095002 -224.515707)
			(xy 362.079003 -224.466467) (xy 362.070904 -224.415329) (xy 362.070396 -224.389442) (xy 361.789472 -224.389442)
			(xy 361.788925 -224.417149) (xy 361.779741 -224.471796) (xy 361.771184 -224.498154) (xy 361.76331 -224.520252)
			(xy 361.968288 -224.87509) (xy 361.991148 -224.879408) (xy 362.015971 -224.884565) (xy 362.063751 -224.90152)
			(xy 362.108371 -224.925592) (xy 362.148778 -224.956214) (xy 362.184019 -224.992662) (xy 362.213263 -225.034077)
			(xy 362.235819 -225.079482) (xy 362.251156 -225.127806) (xy 362.258911 -225.177908) (xy 362.259372 -225.203258)
			(xy 362.258864 -225.229165) (xy 362.250758 -225.280342) (xy 362.234746 -225.329621) (xy 362.211223 -225.375788)
			(xy 362.180767 -225.417707) (xy 362.144129 -225.454345) (xy 362.10221 -225.484801) (xy 362.056043 -225.508324)
			(xy 362.006764 -225.524336) (xy 361.955587 -225.532442) (xy 361.903773 -225.532442) (xy 361.852596 -225.524336)
			(xy 361.803317 -225.508324) (xy 361.75715 -225.484801) (xy 361.715231 -225.454345) (xy 361.678593 -225.417707)
			(xy 361.648137 -225.375788) (xy 361.624614 -225.329621) (xy 361.608602 -225.280342) (xy 361.600496 -225.229165)
			(xy 361.599988 -225.203258) (xy 361.600597 -225.175541) (xy 361.60991 -225.120895) (xy 361.61853 -225.094546)
			(xy 361.626404 -225.072448) (xy 361.421426 -224.71761) (xy 361.398566 -224.713292) (xy 361.373748 -224.708169)
			(xy 361.326005 -224.691172) (xy 361.281426 -224.667071) (xy 361.24106 -224.636431) (xy 361.205857 -224.599976)
			(xy 361.176648 -224.558564) (xy 361.154119 -224.51317) (xy 361.138801 -224.464863) (xy 361.131055 -224.414781)
			(xy 361.130596 -224.389442) (xy 360.849672 -224.389442) (xy 360.849164 -224.415329) (xy 360.841065 -224.466467)
			(xy 360.825066 -224.515707) (xy 360.80156 -224.561839) (xy 360.771128 -224.603726) (xy 360.734518 -224.640336)
			(xy 360.692631 -224.670768) (xy 360.646499 -224.694274) (xy 360.597259 -224.710273) (xy 360.546121 -224.718372)
			(xy 360.494347 -224.718372) (xy 360.443209 -224.710273) (xy 360.393969 -224.694274) (xy 360.347837 -224.670768)
			(xy 360.30595 -224.640336) (xy 360.26934 -224.603726) (xy 360.238908 -224.561839) (xy 360.215402 -224.515707)
			(xy 360.199403 -224.466467) (xy 360.191304 -224.415329) (xy 360.190796 -224.389442) (xy 359.909872 -224.389442)
			(xy 359.909325 -224.417149) (xy 359.900141 -224.471796) (xy 359.891584 -224.498154) (xy 359.88371 -224.520252)
			(xy 360.088688 -224.87509) (xy 360.111548 -224.879408) (xy 360.136371 -224.884565) (xy 360.184151 -224.90152)
			(xy 360.228771 -224.925592) (xy 360.269178 -224.956214) (xy 360.304419 -224.992662) (xy 360.333663 -225.034077)
			(xy 360.356219 -225.079482) (xy 360.371556 -225.127806) (xy 360.379311 -225.177908) (xy 360.379772 -225.203258)
			(xy 360.379264 -225.229165) (xy 360.371158 -225.280342) (xy 360.355146 -225.329621) (xy 360.331623 -225.375788)
			(xy 360.301167 -225.417707) (xy 360.264529 -225.454345) (xy 360.22261 -225.484801) (xy 360.176443 -225.508324)
			(xy 360.127164 -225.524336) (xy 360.075987 -225.532442) (xy 360.024173 -225.532442) (xy 359.972996 -225.524336)
			(xy 359.923717 -225.508324) (xy 359.87755 -225.484801) (xy 359.835631 -225.454345) (xy 359.798993 -225.417707)
			(xy 359.768537 -225.375788) (xy 359.745014 -225.329621) (xy 359.729002 -225.280342) (xy 359.720896 -225.229165)
			(xy 359.720388 -225.203258) (xy 359.720997 -225.175541) (xy 359.73031 -225.120895) (xy 359.73893 -225.094546)
			(xy 359.746804 -225.072448) (xy 359.541826 -224.71761) (xy 359.518966 -224.713292) (xy 359.494148 -224.708169)
			(xy 359.446405 -224.691172) (xy 359.401826 -224.667071) (xy 359.36146 -224.636431) (xy 359.326257 -224.599976)
			(xy 359.297048 -224.558564) (xy 359.274519 -224.51317) (xy 359.259201 -224.464863) (xy 359.251455 -224.414781)
			(xy 359.250996 -224.389442) (xy 358.970072 -224.389442) (xy 358.969564 -224.415329) (xy 358.961465 -224.466467)
			(xy 358.945466 -224.515707) (xy 358.92196 -224.561839) (xy 358.891528 -224.603726) (xy 358.854918 -224.640336)
			(xy 358.813031 -224.670768) (xy 358.766899 -224.694274) (xy 358.717659 -224.710273) (xy 358.666521 -224.718372)
			(xy 358.614747 -224.718372) (xy 358.563609 -224.710273) (xy 358.514369 -224.694274) (xy 358.468237 -224.670768)
			(xy 358.42635 -224.640336) (xy 358.38974 -224.603726) (xy 358.359308 -224.561839) (xy 358.335802 -224.515707)
			(xy 358.319803 -224.466467) (xy 358.311704 -224.415329) (xy 358.311196 -224.389442) (xy 358.030272 -224.389442)
			(xy 358.029725 -224.417149) (xy 358.020541 -224.471796) (xy 358.011984 -224.498154) (xy 358.00411 -224.520252)
			(xy 358.209088 -224.87509) (xy 358.231948 -224.879408) (xy 358.256771 -224.884565) (xy 358.304551 -224.90152)
			(xy 358.349171 -224.925592) (xy 358.389578 -224.956214) (xy 358.424819 -224.992662) (xy 358.454063 -225.034077)
			(xy 358.476619 -225.079482) (xy 358.491956 -225.127806) (xy 358.499711 -225.177908) (xy 358.500172 -225.203258)
			(xy 358.499664 -225.229165) (xy 358.491558 -225.280342) (xy 358.475546 -225.329621) (xy 358.452023 -225.375788)
			(xy 358.421567 -225.417707) (xy 358.384929 -225.454345) (xy 358.34301 -225.484801) (xy 358.296843 -225.508324)
			(xy 358.247564 -225.524336) (xy 358.196387 -225.532442) (xy 358.144573 -225.532442) (xy 358.093396 -225.524336)
			(xy 358.044117 -225.508324) (xy 357.99795 -225.484801) (xy 357.956031 -225.454345) (xy 357.919393 -225.417707)
			(xy 357.888937 -225.375788) (xy 357.865414 -225.329621) (xy 357.849402 -225.280342) (xy 357.841296 -225.229165)
			(xy 357.840788 -225.203258) (xy 357.841397 -225.175541) (xy 357.85071 -225.120895) (xy 357.85933 -225.094546)
			(xy 357.867204 -225.072448) (xy 357.662226 -224.71761) (xy 357.639366 -224.713292) (xy 357.614548 -224.708169)
			(xy 357.566805 -224.691172) (xy 357.522226 -224.667071) (xy 357.48186 -224.636431) (xy 357.446657 -224.599976)
			(xy 357.417448 -224.558564) (xy 357.394919 -224.51317) (xy 357.379601 -224.464863) (xy 357.371855 -224.414781)
			(xy 357.371396 -224.389442) (xy 357.090472 -224.389442) (xy 357.089964 -224.415329) (xy 357.081865 -224.466467)
			(xy 357.065866 -224.515707) (xy 357.04236 -224.561839) (xy 357.011928 -224.603726) (xy 356.975318 -224.640336)
			(xy 356.933431 -224.670768) (xy 356.887299 -224.694274) (xy 356.838059 -224.710273) (xy 356.786921 -224.718372)
			(xy 356.735147 -224.718372) (xy 356.684009 -224.710273) (xy 356.634769 -224.694274) (xy 356.588637 -224.670768)
			(xy 356.54675 -224.640336) (xy 356.51014 -224.603726) (xy 356.479708 -224.561839) (xy 356.456202 -224.515707)
			(xy 356.440203 -224.466467) (xy 356.432104 -224.415329) (xy 356.431596 -224.389442) (xy 356.150672 -224.389442)
			(xy 356.150125 -224.417149) (xy 356.140941 -224.471796) (xy 356.132384 -224.498154) (xy 356.12451 -224.520252)
			(xy 356.329488 -224.87509) (xy 356.352348 -224.879408) (xy 356.377171 -224.884565) (xy 356.424951 -224.90152)
			(xy 356.469571 -224.925592) (xy 356.509978 -224.956214) (xy 356.545219 -224.992662) (xy 356.574463 -225.034077)
			(xy 356.597019 -225.079482) (xy 356.612356 -225.127806) (xy 356.620111 -225.177908) (xy 356.620572 -225.203258)
			(xy 356.620064 -225.229165) (xy 356.611958 -225.280342) (xy 356.595946 -225.329621) (xy 356.572423 -225.375788)
			(xy 356.541967 -225.417707) (xy 356.505329 -225.454345) (xy 356.46341 -225.484801) (xy 356.417243 -225.508324)
			(xy 356.367964 -225.524336) (xy 356.316787 -225.532442) (xy 356.264973 -225.532442) (xy 356.213796 -225.524336)
			(xy 356.164517 -225.508324) (xy 356.11835 -225.484801) (xy 356.076431 -225.454345) (xy 356.039793 -225.417707)
			(xy 356.009337 -225.375788) (xy 355.985814 -225.329621) (xy 355.969802 -225.280342) (xy 355.961696 -225.229165)
			(xy 355.961188 -225.203258) (xy 355.961797 -225.175541) (xy 355.97111 -225.120895) (xy 355.97973 -225.094546)
			(xy 355.987604 -225.072448) (xy 355.782626 -224.71761) (xy 355.759766 -224.713292) (xy 355.734948 -224.708169)
			(xy 355.687205 -224.691172) (xy 355.642626 -224.667071) (xy 355.60226 -224.636431) (xy 355.567057 -224.599976)
			(xy 355.537848 -224.558564) (xy 355.515319 -224.51317) (xy 355.500001 -224.464863) (xy 355.492255 -224.414781)
			(xy 355.491796 -224.389442) (xy 355.210872 -224.389442) (xy 355.210364 -224.415329) (xy 355.202265 -224.466467)
			(xy 355.186266 -224.515707) (xy 355.16276 -224.561839) (xy 355.132328 -224.603726) (xy 355.095718 -224.640336)
			(xy 355.053831 -224.670768) (xy 355.007699 -224.694274) (xy 354.958459 -224.710273) (xy 354.907321 -224.718372)
			(xy 354.855547 -224.718372) (xy 354.804409 -224.710273) (xy 354.755169 -224.694274) (xy 354.709037 -224.670768)
			(xy 354.66715 -224.640336) (xy 354.63054 -224.603726) (xy 354.600108 -224.561839) (xy 354.576602 -224.515707)
			(xy 354.560603 -224.466467) (xy 354.552504 -224.415329) (xy 354.551996 -224.389442) (xy 354.271072 -224.389442)
			(xy 354.270525 -224.417149) (xy 354.261341 -224.471796) (xy 354.252784 -224.498154) (xy 354.24491 -224.520252)
			(xy 354.449888 -224.87509) (xy 354.472748 -224.879408) (xy 354.497571 -224.884565) (xy 354.545351 -224.90152)
			(xy 354.589971 -224.925592) (xy 354.630378 -224.956214) (xy 354.665619 -224.992662) (xy 354.694863 -225.034077)
			(xy 354.717419 -225.079482) (xy 354.732756 -225.127806) (xy 354.740511 -225.177908) (xy 354.740972 -225.203258)
			(xy 354.740464 -225.229165) (xy 354.732358 -225.280342) (xy 354.716346 -225.329621) (xy 354.692823 -225.375788)
			(xy 354.662367 -225.417707) (xy 354.625729 -225.454345) (xy 354.58381 -225.484801) (xy 354.537643 -225.508324)
			(xy 354.488364 -225.524336) (xy 354.437187 -225.532442) (xy 354.385373 -225.532442) (xy 354.334196 -225.524336)
			(xy 354.284917 -225.508324) (xy 354.23875 -225.484801) (xy 354.196831 -225.454345) (xy 354.160193 -225.417707)
			(xy 354.129737 -225.375788) (xy 354.106214 -225.329621) (xy 354.090202 -225.280342) (xy 354.082096 -225.229165)
			(xy 354.081588 -225.203258) (xy 354.082197 -225.175541) (xy 354.09151 -225.120895) (xy 354.10013 -225.094546)
			(xy 354.108004 -225.072448) (xy 353.903026 -224.71761) (xy 353.880166 -224.713292) (xy 353.855348 -224.708169)
			(xy 353.807605 -224.691172) (xy 353.763026 -224.667071) (xy 353.72266 -224.636431) (xy 353.687457 -224.599976)
			(xy 353.658248 -224.558564) (xy 353.635719 -224.51317) (xy 353.620401 -224.464863) (xy 353.612655 -224.414781)
			(xy 353.612196 -224.389442) (xy 353.331272 -224.389442) (xy 353.330764 -224.415329) (xy 353.322665 -224.466467)
			(xy 353.306666 -224.515707) (xy 353.28316 -224.561839) (xy 353.252728 -224.603726) (xy 353.216118 -224.640336)
			(xy 353.174231 -224.670768) (xy 353.128099 -224.694274) (xy 353.078859 -224.710273) (xy 353.027721 -224.718372)
			(xy 352.975947 -224.718372) (xy 352.924809 -224.710273) (xy 352.875569 -224.694274) (xy 352.829437 -224.670768)
			(xy 352.78755 -224.640336) (xy 352.75094 -224.603726) (xy 352.720508 -224.561839) (xy 352.697002 -224.515707)
			(xy 352.681003 -224.466467) (xy 352.672904 -224.415329) (xy 352.672396 -224.389442) (xy 352.391472 -224.389442)
			(xy 352.390925 -224.417149) (xy 352.381741 -224.471796) (xy 352.373184 -224.498154) (xy 352.36531 -224.520252)
			(xy 352.570288 -224.87509) (xy 352.593148 -224.879408) (xy 352.617971 -224.884565) (xy 352.665751 -224.90152)
			(xy 352.710371 -224.925592) (xy 352.750778 -224.956214) (xy 352.786019 -224.992662) (xy 352.815263 -225.034077)
			(xy 352.837819 -225.079482) (xy 352.853156 -225.127806) (xy 352.860911 -225.177908) (xy 352.861372 -225.203258)
			(xy 352.860864 -225.229165) (xy 352.852758 -225.280342) (xy 352.836746 -225.329621) (xy 352.813223 -225.375788)
			(xy 352.782767 -225.417707) (xy 352.746129 -225.454345) (xy 352.70421 -225.484801) (xy 352.658043 -225.508324)
			(xy 352.608764 -225.524336) (xy 352.557587 -225.532442) (xy 352.505773 -225.532442) (xy 352.454596 -225.524336)
			(xy 352.405317 -225.508324) (xy 352.35915 -225.484801) (xy 352.317231 -225.454345) (xy 352.280593 -225.417707)
			(xy 352.250137 -225.375788) (xy 352.226614 -225.329621) (xy 352.210602 -225.280342) (xy 352.202496 -225.229165)
			(xy 352.201988 -225.203258) (xy 352.202597 -225.175541) (xy 352.21191 -225.120895) (xy 352.22053 -225.094546)
			(xy 352.228404 -225.072448) (xy 352.023426 -224.71761) (xy 352.000566 -224.713292) (xy 351.975748 -224.708169)
			(xy 351.928005 -224.691172) (xy 351.883426 -224.667071) (xy 351.84306 -224.636431) (xy 351.807857 -224.599976)
			(xy 351.778648 -224.558564) (xy 351.756119 -224.51317) (xy 351.740801 -224.464863) (xy 351.733055 -224.414781)
			(xy 351.732596 -224.389442) (xy 351.451672 -224.389442) (xy 351.451164 -224.415329) (xy 351.443065 -224.466467)
			(xy 351.427066 -224.515707) (xy 351.40356 -224.561839) (xy 351.373128 -224.603726) (xy 351.336518 -224.640336)
			(xy 351.294631 -224.670768) (xy 351.248499 -224.694274) (xy 351.199259 -224.710273) (xy 351.148121 -224.718372)
			(xy 351.096347 -224.718372) (xy 351.045209 -224.710273) (xy 350.995969 -224.694274) (xy 350.949837 -224.670768)
			(xy 350.90795 -224.640336) (xy 350.87134 -224.603726) (xy 350.840908 -224.561839) (xy 350.817402 -224.515707)
			(xy 350.801403 -224.466467) (xy 350.793304 -224.415329) (xy 350.792796 -224.389442) (xy 350.511872 -224.389442)
			(xy 350.511325 -224.417149) (xy 350.502141 -224.471796) (xy 350.493584 -224.498154) (xy 350.48571 -224.520252)
			(xy 350.690688 -224.87509) (xy 350.713548 -224.879408) (xy 350.738371 -224.884565) (xy 350.786151 -224.90152)
			(xy 350.830771 -224.925592) (xy 350.871178 -224.956214) (xy 350.906419 -224.992662) (xy 350.935663 -225.034077)
			(xy 350.958219 -225.079482) (xy 350.973556 -225.127806) (xy 350.981311 -225.177908) (xy 350.981772 -225.203258)
			(xy 350.981264 -225.229165) (xy 350.973158 -225.280342) (xy 350.957146 -225.329621) (xy 350.933623 -225.375788)
			(xy 350.903167 -225.417707) (xy 350.866529 -225.454345) (xy 350.82461 -225.484801) (xy 350.778443 -225.508324)
			(xy 350.729164 -225.524336) (xy 350.677987 -225.532442) (xy 350.626173 -225.532442) (xy 350.574996 -225.524336)
			(xy 350.525717 -225.508324) (xy 350.47955 -225.484801) (xy 350.437631 -225.454345) (xy 350.400993 -225.417707)
			(xy 350.370537 -225.375788) (xy 350.347014 -225.329621) (xy 350.331002 -225.280342) (xy 350.322896 -225.229165)
			(xy 350.322388 -225.203258) (xy 350.322997 -225.175541) (xy 350.33231 -225.120895) (xy 350.34093 -225.094546)
			(xy 350.348804 -225.072448) (xy 350.143826 -224.71761) (xy 350.120966 -224.713292) (xy 350.096148 -224.708169)
			(xy 350.048405 -224.691172) (xy 350.003826 -224.667071) (xy 349.96346 -224.636431) (xy 349.928257 -224.599976)
			(xy 349.899048 -224.558564) (xy 349.876519 -224.51317) (xy 349.861201 -224.464863) (xy 349.853455 -224.414781)
			(xy 349.852996 -224.389442) (xy 349.572072 -224.389442) (xy 349.571564 -224.415329) (xy 349.563465 -224.466467)
			(xy 349.547466 -224.515707) (xy 349.52396 -224.561839) (xy 349.493528 -224.603726) (xy 349.456918 -224.640336)
			(xy 349.415031 -224.670768) (xy 349.368899 -224.694274) (xy 349.319659 -224.710273) (xy 349.268521 -224.718372)
			(xy 349.216747 -224.718372) (xy 349.165609 -224.710273) (xy 349.116369 -224.694274) (xy 349.070237 -224.670768)
			(xy 349.02835 -224.640336) (xy 348.99174 -224.603726) (xy 348.961308 -224.561839) (xy 348.937802 -224.515707)
			(xy 348.921803 -224.466467) (xy 348.913704 -224.415329) (xy 348.913196 -224.389442) (xy 348.632272 -224.389442)
			(xy 348.631725 -224.417149) (xy 348.622541 -224.471796) (xy 348.613984 -224.498154) (xy 348.60611 -224.520252)
			(xy 348.811088 -224.87509) (xy 348.833948 -224.879408) (xy 348.858771 -224.884565) (xy 348.906551 -224.90152)
			(xy 348.951171 -224.925592) (xy 348.991578 -224.956214) (xy 349.026819 -224.992662) (xy 349.056063 -225.034077)
			(xy 349.078619 -225.079482) (xy 349.093956 -225.127806) (xy 349.101711 -225.177908) (xy 349.102172 -225.203258)
			(xy 349.101664 -225.229165) (xy 349.093558 -225.280342) (xy 349.077546 -225.329621) (xy 349.054023 -225.375788)
			(xy 349.023567 -225.417707) (xy 348.986929 -225.454345) (xy 348.94501 -225.484801) (xy 348.898843 -225.508324)
			(xy 348.849564 -225.524336) (xy 348.798387 -225.532442) (xy 348.746573 -225.532442) (xy 348.695396 -225.524336)
			(xy 348.646117 -225.508324) (xy 348.59995 -225.484801) (xy 348.558031 -225.454345) (xy 348.521393 -225.417707)
			(xy 348.490937 -225.375788) (xy 348.467414 -225.329621) (xy 348.451402 -225.280342) (xy 348.443296 -225.229165)
			(xy 348.442788 -225.203258) (xy 348.443397 -225.175541) (xy 348.45271 -225.120895) (xy 348.46133 -225.094546)
			(xy 348.469204 -225.072448) (xy 348.264226 -224.71761) (xy 348.241366 -224.713292) (xy 348.216548 -224.708169)
			(xy 348.168805 -224.691172) (xy 348.124226 -224.667071) (xy 348.08386 -224.636431) (xy 348.048657 -224.599976)
			(xy 348.019448 -224.558564) (xy 347.996919 -224.51317) (xy 347.981601 -224.464863) (xy 347.973855 -224.414781)
			(xy 347.973396 -224.389442) (xy 347.692472 -224.389442) (xy 347.691964 -224.415329) (xy 347.683865 -224.466467)
			(xy 347.667866 -224.515707) (xy 347.64436 -224.561839) (xy 347.613928 -224.603726) (xy 347.577318 -224.640336)
			(xy 347.535431 -224.670768) (xy 347.489299 -224.694274) (xy 347.440059 -224.710273) (xy 347.388921 -224.718372)
			(xy 347.337147 -224.718372) (xy 347.286009 -224.710273) (xy 347.236769 -224.694274) (xy 347.190637 -224.670768)
			(xy 347.14875 -224.640336) (xy 347.11214 -224.603726) (xy 347.081708 -224.561839) (xy 347.058202 -224.515707)
			(xy 347.042203 -224.466467) (xy 347.034104 -224.415329) (xy 347.033596 -224.389442) (xy 346.752672 -224.389442)
			(xy 346.752125 -224.417149) (xy 346.742941 -224.471796) (xy 346.734384 -224.498154) (xy 346.72651 -224.520252)
			(xy 346.931488 -224.87509) (xy 346.954348 -224.879408) (xy 346.979171 -224.884565) (xy 347.026951 -224.90152)
			(xy 347.071571 -224.925592) (xy 347.111978 -224.956214) (xy 347.147219 -224.992662) (xy 347.176463 -225.034077)
			(xy 347.199019 -225.079482) (xy 347.214356 -225.127806) (xy 347.222111 -225.177908) (xy 347.222572 -225.203258)
			(xy 347.222064 -225.229165) (xy 347.213958 -225.280342) (xy 347.197946 -225.329621) (xy 347.174423 -225.375788)
			(xy 347.143967 -225.417707) (xy 347.107329 -225.454345) (xy 347.06541 -225.484801) (xy 347.019243 -225.508324)
			(xy 346.969964 -225.524336) (xy 346.918787 -225.532442) (xy 346.866973 -225.532442) (xy 346.815796 -225.524336)
			(xy 346.766517 -225.508324) (xy 346.72035 -225.484801) (xy 346.678431 -225.454345) (xy 346.641793 -225.417707)
			(xy 346.611337 -225.375788) (xy 346.587814 -225.329621) (xy 346.571802 -225.280342) (xy 346.563696 -225.229165)
			(xy 346.563188 -225.203258) (xy 346.563797 -225.175541) (xy 346.57311 -225.120895) (xy 346.58173 -225.094546)
			(xy 346.589604 -225.072448) (xy 346.384626 -224.71761) (xy 346.361766 -224.713292) (xy 346.336948 -224.708169)
			(xy 346.289205 -224.691172) (xy 346.244626 -224.667071) (xy 346.20426 -224.636431) (xy 346.169057 -224.599976)
			(xy 346.139848 -224.558564) (xy 346.117319 -224.51317) (xy 346.102001 -224.464863) (xy 346.094255 -224.414781)
			(xy 346.093796 -224.389442) (xy 345.812872 -224.389442) (xy 345.812364 -224.415329) (xy 345.804265 -224.466467)
			(xy 345.788266 -224.515707) (xy 345.76476 -224.561839) (xy 345.734328 -224.603726) (xy 345.697718 -224.640336)
			(xy 345.655831 -224.670768) (xy 345.609699 -224.694274) (xy 345.560459 -224.710273) (xy 345.509321 -224.718372)
			(xy 345.457547 -224.718372) (xy 345.406409 -224.710273) (xy 345.357169 -224.694274) (xy 345.311037 -224.670768)
			(xy 345.26915 -224.640336) (xy 345.23254 -224.603726) (xy 345.202108 -224.561839) (xy 345.178602 -224.515707)
			(xy 345.162603 -224.466467) (xy 345.154504 -224.415329) (xy 345.153996 -224.389442) (xy 344.873072 -224.389442)
			(xy 344.872525 -224.417149) (xy 344.863341 -224.471796) (xy 344.854784 -224.498154) (xy 344.84691 -224.520252)
			(xy 345.051888 -224.87509) (xy 345.074748 -224.879408) (xy 345.099571 -224.884565) (xy 345.147351 -224.90152)
			(xy 345.191971 -224.925592) (xy 345.232378 -224.956214) (xy 345.267619 -224.992662) (xy 345.296863 -225.034077)
			(xy 345.319419 -225.079482) (xy 345.334756 -225.127806) (xy 345.342511 -225.177908) (xy 345.342972 -225.203258)
			(xy 345.342464 -225.229165) (xy 345.334358 -225.280342) (xy 345.318346 -225.329621) (xy 345.294823 -225.375788)
			(xy 345.264367 -225.417707) (xy 345.227729 -225.454345) (xy 345.18581 -225.484801) (xy 345.139643 -225.508324)
			(xy 345.090364 -225.524336) (xy 345.039187 -225.532442) (xy 344.987373 -225.532442) (xy 344.936196 -225.524336)
			(xy 344.886917 -225.508324) (xy 344.84075 -225.484801) (xy 344.798831 -225.454345) (xy 344.762193 -225.417707)
			(xy 344.731737 -225.375788) (xy 344.708214 -225.329621) (xy 344.692202 -225.280342) (xy 344.684096 -225.229165)
			(xy 344.683588 -225.203258) (xy 344.684197 -225.175541) (xy 344.69351 -225.120895) (xy 344.70213 -225.094546)
			(xy 344.710004 -225.072448) (xy 344.505026 -224.71761) (xy 344.482166 -224.713292) (xy 344.457348 -224.708169)
			(xy 344.409605 -224.691172) (xy 344.365026 -224.667071) (xy 344.32466 -224.636431) (xy 344.289457 -224.599976)
			(xy 344.260248 -224.558564) (xy 344.237719 -224.51317) (xy 344.222401 -224.464863) (xy 344.214655 -224.414781)
			(xy 344.214196 -224.389442) (xy 343.933272 -224.389442) (xy 343.932764 -224.415329) (xy 343.924665 -224.466467)
			(xy 343.908666 -224.515707) (xy 343.88516 -224.561839) (xy 343.854728 -224.603726) (xy 343.818118 -224.640336)
			(xy 343.776231 -224.670768) (xy 343.730099 -224.694274) (xy 343.680859 -224.710273) (xy 343.629721 -224.718372)
			(xy 343.577947 -224.718372) (xy 343.526809 -224.710273) (xy 343.477569 -224.694274) (xy 343.431437 -224.670768)
			(xy 343.38955 -224.640336) (xy 343.35294 -224.603726) (xy 343.322508 -224.561839) (xy 343.299002 -224.515707)
			(xy 343.283003 -224.466467) (xy 343.274904 -224.415329) (xy 343.274396 -224.389442) (xy 342.993472 -224.389442)
			(xy 342.992925 -224.417149) (xy 342.983741 -224.471796) (xy 342.975184 -224.498154) (xy 342.96731 -224.520252)
			(xy 343.172288 -224.87509) (xy 343.195148 -224.879408) (xy 343.219971 -224.884565) (xy 343.267751 -224.90152)
			(xy 343.312371 -224.925592) (xy 343.352778 -224.956214) (xy 343.388019 -224.992662) (xy 343.417263 -225.034077)
			(xy 343.439819 -225.079482) (xy 343.455156 -225.127806) (xy 343.462911 -225.177908) (xy 343.463372 -225.203258)
			(xy 343.462864 -225.229165) (xy 343.454758 -225.280342) (xy 343.438746 -225.329621) (xy 343.415223 -225.375788)
			(xy 343.384767 -225.417707) (xy 343.348129 -225.454345) (xy 343.30621 -225.484801) (xy 343.260043 -225.508324)
			(xy 343.210764 -225.524336) (xy 343.159587 -225.532442) (xy 343.107773 -225.532442) (xy 343.056596 -225.524336)
			(xy 343.007317 -225.508324) (xy 342.96115 -225.484801) (xy 342.919231 -225.454345) (xy 342.882593 -225.417707)
			(xy 342.852137 -225.375788) (xy 342.828614 -225.329621) (xy 342.812602 -225.280342) (xy 342.804496 -225.229165)
			(xy 342.803988 -225.203258) (xy 342.804597 -225.175541) (xy 342.81391 -225.120895) (xy 342.82253 -225.094546)
			(xy 342.830404 -225.072448) (xy 342.625426 -224.71761) (xy 342.602566 -224.713292) (xy 342.577748 -224.708169)
			(xy 342.530005 -224.691172) (xy 342.485426 -224.667071) (xy 342.44506 -224.636431) (xy 342.409857 -224.599976)
			(xy 342.380648 -224.558564) (xy 342.358119 -224.51317) (xy 342.342801 -224.464863) (xy 342.335055 -224.414781)
			(xy 342.334596 -224.389442) (xy 342.053672 -224.389442) (xy 342.053164 -224.415329) (xy 342.045065 -224.466467)
			(xy 342.029066 -224.515707) (xy 342.00556 -224.561839) (xy 341.975128 -224.603726) (xy 341.938518 -224.640336)
			(xy 341.896631 -224.670768) (xy 341.850499 -224.694274) (xy 341.801259 -224.710273) (xy 341.750121 -224.718372)
			(xy 341.698347 -224.718372) (xy 341.647209 -224.710273) (xy 341.597969 -224.694274) (xy 341.551837 -224.670768)
			(xy 341.50995 -224.640336) (xy 341.47334 -224.603726) (xy 341.442908 -224.561839) (xy 341.419402 -224.515707)
			(xy 341.403403 -224.466467) (xy 341.395304 -224.415329) (xy 341.394796 -224.389442) (xy 341.113872 -224.389442)
			(xy 341.113872 -224.38995) (xy 341.113311 -224.417593) (xy 341.104122 -224.472111) (xy 341.095584 -224.498408)
			(xy 341.087964 -224.520252) (xy 341.292688 -224.87509) (xy 341.315548 -224.879408) (xy 341.340371 -224.884565)
			(xy 341.388151 -224.90152) (xy 341.432771 -224.925592) (xy 341.473178 -224.956214) (xy 341.508419 -224.992662)
			(xy 341.537663 -225.034077) (xy 341.560219 -225.079482) (xy 341.575556 -225.127806) (xy 341.583311 -225.177908)
			(xy 341.583772 -225.203258) (xy 341.583264 -225.229165) (xy 341.575158 -225.280342) (xy 341.559146 -225.329621)
			(xy 341.535623 -225.375788) (xy 341.505167 -225.417707) (xy 341.468529 -225.454345) (xy 341.42661 -225.484801)
			(xy 341.380443 -225.508324) (xy 341.331164 -225.524336) (xy 341.279987 -225.532442) (xy 341.228173 -225.532442)
			(xy 341.176996 -225.524336) (xy 341.127717 -225.508324) (xy 341.08155 -225.484801) (xy 341.039631 -225.454345)
			(xy 341.002993 -225.417707) (xy 340.972537 -225.375788) (xy 340.949014 -225.329621) (xy 340.933002 -225.280342)
			(xy 340.924896 -225.229165) (xy 340.924388 -225.203258) (xy 340.924388 -225.20275) (xy 340.924995 -225.175096)
			(xy 340.93432 -225.120578) (xy 340.94293 -225.094292) (xy 340.95055 -225.072448) (xy 340.745826 -224.71761)
			(xy 340.722966 -224.713292) (xy 340.698148 -224.708169) (xy 340.650405 -224.691172) (xy 340.605826 -224.667071)
			(xy 340.56546 -224.636431) (xy 340.530257 -224.599976) (xy 340.501048 -224.558564) (xy 340.478519 -224.51317)
			(xy 340.463201 -224.464863) (xy 340.455455 -224.414781) (xy 340.454996 -224.389442) (xy 340.174072 -224.389442)
			(xy 340.173564 -224.415329) (xy 340.165465 -224.466467) (xy 340.149466 -224.515707) (xy 340.12596 -224.561839)
			(xy 340.095528 -224.603726) (xy 340.058918 -224.640336) (xy 340.017031 -224.670768) (xy 339.970899 -224.694274)
			(xy 339.921659 -224.710273) (xy 339.870521 -224.718372) (xy 339.818747 -224.718372) (xy 339.767609 -224.710273)
			(xy 339.718369 -224.694274) (xy 339.672237 -224.670768) (xy 339.63035 -224.640336) (xy 339.59374 -224.603726)
			(xy 339.563308 -224.561839) (xy 339.539802 -224.515707) (xy 339.523803 -224.466467) (xy 339.515704 -224.415329)
			(xy 339.515196 -224.389442) (xy 339.234272 -224.389442) (xy 339.234272 -224.38995) (xy 339.233711 -224.417593)
			(xy 339.224522 -224.472111) (xy 339.215984 -224.498408) (xy 339.208364 -224.520252) (xy 339.413088 -224.87509)
			(xy 339.435948 -224.879408) (xy 339.460771 -224.884565) (xy 339.508551 -224.90152) (xy 339.553171 -224.925592)
			(xy 339.593578 -224.956214) (xy 339.628819 -224.992662) (xy 339.658063 -225.034077) (xy 339.680619 -225.079482)
			(xy 339.695956 -225.127806) (xy 339.703711 -225.177908) (xy 339.704172 -225.203258) (xy 339.703664 -225.229165)
			(xy 339.695558 -225.280342) (xy 339.679546 -225.329621) (xy 339.656023 -225.375788) (xy 339.625567 -225.417707)
			(xy 339.588929 -225.454345) (xy 339.54701 -225.484801) (xy 339.500843 -225.508324) (xy 339.451564 -225.524336)
			(xy 339.400387 -225.532442) (xy 339.348573 -225.532442) (xy 339.297396 -225.524336) (xy 339.248117 -225.508324)
			(xy 339.20195 -225.484801) (xy 339.160031 -225.454345) (xy 339.123393 -225.417707) (xy 339.092937 -225.375788)
			(xy 339.069414 -225.329621) (xy 339.053402 -225.280342) (xy 339.045296 -225.229165) (xy 339.044788 -225.203258)
			(xy 339.044788 -225.20275) (xy 339.045395 -225.175096) (xy 339.05472 -225.120578) (xy 339.06333 -225.094292)
			(xy 339.07095 -225.072448) (xy 338.866226 -224.71761) (xy 338.843366 -224.713292) (xy 338.818548 -224.708169)
			(xy 338.770805 -224.691172) (xy 338.726226 -224.667071) (xy 338.68586 -224.636431) (xy 338.650657 -224.599976)
			(xy 338.621448 -224.558564) (xy 338.598919 -224.51317) (xy 338.583601 -224.464863) (xy 338.575855 -224.414781)
			(xy 338.575396 -224.389442) (xy 338.294472 -224.389442) (xy 338.293964 -224.415329) (xy 338.285865 -224.466467)
			(xy 338.269866 -224.515707) (xy 338.24636 -224.561839) (xy 338.215928 -224.603726) (xy 338.179318 -224.640336)
			(xy 338.137431 -224.670768) (xy 338.091299 -224.694274) (xy 338.042059 -224.710273) (xy 337.990921 -224.718372)
			(xy 337.939147 -224.718372) (xy 337.888009 -224.710273) (xy 337.838769 -224.694274) (xy 337.792637 -224.670768)
			(xy 337.75075 -224.640336) (xy 337.71414 -224.603726) (xy 337.683708 -224.561839) (xy 337.660202 -224.515707)
			(xy 337.644203 -224.466467) (xy 337.636104 -224.415329) (xy 337.635596 -224.389442) (xy 134.525004 -224.389442)
			(xy 134.524474 -224.41715) (xy 134.515275 -224.471796) (xy 134.506716 -224.498154) (xy 134.499096 -224.519998)
			(xy 134.704074 -224.87509) (xy 134.726934 -224.879408) (xy 134.751752 -224.884531) (xy 134.799495 -224.901528)
			(xy 134.844074 -224.925629) (xy 134.88444 -224.956269) (xy 134.919643 -224.992724) (xy 134.948852 -225.034136)
			(xy 134.971381 -225.07953) (xy 134.986699 -225.127837) (xy 134.994445 -225.177919) (xy 134.994904 -225.203258)
			(xy 134.994396 -225.229145) (xy 134.986297 -225.280283) (xy 134.970298 -225.329523) (xy 134.946792 -225.375655)
			(xy 134.91636 -225.417542) (xy 134.87975 -225.454152) (xy 134.837863 -225.484584) (xy 134.791731 -225.50809)
			(xy 134.742491 -225.524089) (xy 134.691353 -225.532188) (xy 134.639579 -225.532188) (xy 134.588441 -225.524089)
			(xy 134.539201 -225.50809) (xy 134.493069 -225.484584) (xy 134.451182 -225.454152) (xy 134.414572 -225.417542)
			(xy 134.38414 -225.375655) (xy 134.360634 -225.329523) (xy 134.344635 -225.280283) (xy 134.336536 -225.229145)
			(xy 134.336028 -225.203258) (xy 134.336028 -225.20275) (xy 134.336589 -225.175107) (xy 134.345778 -225.120589)
			(xy 134.354316 -225.094292) (xy 134.361936 -225.072448) (xy 134.157212 -224.71761) (xy 134.134352 -224.713292)
			(xy 134.109529 -224.708135) (xy 134.061749 -224.69118) (xy 134.017129 -224.667108) (xy 133.976722 -224.636486)
			(xy 133.941481 -224.600038) (xy 133.912237 -224.558623) (xy 133.889681 -224.513218) (xy 133.874344 -224.464894)
			(xy 133.866589 -224.414792) (xy 133.866128 -224.389442) (xy 133.585204 -224.389442) (xy 133.584696 -224.415329)
			(xy 133.576597 -224.466467) (xy 133.560598 -224.515707) (xy 133.537092 -224.561839) (xy 133.50666 -224.603726)
			(xy 133.47005 -224.640336) (xy 133.428163 -224.670768) (xy 133.382031 -224.694274) (xy 133.332791 -224.710273)
			(xy 133.281653 -224.718372) (xy 133.229879 -224.718372) (xy 133.178741 -224.710273) (xy 133.129501 -224.694274)
			(xy 133.083369 -224.670768) (xy 133.041482 -224.640336) (xy 133.004872 -224.603726) (xy 132.97444 -224.561839)
			(xy 132.950934 -224.515707) (xy 132.934935 -224.466467) (xy 132.926836 -224.415329) (xy 132.926328 -224.389442)
			(xy 132.645404 -224.389442) (xy 132.64486 -224.417149) (xy 132.635674 -224.471796) (xy 132.627116 -224.498154)
			(xy 132.619242 -224.520252) (xy 132.82422 -224.87509) (xy 132.84708 -224.879408) (xy 132.871909 -224.884542)
			(xy 132.919688 -224.901501) (xy 132.964308 -224.925578) (xy 133.004714 -224.956202) (xy 133.039954 -224.992654)
			(xy 133.069197 -225.034071) (xy 133.091752 -225.079478) (xy 133.107088 -225.127804) (xy 133.114843 -225.177908)
			(xy 133.115304 -225.203258) (xy 133.114796 -225.229165) (xy 133.10669 -225.280342) (xy 133.090678 -225.329621)
			(xy 133.067155 -225.375788) (xy 133.036699 -225.417707) (xy 133.000061 -225.454345) (xy 132.958142 -225.484801)
			(xy 132.911975 -225.508324) (xy 132.862696 -225.524336) (xy 132.811519 -225.532442) (xy 132.759705 -225.532442)
			(xy 132.708528 -225.524336) (xy 132.659249 -225.508324) (xy 132.613082 -225.484801) (xy 132.571163 -225.454345)
			(xy 132.534525 -225.417707) (xy 132.504069 -225.375788) (xy 132.480546 -225.329621) (xy 132.464534 -225.280342)
			(xy 132.456428 -225.229165) (xy 132.45592 -225.203258) (xy 132.456527 -225.175541) (xy 132.465842 -225.120895)
			(xy 132.474462 -225.094546) (xy 132.482336 -225.072448) (xy 132.277358 -224.71761) (xy 132.254498 -224.713292)
			(xy 132.229685 -224.708145) (xy 132.181943 -224.691153) (xy 132.137363 -224.667056) (xy 132.096996 -224.63642)
			(xy 132.061793 -224.599968) (xy 132.032582 -224.558558) (xy 132.010052 -224.513166) (xy 131.994734 -224.46486)
			(xy 131.986988 -224.41478) (xy 131.986528 -224.389442) (xy 131.705604 -224.389442) (xy 131.705096 -224.415329)
			(xy 131.696997 -224.466467) (xy 131.680998 -224.515707) (xy 131.657492 -224.561839) (xy 131.62706 -224.603726)
			(xy 131.59045 -224.640336) (xy 131.548563 -224.670768) (xy 131.502431 -224.694274) (xy 131.453191 -224.710273)
			(xy 131.402053 -224.718372) (xy 131.350279 -224.718372) (xy 131.299141 -224.710273) (xy 131.249901 -224.694274)
			(xy 131.203769 -224.670768) (xy 131.161882 -224.640336) (xy 131.125272 -224.603726) (xy 131.09484 -224.561839)
			(xy 131.071334 -224.515707) (xy 131.055335 -224.466467) (xy 131.047236 -224.415329) (xy 131.046728 -224.389442)
			(xy 130.765804 -224.389442) (xy 130.76526 -224.417149) (xy 130.756074 -224.471796) (xy 130.747516 -224.498154)
			(xy 130.739642 -224.520252) (xy 130.94462 -224.87509) (xy 130.96748 -224.879408) (xy 130.992309 -224.884542)
			(xy 131.040088 -224.901501) (xy 131.084708 -224.925578) (xy 131.125114 -224.956202) (xy 131.160354 -224.992654)
			(xy 131.189597 -225.034071) (xy 131.212152 -225.079478) (xy 131.227488 -225.127804) (xy 131.235243 -225.177908)
			(xy 131.235704 -225.203258) (xy 131.235196 -225.229165) (xy 131.22709 -225.280342) (xy 131.211078 -225.329621)
			(xy 131.187555 -225.375788) (xy 131.157099 -225.417707) (xy 131.120461 -225.454345) (xy 131.078542 -225.484801)
			(xy 131.032375 -225.508324) (xy 130.983096 -225.524336) (xy 130.931919 -225.532442) (xy 130.880105 -225.532442)
			(xy 130.828928 -225.524336) (xy 130.779649 -225.508324) (xy 130.733482 -225.484801) (xy 130.691563 -225.454345)
			(xy 130.654925 -225.417707) (xy 130.624469 -225.375788) (xy 130.600946 -225.329621) (xy 130.584934 -225.280342)
			(xy 130.576828 -225.229165) (xy 130.57632 -225.203258) (xy 130.576927 -225.175541) (xy 130.586242 -225.120895)
			(xy 130.594862 -225.094546) (xy 130.602736 -225.072448) (xy 130.397758 -224.71761) (xy 130.374898 -224.713292)
			(xy 130.350085 -224.708145) (xy 130.302343 -224.691153) (xy 130.257763 -224.667056) (xy 130.217396 -224.63642)
			(xy 130.182193 -224.599968) (xy 130.152982 -224.558558) (xy 130.130452 -224.513166) (xy 130.115134 -224.46486)
			(xy 130.107388 -224.41478) (xy 130.106928 -224.389442) (xy 129.826004 -224.389442) (xy 129.825496 -224.415329)
			(xy 129.817397 -224.466467) (xy 129.801398 -224.515707) (xy 129.777892 -224.561839) (xy 129.74746 -224.603726)
			(xy 129.71085 -224.640336) (xy 129.668963 -224.670768) (xy 129.622831 -224.694274) (xy 129.573591 -224.710273)
			(xy 129.522453 -224.718372) (xy 129.470679 -224.718372) (xy 129.419541 -224.710273) (xy 129.370301 -224.694274)
			(xy 129.324169 -224.670768) (xy 129.282282 -224.640336) (xy 129.245672 -224.603726) (xy 129.21524 -224.561839)
			(xy 129.191734 -224.515707) (xy 129.175735 -224.466467) (xy 129.167636 -224.415329) (xy 129.167128 -224.389442)
			(xy 128.886204 -224.389442) (xy 128.88566 -224.417149) (xy 128.876474 -224.471796) (xy 128.867916 -224.498154)
			(xy 128.860042 -224.520252) (xy 129.06502 -224.87509) (xy 129.08788 -224.879408) (xy 129.112709 -224.884542)
			(xy 129.160488 -224.901501) (xy 129.205108 -224.925578) (xy 129.245514 -224.956202) (xy 129.280754 -224.992654)
			(xy 129.309997 -225.034071) (xy 129.332552 -225.079478) (xy 129.347888 -225.127804) (xy 129.355643 -225.177908)
			(xy 129.356104 -225.203258) (xy 129.355596 -225.229165) (xy 129.34749 -225.280342) (xy 129.331478 -225.329621)
			(xy 129.307955 -225.375788) (xy 129.277499 -225.417707) (xy 129.240861 -225.454345) (xy 129.198942 -225.484801)
			(xy 129.152775 -225.508324) (xy 129.103496 -225.524336) (xy 129.052319 -225.532442) (xy 129.000505 -225.532442)
			(xy 128.949328 -225.524336) (xy 128.900049 -225.508324) (xy 128.853882 -225.484801) (xy 128.811963 -225.454345)
			(xy 128.775325 -225.417707) (xy 128.744869 -225.375788) (xy 128.721346 -225.329621) (xy 128.705334 -225.280342)
			(xy 128.697228 -225.229165) (xy 128.69672 -225.203258) (xy 128.697327 -225.175541) (xy 128.706642 -225.120895)
			(xy 128.715262 -225.094546) (xy 128.723136 -225.072448) (xy 128.518158 -224.71761) (xy 128.495298 -224.713292)
			(xy 128.470485 -224.708145) (xy 128.422743 -224.691153) (xy 128.378163 -224.667056) (xy 128.337796 -224.63642)
			(xy 128.302593 -224.599968) (xy 128.273382 -224.558558) (xy 128.250852 -224.513166) (xy 128.235534 -224.46486)
			(xy 128.227788 -224.41478) (xy 128.227328 -224.389442) (xy 127.946404 -224.389442) (xy 127.945896 -224.415329)
			(xy 127.937797 -224.466467) (xy 127.921798 -224.515707) (xy 127.898292 -224.561839) (xy 127.86786 -224.603726)
			(xy 127.83125 -224.640336) (xy 127.789363 -224.670768) (xy 127.743231 -224.694274) (xy 127.693991 -224.710273)
			(xy 127.642853 -224.718372) (xy 127.591079 -224.718372) (xy 127.539941 -224.710273) (xy 127.490701 -224.694274)
			(xy 127.444569 -224.670768) (xy 127.402682 -224.640336) (xy 127.366072 -224.603726) (xy 127.33564 -224.561839)
			(xy 127.312134 -224.515707) (xy 127.296135 -224.466467) (xy 127.288036 -224.415329) (xy 127.287528 -224.389442)
			(xy 127.006604 -224.389442) (xy 127.00606 -224.417149) (xy 126.996874 -224.471796) (xy 126.988316 -224.498154)
			(xy 126.980442 -224.520252) (xy 127.18542 -224.87509) (xy 127.20828 -224.879408) (xy 127.233109 -224.884542)
			(xy 127.280888 -224.901501) (xy 127.325508 -224.925578) (xy 127.365914 -224.956202) (xy 127.401154 -224.992654)
			(xy 127.430397 -225.034071) (xy 127.452952 -225.079478) (xy 127.468288 -225.127804) (xy 127.476043 -225.177908)
			(xy 127.476504 -225.203258) (xy 127.475996 -225.229165) (xy 127.46789 -225.280342) (xy 127.451878 -225.329621)
			(xy 127.428355 -225.375788) (xy 127.397899 -225.417707) (xy 127.361261 -225.454345) (xy 127.319342 -225.484801)
			(xy 127.273175 -225.508324) (xy 127.223896 -225.524336) (xy 127.172719 -225.532442) (xy 127.120905 -225.532442)
			(xy 127.069728 -225.524336) (xy 127.020449 -225.508324) (xy 126.974282 -225.484801) (xy 126.932363 -225.454345)
			(xy 126.895725 -225.417707) (xy 126.865269 -225.375788) (xy 126.841746 -225.329621) (xy 126.825734 -225.280342)
			(xy 126.817628 -225.229165) (xy 126.81712 -225.203258) (xy 126.817727 -225.175541) (xy 126.827042 -225.120895)
			(xy 126.835662 -225.094546) (xy 126.843536 -225.072448) (xy 126.638558 -224.71761) (xy 126.615698 -224.713292)
			(xy 126.590885 -224.708145) (xy 126.543143 -224.691153) (xy 126.498563 -224.667056) (xy 126.458196 -224.63642)
			(xy 126.422993 -224.599968) (xy 126.393782 -224.558558) (xy 126.371252 -224.513166) (xy 126.355934 -224.46486)
			(xy 126.348188 -224.41478) (xy 126.347728 -224.389442) (xy 126.066804 -224.389442) (xy 126.066296 -224.415329)
			(xy 126.058197 -224.466467) (xy 126.042198 -224.515707) (xy 126.018692 -224.561839) (xy 125.98826 -224.603726)
			(xy 125.95165 -224.640336) (xy 125.909763 -224.670768) (xy 125.863631 -224.694274) (xy 125.814391 -224.710273)
			(xy 125.763253 -224.718372) (xy 125.711479 -224.718372) (xy 125.660341 -224.710273) (xy 125.611101 -224.694274)
			(xy 125.564969 -224.670768) (xy 125.523082 -224.640336) (xy 125.486472 -224.603726) (xy 125.45604 -224.561839)
			(xy 125.432534 -224.515707) (xy 125.416535 -224.466467) (xy 125.408436 -224.415329) (xy 125.407928 -224.389442)
			(xy 125.127004 -224.389442) (xy 125.12646 -224.417149) (xy 125.117274 -224.471796) (xy 125.108716 -224.498154)
			(xy 125.100842 -224.520252) (xy 125.30582 -224.87509) (xy 125.32868 -224.879408) (xy 125.353509 -224.884542)
			(xy 125.401288 -224.901501) (xy 125.445908 -224.925578) (xy 125.486314 -224.956202) (xy 125.521554 -224.992654)
			(xy 125.550797 -225.034071) (xy 125.573352 -225.079478) (xy 125.588688 -225.127804) (xy 125.596443 -225.177908)
			(xy 125.596904 -225.203258) (xy 125.596396 -225.229165) (xy 125.58829 -225.280342) (xy 125.572278 -225.329621)
			(xy 125.548755 -225.375788) (xy 125.518299 -225.417707) (xy 125.481661 -225.454345) (xy 125.439742 -225.484801)
			(xy 125.393575 -225.508324) (xy 125.344296 -225.524336) (xy 125.293119 -225.532442) (xy 125.241305 -225.532442)
			(xy 125.190128 -225.524336) (xy 125.140849 -225.508324) (xy 125.094682 -225.484801) (xy 125.052763 -225.454345)
			(xy 125.016125 -225.417707) (xy 124.985669 -225.375788) (xy 124.962146 -225.329621) (xy 124.946134 -225.280342)
			(xy 124.938028 -225.229165) (xy 124.93752 -225.203258) (xy 124.938127 -225.175541) (xy 124.947442 -225.120895)
			(xy 124.956062 -225.094546) (xy 124.963936 -225.072448) (xy 124.758958 -224.71761) (xy 124.736098 -224.713292)
			(xy 124.711285 -224.708145) (xy 124.663543 -224.691153) (xy 124.618963 -224.667056) (xy 124.578596 -224.63642)
			(xy 124.543393 -224.599968) (xy 124.514182 -224.558558) (xy 124.491652 -224.513166) (xy 124.476334 -224.46486)
			(xy 124.468588 -224.41478) (xy 124.468128 -224.389442) (xy 124.187204 -224.389442) (xy 124.186696 -224.415329)
			(xy 124.178597 -224.466467) (xy 124.162598 -224.515707) (xy 124.139092 -224.561839) (xy 124.10866 -224.603726)
			(xy 124.07205 -224.640336) (xy 124.030163 -224.670768) (xy 123.984031 -224.694274) (xy 123.934791 -224.710273)
			(xy 123.883653 -224.718372) (xy 123.831879 -224.718372) (xy 123.780741 -224.710273) (xy 123.731501 -224.694274)
			(xy 123.685369 -224.670768) (xy 123.643482 -224.640336) (xy 123.606872 -224.603726) (xy 123.57644 -224.561839)
			(xy 123.552934 -224.515707) (xy 123.536935 -224.466467) (xy 123.528836 -224.415329) (xy 123.528328 -224.389442)
			(xy 123.247404 -224.389442) (xy 123.24686 -224.417149) (xy 123.237674 -224.471796) (xy 123.229116 -224.498154)
			(xy 123.221242 -224.520252) (xy 123.42622 -224.87509) (xy 123.44908 -224.879408) (xy 123.473909 -224.884542)
			(xy 123.521688 -224.901501) (xy 123.566308 -224.925578) (xy 123.606714 -224.956202) (xy 123.641954 -224.992654)
			(xy 123.671197 -225.034071) (xy 123.693752 -225.079478) (xy 123.709088 -225.127804) (xy 123.716843 -225.177908)
			(xy 123.717304 -225.203258) (xy 123.716796 -225.229165) (xy 123.70869 -225.280342) (xy 123.692678 -225.329621)
			(xy 123.669155 -225.375788) (xy 123.638699 -225.417707) (xy 123.602061 -225.454345) (xy 123.560142 -225.484801)
			(xy 123.513975 -225.508324) (xy 123.464696 -225.524336) (xy 123.413519 -225.532442) (xy 123.361705 -225.532442)
			(xy 123.310528 -225.524336) (xy 123.261249 -225.508324) (xy 123.215082 -225.484801) (xy 123.173163 -225.454345)
			(xy 123.136525 -225.417707) (xy 123.106069 -225.375788) (xy 123.082546 -225.329621) (xy 123.066534 -225.280342)
			(xy 123.058428 -225.229165) (xy 123.05792 -225.203258) (xy 123.058527 -225.175541) (xy 123.067842 -225.120895)
			(xy 123.076462 -225.094546) (xy 123.084336 -225.072448) (xy 122.879358 -224.71761) (xy 122.856498 -224.713292)
			(xy 122.831685 -224.708145) (xy 122.783943 -224.691153) (xy 122.739363 -224.667056) (xy 122.698996 -224.63642)
			(xy 122.663793 -224.599968) (xy 122.634582 -224.558558) (xy 122.612052 -224.513166) (xy 122.596734 -224.46486)
			(xy 122.588988 -224.41478) (xy 122.588528 -224.389442) (xy 122.307604 -224.389442) (xy 122.307096 -224.415329)
			(xy 122.298997 -224.466467) (xy 122.282998 -224.515707) (xy 122.259492 -224.561839) (xy 122.22906 -224.603726)
			(xy 122.19245 -224.640336) (xy 122.150563 -224.670768) (xy 122.104431 -224.694274) (xy 122.055191 -224.710273)
			(xy 122.004053 -224.718372) (xy 121.952279 -224.718372) (xy 121.901141 -224.710273) (xy 121.851901 -224.694274)
			(xy 121.805769 -224.670768) (xy 121.763882 -224.640336) (xy 121.727272 -224.603726) (xy 121.69684 -224.561839)
			(xy 121.673334 -224.515707) (xy 121.657335 -224.466467) (xy 121.649236 -224.415329) (xy 121.648728 -224.389442)
			(xy 121.367804 -224.389442) (xy 121.36726 -224.417149) (xy 121.358074 -224.471796) (xy 121.349516 -224.498154)
			(xy 121.341642 -224.520252) (xy 121.54662 -224.87509) (xy 121.56948 -224.879408) (xy 121.594309 -224.884542)
			(xy 121.642088 -224.901501) (xy 121.686708 -224.925578) (xy 121.727114 -224.956202) (xy 121.762354 -224.992654)
			(xy 121.791597 -225.034071) (xy 121.814152 -225.079478) (xy 121.829488 -225.127804) (xy 121.837243 -225.177908)
			(xy 121.837704 -225.203258) (xy 121.837196 -225.229165) (xy 121.82909 -225.280342) (xy 121.813078 -225.329621)
			(xy 121.789555 -225.375788) (xy 121.759099 -225.417707) (xy 121.722461 -225.454345) (xy 121.680542 -225.484801)
			(xy 121.634375 -225.508324) (xy 121.585096 -225.524336) (xy 121.533919 -225.532442) (xy 121.482105 -225.532442)
			(xy 121.430928 -225.524336) (xy 121.381649 -225.508324) (xy 121.335482 -225.484801) (xy 121.293563 -225.454345)
			(xy 121.256925 -225.417707) (xy 121.226469 -225.375788) (xy 121.202946 -225.329621) (xy 121.186934 -225.280342)
			(xy 121.178828 -225.229165) (xy 121.17832 -225.203258) (xy 121.178927 -225.175541) (xy 121.188242 -225.120895)
			(xy 121.196862 -225.094546) (xy 121.204736 -225.072448) (xy 120.999758 -224.71761) (xy 120.976898 -224.713292)
			(xy 120.952085 -224.708145) (xy 120.904343 -224.691153) (xy 120.859763 -224.667056) (xy 120.819396 -224.63642)
			(xy 120.784193 -224.599968) (xy 120.754982 -224.558558) (xy 120.732452 -224.513166) (xy 120.717134 -224.46486)
			(xy 120.709388 -224.41478) (xy 120.708928 -224.389442) (xy 120.428004 -224.389442) (xy 120.427496 -224.415329)
			(xy 120.419397 -224.466467) (xy 120.403398 -224.515707) (xy 120.379892 -224.561839) (xy 120.34946 -224.603726)
			(xy 120.31285 -224.640336) (xy 120.270963 -224.670768) (xy 120.224831 -224.694274) (xy 120.175591 -224.710273)
			(xy 120.124453 -224.718372) (xy 120.072679 -224.718372) (xy 120.021541 -224.710273) (xy 119.972301 -224.694274)
			(xy 119.926169 -224.670768) (xy 119.884282 -224.640336) (xy 119.847672 -224.603726) (xy 119.81724 -224.561839)
			(xy 119.793734 -224.515707) (xy 119.777735 -224.466467) (xy 119.769636 -224.415329) (xy 119.769128 -224.389442)
			(xy 119.488204 -224.389442) (xy 119.48766 -224.417149) (xy 119.478474 -224.471796) (xy 119.469916 -224.498154)
			(xy 119.462042 -224.520252) (xy 119.66702 -224.87509) (xy 119.68988 -224.879408) (xy 119.714709 -224.884542)
			(xy 119.762488 -224.901501) (xy 119.807108 -224.925578) (xy 119.847514 -224.956202) (xy 119.882754 -224.992654)
			(xy 119.911997 -225.034071) (xy 119.934552 -225.079478) (xy 119.949888 -225.127804) (xy 119.957643 -225.177908)
			(xy 119.958104 -225.203258) (xy 119.957596 -225.229165) (xy 119.94949 -225.280342) (xy 119.933478 -225.329621)
			(xy 119.909955 -225.375788) (xy 119.879499 -225.417707) (xy 119.842861 -225.454345) (xy 119.800942 -225.484801)
			(xy 119.754775 -225.508324) (xy 119.705496 -225.524336) (xy 119.654319 -225.532442) (xy 119.602505 -225.532442)
			(xy 119.551328 -225.524336) (xy 119.502049 -225.508324) (xy 119.455882 -225.484801) (xy 119.413963 -225.454345)
			(xy 119.377325 -225.417707) (xy 119.346869 -225.375788) (xy 119.323346 -225.329621) (xy 119.307334 -225.280342)
			(xy 119.299228 -225.229165) (xy 119.29872 -225.203258) (xy 119.299327 -225.175541) (xy 119.308642 -225.120895)
			(xy 119.317262 -225.094546) (xy 119.325136 -225.072448) (xy 119.120158 -224.71761) (xy 119.097298 -224.713292)
			(xy 119.072485 -224.708145) (xy 119.024743 -224.691153) (xy 118.980163 -224.667056) (xy 118.939796 -224.63642)
			(xy 118.904593 -224.599968) (xy 118.875382 -224.558558) (xy 118.852852 -224.513166) (xy 118.837534 -224.46486)
			(xy 118.829788 -224.41478) (xy 118.829328 -224.389442) (xy 118.548404 -224.389442) (xy 118.547896 -224.415329)
			(xy 118.539797 -224.466467) (xy 118.523798 -224.515707) (xy 118.500292 -224.561839) (xy 118.46986 -224.603726)
			(xy 118.43325 -224.640336) (xy 118.391363 -224.670768) (xy 118.345231 -224.694274) (xy 118.295991 -224.710273)
			(xy 118.244853 -224.718372) (xy 118.193079 -224.718372) (xy 118.141941 -224.710273) (xy 118.092701 -224.694274)
			(xy 118.046569 -224.670768) (xy 118.004682 -224.640336) (xy 117.968072 -224.603726) (xy 117.93764 -224.561839)
			(xy 117.914134 -224.515707) (xy 117.898135 -224.466467) (xy 117.890036 -224.415329) (xy 117.889528 -224.389442)
			(xy 117.608604 -224.389442) (xy 117.60806 -224.417149) (xy 117.598874 -224.471796) (xy 117.590316 -224.498154)
			(xy 117.582442 -224.520252) (xy 117.78742 -224.87509) (xy 117.81028 -224.879408) (xy 117.835109 -224.884542)
			(xy 117.882888 -224.901501) (xy 117.927508 -224.925578) (xy 117.967914 -224.956202) (xy 118.003154 -224.992654)
			(xy 118.032397 -225.034071) (xy 118.054952 -225.079478) (xy 118.070288 -225.127804) (xy 118.078043 -225.177908)
			(xy 118.078504 -225.203258) (xy 118.077996 -225.229165) (xy 118.06989 -225.280342) (xy 118.053878 -225.329621)
			(xy 118.030355 -225.375788) (xy 117.999899 -225.417707) (xy 117.963261 -225.454345) (xy 117.921342 -225.484801)
			(xy 117.875175 -225.508324) (xy 117.825896 -225.524336) (xy 117.774719 -225.532442) (xy 117.722905 -225.532442)
			(xy 117.671728 -225.524336) (xy 117.622449 -225.508324) (xy 117.576282 -225.484801) (xy 117.534363 -225.454345)
			(xy 117.497725 -225.417707) (xy 117.467269 -225.375788) (xy 117.443746 -225.329621) (xy 117.427734 -225.280342)
			(xy 117.419628 -225.229165) (xy 117.41912 -225.203258) (xy 117.419727 -225.175541) (xy 117.429042 -225.120895)
			(xy 117.437662 -225.094546) (xy 117.445536 -225.072448) (xy 117.240558 -224.71761) (xy 117.217698 -224.713292)
			(xy 117.192885 -224.708145) (xy 117.145143 -224.691153) (xy 117.100563 -224.667056) (xy 117.060196 -224.63642)
			(xy 117.024993 -224.599968) (xy 116.995782 -224.558558) (xy 116.973252 -224.513166) (xy 116.957934 -224.46486)
			(xy 116.950188 -224.41478) (xy 116.949728 -224.389442) (xy 116.668804 -224.389442) (xy 116.668296 -224.415329)
			(xy 116.660197 -224.466467) (xy 116.644198 -224.515707) (xy 116.620692 -224.561839) (xy 116.59026 -224.603726)
			(xy 116.55365 -224.640336) (xy 116.511763 -224.670768) (xy 116.465631 -224.694274) (xy 116.416391 -224.710273)
			(xy 116.365253 -224.718372) (xy 116.313479 -224.718372) (xy 116.262341 -224.710273) (xy 116.213101 -224.694274)
			(xy 116.166969 -224.670768) (xy 116.125082 -224.640336) (xy 116.088472 -224.603726) (xy 116.05804 -224.561839)
			(xy 116.034534 -224.515707) (xy 116.018535 -224.466467) (xy 116.010436 -224.415329) (xy 116.009928 -224.389442)
			(xy 115.729004 -224.389442) (xy 115.72846 -224.417149) (xy 115.719274 -224.471796) (xy 115.710716 -224.498154)
			(xy 115.702842 -224.520252) (xy 115.90782 -224.87509) (xy 115.93068 -224.879408) (xy 115.955509 -224.884542)
			(xy 116.003288 -224.901501) (xy 116.047908 -224.925578) (xy 116.088314 -224.956202) (xy 116.123554 -224.992654)
			(xy 116.152797 -225.034071) (xy 116.175352 -225.079478) (xy 116.190688 -225.127804) (xy 116.198443 -225.177908)
			(xy 116.198904 -225.203258) (xy 116.198396 -225.229165) (xy 116.19029 -225.280342) (xy 116.174278 -225.329621)
			(xy 116.150755 -225.375788) (xy 116.120299 -225.417707) (xy 116.083661 -225.454345) (xy 116.041742 -225.484801)
			(xy 115.995575 -225.508324) (xy 115.946296 -225.524336) (xy 115.895119 -225.532442) (xy 115.843305 -225.532442)
			(xy 115.792128 -225.524336) (xy 115.742849 -225.508324) (xy 115.696682 -225.484801) (xy 115.654763 -225.454345)
			(xy 115.618125 -225.417707) (xy 115.587669 -225.375788) (xy 115.564146 -225.329621) (xy 115.548134 -225.280342)
			(xy 115.540028 -225.229165) (xy 115.53952 -225.203258) (xy 115.540127 -225.175541) (xy 115.549442 -225.120895)
			(xy 115.558062 -225.094546) (xy 115.565936 -225.072448) (xy 115.360958 -224.71761) (xy 115.338098 -224.713292)
			(xy 115.313285 -224.708145) (xy 115.265543 -224.691153) (xy 115.220963 -224.667056) (xy 115.180596 -224.63642)
			(xy 115.145393 -224.599968) (xy 115.116182 -224.558558) (xy 115.093652 -224.513166) (xy 115.078334 -224.46486)
			(xy 115.070588 -224.41478) (xy 115.070128 -224.389442) (xy 114.789204 -224.389442) (xy 114.788696 -224.415329)
			(xy 114.780597 -224.466467) (xy 114.764598 -224.515707) (xy 114.741092 -224.561839) (xy 114.71066 -224.603726)
			(xy 114.67405 -224.640336) (xy 114.632163 -224.670768) (xy 114.586031 -224.694274) (xy 114.536791 -224.710273)
			(xy 114.485653 -224.718372) (xy 114.433879 -224.718372) (xy 114.382741 -224.710273) (xy 114.333501 -224.694274)
			(xy 114.287369 -224.670768) (xy 114.245482 -224.640336) (xy 114.208872 -224.603726) (xy 114.17844 -224.561839)
			(xy 114.154934 -224.515707) (xy 114.138935 -224.466467) (xy 114.130836 -224.415329) (xy 114.130328 -224.389442)
			(xy 113.849404 -224.389442) (xy 113.84886 -224.417149) (xy 113.839674 -224.471796) (xy 113.831116 -224.498154)
			(xy 113.823242 -224.520252) (xy 114.02822 -224.87509) (xy 114.05108 -224.879408) (xy 114.075909 -224.884542)
			(xy 114.123688 -224.901501) (xy 114.168308 -224.925578) (xy 114.208714 -224.956202) (xy 114.243954 -224.992654)
			(xy 114.273197 -225.034071) (xy 114.295752 -225.079478) (xy 114.311088 -225.127804) (xy 114.318843 -225.177908)
			(xy 114.319304 -225.203258) (xy 114.318796 -225.229165) (xy 114.31069 -225.280342) (xy 114.294678 -225.329621)
			(xy 114.271155 -225.375788) (xy 114.240699 -225.417707) (xy 114.204061 -225.454345) (xy 114.162142 -225.484801)
			(xy 114.115975 -225.508324) (xy 114.066696 -225.524336) (xy 114.015519 -225.532442) (xy 113.963705 -225.532442)
			(xy 113.912528 -225.524336) (xy 113.863249 -225.508324) (xy 113.817082 -225.484801) (xy 113.775163 -225.454345)
			(xy 113.738525 -225.417707) (xy 113.708069 -225.375788) (xy 113.684546 -225.329621) (xy 113.668534 -225.280342)
			(xy 113.660428 -225.229165) (xy 113.65992 -225.203258) (xy 113.660527 -225.175541) (xy 113.669842 -225.120895)
			(xy 113.678462 -225.094546) (xy 113.686336 -225.072448) (xy 113.481358 -224.71761) (xy 113.458498 -224.713292)
			(xy 113.433685 -224.708145) (xy 113.385943 -224.691153) (xy 113.341363 -224.667056) (xy 113.300996 -224.63642)
			(xy 113.265793 -224.599968) (xy 113.236582 -224.558558) (xy 113.214052 -224.513166) (xy 113.198734 -224.46486)
			(xy 113.190988 -224.41478) (xy 113.190528 -224.389442) (xy 112.909604 -224.389442) (xy 112.909096 -224.415329)
			(xy 112.900997 -224.466467) (xy 112.884998 -224.515707) (xy 112.861492 -224.561839) (xy 112.83106 -224.603726)
			(xy 112.79445 -224.640336) (xy 112.752563 -224.670768) (xy 112.706431 -224.694274) (xy 112.657191 -224.710273)
			(xy 112.606053 -224.718372) (xy 112.554279 -224.718372) (xy 112.503141 -224.710273) (xy 112.453901 -224.694274)
			(xy 112.407769 -224.670768) (xy 112.365882 -224.640336) (xy 112.329272 -224.603726) (xy 112.29884 -224.561839)
			(xy 112.275334 -224.515707) (xy 112.259335 -224.466467) (xy 112.251236 -224.415329) (xy 112.250728 -224.389442)
			(xy 111.969804 -224.389442) (xy 111.96926 -224.417149) (xy 111.960074 -224.471796) (xy 111.951516 -224.498154)
			(xy 111.943642 -224.520252) (xy 112.14862 -224.87509) (xy 112.17148 -224.879408) (xy 112.196309 -224.884542)
			(xy 112.244088 -224.901501) (xy 112.288708 -224.925578) (xy 112.329114 -224.956202) (xy 112.364354 -224.992654)
			(xy 112.393597 -225.034071) (xy 112.416152 -225.079478) (xy 112.431488 -225.127804) (xy 112.439243 -225.177908)
			(xy 112.439704 -225.203258) (xy 112.439196 -225.229165) (xy 112.43109 -225.280342) (xy 112.415078 -225.329621)
			(xy 112.391555 -225.375788) (xy 112.361099 -225.417707) (xy 112.324461 -225.454345) (xy 112.282542 -225.484801)
			(xy 112.236375 -225.508324) (xy 112.187096 -225.524336) (xy 112.135919 -225.532442) (xy 112.084105 -225.532442)
			(xy 112.032928 -225.524336) (xy 111.983649 -225.508324) (xy 111.937482 -225.484801) (xy 111.895563 -225.454345)
			(xy 111.858925 -225.417707) (xy 111.828469 -225.375788) (xy 111.804946 -225.329621) (xy 111.788934 -225.280342)
			(xy 111.780828 -225.229165) (xy 111.78032 -225.203258) (xy 111.780927 -225.175541) (xy 111.790242 -225.120895)
			(xy 111.798862 -225.094546) (xy 111.806736 -225.072448) (xy 111.601758 -224.71761) (xy 111.578898 -224.713292)
			(xy 111.554085 -224.708145) (xy 111.506343 -224.691153) (xy 111.461763 -224.667056) (xy 111.421396 -224.63642)
			(xy 111.386193 -224.599968) (xy 111.356982 -224.558558) (xy 111.334452 -224.513166) (xy 111.319134 -224.46486)
			(xy 111.311388 -224.41478) (xy 111.310928 -224.389442) (xy 111.030004 -224.389442) (xy 111.029496 -224.415329)
			(xy 111.021397 -224.466467) (xy 111.005398 -224.515707) (xy 110.981892 -224.561839) (xy 110.95146 -224.603726)
			(xy 110.91485 -224.640336) (xy 110.872963 -224.670768) (xy 110.826831 -224.694274) (xy 110.777591 -224.710273)
			(xy 110.726453 -224.718372) (xy 110.674679 -224.718372) (xy 110.623541 -224.710273) (xy 110.574301 -224.694274)
			(xy 110.528169 -224.670768) (xy 110.486282 -224.640336) (xy 110.449672 -224.603726) (xy 110.41924 -224.561839)
			(xy 110.395734 -224.515707) (xy 110.379735 -224.466467) (xy 110.371636 -224.415329) (xy 110.371128 -224.389442)
			(xy 110.090204 -224.389442) (xy 110.08966 -224.417149) (xy 110.080474 -224.471796) (xy 110.071916 -224.498154)
			(xy 110.064042 -224.520252) (xy 110.26902 -224.87509) (xy 110.29188 -224.879408) (xy 110.316709 -224.884542)
			(xy 110.364488 -224.901501) (xy 110.409108 -224.925578) (xy 110.449514 -224.956202) (xy 110.484754 -224.992654)
			(xy 110.513997 -225.034071) (xy 110.536552 -225.079478) (xy 110.551888 -225.127804) (xy 110.559643 -225.177908)
			(xy 110.560104 -225.203258) (xy 110.559596 -225.229165) (xy 110.55149 -225.280342) (xy 110.535478 -225.329621)
			(xy 110.511955 -225.375788) (xy 110.481499 -225.417707) (xy 110.444861 -225.454345) (xy 110.402942 -225.484801)
			(xy 110.356775 -225.508324) (xy 110.307496 -225.524336) (xy 110.256319 -225.532442) (xy 110.204505 -225.532442)
			(xy 110.153328 -225.524336) (xy 110.104049 -225.508324) (xy 110.057882 -225.484801) (xy 110.015963 -225.454345)
			(xy 109.979325 -225.417707) (xy 109.948869 -225.375788) (xy 109.925346 -225.329621) (xy 109.909334 -225.280342)
			(xy 109.901228 -225.229165) (xy 109.90072 -225.203258) (xy 109.901327 -225.175541) (xy 109.910642 -225.120895)
			(xy 109.919262 -225.094546) (xy 109.927136 -225.072448) (xy 109.722158 -224.71761) (xy 109.699298 -224.713292)
			(xy 109.674485 -224.708145) (xy 109.626743 -224.691153) (xy 109.582163 -224.667056) (xy 109.541796 -224.63642)
			(xy 109.506593 -224.599968) (xy 109.477382 -224.558558) (xy 109.454852 -224.513166) (xy 109.439534 -224.46486)
			(xy 109.431788 -224.41478) (xy 109.431328 -224.389442) (xy 109.150404 -224.389442) (xy 109.149896 -224.415329)
			(xy 109.141797 -224.466467) (xy 109.125798 -224.515707) (xy 109.102292 -224.561839) (xy 109.07186 -224.603726)
			(xy 109.03525 -224.640336) (xy 108.993363 -224.670768) (xy 108.947231 -224.694274) (xy 108.897991 -224.710273)
			(xy 108.846853 -224.718372) (xy 108.795079 -224.718372) (xy 108.743941 -224.710273) (xy 108.694701 -224.694274)
			(xy 108.648569 -224.670768) (xy 108.606682 -224.640336) (xy 108.570072 -224.603726) (xy 108.53964 -224.561839)
			(xy 108.516134 -224.515707) (xy 108.500135 -224.466467) (xy 108.492036 -224.415329) (xy 108.491528 -224.389442)
			(xy 108.210604 -224.389442) (xy 108.21006 -224.417149) (xy 108.200874 -224.471796) (xy 108.192316 -224.498154)
			(xy 108.184442 -224.520252) (xy 108.38942 -224.87509) (xy 108.41228 -224.879408) (xy 108.437109 -224.884542)
			(xy 108.484888 -224.901501) (xy 108.529508 -224.925578) (xy 108.569914 -224.956202) (xy 108.605154 -224.992654)
			(xy 108.634397 -225.034071) (xy 108.656952 -225.079478) (xy 108.672288 -225.127804) (xy 108.680043 -225.177908)
			(xy 108.680504 -225.203258) (xy 108.679996 -225.229165) (xy 108.67189 -225.280342) (xy 108.655878 -225.329621)
			(xy 108.632355 -225.375788) (xy 108.601899 -225.417707) (xy 108.565261 -225.454345) (xy 108.523342 -225.484801)
			(xy 108.477175 -225.508324) (xy 108.427896 -225.524336) (xy 108.376719 -225.532442) (xy 108.324905 -225.532442)
			(xy 108.273728 -225.524336) (xy 108.224449 -225.508324) (xy 108.178282 -225.484801) (xy 108.136363 -225.454345)
			(xy 108.099725 -225.417707) (xy 108.069269 -225.375788) (xy 108.045746 -225.329621) (xy 108.029734 -225.280342)
			(xy 108.021628 -225.229165) (xy 108.02112 -225.203258) (xy 108.021727 -225.175541) (xy 108.031042 -225.120895)
			(xy 108.039662 -225.094546) (xy 108.047536 -225.072448) (xy 107.842558 -224.71761) (xy 107.819698 -224.713292)
			(xy 107.794885 -224.708145) (xy 107.747143 -224.691153) (xy 107.702563 -224.667056) (xy 107.662196 -224.63642)
			(xy 107.626993 -224.599968) (xy 107.597782 -224.558558) (xy 107.575252 -224.513166) (xy 107.559934 -224.46486)
			(xy 107.552188 -224.41478) (xy 107.551728 -224.389442) (xy 107.270804 -224.389442) (xy 107.270296 -224.415329)
			(xy 107.262197 -224.466467) (xy 107.246198 -224.515707) (xy 107.222692 -224.561839) (xy 107.19226 -224.603726)
			(xy 107.15565 -224.640336) (xy 107.113763 -224.670768) (xy 107.067631 -224.694274) (xy 107.018391 -224.710273)
			(xy 106.967253 -224.718372) (xy 106.915479 -224.718372) (xy 106.864341 -224.710273) (xy 106.815101 -224.694274)
			(xy 106.768969 -224.670768) (xy 106.727082 -224.640336) (xy 106.690472 -224.603726) (xy 106.66004 -224.561839)
			(xy 106.636534 -224.515707) (xy 106.620535 -224.466467) (xy 106.612436 -224.415329) (xy 106.611928 -224.389442)
			(xy 106.331004 -224.389442) (xy 106.33046 -224.417149) (xy 106.321274 -224.471796) (xy 106.312716 -224.498154)
			(xy 106.304842 -224.520252) (xy 106.50982 -224.87509) (xy 106.53268 -224.879408) (xy 106.557509 -224.884542)
			(xy 106.605288 -224.901501) (xy 106.649908 -224.925578) (xy 106.690314 -224.956202) (xy 106.725554 -224.992654)
			(xy 106.754797 -225.034071) (xy 106.777352 -225.079478) (xy 106.792688 -225.127804) (xy 106.800443 -225.177908)
			(xy 106.800904 -225.203258) (xy 106.800396 -225.229165) (xy 106.79229 -225.280342) (xy 106.776278 -225.329621)
			(xy 106.752755 -225.375788) (xy 106.722299 -225.417707) (xy 106.685661 -225.454345) (xy 106.643742 -225.484801)
			(xy 106.597575 -225.508324) (xy 106.548296 -225.524336) (xy 106.497119 -225.532442) (xy 106.445305 -225.532442)
			(xy 106.394128 -225.524336) (xy 106.344849 -225.508324) (xy 106.298682 -225.484801) (xy 106.256763 -225.454345)
			(xy 106.220125 -225.417707) (xy 106.189669 -225.375788) (xy 106.166146 -225.329621) (xy 106.150134 -225.280342)
			(xy 106.142028 -225.229165) (xy 106.14152 -225.203258) (xy 106.142127 -225.175541) (xy 106.151442 -225.120895)
			(xy 106.160062 -225.094546) (xy 106.167936 -225.072448) (xy 105.962958 -224.71761) (xy 105.940098 -224.713292)
			(xy 105.915285 -224.708145) (xy 105.867543 -224.691153) (xy 105.822963 -224.667056) (xy 105.782596 -224.63642)
			(xy 105.747393 -224.599968) (xy 105.718182 -224.558558) (xy 105.695652 -224.513166) (xy 105.680334 -224.46486)
			(xy 105.672588 -224.41478) (xy 105.672128 -224.389442) (xy 105.391204 -224.389442) (xy 105.390696 -224.415329)
			(xy 105.382597 -224.466467) (xy 105.366598 -224.515707) (xy 105.343092 -224.561839) (xy 105.31266 -224.603726)
			(xy 105.27605 -224.640336) (xy 105.234163 -224.670768) (xy 105.188031 -224.694274) (xy 105.138791 -224.710273)
			(xy 105.087653 -224.718372) (xy 105.035879 -224.718372) (xy 104.984741 -224.710273) (xy 104.935501 -224.694274)
			(xy 104.889369 -224.670768) (xy 104.847482 -224.640336) (xy 104.810872 -224.603726) (xy 104.78044 -224.561839)
			(xy 104.756934 -224.515707) (xy 104.740935 -224.466467) (xy 104.732836 -224.415329) (xy 104.732328 -224.389442)
			(xy 104.451404 -224.389442) (xy 104.45086 -224.417149) (xy 104.441674 -224.471796) (xy 104.433116 -224.498154)
			(xy 104.425242 -224.520252) (xy 104.63022 -224.87509) (xy 104.65308 -224.879408) (xy 104.677909 -224.884542)
			(xy 104.725688 -224.901501) (xy 104.770308 -224.925578) (xy 104.810714 -224.956202) (xy 104.845954 -224.992654)
			(xy 104.875197 -225.034071) (xy 104.897752 -225.079478) (xy 104.913088 -225.127804) (xy 104.920843 -225.177908)
			(xy 104.921304 -225.203258) (xy 104.920796 -225.229165) (xy 104.91269 -225.280342) (xy 104.896678 -225.329621)
			(xy 104.873155 -225.375788) (xy 104.842699 -225.417707) (xy 104.806061 -225.454345) (xy 104.764142 -225.484801)
			(xy 104.717975 -225.508324) (xy 104.668696 -225.524336) (xy 104.617519 -225.532442) (xy 104.565705 -225.532442)
			(xy 104.514528 -225.524336) (xy 104.465249 -225.508324) (xy 104.419082 -225.484801) (xy 104.377163 -225.454345)
			(xy 104.340525 -225.417707) (xy 104.310069 -225.375788) (xy 104.286546 -225.329621) (xy 104.270534 -225.280342)
			(xy 104.262428 -225.229165) (xy 104.26192 -225.203258) (xy 104.262527 -225.175541) (xy 104.271842 -225.120895)
			(xy 104.280462 -225.094546) (xy 104.288336 -225.072448) (xy 104.083358 -224.71761) (xy 104.060498 -224.713292)
			(xy 104.035685 -224.708145) (xy 103.987943 -224.691153) (xy 103.943363 -224.667056) (xy 103.902996 -224.63642)
			(xy 103.867793 -224.599968) (xy 103.838582 -224.558558) (xy 103.816052 -224.513166) (xy 103.800734 -224.46486)
			(xy 103.792988 -224.41478) (xy 103.792528 -224.389442) (xy 103.511604 -224.389442) (xy 103.511096 -224.415329)
			(xy 103.502997 -224.466467) (xy 103.486998 -224.515707) (xy 103.463492 -224.561839) (xy 103.43306 -224.603726)
			(xy 103.39645 -224.640336) (xy 103.354563 -224.670768) (xy 103.308431 -224.694274) (xy 103.259191 -224.710273)
			(xy 103.208053 -224.718372) (xy 103.156279 -224.718372) (xy 103.105141 -224.710273) (xy 103.055901 -224.694274)
			(xy 103.009769 -224.670768) (xy 102.967882 -224.640336) (xy 102.931272 -224.603726) (xy 102.90084 -224.561839)
			(xy 102.877334 -224.515707) (xy 102.861335 -224.466467) (xy 102.853236 -224.415329) (xy 102.852728 -224.389442)
			(xy 102.571804 -224.389442) (xy 102.57126 -224.417149) (xy 102.562074 -224.471796) (xy 102.553516 -224.498154)
			(xy 102.545642 -224.520252) (xy 102.75062 -224.87509) (xy 102.77348 -224.879408) (xy 102.798309 -224.884542)
			(xy 102.846088 -224.901501) (xy 102.890708 -224.925578) (xy 102.931114 -224.956202) (xy 102.966354 -224.992654)
			(xy 102.995597 -225.034071) (xy 103.018152 -225.079478) (xy 103.033488 -225.127804) (xy 103.041243 -225.177908)
			(xy 103.041704 -225.203258) (xy 103.041196 -225.229165) (xy 103.03309 -225.280342) (xy 103.017078 -225.329621)
			(xy 102.993555 -225.375788) (xy 102.963099 -225.417707) (xy 102.926461 -225.454345) (xy 102.884542 -225.484801)
			(xy 102.838375 -225.508324) (xy 102.789096 -225.524336) (xy 102.737919 -225.532442) (xy 102.686105 -225.532442)
			(xy 102.634928 -225.524336) (xy 102.585649 -225.508324) (xy 102.539482 -225.484801) (xy 102.497563 -225.454345)
			(xy 102.460925 -225.417707) (xy 102.430469 -225.375788) (xy 102.406946 -225.329621) (xy 102.390934 -225.280342)
			(xy 102.382828 -225.229165) (xy 102.38232 -225.203258) (xy 102.382927 -225.175541) (xy 102.392242 -225.120895)
			(xy 102.400862 -225.094546) (xy 102.408736 -225.072448) (xy 102.203758 -224.71761) (xy 102.180898 -224.713292)
			(xy 102.156085 -224.708145) (xy 102.108343 -224.691153) (xy 102.063763 -224.667056) (xy 102.023396 -224.63642)
			(xy 101.988193 -224.599968) (xy 101.958982 -224.558558) (xy 101.936452 -224.513166) (xy 101.921134 -224.46486)
			(xy 101.913388 -224.41478) (xy 101.912928 -224.389442) (xy 101.632004 -224.389442) (xy 101.631496 -224.415329)
			(xy 101.623397 -224.466467) (xy 101.607398 -224.515707) (xy 101.583892 -224.561839) (xy 101.55346 -224.603726)
			(xy 101.51685 -224.640336) (xy 101.474963 -224.670768) (xy 101.428831 -224.694274) (xy 101.379591 -224.710273)
			(xy 101.328453 -224.718372) (xy 101.276679 -224.718372) (xy 101.225541 -224.710273) (xy 101.176301 -224.694274)
			(xy 101.130169 -224.670768) (xy 101.088282 -224.640336) (xy 101.051672 -224.603726) (xy 101.02124 -224.561839)
			(xy 100.997734 -224.515707) (xy 100.981735 -224.466467) (xy 100.973636 -224.415329) (xy 100.973128 -224.389442)
			(xy 100.692204 -224.389442) (xy 100.69166 -224.417149) (xy 100.682474 -224.471796) (xy 100.673916 -224.498154)
			(xy 100.666042 -224.520252) (xy 100.87102 -224.87509) (xy 100.89388 -224.879408) (xy 100.918709 -224.884542)
			(xy 100.966488 -224.901501) (xy 101.011108 -224.925578) (xy 101.051514 -224.956202) (xy 101.086754 -224.992654)
			(xy 101.115997 -225.034071) (xy 101.138552 -225.079478) (xy 101.153888 -225.127804) (xy 101.161643 -225.177908)
			(xy 101.162104 -225.203258) (xy 101.161596 -225.229165) (xy 101.15349 -225.280342) (xy 101.137478 -225.329621)
			(xy 101.113955 -225.375788) (xy 101.083499 -225.417707) (xy 101.046861 -225.454345) (xy 101.004942 -225.484801)
			(xy 100.958775 -225.508324) (xy 100.909496 -225.524336) (xy 100.858319 -225.532442) (xy 100.806505 -225.532442)
			(xy 100.755328 -225.524336) (xy 100.706049 -225.508324) (xy 100.659882 -225.484801) (xy 100.617963 -225.454345)
			(xy 100.581325 -225.417707) (xy 100.550869 -225.375788) (xy 100.527346 -225.329621) (xy 100.511334 -225.280342)
			(xy 100.503228 -225.229165) (xy 100.50272 -225.203258) (xy 100.503327 -225.175541) (xy 100.512642 -225.120895)
			(xy 100.521262 -225.094546) (xy 100.529136 -225.072448) (xy 100.324158 -224.71761) (xy 100.301298 -224.713292)
			(xy 100.276485 -224.708145) (xy 100.228743 -224.691153) (xy 100.184163 -224.667056) (xy 100.143796 -224.63642)
			(xy 100.108593 -224.599968) (xy 100.079382 -224.558558) (xy 100.056852 -224.513166) (xy 100.041534 -224.46486)
			(xy 100.033788 -224.41478) (xy 100.033328 -224.389442) (xy 99.752404 -224.389442) (xy 99.751896 -224.415329)
			(xy 99.743797 -224.466467) (xy 99.727798 -224.515707) (xy 99.704292 -224.561839) (xy 99.67386 -224.603726)
			(xy 99.63725 -224.640336) (xy 99.595363 -224.670768) (xy 99.549231 -224.694274) (xy 99.499991 -224.710273)
			(xy 99.448853 -224.718372) (xy 99.397079 -224.718372) (xy 99.345941 -224.710273) (xy 99.296701 -224.694274)
			(xy 99.250569 -224.670768) (xy 99.208682 -224.640336) (xy 99.172072 -224.603726) (xy 99.14164 -224.561839)
			(xy 99.118134 -224.515707) (xy 99.102135 -224.466467) (xy 99.094036 -224.415329) (xy 99.093528 -224.389442)
			(xy 98.812604 -224.389442) (xy 98.81206 -224.417149) (xy 98.802874 -224.471796) (xy 98.794316 -224.498154)
			(xy 98.786442 -224.520252) (xy 98.99142 -224.87509) (xy 99.01428 -224.879408) (xy 99.039109 -224.884542)
			(xy 99.086888 -224.901501) (xy 99.131508 -224.925578) (xy 99.171914 -224.956202) (xy 99.207154 -224.992654)
			(xy 99.236397 -225.034071) (xy 99.258952 -225.079478) (xy 99.274288 -225.127804) (xy 99.282043 -225.177908)
			(xy 99.282504 -225.203258) (xy 99.281996 -225.229165) (xy 99.27389 -225.280342) (xy 99.257878 -225.329621)
			(xy 99.234355 -225.375788) (xy 99.203899 -225.417707) (xy 99.167261 -225.454345) (xy 99.125342 -225.484801)
			(xy 99.079175 -225.508324) (xy 99.029896 -225.524336) (xy 98.978719 -225.532442) (xy 98.926905 -225.532442)
			(xy 98.875728 -225.524336) (xy 98.826449 -225.508324) (xy 98.780282 -225.484801) (xy 98.738363 -225.454345)
			(xy 98.701725 -225.417707) (xy 98.671269 -225.375788) (xy 98.647746 -225.329621) (xy 98.631734 -225.280342)
			(xy 98.623628 -225.229165) (xy 98.62312 -225.203258) (xy 98.623727 -225.175541) (xy 98.633042 -225.120895)
			(xy 98.641662 -225.094546) (xy 98.649536 -225.072448) (xy 98.444558 -224.71761) (xy 98.421698 -224.713292)
			(xy 98.396885 -224.708145) (xy 98.349143 -224.691153) (xy 98.304563 -224.667056) (xy 98.264196 -224.63642)
			(xy 98.228993 -224.599968) (xy 98.199782 -224.558558) (xy 98.177252 -224.513166) (xy 98.161934 -224.46486)
			(xy 98.154188 -224.41478) (xy 98.153728 -224.389442) (xy 97.872804 -224.389442) (xy 97.872296 -224.415329)
			(xy 97.864197 -224.466467) (xy 97.848198 -224.515707) (xy 97.824692 -224.561839) (xy 97.79426 -224.603726)
			(xy 97.75765 -224.640336) (xy 97.715763 -224.670768) (xy 97.669631 -224.694274) (xy 97.620391 -224.710273)
			(xy 97.569253 -224.718372) (xy 97.517479 -224.718372) (xy 97.466341 -224.710273) (xy 97.417101 -224.694274)
			(xy 97.370969 -224.670768) (xy 97.329082 -224.640336) (xy 97.292472 -224.603726) (xy 97.26204 -224.561839)
			(xy 97.238534 -224.515707) (xy 97.222535 -224.466467) (xy 97.214436 -224.415329) (xy 97.213928 -224.389442)
			(xy 96.933004 -224.389442) (xy 96.93246 -224.417149) (xy 96.923274 -224.471796) (xy 96.914716 -224.498154)
			(xy 96.906842 -224.520252) (xy 97.11182 -224.87509) (xy 97.13468 -224.879408) (xy 97.159509 -224.884542)
			(xy 97.207288 -224.901501) (xy 97.251908 -224.925578) (xy 97.292314 -224.956202) (xy 97.327554 -224.992654)
			(xy 97.356797 -225.034071) (xy 97.379352 -225.079478) (xy 97.394688 -225.127804) (xy 97.402443 -225.177908)
			(xy 97.402904 -225.203258) (xy 97.402396 -225.229165) (xy 97.39429 -225.280342) (xy 97.378278 -225.329621)
			(xy 97.354755 -225.375788) (xy 97.324299 -225.417707) (xy 97.287661 -225.454345) (xy 97.245742 -225.484801)
			(xy 97.199575 -225.508324) (xy 97.150296 -225.524336) (xy 97.099119 -225.532442) (xy 97.047305 -225.532442)
			(xy 96.996128 -225.524336) (xy 96.946849 -225.508324) (xy 96.900682 -225.484801) (xy 96.858763 -225.454345)
			(xy 96.822125 -225.417707) (xy 96.791669 -225.375788) (xy 96.768146 -225.329621) (xy 96.752134 -225.280342)
			(xy 96.744028 -225.229165) (xy 96.74352 -225.203258) (xy 96.744127 -225.175541) (xy 96.753442 -225.120895)
			(xy 96.762062 -225.094546) (xy 96.769936 -225.072448) (xy 96.564958 -224.71761) (xy 96.542098 -224.713292)
			(xy 96.517285 -224.708145) (xy 96.469543 -224.691153) (xy 96.424963 -224.667056) (xy 96.384596 -224.63642)
			(xy 96.349393 -224.599968) (xy 96.320182 -224.558558) (xy 96.297652 -224.513166) (xy 96.282334 -224.46486)
			(xy 96.274588 -224.41478) (xy 96.274128 -224.389442) (xy 95.993204 -224.389442) (xy 95.992696 -224.415329)
			(xy 95.984597 -224.466467) (xy 95.968598 -224.515707) (xy 95.945092 -224.561839) (xy 95.91466 -224.603726)
			(xy 95.87805 -224.640336) (xy 95.836163 -224.670768) (xy 95.790031 -224.694274) (xy 95.740791 -224.710273)
			(xy 95.689653 -224.718372) (xy 95.637879 -224.718372) (xy 95.586741 -224.710273) (xy 95.537501 -224.694274)
			(xy 95.491369 -224.670768) (xy 95.449482 -224.640336) (xy 95.412872 -224.603726) (xy 95.38244 -224.561839)
			(xy 95.358934 -224.515707) (xy 95.342935 -224.466467) (xy 95.334836 -224.415329) (xy 95.334328 -224.389442)
			(xy 95.053404 -224.389442) (xy 95.05286 -224.417149) (xy 95.043674 -224.471796) (xy 95.035116 -224.498154)
			(xy 95.027242 -224.520252) (xy 95.23222 -224.87509) (xy 95.25508 -224.879408) (xy 95.279909 -224.884542)
			(xy 95.327688 -224.901501) (xy 95.372308 -224.925578) (xy 95.412714 -224.956202) (xy 95.447954 -224.992654)
			(xy 95.477197 -225.034071) (xy 95.499752 -225.079478) (xy 95.515088 -225.127804) (xy 95.522843 -225.177908)
			(xy 95.523304 -225.203258) (xy 95.522796 -225.229165) (xy 95.51469 -225.280342) (xy 95.498678 -225.329621)
			(xy 95.475155 -225.375788) (xy 95.444699 -225.417707) (xy 95.408061 -225.454345) (xy 95.366142 -225.484801)
			(xy 95.319975 -225.508324) (xy 95.270696 -225.524336) (xy 95.219519 -225.532442) (xy 95.167705 -225.532442)
			(xy 95.116528 -225.524336) (xy 95.067249 -225.508324) (xy 95.021082 -225.484801) (xy 94.979163 -225.454345)
			(xy 94.942525 -225.417707) (xy 94.912069 -225.375788) (xy 94.888546 -225.329621) (xy 94.872534 -225.280342)
			(xy 94.864428 -225.229165) (xy 94.86392 -225.203258) (xy 94.864527 -225.175541) (xy 94.873842 -225.120895)
			(xy 94.882462 -225.094546) (xy 94.890336 -225.072448) (xy 94.685358 -224.71761) (xy 94.662498 -224.713292)
			(xy 94.637685 -224.708145) (xy 94.589943 -224.691153) (xy 94.545363 -224.667056) (xy 94.504996 -224.63642)
			(xy 94.469793 -224.599968) (xy 94.440582 -224.558558) (xy 94.418052 -224.513166) (xy 94.402734 -224.46486)
			(xy 94.394988 -224.41478) (xy 94.394528 -224.389442) (xy 94.113604 -224.389442) (xy 94.113096 -224.415329)
			(xy 94.104997 -224.466467) (xy 94.088998 -224.515707) (xy 94.065492 -224.561839) (xy 94.03506 -224.603726)
			(xy 93.99845 -224.640336) (xy 93.956563 -224.670768) (xy 93.910431 -224.694274) (xy 93.861191 -224.710273)
			(xy 93.810053 -224.718372) (xy 93.758279 -224.718372) (xy 93.707141 -224.710273) (xy 93.657901 -224.694274)
			(xy 93.611769 -224.670768) (xy 93.569882 -224.640336) (xy 93.533272 -224.603726) (xy 93.50284 -224.561839)
			(xy 93.479334 -224.515707) (xy 93.463335 -224.466467) (xy 93.455236 -224.415329) (xy 93.454728 -224.389442)
			(xy 93.173804 -224.389442) (xy 93.173804 -224.38995) (xy 93.173247 -224.417593) (xy 93.164056 -224.472111)
			(xy 93.155516 -224.498408) (xy 93.147896 -224.520252) (xy 93.35262 -224.87509) (xy 93.37548 -224.879408)
			(xy 93.400309 -224.884542) (xy 93.448088 -224.901501) (xy 93.492708 -224.925578) (xy 93.533114 -224.956202)
			(xy 93.568354 -224.992654) (xy 93.597597 -225.034071) (xy 93.620152 -225.079478) (xy 93.635488 -225.127804)
			(xy 93.643243 -225.177908) (xy 93.643704 -225.203258) (xy 93.643196 -225.229165) (xy 93.63509 -225.280342)
			(xy 93.619078 -225.329621) (xy 93.595555 -225.375788) (xy 93.565099 -225.417707) (xy 93.528461 -225.454345)
			(xy 93.486542 -225.484801) (xy 93.440375 -225.508324) (xy 93.391096 -225.524336) (xy 93.339919 -225.532442)
			(xy 93.288105 -225.532442) (xy 93.236928 -225.524336) (xy 93.187649 -225.508324) (xy 93.141482 -225.484801)
			(xy 93.099563 -225.454345) (xy 93.062925 -225.417707) (xy 93.032469 -225.375788) (xy 93.008946 -225.329621)
			(xy 92.992934 -225.280342) (xy 92.984828 -225.229165) (xy 92.98432 -225.203258) (xy 92.98432 -225.20275)
			(xy 92.98493 -225.175096) (xy 92.994253 -225.120579) (xy 93.002862 -225.094292) (xy 93.010482 -225.072448)
			(xy 92.805758 -224.71761) (xy 92.782898 -224.713292) (xy 92.758085 -224.708145) (xy 92.710343 -224.691153)
			(xy 92.665763 -224.667056) (xy 92.625396 -224.63642) (xy 92.590193 -224.599968) (xy 92.560982 -224.558558)
			(xy 92.538452 -224.513166) (xy 92.523134 -224.46486) (xy 92.515388 -224.41478) (xy 92.514928 -224.389442)
			(xy 92.234004 -224.389442) (xy 92.233496 -224.415329) (xy 92.225397 -224.466467) (xy 92.209398 -224.515707)
			(xy 92.185892 -224.561839) (xy 92.15546 -224.603726) (xy 92.11885 -224.640336) (xy 92.076963 -224.670768)
			(xy 92.030831 -224.694274) (xy 91.981591 -224.710273) (xy 91.930453 -224.718372) (xy 91.878679 -224.718372)
			(xy 91.827541 -224.710273) (xy 91.778301 -224.694274) (xy 91.732169 -224.670768) (xy 91.690282 -224.640336)
			(xy 91.653672 -224.603726) (xy 91.62324 -224.561839) (xy 91.599734 -224.515707) (xy 91.583735 -224.466467)
			(xy 91.575636 -224.415329) (xy 91.575128 -224.389442) (xy 91.294204 -224.389442) (xy 91.294204 -224.38995)
			(xy 91.293647 -224.417593) (xy 91.284456 -224.472111) (xy 91.275916 -224.498408) (xy 91.268296 -224.520252)
			(xy 91.47302 -224.87509) (xy 91.49588 -224.879408) (xy 91.520709 -224.884542) (xy 91.568488 -224.901501)
			(xy 91.613108 -224.925578) (xy 91.653514 -224.956202) (xy 91.688754 -224.992654) (xy 91.717997 -225.034071)
			(xy 91.740552 -225.079478) (xy 91.755888 -225.127804) (xy 91.763643 -225.177908) (xy 91.764104 -225.203258)
			(xy 91.763596 -225.229165) (xy 91.75549 -225.280342) (xy 91.739478 -225.329621) (xy 91.715955 -225.375788)
			(xy 91.685499 -225.417707) (xy 91.648861 -225.454345) (xy 91.606942 -225.484801) (xy 91.560775 -225.508324)
			(xy 91.511496 -225.524336) (xy 91.460319 -225.532442) (xy 91.408505 -225.532442) (xy 91.357328 -225.524336)
			(xy 91.308049 -225.508324) (xy 91.261882 -225.484801) (xy 91.219963 -225.454345) (xy 91.183325 -225.417707)
			(xy 91.152869 -225.375788) (xy 91.129346 -225.329621) (xy 91.113334 -225.280342) (xy 91.105228 -225.229165)
			(xy 91.10472 -225.203258) (xy 91.10472 -225.20275) (xy 91.10533 -225.175096) (xy 91.114653 -225.120579)
			(xy 91.123262 -225.094292) (xy 91.130882 -225.072448) (xy 90.926158 -224.71761) (xy 90.903298 -224.713292)
			(xy 90.878485 -224.708145) (xy 90.830743 -224.691153) (xy 90.786163 -224.667056) (xy 90.745796 -224.63642)
			(xy 90.710593 -224.599968) (xy 90.681382 -224.558558) (xy 90.658852 -224.513166) (xy 90.643534 -224.46486)
			(xy 90.635788 -224.41478) (xy 90.635328 -224.389442) (xy 90.354404 -224.389442) (xy 90.353896 -224.415329)
			(xy 90.345797 -224.466467) (xy 90.329798 -224.515707) (xy 90.306292 -224.561839) (xy 90.27586 -224.603726)
			(xy 90.23925 -224.640336) (xy 90.197363 -224.670768) (xy 90.151231 -224.694274) (xy 90.101991 -224.710273)
			(xy 90.050853 -224.718372) (xy 89.999079 -224.718372) (xy 89.947941 -224.710273) (xy 89.898701 -224.694274)
			(xy 89.852569 -224.670768) (xy 89.810682 -224.640336) (xy 89.774072 -224.603726) (xy 89.74364 -224.561839)
			(xy 89.720134 -224.515707) (xy 89.704135 -224.466467) (xy 89.696036 -224.415329) (xy 89.695528 -224.389442)
			(xy 2.509012 -224.389442) (xy 2.509012 -247.620536) (xy 228.175312 -247.620536) (xy 228.175312 -246.756936)
			(xy 228.175798 -246.729685) (xy 228.183554 -246.675737) (xy 228.198909 -246.623442) (xy 228.221551 -246.573865)
			(xy 228.251017 -246.528015) (xy 228.286708 -246.486824) (xy 228.327899 -246.451133) (xy 228.373749 -246.421667)
			(xy 228.423326 -246.399025) (xy 228.475621 -246.38367) (xy 228.529569 -246.375914) (xy 228.584071 -246.375914)
			(xy 228.638019 -246.38367) (xy 228.690314 -246.399025) (xy 228.739891 -246.421667) (xy 228.785741 -246.451133)
			(xy 228.826932 -246.486824) (xy 228.862623 -246.528015) (xy 228.892089 -246.573865) (xy 228.914731 -246.623442)
			(xy 228.930086 -246.675737) (xy 228.937842 -246.729685) (xy 228.938328 -246.756936) (xy 228.938328 -247.620536)
			(xy 228.937842 -247.647787) (xy 228.930086 -247.701735) (xy 228.914731 -247.75403) (xy 228.892089 -247.803607)
			(xy 228.862623 -247.849457) (xy 228.826932 -247.890648) (xy 228.785741 -247.926339) (xy 228.739891 -247.955805)
			(xy 228.690314 -247.978447) (xy 228.638019 -247.993802) (xy 228.584071 -248.001558) (xy 228.529569 -248.001558)
			(xy 228.475621 -247.993802) (xy 228.423326 -247.978447) (xy 228.373749 -247.955805) (xy 228.327899 -247.926339)
			(xy 228.286708 -247.890648) (xy 228.251017 -247.849457) (xy 228.221551 -247.803607) (xy 228.198909 -247.75403)
			(xy 228.183554 -247.701735) (xy 228.175798 -247.647787) (xy 228.175312 -247.620536) (xy 2.509012 -247.620536)
			(xy 2.509012 -251.76988) (xy 75.695566 -251.76988) (xy 75.699547 -251.63686) (xy 75.711476 -251.504315)
			(xy 75.731311 -251.372722) (xy 75.75898 -251.24255) (xy 75.794384 -251.114265) (xy 75.837397 -250.988328)
			(xy 75.887864 -250.865189) (xy 75.945605 -250.745288) (xy 76.010414 -250.629055) (xy 76.082058 -250.516905)
			(xy 76.16028 -250.409241) (xy 76.244801 -250.306448) (xy 76.335319 -250.208893) (xy 76.431508 -250.116927)
			(xy 76.533026 -250.030877) (xy 76.639507 -249.951053) (xy 76.750572 -249.87774) (xy 76.865823 -249.8112)
			(xy 76.984847 -249.751671) (xy 77.107218 -249.699367) (xy 77.232497 -249.654475) (xy 77.360238 -249.617156)
			(xy 77.489981 -249.587543) (xy 77.621263 -249.565742) (xy 77.753614 -249.551832) (xy 77.88656 -249.545861)
			(xy 78.019625 -249.547852) (xy 78.152333 -249.557797) (xy 78.284209 -249.575661) (xy 78.41478 -249.601379)
			(xy 78.54358 -249.63486) (xy 78.670146 -249.675984) (xy 78.794027 -249.724604) (xy 78.914778 -249.780545)
			(xy 79.031968 -249.843607) (xy 79.145177 -249.913565) (xy 79.253999 -249.990169) (xy 79.358045 -250.073143)
			(xy 79.456943 -250.162191) (xy 79.550338 -250.256994) (xy 79.637896 -250.357212) (xy 79.719305 -250.462488)
			(xy 79.794271 -250.572444) (xy 79.862528 -250.686686) (xy 79.92383 -250.804806) (xy 79.977959 -250.926381)
			(xy 80.02472 -251.050975) (xy 80.063946 -251.178143) (xy 80.095496 -251.307429) (xy 80.119259 -251.43837)
			(xy 80.135148 -251.570498) (xy 80.143106 -251.70334) (xy 80.143604 -251.76988) (xy 143.715496 -251.76988)
			(xy 143.719477 -251.63686) (xy 143.731406 -251.504315) (xy 143.751241 -251.372722) (xy 143.77891 -251.24255)
			(xy 143.814314 -251.114265) (xy 143.857327 -250.988328) (xy 143.907794 -250.865189) (xy 143.965535 -250.745288)
			(xy 144.030344 -250.629055) (xy 144.101988 -250.516905) (xy 144.18021 -250.409241) (xy 144.264731 -250.306448)
			(xy 144.355249 -250.208893) (xy 144.451438 -250.116927) (xy 144.552956 -250.030877) (xy 144.659437 -249.951053)
			(xy 144.770502 -249.87774) (xy 144.885753 -249.8112) (xy 145.004777 -249.751671) (xy 145.127148 -249.699367)
			(xy 145.252427 -249.654475) (xy 145.380168 -249.617156) (xy 145.509911 -249.587543) (xy 145.641193 -249.565742)
			(xy 145.773544 -249.551832) (xy 145.90649 -249.545861) (xy 146.039555 -249.547852) (xy 146.172263 -249.557797)
			(xy 146.304139 -249.575661) (xy 146.43471 -249.601379) (xy 146.56351 -249.63486) (xy 146.690076 -249.675984)
			(xy 146.813957 -249.724604) (xy 146.934708 -249.780545) (xy 147.051898 -249.843607) (xy 147.165107 -249.913565)
			(xy 147.273929 -249.990169) (xy 147.377975 -250.073143) (xy 147.476873 -250.162191) (xy 147.570268 -250.256994)
			(xy 147.657826 -250.357212) (xy 147.739235 -250.462488) (xy 147.814201 -250.572444) (xy 147.882458 -250.686686)
			(xy 147.94376 -250.804806) (xy 147.997889 -250.926381) (xy 148.04465 -251.050975) (xy 148.083876 -251.178143)
			(xy 148.115426 -251.307429) (xy 148.139189 -251.43837) (xy 148.155078 -251.570498) (xy 148.163036 -251.70334)
			(xy 148.163534 -251.76988) (xy 323.635634 -251.76988) (xy 323.639615 -251.63686) (xy 323.651544 -251.504315)
			(xy 323.671379 -251.372722) (xy 323.699048 -251.24255) (xy 323.734452 -251.114265) (xy 323.777465 -250.988328)
			(xy 323.827932 -250.865189) (xy 323.885673 -250.745288) (xy 323.950482 -250.629055) (xy 324.022126 -250.516905)
			(xy 324.100348 -250.409241) (xy 324.184869 -250.306448) (xy 324.275387 -250.208893) (xy 324.371576 -250.116927)
			(xy 324.473094 -250.030877) (xy 324.579575 -249.951053) (xy 324.69064 -249.87774) (xy 324.805891 -249.8112)
			(xy 324.924915 -249.751671) (xy 325.047286 -249.699367) (xy 325.172565 -249.654475) (xy 325.300306 -249.617156)
			(xy 325.430049 -249.587543) (xy 325.561331 -249.565742) (xy 325.693682 -249.551832) (xy 325.826628 -249.545861)
			(xy 325.959693 -249.547852) (xy 326.092401 -249.557797) (xy 326.224277 -249.575661) (xy 326.354848 -249.601379)
			(xy 326.483648 -249.63486) (xy 326.610214 -249.675984) (xy 326.734095 -249.724604) (xy 326.854846 -249.780545)
			(xy 326.972036 -249.843607) (xy 327.085245 -249.913565) (xy 327.194067 -249.990169) (xy 327.298113 -250.073143)
			(xy 327.397011 -250.162191) (xy 327.490406 -250.256994) (xy 327.577964 -250.357212) (xy 327.659373 -250.462488)
			(xy 327.734339 -250.572444) (xy 327.802596 -250.686686) (xy 327.863898 -250.804806) (xy 327.918027 -250.926381)
			(xy 327.964788 -251.050975) (xy 328.004014 -251.178143) (xy 328.035564 -251.307429) (xy 328.059327 -251.43837)
			(xy 328.075216 -251.570498) (xy 328.083174 -251.70334) (xy 328.083672 -251.76988) (xy 391.655564 -251.76988)
			(xy 391.659545 -251.63686) (xy 391.671474 -251.504315) (xy 391.691309 -251.372722) (xy 391.718978 -251.24255)
			(xy 391.754382 -251.114265) (xy 391.797395 -250.988328) (xy 391.847862 -250.865189) (xy 391.905603 -250.745288)
			(xy 391.970412 -250.629055) (xy 392.042056 -250.516905) (xy 392.120278 -250.409241) (xy 392.204799 -250.306448)
			(xy 392.295317 -250.208893) (xy 392.391506 -250.116927) (xy 392.493024 -250.030877) (xy 392.599505 -249.951053)
			(xy 392.71057 -249.87774) (xy 392.825821 -249.8112) (xy 392.944845 -249.751671) (xy 393.067216 -249.699367)
			(xy 393.192495 -249.654475) (xy 393.320236 -249.617156) (xy 393.449979 -249.587543) (xy 393.581261 -249.565742)
			(xy 393.713612 -249.551832) (xy 393.846558 -249.545861) (xy 393.979623 -249.547852) (xy 394.112331 -249.557797)
			(xy 394.244207 -249.575661) (xy 394.374778 -249.601379) (xy 394.503578 -249.63486) (xy 394.630144 -249.675984)
			(xy 394.754025 -249.724604) (xy 394.874776 -249.780545) (xy 394.991966 -249.843607) (xy 395.105175 -249.913565)
			(xy 395.213997 -249.990169) (xy 395.318043 -250.073143) (xy 395.416941 -250.162191) (xy 395.510336 -250.256994)
			(xy 395.597894 -250.357212) (xy 395.679303 -250.462488) (xy 395.754269 -250.572444) (xy 395.822526 -250.686686)
			(xy 395.883828 -250.804806) (xy 395.937957 -250.926381) (xy 395.984718 -251.050975) (xy 396.023944 -251.178143)
			(xy 396.055494 -251.307429) (xy 396.079257 -251.43837) (xy 396.095146 -251.570498) (xy 396.103104 -251.70334)
			(xy 396.103602 -251.76988) (xy 396.103104 -251.83642) (xy 396.095146 -251.969262) (xy 396.079257 -252.10139)
			(xy 396.055494 -252.232331) (xy 396.023944 -252.361617) (xy 395.984718 -252.488785) (xy 395.937957 -252.613379)
			(xy 395.883828 -252.734954) (xy 395.822526 -252.853074) (xy 395.754269 -252.967316) (xy 395.679303 -253.077272)
			(xy 395.597894 -253.182548) (xy 395.510336 -253.282766) (xy 395.416941 -253.377569) (xy 395.318043 -253.466617)
			(xy 395.213997 -253.549591) (xy 395.105175 -253.626195) (xy 394.991966 -253.696153) (xy 394.874776 -253.759215)
			(xy 394.754025 -253.815156) (xy 394.630144 -253.863776) (xy 394.503578 -253.9049) (xy 394.374778 -253.938381)
			(xy 394.244207 -253.964099) (xy 394.112331 -253.981963) (xy 393.979623 -253.991908) (xy 393.846558 -253.993899)
			(xy 393.713612 -253.987928) (xy 393.581261 -253.974018) (xy 393.449979 -253.952217) (xy 393.320236 -253.922604)
			(xy 393.192495 -253.885285) (xy 393.067216 -253.840393) (xy 392.944845 -253.788089) (xy 392.825821 -253.72856)
			(xy 392.71057 -253.66202) (xy 392.599505 -253.588707) (xy 392.493024 -253.508883) (xy 392.391506 -253.422833)
			(xy 392.295317 -253.330867) (xy 392.204799 -253.233312) (xy 392.120278 -253.130519) (xy 392.042056 -253.022855)
			(xy 391.970412 -252.910705) (xy 391.905603 -252.794472) (xy 391.847862 -252.674571) (xy 391.797395 -252.551432)
			(xy 391.754382 -252.425495) (xy 391.718978 -252.29721) (xy 391.691309 -252.167038) (xy 391.671474 -252.035445)
			(xy 391.659545 -251.9029) (xy 391.655564 -251.76988) (xy 328.083672 -251.76988) (xy 328.083174 -251.83642)
			(xy 328.075216 -251.969262) (xy 328.059327 -252.10139) (xy 328.035564 -252.232331) (xy 328.004014 -252.361617)
			(xy 327.964788 -252.488785) (xy 327.918027 -252.613379) (xy 327.863898 -252.734954) (xy 327.802596 -252.853074)
			(xy 327.734339 -252.967316) (xy 327.659373 -253.077272) (xy 327.577964 -253.182548) (xy 327.490406 -253.282766)
			(xy 327.397011 -253.377569) (xy 327.298113 -253.466617) (xy 327.194067 -253.549591) (xy 327.085245 -253.626195)
			(xy 326.972036 -253.696153) (xy 326.854846 -253.759215) (xy 326.734095 -253.815156) (xy 326.610214 -253.863776)
			(xy 326.483648 -253.9049) (xy 326.354848 -253.938381) (xy 326.224277 -253.964099) (xy 326.092401 -253.981963)
			(xy 325.959693 -253.991908) (xy 325.826628 -253.993899) (xy 325.693682 -253.987928) (xy 325.561331 -253.974018)
			(xy 325.430049 -253.952217) (xy 325.300306 -253.922604) (xy 325.172565 -253.885285) (xy 325.047286 -253.840393)
			(xy 324.924915 -253.788089) (xy 324.805891 -253.72856) (xy 324.69064 -253.66202) (xy 324.579575 -253.588707)
			(xy 324.473094 -253.508883) (xy 324.371576 -253.422833) (xy 324.275387 -253.330867) (xy 324.184869 -253.233312)
			(xy 324.100348 -253.130519) (xy 324.022126 -253.022855) (xy 323.950482 -252.910705) (xy 323.885673 -252.794472)
			(xy 323.827932 -252.674571) (xy 323.777465 -252.551432) (xy 323.734452 -252.425495) (xy 323.699048 -252.29721)
			(xy 323.671379 -252.167038) (xy 323.651544 -252.035445) (xy 323.639615 -251.9029) (xy 323.635634 -251.76988)
			(xy 148.163534 -251.76988) (xy 148.163036 -251.83642) (xy 148.155078 -251.969262) (xy 148.139189 -252.10139)
			(xy 148.115426 -252.232331) (xy 148.083876 -252.361617) (xy 148.04465 -252.488785) (xy 147.997889 -252.613379)
			(xy 147.94376 -252.734954) (xy 147.882458 -252.853074) (xy 147.814201 -252.967316) (xy 147.739235 -253.077272)
			(xy 147.657826 -253.182548) (xy 147.570268 -253.282766) (xy 147.476873 -253.377569) (xy 147.377975 -253.466617)
			(xy 147.273929 -253.549591) (xy 147.165107 -253.626195) (xy 147.051898 -253.696153) (xy 146.934708 -253.759215)
			(xy 146.813957 -253.815156) (xy 146.690076 -253.863776) (xy 146.56351 -253.9049) (xy 146.43471 -253.938381)
			(xy 146.304139 -253.964099) (xy 146.172263 -253.981963) (xy 146.039555 -253.991908) (xy 145.90649 -253.993899)
			(xy 145.773544 -253.987928) (xy 145.641193 -253.974018) (xy 145.509911 -253.952217) (xy 145.380168 -253.922604)
			(xy 145.252427 -253.885285) (xy 145.127148 -253.840393) (xy 145.004777 -253.788089) (xy 144.885753 -253.72856)
			(xy 144.770502 -253.66202) (xy 144.659437 -253.588707) (xy 144.552956 -253.508883) (xy 144.451438 -253.422833)
			(xy 144.355249 -253.330867) (xy 144.264731 -253.233312) (xy 144.18021 -253.130519) (xy 144.101988 -253.022855)
			(xy 144.030344 -252.910705) (xy 143.965535 -252.794472) (xy 143.907794 -252.674571) (xy 143.857327 -252.551432)
			(xy 143.814314 -252.425495) (xy 143.77891 -252.29721) (xy 143.751241 -252.167038) (xy 143.731406 -252.035445)
			(xy 143.719477 -251.9029) (xy 143.715496 -251.76988) (xy 80.143604 -251.76988) (xy 80.143106 -251.83642)
			(xy 80.135148 -251.969262) (xy 80.119259 -252.10139) (xy 80.095496 -252.232331) (xy 80.063946 -252.361617)
			(xy 80.02472 -252.488785) (xy 79.977959 -252.613379) (xy 79.92383 -252.734954) (xy 79.862528 -252.853074)
			(xy 79.794271 -252.967316) (xy 79.719305 -253.077272) (xy 79.637896 -253.182548) (xy 79.550338 -253.282766)
			(xy 79.456943 -253.377569) (xy 79.358045 -253.466617) (xy 79.253999 -253.549591) (xy 79.145177 -253.626195)
			(xy 79.031968 -253.696153) (xy 78.914778 -253.759215) (xy 78.794027 -253.815156) (xy 78.670146 -253.863776)
			(xy 78.54358 -253.9049) (xy 78.41478 -253.938381) (xy 78.284209 -253.964099) (xy 78.152333 -253.981963)
			(xy 78.019625 -253.991908) (xy 77.88656 -253.993899) (xy 77.753614 -253.987928) (xy 77.621263 -253.974018)
			(xy 77.489981 -253.952217) (xy 77.360238 -253.922604) (xy 77.232497 -253.885285) (xy 77.107218 -253.840393)
			(xy 76.984847 -253.788089) (xy 76.865823 -253.72856) (xy 76.750572 -253.66202) (xy 76.639507 -253.588707)
			(xy 76.533026 -253.508883) (xy 76.431508 -253.422833) (xy 76.335319 -253.330867) (xy 76.244801 -253.233312)
			(xy 76.16028 -253.130519) (xy 76.082058 -253.022855) (xy 76.010414 -252.910705) (xy 75.945605 -252.794472)
			(xy 75.887864 -252.674571) (xy 75.837397 -252.551432) (xy 75.794384 -252.425495) (xy 75.75898 -252.29721)
			(xy 75.731311 -252.167038) (xy 75.711476 -252.035445) (xy 75.699547 -251.9029) (xy 75.695566 -251.76988)
			(xy 2.509012 -251.76988) (xy 2.509012 -273.453098) (xy 108.574078 -273.453098) (xy 108.574577 -273.426411)
			(xy 108.582532 -273.373632) (xy 108.598264 -273.322629) (xy 108.621422 -273.27454) (xy 108.651489 -273.23044)
			(xy 108.687793 -273.191313) (xy 108.729523 -273.158035) (xy 108.775747 -273.131348) (xy 108.825432 -273.111848)
			(xy 108.877469 -273.099971) (xy 108.930694 -273.095982) (xy 108.983919 -273.099971) (xy 109.035956 -273.111848)
			(xy 109.085641 -273.131348) (xy 109.131865 -273.158035) (xy 109.173595 -273.191313) (xy 109.209899 -273.23044)
			(xy 109.239966 -273.27454) (xy 109.263124 -273.322629) (xy 109.278856 -273.373632) (xy 109.286811 -273.426411)
			(xy 109.28731 -273.453098) (xy 356.514146 -273.453098) (xy 356.514645 -273.426411) (xy 356.5226 -273.373632)
			(xy 356.538332 -273.322629) (xy 356.56149 -273.27454) (xy 356.591557 -273.23044) (xy 356.627861 -273.191313)
			(xy 356.669591 -273.158035) (xy 356.715815 -273.131348) (xy 356.7655 -273.111848) (xy 356.817537 -273.099971)
			(xy 356.870762 -273.095982) (xy 356.923987 -273.099971) (xy 356.976024 -273.111848) (xy 357.025709 -273.131348)
			(xy 357.071933 -273.158035) (xy 357.113663 -273.191313) (xy 357.149967 -273.23044) (xy 357.180034 -273.27454)
			(xy 357.203192 -273.322629) (xy 357.218924 -273.373632) (xy 357.226879 -273.426411) (xy 357.227378 -273.453098)
			(xy 357.227378 -273.453606) (xy 357.226987 -273.476808) (xy 357.220923 -273.522815) (xy 357.208951 -273.567648)
			(xy 357.200454 -273.589242) (xy 357.190802 -273.612356) (xy 357.36276 -273.910044) (xy 357.387652 -273.913346)
			(xy 357.413032 -273.917185) (xy 357.462414 -273.93119) (xy 357.509279 -273.952127) (xy 357.55266 -273.979564)
			(xy 357.591661 -274.012935) (xy 357.625478 -274.05155) (xy 357.653412 -274.094613) (xy 357.674886 -274.141234)
			(xy 357.689458 -274.190452) (xy 357.696826 -274.241249) (xy 357.697278 -274.266914) (xy 357.696779 -274.293601)
			(xy 357.688824 -274.34638) (xy 357.673092 -274.397383) (xy 357.649934 -274.445472) (xy 357.619867 -274.489572)
			(xy 357.583563 -274.528699) (xy 357.541833 -274.561977) (xy 357.495609 -274.588664) (xy 357.445924 -274.608164)
			(xy 357.393887 -274.620041) (xy 357.340662 -274.62403) (xy 357.287437 -274.620041) (xy 357.2354 -274.608164)
			(xy 357.185715 -274.588664) (xy 357.139491 -274.561977) (xy 357.097761 -274.528699) (xy 357.061457 -274.489572)
			(xy 357.03139 -274.445472) (xy 357.008232 -274.397383) (xy 356.9925 -274.34638) (xy 356.984545 -274.293601)
			(xy 356.984046 -274.266914) (xy 356.984403 -274.243574) (xy 356.990507 -274.197295) (xy 357.002614 -274.152213)
			(xy 357.011224 -274.130516) (xy 357.020876 -274.107148) (xy 356.848918 -273.809968) (xy 356.824026 -273.806666)
			(xy 356.798627 -273.802862) (xy 356.749207 -273.788894) (xy 356.702301 -273.767982) (xy 356.658879 -273.740558)
			(xy 356.61984 -273.70719) (xy 356.58599 -273.668567) (xy 356.558031 -273.625489) (xy 356.536539 -273.578845)
			(xy 356.521959 -273.529602) (xy 356.514593 -273.478776) (xy 356.514146 -273.453098) (xy 109.28731 -273.453098)
			(xy 109.28731 -273.453606) (xy 109.286924 -273.476808) (xy 109.280859 -273.522815) (xy 109.268884 -273.567649)
			(xy 109.260386 -273.589242) (xy 109.250734 -273.612356) (xy 109.422692 -273.910044) (xy 109.447584 -273.913346)
			(xy 109.472955 -273.917239) (xy 109.522337 -273.931235) (xy 109.569202 -273.952163) (xy 109.612584 -273.979593)
			(xy 109.651587 -274.012957) (xy 109.685405 -274.051567) (xy 109.713341 -274.094625) (xy 109.734817 -274.141242)
			(xy 109.749389 -274.190456) (xy 109.756758 -274.241251) (xy 109.75721 -274.266914) (xy 351.345246 -274.266914)
			(xy 351.345745 -274.240227) (xy 351.3537 -274.187448) (xy 351.369432 -274.136445) (xy 351.39259 -274.088356)
			(xy 351.422657 -274.044256) (xy 351.458961 -274.005129) (xy 351.500691 -273.971851) (xy 351.546915 -273.945164)
			(xy 351.5966 -273.925664) (xy 351.648637 -273.913787) (xy 351.701862 -273.909798) (xy 351.755087 -273.913787)
			(xy 351.807124 -273.925664) (xy 351.856809 -273.945164) (xy 351.903033 -273.971851) (xy 351.944763 -274.005129)
			(xy 351.981067 -274.044256) (xy 352.011134 -274.088356) (xy 352.034292 -274.136445) (xy 352.050024 -274.187448)
			(xy 352.057979 -274.240227) (xy 352.058478 -274.266914) (xy 352.058478 -274.267422) (xy 352.058092 -274.290624)
			(xy 352.052026 -274.336631) (xy 352.040052 -274.381464) (xy 352.031554 -274.403058) (xy 352.021902 -274.426172)
			(xy 352.194114 -274.72386) (xy 352.219006 -274.727162) (xy 352.244383 -274.731022) (xy 352.293765 -274.745022)
			(xy 352.340632 -274.765954) (xy 352.384014 -274.793388) (xy 352.423017 -274.826756) (xy 352.456835 -274.865369)
			(xy 352.484769 -274.908431) (xy 352.506243 -274.955051) (xy 352.520814 -275.004268) (xy 352.528181 -275.055066)
			(xy 352.528632 -275.08073) (xy 352.528133 -275.107417) (xy 352.520178 -275.160196) (xy 352.504446 -275.211199)
			(xy 352.481288 -275.259288) (xy 352.451221 -275.303388) (xy 352.414917 -275.342515) (xy 352.373187 -275.375793)
			(xy 352.326963 -275.40248) (xy 352.277278 -275.42198) (xy 352.225241 -275.433857) (xy 352.172016 -275.437846)
			(xy 352.118791 -275.433857) (xy 352.066754 -275.42198) (xy 352.017069 -275.40248) (xy 351.970845 -275.375793)
			(xy 351.929115 -275.342515) (xy 351.892811 -275.303388) (xy 351.862744 -275.259288) (xy 351.839586 -275.211199)
			(xy 351.823854 -275.160196) (xy 351.815899 -275.107417) (xy 351.8154 -275.08073) (xy 351.815758 -275.05739)
			(xy 351.821861 -275.011111) (xy 351.833967 -274.966029) (xy 351.842578 -274.944332) (xy 351.85223 -274.920964)
			(xy 351.680526 -274.623784) (xy 351.655634 -274.620482) (xy 351.630212 -274.61668) (xy 351.580727 -274.602776)
			(xy 351.533752 -274.58191) (xy 351.49026 -274.554514) (xy 351.451152 -274.521158) (xy 351.41724 -274.482531)
			(xy 351.389226 -274.439435) (xy 351.36769 -274.392763) (xy 351.353079 -274.343482) (xy 351.345696 -274.292614)
			(xy 351.345246 -274.266914) (xy 109.75721 -274.266914) (xy 109.756711 -274.293601) (xy 109.748756 -274.34638)
			(xy 109.733024 -274.397383) (xy 109.709866 -274.445472) (xy 109.679799 -274.489572) (xy 109.643495 -274.528699)
			(xy 109.601765 -274.561977) (xy 109.555541 -274.588664) (xy 109.505856 -274.608164) (xy 109.453819 -274.620041)
			(xy 109.400594 -274.62403) (xy 109.347369 -274.620041) (xy 109.295332 -274.608164) (xy 109.245647 -274.588664)
			(xy 109.199423 -274.561977) (xy 109.157693 -274.528699) (xy 109.121389 -274.489572) (xy 109.091322 -274.445472)
			(xy 109.068164 -274.397383) (xy 109.052432 -274.34638) (xy 109.044477 -274.293601) (xy 109.043978 -274.266914)
			(xy 109.044332 -274.243574) (xy 109.050438 -274.197295) (xy 109.062545 -274.152213) (xy 109.071156 -274.130516)
			(xy 109.080808 -274.107148) (xy 108.90885 -273.809968) (xy 108.883958 -273.806666) (xy 108.858563 -273.802837)
			(xy 108.809143 -273.788873) (xy 108.762237 -273.767965) (xy 108.718815 -273.740544) (xy 108.679775 -273.707179)
			(xy 108.645925 -273.668559) (xy 108.617964 -273.625483) (xy 108.596471 -273.578842) (xy 108.581891 -273.5296)
			(xy 108.574525 -273.478776) (xy 108.574078 -273.453098) (xy 2.509012 -273.453098) (xy 2.509012 -274.266914)
			(xy 103.405178 -274.266914) (xy 103.405677 -274.240227) (xy 103.413632 -274.187448) (xy 103.429364 -274.136445)
			(xy 103.452522 -274.088356) (xy 103.482589 -274.044256) (xy 103.518893 -274.005129) (xy 103.560623 -273.971851)
			(xy 103.606847 -273.945164) (xy 103.656532 -273.925664) (xy 103.708569 -273.913787) (xy 103.761794 -273.909798)
			(xy 103.815019 -273.913787) (xy 103.867056 -273.925664) (xy 103.916741 -273.945164) (xy 103.962965 -273.971851)
			(xy 104.004695 -274.005129) (xy 104.040999 -274.044256) (xy 104.071066 -274.088356) (xy 104.094224 -274.136445)
			(xy 104.109956 -274.187448) (xy 104.117911 -274.240227) (xy 104.11841 -274.266914) (xy 104.11841 -274.267422)
			(xy 104.118029 -274.290624) (xy 104.111962 -274.336631) (xy 104.099985 -274.381465) (xy 104.091486 -274.403058)
			(xy 104.081834 -274.426172) (xy 104.254046 -274.72386) (xy 104.278938 -274.727162) (xy 104.304319 -274.730997)
			(xy 104.353702 -274.745001) (xy 104.400568 -274.765937) (xy 104.44395 -274.793374) (xy 104.482952 -274.826745)
			(xy 104.516769 -274.865361) (xy 104.544703 -274.908425) (xy 104.566176 -274.955048) (xy 104.580747 -275.004266)
			(xy 104.588113 -275.055065) (xy 104.588564 -275.08073) (xy 104.588065 -275.107417) (xy 104.58011 -275.160196)
			(xy 104.564378 -275.211199) (xy 104.54122 -275.259288) (xy 104.511153 -275.303388) (xy 104.474849 -275.342515)
			(xy 104.433119 -275.375793) (xy 104.386895 -275.40248) (xy 104.33721 -275.42198) (xy 104.285173 -275.433857)
			(xy 104.231948 -275.437846) (xy 104.178723 -275.433857) (xy 104.126686 -275.42198) (xy 104.077001 -275.40248)
			(xy 104.030777 -275.375793) (xy 103.989047 -275.342515) (xy 103.952743 -275.303388) (xy 103.922676 -275.259288)
			(xy 103.899518 -275.211199) (xy 103.883786 -275.160196) (xy 103.875831 -275.107417) (xy 103.875332 -275.08073)
			(xy 103.875695 -275.05739) (xy 103.881797 -275.011112) (xy 103.893901 -274.966029) (xy 103.90251 -274.944332)
			(xy 103.912162 -274.920964) (xy 103.740458 -274.623784) (xy 103.715566 -274.620482) (xy 103.690148 -274.616655)
			(xy 103.640663 -274.602755) (xy 103.593688 -274.581893) (xy 103.550196 -274.554501) (xy 103.511087 -274.521147)
			(xy 103.477174 -274.482523) (xy 103.449159 -274.439429) (xy 103.427623 -274.392759) (xy 103.413011 -274.34348)
			(xy 103.405628 -274.292614) (xy 103.405178 -274.266914) (xy 2.509012 -274.266914) (xy 2.509012 -275.0807)
			(xy 101.996207 -275.0807) (xy 102.000185 -275.027623) (xy 102.01203 -274.975731) (xy 102.031477 -274.926185)
			(xy 102.058092 -274.880091) (xy 102.091281 -274.838478) (xy 102.130301 -274.802278) (xy 102.174281 -274.772298)
			(xy 102.222239 -274.749209) (xy 102.273102 -274.733526) (xy 102.325735 -274.725599) (xy 102.352348 -274.72513)
			(xy 102.377317 -274.725593) (xy 102.426764 -274.73258) (xy 102.474749 -274.74641) (xy 102.52033 -274.766811)
			(xy 102.562611 -274.793384) (xy 102.600763 -274.825606) (xy 102.634037 -274.862844) (xy 102.648258 -274.883372)
			(xy 102.996238 -274.883372) (xy 103.010431 -274.862821) (xy 103.043701 -274.825569) (xy 103.081853 -274.793337)
			(xy 103.124139 -274.766758) (xy 103.169727 -274.746355) (xy 103.21772 -274.732527) (xy 103.267175 -274.725549)
			(xy 103.292148 -274.72513) (xy 103.318759 -274.725571) (xy 103.371386 -274.73351) (xy 103.422242 -274.749203)
			(xy 103.470192 -274.7723) (xy 103.514164 -274.802285) (xy 103.553176 -274.838488) (xy 103.586357 -274.880101)
			(xy 103.612967 -274.926194) (xy 103.632409 -274.975738) (xy 103.644252 -275.027626) (xy 103.648229 -275.0807)
			(xy 103.644252 -275.133774) (xy 103.632409 -275.185662) (xy 103.612967 -275.235206) (xy 103.586357 -275.281299)
			(xy 103.553176 -275.322912) (xy 103.514164 -275.359115) (xy 103.470192 -275.3891) (xy 103.422242 -275.412197)
			(xy 103.371386 -275.42789) (xy 103.318759 -275.435829) (xy 103.292148 -275.43633) (xy 103.267178 -275.435888)
			(xy 103.217729 -275.4289) (xy 103.169743 -275.415067) (xy 103.124162 -275.394663) (xy 103.08188 -275.368086)
			(xy 103.043729 -275.335861) (xy 103.010458 -275.298618) (xy 102.996238 -275.278088) (xy 102.648258 -275.278088)
			(xy 102.634055 -275.298632) (xy 102.600788 -275.335885) (xy 102.562638 -275.368119) (xy 102.520354 -275.3947)
			(xy 102.474768 -275.415105) (xy 102.426775 -275.428933) (xy 102.37732 -275.435912) (xy 102.352348 -275.43633)
			(xy 102.325735 -275.435801) (xy 102.273102 -275.427874) (xy 102.222239 -275.412191) (xy 102.174281 -275.389102)
			(xy 102.130301 -275.359122) (xy 102.091281 -275.322922) (xy 102.058092 -275.281309) (xy 102.031477 -275.235215)
			(xy 102.01203 -275.185669) (xy 102.000185 -275.133777) (xy 101.996207 -275.0807) (xy 2.509012 -275.0807)
			(xy 2.509012 -276.708616) (xy 101.995478 -276.708616) (xy 101.995889 -276.682946) (xy 102.003236 -276.632135)
			(xy 102.017794 -276.582903) (xy 102.039263 -276.536268) (xy 102.067199 -276.493195) (xy 102.101024 -276.454573)
			(xy 102.140038 -276.421202) (xy 102.183435 -276.393772) (xy 102.230317 -276.372849) (xy 102.279716 -276.358867)
			(xy 102.305104 -276.355048) (xy 102.329996 -276.351746) (xy 102.501954 -276.054058) (xy 102.492302 -276.030944)
			(xy 102.483799 -276.009352) (xy 102.47182 -275.964519) (xy 102.465765 -275.918511) (xy 102.465378 -275.895308)
			(xy 102.465378 -275.8948) (xy 102.465877 -275.868113) (xy 102.473832 -275.815334) (xy 102.489564 -275.764331)
			(xy 102.512722 -275.716242) (xy 102.542789 -275.672142) (xy 102.579093 -275.633015) (xy 102.620823 -275.599737)
			(xy 102.667047 -275.57305) (xy 102.716732 -275.55355) (xy 102.768769 -275.541673) (xy 102.821994 -275.537684)
			(xy 102.875219 -275.541673) (xy 102.927256 -275.55355) (xy 102.976941 -275.57305) (xy 103.023165 -275.599737)
			(xy 103.064895 -275.633015) (xy 103.101199 -275.672142) (xy 103.131266 -275.716242) (xy 103.154424 -275.764331)
			(xy 103.170156 -275.815334) (xy 103.178111 -275.868113) (xy 103.17861 -275.8948) (xy 104.344978 -275.8948)
			(xy 104.345374 -275.86913) (xy 104.352723 -275.818318) (xy 104.367284 -275.769086) (xy 104.388755 -275.722451)
			(xy 104.416692 -275.679378) (xy 104.450518 -275.640756) (xy 104.489534 -275.607385) (xy 104.532932 -275.579955)
			(xy 104.579816 -275.559033) (xy 104.629216 -275.545051) (xy 104.654604 -275.541232) (xy 104.679496 -275.53793)
			(xy 104.851708 -275.239988) (xy 104.842056 -275.216874) (xy 104.83356 -275.195279) (xy 104.821579 -275.150448)
			(xy 104.815521 -275.10444) (xy 104.815132 -275.081238) (xy 104.815132 -275.08073) (xy 104.815631 -275.054043)
			(xy 104.823586 -275.001264) (xy 104.839318 -274.950261) (xy 104.862476 -274.902172) (xy 104.892543 -274.858072)
			(xy 104.928847 -274.818945) (xy 104.970577 -274.785667) (xy 105.016801 -274.75898) (xy 105.066486 -274.73948)
			(xy 105.118523 -274.727603) (xy 105.171748 -274.723614) (xy 105.224973 -274.727603) (xy 105.27701 -274.73948)
			(xy 105.326695 -274.75898) (xy 105.372919 -274.785667) (xy 105.414649 -274.818945) (xy 105.450953 -274.858072)
			(xy 105.48102 -274.902172) (xy 105.504178 -274.950261) (xy 105.51991 -275.001264) (xy 105.527865 -275.054043)
			(xy 105.528364 -275.08073) (xy 107.634532 -275.08073) (xy 107.635031 -275.054043) (xy 107.642986 -275.001264)
			(xy 107.658718 -274.950261) (xy 107.681876 -274.902172) (xy 107.711943 -274.858072) (xy 107.748247 -274.818945)
			(xy 107.789977 -274.785667) (xy 107.836201 -274.75898) (xy 107.885886 -274.73948) (xy 107.937923 -274.727603)
			(xy 107.991148 -274.723614) (xy 108.044373 -274.727603) (xy 108.09641 -274.73948) (xy 108.146095 -274.75898)
			(xy 108.192319 -274.785667) (xy 108.234049 -274.818945) (xy 108.270353 -274.858072) (xy 108.30042 -274.902172)
			(xy 108.323578 -274.950261) (xy 108.33931 -275.001264) (xy 108.347265 -275.054043) (xy 108.347763 -275.0807)
			(xy 349.936307 -275.0807) (xy 349.940284 -275.027626) (xy 349.952128 -274.975737) (xy 349.971573 -274.926193)
			(xy 349.998186 -274.880101) (xy 350.031371 -274.83849) (xy 350.070387 -274.80229) (xy 350.114363 -274.772309)
			(xy 350.162316 -274.749218) (xy 350.213175 -274.733532) (xy 350.265804 -274.725602) (xy 350.292416 -274.72513)
			(xy 350.317387 -274.725541) (xy 350.366836 -274.732537) (xy 350.414822 -274.746376) (xy 350.460403 -274.766787)
			(xy 350.502684 -274.793367) (xy 350.540834 -274.825596) (xy 350.574106 -274.862841) (xy 350.588326 -274.883372)
			(xy 350.936306 -274.883372) (xy 350.95052 -274.862836) (xy 350.983786 -274.825584) (xy 351.021935 -274.793351)
			(xy 351.064217 -274.76677) (xy 351.109801 -274.746364) (xy 351.157792 -274.732533) (xy 351.207244 -274.725551)
			(xy 351.232216 -274.72513) (xy 351.258829 -274.725568) (xy 351.311459 -274.733503) (xy 351.36232 -274.749194)
			(xy 351.410274 -274.772289) (xy 351.45425 -274.802273) (xy 351.493266 -274.838477) (xy 351.526451 -274.880091)
			(xy 351.553063 -274.926186) (xy 351.572508 -274.975732) (xy 351.584351 -275.027623) (xy 351.588329 -275.0807)
			(xy 351.584351 -275.133777) (xy 351.572508 -275.185668) (xy 351.553063 -275.235214) (xy 351.526451 -275.281309)
			(xy 351.493266 -275.322923) (xy 351.45425 -275.359127) (xy 351.410274 -275.389111) (xy 351.36232 -275.412206)
			(xy 351.311459 -275.427897) (xy 351.258829 -275.435832) (xy 351.232216 -275.43633) (xy 351.207245 -275.435912)
			(xy 351.157795 -275.428919) (xy 351.109809 -275.415083) (xy 351.064227 -275.394674) (xy 351.021946 -275.368094)
			(xy 350.983796 -275.335865) (xy 350.950525 -275.298619) (xy 350.936306 -275.278088) (xy 350.588326 -275.278088)
			(xy 350.574079 -275.2986) (xy 350.54082 -275.335855) (xy 350.502677 -275.368091) (xy 350.460401 -275.394675)
			(xy 350.414821 -275.415085) (xy 350.366835 -275.42892) (xy 350.317386 -275.435907) (xy 350.292416 -275.43633)
			(xy 350.265804 -275.435798) (xy 350.213175 -275.427868) (xy 350.162316 -275.412182) (xy 350.114363 -275.389091)
			(xy 350.070387 -275.35911) (xy 350.031371 -275.32291) (xy 349.998186 -275.281299) (xy 349.971573 -275.235207)
			(xy 349.952128 -275.185663) (xy 349.940284 -275.133774) (xy 349.936307 -275.0807) (xy 108.347763 -275.0807)
			(xy 108.347764 -275.08073) (xy 108.347389 -275.104069) (xy 108.341292 -275.150348) (xy 108.329193 -275.195431)
			(xy 108.320586 -275.217128) (xy 108.310934 -275.240496) (xy 108.483146 -275.53793) (xy 108.507784 -275.541232)
			(xy 108.533184 -275.54503) (xy 108.582604 -275.558999) (xy 108.62951 -275.579913) (xy 108.672931 -275.607337)
			(xy 108.71197 -275.640706) (xy 108.745819 -275.679329) (xy 108.773779 -275.722408) (xy 108.795271 -275.769052)
			(xy 108.809851 -275.818296) (xy 108.817217 -275.869122) (xy 108.817664 -275.8948) (xy 108.817165 -275.921487)
			(xy 108.80921 -275.974266) (xy 108.793478 -276.025269) (xy 108.77032 -276.073358) (xy 108.740253 -276.117458)
			(xy 108.703949 -276.156585) (xy 108.662219 -276.189863) (xy 108.615995 -276.21655) (xy 108.56631 -276.23605)
			(xy 108.514273 -276.247927) (xy 108.461048 -276.251916) (xy 108.407823 -276.247927) (xy 108.355786 -276.23605)
			(xy 108.306101 -276.21655) (xy 108.259877 -276.189863) (xy 108.218147 -276.156585) (xy 108.181843 -276.117458)
			(xy 108.151776 -276.073358) (xy 108.128618 -276.025269) (xy 108.112886 -275.974266) (xy 108.104931 -275.921487)
			(xy 108.104432 -275.8948) (xy 108.104785 -275.87146) (xy 108.110891 -275.825181) (xy 108.122999 -275.780099)
			(xy 108.13161 -275.758402) (xy 108.141262 -275.735034) (xy 107.96905 -275.4376) (xy 107.944412 -275.434298)
			(xy 107.919017 -275.430474) (xy 107.869599 -275.416506) (xy 107.822695 -275.395594) (xy 107.779275 -275.368172)
			(xy 107.740237 -275.334806) (xy 107.706387 -275.296186) (xy 107.678427 -275.253111) (xy 107.656933 -275.206471)
			(xy 107.642351 -275.15723) (xy 107.634981 -275.106407) (xy 107.634532 -275.08073) (xy 105.528364 -275.08073)
			(xy 105.527862 -275.106429) (xy 105.520479 -275.157293) (xy 105.505871 -275.20657) (xy 105.484339 -275.25324)
			(xy 105.456331 -275.296335) (xy 105.422426 -275.334963) (xy 105.383327 -275.368324) (xy 105.339843 -275.395726)
			(xy 105.292876 -275.416601) (xy 105.243399 -275.430518) (xy 105.217976 -275.434298) (xy 105.193084 -275.4376)
			(xy 105.02138 -275.735034) (xy 105.031032 -275.758402) (xy 105.039597 -275.780114) (xy 105.051685 -275.825194)
			(xy 105.057807 -275.871464) (xy 105.05821 -275.8948) (xy 106.225101 -275.8948) (xy 106.229079 -275.841727)
			(xy 106.240922 -275.789839) (xy 106.260366 -275.740296) (xy 106.286976 -275.694204) (xy 106.320159 -275.652594)
			(xy 106.359174 -275.616393) (xy 106.403147 -275.586412) (xy 106.451098 -275.563319) (xy 106.501956 -275.547631)
			(xy 106.554583 -275.539698) (xy 106.581194 -275.5392) (xy 106.606141 -275.539565) (xy 106.655546 -275.54654)
			(xy 106.70349 -275.560353) (xy 106.749032 -275.580733) (xy 106.791278 -275.60728) (xy 106.829397 -275.639472)
			(xy 106.862642 -275.676678) (xy 106.87685 -275.697188) (xy 107.225338 -275.697188) (xy 107.239534 -275.676673)
			(xy 107.27279 -275.639483) (xy 107.310916 -275.607305) (xy 107.353165 -275.58077) (xy 107.398707 -275.5604)
			(xy 107.446648 -275.546593) (xy 107.496049 -275.539621) (xy 107.520994 -275.5392) (xy 107.547607 -275.539672)
			(xy 107.60024 -275.547605) (xy 107.651102 -275.563293) (xy 107.699058 -275.586386) (xy 107.743036 -275.61637)
			(xy 107.782055 -275.652573) (xy 107.815241 -275.694187) (xy 107.841855 -275.740282) (xy 107.861301 -275.78983)
			(xy 107.873145 -275.841722) (xy 107.877123 -275.8948) (xy 107.873145 -275.947878) (xy 107.861301 -275.99977)
			(xy 107.841855 -276.049318) (xy 107.815241 -276.095413) (xy 107.782055 -276.137027) (xy 107.743036 -276.17323)
			(xy 107.699058 -276.203214) (xy 107.651102 -276.226307) (xy 107.60024 -276.241995) (xy 107.547607 -276.249928)
			(xy 107.520994 -276.2504) (xy 107.496049 -276.249968) (xy 107.446648 -276.243006) (xy 107.398705 -276.229204)
			(xy 107.353163 -276.208835) (xy 107.310916 -276.182298) (xy 107.272795 -276.150115) (xy 107.239548 -276.112918)
			(xy 107.225338 -276.092412) (xy 106.87685 -276.092412) (xy 106.862661 -276.112933) (xy 106.829404 -276.150123)
			(xy 106.791277 -276.1823) (xy 106.749027 -276.208834) (xy 106.703484 -276.229204) (xy 106.655541 -276.243009)
			(xy 106.606139 -276.24998) (xy 106.581194 -276.2504) (xy 106.554583 -276.249902) (xy 106.501956 -276.241969)
			(xy 106.451098 -276.226281) (xy 106.403147 -276.203188) (xy 106.359174 -276.173207) (xy 106.320159 -276.137006)
			(xy 106.286976 -276.095396) (xy 106.260366 -276.049304) (xy 106.240922 -275.999761) (xy 106.229079 -275.947873)
			(xy 106.225101 -275.8948) (xy 105.05821 -275.8948) (xy 105.057711 -275.921487) (xy 105.049756 -275.974266)
			(xy 105.034024 -276.025269) (xy 105.010866 -276.073358) (xy 104.980799 -276.117458) (xy 104.944495 -276.156585)
			(xy 104.902765 -276.189863) (xy 104.856541 -276.21655) (xy 104.806856 -276.23605) (xy 104.754819 -276.247927)
			(xy 104.701594 -276.251916) (xy 104.648369 -276.247927) (xy 104.596332 -276.23605) (xy 104.546647 -276.21655)
			(xy 104.500423 -276.189863) (xy 104.458693 -276.156585) (xy 104.422389 -276.117458) (xy 104.392322 -276.073358)
			(xy 104.369164 -276.025269) (xy 104.353432 -275.974266) (xy 104.345477 -275.921487) (xy 104.344978 -275.8948)
			(xy 103.17861 -275.8948) (xy 103.178103 -275.920477) (xy 103.17075 -275.971301) (xy 103.156181 -276.020545)
			(xy 103.134698 -276.067189) (xy 103.106746 -276.110268) (xy 103.072902 -276.148892) (xy 103.033867 -276.182261)
			(xy 102.990448 -276.209684) (xy 102.943545 -276.230594) (xy 102.894127 -276.244559) (xy 102.86873 -276.248368)
			(xy 102.843838 -276.25167) (xy 102.67188 -276.54885) (xy 102.681532 -276.572218) (xy 102.690102 -276.593928)
			(xy 102.702188 -276.639009) (xy 102.708308 -276.68528) (xy 102.70871 -276.708616) (xy 102.935532 -276.708616)
			(xy 102.936031 -276.681929) (xy 102.943986 -276.62915) (xy 102.959718 -276.578147) (xy 102.982876 -276.530058)
			(xy 103.012943 -276.485958) (xy 103.049247 -276.446831) (xy 103.090977 -276.413553) (xy 103.137201 -276.386866)
			(xy 103.186886 -276.367366) (xy 103.238923 -276.355489) (xy 103.292148 -276.3515) (xy 103.345373 -276.355489)
			(xy 103.39741 -276.367366) (xy 103.447095 -276.386866) (xy 103.493319 -276.413553) (xy 103.535049 -276.446831)
			(xy 103.571353 -276.485958) (xy 103.60142 -276.530058) (xy 103.624578 -276.578147) (xy 103.64031 -276.62915)
			(xy 103.648265 -276.681929) (xy 103.648764 -276.7086) (xy 103.875793 -276.7086) (xy 103.879771 -276.65552)
			(xy 103.891617 -276.603627) (xy 103.911065 -276.554079) (xy 103.937681 -276.507983) (xy 103.970871 -276.466369)
			(xy 104.009892 -276.430167) (xy 104.053874 -276.400186) (xy 104.101834 -276.377096) (xy 104.152699 -276.361412)
			(xy 104.205334 -276.353485) (xy 104.231948 -276.353016) (xy 104.256892 -276.353453) (xy 104.306292 -276.360419)
			(xy 104.354233 -276.374223) (xy 104.399774 -276.394592) (xy 104.44202 -276.421127) (xy 104.480142 -276.453307)
			(xy 104.513392 -276.4905) (xy 104.527604 -276.511004) (xy 104.876092 -276.511004) (xy 104.890323 -276.490514)
			(xy 104.923572 -276.453323) (xy 104.961692 -276.421142) (xy 105.003935 -276.394605) (xy 105.049471 -276.37423)
			(xy 105.097408 -276.360418) (xy 105.146805 -276.35344) (xy 105.171748 -276.353016) (xy 105.198358 -276.353485)
			(xy 105.250983 -276.361423) (xy 105.301837 -276.377116) (xy 105.349785 -276.400212) (xy 105.393755 -276.430196)
			(xy 105.432766 -276.466397) (xy 105.465946 -276.508009) (xy 105.492554 -276.5541) (xy 105.511996 -276.603642)
			(xy 105.523838 -276.655528) (xy 105.527815 -276.7086) (xy 105.523838 -276.761672) (xy 105.511996 -276.813558)
			(xy 105.492554 -276.8631) (xy 105.465946 -276.909191) (xy 105.432766 -276.950803) (xy 105.393755 -276.987004)
			(xy 105.349785 -277.016988) (xy 105.301837 -277.040084) (xy 105.250983 -277.055777) (xy 105.198358 -277.063715)
			(xy 105.171748 -277.064216) (xy 105.146802 -277.063812) (xy 105.0974 -277.056844) (xy 105.049457 -277.043037)
			(xy 105.003915 -277.022663) (xy 104.961669 -276.996122) (xy 104.923548 -276.963935) (xy 104.890302 -276.926735)
			(xy 104.876092 -276.906228) (xy 104.527604 -276.906228) (xy 104.513386 -276.926727) (xy 104.480133 -276.963917)
			(xy 104.44201 -276.996095) (xy 104.399766 -277.022631) (xy 104.354227 -277.043005) (xy 104.306289 -277.056815)
			(xy 104.256892 -277.063793) (xy 104.231948 -277.064216) (xy 104.205334 -277.063715) (xy 104.152699 -277.055788)
			(xy 104.101834 -277.040104) (xy 104.053874 -277.017014) (xy 104.009892 -276.987033) (xy 103.970871 -276.950831)
			(xy 103.937681 -276.909217) (xy 103.911065 -276.863121) (xy 103.891617 -276.813573) (xy 103.879771 -276.76168)
			(xy 103.875793 -276.7086) (xy 103.648764 -276.7086) (xy 103.648764 -276.708616) (xy 103.648384 -276.731955)
			(xy 103.642289 -276.778233) (xy 103.630192 -276.823316) (xy 103.621586 -276.845014) (xy 103.611934 -276.868382)
			(xy 103.783892 -277.165562) (xy 103.808784 -277.168864) (xy 103.834158 -277.17274) (xy 103.883541 -277.186736)
			(xy 103.930408 -277.207666) (xy 103.973791 -277.235098) (xy 104.012794 -277.268464) (xy 104.046612 -277.307076)
			(xy 104.074547 -277.350136) (xy 104.096022 -277.396755) (xy 104.110592 -277.445972) (xy 104.117959 -277.496768)
			(xy 104.11841 -277.522432) (xy 106.224578 -277.522432) (xy 106.225004 -277.496763) (xy 106.232348 -277.445952)
			(xy 106.246905 -277.396721) (xy 106.268372 -277.350086) (xy 106.296306 -277.307012) (xy 106.330129 -277.26839)
			(xy 106.369142 -277.235019) (xy 106.412537 -277.207589) (xy 106.459419 -277.186666) (xy 106.508817 -277.172683)
			(xy 106.534204 -277.168864) (xy 106.559096 -277.165562) (xy 106.731308 -276.867874) (xy 106.721656 -276.84476)
			(xy 106.713156 -276.823167) (xy 106.701176 -276.778335) (xy 106.69512 -276.732326) (xy 106.694732 -276.709124)
			(xy 106.694732 -276.708616) (xy 106.695231 -276.681929) (xy 106.703186 -276.62915) (xy 106.718918 -276.578147)
			(xy 106.742076 -276.530058) (xy 106.772143 -276.485958) (xy 106.808447 -276.446831) (xy 106.850177 -276.413553)
			(xy 106.896401 -276.386866) (xy 106.946086 -276.367366) (xy 106.998123 -276.355489) (xy 107.051348 -276.3515)
			(xy 107.104573 -276.355489) (xy 107.15661 -276.367366) (xy 107.206295 -276.386866) (xy 107.252519 -276.413553)
			(xy 107.294249 -276.446831) (xy 107.330553 -276.485958) (xy 107.36062 -276.530058) (xy 107.383778 -276.578147)
			(xy 107.39951 -276.62915) (xy 107.407465 -276.681929) (xy 107.407964 -276.708616) (xy 108.574078 -276.708616)
			(xy 108.574489 -276.682946) (xy 108.581836 -276.632135) (xy 108.596394 -276.582903) (xy 108.617863 -276.536268)
			(xy 108.645799 -276.493195) (xy 108.679624 -276.454573) (xy 108.718638 -276.421202) (xy 108.762035 -276.393772)
			(xy 108.808917 -276.372849) (xy 108.858316 -276.358867) (xy 108.883704 -276.355048) (xy 108.908596 -276.351746)
			(xy 109.080554 -276.054566) (xy 109.070902 -276.031198) (xy 109.062339 -276.009486) (xy 109.05025 -275.964406)
			(xy 109.044128 -275.918136) (xy 109.043724 -275.8948) (xy 109.044223 -275.868113) (xy 109.052178 -275.815334)
			(xy 109.06791 -275.764331) (xy 109.091068 -275.716242) (xy 109.121135 -275.672142) (xy 109.157439 -275.633015)
			(xy 109.199169 -275.599737) (xy 109.245393 -275.57305) (xy 109.295078 -275.55355) (xy 109.347115 -275.541673)
			(xy 109.40034 -275.537684) (xy 109.453565 -275.541673) (xy 109.505602 -275.55355) (xy 109.555287 -275.57305)
			(xy 109.601511 -275.599737) (xy 109.643241 -275.633015) (xy 109.679545 -275.672142) (xy 109.709612 -275.716242)
			(xy 109.73277 -275.764331) (xy 109.748502 -275.815334) (xy 109.756457 -275.868113) (xy 109.756956 -275.8948)
			(xy 109.75653 -275.920469) (xy 109.749182 -275.971278) (xy 109.734623 -276.020508) (xy 109.713155 -276.067141)
			(xy 109.685221 -276.110213) (xy 109.651398 -276.148834) (xy 109.612386 -276.182205) (xy 109.568992 -276.209637)
			(xy 109.522113 -276.230561) (xy 109.472717 -276.244547) (xy 109.44733 -276.248368) (xy 109.422438 -276.25167)
			(xy 109.25048 -276.54885) (xy 109.260132 -276.572218) (xy 109.268702 -276.593928) (xy 109.280788 -276.639009)
			(xy 109.286908 -276.68528) (xy 109.28731 -276.708616) (xy 349.935546 -276.708616) (xy 349.935985 -276.682947)
			(xy 349.943331 -276.632139) (xy 349.957888 -276.582909) (xy 349.979354 -276.536276) (xy 350.007287 -276.493204)
			(xy 350.041108 -276.454583) (xy 350.080119 -276.421211) (xy 350.123512 -276.39378) (xy 350.170391 -276.372855)
			(xy 350.219786 -276.358869) (xy 350.245172 -276.355048) (xy 350.270064 -276.351746) (xy 350.442022 -276.054058)
			(xy 350.43237 -276.030944) (xy 350.423866 -276.009353) (xy 350.411887 -275.96452) (xy 350.405833 -275.918511)
			(xy 350.405446 -275.895308) (xy 350.405446 -275.8948) (xy 350.405945 -275.868113) (xy 350.4139 -275.815334)
			(xy 350.429632 -275.764331) (xy 350.45279 -275.716242) (xy 350.482857 -275.672142) (xy 350.519161 -275.633015)
			(xy 350.560891 -275.599737) (xy 350.607115 -275.57305) (xy 350.6568 -275.55355) (xy 350.708837 -275.541673)
			(xy 350.762062 -275.537684) (xy 350.815287 -275.541673) (xy 350.867324 -275.55355) (xy 350.917009 -275.57305)
			(xy 350.963233 -275.599737) (xy 351.004963 -275.633015) (xy 351.041267 -275.672142) (xy 351.071334 -275.716242)
			(xy 351.094492 -275.764331) (xy 351.110224 -275.815334) (xy 351.118179 -275.868113) (xy 351.118678 -275.8948)
			(xy 352.285046 -275.8948) (xy 352.28547 -275.869131) (xy 352.292818 -275.818322) (xy 352.307377 -275.769092)
			(xy 352.328846 -275.722459) (xy 352.35678 -275.679386) (xy 352.390603 -275.640765) (xy 352.429615 -275.607394)
			(xy 352.473009 -275.579963) (xy 352.519889 -275.559038) (xy 352.569285 -275.545053) (xy 352.594672 -275.541232)
			(xy 352.619564 -275.53793) (xy 352.791776 -275.239988) (xy 352.782124 -275.216874) (xy 352.773627 -275.19528)
			(xy 352.761646 -275.150448) (xy 352.755589 -275.10444) (xy 352.7552 -275.081238) (xy 352.7552 -275.08073)
			(xy 352.755699 -275.054043) (xy 352.763654 -275.001264) (xy 352.779386 -274.950261) (xy 352.802544 -274.902172)
			(xy 352.832611 -274.858072) (xy 352.868915 -274.818945) (xy 352.910645 -274.785667) (xy 352.956869 -274.75898)
			(xy 353.006554 -274.73948) (xy 353.058591 -274.727603) (xy 353.111816 -274.723614) (xy 353.165041 -274.727603)
			(xy 353.217078 -274.73948) (xy 353.266763 -274.75898) (xy 353.312987 -274.785667) (xy 353.354717 -274.818945)
			(xy 353.391021 -274.858072) (xy 353.421088 -274.902172) (xy 353.444246 -274.950261) (xy 353.459978 -275.001264)
			(xy 353.467933 -275.054043) (xy 353.468432 -275.08073) (xy 355.5746 -275.08073) (xy 355.575099 -275.054043)
			(xy 355.583054 -275.001264) (xy 355.598786 -274.950261) (xy 355.621944 -274.902172) (xy 355.652011 -274.858072)
			(xy 355.688315 -274.818945) (xy 355.730045 -274.785667) (xy 355.776269 -274.75898) (xy 355.825954 -274.73948)
			(xy 355.877991 -274.727603) (xy 355.931216 -274.723614) (xy 355.984441 -274.727603) (xy 356.036478 -274.73948)
			(xy 356.086163 -274.75898) (xy 356.132387 -274.785667) (xy 356.174117 -274.818945) (xy 356.210421 -274.858072)
			(xy 356.240488 -274.902172) (xy 356.263646 -274.950261) (xy 356.279378 -275.001264) (xy 356.287333 -275.054043)
			(xy 356.287832 -275.08073) (xy 356.287459 -275.104069) (xy 356.281361 -275.150348) (xy 356.269261 -275.195431)
			(xy 356.260654 -275.217128) (xy 356.251002 -275.240496) (xy 356.423214 -275.53793) (xy 356.447852 -275.541232)
			(xy 356.473248 -275.545055) (xy 356.522668 -275.55902) (xy 356.569574 -275.57993) (xy 356.612996 -275.607351)
			(xy 356.652035 -275.640717) (xy 356.685885 -275.679337) (xy 356.713846 -275.722414) (xy 356.735338 -275.769056)
			(xy 356.749918 -275.818298) (xy 356.757285 -275.869122) (xy 356.757732 -275.8948) (xy 356.757233 -275.921487)
			(xy 356.749278 -275.974266) (xy 356.733546 -276.025269) (xy 356.710388 -276.073358) (xy 356.680321 -276.117458)
			(xy 356.644017 -276.156585) (xy 356.602287 -276.189863) (xy 356.556063 -276.21655) (xy 356.506378 -276.23605)
			(xy 356.454341 -276.247927) (xy 356.401116 -276.251916) (xy 356.347891 -276.247927) (xy 356.295854 -276.23605)
			(xy 356.246169 -276.21655) (xy 356.199945 -276.189863) (xy 356.158215 -276.156585) (xy 356.121911 -276.117458)
			(xy 356.091844 -276.073358) (xy 356.068686 -276.025269) (xy 356.052954 -275.974266) (xy 356.044999 -275.921487)
			(xy 356.0445 -275.8948) (xy 356.044848 -275.87146) (xy 356.050956 -275.825181) (xy 356.063066 -275.780098)
			(xy 356.071678 -275.758402) (xy 356.08133 -275.735034) (xy 355.909118 -275.4376) (xy 355.88448 -275.434298)
			(xy 355.859081 -275.4305) (xy 355.809662 -275.416527) (xy 355.762759 -275.395611) (xy 355.719339 -275.368186)
			(xy 355.680302 -275.334817) (xy 355.646453 -275.296194) (xy 355.618493 -275.253116) (xy 355.597 -275.206474)
			(xy 355.582419 -275.157232) (xy 355.575049 -275.106408) (xy 355.5746 -275.08073) (xy 353.468432 -275.08073)
			(xy 353.467958 -275.10643) (xy 353.460574 -275.157297) (xy 353.445964 -275.206576) (xy 353.42443 -275.253248)
			(xy 353.396419 -275.296344) (xy 353.362511 -275.334973) (xy 353.323408 -275.368333) (xy 353.27992 -275.395733)
			(xy 353.23295 -275.416607) (xy 353.183469 -275.43052) (xy 353.158044 -275.434298) (xy 353.133152 -275.4376)
			(xy 352.961448 -275.735034) (xy 352.9711 -275.758402) (xy 352.979663 -275.780114) (xy 352.991752 -275.825194)
			(xy 352.997874 -275.871464) (xy 352.998278 -275.8948) (xy 354.165201 -275.8948) (xy 354.169178 -275.84173)
			(xy 354.18102 -275.789845) (xy 354.200462 -275.740304) (xy 354.227069 -275.694215) (xy 354.260249 -275.652605)
			(xy 354.299259 -275.616405) (xy 354.343229 -275.586422) (xy 354.391176 -275.563328) (xy 354.442029 -275.547637)
			(xy 354.494653 -275.5397) (xy 354.521262 -275.5392) (xy 354.546208 -275.539589) (xy 354.595612 -275.54656)
			(xy 354.643555 -275.560368) (xy 354.689098 -275.580745) (xy 354.731344 -275.607288) (xy 354.769464 -275.639477)
			(xy 354.802709 -275.676679) (xy 354.816918 -275.697188) (xy 355.165406 -275.697188) (xy 355.179623 -275.676688)
			(xy 355.212875 -275.639497) (xy 355.250998 -275.607318) (xy 355.293243 -275.580782) (xy 355.338781 -275.560409)
			(xy 355.38672 -275.546599) (xy 355.436118 -275.539623) (xy 355.461062 -275.5392) (xy 355.487677 -275.53967)
			(xy 355.540313 -275.547598) (xy 355.591179 -275.563284) (xy 355.63914 -275.586376) (xy 355.683122 -275.616358)
			(xy 355.722144 -275.652562) (xy 355.755334 -275.694177) (xy 355.781951 -275.740274) (xy 355.801399 -275.789824)
			(xy 355.813245 -275.841719) (xy 355.817223 -275.8948) (xy 355.813245 -275.947881) (xy 355.801399 -275.999776)
			(xy 355.781951 -276.049326) (xy 355.755334 -276.095423) (xy 355.722144 -276.137038) (xy 355.683122 -276.173242)
			(xy 355.63914 -276.203224) (xy 355.591179 -276.226316) (xy 355.540313 -276.242002) (xy 355.487677 -276.24993)
			(xy 355.461062 -276.2504) (xy 355.436116 -276.249992) (xy 355.386714 -276.243025) (xy 355.33877 -276.22922)
			(xy 355.293228 -276.208847) (xy 355.250982 -276.182306) (xy 355.212861 -276.15012) (xy 355.179615 -276.11292)
			(xy 355.165406 -276.092412) (xy 354.816918 -276.092412) (xy 354.802686 -276.112901) (xy 354.769436 -276.150092)
			(xy 354.731316 -276.182271) (xy 354.689074 -276.208809) (xy 354.643538 -276.229184) (xy 354.595601 -276.242997)
			(xy 354.546205 -276.249976) (xy 354.521262 -276.2504) (xy 354.494653 -276.2499) (xy 354.442029 -276.241963)
			(xy 354.391176 -276.226272) (xy 354.343229 -276.203178) (xy 354.299259 -276.173195) (xy 354.260249 -276.136995)
			(xy 354.227069 -276.095385) (xy 354.200462 -276.049296) (xy 354.18102 -275.999755) (xy 354.169178 -275.94787)
			(xy 354.165201 -275.8948) (xy 352.998278 -275.8948) (xy 352.997779 -275.921487) (xy 352.989824 -275.974266)
			(xy 352.974092 -276.025269) (xy 352.950934 -276.073358) (xy 352.920867 -276.117458) (xy 352.884563 -276.156585)
			(xy 352.842833 -276.189863) (xy 352.796609 -276.21655) (xy 352.746924 -276.23605) (xy 352.694887 -276.247927)
			(xy 352.641662 -276.251916) (xy 352.588437 -276.247927) (xy 352.5364 -276.23605) (xy 352.486715 -276.21655)
			(xy 352.440491 -276.189863) (xy 352.398761 -276.156585) (xy 352.362457 -276.117458) (xy 352.33239 -276.073358)
			(xy 352.309232 -276.025269) (xy 352.2935 -275.974266) (xy 352.285545 -275.921487) (xy 352.285046 -275.8948)
			(xy 351.118678 -275.8948) (xy 351.118199 -275.920478) (xy 351.110845 -275.971305) (xy 351.096274 -276.020551)
			(xy 351.074789 -276.067197) (xy 351.046834 -276.110277) (xy 351.012986 -276.148901) (xy 350.973948 -276.182269)
			(xy 350.930525 -276.209691) (xy 350.883618 -276.230599) (xy 350.834196 -276.244561) (xy 350.808798 -276.248368)
			(xy 350.783906 -276.25167) (xy 350.611948 -276.54885) (xy 350.6216 -276.572218) (xy 350.630167 -276.593929)
			(xy 350.642255 -276.63901) (xy 350.648375 -276.68528) (xy 350.648778 -276.708616) (xy 350.8756 -276.708616)
			(xy 350.876099 -276.681929) (xy 350.884054 -276.62915) (xy 350.899786 -276.578147) (xy 350.922944 -276.530058)
			(xy 350.953011 -276.485958) (xy 350.989315 -276.446831) (xy 351.031045 -276.413553) (xy 351.077269 -276.386866)
			(xy 351.126954 -276.367366) (xy 351.178991 -276.355489) (xy 351.232216 -276.3515) (xy 351.285441 -276.355489)
			(xy 351.337478 -276.367366) (xy 351.387163 -276.386866) (xy 351.433387 -276.413553) (xy 351.475117 -276.446831)
			(xy 351.511421 -276.485958) (xy 351.541488 -276.530058) (xy 351.564646 -276.578147) (xy 351.580378 -276.62915)
			(xy 351.588333 -276.681929) (xy 351.588832 -276.7086) (xy 351.815893 -276.7086) (xy 351.819871 -276.655523)
			(xy 351.831715 -276.603633) (xy 351.851161 -276.554087) (xy 351.877774 -276.507993) (xy 351.91096 -276.46638)
			(xy 351.949978 -276.430179) (xy 351.993956 -276.400197) (xy 352.041911 -276.377105) (xy 352.092772 -276.361418)
			(xy 352.145403 -276.353488) (xy 352.172016 -276.353016) (xy 352.19696 -276.353477) (xy 352.246358 -276.360439)
			(xy 352.294298 -276.374239) (xy 352.339839 -276.394604) (xy 352.382086 -276.421135) (xy 352.420209 -276.453312)
			(xy 352.453459 -276.490502) (xy 352.467672 -276.511004) (xy 352.81616 -276.511004) (xy 352.830347 -276.490482)
			(xy 352.863604 -276.453292) (xy 352.901732 -276.421114) (xy 352.943982 -276.39458) (xy 352.989525 -276.37421)
			(xy 353.037468 -276.360405) (xy 353.08687 -276.353435) (xy 353.111816 -276.353016) (xy 353.138428 -276.353482)
			(xy 353.191056 -276.361417) (xy 353.241915 -276.377107) (xy 353.289867 -276.400201) (xy 353.333841 -276.430184)
			(xy 353.372856 -276.466386) (xy 353.406039 -276.507999) (xy 353.43265 -276.554092) (xy 353.452094 -276.603636)
			(xy 353.463937 -276.655525) (xy 353.467915 -276.7086) (xy 353.463937 -276.761675) (xy 353.452094 -276.813564)
			(xy 353.43265 -276.863108) (xy 353.406039 -276.909201) (xy 353.372856 -276.950814) (xy 353.333841 -276.987016)
			(xy 353.289867 -277.016999) (xy 353.241915 -277.040093) (xy 353.191056 -277.055783) (xy 353.138428 -277.063718)
			(xy 353.111816 -277.064216) (xy 353.086869 -277.063836) (xy 353.037466 -277.056863) (xy 352.989522 -277.043052)
			(xy 352.94398 -277.022674) (xy 352.901735 -276.99613) (xy 352.863615 -276.96394) (xy 352.830369 -276.926737)
			(xy 352.81616 -276.906228) (xy 352.467672 -276.906228) (xy 352.453474 -276.926742) (xy 352.420218 -276.963931)
			(xy 352.382092 -276.996109) (xy 352.339844 -277.022643) (xy 352.294302 -277.043014) (xy 352.246361 -277.056821)
			(xy 352.196961 -277.063795) (xy 352.172016 -277.064216) (xy 352.145403 -277.063712) (xy 352.092772 -277.055782)
			(xy 352.041911 -277.040095) (xy 351.993956 -277.017003) (xy 351.949978 -276.987021) (xy 351.91096 -276.95082)
			(xy 351.877774 -276.909207) (xy 351.851161 -276.863113) (xy 351.831715 -276.813567) (xy 351.819871 -276.761677)
			(xy 351.815893 -276.7086) (xy 351.588832 -276.7086) (xy 351.588832 -276.708616) (xy 351.588455 -276.731955)
			(xy 351.582359 -276.778234) (xy 351.570261 -276.823317) (xy 351.561654 -276.845014) (xy 351.552002 -276.868382)
			(xy 351.72396 -277.165562) (xy 351.748852 -277.168864) (xy 351.774235 -277.172686) (xy 351.823618 -277.186692)
			(xy 351.870484 -277.20763) (xy 351.913866 -277.235069) (xy 351.952868 -277.268441) (xy 351.986685 -277.307059)
			(xy 352.014618 -277.350124) (xy 352.036091 -277.396747) (xy 352.050661 -277.445967) (xy 352.058027 -277.496767)
			(xy 352.058478 -277.522432) (xy 354.164646 -277.522432) (xy 354.1651 -277.496764) (xy 354.172443 -277.445956)
			(xy 354.186998 -277.396727) (xy 354.208463 -277.350094) (xy 354.236394 -277.307021) (xy 354.270213 -277.2684)
			(xy 354.309222 -277.235028) (xy 354.352614 -277.207596) (xy 354.399492 -277.186671) (xy 354.448886 -277.172685)
			(xy 354.474272 -277.168864) (xy 354.499164 -277.165562) (xy 354.671376 -276.867874) (xy 354.661724 -276.84476)
			(xy 354.653222 -276.823168) (xy 354.641244 -276.778335) (xy 354.635188 -276.732326) (xy 354.6348 -276.709124)
			(xy 354.6348 -276.708616) (xy 354.635299 -276.681929) (xy 354.643254 -276.62915) (xy 354.658986 -276.578147)
			(xy 354.682144 -276.530058) (xy 354.712211 -276.485958) (xy 354.748515 -276.446831) (xy 354.790245 -276.413553)
			(xy 354.836469 -276.386866) (xy 354.886154 -276.367366) (xy 354.938191 -276.355489) (xy 354.991416 -276.3515)
			(xy 355.044641 -276.355489) (xy 355.096678 -276.367366) (xy 355.146363 -276.386866) (xy 355.192587 -276.413553)
			(xy 355.234317 -276.446831) (xy 355.270621 -276.485958) (xy 355.300688 -276.530058) (xy 355.323846 -276.578147)
			(xy 355.339578 -276.62915) (xy 355.347533 -276.681929) (xy 355.348032 -276.708616) (xy 356.514146 -276.708616)
			(xy 356.514585 -276.682947) (xy 356.521931 -276.632139) (xy 356.536488 -276.582909) (xy 356.557954 -276.536276)
			(xy 356.585887 -276.493204) (xy 356.619708 -276.454583) (xy 356.658719 -276.421211) (xy 356.702112 -276.39378)
			(xy 356.748991 -276.372855) (xy 356.798386 -276.358869) (xy 356.823772 -276.355048) (xy 356.848664 -276.351746)
			(xy 357.020622 -276.054566) (xy 357.01097 -276.031198) (xy 357.002405 -276.009486) (xy 356.990317 -275.964406)
			(xy 356.984195 -275.918136) (xy 356.983792 -275.8948) (xy 356.984291 -275.868113) (xy 356.992246 -275.815334)
			(xy 357.007978 -275.764331) (xy 357.031136 -275.716242) (xy 357.061203 -275.672142) (xy 357.097507 -275.633015)
			(xy 357.139237 -275.599737) (xy 357.185461 -275.57305) (xy 357.235146 -275.55355) (xy 357.287183 -275.541673)
			(xy 357.340408 -275.537684) (xy 357.393633 -275.541673) (xy 357.44567 -275.55355) (xy 357.495355 -275.57305)
			(xy 357.541579 -275.599737) (xy 357.583309 -275.633015) (xy 357.619613 -275.672142) (xy 357.64968 -275.716242)
			(xy 357.672838 -275.764331) (xy 357.68857 -275.815334) (xy 357.696525 -275.868113) (xy 357.697024 -275.8948)
			(xy 357.696626 -275.92047) (xy 357.689277 -275.971282) (xy 357.674716 -276.020514) (xy 357.653246 -276.067149)
			(xy 357.625309 -276.110222) (xy 357.591483 -276.148843) (xy 357.552467 -276.182214) (xy 357.509069 -276.209644)
			(xy 357.462186 -276.230567) (xy 357.412786 -276.244549) (xy 357.387398 -276.248368) (xy 357.362506 -276.25167)
			(xy 357.190548 -276.54885) (xy 357.2002 -276.572218) (xy 357.208767 -276.593929) (xy 357.220855 -276.63901)
			(xy 357.226975 -276.68528) (xy 357.227378 -276.708616) (xy 357.226879 -276.735303) (xy 357.218924 -276.788082)
			(xy 357.203192 -276.839085) (xy 357.180034 -276.887174) (xy 357.149967 -276.931274) (xy 357.113663 -276.970401)
			(xy 357.071933 -277.003679) (xy 357.025709 -277.030366) (xy 356.976024 -277.049866) (xy 356.923987 -277.061743)
			(xy 356.870762 -277.065732) (xy 356.817537 -277.061743) (xy 356.7655 -277.049866) (xy 356.715815 -277.030366)
			(xy 356.669591 -277.003679) (xy 356.627861 -276.970401) (xy 356.591557 -276.931274) (xy 356.56149 -276.887174)
			(xy 356.538332 -276.839085) (xy 356.5226 -276.788082) (xy 356.514645 -276.735303) (xy 356.514146 -276.708616)
			(xy 355.348032 -276.708616) (xy 355.347637 -276.734318) (xy 355.340241 -276.785188) (xy 355.32562 -276.834469)
			(xy 355.304076 -276.881141) (xy 355.276055 -276.924238) (xy 355.242139 -276.962865) (xy 355.203028 -276.996224)
			(xy 355.159534 -277.023623) (xy 355.112557 -277.044494) (xy 355.063071 -277.058407) (xy 355.037644 -277.062184)
			(xy 355.012752 -277.065486) (xy 354.841048 -277.362666) (xy 354.8507 -277.386034) (xy 354.859272 -277.407743)
			(xy 354.871358 -277.452825) (xy 354.877476 -277.499096) (xy 354.877878 -277.522432) (xy 355.104446 -277.522432)
			(xy 355.104945 -277.495745) (xy 355.1129 -277.442966) (xy 355.128632 -277.391963) (xy 355.15179 -277.343874)
			(xy 355.181857 -277.299774) (xy 355.218161 -277.260647) (xy 355.259891 -277.227369) (xy 355.306115 -277.200682)
			(xy 355.3558 -277.181182) (xy 355.407837 -277.169305) (xy 355.461062 -277.165316) (xy 355.514287 -277.169305)
			(xy 355.566324 -277.181182) (xy 355.616009 -277.200682) (xy 355.662233 -277.227369) (xy 355.703963 -277.260647)
			(xy 355.740267 -277.299774) (xy 355.770334 -277.343874) (xy 355.793492 -277.391963) (xy 355.809224 -277.442966)
			(xy 355.817179 -277.495745) (xy 355.817677 -277.5224) (xy 356.044833 -277.5224) (xy 356.04881 -277.469335)
			(xy 356.06065 -277.417454) (xy 356.08009 -277.367918) (xy 356.106696 -277.321833) (xy 356.139872 -277.280227)
			(xy 356.178879 -277.24403) (xy 356.222845 -277.21405) (xy 356.270787 -277.190958) (xy 356.321636 -277.175268)
			(xy 356.374255 -277.167332) (xy 356.400862 -277.166832) (xy 356.425807 -277.167251) (xy 356.475208 -277.17422)
			(xy 356.523149 -277.188026) (xy 356.56869 -277.208398) (xy 356.610936 -277.234936) (xy 356.649058 -277.267119)
			(xy 356.682307 -277.304315) (xy 356.696518 -277.32482) (xy 357.045006 -277.32482) (xy 357.059233 -277.304327)
			(xy 357.092482 -277.267135) (xy 357.130603 -277.234954) (xy 357.172846 -277.208417) (xy 357.218384 -277.188042)
			(xy 357.266321 -277.174231) (xy 357.315718 -277.167255) (xy 357.340662 -277.166832) (xy 357.367279 -277.167238)
			(xy 357.41992 -277.175167) (xy 357.470791 -277.190854) (xy 357.518756 -277.213948) (xy 357.562742 -277.243933)
			(xy 357.601768 -277.280139) (xy 357.634961 -277.321758) (xy 357.66158 -277.36786) (xy 357.68103 -277.417414)
			(xy 357.692877 -277.469314) (xy 357.696856 -277.5224) (xy 357.692877 -277.575486) (xy 357.68103 -277.627386)
			(xy 357.66158 -277.67694) (xy 357.634961 -277.723042) (xy 357.601768 -277.764661) (xy 357.562742 -277.800867)
			(xy 357.518756 -277.830852) (xy 357.470791 -277.853946) (xy 357.41992 -277.869633) (xy 357.367279 -277.877562)
			(xy 357.340662 -277.878032) (xy 357.315717 -277.87761) (xy 357.266316 -277.870644) (xy 357.218373 -277.85684)
			(xy 357.172832 -277.836469) (xy 357.130585 -277.809931) (xy 357.092464 -277.777747) (xy 357.059216 -277.74055)
			(xy 357.045006 -277.720044) (xy 356.696518 -277.720044) (xy 356.682264 -277.740518) (xy 356.64902 -277.777712)
			(xy 356.610905 -277.809895) (xy 356.568666 -277.836435) (xy 356.523133 -277.856813) (xy 356.475199 -277.870627)
			(xy 356.425804 -277.877607) (xy 356.400862 -277.878032) (xy 356.374255 -277.877468) (xy 356.321636 -277.869532)
			(xy 356.270787 -277.853842) (xy 356.222845 -277.83075) (xy 356.178879 -277.80077) (xy 356.139872 -277.764573)
			(xy 356.106696 -277.722967) (xy 356.08009 -277.676882) (xy 356.06065 -277.627346) (xy 356.04881 -277.575465)
			(xy 356.044833 -277.5224) (xy 355.817677 -277.5224) (xy 355.817678 -277.522432) (xy 355.817678 -277.52294)
			(xy 355.817266 -277.546141) (xy 355.811211 -277.592147) (xy 355.799247 -277.636982) (xy 355.790754 -277.658576)
			(xy 355.781102 -277.68169) (xy 355.953314 -277.979632) (xy 355.978206 -277.982934) (xy 356.003595 -277.986725)
			(xy 356.052983 -278.000728) (xy 356.099854 -278.021666) (xy 356.14324 -278.049106) (xy 356.182244 -278.082482)
			(xy 356.216061 -278.121104) (xy 356.243993 -278.164175) (xy 356.265463 -278.210804) (xy 356.280028 -278.26003)
			(xy 356.287386 -278.310835) (xy 356.287832 -278.336502) (xy 356.287333 -278.363189) (xy 356.279378 -278.415968)
			(xy 356.263646 -278.466971) (xy 356.240488 -278.51506) (xy 356.210421 -278.55916) (xy 356.174117 -278.598287)
			(xy 356.132387 -278.631565) (xy 356.086163 -278.658252) (xy 356.036478 -278.677752) (xy 355.984441 -278.689629)
			(xy 355.931216 -278.693618) (xy 355.877991 -278.689629) (xy 355.825954 -278.677752) (xy 355.776269 -278.658252)
			(xy 355.730045 -278.631565) (xy 355.688315 -278.598287) (xy 355.652011 -278.55916) (xy 355.621944 -278.51506)
			(xy 355.598786 -278.466971) (xy 355.583054 -278.415968) (xy 355.575099 -278.363189) (xy 355.5746 -278.336502)
			(xy 355.574949 -278.313162) (xy 355.581056 -278.266883) (xy 355.593166 -278.2218) (xy 355.601778 -278.200104)
			(xy 355.61143 -278.176736) (xy 355.439726 -277.879302) (xy 355.414834 -277.876) (xy 355.389398 -277.872277)
			(xy 355.339907 -277.858368) (xy 355.292927 -277.837496) (xy 355.249431 -277.810093) (xy 355.210322 -277.776728)
			(xy 355.17641 -277.738091) (xy 355.148398 -277.694985) (xy 355.126867 -277.648303) (xy 355.112264 -277.599013)
			(xy 355.104891 -277.548136) (xy 355.104446 -277.522432) (xy 354.877878 -277.522432) (xy 354.877379 -277.549119)
			(xy 354.869424 -277.601898) (xy 354.853692 -277.652901) (xy 354.830534 -277.70099) (xy 354.800467 -277.74509)
			(xy 354.764163 -277.784217) (xy 354.722433 -277.817495) (xy 354.676209 -277.844182) (xy 354.626524 -277.863682)
			(xy 354.574487 -277.875559) (xy 354.521262 -277.879548) (xy 354.468037 -277.875559) (xy 354.416 -277.863682)
			(xy 354.366315 -277.844182) (xy 354.320091 -277.817495) (xy 354.278361 -277.784217) (xy 354.242057 -277.74509)
			(xy 354.21199 -277.70099) (xy 354.188832 -277.652901) (xy 354.1731 -277.601898) (xy 354.165145 -277.549119)
			(xy 354.164646 -277.522432) (xy 352.058478 -277.522432) (xy 352.057979 -277.549119) (xy 352.050024 -277.601898)
			(xy 352.034292 -277.652901) (xy 352.011134 -277.70099) (xy 351.981067 -277.74509) (xy 351.944763 -277.784217)
			(xy 351.903033 -277.817495) (xy 351.856809 -277.844182) (xy 351.807124 -277.863682) (xy 351.755087 -277.875559)
			(xy 351.701862 -277.879548) (xy 351.648637 -277.875559) (xy 351.5966 -277.863682) (xy 351.546915 -277.844182)
			(xy 351.500691 -277.817495) (xy 351.458961 -277.784217) (xy 351.422657 -277.74509) (xy 351.39259 -277.70099)
			(xy 351.369432 -277.652901) (xy 351.3537 -277.601898) (xy 351.345745 -277.549119) (xy 351.345246 -277.522432)
			(xy 351.345608 -277.499092) (xy 351.351711 -277.452814) (xy 351.363815 -277.407731) (xy 351.372424 -277.386034)
			(xy 351.382076 -277.362666) (xy 351.210118 -277.065486) (xy 351.185226 -277.062184) (xy 351.159844 -277.058351)
			(xy 351.110457 -277.044353) (xy 351.063588 -277.02342) (xy 351.020202 -276.995985) (xy 350.981198 -276.962614)
			(xy 350.94738 -276.923997) (xy 350.919446 -276.880931) (xy 350.897974 -276.834305) (xy 350.883408 -276.785083)
			(xy 350.876047 -276.734282) (xy 350.8756 -276.708616) (xy 350.648778 -276.708616) (xy 350.648279 -276.735303)
			(xy 350.640324 -276.788082) (xy 350.624592 -276.839085) (xy 350.601434 -276.887174) (xy 350.571367 -276.931274)
			(xy 350.535063 -276.970401) (xy 350.493333 -277.003679) (xy 350.447109 -277.030366) (xy 350.397424 -277.049866)
			(xy 350.345387 -277.061743) (xy 350.292162 -277.065732) (xy 350.238937 -277.061743) (xy 350.1869 -277.049866)
			(xy 350.137215 -277.030366) (xy 350.090991 -277.003679) (xy 350.049261 -276.970401) (xy 350.012957 -276.931274)
			(xy 349.98289 -276.887174) (xy 349.959732 -276.839085) (xy 349.944 -276.788082) (xy 349.936045 -276.735303)
			(xy 349.935546 -276.708616) (xy 109.28731 -276.708616) (xy 109.286811 -276.735303) (xy 109.278856 -276.788082)
			(xy 109.263124 -276.839085) (xy 109.239966 -276.887174) (xy 109.209899 -276.931274) (xy 109.173595 -276.970401)
			(xy 109.131865 -277.003679) (xy 109.085641 -277.030366) (xy 109.035956 -277.049866) (xy 108.983919 -277.061743)
			(xy 108.930694 -277.065732) (xy 108.877469 -277.061743) (xy 108.825432 -277.049866) (xy 108.775747 -277.030366)
			(xy 108.729523 -277.003679) (xy 108.687793 -276.970401) (xy 108.651489 -276.931274) (xy 108.621422 -276.887174)
			(xy 108.598264 -276.839085) (xy 108.582532 -276.788082) (xy 108.574577 -276.735303) (xy 108.574078 -276.708616)
			(xy 107.407964 -276.708616) (xy 107.407541 -276.734317) (xy 107.400147 -276.785184) (xy 107.385527 -276.834463)
			(xy 107.363985 -276.881134) (xy 107.335967 -276.924229) (xy 107.302054 -276.962856) (xy 107.262947 -276.996215)
			(xy 107.219457 -277.023615) (xy 107.172484 -277.044489) (xy 107.123002 -277.058405) (xy 107.097576 -277.062184)
			(xy 107.072684 -277.065486) (xy 106.90098 -277.362666) (xy 106.910632 -277.386034) (xy 106.919206 -277.407742)
			(xy 106.931291 -277.452824) (xy 106.937409 -277.499095) (xy 106.93781 -277.522432) (xy 107.164378 -277.522432)
			(xy 107.164877 -277.495745) (xy 107.172832 -277.442966) (xy 107.188564 -277.391963) (xy 107.211722 -277.343874)
			(xy 107.241789 -277.299774) (xy 107.278093 -277.260647) (xy 107.319823 -277.227369) (xy 107.366047 -277.200682)
			(xy 107.415732 -277.181182) (xy 107.467769 -277.169305) (xy 107.520994 -277.165316) (xy 107.574219 -277.169305)
			(xy 107.626256 -277.181182) (xy 107.675941 -277.200682) (xy 107.722165 -277.227369) (xy 107.763895 -277.260647)
			(xy 107.800199 -277.299774) (xy 107.830266 -277.343874) (xy 107.853424 -277.391963) (xy 107.869156 -277.442966)
			(xy 107.877111 -277.495745) (xy 107.877609 -277.5224) (xy 108.104733 -277.5224) (xy 108.10871 -277.469332)
			(xy 108.120552 -277.417449) (xy 108.139994 -277.36791) (xy 108.166603 -277.321822) (xy 108.199783 -277.280215)
			(xy 108.238793 -277.244018) (xy 108.282763 -277.214039) (xy 108.33071 -277.190949) (xy 108.381563 -277.175262)
			(xy 108.434185 -277.16733) (xy 108.460794 -277.166832) (xy 108.48574 -277.167227) (xy 108.535142 -277.1742)
			(xy 108.583084 -277.18801) (xy 108.628625 -277.208386) (xy 108.670871 -277.234928) (xy 108.708992 -277.267114)
			(xy 108.742239 -277.304313) (xy 108.75645 -277.32482) (xy 109.104938 -277.32482) (xy 109.119145 -277.304312)
			(xy 109.152397 -277.26712) (xy 109.190521 -277.234941) (xy 109.232768 -277.208405) (xy 109.278309 -277.188033)
			(xy 109.326249 -277.174225) (xy 109.375649 -277.167253) (xy 109.400594 -277.166832) (xy 109.42721 -277.16724)
			(xy 109.479847 -277.175173) (xy 109.530714 -277.190863) (xy 109.578674 -277.213958) (xy 109.622657 -277.243944)
			(xy 109.661679 -277.280151) (xy 109.694868 -277.321769) (xy 109.721484 -277.367868) (xy 109.740932 -277.41742)
			(xy 109.752777 -277.469317) (xy 109.756756 -277.5224) (xy 109.752777 -277.575483) (xy 109.740932 -277.62738)
			(xy 109.721484 -277.676932) (xy 109.694868 -277.723031) (xy 109.661679 -277.764649) (xy 109.622657 -277.800856)
			(xy 109.578674 -277.830842) (xy 109.530714 -277.853937) (xy 109.479847 -277.869627) (xy 109.42721 -277.87756)
			(xy 109.400594 -277.878032) (xy 109.37565 -277.877586) (xy 109.326249 -277.870624) (xy 109.278308 -277.856824)
			(xy 109.232766 -277.836457) (xy 109.19052 -277.809923) (xy 109.152398 -277.777742) (xy 109.119149 -277.740549)
			(xy 109.104938 -277.720044) (xy 108.75645 -277.720044) (xy 108.742239 -277.740549) (xy 108.708988 -277.777742)
			(xy 108.670866 -277.809923) (xy 108.62862 -277.83646) (xy 108.583079 -277.856832) (xy 108.535139 -277.87064)
			(xy 108.485739 -277.877612) (xy 108.460794 -277.878032) (xy 108.434185 -277.87747) (xy 108.381563 -277.869538)
			(xy 108.33071 -277.853851) (xy 108.282763 -277.830761) (xy 108.238793 -277.800782) (xy 108.199783 -277.764585)
			(xy 108.166603 -277.722978) (xy 108.139994 -277.67689) (xy 108.120552 -277.627351) (xy 108.10871 -277.575468)
			(xy 108.104733 -277.5224) (xy 107.877609 -277.5224) (xy 107.87761 -277.522432) (xy 107.87761 -277.52294)
			(xy 107.877203 -277.546141) (xy 107.871147 -277.592148) (xy 107.85918 -277.636982) (xy 107.850686 -277.658576)
			(xy 107.841034 -277.68169) (xy 108.013246 -277.979632) (xy 108.038138 -277.982934) (xy 108.063531 -277.9867)
			(xy 108.11292 -278.000707) (xy 108.15979 -278.021649) (xy 108.203175 -278.049093) (xy 108.242179 -278.082472)
			(xy 108.275995 -278.121096) (xy 108.303927 -278.164169) (xy 108.325396 -278.2108) (xy 108.33996 -278.260028)
			(xy 108.347318 -278.310834) (xy 108.347764 -278.336502) (xy 108.347265 -278.363189) (xy 108.33931 -278.415968)
			(xy 108.323578 -278.466971) (xy 108.30042 -278.51506) (xy 108.270353 -278.55916) (xy 108.234049 -278.598287)
			(xy 108.192319 -278.631565) (xy 108.146095 -278.658252) (xy 108.09641 -278.677752) (xy 108.044373 -278.689629)
			(xy 107.991148 -278.693618) (xy 107.937923 -278.689629) (xy 107.885886 -278.677752) (xy 107.836201 -278.658252)
			(xy 107.789977 -278.631565) (xy 107.748247 -278.598287) (xy 107.711943 -278.55916) (xy 107.681876 -278.51506)
			(xy 107.658718 -278.466971) (xy 107.642986 -278.415968) (xy 107.635031 -278.363189) (xy 107.634532 -278.336502)
			(xy 107.634886 -278.313162) (xy 107.640992 -278.266883) (xy 107.653099 -278.221801) (xy 107.66171 -278.200104)
			(xy 107.671362 -278.176736) (xy 107.499658 -277.879302) (xy 107.474766 -277.876) (xy 107.449334 -277.872252)
			(xy 107.399843 -277.858348) (xy 107.352863 -277.837479) (xy 107.309367 -277.81008) (xy 107.270257 -277.776717)
			(xy 107.236344 -277.738083) (xy 107.208331 -277.694979) (xy 107.1868 -277.648299) (xy 107.172196 -277.599011)
			(xy 107.164823 -277.548135) (xy 107.164378 -277.522432) (xy 106.93781 -277.522432) (xy 106.937311 -277.549119)
			(xy 106.929356 -277.601898) (xy 106.913624 -277.652901) (xy 106.890466 -277.70099) (xy 106.860399 -277.74509)
			(xy 106.824095 -277.784217) (xy 106.782365 -277.817495) (xy 106.736141 -277.844182) (xy 106.686456 -277.863682)
			(xy 106.634419 -277.875559) (xy 106.581194 -277.879548) (xy 106.527969 -277.875559) (xy 106.475932 -277.863682)
			(xy 106.426247 -277.844182) (xy 106.380023 -277.817495) (xy 106.338293 -277.784217) (xy 106.301989 -277.74509)
			(xy 106.271922 -277.70099) (xy 106.248764 -277.652901) (xy 106.233032 -277.601898) (xy 106.225077 -277.549119)
			(xy 106.224578 -277.522432) (xy 104.11841 -277.522432) (xy 104.117911 -277.549119) (xy 104.109956 -277.601898)
			(xy 104.094224 -277.652901) (xy 104.071066 -277.70099) (xy 104.040999 -277.74509) (xy 104.004695 -277.784217)
			(xy 103.962965 -277.817495) (xy 103.916741 -277.844182) (xy 103.867056 -277.863682) (xy 103.815019 -277.875559)
			(xy 103.761794 -277.879548) (xy 103.708569 -277.875559) (xy 103.656532 -277.863682) (xy 103.606847 -277.844182)
			(xy 103.560623 -277.817495) (xy 103.518893 -277.784217) (xy 103.482589 -277.74509) (xy 103.452522 -277.70099)
			(xy 103.429364 -277.652901) (xy 103.413632 -277.601898) (xy 103.405677 -277.549119) (xy 103.405178 -277.522432)
			(xy 103.405538 -277.499092) (xy 103.411641 -277.452813) (xy 103.423746 -277.407731) (xy 103.432356 -277.386034)
			(xy 103.442008 -277.362666) (xy 103.27005 -277.065486) (xy 103.245158 -277.062184) (xy 103.219767 -277.058404)
			(xy 103.17038 -277.044397) (xy 103.123511 -277.023456) (xy 103.080127 -276.996013) (xy 103.041124 -276.962636)
			(xy 103.007307 -276.924013) (xy 102.979375 -276.880943) (xy 102.957905 -276.834313) (xy 102.943339 -276.785088)
			(xy 102.935979 -276.734283) (xy 102.935532 -276.708616) (xy 102.70871 -276.708616) (xy 102.708211 -276.735303)
			(xy 102.700256 -276.788082) (xy 102.684524 -276.839085) (xy 102.661366 -276.887174) (xy 102.631299 -276.931274)
			(xy 102.594995 -276.970401) (xy 102.553265 -277.003679) (xy 102.507041 -277.030366) (xy 102.457356 -277.049866)
			(xy 102.405319 -277.061743) (xy 102.352094 -277.065732) (xy 102.298869 -277.061743) (xy 102.246832 -277.049866)
			(xy 102.197147 -277.030366) (xy 102.150923 -277.003679) (xy 102.109193 -276.970401) (xy 102.072889 -276.931274)
			(xy 102.042822 -276.887174) (xy 102.019664 -276.839085) (xy 102.003932 -276.788082) (xy 101.995977 -276.735303)
			(xy 101.995478 -276.708616) (xy 2.509012 -276.708616) (xy 2.509012 -279.150318) (xy 101.525578 -279.150318)
			(xy 101.526077 -279.123631) (xy 101.534032 -279.070852) (xy 101.549764 -279.019849) (xy 101.572922 -278.97176)
			(xy 101.602989 -278.92766) (xy 101.639293 -278.888533) (xy 101.681023 -278.855255) (xy 101.727247 -278.828568)
			(xy 101.776932 -278.809068) (xy 101.828969 -278.797191) (xy 101.882194 -278.793202) (xy 101.935419 -278.797191)
			(xy 101.987456 -278.809068) (xy 102.037141 -278.828568) (xy 102.083365 -278.855255) (xy 102.125095 -278.888533)
			(xy 102.161399 -278.92766) (xy 102.191466 -278.97176) (xy 102.214624 -279.019849) (xy 102.230356 -279.070852)
			(xy 102.238311 -279.123631) (xy 102.23881 -279.1503) (xy 102.465919 -279.1503) (xy 102.469897 -279.09723)
			(xy 102.481739 -279.045345) (xy 102.501182 -278.995804) (xy 102.527791 -278.949715) (xy 102.560973 -278.908106)
			(xy 102.599985 -278.871907) (xy 102.643956 -278.841927) (xy 102.691905 -278.818836) (xy 102.74276 -278.803148)
			(xy 102.795384 -278.795216) (xy 102.821994 -278.794718) (xy 102.846964 -278.795151) (xy 102.896412 -278.802144)
			(xy 102.944397 -278.81598) (xy 102.989978 -278.836386) (xy 103.032259 -278.862963) (xy 103.07041 -278.895189)
			(xy 103.103683 -278.932431) (xy 103.117904 -278.95296) (xy 103.465884 -278.95296) (xy 103.480108 -278.932431)
			(xy 103.513373 -278.89518) (xy 103.55152 -278.862947) (xy 103.593801 -278.836365) (xy 103.639383 -278.815958)
			(xy 103.687372 -278.802125) (xy 103.736823 -278.79514) (xy 103.761794 -278.794718) (xy 103.788409 -278.795154)
			(xy 103.841044 -278.803087) (xy 103.891909 -278.818776) (xy 103.939867 -278.84187) (xy 103.983848 -278.871855)
			(xy 104.022868 -278.90806) (xy 104.056057 -278.949676) (xy 104.082672 -278.995774) (xy 104.102119 -279.045324)
			(xy 104.113964 -279.097219) (xy 104.117942 -279.1503) (xy 104.117941 -279.150318) (xy 349.465646 -279.150318)
			(xy 349.466145 -279.123631) (xy 349.4741 -279.070852) (xy 349.489832 -279.019849) (xy 349.51299 -278.97176)
			(xy 349.543057 -278.92766) (xy 349.579361 -278.888533) (xy 349.621091 -278.855255) (xy 349.667315 -278.828568)
			(xy 349.717 -278.809068) (xy 349.769037 -278.797191) (xy 349.822262 -278.793202) (xy 349.875487 -278.797191)
			(xy 349.927524 -278.809068) (xy 349.977209 -278.828568) (xy 350.023433 -278.855255) (xy 350.065163 -278.888533)
			(xy 350.101467 -278.92766) (xy 350.131534 -278.97176) (xy 350.154692 -279.019849) (xy 350.170424 -279.070852)
			(xy 350.178379 -279.123631) (xy 350.178878 -279.1503) (xy 350.406019 -279.1503) (xy 350.409996 -279.097233)
			(xy 350.421837 -279.04535) (xy 350.441278 -278.995812) (xy 350.467884 -278.949725) (xy 350.501062 -278.908117)
			(xy 350.54007 -278.871919) (xy 350.584038 -278.841938) (xy 350.631982 -278.818845) (xy 350.682833 -278.803154)
			(xy 350.735454 -278.795218) (xy 350.762062 -278.794718) (xy 350.787031 -278.795175) (xy 350.836478 -278.802164)
			(xy 350.884463 -278.815995) (xy 350.930044 -278.836398) (xy 350.972325 -278.862971) (xy 351.010477 -278.895194)
			(xy 351.043751 -278.932432) (xy 351.057972 -278.95296) (xy 351.405952 -278.95296) (xy 351.420132 -278.9324)
			(xy 351.453404 -278.895149) (xy 351.49156 -278.862918) (xy 351.533847 -278.83634) (xy 351.579437 -278.815938)
			(xy 351.627432 -278.802113) (xy 351.676889 -278.795136) (xy 351.701862 -278.794718) (xy 351.728478 -278.795152)
			(xy 351.781117 -278.80308) (xy 351.831986 -278.818767) (xy 351.879949 -278.84186) (xy 351.923934 -278.871844)
			(xy 351.962958 -278.908049) (xy 351.99615 -278.949666) (xy 352.022768 -278.995766) (xy 352.042217 -279.045319)
			(xy 352.054063 -279.097216) (xy 352.058042 -279.1503) (xy 352.054063 -279.203384) (xy 352.042217 -279.255281)
			(xy 352.022768 -279.304834) (xy 351.99615 -279.350934) (xy 351.962958 -279.392551) (xy 351.923934 -279.428756)
			(xy 351.879949 -279.45874) (xy 351.831986 -279.481833) (xy 351.781117 -279.49752) (xy 351.728478 -279.505448)
			(xy 351.701862 -279.505918) (xy 351.676892 -279.505471) (xy 351.627443 -279.498484) (xy 351.579457 -279.484653)
			(xy 351.533876 -279.464249) (xy 351.491594 -279.437674) (xy 351.453443 -279.405448) (xy 351.420172 -279.368206)
			(xy 351.405952 -279.347676) (xy 351.057972 -279.347676) (xy 351.043756 -279.368211) (xy 351.010492 -279.405465)
			(xy 350.972344 -279.4377) (xy 350.930062 -279.464282) (xy 350.884478 -279.484688) (xy 350.836487 -279.498518)
			(xy 350.787034 -279.505499) (xy 350.762062 -279.505918) (xy 350.735454 -279.505382) (xy 350.682833 -279.497446)
			(xy 350.631982 -279.481755) (xy 350.584038 -279.458662) (xy 350.54007 -279.428681) (xy 350.501062 -279.392483)
			(xy 350.467884 -279.350875) (xy 350.441278 -279.304788) (xy 350.421837 -279.25525) (xy 350.409996 -279.203367)
			(xy 350.406019 -279.1503) (xy 350.178878 -279.1503) (xy 350.178878 -279.150318) (xy 350.178878 -279.150826)
			(xy 350.178493 -279.174028) (xy 350.172427 -279.220035) (xy 350.160452 -279.264868) (xy 350.151954 -279.286462)
			(xy 350.142302 -279.309576) (xy 350.314514 -279.607264) (xy 350.339406 -279.610566) (xy 350.364784 -279.614422)
			(xy 350.414166 -279.628422) (xy 350.461033 -279.649355) (xy 350.504416 -279.676789) (xy 350.543419 -279.710157)
			(xy 350.577236 -279.748771) (xy 350.60517 -279.791833) (xy 350.626645 -279.838454) (xy 350.641215 -279.887672)
			(xy 350.648581 -279.93847) (xy 350.649032 -279.964134) (xy 350.648533 -279.990821) (xy 350.640578 -280.0436)
			(xy 350.624846 -280.094603) (xy 350.601688 -280.142692) (xy 350.571621 -280.186792) (xy 350.535317 -280.225919)
			(xy 350.493587 -280.259197) (xy 350.447363 -280.285884) (xy 350.397678 -280.305384) (xy 350.345641 -280.317261)
			(xy 350.292416 -280.32125) (xy 350.239191 -280.317261) (xy 350.187154 -280.305384) (xy 350.137469 -280.285884)
			(xy 350.091245 -280.259197) (xy 350.049515 -280.225919) (xy 350.013211 -280.186792) (xy 349.983144 -280.142692)
			(xy 349.959986 -280.094603) (xy 349.944254 -280.0436) (xy 349.936299 -279.990821) (xy 349.9358 -279.964134)
			(xy 349.936159 -279.940794) (xy 349.942262 -279.894515) (xy 349.954368 -279.849433) (xy 349.962978 -279.827736)
			(xy 349.97263 -279.804368) (xy 349.800926 -279.507188) (xy 349.776034 -279.503886) (xy 349.750612 -279.50008)
			(xy 349.701128 -279.486176) (xy 349.654153 -279.46531) (xy 349.610661 -279.437915) (xy 349.571554 -279.404559)
			(xy 349.537641 -279.365933) (xy 349.509627 -279.322838) (xy 349.488091 -279.276166) (xy 349.47348 -279.226886)
			(xy 349.466096 -279.176018) (xy 349.465646 -279.150318) (xy 104.117941 -279.150318) (xy 104.113964 -279.203381)
			(xy 104.102119 -279.255276) (xy 104.082672 -279.304826) (xy 104.056057 -279.350924) (xy 104.022868 -279.39254)
			(xy 103.983848 -279.428745) (xy 103.939867 -279.45873) (xy 103.891909 -279.481824) (xy 103.841044 -279.497513)
			(xy 103.788409 -279.505446) (xy 103.761794 -279.505918) (xy 103.736822 -279.505522) (xy 103.687371 -279.498526)
			(xy 103.639384 -279.484686) (xy 103.593802 -279.464274) (xy 103.551521 -279.437691) (xy 103.513372 -279.405458)
			(xy 103.480102 -279.368209) (xy 103.465884 -279.347676) (xy 103.117904 -279.347676) (xy 103.103668 -279.368196)
			(xy 103.070407 -279.40545) (xy 103.032263 -279.437686) (xy 102.989984 -279.46427) (xy 102.944403 -279.484679)
			(xy 102.896416 -279.498512) (xy 102.846965 -279.505497) (xy 102.821994 -279.505918) (xy 102.795384 -279.505384)
			(xy 102.74276 -279.497452) (xy 102.691905 -279.481764) (xy 102.643956 -279.458673) (xy 102.599985 -279.428693)
			(xy 102.560973 -279.392494) (xy 102.527791 -279.350885) (xy 102.501182 -279.304796) (xy 102.481739 -279.255255)
			(xy 102.469897 -279.20337) (xy 102.465919 -279.1503) (xy 102.23881 -279.1503) (xy 102.23881 -279.150318)
			(xy 102.23881 -279.150826) (xy 102.23843 -279.174028) (xy 102.232363 -279.220036) (xy 102.220386 -279.264869)
			(xy 102.211886 -279.286462) (xy 102.202234 -279.309576) (xy 102.374446 -279.607264) (xy 102.399338 -279.610566)
			(xy 102.42472 -279.614397) (xy 102.474103 -279.628401) (xy 102.520969 -279.649338) (xy 102.564351 -279.676775)
			(xy 102.603353 -279.710147) (xy 102.63717 -279.748763) (xy 102.665104 -279.791827) (xy 102.686577 -279.83845)
			(xy 102.701147 -279.88767) (xy 102.708513 -279.938469) (xy 102.708964 -279.964134) (xy 102.708465 -279.990821)
			(xy 102.70051 -280.0436) (xy 102.684778 -280.094603) (xy 102.66162 -280.142692) (xy 102.631553 -280.186792)
			(xy 102.595249 -280.225919) (xy 102.553519 -280.259197) (xy 102.507295 -280.285884) (xy 102.45761 -280.305384)
			(xy 102.405573 -280.317261) (xy 102.352348 -280.32125) (xy 102.299123 -280.317261) (xy 102.247086 -280.305384)
			(xy 102.197401 -280.285884) (xy 102.151177 -280.259197) (xy 102.109447 -280.225919) (xy 102.073143 -280.186792)
			(xy 102.043076 -280.142692) (xy 102.019918 -280.094603) (xy 102.004186 -280.0436) (xy 101.996231 -279.990821)
			(xy 101.995732 -279.964134) (xy 101.996096 -279.940794) (xy 102.002198 -279.894516) (xy 102.014301 -279.849433)
			(xy 102.02291 -279.827736) (xy 102.032562 -279.804368) (xy 101.860858 -279.507188) (xy 101.835966 -279.503886)
			(xy 101.810548 -279.500055) (xy 101.761064 -279.486155) (xy 101.714089 -279.465293) (xy 101.670597 -279.437902)
			(xy 101.631489 -279.404549) (xy 101.597576 -279.365925) (xy 101.56956 -279.322832) (xy 101.548024 -279.276162)
			(xy 101.533412 -279.226884) (xy 101.526029 -279.176018) (xy 101.525578 -279.150318) (xy 2.509012 -279.150318)
			(xy 2.509012 -279.9641) (xy 88.838835 -279.9641) (xy 88.842812 -279.911032) (xy 88.854654 -279.859149)
			(xy 88.874096 -279.809611) (xy 88.900704 -279.763524) (xy 88.933884 -279.721917) (xy 88.972895 -279.68572)
			(xy 89.016864 -279.655741) (xy 89.064811 -279.632651) (xy 89.115663 -279.616964) (xy 89.168286 -279.609032)
			(xy 89.194894 -279.608534) (xy 89.219864 -279.60896) (xy 89.269313 -279.615953) (xy 89.317299 -279.62979)
			(xy 89.36288 -279.650197) (xy 89.405161 -279.676776) (xy 89.443312 -279.709003) (xy 89.476584 -279.746246)
			(xy 89.490804 -279.766776) (xy 89.838784 -279.766776) (xy 89.853013 -279.746251) (xy 89.886276 -279.708999)
			(xy 89.924423 -279.676765) (xy 89.966702 -279.650182) (xy 90.012284 -279.629774) (xy 90.060272 -279.615942)
			(xy 90.109723 -279.608956) (xy 90.134694 -279.608534) (xy 90.16131 -279.608938) (xy 90.213947 -279.616871)
			(xy 90.264815 -279.632561) (xy 90.312775 -279.655657) (xy 90.356758 -279.685643) (xy 90.39578 -279.721849)
			(xy 90.42897 -279.763467) (xy 90.455586 -279.809568) (xy 90.475034 -279.85912) (xy 90.486879 -279.911017)
			(xy 90.490858 -279.9641) (xy 90.490855 -279.964134) (xy 96.356932 -279.964134) (xy 96.357431 -279.937447)
			(xy 96.365386 -279.884668) (xy 96.381118 -279.833665) (xy 96.404276 -279.785576) (xy 96.434343 -279.741476)
			(xy 96.470647 -279.702349) (xy 96.512377 -279.669071) (xy 96.558601 -279.642384) (xy 96.608286 -279.622884)
			(xy 96.660323 -279.611007) (xy 96.713548 -279.607018) (xy 96.766773 -279.611007) (xy 96.81881 -279.622884)
			(xy 96.868495 -279.642384) (xy 96.914719 -279.669071) (xy 96.956449 -279.702349) (xy 96.992753 -279.741476)
			(xy 97.02282 -279.785576) (xy 97.045978 -279.833665) (xy 97.06171 -279.884668) (xy 97.069665 -279.937447)
			(xy 97.070164 -279.964134) (xy 97.069649 -279.991571) (xy 97.061212 -280.045794) (xy 97.044588 -280.09809)
			(xy 97.032826 -280.122884) (xy 97.205292 -280.421334) (xy 97.230184 -280.424636) (xy 97.255554 -280.428539)
			(xy 97.304934 -280.442534) (xy 97.351799 -280.463462) (xy 97.395181 -280.49089) (xy 97.434183 -280.524253)
			(xy 97.468002 -280.562862) (xy 97.495937 -280.605919) (xy 97.517414 -280.652535) (xy 97.531987 -280.701748)
			(xy 97.539357 -280.752541) (xy 97.53981 -280.778204) (xy 97.539311 -280.804891) (xy 97.531356 -280.85767)
			(xy 97.515624 -280.908673) (xy 97.492466 -280.956762) (xy 97.462399 -281.000862) (xy 97.426095 -281.039989)
			(xy 97.384365 -281.073267) (xy 97.338141 -281.099954) (xy 97.288456 -281.119454) (xy 97.236419 -281.131331)
			(xy 97.183194 -281.13532) (xy 97.129969 -281.131331) (xy 97.077932 -281.119454) (xy 97.028247 -281.099954)
			(xy 96.982023 -281.073267) (xy 96.940293 -281.039989) (xy 96.903989 -281.000862) (xy 96.873922 -280.956762)
			(xy 96.850764 -280.908673) (xy 96.835032 -280.85767) (xy 96.827077 -280.804891) (xy 96.826578 -280.778204)
			(xy 96.826929 -280.754864) (xy 96.833036 -280.708585) (xy 96.845144 -280.663502) (xy 96.853756 -280.641806)
			(xy 96.863408 -280.618438) (xy 96.690688 -280.319988) (xy 96.663891 -280.31783) (xy 96.611364 -280.306374)
			(xy 96.561152 -280.287163) (xy 96.514394 -280.260632) (xy 96.472148 -280.227381) (xy 96.435373 -280.188166)
			(xy 96.404902 -280.143874) (xy 96.381426 -280.095509) (xy 96.365477 -280.044168) (xy 96.357416 -279.991015)
			(xy 96.356932 -279.964134) (xy 90.490855 -279.964134) (xy 90.486879 -280.017183) (xy 90.475034 -280.06908)
			(xy 90.455586 -280.118632) (xy 90.42897 -280.164733) (xy 90.39578 -280.206351) (xy 90.356758 -280.242557)
			(xy 90.312775 -280.272543) (xy 90.264815 -280.295639) (xy 90.213947 -280.311329) (xy 90.16131 -280.319262)
			(xy 90.134694 -280.319734) (xy 90.109723 -280.319331) (xy 90.060272 -280.312336) (xy 90.012285 -280.298496)
			(xy 89.966704 -280.278085) (xy 89.924423 -280.251503) (xy 89.886273 -280.219272) (xy 89.853003 -280.182024)
			(xy 89.838784 -280.161492) (xy 89.490804 -280.161492) (xy 89.476573 -280.182016) (xy 89.443311 -280.219269)
			(xy 89.405165 -280.251504) (xy 89.362886 -280.278088) (xy 89.317304 -280.298496) (xy 89.269316 -280.312328)
			(xy 89.219865 -280.319313) (xy 89.194894 -280.319734) (xy 89.168286 -280.319168) (xy 89.115663 -280.311236)
			(xy 89.064811 -280.295549) (xy 89.016864 -280.272459) (xy 88.972895 -280.24248) (xy 88.933884 -280.206283)
			(xy 88.900704 -280.164676) (xy 88.874096 -280.118589) (xy 88.854654 -280.069051) (xy 88.842812 -280.017168)
			(xy 88.838835 -279.9641) (xy 2.509012 -279.9641) (xy 2.509012 -280.7782) (xy 86.489305 -280.7782)
			(xy 86.493283 -280.725127) (xy 86.505125 -280.67324) (xy 86.524569 -280.623698) (xy 86.55118 -280.577607)
			(xy 86.584362 -280.535996) (xy 86.623376 -280.499796) (xy 86.667349 -280.469815) (xy 86.7153 -280.446723)
			(xy 86.766156 -280.431035) (xy 86.818783 -280.423102) (xy 86.845394 -280.422604) (xy 86.870341 -280.422967)
			(xy 86.919746 -280.429942) (xy 86.96769 -280.443755) (xy 87.013232 -280.464136) (xy 87.055478 -280.490683)
			(xy 87.093598 -280.522876) (xy 87.126842 -280.560082) (xy 87.14105 -280.580592) (xy 87.489538 -280.580592)
			(xy 87.503736 -280.560078) (xy 87.536991 -280.522888) (xy 87.575117 -280.490709) (xy 87.617365 -280.464175)
			(xy 87.662907 -280.443804) (xy 87.710849 -280.429997) (xy 87.760249 -280.423025) (xy 87.785194 -280.422604)
			(xy 87.811808 -280.423068) (xy 87.864441 -280.431001) (xy 87.915304 -280.446689) (xy 87.96326 -280.469783)
			(xy 88.007239 -280.499767) (xy 88.046258 -280.53597) (xy 88.079445 -280.577585) (xy 88.106059 -280.623681)
			(xy 88.125505 -280.673229) (xy 88.137349 -280.725121) (xy 88.141327 -280.7782) (xy 88.137349 -280.831279)
			(xy 88.125505 -280.883171) (xy 88.106059 -280.932719) (xy 88.079445 -280.978815) (xy 88.046258 -281.02043)
			(xy 88.007239 -281.056633) (xy 87.96326 -281.086617) (xy 87.915304 -281.109711) (xy 87.864441 -281.125399)
			(xy 87.811808 -281.133332) (xy 87.785194 -281.133804) (xy 87.760249 -281.13337) (xy 87.710848 -281.126408)
			(xy 87.662905 -281.112607) (xy 87.617363 -281.092238) (xy 87.575117 -281.065701) (xy 87.536995 -281.033519)
			(xy 87.503748 -280.996322) (xy 87.489538 -280.975816) (xy 87.14105 -280.975816) (xy 87.126863 -280.996338)
			(xy 87.093605 -281.033527) (xy 87.055477 -281.065705) (xy 87.013227 -281.092238) (xy 86.967684 -281.112608)
			(xy 86.919741 -281.126413) (xy 86.87034 -281.133384) (xy 86.845394 -281.133804) (xy 86.818783 -281.133298)
			(xy 86.766156 -281.125365) (xy 86.7153 -281.109677) (xy 86.667349 -281.086585) (xy 86.623376 -281.056604)
			(xy 86.584362 -281.020404) (xy 86.55118 -280.978793) (xy 86.524569 -280.932702) (xy 86.505125 -280.88316)
			(xy 86.493283 -280.831273) (xy 86.489305 -280.7782) (xy 2.509012 -280.7782) (xy 2.509012 -282.405836)
			(xy 86.489032 -282.405836) (xy 86.489501 -282.380169) (xy 86.496844 -282.329362) (xy 86.511398 -282.280134)
			(xy 86.532861 -282.233501) (xy 86.56079 -282.190429) (xy 86.594608 -282.151808) (xy 86.633615 -282.118436)
			(xy 86.677005 -282.091004) (xy 86.723881 -282.070077) (xy 86.773273 -282.05609) (xy 86.798658 -282.052268)
			(xy 86.82355 -282.048966) (xy 86.995508 -281.751278) (xy 86.985856 -281.728164) (xy 86.977357 -281.706571)
			(xy 86.965377 -281.661739) (xy 86.959321 -281.61573) (xy 86.958932 -281.592528) (xy 86.958932 -281.59202)
			(xy 86.959431 -281.565333) (xy 86.967386 -281.512554) (xy 86.983118 -281.461551) (xy 87.006276 -281.413462)
			(xy 87.036343 -281.369362) (xy 87.072647 -281.330235) (xy 87.114377 -281.296957) (xy 87.160601 -281.27027)
			(xy 87.210286 -281.25077) (xy 87.262323 -281.238893) (xy 87.315548 -281.234904) (xy 87.368773 -281.238893)
			(xy 87.42081 -281.25077) (xy 87.470495 -281.27027) (xy 87.516719 -281.296957) (xy 87.558449 -281.330235)
			(xy 87.594753 -281.369362) (xy 87.62482 -281.413462) (xy 87.647978 -281.461551) (xy 87.66371 -281.512554)
			(xy 87.671665 -281.565333) (xy 87.672164 -281.59202) (xy 88.838532 -281.59202) (xy 88.838987 -281.566352)
			(xy 88.846332 -281.515545) (xy 88.860887 -281.466316) (xy 88.882352 -281.419684) (xy 88.910283 -281.376612)
			(xy 88.944103 -281.337991) (xy 88.983111 -281.304619) (xy 89.026502 -281.277187) (xy 89.073379 -281.256261)
			(xy 89.122773 -281.242274) (xy 89.148158 -281.238452) (xy 89.17305 -281.23515) (xy 89.345516 -280.936954)
			(xy 89.333735 -280.912167) (xy 89.317092 -280.859873) (xy 89.308679 -280.805643) (xy 89.308178 -280.778204)
			(xy 89.308677 -280.751517) (xy 89.316632 -280.698738) (xy 89.332364 -280.647735) (xy 89.355522 -280.599646)
			(xy 89.385589 -280.555546) (xy 89.421893 -280.516419) (xy 89.463623 -280.483141) (xy 89.509847 -280.456454)
			(xy 89.559532 -280.436954) (xy 89.611569 -280.425077) (xy 89.664794 -280.421088) (xy 89.718019 -280.425077)
			(xy 89.770056 -280.436954) (xy 89.819741 -280.456454) (xy 89.865965 -280.483141) (xy 89.907695 -280.516419)
			(xy 89.943999 -280.555546) (xy 89.974066 -280.599646) (xy 89.997224 -280.647735) (xy 90.012956 -280.698738)
			(xy 90.020911 -280.751517) (xy 90.02141 -280.778204) (xy 92.127832 -280.778204) (xy 92.128331 -280.751517)
			(xy 92.136286 -280.698738) (xy 92.152018 -280.647735) (xy 92.175176 -280.599646) (xy 92.205243 -280.555546)
			(xy 92.241547 -280.516419) (xy 92.283277 -280.483141) (xy 92.329501 -280.456454) (xy 92.379186 -280.436954)
			(xy 92.431223 -280.425077) (xy 92.484448 -280.421088) (xy 92.537673 -280.425077) (xy 92.58971 -280.436954)
			(xy 92.639395 -280.456454) (xy 92.685619 -280.483141) (xy 92.727349 -280.516419) (xy 92.763653 -280.555546)
			(xy 92.79372 -280.599646) (xy 92.816878 -280.647735) (xy 92.83261 -280.698738) (xy 92.840565 -280.751517)
			(xy 92.841064 -280.7782) (xy 94.947505 -280.7782) (xy 94.951483 -280.725127) (xy 94.963325 -280.67324)
			(xy 94.982769 -280.623698) (xy 95.00938 -280.577607) (xy 95.042562 -280.535996) (xy 95.081576 -280.499796)
			(xy 95.125549 -280.469815) (xy 95.1735 -280.446723) (xy 95.224356 -280.431035) (xy 95.276983 -280.423102)
			(xy 95.303594 -280.422604) (xy 95.328541 -280.422967) (xy 95.377946 -280.429942) (xy 95.42589 -280.443755)
			(xy 95.471432 -280.464136) (xy 95.513678 -280.490683) (xy 95.551798 -280.522876) (xy 95.585042 -280.560082)
			(xy 95.59925 -280.580592) (xy 95.947992 -280.580592) (xy 95.962219 -280.560099) (xy 95.99547 -280.522908)
			(xy 96.03359 -280.490729) (xy 96.075834 -280.464192) (xy 96.121371 -280.443817) (xy 96.169308 -280.430006)
			(xy 96.218704 -280.423028) (xy 96.243648 -280.422604) (xy 96.270257 -280.423097) (xy 96.32288 -280.431035)
			(xy 96.373733 -280.446727) (xy 96.421679 -280.469822) (xy 96.465648 -280.499805) (xy 96.504657 -280.536006)
			(xy 96.537836 -280.577615) (xy 96.564443 -280.623705) (xy 96.583885 -280.673246) (xy 96.595726 -280.72513)
			(xy 96.599703 -280.7782) (xy 96.595726 -280.83127) (xy 96.583885 -280.883154) (xy 96.564443 -280.932695)
			(xy 96.537836 -280.978785) (xy 96.504657 -281.020394) (xy 96.465648 -281.056595) (xy 96.421679 -281.086578)
			(xy 96.373733 -281.109673) (xy 96.32288 -281.125365) (xy 96.270257 -281.133303) (xy 96.243648 -281.133804)
			(xy 96.218702 -281.133405) (xy 96.169299 -281.126437) (xy 96.121356 -281.112629) (xy 96.075814 -281.092255)
			(xy 96.033568 -281.065713) (xy 95.995447 -281.033525) (xy 95.962201 -280.996324) (xy 95.947992 -280.975816)
			(xy 95.59925 -280.975816) (xy 95.585063 -280.996338) (xy 95.551805 -281.033527) (xy 95.513677 -281.065705)
			(xy 95.471427 -281.092238) (xy 95.425884 -281.112608) (xy 95.377941 -281.126413) (xy 95.32854 -281.133384)
			(xy 95.303594 -281.133804) (xy 95.276983 -281.133298) (xy 95.224356 -281.125365) (xy 95.1735 -281.109677)
			(xy 95.125549 -281.086585) (xy 95.081576 -281.056604) (xy 95.042562 -281.020404) (xy 95.00938 -280.978793)
			(xy 94.982769 -280.932702) (xy 94.963325 -280.88316) (xy 94.951483 -280.831273) (xy 94.947505 -280.7782)
			(xy 92.841064 -280.7782) (xy 92.841064 -280.778204) (xy 92.840538 -280.805641) (xy 92.832106 -280.859863)
			(xy 92.815486 -280.91216) (xy 92.803726 -280.936954) (xy 92.976192 -281.23515) (xy 93.001084 -281.238452)
			(xy 93.026456 -281.242339) (xy 93.075838 -281.256335) (xy 93.122704 -281.277264) (xy 93.166086 -281.304694)
			(xy 93.205089 -281.338059) (xy 93.238908 -281.37667) (xy 93.266843 -281.419729) (xy 93.288318 -281.466347)
			(xy 93.30289 -281.515561) (xy 93.310258 -281.566357) (xy 93.31071 -281.59202) (xy 93.310211 -281.618707)
			(xy 93.302256 -281.671486) (xy 93.286524 -281.722489) (xy 93.263366 -281.770578) (xy 93.233299 -281.814678)
			(xy 93.196995 -281.853805) (xy 93.155265 -281.887083) (xy 93.109041 -281.91377) (xy 93.059356 -281.93327)
			(xy 93.007319 -281.945147) (xy 92.954094 -281.949136) (xy 92.900869 -281.945147) (xy 92.848832 -281.93327)
			(xy 92.799147 -281.91377) (xy 92.752923 -281.887083) (xy 92.711193 -281.853805) (xy 92.674889 -281.814678)
			(xy 92.644822 -281.770578) (xy 92.621664 -281.722489) (xy 92.605932 -281.671486) (xy 92.597977 -281.618707)
			(xy 92.597478 -281.59202) (xy 92.597478 -281.591512) (xy 92.597871 -281.56831) (xy 92.603933 -281.522303)
			(xy 92.615905 -281.47747) (xy 92.624402 -281.455876) (xy 92.634054 -281.432762) (xy 92.461588 -281.134058)
			(xy 92.434798 -281.131831) (xy 92.382278 -281.120378) (xy 92.332071 -281.101172) (xy 92.285317 -281.074647)
			(xy 92.243073 -281.041404) (xy 92.206299 -281.002197) (xy 92.175826 -280.957914) (xy 92.152346 -280.909559)
			(xy 92.13639 -280.858227) (xy 92.128321 -280.805081) (xy 92.127832 -280.778204) (xy 90.02141 -280.778204)
			(xy 90.020902 -280.805081) (xy 90.012834 -280.858226) (xy 89.996879 -280.909558) (xy 89.973401 -280.957913)
			(xy 89.942931 -281.002197) (xy 89.906159 -281.041406) (xy 89.863919 -281.074651) (xy 89.817167 -281.10118)
			(xy 89.766963 -281.12039) (xy 89.714444 -281.131848) (xy 89.687654 -281.134058) (xy 89.515188 -281.432508)
			(xy 89.52484 -281.455622) (xy 89.533362 -281.477297) (xy 89.545366 -281.522298) (xy 89.551402 -281.568479)
			(xy 89.551764 -281.591766) (xy 89.551764 -281.592) (xy 90.718421 -281.592) (xy 90.722399 -281.53893)
			(xy 90.734241 -281.487045) (xy 90.753684 -281.437505) (xy 90.780293 -281.391416) (xy 90.813474 -281.349807)
			(xy 90.852486 -281.313609) (xy 90.896457 -281.283629) (xy 90.944406 -281.260538) (xy 90.99526 -281.24485)
			(xy 91.047885 -281.236918) (xy 91.074494 -281.23642) (xy 91.09944 -281.23682) (xy 91.148841 -281.243793)
			(xy 91.196783 -281.257603) (xy 91.242324 -281.277978) (xy 91.284569 -281.304519) (xy 91.322691 -281.336704)
			(xy 91.355939 -281.373902) (xy 91.37015 -281.394408) (xy 91.718638 -281.394408) (xy 91.732841 -281.373897)
			(xy 91.766095 -281.336706) (xy 91.80422 -281.304527) (xy 91.846467 -281.277992) (xy 91.892008 -281.257621)
			(xy 91.939949 -281.243813) (xy 91.989349 -281.236841) (xy 92.014294 -281.23642) (xy 92.040909 -281.236852)
			(xy 92.093544 -281.244785) (xy 92.14441 -281.260474) (xy 92.192368 -281.283569) (xy 92.236349 -281.313554)
			(xy 92.27537 -281.349759) (xy 92.308558 -281.391375) (xy 92.335173 -281.437474) (xy 92.354621 -281.487024)
			(xy 92.366466 -281.538919) (xy 92.370444 -281.592) (xy 92.366466 -281.645081) (xy 92.354621 -281.696976)
			(xy 92.335173 -281.746526) (xy 92.308558 -281.792625) (xy 92.27537 -281.834241) (xy 92.236349 -281.870446)
			(xy 92.192368 -281.900431) (xy 92.14441 -281.923526) (xy 92.093544 -281.939215) (xy 92.040909 -281.947148)
			(xy 92.014294 -281.94762) (xy 91.989349 -281.947179) (xy 91.939949 -281.940217) (xy 91.892007 -281.926417)
			(xy 91.846465 -281.906049) (xy 91.804218 -281.879513) (xy 91.766097 -281.847332) (xy 91.732849 -281.810137)
			(xy 91.718638 -281.789632) (xy 91.37015 -281.789632) (xy 91.355968 -281.810157) (xy 91.322709 -281.847346)
			(xy 91.28458 -281.879523) (xy 91.242329 -281.906056) (xy 91.196785 -281.926425) (xy 91.148842 -281.94023)
			(xy 91.09944 -281.9472) (xy 91.074494 -281.94762) (xy 91.047885 -281.947082) (xy 90.99526 -281.93915)
			(xy 90.944406 -281.923462) (xy 90.896457 -281.900371) (xy 90.852486 -281.870391) (xy 90.813474 -281.834193)
			(xy 90.780293 -281.792584) (xy 90.753684 -281.746495) (xy 90.734241 -281.696955) (xy 90.722399 -281.64507)
			(xy 90.718421 -281.592) (xy 89.551764 -281.592) (xy 89.551764 -281.59202) (xy 89.551265 -281.618707)
			(xy 89.54331 -281.671486) (xy 89.527578 -281.722489) (xy 89.50442 -281.770578) (xy 89.474353 -281.814678)
			(xy 89.438049 -281.853805) (xy 89.396319 -281.887083) (xy 89.350095 -281.91377) (xy 89.30041 -281.93327)
			(xy 89.248373 -281.945147) (xy 89.195148 -281.949136) (xy 89.141923 -281.945147) (xy 89.089886 -281.93327)
			(xy 89.040201 -281.91377) (xy 88.993977 -281.887083) (xy 88.952247 -281.853805) (xy 88.915943 -281.814678)
			(xy 88.885876 -281.770578) (xy 88.862718 -281.722489) (xy 88.846986 -281.671486) (xy 88.839031 -281.618707)
			(xy 88.838532 -281.59202) (xy 87.672164 -281.59202) (xy 87.67175 -281.617689) (xy 87.664399 -281.668498)
			(xy 87.649838 -281.717728) (xy 87.628368 -281.764361) (xy 87.600432 -281.807433) (xy 87.566608 -281.846053)
			(xy 87.527596 -281.879424) (xy 87.484201 -281.906856) (xy 87.437321 -281.92778) (xy 87.387925 -281.941766)
			(xy 87.362538 -281.945588) (xy 87.337646 -281.94889) (xy 87.165688 -282.246578) (xy 87.17534 -282.269692)
			(xy 87.183855 -282.291279) (xy 87.195829 -282.336114) (xy 87.201879 -282.382125) (xy 87.202264 -282.405328)
			(xy 87.202264 -282.405836) (xy 87.428578 -282.405836) (xy 87.429077 -282.379149) (xy 87.437032 -282.32637)
			(xy 87.452764 -282.275367) (xy 87.475922 -282.227278) (xy 87.505989 -282.183178) (xy 87.542293 -282.144051)
			(xy 87.584023 -282.110773) (xy 87.630247 -282.084086) (xy 87.679932 -282.064586) (xy 87.731969 -282.052709)
			(xy 87.785194 -282.04872) (xy 87.838419 -282.052709) (xy 87.890456 -282.064586) (xy 87.940141 -282.084086)
			(xy 87.986365 -282.110773) (xy 88.028095 -282.144051) (xy 88.064399 -282.183178) (xy 88.094466 -282.227278)
			(xy 88.117624 -282.275367) (xy 88.133356 -282.32637) (xy 88.141311 -282.379149) (xy 88.141809 -282.4058)
			(xy 88.369113 -282.4058) (xy 88.373091 -282.352723) (xy 88.384936 -282.300833) (xy 88.404383 -282.251287)
			(xy 88.430997 -282.205194) (xy 88.464185 -282.163583) (xy 88.503205 -282.127383) (xy 88.547184 -282.097404)
			(xy 88.595141 -282.074315) (xy 88.646003 -282.058632) (xy 88.698635 -282.050705) (xy 88.725248 -282.050236)
			(xy 88.750193 -282.050664) (xy 88.799593 -282.057631) (xy 88.847535 -282.071435) (xy 88.893076 -282.091806)
			(xy 88.935322 -282.118342) (xy 88.973444 -282.150524) (xy 89.006693 -282.187719) (xy 89.020904 -282.208224)
			(xy 89.369392 -282.208224) (xy 89.383629 -282.187738) (xy 89.416877 -282.150546) (xy 89.454995 -282.118365)
			(xy 89.497237 -282.091826) (xy 89.542773 -282.071451) (xy 89.590709 -282.057638) (xy 89.640105 -282.05066)
			(xy 89.665048 -282.050236) (xy 89.69166 -282.050665) (xy 89.744288 -282.058604) (xy 89.795145 -282.074297)
			(xy 89.843095 -282.097395) (xy 89.887068 -282.12738) (xy 89.926081 -282.163584) (xy 89.959262 -282.205197)
			(xy 89.985872 -282.251291) (xy 90.005315 -282.300836) (xy 90.017157 -282.352725) (xy 90.021135 -282.4058)
			(xy 90.017157 -282.458875) (xy 90.005315 -282.510764) (xy 89.985872 -282.560309) (xy 89.959262 -282.606403)
			(xy 89.926081 -282.648016) (xy 89.887068 -282.68422) (xy 89.843095 -282.714206) (xy 89.795145 -282.737303)
			(xy 89.744288 -282.752996) (xy 89.69166 -282.760935) (xy 89.665048 -282.761436) (xy 89.640103 -282.761023)
			(xy 89.590701 -282.754055) (xy 89.542759 -282.740249) (xy 89.497217 -282.719876) (xy 89.454971 -282.693337)
			(xy 89.41685 -282.661152) (xy 89.383602 -282.623954) (xy 89.369392 -282.603448) (xy 89.020904 -282.603448)
			(xy 89.00666 -282.623929) (xy 88.973415 -282.661123) (xy 88.935298 -282.693305) (xy 88.893057 -282.719845)
			(xy 88.847522 -282.740221) (xy 88.799587 -282.754034) (xy 88.750191 -282.761012) (xy 88.725248 -282.761436)
			(xy 88.698635 -282.760895) (xy 88.646003 -282.752968) (xy 88.595141 -282.737285) (xy 88.547184 -282.714196)
			(xy 88.503205 -282.684217) (xy 88.464185 -282.648017) (xy 88.430997 -282.606406) (xy 88.404383 -282.560313)
			(xy 88.384936 -282.510767) (xy 88.373091 -282.458877) (xy 88.369113 -282.4058) (xy 88.141809 -282.4058)
			(xy 88.14181 -282.405836) (xy 88.141441 -282.429175) (xy 88.135342 -282.475454) (xy 88.12324 -282.520537)
			(xy 88.114632 -282.542234) (xy 88.10498 -282.565602) (xy 88.277192 -282.863036) (xy 88.30183 -282.866338)
			(xy 88.327237 -282.870094) (xy 88.376658 -282.88407) (xy 88.423564 -282.904989) (xy 88.466985 -282.932419)
			(xy 88.506023 -282.965793) (xy 88.539871 -283.004421) (xy 88.567829 -283.047504) (xy 88.58932 -283.094151)
			(xy 88.603898 -283.143398) (xy 88.611263 -283.194226) (xy 88.61171 -283.219906) (xy 90.717878 -283.219906)
			(xy 90.71828 -283.194236) (xy 90.725628 -283.143425) (xy 90.740188 -283.094192) (xy 90.761658 -283.047558)
			(xy 90.789595 -283.004484) (xy 90.82342 -282.965863) (xy 90.862435 -282.932492) (xy 90.905833 -282.905062)
			(xy 90.952717 -282.884139) (xy 91.002116 -282.870157) (xy 91.027504 -282.866338) (xy 91.052396 -282.863036)
			(xy 91.224608 -282.565094) (xy 91.214956 -282.54198) (xy 91.206462 -282.520385) (xy 91.19448 -282.475554)
			(xy 91.188422 -282.429546) (xy 91.188032 -282.406344) (xy 91.188032 -282.405836) (xy 91.188531 -282.379149)
			(xy 91.196486 -282.32637) (xy 91.212218 -282.275367) (xy 91.235376 -282.227278) (xy 91.265443 -282.183178)
			(xy 91.301747 -282.144051) (xy 91.343477 -282.110773) (xy 91.389701 -282.084086) (xy 91.439386 -282.064586)
			(xy 91.491423 -282.052709) (xy 91.544648 -282.04872) (xy 91.597873 -282.052709) (xy 91.64991 -282.064586)
			(xy 91.699595 -282.084086) (xy 91.745819 -282.110773) (xy 91.787549 -282.144051) (xy 91.823853 -282.183178)
			(xy 91.85392 -282.227278) (xy 91.877078 -282.275367) (xy 91.89281 -282.32637) (xy 91.900765 -282.379149)
			(xy 91.901264 -282.405836) (xy 93.067632 -282.405836) (xy 93.068101 -282.380169) (xy 93.075444 -282.329362)
			(xy 93.089998 -282.280134) (xy 93.111461 -282.233501) (xy 93.13939 -282.190429) (xy 93.173208 -282.151808)
			(xy 93.212215 -282.118436) (xy 93.255605 -282.091004) (xy 93.302481 -282.070077) (xy 93.351873 -282.05609)
			(xy 93.377258 -282.052268) (xy 93.40215 -282.048966) (xy 93.574108 -281.751786) (xy 93.564456 -281.728418)
			(xy 93.555872 -281.706714) (xy 93.54379 -281.66163) (xy 93.537677 -281.615357) (xy 93.537278 -281.59202)
			(xy 93.537777 -281.565333) (xy 93.545732 -281.512554) (xy 93.561464 -281.461551) (xy 93.584622 -281.413462)
			(xy 93.614689 -281.369362) (xy 93.650993 -281.330235) (xy 93.692723 -281.296957) (xy 93.738947 -281.27027)
			(xy 93.788632 -281.25077) (xy 93.840669 -281.238893) (xy 93.893894 -281.234904) (xy 93.947119 -281.238893)
			(xy 93.999156 -281.25077) (xy 94.048841 -281.27027) (xy 94.095065 -281.296957) (xy 94.136795 -281.330235)
			(xy 94.173099 -281.369362) (xy 94.203166 -281.413462) (xy 94.226324 -281.461551) (xy 94.242056 -281.512554)
			(xy 94.250011 -281.565333) (xy 94.25051 -281.59202) (xy 94.250142 -281.617691) (xy 94.24279 -281.668504)
			(xy 94.228227 -281.717738) (xy 94.206752 -281.764374) (xy 94.178812 -281.807447) (xy 94.144982 -281.846069)
			(xy 94.105964 -281.879439) (xy 94.062562 -281.906868) (xy 94.015676 -281.927789) (xy 93.966274 -281.94177)
			(xy 93.940884 -281.945588) (xy 93.915992 -281.94889) (xy 93.744034 -282.24607) (xy 93.753686 -282.269438)
			(xy 93.762259 -282.291147) (xy 93.774344 -282.336229) (xy 93.780462 -282.3825) (xy 93.780864 -282.405836)
			(xy 94.946978 -282.405836) (xy 94.947408 -282.380167) (xy 94.954752 -282.329356) (xy 94.969307 -282.280125)
			(xy 94.990774 -282.23349) (xy 95.018707 -282.190417) (xy 95.05253 -282.151795) (xy 95.091543 -282.118423)
			(xy 95.134938 -282.090993) (xy 95.181819 -282.07007) (xy 95.231217 -282.056088) (xy 95.256604 -282.052268)
			(xy 95.281496 -282.048966) (xy 95.453708 -281.751278) (xy 95.444056 -281.728164) (xy 95.435557 -281.706571)
			(xy 95.423577 -281.661739) (xy 95.417521 -281.61573) (xy 95.417132 -281.592528) (xy 95.417132 -281.59202)
			(xy 95.417631 -281.565333) (xy 95.425586 -281.512554) (xy 95.441318 -281.461551) (xy 95.464476 -281.413462)
			(xy 95.494543 -281.369362) (xy 95.530847 -281.330235) (xy 95.572577 -281.296957) (xy 95.618801 -281.27027)
			(xy 95.668486 -281.25077) (xy 95.720523 -281.238893) (xy 95.773748 -281.234904) (xy 95.826973 -281.238893)
			(xy 95.87901 -281.25077) (xy 95.928695 -281.27027) (xy 95.974919 -281.296957) (xy 96.016649 -281.330235)
			(xy 96.052953 -281.369362) (xy 96.08302 -281.413462) (xy 96.106178 -281.461551) (xy 96.12191 -281.512554)
			(xy 96.129865 -281.565333) (xy 96.130364 -281.59202) (xy 97.296732 -281.59202) (xy 97.297187 -281.566352)
			(xy 97.304532 -281.515545) (xy 97.319087 -281.466316) (xy 97.340552 -281.419684) (xy 97.368483 -281.376612)
			(xy 97.402303 -281.337991) (xy 97.441311 -281.304619) (xy 97.484702 -281.277187) (xy 97.531579 -281.256261)
			(xy 97.580973 -281.242274) (xy 97.606358 -281.238452) (xy 97.63125 -281.23515) (xy 97.803208 -280.93797)
			(xy 97.793556 -280.914602) (xy 97.784997 -280.892888) (xy 97.772906 -280.847809) (xy 97.766782 -280.80154)
			(xy 97.766378 -280.778204) (xy 97.766877 -280.751517) (xy 97.774832 -280.698738) (xy 97.790564 -280.647735)
			(xy 97.813722 -280.599646) (xy 97.843789 -280.555546) (xy 97.880093 -280.516419) (xy 97.921823 -280.483141)
			(xy 97.968047 -280.456454) (xy 98.017732 -280.436954) (xy 98.069769 -280.425077) (xy 98.122994 -280.421088)
			(xy 98.176219 -280.425077) (xy 98.228256 -280.436954) (xy 98.277941 -280.456454) (xy 98.324165 -280.483141)
			(xy 98.365895 -280.516419) (xy 98.402199 -280.555546) (xy 98.432266 -280.599646) (xy 98.455424 -280.647735)
			(xy 98.471156 -280.698738) (xy 98.479111 -280.751517) (xy 98.47961 -280.778204) (xy 100.585778 -280.778204)
			(xy 100.586277 -280.751517) (xy 100.594232 -280.698738) (xy 100.609964 -280.647735) (xy 100.633122 -280.599646)
			(xy 100.663189 -280.555546) (xy 100.699493 -280.516419) (xy 100.741223 -280.483141) (xy 100.787447 -280.456454)
			(xy 100.837132 -280.436954) (xy 100.889169 -280.425077) (xy 100.942394 -280.421088) (xy 100.995619 -280.425077)
			(xy 101.047656 -280.436954) (xy 101.097341 -280.456454) (xy 101.143565 -280.483141) (xy 101.185295 -280.516419)
			(xy 101.221599 -280.555546) (xy 101.251666 -280.599646) (xy 101.274824 -280.647735) (xy 101.290556 -280.698738)
			(xy 101.298511 -280.751517) (xy 101.29901 -280.778204) (xy 103.405178 -280.778204) (xy 103.405677 -280.751517)
			(xy 103.413632 -280.698738) (xy 103.429364 -280.647735) (xy 103.452522 -280.599646) (xy 103.482589 -280.555546)
			(xy 103.518893 -280.516419) (xy 103.560623 -280.483141) (xy 103.606847 -280.456454) (xy 103.656532 -280.436954)
			(xy 103.708569 -280.425077) (xy 103.761794 -280.421088) (xy 103.815019 -280.425077) (xy 103.867056 -280.436954)
			(xy 103.916741 -280.456454) (xy 103.962965 -280.483141) (xy 104.004695 -280.516419) (xy 104.040999 -280.555546)
			(xy 104.071066 -280.599646) (xy 104.094224 -280.647735) (xy 104.109956 -280.698738) (xy 104.117911 -280.751517)
			(xy 104.11841 -280.778204) (xy 104.344978 -280.778204) (xy 104.345378 -280.752534) (xy 104.352727 -280.701722)
			(xy 104.367287 -280.65249) (xy 104.388757 -280.605855) (xy 104.416694 -280.562782) (xy 104.45052 -280.52416)
			(xy 104.489535 -280.49079) (xy 104.532933 -280.46336) (xy 104.579816 -280.442437) (xy 104.629216 -280.428455)
			(xy 104.654604 -280.424636) (xy 104.679496 -280.421334) (xy 104.851708 -280.123392) (xy 104.842056 -280.100278)
			(xy 104.833561 -280.078683) (xy 104.82158 -280.033852) (xy 104.815522 -279.987844) (xy 104.815132 -279.964642)
			(xy 104.815132 -279.964134) (xy 104.815631 -279.937447) (xy 104.823586 -279.884668) (xy 104.839318 -279.833665)
			(xy 104.862476 -279.785576) (xy 104.892543 -279.741476) (xy 104.928847 -279.702349) (xy 104.970577 -279.669071)
			(xy 105.016801 -279.642384) (xy 105.066486 -279.622884) (xy 105.118523 -279.611007) (xy 105.171748 -279.607018)
			(xy 105.224973 -279.611007) (xy 105.27701 -279.622884) (xy 105.326695 -279.642384) (xy 105.372919 -279.669071)
			(xy 105.414649 -279.702349) (xy 105.450953 -279.741476) (xy 105.48102 -279.785576) (xy 105.504178 -279.833665)
			(xy 105.51991 -279.884668) (xy 105.527865 -279.937447) (xy 105.528363 -279.9641) (xy 336.778935 -279.9641)
			(xy 336.782912 -279.911035) (xy 336.794752 -279.859155) (xy 336.814192 -279.809619) (xy 336.840798 -279.763534)
			(xy 336.873974 -279.721928) (xy 336.91298 -279.685731) (xy 336.956946 -279.655752) (xy 337.004888 -279.632659)
			(xy 337.055736 -279.61697) (xy 337.108355 -279.609034) (xy 337.134962 -279.608534) (xy 337.159931 -279.608984)
			(xy 337.209379 -279.615973) (xy 337.257364 -279.629805) (xy 337.302945 -279.650209) (xy 337.345227 -279.676784)
			(xy 337.383378 -279.709007) (xy 337.416651 -279.746247) (xy 337.430872 -279.766776) (xy 337.778852 -279.766776)
			(xy 337.793037 -279.746219) (xy 337.826308 -279.708968) (xy 337.864462 -279.676736) (xy 337.906749 -279.650157)
			(xy 337.952338 -279.629755) (xy 338.000332 -279.615929) (xy 338.049789 -279.608952) (xy 338.074762 -279.608534)
			(xy 338.10138 -279.608936) (xy 338.154021 -279.616865) (xy 338.204892 -279.632552) (xy 338.252857 -279.655646)
			(xy 338.296844 -279.685631) (xy 338.33587 -279.721838) (xy 338.369063 -279.763457) (xy 338.395682 -279.809559)
			(xy 338.415132 -279.859114) (xy 338.426979 -279.911014) (xy 338.430958 -279.9641) (xy 338.430955 -279.964134)
			(xy 344.297 -279.964134) (xy 344.297499 -279.937447) (xy 344.305454 -279.884668) (xy 344.321186 -279.833665)
			(xy 344.344344 -279.785576) (xy 344.374411 -279.741476) (xy 344.410715 -279.702349) (xy 344.452445 -279.669071)
			(xy 344.498669 -279.642384) (xy 344.548354 -279.622884) (xy 344.600391 -279.611007) (xy 344.653616 -279.607018)
			(xy 344.706841 -279.611007) (xy 344.758878 -279.622884) (xy 344.808563 -279.642384) (xy 344.854787 -279.669071)
			(xy 344.896517 -279.702349) (xy 344.932821 -279.741476) (xy 344.962888 -279.785576) (xy 344.986046 -279.833665)
			(xy 345.001778 -279.884668) (xy 345.009733 -279.937447) (xy 345.010232 -279.964134) (xy 345.00972 -279.991571)
			(xy 345.001283 -280.045794) (xy 344.984657 -280.098091) (xy 344.972894 -280.122884) (xy 345.14536 -280.421334)
			(xy 345.170252 -280.424636) (xy 345.19563 -280.428485) (xy 345.245011 -280.442489) (xy 345.291876 -280.463426)
			(xy 345.335256 -280.490862) (xy 345.374258 -280.524231) (xy 345.408074 -280.562845) (xy 345.436008 -280.605907)
			(xy 345.457483 -280.652527) (xy 345.472056 -280.701743) (xy 345.479425 -280.75254) (xy 345.479878 -280.778204)
			(xy 345.479379 -280.804891) (xy 345.471424 -280.85767) (xy 345.455692 -280.908673) (xy 345.432534 -280.956762)
			(xy 345.402467 -281.000862) (xy 345.366163 -281.039989) (xy 345.324433 -281.073267) (xy 345.278209 -281.099954)
			(xy 345.228524 -281.119454) (xy 345.176487 -281.131331) (xy 345.123262 -281.13532) (xy 345.070037 -281.131331)
			(xy 345.018 -281.119454) (xy 344.968315 -281.099954) (xy 344.922091 -281.073267) (xy 344.880361 -281.039989)
			(xy 344.844057 -281.000862) (xy 344.81399 -280.956762) (xy 344.790832 -280.908673) (xy 344.7751 -280.85767)
			(xy 344.767145 -280.804891) (xy 344.766646 -280.778204) (xy 344.766999 -280.754864) (xy 344.773105 -280.708585)
			(xy 344.785213 -280.663503) (xy 344.793824 -280.641806) (xy 344.803476 -280.618438) (xy 344.630756 -280.319988)
			(xy 344.603956 -280.317857) (xy 344.551429 -280.306397) (xy 344.501217 -280.287182) (xy 344.454459 -280.260647)
			(xy 344.412214 -280.227393) (xy 344.375439 -280.188175) (xy 344.344969 -280.14388) (xy 344.321494 -280.095513)
			(xy 344.305545 -280.044171) (xy 344.297484 -279.991016) (xy 344.297 -279.964134) (xy 338.430955 -279.964134)
			(xy 338.426979 -280.017186) (xy 338.415132 -280.069086) (xy 338.395682 -280.118641) (xy 338.369063 -280.164743)
			(xy 338.33587 -280.206362) (xy 338.296844 -280.242569) (xy 338.252857 -280.272554) (xy 338.204892 -280.295648)
			(xy 338.154021 -280.311335) (xy 338.10138 -280.319264) (xy 338.074762 -280.319734) (xy 338.049792 -280.31928)
			(xy 338.000344 -280.312293) (xy 337.952359 -280.298463) (xy 337.906777 -280.27806) (xy 337.864496 -280.251486)
			(xy 337.826344 -280.219262) (xy 337.793072 -280.182021) (xy 337.778852 -280.161492) (xy 337.430872 -280.161492)
			(xy 337.416661 -280.18203) (xy 337.383396 -280.219284) (xy 337.345247 -280.251518) (xy 337.302964 -280.278099)
			(xy 337.257379 -280.298505) (xy 337.209388 -280.312334) (xy 337.159934 -280.319315) (xy 337.134962 -280.319734)
			(xy 337.108355 -280.319166) (xy 337.055736 -280.31123) (xy 337.004888 -280.295541) (xy 336.956946 -280.272448)
			(xy 336.91298 -280.242469) (xy 336.873974 -280.206272) (xy 336.840798 -280.164666) (xy 336.814192 -280.118581)
			(xy 336.794752 -280.069045) (xy 336.782912 -280.017165) (xy 336.778935 -279.9641) (xy 105.528363 -279.9641)
			(xy 105.528364 -279.964134) (xy 105.527866 -279.989833) (xy 105.520482 -280.040697) (xy 105.505873 -280.089975)
			(xy 105.484341 -280.136644) (xy 105.456333 -280.17974) (xy 105.422427 -280.218368) (xy 105.383328 -280.251728)
			(xy 105.339844 -280.27913) (xy 105.292877 -280.300005) (xy 105.243399 -280.313922) (xy 105.217976 -280.317702)
			(xy 105.193084 -280.321004) (xy 105.02138 -280.618438) (xy 105.031032 -280.641806) (xy 105.039598 -280.663517)
			(xy 105.051685 -280.708598) (xy 105.057807 -280.754868) (xy 105.05821 -280.7782) (xy 105.285305 -280.7782)
			(xy 105.289283 -280.725127) (xy 105.301125 -280.67324) (xy 105.320569 -280.623698) (xy 105.34718 -280.577607)
			(xy 105.380362 -280.535996) (xy 105.419376 -280.499796) (xy 105.463349 -280.469815) (xy 105.5113 -280.446723)
			(xy 105.562156 -280.431035) (xy 105.614783 -280.423102) (xy 105.641394 -280.422604) (xy 105.666341 -280.422967)
			(xy 105.715746 -280.429942) (xy 105.76369 -280.443755) (xy 105.809232 -280.464136) (xy 105.851478 -280.490683)
			(xy 105.889598 -280.522876) (xy 105.922842 -280.560082) (xy 105.93705 -280.580592) (xy 106.285538 -280.580592)
			(xy 106.299736 -280.560078) (xy 106.332991 -280.522888) (xy 106.371117 -280.490709) (xy 106.413365 -280.464175)
			(xy 106.458907 -280.443804) (xy 106.506849 -280.429997) (xy 106.556249 -280.423025) (xy 106.581194 -280.422604)
			(xy 106.607808 -280.423068) (xy 106.660441 -280.431001) (xy 106.711304 -280.446689) (xy 106.75926 -280.469783)
			(xy 106.803239 -280.499767) (xy 106.842258 -280.53597) (xy 106.875445 -280.577585) (xy 106.902059 -280.623681)
			(xy 106.921505 -280.673229) (xy 106.933349 -280.725121) (xy 106.937327 -280.7782) (xy 334.429405 -280.7782)
			(xy 334.433382 -280.72513) (xy 334.445224 -280.673246) (xy 334.464665 -280.623706) (xy 334.491273 -280.577617)
			(xy 334.524452 -280.536008) (xy 334.563462 -280.499808) (xy 334.607431 -280.469826) (xy 334.655377 -280.446732)
			(xy 334.70623 -280.431041) (xy 334.758853 -280.423104) (xy 334.785462 -280.422604) (xy 334.810408 -280.422992)
			(xy 334.859812 -280.429962) (xy 334.907756 -280.443771) (xy 334.953298 -280.464147) (xy 334.995544 -280.490691)
			(xy 335.033664 -280.52288) (xy 335.066909 -280.560083) (xy 335.081118 -280.580592) (xy 335.429606 -280.580592)
			(xy 335.443824 -280.560092) (xy 335.477076 -280.522902) (xy 335.515198 -280.490723) (xy 335.557443 -280.464186)
			(xy 335.602982 -280.443813) (xy 335.65092 -280.430003) (xy 335.700318 -280.423027) (xy 335.725262 -280.422604)
			(xy 335.751877 -280.423066) (xy 335.804514 -280.430995) (xy 335.855381 -280.44668) (xy 335.903342 -280.469772)
			(xy 335.947325 -280.499755) (xy 335.986347 -280.535959) (xy 336.019538 -280.577575) (xy 336.046155 -280.623672)
			(xy 336.065603 -280.673223) (xy 336.077449 -280.725118) (xy 336.081427 -280.7782) (xy 336.077449 -280.831282)
			(xy 336.065603 -280.883177) (xy 336.046155 -280.932728) (xy 336.019538 -280.978825) (xy 335.986347 -281.020441)
			(xy 335.947325 -281.056645) (xy 335.903342 -281.086628) (xy 335.855381 -281.10972) (xy 335.804514 -281.125405)
			(xy 335.751877 -281.133334) (xy 335.725262 -281.133804) (xy 335.700316 -281.133395) (xy 335.650914 -281.126428)
			(xy 335.602971 -281.112622) (xy 335.557429 -281.092249) (xy 335.515182 -281.065709) (xy 335.477062 -281.033523)
			(xy 335.443816 -280.996323) (xy 335.429606 -280.975816) (xy 335.081118 -280.975816) (xy 335.066887 -280.996306)
			(xy 335.033637 -281.033496) (xy 334.995517 -281.065676) (xy 334.953274 -281.092213) (xy 334.907738 -281.112588)
			(xy 334.859801 -281.126401) (xy 334.810405 -281.13338) (xy 334.785462 -281.133804) (xy 334.758853 -281.133296)
			(xy 334.70623 -281.125359) (xy 334.655377 -281.109668) (xy 334.607431 -281.086574) (xy 334.563462 -281.056592)
			(xy 334.524452 -281.020392) (xy 334.491273 -280.978783) (xy 334.464665 -280.932694) (xy 334.445224 -280.883154)
			(xy 334.433382 -280.83127) (xy 334.429405 -280.7782) (xy 106.937327 -280.7782) (xy 106.933349 -280.831279)
			(xy 106.921505 -280.883171) (xy 106.902059 -280.932719) (xy 106.875445 -280.978815) (xy 106.842258 -281.02043)
			(xy 106.803239 -281.056633) (xy 106.75926 -281.086617) (xy 106.711304 -281.109711) (xy 106.660441 -281.125399)
			(xy 106.607808 -281.133332) (xy 106.581194 -281.133804) (xy 106.556249 -281.13337) (xy 106.506848 -281.126408)
			(xy 106.458905 -281.112607) (xy 106.413363 -281.092238) (xy 106.371117 -281.065701) (xy 106.332995 -281.033519)
			(xy 106.299748 -280.996322) (xy 106.285538 -280.975816) (xy 105.93705 -280.975816) (xy 105.922863 -280.996338)
			(xy 105.889605 -281.033527) (xy 105.851477 -281.065705) (xy 105.809227 -281.092238) (xy 105.763684 -281.112608)
			(xy 105.715741 -281.126413) (xy 105.66634 -281.133384) (xy 105.641394 -281.133804) (xy 105.614783 -281.133298)
			(xy 105.562156 -281.125365) (xy 105.5113 -281.109677) (xy 105.463349 -281.086585) (xy 105.419376 -281.056604)
			(xy 105.380362 -281.020404) (xy 105.34718 -280.978793) (xy 105.320569 -280.932702) (xy 105.301125 -280.88316)
			(xy 105.289283 -280.831273) (xy 105.285305 -280.7782) (xy 105.05821 -280.7782) (xy 105.05821 -280.778204)
			(xy 105.057711 -280.804891) (xy 105.049756 -280.85767) (xy 105.034024 -280.908673) (xy 105.010866 -280.956762)
			(xy 104.980799 -281.000862) (xy 104.944495 -281.039989) (xy 104.902765 -281.073267) (xy 104.856541 -281.099954)
			(xy 104.806856 -281.119454) (xy 104.754819 -281.131331) (xy 104.701594 -281.13532) (xy 104.648369 -281.131331)
			(xy 104.596332 -281.119454) (xy 104.546647 -281.099954) (xy 104.500423 -281.073267) (xy 104.458693 -281.039989)
			(xy 104.422389 -281.000862) (xy 104.392322 -280.956762) (xy 104.369164 -280.908673) (xy 104.353432 -280.85767)
			(xy 104.345477 -280.804891) (xy 104.344978 -280.778204) (xy 104.11841 -280.778204) (xy 104.11841 -280.778712)
			(xy 104.118026 -280.801914) (xy 104.11196 -280.847921) (xy 104.099985 -280.892755) (xy 104.091486 -280.914348)
			(xy 104.081834 -280.937462) (xy 104.254046 -281.23515) (xy 104.278938 -281.238452) (xy 104.304317 -281.242297)
			(xy 104.353699 -281.2563) (xy 104.400565 -281.277236) (xy 104.443946 -281.304672) (xy 104.482948 -281.338042)
			(xy 104.516765 -281.376656) (xy 104.544699 -281.419719) (xy 104.566173 -281.46634) (xy 104.580745 -281.515558)
			(xy 104.588112 -281.566355) (xy 104.588564 -281.59202) (xy 105.754932 -281.59202) (xy 105.755431 -281.565333)
			(xy 105.763386 -281.512554) (xy 105.779118 -281.461551) (xy 105.802276 -281.413462) (xy 105.832343 -281.369362)
			(xy 105.868647 -281.330235) (xy 105.910377 -281.296957) (xy 105.956601 -281.27027) (xy 106.006286 -281.25077)
			(xy 106.058323 -281.238893) (xy 106.111548 -281.234904) (xy 106.164773 -281.238893) (xy 106.21681 -281.25077)
			(xy 106.266495 -281.27027) (xy 106.312719 -281.296957) (xy 106.354449 -281.330235) (xy 106.390753 -281.369362)
			(xy 106.42082 -281.413462) (xy 106.443978 -281.461551) (xy 106.45971 -281.512554) (xy 106.467665 -281.565333)
			(xy 106.468164 -281.59202) (xy 106.467786 -281.615359) (xy 106.46169 -281.661637) (xy 106.449592 -281.706721)
			(xy 106.440986 -281.728418) (xy 106.431334 -281.751786) (xy 106.603292 -282.048966) (xy 106.628184 -282.052268)
			(xy 106.653559 -282.05614) (xy 106.702942 -282.070137) (xy 106.749809 -282.091067) (xy 106.793192 -282.118499)
			(xy 106.832195 -282.151865) (xy 106.866013 -282.190477) (xy 106.893948 -282.233538) (xy 106.915423 -282.280158)
			(xy 106.929993 -282.329375) (xy 106.937359 -282.380172) (xy 106.93781 -282.405836) (xy 334.4291 -282.405836)
			(xy 334.429597 -282.38017) (xy 334.436939 -282.329366) (xy 334.451491 -282.280139) (xy 334.472952 -282.233509)
			(xy 334.500878 -282.190438) (xy 334.534693 -282.151817) (xy 334.573696 -282.118445) (xy 334.617082 -282.091011)
			(xy 334.663954 -282.070083) (xy 334.713343 -282.056092) (xy 334.738726 -282.052268) (xy 334.763618 -282.048966)
			(xy 334.935576 -281.751278) (xy 334.925924 -281.728164) (xy 334.917424 -281.706571) (xy 334.905444 -281.661739)
			(xy 334.899389 -281.61573) (xy 334.899 -281.592528) (xy 334.899 -281.59202) (xy 334.899499 -281.565333)
			(xy 334.907454 -281.512554) (xy 334.923186 -281.461551) (xy 334.946344 -281.413462) (xy 334.976411 -281.369362)
			(xy 335.012715 -281.330235) (xy 335.054445 -281.296957) (xy 335.100669 -281.27027) (xy 335.150354 -281.25077)
			(xy 335.202391 -281.238893) (xy 335.255616 -281.234904) (xy 335.308841 -281.238893) (xy 335.360878 -281.25077)
			(xy 335.410563 -281.27027) (xy 335.456787 -281.296957) (xy 335.498517 -281.330235) (xy 335.534821 -281.369362)
			(xy 335.564888 -281.413462) (xy 335.588046 -281.461551) (xy 335.603778 -281.512554) (xy 335.611733 -281.565333)
			(xy 335.612232 -281.59202) (xy 336.7786 -281.59202) (xy 336.779082 -281.566353) (xy 336.786427 -281.515549)
			(xy 336.800981 -281.466322) (xy 336.822443 -281.419692) (xy 336.850371 -281.376621) (xy 336.884187 -281.338)
			(xy 336.923192 -281.304628) (xy 336.966579 -281.277195) (xy 337.013452 -281.256266) (xy 337.062842 -281.242276)
			(xy 337.088226 -281.238452) (xy 337.113118 -281.23515) (xy 337.285584 -280.936954) (xy 337.273807 -280.912165)
			(xy 337.257162 -280.859872) (xy 337.248747 -280.805643) (xy 337.248246 -280.778204) (xy 337.248745 -280.751517)
			(xy 337.2567 -280.698738) (xy 337.272432 -280.647735) (xy 337.29559 -280.599646) (xy 337.325657 -280.555546)
			(xy 337.361961 -280.516419) (xy 337.403691 -280.483141) (xy 337.449915 -280.456454) (xy 337.4996 -280.436954)
			(xy 337.551637 -280.425077) (xy 337.604862 -280.421088) (xy 337.658087 -280.425077) (xy 337.710124 -280.436954)
			(xy 337.759809 -280.456454) (xy 337.806033 -280.483141) (xy 337.847763 -280.516419) (xy 337.884067 -280.555546)
			(xy 337.914134 -280.599646) (xy 337.937292 -280.647735) (xy 337.953024 -280.698738) (xy 337.960979 -280.751517)
			(xy 337.961478 -280.778204) (xy 340.0679 -280.778204) (xy 340.068399 -280.751517) (xy 340.076354 -280.698738)
			(xy 340.092086 -280.647735) (xy 340.115244 -280.599646) (xy 340.145311 -280.555546) (xy 340.181615 -280.516419)
			(xy 340.223345 -280.483141) (xy 340.269569 -280.456454) (xy 340.319254 -280.436954) (xy 340.371291 -280.425077)
			(xy 340.424516 -280.421088) (xy 340.477741 -280.425077) (xy 340.529778 -280.436954) (xy 340.579463 -280.456454)
			(xy 340.625687 -280.483141) (xy 340.667417 -280.516419) (xy 340.703721 -280.555546) (xy 340.733788 -280.599646)
			(xy 340.756946 -280.647735) (xy 340.772678 -280.698738) (xy 340.780633 -280.751517) (xy 340.781132 -280.7782)
			(xy 342.887605 -280.7782) (xy 342.891582 -280.72513) (xy 342.903424 -280.673246) (xy 342.922865 -280.623706)
			(xy 342.949473 -280.577617) (xy 342.982652 -280.536008) (xy 343.021662 -280.499808) (xy 343.065631 -280.469826)
			(xy 343.113577 -280.446732) (xy 343.16443 -280.431041) (xy 343.217053 -280.423104) (xy 343.243662 -280.422604)
			(xy 343.268608 -280.422992) (xy 343.318012 -280.429962) (xy 343.365956 -280.443771) (xy 343.411498 -280.464147)
			(xy 343.453744 -280.490691) (xy 343.491864 -280.52288) (xy 343.525109 -280.560083) (xy 343.539318 -280.580592)
			(xy 343.88806 -280.580592) (xy 343.902244 -280.560067) (xy 343.935501 -280.522878) (xy 343.97363 -280.4907)
			(xy 344.01588 -280.464167) (xy 344.061424 -280.443798) (xy 344.109368 -280.429993) (xy 344.15877 -280.423023)
			(xy 344.183716 -280.422604) (xy 344.210327 -280.423094) (xy 344.262954 -280.431029) (xy 344.31381 -280.446718)
			(xy 344.361761 -280.469812) (xy 344.405733 -280.499794) (xy 344.444747 -280.535994) (xy 344.477929 -280.577605)
			(xy 344.504539 -280.623697) (xy 344.523983 -280.67324) (xy 344.535825 -280.725127) (xy 344.539803 -280.7782)
			(xy 344.535825 -280.831273) (xy 344.523983 -280.88316) (xy 344.504539 -280.932703) (xy 344.477929 -280.978795)
			(xy 344.444747 -281.020406) (xy 344.405733 -281.056606) (xy 344.361761 -281.086588) (xy 344.31381 -281.109682)
			(xy 344.262954 -281.125371) (xy 344.210327 -281.133306) (xy 344.183716 -281.133804) (xy 344.158769 -281.13343)
			(xy 344.109365 -281.126457) (xy 344.061421 -281.112645) (xy 344.015879 -281.092266) (xy 343.973633 -281.065721)
			(xy 343.935514 -281.03353) (xy 343.902269 -280.996325) (xy 343.88806 -280.975816) (xy 343.539318 -280.975816)
			(xy 343.525087 -280.996306) (xy 343.491837 -281.033496) (xy 343.453717 -281.065676) (xy 343.411474 -281.092213)
			(xy 343.365938 -281.112588) (xy 343.318001 -281.126401) (xy 343.268605 -281.13338) (xy 343.243662 -281.133804)
			(xy 343.217053 -281.133296) (xy 343.16443 -281.125359) (xy 343.113577 -281.109668) (xy 343.065631 -281.086574)
			(xy 343.021662 -281.056592) (xy 342.982652 -281.020392) (xy 342.949473 -280.978783) (xy 342.922865 -280.932694)
			(xy 342.903424 -280.883154) (xy 342.891582 -280.83127) (xy 342.887605 -280.7782) (xy 340.781132 -280.7782)
			(xy 340.781132 -280.778204) (xy 340.780609 -280.805641) (xy 340.772176 -280.859863) (xy 340.755555 -280.91216)
			(xy 340.743794 -280.936954) (xy 340.91626 -281.23515) (xy 340.941152 -281.238452) (xy 340.966533 -281.242286)
			(xy 341.015915 -281.256291) (xy 341.062781 -281.277228) (xy 341.106162 -281.304666) (xy 341.145164 -281.338037)
			(xy 341.17898 -281.376653) (xy 341.206914 -281.419716) (xy 341.228388 -281.466339) (xy 341.242959 -281.515557)
			(xy 341.250326 -281.566355) (xy 341.250778 -281.59202) (xy 341.250279 -281.618707) (xy 341.242324 -281.671486)
			(xy 341.226592 -281.722489) (xy 341.203434 -281.770578) (xy 341.173367 -281.814678) (xy 341.137063 -281.853805)
			(xy 341.095333 -281.887083) (xy 341.049109 -281.91377) (xy 340.999424 -281.93327) (xy 340.947387 -281.945147)
			(xy 340.894162 -281.949136) (xy 340.840937 -281.945147) (xy 340.7889 -281.93327) (xy 340.739215 -281.91377)
			(xy 340.692991 -281.887083) (xy 340.651261 -281.853805) (xy 340.614957 -281.814678) (xy 340.58489 -281.770578)
			(xy 340.561732 -281.722489) (xy 340.546 -281.671486) (xy 340.538045 -281.618707) (xy 340.537546 -281.59202)
			(xy 340.537546 -281.591512) (xy 340.537941 -281.56831) (xy 340.544003 -281.522304) (xy 340.555974 -281.47747)
			(xy 340.56447 -281.455876) (xy 340.574122 -281.432762) (xy 340.401656 -281.134058) (xy 340.374864 -281.131858)
			(xy 340.322342 -281.120401) (xy 340.272136 -281.101191) (xy 340.225382 -281.074662) (xy 340.183139 -281.041416)
			(xy 340.146365 -281.002206) (xy 340.115893 -280.957921) (xy 340.092413 -280.909563) (xy 340.076458 -280.858229)
			(xy 340.068389 -280.805082) (xy 340.0679 -280.778204) (xy 337.961478 -280.778204) (xy 337.960907 -280.805078)
			(xy 337.95284 -280.858217) (xy 337.93689 -280.909544) (xy 337.913417 -280.957895) (xy 337.882954 -281.002176)
			(xy 337.84619 -281.041384) (xy 337.803958 -281.07463) (xy 337.757215 -281.101162) (xy 337.70702 -281.120378)
			(xy 337.654509 -281.131843) (xy 337.627722 -281.134058) (xy 337.455256 -281.432508) (xy 337.464908 -281.455622)
			(xy 337.473428 -281.477298) (xy 337.485433 -281.522298) (xy 337.49147 -281.568479) (xy 337.491832 -281.591766)
			(xy 337.491832 -281.592) (xy 338.658521 -281.592) (xy 338.662498 -281.538933) (xy 338.674339 -281.487051)
			(xy 338.69378 -281.437513) (xy 338.720386 -281.391426) (xy 338.753564 -281.349818) (xy 338.792572 -281.31362)
			(xy 338.836539 -281.28364) (xy 338.884483 -281.260546) (xy 338.935333 -281.244856) (xy 338.987954 -281.23692)
			(xy 339.014562 -281.23642) (xy 339.039507 -281.236845) (xy 339.088907 -281.243813) (xy 339.136848 -281.257618)
			(xy 339.182389 -281.27799) (xy 339.224635 -281.304527) (xy 339.262757 -281.336709) (xy 339.296006 -281.373903)
			(xy 339.310218 -281.394408) (xy 339.658706 -281.394408) (xy 339.672929 -281.373912) (xy 339.70618 -281.336721)
			(xy 339.744301 -281.304541) (xy 339.786545 -281.278004) (xy 339.832083 -281.25763) (xy 339.880021 -281.243819)
			(xy 339.929418 -281.236843) (xy 339.954362 -281.23642) (xy 339.980978 -281.23685) (xy 340.033618 -281.244779)
			(xy 340.084487 -281.260465) (xy 340.13245 -281.283558) (xy 340.176435 -281.313542) (xy 340.215459 -281.349748)
			(xy 340.248651 -281.391365) (xy 340.275269 -281.437465) (xy 340.294719 -281.487018) (xy 340.306565 -281.538916)
			(xy 340.310544 -281.592) (xy 340.306565 -281.645084) (xy 340.294719 -281.696982) (xy 340.275269 -281.746535)
			(xy 340.248651 -281.792635) (xy 340.215459 -281.834252) (xy 340.176435 -281.870458) (xy 340.13245 -281.900442)
			(xy 340.084487 -281.923535) (xy 340.033618 -281.939221) (xy 339.980978 -281.94715) (xy 339.954362 -281.94762)
			(xy 339.929417 -281.947204) (xy 339.880015 -281.940237) (xy 339.832072 -281.926432) (xy 339.78653 -281.90606)
			(xy 339.744284 -281.879521) (xy 339.706163 -281.847337) (xy 339.672916 -281.810139) (xy 339.658706 -281.789632)
			(xy 339.310218 -281.789632) (xy 339.295992 -281.810126) (xy 339.262741 -281.847315) (xy 339.224619 -281.879494)
			(xy 339.182376 -281.906031) (xy 339.136839 -281.926405) (xy 339.088902 -281.940217) (xy 339.039505 -281.947196)
			(xy 339.014562 -281.94762) (xy 338.987954 -281.94708) (xy 338.935333 -281.939144) (xy 338.884483 -281.923454)
			(xy 338.836539 -281.90036) (xy 338.792572 -281.87038) (xy 338.753564 -281.834182) (xy 338.720386 -281.792574)
			(xy 338.69378 -281.746487) (xy 338.674339 -281.696949) (xy 338.662498 -281.645067) (xy 338.658521 -281.592)
			(xy 337.491832 -281.592) (xy 337.491832 -281.59202) (xy 337.491333 -281.618707) (xy 337.483378 -281.671486)
			(xy 337.467646 -281.722489) (xy 337.444488 -281.770578) (xy 337.414421 -281.814678) (xy 337.378117 -281.853805)
			(xy 337.336387 -281.887083) (xy 337.290163 -281.91377) (xy 337.240478 -281.93327) (xy 337.188441 -281.945147)
			(xy 337.135216 -281.949136) (xy 337.081991 -281.945147) (xy 337.029954 -281.93327) (xy 336.980269 -281.91377)
			(xy 336.934045 -281.887083) (xy 336.892315 -281.853805) (xy 336.856011 -281.814678) (xy 336.825944 -281.770578)
			(xy 336.802786 -281.722489) (xy 336.787054 -281.671486) (xy 336.779099 -281.618707) (xy 336.7786 -281.59202)
			(xy 335.612232 -281.59202) (xy 335.611845 -281.61769) (xy 335.604494 -281.668502) (xy 335.589931 -281.717734)
			(xy 335.568459 -281.764368) (xy 335.54052 -281.807441) (xy 335.506693 -281.846062) (xy 335.467677 -281.879433)
			(xy 335.424278 -281.906863) (xy 335.377394 -281.927786) (xy 335.327994 -281.941768) (xy 335.302606 -281.945588)
			(xy 335.277714 -281.94889) (xy 335.105756 -282.246578) (xy 335.115408 -282.269692) (xy 335.123922 -282.29128)
			(xy 335.135897 -282.336115) (xy 335.141947 -282.382125) (xy 335.142332 -282.405328) (xy 335.142332 -282.405836)
			(xy 335.368646 -282.405836) (xy 335.369145 -282.379149) (xy 335.3771 -282.32637) (xy 335.392832 -282.275367)
			(xy 335.41599 -282.227278) (xy 335.446057 -282.183178) (xy 335.482361 -282.144051) (xy 335.524091 -282.110773)
			(xy 335.570315 -282.084086) (xy 335.62 -282.064586) (xy 335.672037 -282.052709) (xy 335.725262 -282.04872)
			(xy 335.778487 -282.052709) (xy 335.830524 -282.064586) (xy 335.880209 -282.084086) (xy 335.926433 -282.110773)
			(xy 335.968163 -282.144051) (xy 336.004467 -282.183178) (xy 336.034534 -282.227278) (xy 336.057692 -282.275367)
			(xy 336.073424 -282.32637) (xy 336.081379 -282.379149) (xy 336.081877 -282.4058) (xy 336.309213 -282.4058)
			(xy 336.31319 -282.352726) (xy 336.325034 -282.300839) (xy 336.344479 -282.251296) (xy 336.371091 -282.205204)
			(xy 336.404275 -282.163594) (xy 336.443291 -282.127394) (xy 336.487266 -282.097414) (xy 336.535218 -282.074323)
			(xy 336.586077 -282.058638) (xy 336.638705 -282.050708) (xy 336.665316 -282.050236) (xy 336.69026 -282.050689)
			(xy 336.739659 -282.057651) (xy 336.7876 -282.071451) (xy 336.833141 -282.091818) (xy 336.875388 -282.11835)
			(xy 336.91351 -282.150529) (xy 336.94676 -282.187721) (xy 336.960972 -282.208224) (xy 337.30946 -282.208224)
			(xy 337.323654 -282.187707) (xy 337.356909 -282.150515) (xy 337.395035 -282.118336) (xy 337.437284 -282.091801)
			(xy 337.482827 -282.071431) (xy 337.530769 -282.057625) (xy 337.580171 -282.050655) (xy 337.605116 -282.050236)
			(xy 337.631729 -282.050662) (xy 337.684361 -282.058598) (xy 337.735222 -282.074288) (xy 337.783177 -282.097384)
			(xy 337.827153 -282.127369) (xy 337.86617 -282.163573) (xy 337.899356 -282.205187) (xy 337.925968 -282.251283)
			(xy 337.945413 -282.30083) (xy 337.957257 -282.352722) (xy 337.961235 -282.4058) (xy 337.957257 -282.458878)
			(xy 337.945413 -282.51077) (xy 337.925968 -282.560317) (xy 337.899356 -282.606413) (xy 337.86617 -282.648027)
			(xy 337.827153 -282.684231) (xy 337.783177 -282.714216) (xy 337.735222 -282.737312) (xy 337.684361 -282.753002)
			(xy 337.631729 -282.760938) (xy 337.605116 -282.761436) (xy 337.58017 -282.761048) (xy 337.530767 -282.754075)
			(xy 337.482824 -282.740265) (xy 337.437283 -282.719888) (xy 337.395037 -282.693345) (xy 337.356916 -282.661157)
			(xy 337.32367 -282.623956) (xy 337.30946 -282.603448) (xy 336.960972 -282.603448) (xy 336.946749 -282.623944)
			(xy 336.9135 -282.661137) (xy 336.875379 -282.693319) (xy 336.833135 -282.719856) (xy 336.787597 -282.74023)
			(xy 336.739658 -282.75404) (xy 336.69026 -282.761014) (xy 336.665316 -282.761436) (xy 336.638705 -282.760892)
			(xy 336.586077 -282.752962) (xy 336.535218 -282.737276) (xy 336.487266 -282.714186) (xy 336.443291 -282.684206)
			(xy 336.404275 -282.648006) (xy 336.371091 -282.606396) (xy 336.344479 -282.560304) (xy 336.325034 -282.510761)
			(xy 336.31319 -282.458874) (xy 336.309213 -282.4058) (xy 336.081877 -282.4058) (xy 336.081878 -282.405836)
			(xy 336.081504 -282.429175) (xy 336.075406 -282.475454) (xy 336.063307 -282.520537) (xy 336.0547 -282.542234)
			(xy 336.045048 -282.565602) (xy 336.21726 -282.863036) (xy 336.241898 -282.866338) (xy 336.267301 -282.870119)
			(xy 336.316721 -282.884091) (xy 336.363628 -282.905006) (xy 336.407049 -282.932433) (xy 336.446088 -282.965804)
			(xy 336.479937 -283.004429) (xy 336.507896 -283.047509) (xy 336.529387 -283.094155) (xy 336.543966 -283.1434)
			(xy 336.551331 -283.194227) (xy 336.551778 -283.219906) (xy 338.657946 -283.219906) (xy 338.658376 -283.194237)
			(xy 338.665723 -283.143428) (xy 338.680281 -283.094198) (xy 338.701749 -283.047565) (xy 338.729683 -283.004493)
			(xy 338.763505 -282.965872) (xy 338.802516 -282.932501) (xy 338.84591 -282.905069) (xy 338.89279 -282.884144)
			(xy 338.942185 -282.870159) (xy 338.967572 -282.866338) (xy 338.992464 -282.863036) (xy 339.164676 -282.565094)
			(xy 339.155024 -282.54198) (xy 339.146528 -282.520385) (xy 339.134547 -282.475554) (xy 339.12849 -282.429546)
			(xy 339.1281 -282.406344) (xy 339.1281 -282.405836) (xy 339.128599 -282.379149) (xy 339.136554 -282.32637)
			(xy 339.152286 -282.275367) (xy 339.175444 -282.227278) (xy 339.205511 -282.183178) (xy 339.241815 -282.144051)
			(xy 339.283545 -282.110773) (xy 339.329769 -282.084086) (xy 339.379454 -282.064586) (xy 339.431491 -282.052709)
			(xy 339.484716 -282.04872) (xy 339.537941 -282.052709) (xy 339.589978 -282.064586) (xy 339.639663 -282.084086)
			(xy 339.685887 -282.110773) (xy 339.727617 -282.144051) (xy 339.763921 -282.183178) (xy 339.793988 -282.227278)
			(xy 339.817146 -282.275367) (xy 339.832878 -282.32637) (xy 339.840833 -282.379149) (xy 339.841332 -282.405836)
			(xy 341.0077 -282.405836) (xy 341.008197 -282.38017) (xy 341.015539 -282.329366) (xy 341.030091 -282.280139)
			(xy 341.051552 -282.233509) (xy 341.079478 -282.190438) (xy 341.113293 -282.151817) (xy 341.152296 -282.118445)
			(xy 341.195682 -282.091011) (xy 341.242554 -282.070083) (xy 341.291943 -282.056092) (xy 341.317326 -282.052268)
			(xy 341.342218 -282.048966) (xy 341.514176 -281.751786) (xy 341.504524 -281.728418) (xy 341.495939 -281.706714)
			(xy 341.483858 -281.66163) (xy 341.477745 -281.615357) (xy 341.477346 -281.59202) (xy 341.477845 -281.565333)
			(xy 341.4858 -281.512554) (xy 341.501532 -281.461551) (xy 341.52469 -281.413462) (xy 341.554757 -281.369362)
			(xy 341.591061 -281.330235) (xy 341.632791 -281.296957) (xy 341.679015 -281.27027) (xy 341.7287 -281.25077)
			(xy 341.780737 -281.238893) (xy 341.833962 -281.234904) (xy 341.887187 -281.238893) (xy 341.939224 -281.25077)
			(xy 341.988909 -281.27027) (xy 342.035133 -281.296957) (xy 342.076863 -281.330235) (xy 342.113167 -281.369362)
			(xy 342.143234 -281.413462) (xy 342.166392 -281.461551) (xy 342.182124 -281.512554) (xy 342.190079 -281.565333)
			(xy 342.190578 -281.59202) (xy 342.190152 -281.617689) (xy 342.182801 -281.668496) (xy 342.168241 -281.717725)
			(xy 342.146772 -281.764357) (xy 342.118837 -281.807429) (xy 342.085015 -281.846049) (xy 342.046004 -281.87942)
			(xy 342.002611 -281.906852) (xy 341.955733 -281.927778) (xy 341.906338 -281.941765) (xy 341.880952 -281.945588)
			(xy 341.85606 -281.94889) (xy 341.684102 -282.24607) (xy 341.693754 -282.269438) (xy 341.702325 -282.291147)
			(xy 341.714411 -282.336229) (xy 341.72053 -282.3825) (xy 341.720932 -282.405836) (xy 342.887046 -282.405836)
			(xy 342.887503 -282.380168) (xy 342.894846 -282.32936) (xy 342.909401 -282.280131) (xy 342.930865 -282.233498)
			(xy 342.958795 -282.190425) (xy 342.992615 -282.151804) (xy 343.031623 -282.118432) (xy 343.075015 -282.091)
			(xy 343.121892 -282.070075) (xy 343.171286 -282.056089) (xy 343.196672 -282.052268) (xy 343.221564 -282.048966)
			(xy 343.393776 -281.751278) (xy 343.384124 -281.728164) (xy 343.375624 -281.706571) (xy 343.363644 -281.661739)
			(xy 343.357589 -281.61573) (xy 343.3572 -281.592528) (xy 343.3572 -281.59202) (xy 343.357699 -281.565333)
			(xy 343.365654 -281.512554) (xy 343.381386 -281.461551) (xy 343.404544 -281.413462) (xy 343.434611 -281.369362)
			(xy 343.470915 -281.330235) (xy 343.512645 -281.296957) (xy 343.558869 -281.27027) (xy 343.608554 -281.25077)
			(xy 343.660591 -281.238893) (xy 343.713816 -281.234904) (xy 343.767041 -281.238893) (xy 343.819078 -281.25077)
			(xy 343.868763 -281.27027) (xy 343.914987 -281.296957) (xy 343.956717 -281.330235) (xy 343.993021 -281.369362)
			(xy 344.023088 -281.413462) (xy 344.046246 -281.461551) (xy 344.061978 -281.512554) (xy 344.069933 -281.565333)
			(xy 344.070432 -281.59202) (xy 345.2368 -281.59202) (xy 345.237282 -281.566353) (xy 345.244627 -281.515549)
			(xy 345.259181 -281.466322) (xy 345.280643 -281.419692) (xy 345.308571 -281.376621) (xy 345.342387 -281.338)
			(xy 345.381392 -281.304628) (xy 345.424779 -281.277195) (xy 345.471652 -281.256266) (xy 345.521042 -281.242276)
			(xy 345.546426 -281.238452) (xy 345.571318 -281.23515) (xy 345.743276 -280.93797) (xy 345.733624 -280.914602)
			(xy 345.725064 -280.892889) (xy 345.712974 -280.847809) (xy 345.70685 -280.80154) (xy 345.706446 -280.778204)
			(xy 345.706945 -280.751517) (xy 345.7149 -280.698738) (xy 345.730632 -280.647735) (xy 345.75379 -280.599646)
			(xy 345.783857 -280.555546) (xy 345.820161 -280.516419) (xy 345.861891 -280.483141) (xy 345.908115 -280.456454)
			(xy 345.9578 -280.436954) (xy 346.009837 -280.425077) (xy 346.063062 -280.421088) (xy 346.116287 -280.425077)
			(xy 346.168324 -280.436954) (xy 346.218009 -280.456454) (xy 346.264233 -280.483141) (xy 346.305963 -280.516419)
			(xy 346.342267 -280.555546) (xy 346.372334 -280.599646) (xy 346.395492 -280.647735) (xy 346.411224 -280.698738)
			(xy 346.419179 -280.751517) (xy 346.419678 -280.778204) (xy 348.525846 -280.778204) (xy 348.526345 -280.751517)
			(xy 348.5343 -280.698738) (xy 348.550032 -280.647735) (xy 348.57319 -280.599646) (xy 348.603257 -280.555546)
			(xy 348.639561 -280.516419) (xy 348.681291 -280.483141) (xy 348.727515 -280.456454) (xy 348.7772 -280.436954)
			(xy 348.829237 -280.425077) (xy 348.882462 -280.421088) (xy 348.935687 -280.425077) (xy 348.987724 -280.436954)
			(xy 349.037409 -280.456454) (xy 349.083633 -280.483141) (xy 349.125363 -280.516419) (xy 349.161667 -280.555546)
			(xy 349.191734 -280.599646) (xy 349.214892 -280.647735) (xy 349.230624 -280.698738) (xy 349.238579 -280.751517)
			(xy 349.239078 -280.778204) (xy 351.345246 -280.778204) (xy 351.345745 -280.751517) (xy 351.3537 -280.698738)
			(xy 351.369432 -280.647735) (xy 351.39259 -280.599646) (xy 351.422657 -280.555546) (xy 351.458961 -280.516419)
			(xy 351.500691 -280.483141) (xy 351.546915 -280.456454) (xy 351.5966 -280.436954) (xy 351.648637 -280.425077)
			(xy 351.701862 -280.421088) (xy 351.755087 -280.425077) (xy 351.807124 -280.436954) (xy 351.856809 -280.456454)
			(xy 351.903033 -280.483141) (xy 351.944763 -280.516419) (xy 351.981067 -280.555546) (xy 352.011134 -280.599646)
			(xy 352.034292 -280.647735) (xy 352.050024 -280.698738) (xy 352.057979 -280.751517) (xy 352.058478 -280.778204)
			(xy 352.285046 -280.778204) (xy 352.285474 -280.752535) (xy 352.292821 -280.701726) (xy 352.30738 -280.652496)
			(xy 352.328848 -280.605863) (xy 352.356782 -280.562791) (xy 352.390604 -280.52417) (xy 352.429616 -280.490799)
			(xy 352.47301 -280.463367) (xy 352.51989 -280.442442) (xy 352.569285 -280.428457) (xy 352.594672 -280.424636)
			(xy 352.619564 -280.421334) (xy 352.791776 -280.123392) (xy 352.782124 -280.100278) (xy 352.773628 -280.078684)
			(xy 352.761647 -280.033852) (xy 352.755589 -279.987844) (xy 352.7552 -279.964642) (xy 352.7552 -279.964134)
			(xy 352.755699 -279.937447) (xy 352.763654 -279.884668) (xy 352.779386 -279.833665) (xy 352.802544 -279.785576)
			(xy 352.832611 -279.741476) (xy 352.868915 -279.702349) (xy 352.910645 -279.669071) (xy 352.956869 -279.642384)
			(xy 353.006554 -279.622884) (xy 353.058591 -279.611007) (xy 353.111816 -279.607018) (xy 353.165041 -279.611007)
			(xy 353.217078 -279.622884) (xy 353.266763 -279.642384) (xy 353.312987 -279.669071) (xy 353.354717 -279.702349)
			(xy 353.391021 -279.741476) (xy 353.421088 -279.785576) (xy 353.444246 -279.833665) (xy 353.459978 -279.884668)
			(xy 353.467933 -279.937447) (xy 353.468432 -279.964134) (xy 353.467962 -279.989834) (xy 353.460577 -280.040701)
			(xy 353.445967 -280.089981) (xy 353.424432 -280.136652) (xy 353.396421 -280.179749) (xy 353.362512 -280.218377)
			(xy 353.323409 -280.251737) (xy 353.279921 -280.279138) (xy 353.23295 -280.300011) (xy 353.183469 -280.313924)
			(xy 353.158044 -280.317702) (xy 353.133152 -280.321004) (xy 352.961448 -280.618438) (xy 352.9711 -280.641806)
			(xy 352.979664 -280.663518) (xy 352.991752 -280.708598) (xy 352.997874 -280.754868) (xy 352.998278 -280.7782)
			(xy 353.225405 -280.7782) (xy 353.229382 -280.72513) (xy 353.241224 -280.673246) (xy 353.260665 -280.623706)
			(xy 353.287273 -280.577617) (xy 353.320452 -280.536008) (xy 353.359462 -280.499808) (xy 353.403431 -280.469826)
			(xy 353.451377 -280.446732) (xy 353.50223 -280.431041) (xy 353.554853 -280.423104) (xy 353.581462 -280.422604)
			(xy 353.606408 -280.422992) (xy 353.655812 -280.429962) (xy 353.703756 -280.443771) (xy 353.749298 -280.464147)
			(xy 353.791544 -280.490691) (xy 353.829664 -280.52288) (xy 353.862909 -280.560083) (xy 353.877118 -280.580592)
			(xy 354.225606 -280.580592) (xy 354.239824 -280.560092) (xy 354.273076 -280.522902) (xy 354.311198 -280.490723)
			(xy 354.353443 -280.464186) (xy 354.398982 -280.443813) (xy 354.44692 -280.430003) (xy 354.496318 -280.423027)
			(xy 354.521262 -280.422604) (xy 354.547877 -280.423066) (xy 354.600514 -280.430995) (xy 354.651381 -280.44668)
			(xy 354.699342 -280.469772) (xy 354.743325 -280.499755) (xy 354.782347 -280.535959) (xy 354.815538 -280.577575)
			(xy 354.842155 -280.623672) (xy 354.861603 -280.673223) (xy 354.873449 -280.725118) (xy 354.877427 -280.7782)
			(xy 354.873449 -280.831282) (xy 354.861603 -280.883177) (xy 354.842155 -280.932728) (xy 354.815538 -280.978825)
			(xy 354.782347 -281.020441) (xy 354.743325 -281.056645) (xy 354.699342 -281.086628) (xy 354.651381 -281.10972)
			(xy 354.600514 -281.125405) (xy 354.547877 -281.133334) (xy 354.521262 -281.133804) (xy 354.496316 -281.133395)
			(xy 354.446914 -281.126428) (xy 354.398971 -281.112622) (xy 354.353429 -281.092249) (xy 354.311182 -281.065709)
			(xy 354.273062 -281.033523) (xy 354.239816 -280.996323) (xy 354.225606 -280.975816) (xy 353.877118 -280.975816)
			(xy 353.862887 -280.996306) (xy 353.829637 -281.033496) (xy 353.791517 -281.065676) (xy 353.749274 -281.092213)
			(xy 353.703738 -281.112588) (xy 353.655801 -281.126401) (xy 353.606405 -281.13338) (xy 353.581462 -281.133804)
			(xy 353.554853 -281.133296) (xy 353.50223 -281.125359) (xy 353.451377 -281.109668) (xy 353.403431 -281.086574)
			(xy 353.359462 -281.056592) (xy 353.320452 -281.020392) (xy 353.287273 -280.978783) (xy 353.260665 -280.932694)
			(xy 353.241224 -280.883154) (xy 353.229382 -280.83127) (xy 353.225405 -280.7782) (xy 352.998278 -280.7782)
			(xy 352.998278 -280.778204) (xy 352.997779 -280.804891) (xy 352.989824 -280.85767) (xy 352.974092 -280.908673)
			(xy 352.950934 -280.956762) (xy 352.920867 -281.000862) (xy 352.884563 -281.039989) (xy 352.842833 -281.073267)
			(xy 352.796609 -281.099954) (xy 352.746924 -281.119454) (xy 352.694887 -281.131331) (xy 352.641662 -281.13532)
			(xy 352.588437 -281.131331) (xy 352.5364 -281.119454) (xy 352.486715 -281.099954) (xy 352.440491 -281.073267)
			(xy 352.398761 -281.039989) (xy 352.362457 -281.000862) (xy 352.33239 -280.956762) (xy 352.309232 -280.908673)
			(xy 352.2935 -280.85767) (xy 352.285545 -280.804891) (xy 352.285046 -280.778204) (xy 352.058478 -280.778204)
			(xy 352.058478 -280.778712) (xy 352.058089 -280.801914) (xy 352.052024 -280.847921) (xy 352.040051 -280.892754)
			(xy 352.031554 -280.914348) (xy 352.021902 -280.937462) (xy 352.194114 -281.23515) (xy 352.219006 -281.238452)
			(xy 352.244381 -281.242322) (xy 352.293763 -281.256321) (xy 352.340629 -281.277253) (xy 352.384011 -281.304685)
			(xy 352.423013 -281.338052) (xy 352.456831 -281.376664) (xy 352.484766 -281.419725) (xy 352.506241 -281.466344)
			(xy 352.520812 -281.51556) (xy 352.52818 -281.566356) (xy 352.528632 -281.59202) (xy 353.695 -281.59202)
			(xy 353.695499 -281.565333) (xy 353.703454 -281.512554) (xy 353.719186 -281.461551) (xy 353.742344 -281.413462)
			(xy 353.772411 -281.369362) (xy 353.808715 -281.330235) (xy 353.850445 -281.296957) (xy 353.896669 -281.27027)
			(xy 353.946354 -281.25077) (xy 353.998391 -281.238893) (xy 354.051616 -281.234904) (xy 354.104841 -281.238893)
			(xy 354.156878 -281.25077) (xy 354.206563 -281.27027) (xy 354.252787 -281.296957) (xy 354.294517 -281.330235)
			(xy 354.330821 -281.369362) (xy 354.360888 -281.413462) (xy 354.384046 -281.461551) (xy 354.399778 -281.512554)
			(xy 354.407733 -281.565333) (xy 354.408232 -281.59202) (xy 354.407856 -281.615359) (xy 354.40176 -281.661638)
			(xy 354.389661 -281.706721) (xy 354.381054 -281.728418) (xy 354.371402 -281.751786) (xy 354.54336 -282.048966)
			(xy 354.568252 -282.052268) (xy 354.593636 -282.056086) (xy 354.643019 -282.070092) (xy 354.689886 -282.091031)
			(xy 354.733268 -282.11847) (xy 354.772269 -282.151843) (xy 354.806086 -282.190461) (xy 354.834019 -282.233526)
			(xy 354.855492 -282.28015) (xy 354.870062 -282.32937) (xy 354.877427 -282.38017) (xy 354.877878 -282.405836)
			(xy 354.877379 -282.432523) (xy 354.869424 -282.485302) (xy 354.853692 -282.536305) (xy 354.830534 -282.584394)
			(xy 354.800467 -282.628494) (xy 354.764163 -282.667621) (xy 354.722433 -282.700899) (xy 354.676209 -282.727586)
			(xy 354.626524 -282.747086) (xy 354.574487 -282.758963) (xy 354.521262 -282.762952) (xy 354.468037 -282.758963)
			(xy 354.416 -282.747086) (xy 354.366315 -282.727586) (xy 354.320091 -282.700899) (xy 354.278361 -282.667621)
			(xy 354.242057 -282.628494) (xy 354.21199 -282.584394) (xy 354.188832 -282.536305) (xy 354.1731 -282.485302)
			(xy 354.165145 -282.432523) (xy 354.164646 -282.405836) (xy 354.16501 -282.382496) (xy 354.171111 -282.336218)
			(xy 354.183215 -282.291135) (xy 354.191824 -282.269438) (xy 354.201476 -282.24607) (xy 354.029518 -281.94889)
			(xy 354.004626 -281.945588) (xy 353.979245 -281.941751) (xy 353.929858 -281.927753) (xy 353.882989 -281.906821)
			(xy 353.839604 -281.879386) (xy 353.800599 -281.846015) (xy 353.766781 -281.807399) (xy 353.738847 -281.764333)
			(xy 353.717375 -281.717708) (xy 353.702809 -281.668487) (xy 353.695448 -281.617686) (xy 353.695 -281.59202)
			(xy 352.528632 -281.59202) (xy 352.528133 -281.618707) (xy 352.520178 -281.671486) (xy 352.504446 -281.722489)
			(xy 352.481288 -281.770578) (xy 352.451221 -281.814678) (xy 352.414917 -281.853805) (xy 352.373187 -281.887083)
			(xy 352.326963 -281.91377) (xy 352.277278 -281.93327) (xy 352.225241 -281.945147) (xy 352.172016 -281.949136)
			(xy 352.118791 -281.945147) (xy 352.066754 -281.93327) (xy 352.017069 -281.91377) (xy 351.970845 -281.887083)
			(xy 351.929115 -281.853805) (xy 351.892811 -281.814678) (xy 351.862744 -281.770578) (xy 351.839586 -281.722489)
			(xy 351.823854 -281.671486) (xy 351.815899 -281.618707) (xy 351.8154 -281.59202) (xy 351.815754 -281.56868)
			(xy 351.821859 -281.522401) (xy 351.833967 -281.477318) (xy 351.842578 -281.455622) (xy 351.85223 -281.432254)
			(xy 351.680526 -281.135074) (xy 351.655634 -281.131772) (xy 351.63021 -281.12798) (xy 351.580725 -281.114075)
			(xy 351.533749 -281.093208) (xy 351.490256 -281.065812) (xy 351.451149 -281.032454) (xy 351.417236 -280.993826)
			(xy 351.389222 -280.950729) (xy 351.367687 -280.904056) (xy 351.353077 -280.854774) (xy 351.345696 -280.803905)
			(xy 351.345246 -280.778204) (xy 349.239078 -280.778204) (xy 349.239078 -280.778712) (xy 349.238689 -280.801914)
			(xy 349.232624 -280.847921) (xy 349.220651 -280.892754) (xy 349.212154 -280.914348) (xy 349.202502 -280.937462)
			(xy 349.374714 -281.23515) (xy 349.399606 -281.238452) (xy 349.424981 -281.242322) (xy 349.474363 -281.256321)
			(xy 349.521229 -281.277253) (xy 349.564611 -281.304685) (xy 349.603613 -281.338052) (xy 349.637431 -281.376664)
			(xy 349.665366 -281.419725) (xy 349.686841 -281.466344) (xy 349.701412 -281.51556) (xy 349.70878 -281.566356)
			(xy 349.709232 -281.59202) (xy 349.708733 -281.618707) (xy 349.700778 -281.671486) (xy 349.685046 -281.722489)
			(xy 349.661888 -281.770578) (xy 349.631821 -281.814678) (xy 349.595517 -281.853805) (xy 349.553787 -281.887083)
			(xy 349.507563 -281.91377) (xy 349.457878 -281.93327) (xy 349.405841 -281.945147) (xy 349.352616 -281.949136)
			(xy 349.299391 -281.945147) (xy 349.247354 -281.93327) (xy 349.197669 -281.91377) (xy 349.151445 -281.887083)
			(xy 349.109715 -281.853805) (xy 349.073411 -281.814678) (xy 349.043344 -281.770578) (xy 349.020186 -281.722489)
			(xy 349.004454 -281.671486) (xy 348.996499 -281.618707) (xy 348.996 -281.59202) (xy 348.996354 -281.56868)
			(xy 349.002459 -281.522401) (xy 349.014567 -281.477318) (xy 349.023178 -281.455622) (xy 349.03283 -281.432254)
			(xy 348.861126 -281.135074) (xy 348.836234 -281.131772) (xy 348.81081 -281.12798) (xy 348.761325 -281.114075)
			(xy 348.714349 -281.093208) (xy 348.670856 -281.065812) (xy 348.631749 -281.032454) (xy 348.597836 -280.993826)
			(xy 348.569822 -280.950729) (xy 348.548287 -280.904056) (xy 348.533677 -280.854774) (xy 348.526296 -280.803905)
			(xy 348.525846 -280.778204) (xy 346.419678 -280.778204) (xy 346.419237 -280.803872) (xy 346.411889 -280.854679)
			(xy 346.39733 -280.903908) (xy 346.375863 -280.95054) (xy 346.34793 -280.993611) (xy 346.31411 -281.032232)
			(xy 346.2751 -281.065603) (xy 346.231709 -281.093036) (xy 346.184831 -281.113962) (xy 346.135438 -281.127949)
			(xy 346.110052 -281.131772) (xy 346.08516 -281.135074) (xy 345.913202 -281.432254) (xy 345.922854 -281.455622)
			(xy 345.93142 -281.477333) (xy 345.943508 -281.522414) (xy 345.949629 -281.568684) (xy 345.950032 -281.592)
			(xy 347.116897 -281.592) (xy 347.120875 -281.538924) (xy 347.132719 -281.487034) (xy 347.152164 -281.437489)
			(xy 347.178777 -281.391395) (xy 347.211963 -281.349783) (xy 347.250981 -281.313582) (xy 347.294958 -281.2836)
			(xy 347.342912 -281.260509) (xy 347.393773 -281.244822) (xy 347.446404 -281.236892) (xy 347.473016 -281.23642)
			(xy 347.49796 -281.23688) (xy 347.547358 -281.243842) (xy 347.595299 -281.257641) (xy 347.640839 -281.278007)
			(xy 347.683086 -281.304538) (xy 347.721209 -281.336715) (xy 347.754459 -281.373905) (xy 347.768672 -281.394408)
			(xy 348.11716 -281.394408) (xy 348.131349 -281.373887) (xy 348.164605 -281.336696) (xy 348.202732 -281.304518)
			(xy 348.244982 -281.277984) (xy 348.290525 -281.257614) (xy 348.338469 -281.243809) (xy 348.38787 -281.236839)
			(xy 348.412816 -281.23642) (xy 348.439428 -281.236878) (xy 348.492057 -281.244813) (xy 348.542916 -281.260503)
			(xy 348.590869 -281.283598) (xy 348.634843 -281.313581) (xy 348.673859 -281.349783) (xy 348.707042 -281.391396)
			(xy 348.733654 -281.43749) (xy 348.753098 -281.487035) (xy 348.764941 -281.538925) (xy 348.768919 -281.592)
			(xy 348.764941 -281.645075) (xy 348.753098 -281.696965) (xy 348.733654 -281.74651) (xy 348.707042 -281.792604)
			(xy 348.673859 -281.834217) (xy 348.634843 -281.870419) (xy 348.590869 -281.900402) (xy 348.542916 -281.923497)
			(xy 348.492057 -281.939187) (xy 348.439428 -281.947122) (xy 348.412816 -281.94762) (xy 348.387869 -281.947239)
			(xy 348.338466 -281.940266) (xy 348.290523 -281.926455) (xy 348.244981 -281.906077) (xy 348.202735 -281.879533)
			(xy 348.164615 -281.847343) (xy 348.131369 -281.810141) (xy 348.11716 -281.789632) (xy 347.768672 -281.789632)
			(xy 347.754476 -281.810147) (xy 347.721219 -281.847336) (xy 347.683093 -281.879513) (xy 347.640844 -281.906048)
			(xy 347.595302 -281.926418) (xy 347.547361 -281.940226) (xy 347.497961 -281.947199) (xy 347.473016 -281.94762)
			(xy 347.446404 -281.947108) (xy 347.393773 -281.939178) (xy 347.342912 -281.923491) (xy 347.294958 -281.9004)
			(xy 347.250981 -281.870418) (xy 347.211963 -281.834217) (xy 347.178777 -281.792605) (xy 347.152164 -281.746511)
			(xy 347.132719 -281.696966) (xy 347.120875 -281.645076) (xy 347.116897 -281.592) (xy 345.950032 -281.592)
			(xy 345.950032 -281.59202) (xy 345.949533 -281.618707) (xy 345.941578 -281.671486) (xy 345.925846 -281.722489)
			(xy 345.902688 -281.770578) (xy 345.872621 -281.814678) (xy 345.836317 -281.853805) (xy 345.794587 -281.887083)
			(xy 345.748363 -281.91377) (xy 345.698678 -281.93327) (xy 345.646641 -281.945147) (xy 345.593416 -281.949136)
			(xy 345.540191 -281.945147) (xy 345.488154 -281.93327) (xy 345.438469 -281.91377) (xy 345.392245 -281.887083)
			(xy 345.350515 -281.853805) (xy 345.314211 -281.814678) (xy 345.284144 -281.770578) (xy 345.260986 -281.722489)
			(xy 345.245254 -281.671486) (xy 345.237299 -281.618707) (xy 345.2368 -281.59202) (xy 344.070432 -281.59202)
			(xy 344.070041 -281.617722) (xy 344.062645 -281.668592) (xy 344.048023 -281.717874) (xy 344.026478 -281.764546)
			(xy 343.998457 -281.807642) (xy 343.96454 -281.846269) (xy 343.925429 -281.879628) (xy 343.881935 -281.907027)
			(xy 343.834958 -281.927899) (xy 343.785471 -281.941811) (xy 343.760044 -281.945588) (xy 343.735152 -281.94889)
			(xy 343.563448 -282.24607) (xy 343.5731 -282.269438) (xy 343.581673 -282.291146) (xy 343.593758 -282.336228)
			(xy 343.599876 -282.382499) (xy 343.600278 -282.405836) (xy 343.826846 -282.405836) (xy 343.827345 -282.379149)
			(xy 343.8353 -282.32637) (xy 343.851032 -282.275367) (xy 343.87419 -282.227278) (xy 343.904257 -282.183178)
			(xy 343.940561 -282.144051) (xy 343.982291 -282.110773) (xy 344.028515 -282.084086) (xy 344.0782 -282.064586)
			(xy 344.130237 -282.052709) (xy 344.183462 -282.04872) (xy 344.236687 -282.052709) (xy 344.288724 -282.064586)
			(xy 344.338409 -282.084086) (xy 344.384633 -282.110773) (xy 344.426363 -282.144051) (xy 344.462667 -282.183178)
			(xy 344.492734 -282.227278) (xy 344.515892 -282.275367) (xy 344.531624 -282.32637) (xy 344.539579 -282.379149)
			(xy 344.540077 -282.4058) (xy 344.767237 -282.4058) (xy 344.771214 -282.352735) (xy 344.783054 -282.300856)
			(xy 344.802494 -282.25132) (xy 344.829099 -282.205235) (xy 344.862275 -282.163629) (xy 344.901282 -282.127433)
			(xy 344.945247 -282.097454) (xy 344.993189 -282.074361) (xy 345.044037 -282.058672) (xy 345.096655 -282.050736)
			(xy 345.123262 -282.050236) (xy 345.148207 -282.050654) (xy 345.197608 -282.057622) (xy 345.24555 -282.071428)
			(xy 345.291091 -282.091801) (xy 345.333337 -282.118339) (xy 345.371458 -282.150522) (xy 345.404707 -282.187719)
			(xy 345.418918 -282.208224) (xy 345.767406 -282.208224) (xy 345.781634 -282.187732) (xy 345.814883 -282.15054)
			(xy 345.853004 -282.118359) (xy 345.895247 -282.091821) (xy 345.940784 -282.071447) (xy 345.988721 -282.057635)
			(xy 346.038118 -282.050659) (xy 346.063062 -282.050236) (xy 346.08968 -282.050634) (xy 346.142321 -282.058563)
			(xy 346.193193 -282.07425) (xy 346.241158 -282.097344) (xy 346.285145 -282.12733) (xy 346.324171 -282.163537)
			(xy 346.357365 -282.205156) (xy 346.383984 -282.251258) (xy 346.403434 -282.300813) (xy 346.415281 -282.352714)
			(xy 346.41926 -282.4058) (xy 346.415281 -282.458886) (xy 346.403434 -282.510787) (xy 346.383984 -282.560342)
			(xy 346.357365 -282.606444) (xy 346.324171 -282.648063) (xy 346.285145 -282.68427) (xy 346.241158 -282.714256)
			(xy 346.193193 -282.73735) (xy 346.142321 -282.753037) (xy 346.08968 -282.760966) (xy 346.063062 -282.761436)
			(xy 346.038117 -282.761012) (xy 345.988716 -282.754046) (xy 345.940774 -282.740242) (xy 345.895232 -282.719871)
			(xy 345.852986 -282.693334) (xy 345.814864 -282.66115) (xy 345.781617 -282.623954) (xy 345.767406 -282.603448)
			(xy 345.418918 -282.603448) (xy 345.404665 -282.623923) (xy 345.371421 -282.661116) (xy 345.333306 -282.693299)
			(xy 345.291067 -282.71984) (xy 345.245533 -282.740217) (xy 345.197599 -282.754031) (xy 345.148205 -282.761011)
			(xy 345.123262 -282.761436) (xy 345.096655 -282.760864) (xy 345.044037 -282.752928) (xy 344.993189 -282.737239)
			(xy 344.945247 -282.714146) (xy 344.901282 -282.684167) (xy 344.862275 -282.647971) (xy 344.829099 -282.606365)
			(xy 344.802494 -282.56028) (xy 344.783054 -282.510744) (xy 344.771214 -282.458865) (xy 344.767237 -282.4058)
			(xy 344.540077 -282.4058) (xy 344.540078 -282.405836) (xy 344.540078 -282.406344) (xy 344.539667 -282.429545)
			(xy 344.533612 -282.475551) (xy 344.521647 -282.520386) (xy 344.513154 -282.54198) (xy 344.503502 -282.565094)
			(xy 344.675714 -282.863036) (xy 344.700606 -282.866338) (xy 344.725979 -282.870221) (xy 344.77536 -282.88422)
			(xy 344.822224 -282.90515) (xy 344.865606 -282.932582) (xy 344.904608 -282.965947) (xy 344.938426 -283.004557)
			(xy 344.966361 -283.047616) (xy 344.987837 -283.094234) (xy 345.00241 -283.143448) (xy 345.009779 -283.194243)
			(xy 345.010232 -283.219906) (xy 347.1164 -283.219906) (xy 347.116869 -283.194239) (xy 347.124216 -283.143434)
			(xy 347.138771 -283.094207) (xy 347.160236 -283.047576) (xy 347.188166 -283.004506) (xy 347.221983 -282.965885)
			(xy 347.260989 -282.932513) (xy 347.304377 -282.90508) (xy 347.351251 -282.884152) (xy 347.400642 -282.870162)
			(xy 347.426026 -282.866338) (xy 347.450918 -282.863036) (xy 347.623384 -282.564586) (xy 347.611618 -282.539792)
			(xy 347.594969 -282.487502) (xy 347.586549 -282.433275) (xy 347.586046 -282.405836) (xy 347.586545 -282.379149)
			(xy 347.5945 -282.32637) (xy 347.610232 -282.275367) (xy 347.63339 -282.227278) (xy 347.663457 -282.183178)
			(xy 347.699761 -282.144051) (xy 347.741491 -282.110773) (xy 347.787715 -282.084086) (xy 347.8374 -282.064586)
			(xy 347.889437 -282.052709) (xy 347.942662 -282.04872) (xy 347.995887 -282.052709) (xy 348.047924 -282.064586)
			(xy 348.097609 -282.084086) (xy 348.143833 -282.110773) (xy 348.185563 -282.144051) (xy 348.221867 -282.183178)
			(xy 348.251934 -282.227278) (xy 348.275092 -282.275367) (xy 348.290824 -282.32637) (xy 348.298779 -282.379149)
			(xy 348.299278 -282.405836) (xy 349.465646 -282.405836) (xy 349.466103 -282.380168) (xy 349.473446 -282.32936)
			(xy 349.488001 -282.280131) (xy 349.509465 -282.233498) (xy 349.537395 -282.190425) (xy 349.571215 -282.151804)
			(xy 349.610223 -282.118432) (xy 349.653615 -282.091) (xy 349.700492 -282.070075) (xy 349.749886 -282.056089)
			(xy 349.775272 -282.052268) (xy 349.800164 -282.048966) (xy 349.972376 -281.751278) (xy 349.962724 -281.728164)
			(xy 349.954224 -281.706571) (xy 349.942244 -281.661739) (xy 349.936189 -281.61573) (xy 349.9358 -281.592528)
			(xy 349.9358 -281.59202) (xy 349.936299 -281.565333) (xy 349.944254 -281.512554) (xy 349.959986 -281.461551)
			(xy 349.983144 -281.413462) (xy 350.013211 -281.369362) (xy 350.049515 -281.330235) (xy 350.091245 -281.296957)
			(xy 350.137469 -281.27027) (xy 350.187154 -281.25077) (xy 350.239191 -281.238893) (xy 350.292416 -281.234904)
			(xy 350.345641 -281.238893) (xy 350.397678 -281.25077) (xy 350.447363 -281.27027) (xy 350.493587 -281.296957)
			(xy 350.535317 -281.330235) (xy 350.571621 -281.369362) (xy 350.601688 -281.413462) (xy 350.624846 -281.461551)
			(xy 350.640578 -281.512554) (xy 350.648533 -281.565333) (xy 350.649032 -281.59202) (xy 350.648641 -281.617722)
			(xy 350.641245 -281.668592) (xy 350.626623 -281.717874) (xy 350.605078 -281.764546) (xy 350.577057 -281.807642)
			(xy 350.54314 -281.846269) (xy 350.504029 -281.879628) (xy 350.460535 -281.907027) (xy 350.413558 -281.927899)
			(xy 350.364071 -281.941811) (xy 350.338644 -281.945588) (xy 350.313752 -281.94889) (xy 350.142048 -282.24607)
			(xy 350.1517 -282.269438) (xy 350.160273 -282.291146) (xy 350.172358 -282.336228) (xy 350.178476 -282.382499)
			(xy 350.178877 -282.4058) (xy 351.345837 -282.4058) (xy 351.349814 -282.352735) (xy 351.361654 -282.300856)
			(xy 351.381094 -282.25132) (xy 351.407699 -282.205235) (xy 351.440875 -282.163629) (xy 351.479882 -282.127433)
			(xy 351.523847 -282.097454) (xy 351.571789 -282.074361) (xy 351.622637 -282.058672) (xy 351.675255 -282.050736)
			(xy 351.701862 -282.050236) (xy 351.726807 -282.050654) (xy 351.776208 -282.057622) (xy 351.82415 -282.071428)
			(xy 351.869691 -282.091801) (xy 351.911937 -282.118339) (xy 351.950058 -282.150522) (xy 351.983307 -282.187719)
			(xy 351.997518 -282.208224) (xy 352.346006 -282.208224) (xy 352.360234 -282.187732) (xy 352.393483 -282.15054)
			(xy 352.431604 -282.118359) (xy 352.473847 -282.091821) (xy 352.519384 -282.071447) (xy 352.567321 -282.057635)
			(xy 352.616718 -282.050659) (xy 352.641662 -282.050236) (xy 352.66828 -282.050634) (xy 352.720921 -282.058563)
			(xy 352.771793 -282.07425) (xy 352.819758 -282.097344) (xy 352.863745 -282.12733) (xy 352.902771 -282.163537)
			(xy 352.935965 -282.205156) (xy 352.962584 -282.251258) (xy 352.982034 -282.300813) (xy 352.993881 -282.352714)
			(xy 352.99786 -282.4058) (xy 352.993881 -282.458886) (xy 352.982034 -282.510787) (xy 352.962584 -282.560342)
			(xy 352.935965 -282.606444) (xy 352.902771 -282.648063) (xy 352.863745 -282.68427) (xy 352.819758 -282.714256)
			(xy 352.771793 -282.73735) (xy 352.720921 -282.753037) (xy 352.66828 -282.760966) (xy 352.641662 -282.761436)
			(xy 352.616717 -282.761012) (xy 352.567316 -282.754046) (xy 352.519374 -282.740242) (xy 352.473832 -282.719871)
			(xy 352.431586 -282.693334) (xy 352.393464 -282.66115) (xy 352.360217 -282.623954) (xy 352.346006 -282.603448)
			(xy 351.997518 -282.603448) (xy 351.983265 -282.623923) (xy 351.950021 -282.661116) (xy 351.911906 -282.693299)
			(xy 351.869667 -282.71984) (xy 351.824133 -282.740217) (xy 351.776199 -282.754031) (xy 351.726805 -282.761011)
			(xy 351.701862 -282.761436) (xy 351.675255 -282.760864) (xy 351.622637 -282.752928) (xy 351.571789 -282.737239)
			(xy 351.523847 -282.714146) (xy 351.479882 -282.684167) (xy 351.440875 -282.647971) (xy 351.407699 -282.606365)
			(xy 351.381094 -282.56028) (xy 351.361654 -282.510744) (xy 351.349814 -282.458865) (xy 351.345837 -282.4058)
			(xy 350.178877 -282.4058) (xy 350.178878 -282.405836) (xy 350.178379 -282.432523) (xy 350.170424 -282.485302)
			(xy 350.154692 -282.536305) (xy 350.131534 -282.584394) (xy 350.101467 -282.628494) (xy 350.065163 -282.667621)
			(xy 350.023433 -282.700899) (xy 349.977209 -282.727586) (xy 349.927524 -282.747086) (xy 349.875487 -282.758963)
			(xy 349.822262 -282.762952) (xy 349.769037 -282.758963) (xy 349.717 -282.747086) (xy 349.667315 -282.727586)
			(xy 349.621091 -282.700899) (xy 349.579361 -282.667621) (xy 349.543057 -282.628494) (xy 349.51299 -282.584394)
			(xy 349.489832 -282.536305) (xy 349.4741 -282.485302) (xy 349.466145 -282.432523) (xy 349.465646 -282.405836)
			(xy 348.299278 -282.405836) (xy 348.298737 -282.432711) (xy 348.290665 -282.485851) (xy 348.27471 -282.537178)
			(xy 348.251234 -282.58553) (xy 348.220767 -282.629811) (xy 348.184 -282.669018) (xy 348.141765 -282.702264)
			(xy 348.09502 -282.728795) (xy 348.044823 -282.748011) (xy 347.99231 -282.759476) (xy 347.965522 -282.76169)
			(xy 347.792802 -283.06014) (xy 347.802454 -283.083508) (xy 347.811016 -283.105221) (xy 347.823106 -283.1503)
			(xy 347.829228 -283.19657) (xy 347.829632 -283.2199) (xy 348.996483 -283.2199) (xy 349.000461 -283.166822)
			(xy 349.012305 -283.11493) (xy 349.031752 -283.065382) (xy 349.058366 -283.019287) (xy 349.091553 -282.977673)
			(xy 349.130572 -282.941471) (xy 349.174551 -282.911488) (xy 349.222507 -282.888396) (xy 349.27337 -282.872709)
			(xy 349.326003 -282.864778) (xy 349.352616 -282.864306) (xy 349.377588 -282.864683) (xy 349.427041 -282.871681)
			(xy 349.475029 -282.885524) (xy 349.520611 -282.905939) (xy 349.562892 -282.932525) (xy 349.601041 -282.964761)
			(xy 349.634309 -283.002013) (xy 349.648526 -283.022548) (xy 349.996506 -283.022548) (xy 350.010744 -283.002029)
			(xy 350.044003 -282.964773) (xy 350.082147 -282.932536) (xy 350.124425 -282.905952) (xy 350.170006 -282.885543)
			(xy 350.217994 -282.871711) (xy 350.267445 -282.864727) (xy 350.292416 -282.864306) (xy 350.319027 -282.864792)
			(xy 350.371654 -282.872727) (xy 350.422511 -282.888416) (xy 350.470462 -282.91151) (xy 350.514435 -282.941492)
			(xy 350.553448 -282.977693) (xy 350.586631 -283.019304) (xy 350.613241 -283.065396) (xy 350.632685 -283.114939)
			(xy 350.644527 -283.166827) (xy 350.648505 -283.2199) (xy 350.648505 -283.219906) (xy 352.7552 -283.219906)
			(xy 352.755669 -283.194239) (xy 352.763016 -283.143434) (xy 352.777571 -283.094207) (xy 352.799036 -283.047576)
			(xy 352.826966 -283.004506) (xy 352.860783 -282.965885) (xy 352.899789 -282.932513) (xy 352.943177 -282.90508)
			(xy 352.990051 -282.884152) (xy 353.039442 -282.870162) (xy 353.064826 -282.866338) (xy 353.089718 -282.863036)
			(xy 353.262184 -282.564586) (xy 353.250418 -282.539792) (xy 353.233769 -282.487502) (xy 353.225349 -282.433275)
			(xy 353.224846 -282.405836) (xy 353.225345 -282.379149) (xy 353.2333 -282.32637) (xy 353.249032 -282.275367)
			(xy 353.27219 -282.227278) (xy 353.302257 -282.183178) (xy 353.338561 -282.144051) (xy 353.380291 -282.110773)
			(xy 353.426515 -282.084086) (xy 353.4762 -282.064586) (xy 353.528237 -282.052709) (xy 353.581462 -282.04872)
			(xy 353.634687 -282.052709) (xy 353.686724 -282.064586) (xy 353.736409 -282.084086) (xy 353.782633 -282.110773)
			(xy 353.824363 -282.144051) (xy 353.860667 -282.183178) (xy 353.890734 -282.227278) (xy 353.913892 -282.275367)
			(xy 353.929624 -282.32637) (xy 353.937579 -282.379149) (xy 353.938078 -282.405836) (xy 353.937537 -282.432711)
			(xy 353.929465 -282.485851) (xy 353.91351 -282.537178) (xy 353.890034 -282.58553) (xy 353.859567 -282.629811)
			(xy 353.8228 -282.669018) (xy 353.780565 -282.702264) (xy 353.73382 -282.728795) (xy 353.683623 -282.748011)
			(xy 353.63111 -282.759476) (xy 353.604322 -282.76169) (xy 353.431602 -283.06014) (xy 353.441254 -283.083508)
			(xy 353.449816 -283.105221) (xy 353.461906 -283.1503) (xy 353.468028 -283.19657) (xy 353.468432 -283.219906)
			(xy 353.467933 -283.246593) (xy 353.459978 -283.299372) (xy 353.444246 -283.350375) (xy 353.421088 -283.398464)
			(xy 353.391021 -283.442564) (xy 353.354717 -283.481691) (xy 353.312987 -283.514969) (xy 353.266763 -283.541656)
			(xy 353.217078 -283.561156) (xy 353.165041 -283.573033) (xy 353.111816 -283.577022) (xy 353.058591 -283.573033)
			(xy 353.006554 -283.561156) (xy 352.956869 -283.541656) (xy 352.910645 -283.514969) (xy 352.868915 -283.481691)
			(xy 352.832611 -283.442564) (xy 352.802544 -283.398464) (xy 352.779386 -283.350375) (xy 352.763654 -283.299372)
			(xy 352.755699 -283.246593) (xy 352.7552 -283.219906) (xy 350.648505 -283.219906) (xy 350.644527 -283.272973)
			(xy 350.632685 -283.324861) (xy 350.613241 -283.374404) (xy 350.586631 -283.420496) (xy 350.553448 -283.462107)
			(xy 350.514435 -283.498308) (xy 350.470462 -283.52829) (xy 350.422511 -283.551384) (xy 350.371654 -283.567073)
			(xy 350.319027 -283.575008) (xy 350.292416 -283.575506) (xy 350.267445 -283.575099) (xy 350.217994 -283.568106)
			(xy 350.170007 -283.554268) (xy 350.124425 -283.533858) (xy 350.082144 -283.507276) (xy 350.043994 -283.475045)
			(xy 350.010724 -283.437797) (xy 349.996506 -283.417264) (xy 349.648526 -283.417264) (xy 349.634272 -283.437771)
			(xy 349.601015 -283.475026) (xy 349.562873 -283.507264) (xy 349.520598 -283.533849) (xy 349.47502 -283.55426)
			(xy 349.427035 -283.568096) (xy 349.377586 -283.575083) (xy 349.352616 -283.575506) (xy 349.326003 -283.575022)
			(xy 349.27337 -283.567091) (xy 349.222507 -283.551404) (xy 349.174551 -283.528312) (xy 349.130572 -283.498329)
			(xy 349.091553 -283.462127) (xy 349.058366 -283.420513) (xy 349.031752 -283.374418) (xy 349.012305 -283.32487)
			(xy 349.000461 -283.272978) (xy 348.996483 -283.2199) (xy 347.829632 -283.2199) (xy 347.829632 -283.219906)
			(xy 347.829133 -283.246593) (xy 347.821178 -283.299372) (xy 347.805446 -283.350375) (xy 347.782288 -283.398464)
			(xy 347.752221 -283.442564) (xy 347.715917 -283.481691) (xy 347.674187 -283.514969) (xy 347.627963 -283.541656)
			(xy 347.578278 -283.561156) (xy 347.526241 -283.573033) (xy 347.473016 -283.577022) (xy 347.419791 -283.573033)
			(xy 347.367754 -283.561156) (xy 347.318069 -283.541656) (xy 347.271845 -283.514969) (xy 347.230115 -283.481691)
			(xy 347.193811 -283.442564) (xy 347.163744 -283.398464) (xy 347.140586 -283.350375) (xy 347.124854 -283.299372)
			(xy 347.116899 -283.246593) (xy 347.1164 -283.219906) (xy 345.010232 -283.219906) (xy 345.009733 -283.246593)
			(xy 345.001778 -283.299372) (xy 344.986046 -283.350375) (xy 344.962888 -283.398464) (xy 344.932821 -283.442564)
			(xy 344.896517 -283.481691) (xy 344.854787 -283.514969) (xy 344.808563 -283.541656) (xy 344.758878 -283.561156)
			(xy 344.706841 -283.573033) (xy 344.653616 -283.577022) (xy 344.600391 -283.573033) (xy 344.548354 -283.561156)
			(xy 344.498669 -283.541656) (xy 344.452445 -283.514969) (xy 344.410715 -283.481691) (xy 344.374411 -283.442564)
			(xy 344.344344 -283.398464) (xy 344.321186 -283.350375) (xy 344.305454 -283.299372) (xy 344.297499 -283.246593)
			(xy 344.297 -283.219906) (xy 344.29735 -283.196566) (xy 344.303457 -283.150287) (xy 344.315566 -283.105204)
			(xy 344.324178 -283.083508) (xy 344.33383 -283.06014) (xy 344.162126 -282.762706) (xy 344.137234 -282.759404)
			(xy 344.111798 -282.755678) (xy 344.062308 -282.741769) (xy 344.015328 -282.720897) (xy 343.971833 -282.693494)
			(xy 343.932723 -282.660129) (xy 343.898811 -282.621493) (xy 343.870799 -282.578388) (xy 343.849268 -282.531706)
			(xy 343.834665 -282.482416) (xy 343.827291 -282.43154) (xy 343.826846 -282.405836) (xy 343.600278 -282.405836)
			(xy 343.599779 -282.432523) (xy 343.591824 -282.485302) (xy 343.576092 -282.536305) (xy 343.552934 -282.584394)
			(xy 343.522867 -282.628494) (xy 343.486563 -282.667621) (xy 343.444833 -282.700899) (xy 343.398609 -282.727586)
			(xy 343.348924 -282.747086) (xy 343.296887 -282.758963) (xy 343.243662 -282.762952) (xy 343.190437 -282.758963)
			(xy 343.1384 -282.747086) (xy 343.088715 -282.727586) (xy 343.042491 -282.700899) (xy 343.000761 -282.667621)
			(xy 342.964457 -282.628494) (xy 342.93439 -282.584394) (xy 342.911232 -282.536305) (xy 342.8955 -282.485302)
			(xy 342.887545 -282.432523) (xy 342.887046 -282.405836) (xy 341.720932 -282.405836) (xy 341.720433 -282.432523)
			(xy 341.712478 -282.485302) (xy 341.696746 -282.536305) (xy 341.673588 -282.584394) (xy 341.643521 -282.628494)
			(xy 341.607217 -282.667621) (xy 341.565487 -282.700899) (xy 341.519263 -282.727586) (xy 341.469578 -282.747086)
			(xy 341.417541 -282.758963) (xy 341.364316 -282.762952) (xy 341.311091 -282.758963) (xy 341.259054 -282.747086)
			(xy 341.209369 -282.727586) (xy 341.163145 -282.700899) (xy 341.121415 -282.667621) (xy 341.085111 -282.628494)
			(xy 341.055044 -282.584394) (xy 341.031886 -282.536305) (xy 341.016154 -282.485302) (xy 341.008199 -282.432523)
			(xy 341.0077 -282.405836) (xy 339.841332 -282.405836) (xy 339.840839 -282.431513) (xy 339.833482 -282.482337)
			(xy 339.818909 -282.53158) (xy 339.797424 -282.578223) (xy 339.769469 -282.621301) (xy 339.735624 -282.659924)
			(xy 339.696589 -282.693293) (xy 339.65317 -282.720716) (xy 339.606267 -282.741627) (xy 339.556849 -282.755594)
			(xy 339.531452 -282.759404) (xy 339.50656 -282.762706) (xy 339.334602 -283.060394) (xy 339.344254 -283.083508)
			(xy 339.352772 -283.105185) (xy 339.364777 -283.150184) (xy 339.370815 -283.196365) (xy 339.371178 -283.219652)
			(xy 339.371178 -283.2199) (xy 340.538107 -283.2199) (xy 340.542084 -283.166831) (xy 340.553926 -283.114947)
			(xy 340.573367 -283.065407) (xy 340.599974 -283.019318) (xy 340.633153 -282.977709) (xy 340.672163 -282.941509)
			(xy 340.716132 -282.911528) (xy 340.764078 -282.888433) (xy 340.81493 -282.872743) (xy 340.867553 -282.864806)
			(xy 340.894162 -282.864306) (xy 340.919133 -282.864725) (xy 340.968583 -282.871715) (xy 341.016571 -282.88555)
			(xy 341.062153 -282.905958) (xy 341.104434 -282.932539) (xy 341.142584 -282.964769) (xy 341.175854 -283.002016)
			(xy 341.190072 -283.022548) (xy 341.538052 -283.022548) (xy 341.55226 -283.002007) (xy 341.585525 -282.964752)
			(xy 341.623673 -282.932517) (xy 341.665957 -282.905935) (xy 341.711543 -282.88553) (xy 341.759535 -282.871702)
			(xy 341.80899 -282.864724) (xy 341.833962 -282.864306) (xy 341.860577 -282.864764) (xy 341.913214 -282.872693)
			(xy 341.964082 -282.888378) (xy 342.012043 -282.911471) (xy 342.056026 -282.941454) (xy 342.095049 -282.977657)
			(xy 342.128239 -283.019273) (xy 342.154856 -283.065372) (xy 342.174305 -283.114922) (xy 342.186151 -283.166818)
			(xy 342.190129 -283.2199) (xy 342.186151 -283.272982) (xy 342.174305 -283.324878) (xy 342.154856 -283.374428)
			(xy 342.128239 -283.420527) (xy 342.095049 -283.462143) (xy 342.056026 -283.498346) (xy 342.012043 -283.528329)
			(xy 341.964082 -283.551422) (xy 341.913214 -283.567107) (xy 341.860577 -283.575036) (xy 341.833962 -283.575506)
			(xy 341.808992 -283.575064) (xy 341.759543 -283.568077) (xy 341.711556 -283.554245) (xy 341.665974 -283.533841)
			(xy 341.623693 -283.507265) (xy 341.585542 -283.475038) (xy 341.552271 -283.437795) (xy 341.538052 -283.417264)
			(xy 341.190072 -283.417264) (xy 341.175852 -283.437796) (xy 341.142589 -283.475051) (xy 341.104442 -283.507286)
			(xy 341.062161 -283.533869) (xy 341.016577 -283.554276) (xy 340.968587 -283.568106) (xy 340.919134 -283.575087)
			(xy 340.894162 -283.575506) (xy 340.867553 -283.574994) (xy 340.81493 -283.567057) (xy 340.764078 -283.551367)
			(xy 340.716132 -283.528272) (xy 340.672163 -283.498291) (xy 340.633153 -283.462091) (xy 340.599974 -283.420482)
			(xy 340.573367 -283.374393) (xy 340.553926 -283.324853) (xy 340.542084 -283.272969) (xy 340.538107 -283.2199)
			(xy 339.371178 -283.2199) (xy 339.371178 -283.219906) (xy 339.370679 -283.246593) (xy 339.362724 -283.299372)
			(xy 339.346992 -283.350375) (xy 339.323834 -283.398464) (xy 339.293767 -283.442564) (xy 339.257463 -283.481691)
			(xy 339.215733 -283.514969) (xy 339.169509 -283.541656) (xy 339.119824 -283.561156) (xy 339.067787 -283.573033)
			(xy 339.014562 -283.577022) (xy 338.961337 -283.573033) (xy 338.9093 -283.561156) (xy 338.859615 -283.541656)
			(xy 338.813391 -283.514969) (xy 338.771661 -283.481691) (xy 338.735357 -283.442564) (xy 338.70529 -283.398464)
			(xy 338.682132 -283.350375) (xy 338.6664 -283.299372) (xy 338.658445 -283.246593) (xy 338.657946 -283.219906)
			(xy 336.551778 -283.219906) (xy 336.551279 -283.246593) (xy 336.543324 -283.299372) (xy 336.527592 -283.350375)
			(xy 336.504434 -283.398464) (xy 336.474367 -283.442564) (xy 336.438063 -283.481691) (xy 336.396333 -283.514969)
			(xy 336.350109 -283.541656) (xy 336.300424 -283.561156) (xy 336.248387 -283.573033) (xy 336.195162 -283.577022)
			(xy 336.141937 -283.573033) (xy 336.0899 -283.561156) (xy 336.040215 -283.541656) (xy 335.993991 -283.514969)
			(xy 335.952261 -283.481691) (xy 335.915957 -283.442564) (xy 335.88589 -283.398464) (xy 335.862732 -283.350375)
			(xy 335.847 -283.299372) (xy 335.839045 -283.246593) (xy 335.838546 -283.219906) (xy 335.8389 -283.196566)
			(xy 335.845006 -283.150287) (xy 335.857113 -283.105205) (xy 335.865724 -283.083508) (xy 335.875376 -283.06014)
			(xy 335.703164 -282.762706) (xy 335.678526 -282.759404) (xy 335.653134 -282.755564) (xy 335.603716 -282.741597)
			(xy 335.556812 -282.720688) (xy 335.513392 -282.693268) (xy 335.474354 -282.659904) (xy 335.440504 -282.621286)
			(xy 335.412543 -282.578212) (xy 335.391049 -282.531573) (xy 335.376466 -282.482334) (xy 335.369096 -282.431513)
			(xy 335.368646 -282.405836) (xy 335.142332 -282.405836) (xy 335.141833 -282.432523) (xy 335.133878 -282.485302)
			(xy 335.118146 -282.536305) (xy 335.094988 -282.584394) (xy 335.064921 -282.628494) (xy 335.028617 -282.667621)
			(xy 334.986887 -282.700899) (xy 334.940663 -282.727586) (xy 334.890978 -282.747086) (xy 334.838941 -282.758963)
			(xy 334.785716 -282.762952) (xy 334.732491 -282.758963) (xy 334.680454 -282.747086) (xy 334.630769 -282.727586)
			(xy 334.584545 -282.700899) (xy 334.542815 -282.667621) (xy 334.506511 -282.628494) (xy 334.476444 -282.584394)
			(xy 334.453286 -282.536305) (xy 334.437554 -282.485302) (xy 334.429599 -282.432523) (xy 334.4291 -282.405836)
			(xy 106.93781 -282.405836) (xy 106.937311 -282.432523) (xy 106.929356 -282.485302) (xy 106.913624 -282.536305)
			(xy 106.890466 -282.584394) (xy 106.860399 -282.628494) (xy 106.824095 -282.667621) (xy 106.782365 -282.700899)
			(xy 106.736141 -282.727586) (xy 106.686456 -282.747086) (xy 106.634419 -282.758963) (xy 106.581194 -282.762952)
			(xy 106.527969 -282.758963) (xy 106.475932 -282.747086) (xy 106.426247 -282.727586) (xy 106.380023 -282.700899)
			(xy 106.338293 -282.667621) (xy 106.301989 -282.628494) (xy 106.271922 -282.584394) (xy 106.248764 -282.536305)
			(xy 106.233032 -282.485302) (xy 106.225077 -282.432523) (xy 106.224578 -282.405836) (xy 106.224939 -282.382496)
			(xy 106.231042 -282.336217) (xy 106.243146 -282.291135) (xy 106.251756 -282.269438) (xy 106.261408 -282.24607)
			(xy 106.08945 -281.94889) (xy 106.064558 -281.945588) (xy 106.039168 -281.941804) (xy 105.989781 -281.927797)
			(xy 105.942912 -281.906857) (xy 105.899528 -281.879414) (xy 105.860525 -281.846038) (xy 105.826708 -281.807415)
			(xy 105.798776 -281.764345) (xy 105.777306 -281.717716) (xy 105.76274 -281.668491) (xy 105.75538 -281.617687)
			(xy 105.754932 -281.59202) (xy 104.588564 -281.59202) (xy 104.588065 -281.618707) (xy 104.58011 -281.671486)
			(xy 104.564378 -281.722489) (xy 104.54122 -281.770578) (xy 104.511153 -281.814678) (xy 104.474849 -281.853805)
			(xy 104.433119 -281.887083) (xy 104.386895 -281.91377) (xy 104.33721 -281.93327) (xy 104.285173 -281.945147)
			(xy 104.231948 -281.949136) (xy 104.178723 -281.945147) (xy 104.126686 -281.93327) (xy 104.077001 -281.91377)
			(xy 104.030777 -281.887083) (xy 103.989047 -281.853805) (xy 103.952743 -281.814678) (xy 103.922676 -281.770578)
			(xy 103.899518 -281.722489) (xy 103.883786 -281.671486) (xy 103.875831 -281.618707) (xy 103.875332 -281.59202)
			(xy 103.875692 -281.56868) (xy 103.881795 -281.522401) (xy 103.8939 -281.477319) (xy 103.90251 -281.455622)
			(xy 103.912162 -281.432254) (xy 103.740458 -281.135074) (xy 103.715566 -281.131772) (xy 103.690146 -281.127955)
			(xy 103.640661 -281.114054) (xy 103.593685 -281.093191) (xy 103.550192 -281.065798) (xy 103.511084 -281.032443)
			(xy 103.47717 -280.993818) (xy 103.449156 -280.950723) (xy 103.42762 -280.904052) (xy 103.41301 -280.854772)
			(xy 103.405628 -280.803904) (xy 103.405178 -280.778204) (xy 101.29901 -280.778204) (xy 101.29901 -280.778712)
			(xy 101.298626 -280.801914) (xy 101.29256 -280.847921) (xy 101.280585 -280.892755) (xy 101.272086 -280.914348)
			(xy 101.262434 -280.937462) (xy 101.434646 -281.23515) (xy 101.459538 -281.238452) (xy 101.484917 -281.242297)
			(xy 101.534299 -281.2563) (xy 101.581165 -281.277236) (xy 101.624546 -281.304672) (xy 101.663548 -281.338042)
			(xy 101.697365 -281.376656) (xy 101.725299 -281.419719) (xy 101.746773 -281.46634) (xy 101.761345 -281.515558)
			(xy 101.768712 -281.566355) (xy 101.769164 -281.59202) (xy 101.768665 -281.618707) (xy 101.76071 -281.671486)
			(xy 101.744978 -281.722489) (xy 101.72182 -281.770578) (xy 101.691753 -281.814678) (xy 101.655449 -281.853805)
			(xy 101.613719 -281.887083) (xy 101.567495 -281.91377) (xy 101.51781 -281.93327) (xy 101.465773 -281.945147)
			(xy 101.412548 -281.949136) (xy 101.359323 -281.945147) (xy 101.307286 -281.93327) (xy 101.257601 -281.91377)
			(xy 101.211377 -281.887083) (xy 101.169647 -281.853805) (xy 101.133343 -281.814678) (xy 101.103276 -281.770578)
			(xy 101.080118 -281.722489) (xy 101.064386 -281.671486) (xy 101.056431 -281.618707) (xy 101.055932 -281.59202)
			(xy 101.056292 -281.56868) (xy 101.062395 -281.522401) (xy 101.0745 -281.477319) (xy 101.08311 -281.455622)
			(xy 101.092762 -281.432254) (xy 100.921058 -281.135074) (xy 100.896166 -281.131772) (xy 100.870746 -281.127955)
			(xy 100.821261 -281.114054) (xy 100.774285 -281.093191) (xy 100.730792 -281.065798) (xy 100.691684 -281.032443)
			(xy 100.65777 -280.993818) (xy 100.629756 -280.950723) (xy 100.60822 -280.904052) (xy 100.59361 -280.854772)
			(xy 100.586228 -280.803904) (xy 100.585778 -280.778204) (xy 98.47961 -280.778204) (xy 98.479228 -280.803875)
			(xy 98.471878 -280.854687) (xy 98.457316 -280.903921) (xy 98.435844 -280.950556) (xy 98.407905 -280.99363)
			(xy 98.374077 -281.032252) (xy 98.33506 -281.065622) (xy 98.29166 -281.093052) (xy 98.244774 -281.113973)
			(xy 98.195373 -281.127953) (xy 98.169984 -281.131772) (xy 98.145092 -281.135074) (xy 97.973134 -281.432254)
			(xy 97.982786 -281.455622) (xy 97.991354 -281.477332) (xy 98.003441 -281.522413) (xy 98.009561 -281.568684)
			(xy 98.009964 -281.592) (xy 99.176797 -281.592) (xy 99.180775 -281.538921) (xy 99.19262 -281.487028)
			(xy 99.212068 -281.43748) (xy 99.238684 -281.391385) (xy 99.271874 -281.349772) (xy 99.310895 -281.31357)
			(xy 99.354876 -281.28359) (xy 99.402835 -281.2605) (xy 99.4537 -281.244816) (xy 99.506334 -281.236889)
			(xy 99.532948 -281.23642) (xy 99.557892 -281.236855) (xy 99.607292 -281.243822) (xy 99.655233 -281.257625)
			(xy 99.700774 -281.277995) (xy 99.74302 -281.30453) (xy 99.781142 -281.336711) (xy 99.814392 -281.373904)
			(xy 99.828604 -281.394408) (xy 100.177092 -281.394408) (xy 100.191324 -281.373919) (xy 100.224573 -281.336727)
			(xy 100.262693 -281.304547) (xy 100.304935 -281.278009) (xy 100.350472 -281.257634) (xy 100.398408 -281.243822)
			(xy 100.447805 -281.236844) (xy 100.472748 -281.23642) (xy 100.499358 -281.236881) (xy 100.551984 -281.244819)
			(xy 100.602839 -281.260512) (xy 100.650787 -281.283608) (xy 100.694758 -281.313592) (xy 100.733769 -281.349795)
			(xy 100.766949 -281.391406) (xy 100.793558 -281.437498) (xy 100.813 -281.487041) (xy 100.824842 -281.538928)
			(xy 100.828819 -281.592) (xy 100.824842 -281.645072) (xy 100.813 -281.696959) (xy 100.793558 -281.746502)
			(xy 100.766949 -281.792594) (xy 100.733769 -281.834205) (xy 100.694758 -281.870408) (xy 100.650787 -281.900392)
			(xy 100.602839 -281.923488) (xy 100.551984 -281.939181) (xy 100.499358 -281.947119) (xy 100.472748 -281.94762)
			(xy 100.447802 -281.947214) (xy 100.3984 -281.940246) (xy 100.350457 -281.926439) (xy 100.304915 -281.906065)
			(xy 100.262669 -281.879525) (xy 100.224548 -281.847339) (xy 100.191302 -281.810139) (xy 100.177092 -281.789632)
			(xy 99.828604 -281.789632) (xy 99.814387 -281.810132) (xy 99.781134 -281.847321) (xy 99.743011 -281.8795)
			(xy 99.700766 -281.906036) (xy 99.655228 -281.926409) (xy 99.60729 -281.94022) (xy 99.557892 -281.947197)
			(xy 99.532948 -281.94762) (xy 99.506334 -281.947111) (xy 99.4537 -281.939184) (xy 99.402835 -281.9235)
			(xy 99.354876 -281.90041) (xy 99.310895 -281.87043) (xy 99.271874 -281.834228) (xy 99.238684 -281.792615)
			(xy 99.212068 -281.74652) (xy 99.19262 -281.696972) (xy 99.180775 -281.645079) (xy 99.176797 -281.592)
			(xy 98.009964 -281.592) (xy 98.009964 -281.59202) (xy 98.009465 -281.618707) (xy 98.00151 -281.671486)
			(xy 97.985778 -281.722489) (xy 97.96262 -281.770578) (xy 97.932553 -281.814678) (xy 97.896249 -281.853805)
			(xy 97.854519 -281.887083) (xy 97.808295 -281.91377) (xy 97.75861 -281.93327) (xy 97.706573 -281.945147)
			(xy 97.653348 -281.949136) (xy 97.600123 -281.945147) (xy 97.548086 -281.93327) (xy 97.498401 -281.91377)
			(xy 97.452177 -281.887083) (xy 97.410447 -281.853805) (xy 97.374143 -281.814678) (xy 97.344076 -281.770578)
			(xy 97.320918 -281.722489) (xy 97.305186 -281.671486) (xy 97.297231 -281.618707) (xy 97.296732 -281.59202)
			(xy 96.130364 -281.59202) (xy 96.129945 -281.617721) (xy 96.12255 -281.668588) (xy 96.107929 -281.717868)
			(xy 96.086387 -281.764538) (xy 96.058369 -281.807633) (xy 96.024455 -281.84626) (xy 95.985348 -281.879619)
			(xy 95.941858 -281.907019) (xy 95.894885 -281.927893) (xy 95.845402 -281.941809) (xy 95.819976 -281.945588)
			(xy 95.795084 -281.94889) (xy 95.62338 -282.24607) (xy 95.633032 -282.269438) (xy 95.641608 -282.291146)
			(xy 95.653691 -282.336228) (xy 95.659809 -282.382499) (xy 95.66021 -282.405836) (xy 95.886778 -282.405836)
			(xy 95.887277 -282.379149) (xy 95.895232 -282.32637) (xy 95.910964 -282.275367) (xy 95.934122 -282.227278)
			(xy 95.964189 -282.183178) (xy 96.000493 -282.144051) (xy 96.042223 -282.110773) (xy 96.088447 -282.084086)
			(xy 96.138132 -282.064586) (xy 96.190169 -282.052709) (xy 96.243394 -282.04872) (xy 96.296619 -282.052709)
			(xy 96.348656 -282.064586) (xy 96.398341 -282.084086) (xy 96.444565 -282.110773) (xy 96.486295 -282.144051)
			(xy 96.522599 -282.183178) (xy 96.552666 -282.227278) (xy 96.575824 -282.275367) (xy 96.591556 -282.32637)
			(xy 96.599511 -282.379149) (xy 96.600009 -282.4058) (xy 96.827137 -282.4058) (xy 96.831114 -282.352732)
			(xy 96.842956 -282.30085) (xy 96.862398 -282.251312) (xy 96.889006 -282.205225) (xy 96.922186 -282.163618)
			(xy 96.961196 -282.127421) (xy 97.005165 -282.097443) (xy 97.053111 -282.074352) (xy 97.103964 -282.058666)
			(xy 97.156586 -282.050734) (xy 97.183194 -282.050236) (xy 97.20814 -282.050629) (xy 97.257542 -282.057602)
			(xy 97.305484 -282.071413) (xy 97.351025 -282.091789) (xy 97.393271 -282.118331) (xy 97.431392 -282.150518)
			(xy 97.464639 -282.187717) (xy 97.47885 -282.208224) (xy 97.827338 -282.208224) (xy 97.841546 -282.187717)
			(xy 97.874798 -282.150525) (xy 97.912922 -282.118345) (xy 97.955169 -282.091809) (xy 98.000709 -282.071437)
			(xy 98.04865 -282.057629) (xy 98.098049 -282.050657) (xy 98.122994 -282.050236) (xy 98.14961 -282.050636)
			(xy 98.202248 -282.058569) (xy 98.253115 -282.074259) (xy 98.301076 -282.097355) (xy 98.345059 -282.127341)
			(xy 98.384081 -282.163548) (xy 98.417271 -282.205166) (xy 98.443888 -282.251267) (xy 98.463336 -282.300819)
			(xy 98.475181 -282.352717) (xy 98.47916 -282.4058) (xy 98.475181 -282.458883) (xy 98.463336 -282.510781)
			(xy 98.443888 -282.560333) (xy 98.417271 -282.606434) (xy 98.384081 -282.648052) (xy 98.345059 -282.684259)
			(xy 98.301076 -282.714245) (xy 98.253115 -282.737341) (xy 98.202248 -282.753031) (xy 98.14961 -282.760964)
			(xy 98.122994 -282.761436) (xy 98.09805 -282.760988) (xy 98.04865 -282.754026) (xy 98.000708 -282.740227)
			(xy 97.955167 -282.71986) (xy 97.91292 -282.693326) (xy 97.874798 -282.661146) (xy 97.841549 -282.623952)
			(xy 97.827338 -282.603448) (xy 97.47885 -282.603448) (xy 97.464641 -282.623954) (xy 97.431389 -282.661147)
			(xy 97.393266 -282.693328) (xy 97.35102 -282.719865) (xy 97.305479 -282.740237) (xy 97.257539 -282.754044)
			(xy 97.208139 -282.761016) (xy 97.183194 -282.761436) (xy 97.156586 -282.760866) (xy 97.103964 -282.752934)
			(xy 97.053112 -282.737248) (xy 97.005165 -282.714157) (xy 96.961196 -282.684179) (xy 96.922186 -282.647982)
			(xy 96.889006 -282.606375) (xy 96.862398 -282.560288) (xy 96.842956 -282.51075) (xy 96.831114 -282.458868)
			(xy 96.827137 -282.4058) (xy 96.600009 -282.4058) (xy 96.60001 -282.405836) (xy 96.60001 -282.406344)
			(xy 96.599604 -282.429545) (xy 96.593547 -282.475552) (xy 96.581581 -282.520386) (xy 96.573086 -282.54198)
			(xy 96.563434 -282.565094) (xy 96.735646 -282.863036) (xy 96.760538 -282.866338) (xy 96.785915 -282.870196)
			(xy 96.835296 -282.884199) (xy 96.882161 -282.905133) (xy 96.925541 -282.932568) (xy 96.964543 -282.965936)
			(xy 96.99836 -283.00455) (xy 97.026294 -283.04761) (xy 97.04777 -283.09423) (xy 97.062342 -283.143446)
			(xy 97.069711 -283.194242) (xy 97.070164 -283.219906) (xy 99.176332 -283.219906) (xy 99.176774 -283.194238)
			(xy 99.184121 -283.14343) (xy 99.198678 -283.094201) (xy 99.220145 -283.047569) (xy 99.248078 -283.004497)
			(xy 99.281898 -282.965876) (xy 99.320908 -282.932505) (xy 99.3643 -282.905072) (xy 99.411178 -282.884147)
			(xy 99.460572 -282.87016) (xy 99.485958 -282.866338) (xy 99.51085 -282.863036) (xy 99.683316 -282.564586)
			(xy 99.671546 -282.539795) (xy 99.654899 -282.487503) (xy 99.646481 -282.433275) (xy 99.645978 -282.405836)
			(xy 99.646477 -282.379149) (xy 99.654432 -282.32637) (xy 99.670164 -282.275367) (xy 99.693322 -282.227278)
			(xy 99.723389 -282.183178) (xy 99.759693 -282.144051) (xy 99.801423 -282.110773) (xy 99.847647 -282.084086)
			(xy 99.897332 -282.064586) (xy 99.949369 -282.052709) (xy 100.002594 -282.04872) (xy 100.055819 -282.052709)
			(xy 100.107856 -282.064586) (xy 100.157541 -282.084086) (xy 100.203765 -282.110773) (xy 100.245495 -282.144051)
			(xy 100.281799 -282.183178) (xy 100.311866 -282.227278) (xy 100.335024 -282.275367) (xy 100.350756 -282.32637)
			(xy 100.358711 -282.379149) (xy 100.35921 -282.405836) (xy 101.525578 -282.405836) (xy 101.526008 -282.380167)
			(xy 101.533352 -282.329356) (xy 101.547907 -282.280125) (xy 101.569374 -282.23349) (xy 101.597307 -282.190417)
			(xy 101.63113 -282.151795) (xy 101.670143 -282.118423) (xy 101.713538 -282.090993) (xy 101.760419 -282.07007)
			(xy 101.809817 -282.056088) (xy 101.835204 -282.052268) (xy 101.860096 -282.048966) (xy 102.032308 -281.751278)
			(xy 102.022656 -281.728164) (xy 102.014157 -281.706571) (xy 102.002177 -281.661739) (xy 101.996121 -281.61573)
			(xy 101.995732 -281.592528) (xy 101.995732 -281.59202) (xy 101.996231 -281.565333) (xy 102.004186 -281.512554)
			(xy 102.019918 -281.461551) (xy 102.043076 -281.413462) (xy 102.073143 -281.369362) (xy 102.109447 -281.330235)
			(xy 102.151177 -281.296957) (xy 102.197401 -281.27027) (xy 102.247086 -281.25077) (xy 102.299123 -281.238893)
			(xy 102.352348 -281.234904) (xy 102.405573 -281.238893) (xy 102.45761 -281.25077) (xy 102.507295 -281.27027)
			(xy 102.553519 -281.296957) (xy 102.595249 -281.330235) (xy 102.631553 -281.369362) (xy 102.66162 -281.413462)
			(xy 102.684778 -281.461551) (xy 102.70051 -281.512554) (xy 102.708465 -281.565333) (xy 102.708964 -281.59202)
			(xy 102.708545 -281.617721) (xy 102.70115 -281.668588) (xy 102.686529 -281.717868) (xy 102.664987 -281.764538)
			(xy 102.636969 -281.807633) (xy 102.603055 -281.84626) (xy 102.563948 -281.879619) (xy 102.520458 -281.907019)
			(xy 102.473485 -281.927893) (xy 102.424002 -281.941809) (xy 102.398576 -281.945588) (xy 102.373684 -281.94889)
			(xy 102.20198 -282.24607) (xy 102.211632 -282.269438) (xy 102.220208 -282.291146) (xy 102.232291 -282.336228)
			(xy 102.238409 -282.382499) (xy 102.238809 -282.4058) (xy 103.405737 -282.4058) (xy 103.409714 -282.352732)
			(xy 103.421556 -282.30085) (xy 103.440998 -282.251312) (xy 103.467606 -282.205225) (xy 103.500786 -282.163618)
			(xy 103.539796 -282.127421) (xy 103.583765 -282.097443) (xy 103.631711 -282.074352) (xy 103.682564 -282.058666)
			(xy 103.735186 -282.050734) (xy 103.761794 -282.050236) (xy 103.78674 -282.050629) (xy 103.836142 -282.057602)
			(xy 103.884084 -282.071413) (xy 103.929625 -282.091789) (xy 103.971871 -282.118331) (xy 104.009992 -282.150518)
			(xy 104.043239 -282.187717) (xy 104.05745 -282.208224) (xy 104.405938 -282.208224) (xy 104.420146 -282.187717)
			(xy 104.453398 -282.150525) (xy 104.491522 -282.118345) (xy 104.533769 -282.091809) (xy 104.579309 -282.071437)
			(xy 104.62725 -282.057629) (xy 104.676649 -282.050657) (xy 104.701594 -282.050236) (xy 104.72821 -282.050636)
			(xy 104.780848 -282.058569) (xy 104.831715 -282.074259) (xy 104.879676 -282.097355) (xy 104.923659 -282.127341)
			(xy 104.962681 -282.163548) (xy 104.995871 -282.205166) (xy 105.022488 -282.251267) (xy 105.041936 -282.300819)
			(xy 105.053781 -282.352717) (xy 105.05776 -282.4058) (xy 105.053781 -282.458883) (xy 105.041936 -282.510781)
			(xy 105.022488 -282.560333) (xy 104.995871 -282.606434) (xy 104.962681 -282.648052) (xy 104.923659 -282.684259)
			(xy 104.879676 -282.714245) (xy 104.831715 -282.737341) (xy 104.780848 -282.753031) (xy 104.72821 -282.760964)
			(xy 104.701594 -282.761436) (xy 104.67665 -282.760988) (xy 104.62725 -282.754026) (xy 104.579308 -282.740227)
			(xy 104.533767 -282.71986) (xy 104.49152 -282.693326) (xy 104.453398 -282.661146) (xy 104.420149 -282.623952)
			(xy 104.405938 -282.603448) (xy 104.05745 -282.603448) (xy 104.043241 -282.623954) (xy 104.009989 -282.661147)
			(xy 103.971866 -282.693328) (xy 103.92962 -282.719865) (xy 103.884079 -282.740237) (xy 103.836139 -282.754044)
			(xy 103.786739 -282.761016) (xy 103.761794 -282.761436) (xy 103.735186 -282.760866) (xy 103.682564 -282.752934)
			(xy 103.631712 -282.737248) (xy 103.583765 -282.714157) (xy 103.539796 -282.684179) (xy 103.500786 -282.647982)
			(xy 103.467606 -282.606375) (xy 103.440998 -282.560288) (xy 103.421556 -282.51075) (xy 103.409714 -282.458868)
			(xy 103.405737 -282.4058) (xy 102.238809 -282.4058) (xy 102.23881 -282.405836) (xy 102.238311 -282.432523)
			(xy 102.230356 -282.485302) (xy 102.214624 -282.536305) (xy 102.191466 -282.584394) (xy 102.161399 -282.628494)
			(xy 102.125095 -282.667621) (xy 102.083365 -282.700899) (xy 102.037141 -282.727586) (xy 101.987456 -282.747086)
			(xy 101.935419 -282.758963) (xy 101.882194 -282.762952) (xy 101.828969 -282.758963) (xy 101.776932 -282.747086)
			(xy 101.727247 -282.727586) (xy 101.681023 -282.700899) (xy 101.639293 -282.667621) (xy 101.602989 -282.628494)
			(xy 101.572922 -282.584394) (xy 101.549764 -282.536305) (xy 101.534032 -282.485302) (xy 101.526077 -282.432523)
			(xy 101.525578 -282.405836) (xy 100.35921 -282.405836) (xy 100.358732 -282.432714) (xy 100.350659 -282.48586)
			(xy 100.3347 -282.537192) (xy 100.311218 -282.585548) (xy 100.280744 -282.629832) (xy 100.243969 -282.66904)
			(xy 100.201726 -282.702285) (xy 100.154972 -282.728813) (xy 100.104766 -282.748023) (xy 100.052245 -282.75948)
			(xy 100.025454 -282.76169) (xy 99.852734 -283.06014) (xy 99.862386 -283.083508) (xy 99.87095 -283.10522)
			(xy 99.883038 -283.1503) (xy 99.88916 -283.19657) (xy 99.889564 -283.2199) (xy 101.056383 -283.2199)
			(xy 101.060361 -283.166819) (xy 101.072207 -283.114924) (xy 101.091656 -283.065374) (xy 101.118273 -283.019277)
			(xy 101.151463 -282.977662) (xy 101.190486 -282.941459) (xy 101.234469 -282.911478) (xy 101.28243 -282.888387)
			(xy 101.333297 -282.872702) (xy 101.385933 -282.864775) (xy 101.412548 -282.864306) (xy 101.437519 -282.864735)
			(xy 101.486969 -282.871724) (xy 101.534956 -282.885557) (xy 101.580538 -282.905964) (xy 101.622819 -282.932542)
			(xy 101.660969 -282.964771) (xy 101.694239 -283.002016) (xy 101.708458 -283.022548) (xy 102.056438 -283.022548)
			(xy 102.070655 -283.002014) (xy 102.103918 -282.964759) (xy 102.142065 -282.932523) (xy 102.184347 -282.90594)
			(xy 102.229932 -282.885534) (xy 102.277923 -282.871705) (xy 102.327376 -282.864725) (xy 102.352348 -282.864306)
			(xy 102.378957 -282.864795) (xy 102.431581 -282.872733) (xy 102.482434 -282.888425) (xy 102.53038 -282.91152)
			(xy 102.574349 -282.941503) (xy 102.613359 -282.977704) (xy 102.646538 -283.019314) (xy 102.673145 -283.065404)
			(xy 102.692586 -283.114945) (xy 102.704428 -283.16683) (xy 102.708405 -283.2199) (xy 102.708405 -283.219906)
			(xy 104.815132 -283.219906) (xy 104.815574 -283.194238) (xy 104.822921 -283.14343) (xy 104.837478 -283.094201)
			(xy 104.858945 -283.047569) (xy 104.886878 -283.004497) (xy 104.920698 -282.965876) (xy 104.959708 -282.932505)
			(xy 105.0031 -282.905072) (xy 105.049978 -282.884147) (xy 105.099372 -282.87016) (xy 105.124758 -282.866338)
			(xy 105.14965 -282.863036) (xy 105.322116 -282.564586) (xy 105.310346 -282.539795) (xy 105.293699 -282.487503)
			(xy 105.285281 -282.433275) (xy 105.284778 -282.405836) (xy 105.285277 -282.379149) (xy 105.293232 -282.32637)
			(xy 105.308964 -282.275367) (xy 105.332122 -282.227278) (xy 105.362189 -282.183178) (xy 105.398493 -282.144051)
			(xy 105.440223 -282.110773) (xy 105.486447 -282.084086) (xy 105.536132 -282.064586) (xy 105.588169 -282.052709)
			(xy 105.641394 -282.04872) (xy 105.694619 -282.052709) (xy 105.746656 -282.064586) (xy 105.796341 -282.084086)
			(xy 105.842565 -282.110773) (xy 105.884295 -282.144051) (xy 105.920599 -282.183178) (xy 105.950666 -282.227278)
			(xy 105.973824 -282.275367) (xy 105.989556 -282.32637) (xy 105.997511 -282.379149) (xy 105.99801 -282.405836)
			(xy 105.997532 -282.432714) (xy 105.989459 -282.48586) (xy 105.9735 -282.537192) (xy 105.950018 -282.585548)
			(xy 105.919544 -282.629832) (xy 105.882769 -282.66904) (xy 105.840526 -282.702285) (xy 105.793772 -282.728813)
			(xy 105.743566 -282.748023) (xy 105.691045 -282.75948) (xy 105.664254 -282.76169) (xy 105.491534 -283.06014)
			(xy 105.501186 -283.083508) (xy 105.50975 -283.10522) (xy 105.521838 -283.1503) (xy 105.52796 -283.19657)
			(xy 105.528364 -283.219906) (xy 105.527865 -283.246593) (xy 105.51991 -283.299372) (xy 105.504178 -283.350375)
			(xy 105.48102 -283.398464) (xy 105.450953 -283.442564) (xy 105.414649 -283.481691) (xy 105.372919 -283.514969)
			(xy 105.326695 -283.541656) (xy 105.27701 -283.561156) (xy 105.224973 -283.573033) (xy 105.171748 -283.577022)
			(xy 105.118523 -283.573033) (xy 105.066486 -283.561156) (xy 105.016801 -283.541656) (xy 104.970577 -283.514969)
			(xy 104.928847 -283.481691) (xy 104.892543 -283.442564) (xy 104.862476 -283.398464) (xy 104.839318 -283.350375)
			(xy 104.823586 -283.299372) (xy 104.815631 -283.246593) (xy 104.815132 -283.219906) (xy 102.708405 -283.219906)
			(xy 102.704428 -283.27297) (xy 102.692586 -283.324855) (xy 102.673145 -283.374396) (xy 102.646538 -283.420486)
			(xy 102.613359 -283.462096) (xy 102.574349 -283.498297) (xy 102.53038 -283.52828) (xy 102.482434 -283.551375)
			(xy 102.431581 -283.567067) (xy 102.378957 -283.575005) (xy 102.352348 -283.575506) (xy 102.327378 -283.575075)
			(xy 102.277928 -283.568086) (xy 102.229941 -283.554252) (xy 102.184359 -283.533846) (xy 102.142078 -283.507268)
			(xy 102.103927 -283.47504) (xy 102.070657 -283.437795) (xy 102.056438 -283.417264) (xy 101.708458 -283.417264)
			(xy 101.694247 -283.437803) (xy 101.660983 -283.475057) (xy 101.622834 -283.507292) (xy 101.580551 -283.533874)
			(xy 101.534966 -283.55428) (xy 101.486974 -283.568108) (xy 101.43752 -283.575088) (xy 101.412548 -283.575506)
			(xy 101.385933 -283.575025) (xy 101.333297 -283.567098) (xy 101.28243 -283.551413) (xy 101.234469 -283.528322)
			(xy 101.190486 -283.498341) (xy 101.151463 -283.462138) (xy 101.118273 -283.420523) (xy 101.091656 -283.374426)
			(xy 101.072207 -283.324876) (xy 101.060361 -283.272981) (xy 101.056383 -283.2199) (xy 99.889564 -283.2199)
			(xy 99.889564 -283.219906) (xy 99.889065 -283.246593) (xy 99.88111 -283.299372) (xy 99.865378 -283.350375)
			(xy 99.84222 -283.398464) (xy 99.812153 -283.442564) (xy 99.775849 -283.481691) (xy 99.734119 -283.514969)
			(xy 99.687895 -283.541656) (xy 99.63821 -283.561156) (xy 99.586173 -283.573033) (xy 99.532948 -283.577022)
			(xy 99.479723 -283.573033) (xy 99.427686 -283.561156) (xy 99.378001 -283.541656) (xy 99.331777 -283.514969)
			(xy 99.290047 -283.481691) (xy 99.253743 -283.442564) (xy 99.223676 -283.398464) (xy 99.200518 -283.350375)
			(xy 99.184786 -283.299372) (xy 99.176831 -283.246593) (xy 99.176332 -283.219906) (xy 97.070164 -283.219906)
			(xy 97.069665 -283.246593) (xy 97.06171 -283.299372) (xy 97.045978 -283.350375) (xy 97.02282 -283.398464)
			(xy 96.992753 -283.442564) (xy 96.956449 -283.481691) (xy 96.914719 -283.514969) (xy 96.868495 -283.541656)
			(xy 96.81881 -283.561156) (xy 96.766773 -283.573033) (xy 96.713548 -283.577022) (xy 96.660323 -283.573033)
			(xy 96.608286 -283.561156) (xy 96.558601 -283.541656) (xy 96.512377 -283.514969) (xy 96.470647 -283.481691)
			(xy 96.434343 -283.442564) (xy 96.404276 -283.398464) (xy 96.381118 -283.350375) (xy 96.365386 -283.299372)
			(xy 96.357431 -283.246593) (xy 96.356932 -283.219906) (xy 96.357287 -283.196566) (xy 96.363393 -283.150287)
			(xy 96.3755 -283.105205) (xy 96.38411 -283.083508) (xy 96.393762 -283.06014) (xy 96.222058 -282.762706)
			(xy 96.197166 -282.759404) (xy 96.171734 -282.755652) (xy 96.122244 -282.741748) (xy 96.075264 -282.72088)
			(xy 96.031768 -282.693481) (xy 95.992658 -282.660119) (xy 95.958745 -282.621485) (xy 95.930733 -282.578382)
			(xy 95.909201 -282.531702) (xy 95.894597 -282.482414) (xy 95.887223 -282.431539) (xy 95.886778 -282.405836)
			(xy 95.66021 -282.405836) (xy 95.659711 -282.432523) (xy 95.651756 -282.485302) (xy 95.636024 -282.536305)
			(xy 95.612866 -282.584394) (xy 95.582799 -282.628494) (xy 95.546495 -282.667621) (xy 95.504765 -282.700899)
			(xy 95.458541 -282.727586) (xy 95.408856 -282.747086) (xy 95.356819 -282.758963) (xy 95.303594 -282.762952)
			(xy 95.250369 -282.758963) (xy 95.198332 -282.747086) (xy 95.148647 -282.727586) (xy 95.102423 -282.700899)
			(xy 95.060693 -282.667621) (xy 95.024389 -282.628494) (xy 94.994322 -282.584394) (xy 94.971164 -282.536305)
			(xy 94.955432 -282.485302) (xy 94.947477 -282.432523) (xy 94.946978 -282.405836) (xy 93.780864 -282.405836)
			(xy 93.780365 -282.432523) (xy 93.77241 -282.485302) (xy 93.756678 -282.536305) (xy 93.73352 -282.584394)
			(xy 93.703453 -282.628494) (xy 93.667149 -282.667621) (xy 93.625419 -282.700899) (xy 93.579195 -282.727586)
			(xy 93.52951 -282.747086) (xy 93.477473 -282.758963) (xy 93.424248 -282.762952) (xy 93.371023 -282.758963)
			(xy 93.318986 -282.747086) (xy 93.269301 -282.727586) (xy 93.223077 -282.700899) (xy 93.181347 -282.667621)
			(xy 93.145043 -282.628494) (xy 93.114976 -282.584394) (xy 93.091818 -282.536305) (xy 93.076086 -282.485302)
			(xy 93.068131 -282.432523) (xy 93.067632 -282.405836) (xy 91.901264 -282.405836) (xy 91.90083 -282.431516)
			(xy 91.893471 -282.482345) (xy 91.878895 -282.531592) (xy 91.857404 -282.578239) (xy 91.829444 -282.62132)
			(xy 91.795591 -282.659944) (xy 91.756548 -282.693311) (xy 91.713121 -282.720732) (xy 91.66621 -282.741638)
			(xy 91.616784 -282.755598) (xy 91.591384 -282.759404) (xy 91.566492 -282.762706) (xy 91.394534 -283.060394)
			(xy 91.404186 -283.083508) (xy 91.412706 -283.105184) (xy 91.42471 -283.150184) (xy 91.430747 -283.196365)
			(xy 91.43111 -283.219652) (xy 91.43111 -283.2199) (xy 92.598007 -283.2199) (xy 92.601985 -283.166828)
			(xy 92.613827 -283.114941) (xy 92.633271 -283.065399) (xy 92.659881 -283.019308) (xy 92.693064 -282.977698)
			(xy 92.732077 -282.941498) (xy 92.77605 -282.911517) (xy 92.824001 -282.888425) (xy 92.874857 -282.872737)
			(xy 92.927483 -282.864804) (xy 92.954094 -282.864306) (xy 92.979066 -282.8647) (xy 93.028517 -282.871695)
			(xy 93.076505 -282.885535) (xy 93.122087 -282.905947) (xy 93.164368 -282.932531) (xy 93.202518 -282.964764)
			(xy 93.235786 -283.002014) (xy 93.250004 -283.022548) (xy 93.597984 -283.022548) (xy 93.612236 -283.002039)
			(xy 93.645493 -282.964783) (xy 93.683634 -282.932546) (xy 93.72591 -282.90596) (xy 93.771489 -282.885549)
			(xy 93.819475 -282.871715) (xy 93.868924 -282.864728) (xy 93.893894 -282.864306) (xy 93.920508 -282.864766)
			(xy 93.973141 -282.872699) (xy 94.024004 -282.888387) (xy 94.071961 -282.911481) (xy 94.11594 -282.941465)
			(xy 94.154959 -282.977669) (xy 94.188146 -283.019283) (xy 94.21476 -283.06538) (xy 94.234207 -283.114928)
			(xy 94.246051 -283.166821) (xy 94.250029 -283.2199) (xy 94.246051 -283.272979) (xy 94.234207 -283.324872)
			(xy 94.21476 -283.37442) (xy 94.188146 -283.420517) (xy 94.154959 -283.462131) (xy 94.11594 -283.498335)
			(xy 94.071961 -283.528319) (xy 94.024004 -283.551413) (xy 93.973141 -283.567101) (xy 93.920508 -283.575034)
			(xy 93.893894 -283.575506) (xy 93.868922 -283.575116) (xy 93.819471 -283.568119) (xy 93.771483 -283.554279)
			(xy 93.725901 -283.533866) (xy 93.68362 -283.507281) (xy 93.645471 -283.475048) (xy 93.612202 -283.437798)
			(xy 93.597984 -283.417264) (xy 93.250004 -283.417264) (xy 93.235764 -283.437781) (xy 93.202504 -283.475036)
			(xy 93.164361 -283.507273) (xy 93.122083 -283.533857) (xy 93.076502 -283.554267) (xy 93.028515 -283.5681)
			(xy 92.979065 -283.575084) (xy 92.954094 -283.575506) (xy 92.927483 -283.574996) (xy 92.874857 -283.567063)
			(xy 92.824001 -283.551375) (xy 92.77605 -283.528283) (xy 92.732077 -283.498302) (xy 92.693064 -283.462102)
			(xy 92.659881 -283.420492) (xy 92.633271 -283.374401) (xy 92.613827 -283.324859) (xy 92.601985 -283.272972)
			(xy 92.598007 -283.2199) (xy 91.43111 -283.2199) (xy 91.43111 -283.219906) (xy 91.430611 -283.246593)
			(xy 91.422656 -283.299372) (xy 91.406924 -283.350375) (xy 91.383766 -283.398464) (xy 91.353699 -283.442564)
			(xy 91.317395 -283.481691) (xy 91.275665 -283.514969) (xy 91.229441 -283.541656) (xy 91.179756 -283.561156)
			(xy 91.127719 -283.573033) (xy 91.074494 -283.577022) (xy 91.021269 -283.573033) (xy 90.969232 -283.561156)
			(xy 90.919547 -283.541656) (xy 90.873323 -283.514969) (xy 90.831593 -283.481691) (xy 90.795289 -283.442564)
			(xy 90.765222 -283.398464) (xy 90.742064 -283.350375) (xy 90.726332 -283.299372) (xy 90.718377 -283.246593)
			(xy 90.717878 -283.219906) (xy 88.61171 -283.219906) (xy 88.611211 -283.246593) (xy 88.603256 -283.299372)
			(xy 88.587524 -283.350375) (xy 88.564366 -283.398464) (xy 88.534299 -283.442564) (xy 88.497995 -283.481691)
			(xy 88.456265 -283.514969) (xy 88.410041 -283.541656) (xy 88.360356 -283.561156) (xy 88.308319 -283.573033)
			(xy 88.255094 -283.577022) (xy 88.201869 -283.573033) (xy 88.149832 -283.561156) (xy 88.100147 -283.541656)
			(xy 88.053923 -283.514969) (xy 88.012193 -283.481691) (xy 87.975889 -283.442564) (xy 87.945822 -283.398464)
			(xy 87.922664 -283.350375) (xy 87.906932 -283.299372) (xy 87.898977 -283.246593) (xy 87.898478 -283.219906)
			(xy 87.89883 -283.196566) (xy 87.904936 -283.150287) (xy 87.917044 -283.105204) (xy 87.925656 -283.083508)
			(xy 87.935308 -283.06014) (xy 87.763096 -282.762706) (xy 87.738458 -282.759404) (xy 87.71307 -282.755538)
			(xy 87.663652 -282.741577) (xy 87.616748 -282.720671) (xy 87.573328 -282.693254) (xy 87.534289 -282.659893)
			(xy 87.500439 -282.621278) (xy 87.472477 -282.578206) (xy 87.450982 -282.53157) (xy 87.436398 -282.482332)
			(xy 87.429028 -282.431512) (xy 87.428578 -282.405836) (xy 87.202264 -282.405836) (xy 87.201765 -282.432523)
			(xy 87.19381 -282.485302) (xy 87.178078 -282.536305) (xy 87.15492 -282.584394) (xy 87.124853 -282.628494)
			(xy 87.088549 -282.667621) (xy 87.046819 -282.700899) (xy 87.000595 -282.727586) (xy 86.95091 -282.747086)
			(xy 86.898873 -282.758963) (xy 86.845648 -282.762952) (xy 86.792423 -282.758963) (xy 86.740386 -282.747086)
			(xy 86.690701 -282.727586) (xy 86.644477 -282.700899) (xy 86.602747 -282.667621) (xy 86.566443 -282.628494)
			(xy 86.536376 -282.584394) (xy 86.513218 -282.536305) (xy 86.497486 -282.485302) (xy 86.489531 -282.432523)
			(xy 86.489032 -282.405836) (xy 2.509012 -282.405836) (xy 2.509012 -284.033722) (xy 86.489032 -284.033722)
			(xy 86.489531 -284.007035) (xy 86.497486 -283.954256) (xy 86.513218 -283.903253) (xy 86.536376 -283.855164)
			(xy 86.566443 -283.811064) (xy 86.602747 -283.771937) (xy 86.644477 -283.738659) (xy 86.690701 -283.711972)
			(xy 86.740386 -283.692472) (xy 86.792423 -283.680595) (xy 86.845648 -283.676606) (xy 86.898873 -283.680595)
			(xy 86.95091 -283.692472) (xy 87.000595 -283.711972) (xy 87.046819 -283.738659) (xy 87.088549 -283.771937)
			(xy 87.124853 -283.811064) (xy 87.15492 -283.855164) (xy 87.178078 -283.903253) (xy 87.19381 -283.954256)
			(xy 87.201765 -284.007035) (xy 87.202264 -284.033722) (xy 334.4291 -284.033722) (xy 334.429599 -284.007035)
			(xy 334.437554 -283.954256) (xy 334.453286 -283.903253) (xy 334.476444 -283.855164) (xy 334.506511 -283.811064)
			(xy 334.542815 -283.771937) (xy 334.584545 -283.738659) (xy 334.630769 -283.711972) (xy 334.680454 -283.692472)
			(xy 334.732491 -283.680595) (xy 334.785716 -283.676606) (xy 334.838941 -283.680595) (xy 334.890978 -283.692472)
			(xy 334.940663 -283.711972) (xy 334.986887 -283.738659) (xy 335.028617 -283.771937) (xy 335.064921 -283.811064)
			(xy 335.094988 -283.855164) (xy 335.118146 -283.903253) (xy 335.133878 -283.954256) (xy 335.141833 -284.007035)
			(xy 335.142332 -284.033722) (xy 335.141957 -284.057061) (xy 335.13586 -284.10334) (xy 335.123761 -284.148423)
			(xy 335.115154 -284.17012) (xy 335.105502 -284.193488) (xy 335.27746 -284.490668) (xy 335.302352 -284.49397)
			(xy 335.327736 -284.497786) (xy 335.37712 -284.511792) (xy 335.423986 -284.532731) (xy 335.467368 -284.56017)
			(xy 335.50637 -284.593544) (xy 335.540187 -284.632162) (xy 335.56812 -284.675227) (xy 335.589593 -284.721852)
			(xy 335.604162 -284.771072) (xy 335.611527 -284.821872) (xy 335.611978 -284.847538) (xy 335.611479 -284.874225)
			(xy 335.603524 -284.927004) (xy 335.587792 -284.978007) (xy 335.564634 -285.026096) (xy 335.534567 -285.070196)
			(xy 335.498263 -285.109323) (xy 335.456533 -285.142601) (xy 335.410309 -285.169288) (xy 335.360624 -285.188788)
			(xy 335.308587 -285.200665) (xy 335.255362 -285.204654) (xy 335.202137 -285.200665) (xy 335.1501 -285.188788)
			(xy 335.100415 -285.169288) (xy 335.054191 -285.142601) (xy 335.012461 -285.109323) (xy 334.976157 -285.070196)
			(xy 334.94609 -285.026096) (xy 334.922932 -284.978007) (xy 334.9072 -284.927004) (xy 334.899245 -284.874225)
			(xy 334.898746 -284.847538) (xy 334.89911 -284.824198) (xy 334.905212 -284.77792) (xy 334.917315 -284.732837)
			(xy 334.925924 -284.71114) (xy 334.935576 -284.687772) (xy 334.763618 -284.390592) (xy 334.738726 -284.38729)
			(xy 334.713345 -284.383451) (xy 334.663959 -284.369453) (xy 334.617089 -284.348521) (xy 334.573704 -284.321086)
			(xy 334.5347 -284.287716) (xy 334.500882 -284.2491) (xy 334.472948 -284.206034) (xy 334.451476 -284.15941)
			(xy 334.436909 -284.110189) (xy 334.429548 -284.059388) (xy 334.4291 -284.033722) (xy 87.202264 -284.033722)
			(xy 87.201886 -284.057061) (xy 87.19579 -284.103339) (xy 87.183692 -284.148423) (xy 87.175086 -284.17012)
			(xy 87.165434 -284.193488) (xy 87.337392 -284.490668) (xy 87.362284 -284.49397) (xy 87.387659 -284.49784)
			(xy 87.437042 -284.511837) (xy 87.48391 -284.532767) (xy 87.527293 -284.560199) (xy 87.566296 -284.593566)
			(xy 87.600114 -284.632178) (xy 87.628049 -284.67524) (xy 87.649523 -284.72186) (xy 87.664094 -284.771077)
			(xy 87.671459 -284.821874) (xy 87.67191 -284.847538) (xy 87.671411 -284.874225) (xy 87.663456 -284.927004)
			(xy 87.647724 -284.978007) (xy 87.624566 -285.026096) (xy 87.594499 -285.070196) (xy 87.558195 -285.109323)
			(xy 87.516465 -285.142601) (xy 87.470241 -285.169288) (xy 87.420556 -285.188788) (xy 87.368519 -285.200665)
			(xy 87.315294 -285.204654) (xy 87.262069 -285.200665) (xy 87.210032 -285.188788) (xy 87.160347 -285.169288)
			(xy 87.114123 -285.142601) (xy 87.072393 -285.109323) (xy 87.036089 -285.070196) (xy 87.006022 -285.026096)
			(xy 86.982864 -284.978007) (xy 86.967132 -284.927004) (xy 86.959177 -284.874225) (xy 86.958678 -284.847538)
			(xy 86.95904 -284.824198) (xy 86.965142 -284.777919) (xy 86.977246 -284.732837) (xy 86.985856 -284.71114)
			(xy 86.995508 -284.687772) (xy 86.82355 -284.390592) (xy 86.798658 -284.38729) (xy 86.773268 -284.383504)
			(xy 86.723882 -284.369497) (xy 86.677013 -284.348557) (xy 86.633629 -284.321115) (xy 86.594626 -284.287738)
			(xy 86.560809 -284.249116) (xy 86.532877 -284.206046) (xy 86.511406 -284.159418) (xy 86.49684 -284.110193)
			(xy 86.48948 -284.059389) (xy 86.489032 -284.033722) (xy 2.509012 -284.033722) (xy 2.509012 -284.8475)
			(xy 85.079639 -284.8475) (xy 85.083616 -284.794433) (xy 85.095458 -284.74255) (xy 85.1149 -284.693013)
			(xy 85.141508 -284.646926) (xy 85.174687 -284.605319) (xy 85.213697 -284.569123) (xy 85.257666 -284.539145)
			(xy 85.305612 -284.516054) (xy 85.356464 -284.500368) (xy 85.409086 -284.492436) (xy 85.435694 -284.491938)
			(xy 85.460664 -284.492362) (xy 85.510113 -284.499356) (xy 85.558099 -284.513192) (xy 85.60368 -284.5336)
			(xy 85.645961 -284.560179) (xy 85.684112 -284.592406) (xy 85.717384 -284.62965) (xy 85.731604 -284.65018)
			(xy 86.079584 -284.65018) (xy 86.093814 -284.629656) (xy 86.127077 -284.592403) (xy 86.165223 -284.560169)
			(xy 86.207503 -284.533587) (xy 86.253085 -284.513178) (xy 86.301072 -284.499346) (xy 86.350523 -284.49236)
			(xy 86.375494 -284.491938) (xy 86.40211 -284.492334) (xy 86.454748 -284.500267) (xy 86.505616 -284.515957)
			(xy 86.553577 -284.539053) (xy 86.59756 -284.56904) (xy 86.636583 -284.605247) (xy 86.669773 -284.646865)
			(xy 86.69639 -284.692966) (xy 86.715838 -284.742518) (xy 86.727683 -284.794416) (xy 86.731662 -284.8475)
			(xy 86.727683 -284.900584) (xy 86.715838 -284.952482) (xy 86.69639 -285.002034) (xy 86.669773 -285.048135)
			(xy 86.636583 -285.089753) (xy 86.59756 -285.12596) (xy 86.553577 -285.155947) (xy 86.505616 -285.179043)
			(xy 86.454748 -285.194733) (xy 86.40211 -285.202666) (xy 86.375494 -285.203138) (xy 86.350523 -285.202734)
			(xy 86.301073 -285.195738) (xy 86.253086 -285.181899) (xy 86.207504 -285.161488) (xy 86.165224 -285.134906)
			(xy 86.127073 -285.102675) (xy 86.093803 -285.065428) (xy 86.079584 -285.044896) (xy 85.731604 -285.044896)
			(xy 85.717374 -285.06542) (xy 85.684112 -285.102674) (xy 85.645966 -285.134909) (xy 85.603686 -285.161492)
			(xy 85.558104 -285.1819) (xy 85.510116 -285.195732) (xy 85.460665 -285.202717) (xy 85.435694 -285.203138)
			(xy 85.409086 -285.202564) (xy 85.356464 -285.194632) (xy 85.305612 -285.178946) (xy 85.257666 -285.155855)
			(xy 85.213697 -285.125877) (xy 85.174687 -285.089681) (xy 85.141508 -285.048074) (xy 85.1149 -285.001987)
			(xy 85.095458 -284.95245) (xy 85.083616 -284.900567) (xy 85.079639 -284.8475) (xy 2.509012 -284.8475)
			(xy 2.509012 -285.661354) (xy 87.428578 -285.661354) (xy 87.429024 -285.635685) (xy 87.436366 -285.584876)
			(xy 87.450919 -285.535644) (xy 87.472384 -285.48901) (xy 87.500315 -285.445936) (xy 87.534136 -285.407314)
			(xy 87.573147 -285.373942) (xy 87.616541 -285.346511) (xy 87.663421 -285.325588) (xy 87.712817 -285.311606)
			(xy 87.738204 -285.307786) (xy 87.763096 -285.304484) (xy 87.935054 -285.006796) (xy 87.925402 -284.983682)
			(xy 87.916911 -284.962086) (xy 87.904927 -284.917255) (xy 87.898868 -284.871248) (xy 87.898478 -284.848046)
			(xy 87.898478 -284.847538) (xy 87.898977 -284.820851) (xy 87.906932 -284.768072) (xy 87.922664 -284.717069)
			(xy 87.945822 -284.66898) (xy 87.975889 -284.62488) (xy 88.012193 -284.585753) (xy 88.053923 -284.552475)
			(xy 88.100147 -284.525788) (xy 88.149832 -284.506288) (xy 88.201869 -284.494411) (xy 88.255094 -284.490422)
			(xy 88.308319 -284.494411) (xy 88.360356 -284.506288) (xy 88.410041 -284.525788) (xy 88.456265 -284.552475)
			(xy 88.497995 -284.585753) (xy 88.534299 -284.62488) (xy 88.564366 -284.66898) (xy 88.587524 -284.717069)
			(xy 88.603256 -284.768072) (xy 88.611211 -284.820851) (xy 88.61171 -284.847538) (xy 88.611267 -284.873207)
			(xy 88.603926 -284.924017) (xy 88.589373 -284.973249) (xy 88.567909 -285.019884) (xy 88.539977 -285.062959)
			(xy 88.506156 -285.101581) (xy 88.467144 -285.134952) (xy 88.423749 -285.162383) (xy 88.376868 -285.183306)
			(xy 88.327471 -285.197287) (xy 88.302084 -285.201106) (xy 88.277192 -285.204408) (xy 88.105234 -285.502096)
			(xy 88.114886 -285.52521) (xy 88.123374 -285.546807) (xy 88.135359 -285.591637) (xy 88.14142 -285.637644)
			(xy 88.14181 -285.660846) (xy 88.14181 -285.661354) (xy 89.335356 -285.661354) (xy 89.335864 -285.635467)
			(xy 89.343963 -285.584329) (xy 89.359962 -285.535089) (xy 89.383468 -285.488957) (xy 89.4139 -285.44707)
			(xy 89.45051 -285.41046) (xy 89.492397 -285.380028) (xy 89.538529 -285.356522) (xy 89.587769 -285.340523)
			(xy 89.638907 -285.332424) (xy 89.690681 -285.332424) (xy 89.741819 -285.340523) (xy 89.791059 -285.356522)
			(xy 89.837191 -285.380028) (xy 89.879078 -285.41046) (xy 89.915688 -285.44707) (xy 89.94612 -285.488957)
			(xy 89.969626 -285.535089) (xy 89.985625 -285.584329) (xy 89.993724 -285.635467) (xy 89.994232 -285.661354)
			(xy 90.275156 -285.661354) (xy 90.27559 -285.636007) (xy 90.28337 -285.585913) (xy 90.298725 -285.537599)
			(xy 90.321292 -285.492204) (xy 90.35054 -285.450798) (xy 90.385779 -285.414354) (xy 90.426181 -285.383733)
			(xy 90.470793 -285.359656) (xy 90.518564 -285.342688) (xy 90.54338 -285.337504) (xy 90.56624 -285.333186)
			(xy 90.771218 -284.978348) (xy 90.763344 -284.956504) (xy 90.754767 -284.930085) (xy 90.745569 -284.87531)
			(xy 90.745056 -284.847538) (xy 90.745564 -284.821651) (xy 90.753663 -284.770513) (xy 90.769662 -284.721273)
			(xy 90.793168 -284.675141) (xy 90.8236 -284.633254) (xy 90.86021 -284.596644) (xy 90.902097 -284.566212)
			(xy 90.948229 -284.542706) (xy 90.997469 -284.526707) (xy 91.048607 -284.518608) (xy 91.100381 -284.518608)
			(xy 91.151519 -284.526707) (xy 91.200759 -284.542706) (xy 91.246891 -284.566212) (xy 91.288778 -284.596644)
			(xy 91.325388 -284.633254) (xy 91.35582 -284.675141) (xy 91.379326 -284.721273) (xy 91.395325 -284.770513)
			(xy 91.403424 -284.821651) (xy 91.403932 -284.847538) (xy 91.403458 -284.872872) (xy 91.395701 -284.922944)
			(xy 91.380375 -284.971239) (xy 91.357841 -285.016622) (xy 91.32863 -285.058022) (xy 91.29343 -285.094467)
			(xy 91.253068 -285.125098) (xy 91.208495 -285.149194) (xy 91.160761 -285.166187) (xy 91.135962 -285.171388)
			(xy 91.113102 -285.175706) (xy 90.908124 -285.530544) (xy 90.915998 -285.552642) (xy 90.924622 -285.57899)
			(xy 90.933948 -285.633636) (xy 90.93454 -285.661354) (xy 91.214956 -285.661354) (xy 91.215464 -285.635447)
			(xy 91.22357 -285.58427) (xy 91.239582 -285.534991) (xy 91.263105 -285.488824) (xy 91.293561 -285.446905)
			(xy 91.330199 -285.410267) (xy 91.372118 -285.379811) (xy 91.418285 -285.356288) (xy 91.467564 -285.340276)
			(xy 91.518741 -285.33217) (xy 91.570555 -285.33217) (xy 91.621732 -285.340276) (xy 91.671011 -285.356288)
			(xy 91.717178 -285.379811) (xy 91.759097 -285.410267) (xy 91.795735 -285.446905) (xy 91.826191 -285.488824)
			(xy 91.849714 -285.534991) (xy 91.865726 -285.58427) (xy 91.873832 -285.635447) (xy 91.87434 -285.661354)
			(xy 92.154756 -285.661354) (xy 92.155232 -285.63602) (xy 92.16299 -285.585949) (xy 92.178317 -285.537654)
			(xy 92.20085 -285.492273) (xy 92.230061 -285.450872) (xy 92.265261 -285.414427) (xy 92.305622 -285.383796)
			(xy 92.350194 -285.3597) (xy 92.397927 -285.342705) (xy 92.422726 -285.337504) (xy 92.445586 -285.333186)
			(xy 92.650818 -284.97784) (xy 92.643198 -284.955996) (xy 92.634574 -284.929714) (xy 92.625259 -284.875193)
			(xy 92.624656 -284.847538) (xy 92.625164 -284.821631) (xy 92.63327 -284.770454) (xy 92.649282 -284.721175)
			(xy 92.672805 -284.675008) (xy 92.703261 -284.633089) (xy 92.739899 -284.596451) (xy 92.781818 -284.565995)
			(xy 92.827985 -284.542472) (xy 92.877264 -284.52646) (xy 92.928441 -284.518354) (xy 92.980255 -284.518354)
			(xy 93.031432 -284.52646) (xy 93.080711 -284.542472) (xy 93.126878 -284.565995) (xy 93.168797 -284.596451)
			(xy 93.205435 -284.633089) (xy 93.235891 -284.675008) (xy 93.259414 -284.721175) (xy 93.275426 -284.770454)
			(xy 93.283532 -284.821631) (xy 93.28404 -284.847538) (xy 93.283648 -284.872916) (xy 93.275873 -284.923072)
			(xy 93.260496 -284.971442) (xy 93.237881 -285.016882) (xy 93.208565 -285.058314) (xy 93.17324 -285.09476)
			(xy 93.132743 -285.125356) (xy 93.088033 -285.149379) (xy 93.040166 -285.166259) (xy 93.015308 -285.171388)
			(xy 92.992448 -285.175706) (xy 92.78747 -285.530544) (xy 92.795344 -285.552642) (xy 92.803916 -285.578997)
			(xy 92.813107 -285.633645) (xy 92.813632 -285.661354) (xy 93.094556 -285.661354) (xy 93.095064 -285.635467)
			(xy 93.103163 -285.584329) (xy 93.119162 -285.535089) (xy 93.142668 -285.488957) (xy 93.1731 -285.44707)
			(xy 93.20971 -285.41046) (xy 93.251597 -285.380028) (xy 93.297729 -285.356522) (xy 93.346969 -285.340523)
			(xy 93.398107 -285.332424) (xy 93.449881 -285.332424) (xy 93.501019 -285.340523) (xy 93.550259 -285.356522)
			(xy 93.596391 -285.380028) (xy 93.638278 -285.41046) (xy 93.674888 -285.44707) (xy 93.70532 -285.488957)
			(xy 93.728826 -285.535089) (xy 93.744825 -285.584329) (xy 93.752924 -285.635467) (xy 93.753432 -285.661354)
			(xy 94.034356 -285.661354) (xy 94.034832 -285.63602) (xy 94.04259 -285.585949) (xy 94.057917 -285.537654)
			(xy 94.08045 -285.492273) (xy 94.109661 -285.450872) (xy 94.144861 -285.414427) (xy 94.185222 -285.383796)
			(xy 94.229794 -285.3597) (xy 94.277527 -285.342705) (xy 94.302326 -285.337504) (xy 94.325186 -285.333186)
			(xy 94.530418 -284.97784) (xy 94.522798 -284.955996) (xy 94.514174 -284.929714) (xy 94.504859 -284.875193)
			(xy 94.504256 -284.847538) (xy 94.504764 -284.821631) (xy 94.51287 -284.770454) (xy 94.528882 -284.721175)
			(xy 94.552405 -284.675008) (xy 94.582861 -284.633089) (xy 94.619499 -284.596451) (xy 94.661418 -284.565995)
			(xy 94.707585 -284.542472) (xy 94.756864 -284.52646) (xy 94.808041 -284.518354) (xy 94.859855 -284.518354)
			(xy 94.911032 -284.52646) (xy 94.960311 -284.542472) (xy 95.006478 -284.565995) (xy 95.048397 -284.596451)
			(xy 95.085035 -284.633089) (xy 95.115491 -284.675008) (xy 95.139014 -284.721175) (xy 95.155026 -284.770454)
			(xy 95.163132 -284.821631) (xy 95.16364 -284.847538) (xy 95.163248 -284.872916) (xy 95.155473 -284.923072)
			(xy 95.140096 -284.971442) (xy 95.117481 -285.016882) (xy 95.088165 -285.058314) (xy 95.05284 -285.09476)
			(xy 95.012343 -285.125356) (xy 94.967633 -285.149379) (xy 94.919766 -285.166259) (xy 94.894908 -285.171388)
			(xy 94.872048 -285.175706) (xy 94.66707 -285.530544) (xy 94.674944 -285.552642) (xy 94.683516 -285.578997)
			(xy 94.692707 -285.633645) (xy 94.693232 -285.661354) (xy 94.974156 -285.661354) (xy 94.974664 -285.635467)
			(xy 94.982763 -285.584329) (xy 94.998762 -285.535089) (xy 95.022268 -285.488957) (xy 95.0527 -285.44707)
			(xy 95.08931 -285.41046) (xy 95.131197 -285.380028) (xy 95.177329 -285.356522) (xy 95.226569 -285.340523)
			(xy 95.277707 -285.332424) (xy 95.329481 -285.332424) (xy 95.380619 -285.340523) (xy 95.429859 -285.356522)
			(xy 95.475991 -285.380028) (xy 95.517878 -285.41046) (xy 95.554488 -285.44707) (xy 95.58492 -285.488957)
			(xy 95.608426 -285.535089) (xy 95.624425 -285.584329) (xy 95.632524 -285.635467) (xy 95.633032 -285.661354)
			(xy 95.913956 -285.661354) (xy 95.914432 -285.63602) (xy 95.92219 -285.585949) (xy 95.937517 -285.537654)
			(xy 95.96005 -285.492273) (xy 95.989261 -285.450872) (xy 96.024461 -285.414427) (xy 96.064822 -285.383796)
			(xy 96.109394 -285.3597) (xy 96.157127 -285.342705) (xy 96.181926 -285.337504) (xy 96.204786 -285.333186)
			(xy 96.410018 -284.97784) (xy 96.402398 -284.955996) (xy 96.393774 -284.929714) (xy 96.384459 -284.875193)
			(xy 96.383856 -284.847538) (xy 96.384364 -284.821631) (xy 96.39247 -284.770454) (xy 96.408482 -284.721175)
			(xy 96.432005 -284.675008) (xy 96.462461 -284.633089) (xy 96.499099 -284.596451) (xy 96.541018 -284.565995)
			(xy 96.587185 -284.542472) (xy 96.636464 -284.52646) (xy 96.687641 -284.518354) (xy 96.739455 -284.518354)
			(xy 96.790632 -284.52646) (xy 96.839911 -284.542472) (xy 96.886078 -284.565995) (xy 96.927997 -284.596451)
			(xy 96.964635 -284.633089) (xy 96.995091 -284.675008) (xy 97.018614 -284.721175) (xy 97.034626 -284.770454)
			(xy 97.042732 -284.821631) (xy 97.04324 -284.847538) (xy 97.042848 -284.872916) (xy 97.035073 -284.923072)
			(xy 97.019696 -284.971442) (xy 96.997081 -285.016882) (xy 96.967765 -285.058314) (xy 96.93244 -285.09476)
			(xy 96.891943 -285.125356) (xy 96.847233 -285.149379) (xy 96.799366 -285.166259) (xy 96.774508 -285.171388)
			(xy 96.751648 -285.175706) (xy 96.54667 -285.530544) (xy 96.554544 -285.552642) (xy 96.563116 -285.578997)
			(xy 96.572307 -285.633645) (xy 96.572832 -285.661354) (xy 96.853756 -285.661354) (xy 96.854264 -285.635467)
			(xy 96.862363 -285.584329) (xy 96.878362 -285.535089) (xy 96.901868 -285.488957) (xy 96.9323 -285.44707)
			(xy 96.96891 -285.41046) (xy 97.010797 -285.380028) (xy 97.056929 -285.356522) (xy 97.106169 -285.340523)
			(xy 97.157307 -285.332424) (xy 97.209081 -285.332424) (xy 97.260219 -285.340523) (xy 97.309459 -285.356522)
			(xy 97.355591 -285.380028) (xy 97.397478 -285.41046) (xy 97.434088 -285.44707) (xy 97.46452 -285.488957)
			(xy 97.488026 -285.535089) (xy 97.504025 -285.584329) (xy 97.512124 -285.635467) (xy 97.512632 -285.661354)
			(xy 97.793556 -285.661354) (xy 97.794032 -285.63602) (xy 97.80179 -285.585949) (xy 97.817117 -285.537654)
			(xy 97.83965 -285.492273) (xy 97.868861 -285.450872) (xy 97.904061 -285.414427) (xy 97.944422 -285.383796)
			(xy 97.988994 -285.3597) (xy 98.036727 -285.342705) (xy 98.061526 -285.337504) (xy 98.084386 -285.333186)
			(xy 98.289618 -284.97784) (xy 98.281998 -284.955996) (xy 98.273374 -284.929714) (xy 98.264059 -284.875193)
			(xy 98.263456 -284.847538) (xy 98.263964 -284.821631) (xy 98.27207 -284.770454) (xy 98.288082 -284.721175)
			(xy 98.311605 -284.675008) (xy 98.342061 -284.633089) (xy 98.378699 -284.596451) (xy 98.420618 -284.565995)
			(xy 98.466785 -284.542472) (xy 98.516064 -284.52646) (xy 98.567241 -284.518354) (xy 98.619055 -284.518354)
			(xy 98.670232 -284.52646) (xy 98.719511 -284.542472) (xy 98.765678 -284.565995) (xy 98.807597 -284.596451)
			(xy 98.844235 -284.633089) (xy 98.874691 -284.675008) (xy 98.898214 -284.721175) (xy 98.914226 -284.770454)
			(xy 98.922332 -284.821631) (xy 98.92284 -284.847538) (xy 98.922448 -284.872916) (xy 98.914673 -284.923072)
			(xy 98.899296 -284.971442) (xy 98.876681 -285.016882) (xy 98.847365 -285.058314) (xy 98.81204 -285.09476)
			(xy 98.771543 -285.125356) (xy 98.726833 -285.149379) (xy 98.678966 -285.166259) (xy 98.654108 -285.171388)
			(xy 98.631248 -285.175706) (xy 98.42627 -285.530544) (xy 98.434144 -285.552642) (xy 98.442716 -285.578997)
			(xy 98.451907 -285.633645) (xy 98.452432 -285.661354) (xy 98.733356 -285.661354) (xy 98.733864 -285.635467)
			(xy 98.741963 -285.584329) (xy 98.757962 -285.535089) (xy 98.781468 -285.488957) (xy 98.8119 -285.44707)
			(xy 98.84851 -285.41046) (xy 98.890397 -285.380028) (xy 98.936529 -285.356522) (xy 98.985769 -285.340523)
			(xy 99.036907 -285.332424) (xy 99.088681 -285.332424) (xy 99.139819 -285.340523) (xy 99.189059 -285.356522)
			(xy 99.235191 -285.380028) (xy 99.277078 -285.41046) (xy 99.313688 -285.44707) (xy 99.34412 -285.488957)
			(xy 99.367626 -285.535089) (xy 99.383625 -285.584329) (xy 99.391724 -285.635467) (xy 99.392232 -285.661354)
			(xy 99.673156 -285.661354) (xy 99.673632 -285.63602) (xy 99.68139 -285.585949) (xy 99.696717 -285.537654)
			(xy 99.71925 -285.492273) (xy 99.748461 -285.450872) (xy 99.783661 -285.414427) (xy 99.824022 -285.383796)
			(xy 99.868594 -285.3597) (xy 99.916327 -285.342705) (xy 99.941126 -285.337504) (xy 99.963986 -285.333186)
			(xy 100.169218 -284.97784) (xy 100.161598 -284.955996) (xy 100.152974 -284.929714) (xy 100.143659 -284.875193)
			(xy 100.143056 -284.847538) (xy 100.143564 -284.821631) (xy 100.15167 -284.770454) (xy 100.167682 -284.721175)
			(xy 100.191205 -284.675008) (xy 100.221661 -284.633089) (xy 100.258299 -284.596451) (xy 100.300218 -284.565995)
			(xy 100.346385 -284.542472) (xy 100.395664 -284.52646) (xy 100.446841 -284.518354) (xy 100.498655 -284.518354)
			(xy 100.549832 -284.52646) (xy 100.599111 -284.542472) (xy 100.645278 -284.565995) (xy 100.687197 -284.596451)
			(xy 100.723835 -284.633089) (xy 100.754291 -284.675008) (xy 100.777814 -284.721175) (xy 100.793826 -284.770454)
			(xy 100.801932 -284.821631) (xy 100.80244 -284.847538) (xy 100.802048 -284.872916) (xy 100.794273 -284.923072)
			(xy 100.778896 -284.971442) (xy 100.756281 -285.016882) (xy 100.726965 -285.058314) (xy 100.69164 -285.09476)
			(xy 100.651143 -285.125356) (xy 100.606433 -285.149379) (xy 100.558566 -285.166259) (xy 100.533708 -285.171388)
			(xy 100.510848 -285.175706) (xy 100.30587 -285.530544) (xy 100.313744 -285.552642) (xy 100.322316 -285.578997)
			(xy 100.331507 -285.633645) (xy 100.332032 -285.661354) (xy 100.612956 -285.661354) (xy 100.613464 -285.635467)
			(xy 100.621563 -285.584329) (xy 100.637562 -285.535089) (xy 100.661068 -285.488957) (xy 100.6915 -285.44707)
			(xy 100.72811 -285.41046) (xy 100.769997 -285.380028) (xy 100.816129 -285.356522) (xy 100.865369 -285.340523)
			(xy 100.916507 -285.332424) (xy 100.968281 -285.332424) (xy 101.019419 -285.340523) (xy 101.068659 -285.356522)
			(xy 101.114791 -285.380028) (xy 101.156678 -285.41046) (xy 101.193288 -285.44707) (xy 101.22372 -285.488957)
			(xy 101.247226 -285.535089) (xy 101.263225 -285.584329) (xy 101.271324 -285.635467) (xy 101.271832 -285.661354)
			(xy 101.552756 -285.661354) (xy 101.553232 -285.63602) (xy 101.56099 -285.585949) (xy 101.576317 -285.537654)
			(xy 101.59885 -285.492273) (xy 101.628061 -285.450872) (xy 101.663261 -285.414427) (xy 101.703622 -285.383796)
			(xy 101.748194 -285.3597) (xy 101.795927 -285.342705) (xy 101.820726 -285.337504) (xy 101.843586 -285.333186)
			(xy 102.048818 -284.97784) (xy 102.041198 -284.955996) (xy 102.032574 -284.929714) (xy 102.023259 -284.875193)
			(xy 102.022656 -284.847538) (xy 102.023164 -284.821631) (xy 102.03127 -284.770454) (xy 102.047282 -284.721175)
			(xy 102.070805 -284.675008) (xy 102.101261 -284.633089) (xy 102.137899 -284.596451) (xy 102.179818 -284.565995)
			(xy 102.225985 -284.542472) (xy 102.275264 -284.52646) (xy 102.326441 -284.518354) (xy 102.378255 -284.518354)
			(xy 102.429432 -284.52646) (xy 102.478711 -284.542472) (xy 102.524878 -284.565995) (xy 102.566797 -284.596451)
			(xy 102.603435 -284.633089) (xy 102.633891 -284.675008) (xy 102.657414 -284.721175) (xy 102.673426 -284.770454)
			(xy 102.681532 -284.821631) (xy 102.68204 -284.847538) (xy 102.681648 -284.872916) (xy 102.673873 -284.923072)
			(xy 102.658496 -284.971442) (xy 102.635881 -285.016882) (xy 102.606565 -285.058314) (xy 102.57124 -285.09476)
			(xy 102.530743 -285.125356) (xy 102.486033 -285.149379) (xy 102.438166 -285.166259) (xy 102.413308 -285.171388)
			(xy 102.390448 -285.175706) (xy 102.18547 -285.530544) (xy 102.193344 -285.552642) (xy 102.201916 -285.578997)
			(xy 102.211107 -285.633645) (xy 102.211632 -285.661354) (xy 102.492556 -285.661354) (xy 102.493064 -285.635467)
			(xy 102.501163 -285.584329) (xy 102.517162 -285.535089) (xy 102.540668 -285.488957) (xy 102.5711 -285.44707)
			(xy 102.60771 -285.41046) (xy 102.649597 -285.380028) (xy 102.695729 -285.356522) (xy 102.744969 -285.340523)
			(xy 102.796107 -285.332424) (xy 102.847881 -285.332424) (xy 102.899019 -285.340523) (xy 102.948259 -285.356522)
			(xy 102.994391 -285.380028) (xy 103.036278 -285.41046) (xy 103.072888 -285.44707) (xy 103.10332 -285.488957)
			(xy 103.126826 -285.535089) (xy 103.142825 -285.584329) (xy 103.150924 -285.635467) (xy 103.151432 -285.661354)
			(xy 103.432356 -285.661354) (xy 103.432832 -285.63602) (xy 103.44059 -285.585949) (xy 103.455917 -285.537654)
			(xy 103.47845 -285.492273) (xy 103.507661 -285.450872) (xy 103.542861 -285.414427) (xy 103.583222 -285.383796)
			(xy 103.627794 -285.3597) (xy 103.675527 -285.342705) (xy 103.700326 -285.337504) (xy 103.723186 -285.333186)
			(xy 103.928418 -284.97784) (xy 103.920798 -284.955996) (xy 103.912174 -284.929714) (xy 103.902859 -284.875193)
			(xy 103.902256 -284.847538) (xy 103.902764 -284.821631) (xy 103.91087 -284.770454) (xy 103.926882 -284.721175)
			(xy 103.950405 -284.675008) (xy 103.980861 -284.633089) (xy 104.017499 -284.596451) (xy 104.059418 -284.565995)
			(xy 104.105585 -284.542472) (xy 104.154864 -284.52646) (xy 104.206041 -284.518354) (xy 104.257855 -284.518354)
			(xy 104.309032 -284.52646) (xy 104.358311 -284.542472) (xy 104.404478 -284.565995) (xy 104.446397 -284.596451)
			(xy 104.483035 -284.633089) (xy 104.513491 -284.675008) (xy 104.537014 -284.721175) (xy 104.553026 -284.770454)
			(xy 104.561132 -284.821631) (xy 104.56164 -284.847538) (xy 118.939056 -284.847538) (xy 118.939564 -284.821631)
			(xy 118.94767 -284.770454) (xy 118.963682 -284.721175) (xy 118.987205 -284.675008) (xy 119.017661 -284.633089)
			(xy 119.054299 -284.596451) (xy 119.096218 -284.565995) (xy 119.142385 -284.542472) (xy 119.191664 -284.52646)
			(xy 119.242841 -284.518354) (xy 119.294655 -284.518354) (xy 119.345832 -284.52646) (xy 119.395111 -284.542472)
			(xy 119.441278 -284.565995) (xy 119.483197 -284.596451) (xy 119.519835 -284.633089) (xy 119.550291 -284.675008)
			(xy 119.573814 -284.721175) (xy 119.589826 -284.770454) (xy 119.597932 -284.821631) (xy 119.59844 -284.847538)
			(xy 120.818656 -284.847538) (xy 120.819164 -284.821631) (xy 120.82727 -284.770454) (xy 120.843282 -284.721175)
			(xy 120.866805 -284.675008) (xy 120.897261 -284.633089) (xy 120.933899 -284.596451) (xy 120.975818 -284.565995)
			(xy 121.021985 -284.542472) (xy 121.071264 -284.52646) (xy 121.122441 -284.518354) (xy 121.174255 -284.518354)
			(xy 121.225432 -284.52646) (xy 121.274711 -284.542472) (xy 121.320878 -284.565995) (xy 121.362797 -284.596451)
			(xy 121.399435 -284.633089) (xy 121.429891 -284.675008) (xy 121.453414 -284.721175) (xy 121.469426 -284.770454)
			(xy 121.477532 -284.821631) (xy 121.47804 -284.847538) (xy 122.698256 -284.847538) (xy 122.698764 -284.821631)
			(xy 122.70687 -284.770454) (xy 122.722882 -284.721175) (xy 122.746405 -284.675008) (xy 122.776861 -284.633089)
			(xy 122.813499 -284.596451) (xy 122.855418 -284.565995) (xy 122.901585 -284.542472) (xy 122.950864 -284.52646)
			(xy 123.002041 -284.518354) (xy 123.053855 -284.518354) (xy 123.105032 -284.52646) (xy 123.154311 -284.542472)
			(xy 123.200478 -284.565995) (xy 123.242397 -284.596451) (xy 123.279035 -284.633089) (xy 123.309491 -284.675008)
			(xy 123.333014 -284.721175) (xy 123.349026 -284.770454) (xy 123.357132 -284.821631) (xy 123.35764 -284.847538)
			(xy 124.577856 -284.847538) (xy 124.578364 -284.821631) (xy 124.58647 -284.770454) (xy 124.602482 -284.721175)
			(xy 124.626005 -284.675008) (xy 124.656461 -284.633089) (xy 124.693099 -284.596451) (xy 124.735018 -284.565995)
			(xy 124.781185 -284.542472) (xy 124.830464 -284.52646) (xy 124.881641 -284.518354) (xy 124.933455 -284.518354)
			(xy 124.984632 -284.52646) (xy 125.033911 -284.542472) (xy 125.080078 -284.565995) (xy 125.121997 -284.596451)
			(xy 125.158635 -284.633089) (xy 125.189091 -284.675008) (xy 125.212614 -284.721175) (xy 125.228626 -284.770454)
			(xy 125.236732 -284.821631) (xy 125.23724 -284.847538) (xy 126.457456 -284.847538) (xy 126.457964 -284.821631)
			(xy 126.46607 -284.770454) (xy 126.482082 -284.721175) (xy 126.505605 -284.675008) (xy 126.536061 -284.633089)
			(xy 126.572699 -284.596451) (xy 126.614618 -284.565995) (xy 126.660785 -284.542472) (xy 126.710064 -284.52646)
			(xy 126.761241 -284.518354) (xy 126.813055 -284.518354) (xy 126.864232 -284.52646) (xy 126.913511 -284.542472)
			(xy 126.959678 -284.565995) (xy 127.001597 -284.596451) (xy 127.038235 -284.633089) (xy 127.068691 -284.675008)
			(xy 127.092214 -284.721175) (xy 127.108226 -284.770454) (xy 127.116332 -284.821631) (xy 127.11684 -284.847538)
			(xy 128.337056 -284.847538) (xy 128.337564 -284.821631) (xy 128.34567 -284.770454) (xy 128.361682 -284.721175)
			(xy 128.385205 -284.675008) (xy 128.415661 -284.633089) (xy 128.452299 -284.596451) (xy 128.494218 -284.565995)
			(xy 128.540385 -284.542472) (xy 128.589664 -284.52646) (xy 128.640841 -284.518354) (xy 128.692655 -284.518354)
			(xy 128.743832 -284.52646) (xy 128.793111 -284.542472) (xy 128.839278 -284.565995) (xy 128.881197 -284.596451)
			(xy 128.917835 -284.633089) (xy 128.948291 -284.675008) (xy 128.971814 -284.721175) (xy 128.987826 -284.770454)
			(xy 128.995932 -284.821631) (xy 128.99644 -284.847538) (xy 130.216656 -284.847538) (xy 130.217164 -284.821631)
			(xy 130.22527 -284.770454) (xy 130.241282 -284.721175) (xy 130.264805 -284.675008) (xy 130.295261 -284.633089)
			(xy 130.331899 -284.596451) (xy 130.373818 -284.565995) (xy 130.419985 -284.542472) (xy 130.469264 -284.52646)
			(xy 130.520441 -284.518354) (xy 130.572255 -284.518354) (xy 130.623432 -284.52646) (xy 130.672711 -284.542472)
			(xy 130.718878 -284.565995) (xy 130.760797 -284.596451) (xy 130.797435 -284.633089) (xy 130.827891 -284.675008)
			(xy 130.851414 -284.721175) (xy 130.867426 -284.770454) (xy 130.875532 -284.821631) (xy 130.87604 -284.847538)
			(xy 132.096256 -284.847538) (xy 132.096764 -284.821631) (xy 132.10487 -284.770454) (xy 132.120882 -284.721175)
			(xy 132.144405 -284.675008) (xy 132.174861 -284.633089) (xy 132.211499 -284.596451) (xy 132.253418 -284.565995)
			(xy 132.299585 -284.542472) (xy 132.348864 -284.52646) (xy 132.400041 -284.518354) (xy 132.451855 -284.518354)
			(xy 132.503032 -284.52646) (xy 132.552311 -284.542472) (xy 132.598478 -284.565995) (xy 132.640397 -284.596451)
			(xy 132.677035 -284.633089) (xy 132.707491 -284.675008) (xy 132.731014 -284.721175) (xy 132.747026 -284.770454)
			(xy 132.755132 -284.821631) (xy 132.755639 -284.8475) (xy 333.019739 -284.8475) (xy 333.023716 -284.794436)
			(xy 333.035556 -284.742556) (xy 333.054996 -284.693021) (xy 333.081601 -284.646936) (xy 333.114777 -284.605331)
			(xy 333.153783 -284.569134) (xy 333.197748 -284.539155) (xy 333.24569 -284.516063) (xy 333.296537 -284.500374)
			(xy 333.349155 -284.492438) (xy 333.375762 -284.491938) (xy 333.400732 -284.492387) (xy 333.450179 -284.499376)
			(xy 333.498165 -284.513208) (xy 333.543746 -284.533612) (xy 333.586027 -284.560187) (xy 333.624179 -284.592411)
			(xy 333.657451 -284.629651) (xy 333.671672 -284.65018) (xy 334.019652 -284.65018) (xy 334.033839 -284.629624)
			(xy 334.067109 -284.592373) (xy 334.105263 -284.56014) (xy 334.14755 -284.533562) (xy 334.193138 -284.513159)
			(xy 334.241133 -284.499333) (xy 334.290589 -284.492356) (xy 334.315562 -284.491938) (xy 334.34218 -284.492332)
			(xy 334.394822 -284.500261) (xy 334.445693 -284.515948) (xy 334.493659 -284.539042) (xy 334.537646 -284.569028)
			(xy 334.576673 -284.605235) (xy 334.609866 -284.646855) (xy 334.636486 -284.692958) (xy 334.655936 -284.742513)
			(xy 334.667783 -284.794413) (xy 334.671762 -284.8475) (xy 334.667783 -284.900587) (xy 334.655936 -284.952487)
			(xy 334.636486 -285.002042) (xy 334.609866 -285.048145) (xy 334.576673 -285.089765) (xy 334.537646 -285.125972)
			(xy 334.493659 -285.155958) (xy 334.445693 -285.179052) (xy 334.394822 -285.194739) (xy 334.34218 -285.202668)
			(xy 334.315562 -285.203138) (xy 334.290593 -285.202682) (xy 334.241145 -285.195695) (xy 334.193159 -285.181865)
			(xy 334.147578 -285.161463) (xy 334.105296 -285.134889) (xy 334.067145 -285.102665) (xy 334.033872 -285.065425)
			(xy 334.019652 -285.044896) (xy 333.671672 -285.044896) (xy 333.657462 -285.065435) (xy 333.624197 -285.102688)
			(xy 333.586047 -285.134922) (xy 333.543764 -285.161504) (xy 333.498179 -285.181909) (xy 333.450188 -285.195738)
			(xy 333.400734 -285.202719) (xy 333.375762 -285.203138) (xy 333.349155 -285.202562) (xy 333.296537 -285.194626)
			(xy 333.24569 -285.178937) (xy 333.197748 -285.155845) (xy 333.153783 -285.125866) (xy 333.114777 -285.089669)
			(xy 333.081601 -285.048064) (xy 333.054996 -285.001979) (xy 333.035556 -284.952444) (xy 333.023716 -284.900564)
			(xy 333.019739 -284.8475) (xy 132.755639 -284.8475) (xy 132.75564 -284.847538) (xy 132.755034 -284.875255)
			(xy 132.745719 -284.929901) (xy 132.737098 -284.95625) (xy 132.729224 -284.978348) (xy 132.934202 -285.333186)
			(xy 132.957062 -285.337504) (xy 132.981868 -285.342683) (xy 133.02961 -285.359669) (xy 133.07419 -285.383762)
			(xy 133.114558 -285.414393) (xy 133.149763 -285.450841) (xy 133.178975 -285.492247) (xy 133.201506 -285.537636)
			(xy 133.216825 -285.585939) (xy 133.224572 -285.636017) (xy 133.225032 -285.661354) (xy 133.224524 -285.687241)
			(xy 133.216425 -285.738379) (xy 133.200426 -285.787619) (xy 133.17692 -285.833751) (xy 133.146488 -285.875638)
			(xy 133.109878 -285.912248) (xy 133.067991 -285.94268) (xy 133.021859 -285.966186) (xy 132.972619 -285.982185)
			(xy 132.921481 -285.990284) (xy 132.869707 -285.990284) (xy 132.818569 -285.982185) (xy 132.769329 -285.966186)
			(xy 132.723197 -285.94268) (xy 132.68131 -285.912248) (xy 132.6447 -285.875638) (xy 132.614268 -285.833751)
			(xy 132.590762 -285.787619) (xy 132.574763 -285.738379) (xy 132.566664 -285.687241) (xy 132.566156 -285.661354)
			(xy 132.566701 -285.633647) (xy 132.575886 -285.579) (xy 132.584444 -285.552642) (xy 132.592318 -285.530544)
			(xy 132.38734 -285.175706) (xy 132.36448 -285.171388) (xy 132.33966 -285.166215) (xy 132.29188 -285.149263)
			(xy 132.247259 -285.125194) (xy 132.206851 -285.094575) (xy 132.171609 -285.058129) (xy 132.142365 -285.016715)
			(xy 132.119809 -284.971312) (xy 132.104472 -284.922989) (xy 132.096717 -284.872887) (xy 132.096256 -284.847538)
			(xy 130.87604 -284.847538) (xy 130.875434 -284.875255) (xy 130.866119 -284.929901) (xy 130.857498 -284.95625)
			(xy 130.849624 -284.978348) (xy 131.054602 -285.333186) (xy 131.077462 -285.337504) (xy 131.102268 -285.342683)
			(xy 131.15001 -285.359669) (xy 131.19459 -285.383762) (xy 131.234958 -285.414393) (xy 131.270163 -285.450841)
			(xy 131.299375 -285.492247) (xy 131.321906 -285.537636) (xy 131.337225 -285.585939) (xy 131.344972 -285.636017)
			(xy 131.345432 -285.661354) (xy 131.344924 -285.687241) (xy 131.336825 -285.738379) (xy 131.320826 -285.787619)
			(xy 131.29732 -285.833751) (xy 131.266888 -285.875638) (xy 131.230278 -285.912248) (xy 131.188391 -285.94268)
			(xy 131.142259 -285.966186) (xy 131.093019 -285.982185) (xy 131.041881 -285.990284) (xy 130.990107 -285.990284)
			(xy 130.938969 -285.982185) (xy 130.889729 -285.966186) (xy 130.843597 -285.94268) (xy 130.80171 -285.912248)
			(xy 130.7651 -285.875638) (xy 130.734668 -285.833751) (xy 130.711162 -285.787619) (xy 130.695163 -285.738379)
			(xy 130.687064 -285.687241) (xy 130.686556 -285.661354) (xy 130.687101 -285.633647) (xy 130.696286 -285.579)
			(xy 130.704844 -285.552642) (xy 130.712718 -285.530544) (xy 130.50774 -285.175706) (xy 130.48488 -285.171388)
			(xy 130.46006 -285.166215) (xy 130.41228 -285.149263) (xy 130.367659 -285.125194) (xy 130.327251 -285.094575)
			(xy 130.292009 -285.058129) (xy 130.262765 -285.016715) (xy 130.240209 -284.971312) (xy 130.224872 -284.922989)
			(xy 130.217117 -284.872887) (xy 130.216656 -284.847538) (xy 128.99644 -284.847538) (xy 128.995834 -284.875255)
			(xy 128.986519 -284.929901) (xy 128.977898 -284.95625) (xy 128.970024 -284.978348) (xy 129.175002 -285.333186)
			(xy 129.197862 -285.337504) (xy 129.222668 -285.342683) (xy 129.27041 -285.359669) (xy 129.31499 -285.383762)
			(xy 129.355358 -285.414393) (xy 129.390563 -285.450841) (xy 129.419775 -285.492247) (xy 129.442306 -285.537636)
			(xy 129.457625 -285.585939) (xy 129.465372 -285.636017) (xy 129.465832 -285.661354) (xy 129.465324 -285.687241)
			(xy 129.457225 -285.738379) (xy 129.441226 -285.787619) (xy 129.41772 -285.833751) (xy 129.387288 -285.875638)
			(xy 129.350678 -285.912248) (xy 129.308791 -285.94268) (xy 129.262659 -285.966186) (xy 129.213419 -285.982185)
			(xy 129.162281 -285.990284) (xy 129.110507 -285.990284) (xy 129.059369 -285.982185) (xy 129.010129 -285.966186)
			(xy 128.963997 -285.94268) (xy 128.92211 -285.912248) (xy 128.8855 -285.875638) (xy 128.855068 -285.833751)
			(xy 128.831562 -285.787619) (xy 128.815563 -285.738379) (xy 128.807464 -285.687241) (xy 128.806956 -285.661354)
			(xy 128.807501 -285.633647) (xy 128.816686 -285.579) (xy 128.825244 -285.552642) (xy 128.833118 -285.530544)
			(xy 128.62814 -285.175706) (xy 128.60528 -285.171388) (xy 128.58046 -285.166215) (xy 128.53268 -285.149263)
			(xy 128.488059 -285.125194) (xy 128.447651 -285.094575) (xy 128.412409 -285.058129) (xy 128.383165 -285.016715)
			(xy 128.360609 -284.971312) (xy 128.345272 -284.922989) (xy 128.337517 -284.872887) (xy 128.337056 -284.847538)
			(xy 127.11684 -284.847538) (xy 127.116234 -284.875255) (xy 127.106919 -284.929901) (xy 127.098298 -284.95625)
			(xy 127.090424 -284.978348) (xy 127.295402 -285.333186) (xy 127.318262 -285.337504) (xy 127.343068 -285.342683)
			(xy 127.39081 -285.359669) (xy 127.43539 -285.383762) (xy 127.475758 -285.414393) (xy 127.510963 -285.450841)
			(xy 127.540175 -285.492247) (xy 127.562706 -285.537636) (xy 127.578025 -285.585939) (xy 127.585772 -285.636017)
			(xy 127.586232 -285.661354) (xy 127.585724 -285.687241) (xy 127.577625 -285.738379) (xy 127.561626 -285.787619)
			(xy 127.53812 -285.833751) (xy 127.507688 -285.875638) (xy 127.471078 -285.912248) (xy 127.429191 -285.94268)
			(xy 127.383059 -285.966186) (xy 127.333819 -285.982185) (xy 127.282681 -285.990284) (xy 127.230907 -285.990284)
			(xy 127.179769 -285.982185) (xy 127.130529 -285.966186) (xy 127.084397 -285.94268) (xy 127.04251 -285.912248)
			(xy 127.0059 -285.875638) (xy 126.975468 -285.833751) (xy 126.951962 -285.787619) (xy 126.935963 -285.738379)
			(xy 126.927864 -285.687241) (xy 126.927356 -285.661354) (xy 126.927901 -285.633647) (xy 126.937086 -285.579)
			(xy 126.945644 -285.552642) (xy 126.953518 -285.530544) (xy 126.74854 -285.175706) (xy 126.72568 -285.171388)
			(xy 126.70086 -285.166215) (xy 126.65308 -285.149263) (xy 126.608459 -285.125194) (xy 126.568051 -285.094575)
			(xy 126.532809 -285.058129) (xy 126.503565 -285.016715) (xy 126.481009 -284.971312) (xy 126.465672 -284.922989)
			(xy 126.457917 -284.872887) (xy 126.457456 -284.847538) (xy 125.23724 -284.847538) (xy 125.236634 -284.875255)
			(xy 125.227319 -284.929901) (xy 125.218698 -284.95625) (xy 125.210824 -284.978348) (xy 125.415802 -285.333186)
			(xy 125.438662 -285.337504) (xy 125.463468 -285.342683) (xy 125.51121 -285.359669) (xy 125.55579 -285.383762)
			(xy 125.596158 -285.414393) (xy 125.631363 -285.450841) (xy 125.660575 -285.492247) (xy 125.683106 -285.537636)
			(xy 125.698425 -285.585939) (xy 125.706172 -285.636017) (xy 125.706632 -285.661354) (xy 125.706124 -285.687241)
			(xy 125.698025 -285.738379) (xy 125.682026 -285.787619) (xy 125.65852 -285.833751) (xy 125.628088 -285.875638)
			(xy 125.591478 -285.912248) (xy 125.549591 -285.94268) (xy 125.503459 -285.966186) (xy 125.454219 -285.982185)
			(xy 125.403081 -285.990284) (xy 125.351307 -285.990284) (xy 125.300169 -285.982185) (xy 125.250929 -285.966186)
			(xy 125.204797 -285.94268) (xy 125.16291 -285.912248) (xy 125.1263 -285.875638) (xy 125.095868 -285.833751)
			(xy 125.072362 -285.787619) (xy 125.056363 -285.738379) (xy 125.048264 -285.687241) (xy 125.047756 -285.661354)
			(xy 125.048301 -285.633647) (xy 125.057486 -285.579) (xy 125.066044 -285.552642) (xy 125.073918 -285.530544)
			(xy 124.86894 -285.175706) (xy 124.84608 -285.171388) (xy 124.82126 -285.166215) (xy 124.77348 -285.149263)
			(xy 124.728859 -285.125194) (xy 124.688451 -285.094575) (xy 124.653209 -285.058129) (xy 124.623965 -285.016715)
			(xy 124.601409 -284.971312) (xy 124.586072 -284.922989) (xy 124.578317 -284.872887) (xy 124.577856 -284.847538)
			(xy 123.35764 -284.847538) (xy 123.357034 -284.875255) (xy 123.347719 -284.929901) (xy 123.339098 -284.95625)
			(xy 123.331224 -284.978348) (xy 123.536202 -285.333186) (xy 123.559062 -285.337504) (xy 123.583868 -285.342683)
			(xy 123.63161 -285.359669) (xy 123.67619 -285.383762) (xy 123.716558 -285.414393) (xy 123.751763 -285.450841)
			(xy 123.780975 -285.492247) (xy 123.803506 -285.537636) (xy 123.818825 -285.585939) (xy 123.826572 -285.636017)
			(xy 123.827032 -285.661354) (xy 123.826524 -285.687241) (xy 123.818425 -285.738379) (xy 123.802426 -285.787619)
			(xy 123.77892 -285.833751) (xy 123.748488 -285.875638) (xy 123.711878 -285.912248) (xy 123.669991 -285.94268)
			(xy 123.623859 -285.966186) (xy 123.574619 -285.982185) (xy 123.523481 -285.990284) (xy 123.471707 -285.990284)
			(xy 123.420569 -285.982185) (xy 123.371329 -285.966186) (xy 123.325197 -285.94268) (xy 123.28331 -285.912248)
			(xy 123.2467 -285.875638) (xy 123.216268 -285.833751) (xy 123.192762 -285.787619) (xy 123.176763 -285.738379)
			(xy 123.168664 -285.687241) (xy 123.168156 -285.661354) (xy 123.168701 -285.633647) (xy 123.177886 -285.579)
			(xy 123.186444 -285.552642) (xy 123.194318 -285.530544) (xy 122.98934 -285.175706) (xy 122.96648 -285.171388)
			(xy 122.94166 -285.166215) (xy 122.89388 -285.149263) (xy 122.849259 -285.125194) (xy 122.808851 -285.094575)
			(xy 122.773609 -285.058129) (xy 122.744365 -285.016715) (xy 122.721809 -284.971312) (xy 122.706472 -284.922989)
			(xy 122.698717 -284.872887) (xy 122.698256 -284.847538) (xy 121.47804 -284.847538) (xy 121.477434 -284.875255)
			(xy 121.468119 -284.929901) (xy 121.459498 -284.95625) (xy 121.451624 -284.978348) (xy 121.656602 -285.333186)
			(xy 121.679462 -285.337504) (xy 121.704268 -285.342683) (xy 121.75201 -285.359669) (xy 121.79659 -285.383762)
			(xy 121.836958 -285.414393) (xy 121.872163 -285.450841) (xy 121.901375 -285.492247) (xy 121.923906 -285.537636)
			(xy 121.939225 -285.585939) (xy 121.946972 -285.636017) (xy 121.947432 -285.661354) (xy 121.946924 -285.687241)
			(xy 121.938825 -285.738379) (xy 121.922826 -285.787619) (xy 121.89932 -285.833751) (xy 121.868888 -285.875638)
			(xy 121.832278 -285.912248) (xy 121.790391 -285.94268) (xy 121.744259 -285.966186) (xy 121.695019 -285.982185)
			(xy 121.643881 -285.990284) (xy 121.592107 -285.990284) (xy 121.540969 -285.982185) (xy 121.491729 -285.966186)
			(xy 121.445597 -285.94268) (xy 121.40371 -285.912248) (xy 121.3671 -285.875638) (xy 121.336668 -285.833751)
			(xy 121.313162 -285.787619) (xy 121.297163 -285.738379) (xy 121.289064 -285.687241) (xy 121.288556 -285.661354)
			(xy 121.289101 -285.633647) (xy 121.298286 -285.579) (xy 121.306844 -285.552642) (xy 121.314718 -285.530544)
			(xy 121.10974 -285.175706) (xy 121.08688 -285.171388) (xy 121.06206 -285.166215) (xy 121.01428 -285.149263)
			(xy 120.969659 -285.125194) (xy 120.929251 -285.094575) (xy 120.894009 -285.058129) (xy 120.864765 -285.016715)
			(xy 120.842209 -284.971312) (xy 120.826872 -284.922989) (xy 120.819117 -284.872887) (xy 120.818656 -284.847538)
			(xy 119.59844 -284.847538) (xy 119.597834 -284.875255) (xy 119.588519 -284.929901) (xy 119.579898 -284.95625)
			(xy 119.572024 -284.978348) (xy 119.777002 -285.333186) (xy 119.799862 -285.337504) (xy 119.824668 -285.342683)
			(xy 119.87241 -285.359669) (xy 119.91699 -285.383762) (xy 119.957358 -285.414393) (xy 119.992563 -285.450841)
			(xy 120.021775 -285.492247) (xy 120.044306 -285.537636) (xy 120.059625 -285.585939) (xy 120.067372 -285.636017)
			(xy 120.067832 -285.661354) (xy 120.067324 -285.687241) (xy 120.059225 -285.738379) (xy 120.043226 -285.787619)
			(xy 120.01972 -285.833751) (xy 119.989288 -285.875638) (xy 119.952678 -285.912248) (xy 119.910791 -285.94268)
			(xy 119.864659 -285.966186) (xy 119.815419 -285.982185) (xy 119.764281 -285.990284) (xy 119.712507 -285.990284)
			(xy 119.661369 -285.982185) (xy 119.612129 -285.966186) (xy 119.565997 -285.94268) (xy 119.52411 -285.912248)
			(xy 119.4875 -285.875638) (xy 119.457068 -285.833751) (xy 119.433562 -285.787619) (xy 119.417563 -285.738379)
			(xy 119.409464 -285.687241) (xy 119.408956 -285.661354) (xy 119.409501 -285.633647) (xy 119.418686 -285.579)
			(xy 119.427244 -285.552642) (xy 119.435118 -285.530544) (xy 119.23014 -285.175706) (xy 119.20728 -285.171388)
			(xy 119.18246 -285.166215) (xy 119.13468 -285.149263) (xy 119.090059 -285.125194) (xy 119.049651 -285.094575)
			(xy 119.014409 -285.058129) (xy 118.985165 -285.016715) (xy 118.962609 -284.971312) (xy 118.947272 -284.922989)
			(xy 118.939517 -284.872887) (xy 118.939056 -284.847538) (xy 104.56164 -284.847538) (xy 104.561248 -284.872916)
			(xy 104.553473 -284.923072) (xy 104.538096 -284.971442) (xy 104.515481 -285.016882) (xy 104.486165 -285.058314)
			(xy 104.45084 -285.09476) (xy 104.410343 -285.125356) (xy 104.365633 -285.149379) (xy 104.317766 -285.166259)
			(xy 104.292908 -285.171388) (xy 104.270048 -285.175706) (xy 104.06507 -285.530544) (xy 104.072944 -285.552642)
			(xy 104.081516 -285.578997) (xy 104.090707 -285.633645) (xy 104.091232 -285.661354) (xy 104.090724 -285.687241)
			(xy 104.082625 -285.738379) (xy 104.066626 -285.787619) (xy 104.04312 -285.833751) (xy 104.012688 -285.875638)
			(xy 103.976078 -285.912248) (xy 103.934191 -285.94268) (xy 103.888059 -285.966186) (xy 103.838819 -285.982185)
			(xy 103.787681 -285.990284) (xy 103.735907 -285.990284) (xy 103.684769 -285.982185) (xy 103.635529 -285.966186)
			(xy 103.589397 -285.94268) (xy 103.54751 -285.912248) (xy 103.5109 -285.875638) (xy 103.480468 -285.833751)
			(xy 103.456962 -285.787619) (xy 103.440963 -285.738379) (xy 103.432864 -285.687241) (xy 103.432356 -285.661354)
			(xy 103.151432 -285.661354) (xy 103.151432 -285.661862) (xy 103.150853 -285.689379) (xy 103.141659 -285.74364)
			(xy 103.133144 -285.769812) (xy 103.125524 -285.79191) (xy 103.330756 -286.147256) (xy 103.353616 -286.151574)
			(xy 103.378427 -286.156786) (xy 103.426204 -286.173734) (xy 103.470823 -286.197799) (xy 103.51123 -286.228413)
			(xy 103.546472 -286.264855) (xy 103.575717 -286.306263) (xy 103.598276 -286.351662) (xy 103.613617 -286.399979)
			(xy 103.621377 -286.450077) (xy 103.62184 -286.475424) (xy 119.878856 -286.475424) (xy 119.879354 -286.450079)
			(xy 119.887123 -286.399987) (xy 119.902468 -286.351675) (xy 119.925026 -286.306281) (xy 119.954266 -286.264873)
			(xy 119.989499 -286.228429) (xy 120.029894 -286.197807) (xy 120.0745 -286.173728) (xy 120.122266 -286.156759)
			(xy 120.14708 -286.151574) (xy 120.16994 -286.147256) (xy 120.374918 -285.792164) (xy 120.367044 -285.77032)
			(xy 120.358471 -285.743899) (xy 120.34927 -285.689126) (xy 120.348756 -285.661354) (xy 120.349264 -285.635467)
			(xy 120.357363 -285.584329) (xy 120.373362 -285.535089) (xy 120.396868 -285.488957) (xy 120.4273 -285.44707)
			(xy 120.46391 -285.41046) (xy 120.505797 -285.380028) (xy 120.551929 -285.356522) (xy 120.601169 -285.340523)
			(xy 120.652307 -285.332424) (xy 120.704081 -285.332424) (xy 120.755219 -285.340523) (xy 120.804459 -285.356522)
			(xy 120.850591 -285.380028) (xy 120.892478 -285.41046) (xy 120.929088 -285.44707) (xy 120.95952 -285.488957)
			(xy 120.983026 -285.535089) (xy 120.999025 -285.584329) (xy 121.007124 -285.635467) (xy 121.007632 -285.661354)
			(xy 121.007172 -285.686689) (xy 120.999413 -285.736761) (xy 120.984085 -285.785057) (xy 120.961549 -285.830439)
			(xy 120.932336 -285.87184) (xy 120.897134 -285.908285) (xy 120.856771 -285.938915) (xy 120.812197 -285.963011)
			(xy 120.764462 -285.980004) (xy 120.739662 -285.985204) (xy 120.716802 -285.989522) (xy 120.511824 -286.344614)
			(xy 120.519698 -286.366458) (xy 120.528349 -286.392865) (xy 120.537666 -286.447642) (xy 120.53824 -286.475424)
			(xy 121.758456 -286.475424) (xy 121.758954 -286.450079) (xy 121.766723 -286.399987) (xy 121.782068 -286.351675)
			(xy 121.804626 -286.306281) (xy 121.833866 -286.264873) (xy 121.869099 -286.228429) (xy 121.909494 -286.197807)
			(xy 121.9541 -286.173728) (xy 122.001866 -286.156759) (xy 122.02668 -286.151574) (xy 122.04954 -286.147256)
			(xy 122.254518 -285.792164) (xy 122.246644 -285.77032) (xy 122.238071 -285.743899) (xy 122.22887 -285.689126)
			(xy 122.228356 -285.661354) (xy 122.228864 -285.635467) (xy 122.236963 -285.584329) (xy 122.252962 -285.535089)
			(xy 122.276468 -285.488957) (xy 122.3069 -285.44707) (xy 122.34351 -285.41046) (xy 122.385397 -285.380028)
			(xy 122.431529 -285.356522) (xy 122.480769 -285.340523) (xy 122.531907 -285.332424) (xy 122.583681 -285.332424)
			(xy 122.634819 -285.340523) (xy 122.684059 -285.356522) (xy 122.730191 -285.380028) (xy 122.772078 -285.41046)
			(xy 122.808688 -285.44707) (xy 122.83912 -285.488957) (xy 122.862626 -285.535089) (xy 122.878625 -285.584329)
			(xy 122.886724 -285.635467) (xy 122.887232 -285.661354) (xy 122.886772 -285.686689) (xy 122.879013 -285.736761)
			(xy 122.863685 -285.785057) (xy 122.841149 -285.830439) (xy 122.811936 -285.87184) (xy 122.776734 -285.908285)
			(xy 122.736371 -285.938915) (xy 122.691797 -285.963011) (xy 122.644062 -285.980004) (xy 122.619262 -285.985204)
			(xy 122.596402 -285.989522) (xy 122.391424 -286.344614) (xy 122.399298 -286.366458) (xy 122.407949 -286.392865)
			(xy 122.417266 -286.447642) (xy 122.41784 -286.475424) (xy 123.638056 -286.475424) (xy 123.638554 -286.450079)
			(xy 123.646323 -286.399987) (xy 123.661668 -286.351675) (xy 123.684226 -286.306281) (xy 123.713466 -286.264873)
			(xy 123.748699 -286.228429) (xy 123.789094 -286.197807) (xy 123.8337 -286.173728) (xy 123.881466 -286.156759)
			(xy 123.90628 -286.151574) (xy 123.92914 -286.147256) (xy 124.134118 -285.792164) (xy 124.126244 -285.77032)
			(xy 124.117671 -285.743899) (xy 124.10847 -285.689126) (xy 124.107956 -285.661354) (xy 124.108464 -285.635467)
			(xy 124.116563 -285.584329) (xy 124.132562 -285.535089) (xy 124.156068 -285.488957) (xy 124.1865 -285.44707)
			(xy 124.22311 -285.41046) (xy 124.264997 -285.380028) (xy 124.311129 -285.356522) (xy 124.360369 -285.340523)
			(xy 124.411507 -285.332424) (xy 124.463281 -285.332424) (xy 124.514419 -285.340523) (xy 124.563659 -285.356522)
			(xy 124.609791 -285.380028) (xy 124.651678 -285.41046) (xy 124.688288 -285.44707) (xy 124.71872 -285.488957)
			(xy 124.742226 -285.535089) (xy 124.758225 -285.584329) (xy 124.766324 -285.635467) (xy 124.766832 -285.661354)
			(xy 124.766372 -285.686689) (xy 124.758613 -285.736761) (xy 124.743285 -285.785057) (xy 124.720749 -285.830439)
			(xy 124.691536 -285.87184) (xy 124.656334 -285.908285) (xy 124.615971 -285.938915) (xy 124.571397 -285.963011)
			(xy 124.523662 -285.980004) (xy 124.498862 -285.985204) (xy 124.476002 -285.989522) (xy 124.271024 -286.344614)
			(xy 124.278898 -286.366458) (xy 124.287549 -286.392865) (xy 124.296866 -286.447642) (xy 124.29744 -286.475424)
			(xy 125.517656 -286.475424) (xy 125.518154 -286.450079) (xy 125.525923 -286.399987) (xy 125.541268 -286.351675)
			(xy 125.563826 -286.306281) (xy 125.593066 -286.264873) (xy 125.628299 -286.228429) (xy 125.668694 -286.197807)
			(xy 125.7133 -286.173728) (xy 125.761066 -286.156759) (xy 125.78588 -286.151574) (xy 125.80874 -286.147256)
			(xy 126.013718 -285.792164) (xy 126.005844 -285.77032) (xy 125.997271 -285.743899) (xy 125.98807 -285.689126)
			(xy 125.987556 -285.661354) (xy 125.988064 -285.635467) (xy 125.996163 -285.584329) (xy 126.012162 -285.535089)
			(xy 126.035668 -285.488957) (xy 126.0661 -285.44707) (xy 126.10271 -285.41046) (xy 126.144597 -285.380028)
			(xy 126.190729 -285.356522) (xy 126.239969 -285.340523) (xy 126.291107 -285.332424) (xy 126.342881 -285.332424)
			(xy 126.394019 -285.340523) (xy 126.443259 -285.356522) (xy 126.489391 -285.380028) (xy 126.531278 -285.41046)
			(xy 126.567888 -285.44707) (xy 126.59832 -285.488957) (xy 126.621826 -285.535089) (xy 126.637825 -285.584329)
			(xy 126.645924 -285.635467) (xy 126.646432 -285.661354) (xy 126.645972 -285.686689) (xy 126.638213 -285.736761)
			(xy 126.622885 -285.785057) (xy 126.600349 -285.830439) (xy 126.571136 -285.87184) (xy 126.535934 -285.908285)
			(xy 126.495571 -285.938915) (xy 126.450997 -285.963011) (xy 126.403262 -285.980004) (xy 126.378462 -285.985204)
			(xy 126.355602 -285.989522) (xy 126.150624 -286.344614) (xy 126.158498 -286.366458) (xy 126.167149 -286.392865)
			(xy 126.176466 -286.447642) (xy 126.17704 -286.475424) (xy 127.397256 -286.475424) (xy 127.397754 -286.450079)
			(xy 127.405523 -286.399987) (xy 127.420868 -286.351675) (xy 127.443426 -286.306281) (xy 127.472666 -286.264873)
			(xy 127.507899 -286.228429) (xy 127.548294 -286.197807) (xy 127.5929 -286.173728) (xy 127.640666 -286.156759)
			(xy 127.66548 -286.151574) (xy 127.68834 -286.147256) (xy 127.893318 -285.792164) (xy 127.885444 -285.77032)
			(xy 127.876871 -285.743899) (xy 127.86767 -285.689126) (xy 127.867156 -285.661354) (xy 127.867664 -285.635467)
			(xy 127.875763 -285.584329) (xy 127.891762 -285.535089) (xy 127.915268 -285.488957) (xy 127.9457 -285.44707)
			(xy 127.98231 -285.41046) (xy 128.024197 -285.380028) (xy 128.070329 -285.356522) (xy 128.119569 -285.340523)
			(xy 128.170707 -285.332424) (xy 128.222481 -285.332424) (xy 128.273619 -285.340523) (xy 128.322859 -285.356522)
			(xy 128.368991 -285.380028) (xy 128.410878 -285.41046) (xy 128.447488 -285.44707) (xy 128.47792 -285.488957)
			(xy 128.501426 -285.535089) (xy 128.517425 -285.584329) (xy 128.525524 -285.635467) (xy 128.526032 -285.661354)
			(xy 128.525572 -285.686689) (xy 128.517813 -285.736761) (xy 128.502485 -285.785057) (xy 128.479949 -285.830439)
			(xy 128.450736 -285.87184) (xy 128.415534 -285.908285) (xy 128.375171 -285.938915) (xy 128.330597 -285.963011)
			(xy 128.282862 -285.980004) (xy 128.258062 -285.985204) (xy 128.235202 -285.989522) (xy 128.030224 -286.344614)
			(xy 128.038098 -286.366458) (xy 128.046749 -286.392865) (xy 128.056066 -286.447642) (xy 128.05664 -286.475424)
			(xy 129.276856 -286.475424) (xy 129.277354 -286.450079) (xy 129.285123 -286.399987) (xy 129.300468 -286.351675)
			(xy 129.323026 -286.306281) (xy 129.352266 -286.264873) (xy 129.387499 -286.228429) (xy 129.427894 -286.197807)
			(xy 129.4725 -286.173728) (xy 129.520266 -286.156759) (xy 129.54508 -286.151574) (xy 129.56794 -286.147256)
			(xy 129.772918 -285.792164) (xy 129.765044 -285.77032) (xy 129.756471 -285.743899) (xy 129.74727 -285.689126)
			(xy 129.746756 -285.661354) (xy 129.747264 -285.635467) (xy 129.755363 -285.584329) (xy 129.771362 -285.535089)
			(xy 129.794868 -285.488957) (xy 129.8253 -285.44707) (xy 129.86191 -285.41046) (xy 129.903797 -285.380028)
			(xy 129.949929 -285.356522) (xy 129.999169 -285.340523) (xy 130.050307 -285.332424) (xy 130.102081 -285.332424)
			(xy 130.153219 -285.340523) (xy 130.202459 -285.356522) (xy 130.248591 -285.380028) (xy 130.290478 -285.41046)
			(xy 130.327088 -285.44707) (xy 130.35752 -285.488957) (xy 130.381026 -285.535089) (xy 130.397025 -285.584329)
			(xy 130.405124 -285.635467) (xy 130.405632 -285.661354) (xy 130.405172 -285.686689) (xy 130.397413 -285.736761)
			(xy 130.382085 -285.785057) (xy 130.359549 -285.830439) (xy 130.330336 -285.87184) (xy 130.295134 -285.908285)
			(xy 130.254771 -285.938915) (xy 130.210197 -285.963011) (xy 130.162462 -285.980004) (xy 130.137662 -285.985204)
			(xy 130.114802 -285.989522) (xy 129.909824 -286.344614) (xy 129.917698 -286.366458) (xy 129.926349 -286.392865)
			(xy 129.935666 -286.447642) (xy 129.93624 -286.475424) (xy 131.156456 -286.475424) (xy 131.156954 -286.450079)
			(xy 131.164723 -286.399987) (xy 131.180068 -286.351675) (xy 131.202626 -286.306281) (xy 131.231866 -286.264873)
			(xy 131.267099 -286.228429) (xy 131.307494 -286.197807) (xy 131.3521 -286.173728) (xy 131.399866 -286.156759)
			(xy 131.42468 -286.151574) (xy 131.44754 -286.147256) (xy 131.652518 -285.792164) (xy 131.644644 -285.77032)
			(xy 131.636071 -285.743899) (xy 131.62687 -285.689126) (xy 131.626356 -285.661354) (xy 131.626864 -285.635467)
			(xy 131.634963 -285.584329) (xy 131.650962 -285.535089) (xy 131.674468 -285.488957) (xy 131.7049 -285.44707)
			(xy 131.74151 -285.41046) (xy 131.783397 -285.380028) (xy 131.829529 -285.356522) (xy 131.878769 -285.340523)
			(xy 131.929907 -285.332424) (xy 131.981681 -285.332424) (xy 132.032819 -285.340523) (xy 132.082059 -285.356522)
			(xy 132.128191 -285.380028) (xy 132.170078 -285.41046) (xy 132.206688 -285.44707) (xy 132.23712 -285.488957)
			(xy 132.260626 -285.535089) (xy 132.276625 -285.584329) (xy 132.284724 -285.635467) (xy 132.285232 -285.661354)
			(xy 132.284772 -285.686689) (xy 132.277013 -285.736761) (xy 132.261685 -285.785057) (xy 132.239149 -285.830439)
			(xy 132.209936 -285.87184) (xy 132.174734 -285.908285) (xy 132.134371 -285.938915) (xy 132.089797 -285.963011)
			(xy 132.042062 -285.980004) (xy 132.017262 -285.985204) (xy 131.994402 -285.989522) (xy 131.789424 -286.344614)
			(xy 131.797298 -286.366458) (xy 131.805949 -286.392865) (xy 131.815266 -286.447642) (xy 131.81584 -286.475424)
			(xy 133.036056 -286.475424) (xy 133.036554 -286.450079) (xy 133.044323 -286.399987) (xy 133.059668 -286.351675)
			(xy 133.082226 -286.306281) (xy 133.111466 -286.264873) (xy 133.146699 -286.228429) (xy 133.187094 -286.197807)
			(xy 133.2317 -286.173728) (xy 133.279466 -286.156759) (xy 133.30428 -286.151574) (xy 133.32714 -286.147256)
			(xy 133.532118 -285.792164) (xy 133.524244 -285.77032) (xy 133.515671 -285.743899) (xy 133.50647 -285.689126)
			(xy 133.505956 -285.661354) (xy 133.506464 -285.635467) (xy 133.514563 -285.584329) (xy 133.530562 -285.535089)
			(xy 133.554068 -285.488957) (xy 133.5845 -285.44707) (xy 133.62111 -285.41046) (xy 133.662997 -285.380028)
			(xy 133.709129 -285.356522) (xy 133.758369 -285.340523) (xy 133.809507 -285.332424) (xy 133.861281 -285.332424)
			(xy 133.912419 -285.340523) (xy 133.961659 -285.356522) (xy 134.007791 -285.380028) (xy 134.049678 -285.41046)
			(xy 134.086288 -285.44707) (xy 134.11672 -285.488957) (xy 134.140226 -285.535089) (xy 134.156225 -285.584329)
			(xy 134.164324 -285.635467) (xy 134.164832 -285.661354) (xy 335.368646 -285.661354) (xy 335.36912 -285.635686)
			(xy 335.376461 -285.584879) (xy 335.391012 -285.53565) (xy 335.412475 -285.489017) (xy 335.440403 -285.445945)
			(xy 335.474221 -285.407323) (xy 335.513228 -285.373951) (xy 335.556618 -285.346519) (xy 335.603494 -285.325594)
			(xy 335.652887 -285.311608) (xy 335.678272 -285.307786) (xy 335.703164 -285.304484) (xy 335.875122 -285.006796)
			(xy 335.86547 -284.983682) (xy 335.856977 -284.962086) (xy 335.844995 -284.917255) (xy 335.838936 -284.871248)
			(xy 335.838546 -284.848046) (xy 335.838546 -284.847538) (xy 335.839045 -284.820851) (xy 335.847 -284.768072)
			(xy 335.862732 -284.717069) (xy 335.88589 -284.66898) (xy 335.915957 -284.62488) (xy 335.952261 -284.585753)
			(xy 335.993991 -284.552475) (xy 336.040215 -284.525788) (xy 336.0899 -284.506288) (xy 336.141937 -284.494411)
			(xy 336.195162 -284.490422) (xy 336.248387 -284.494411) (xy 336.300424 -284.506288) (xy 336.350109 -284.525788)
			(xy 336.396333 -284.552475) (xy 336.438063 -284.585753) (xy 336.474367 -284.62488) (xy 336.504434 -284.66898)
			(xy 336.527592 -284.717069) (xy 336.543324 -284.768072) (xy 336.551279 -284.820851) (xy 336.551778 -284.847538)
			(xy 336.551276 -284.873204) (xy 336.543937 -284.924009) (xy 336.529387 -284.973236) (xy 336.507928 -285.019868)
			(xy 336.480003 -285.06294) (xy 336.446188 -285.101561) (xy 336.407185 -285.134934) (xy 336.363798 -285.162367)
			(xy 336.316925 -285.183294) (xy 336.267536 -285.197283) (xy 336.242152 -285.201106) (xy 336.21726 -285.204408)
			(xy 336.045302 -285.502096) (xy 336.054954 -285.52521) (xy 336.063445 -285.546806) (xy 336.075428 -285.591637)
			(xy 336.081488 -285.637644) (xy 336.081878 -285.660846) (xy 336.081878 -285.661354) (xy 337.275424 -285.661354)
			(xy 337.275932 -285.635467) (xy 337.284031 -285.584329) (xy 337.30003 -285.535089) (xy 337.323536 -285.488957)
			(xy 337.353968 -285.44707) (xy 337.390578 -285.41046) (xy 337.432465 -285.380028) (xy 337.478597 -285.356522)
			(xy 337.527837 -285.340523) (xy 337.578975 -285.332424) (xy 337.630749 -285.332424) (xy 337.681887 -285.340523)
			(xy 337.731127 -285.356522) (xy 337.777259 -285.380028) (xy 337.819146 -285.41046) (xy 337.855756 -285.44707)
			(xy 337.886188 -285.488957) (xy 337.909694 -285.535089) (xy 337.925693 -285.584329) (xy 337.933792 -285.635467)
			(xy 337.9343 -285.661354) (xy 338.215224 -285.661354) (xy 338.215684 -285.636008) (xy 338.223463 -285.585916)
			(xy 338.238816 -285.537605) (xy 338.26138 -285.492212) (xy 338.290625 -285.450806) (xy 338.325861 -285.414363)
			(xy 338.366259 -285.383741) (xy 338.410867 -285.359661) (xy 338.458634 -285.34269) (xy 338.483448 -285.337504)
			(xy 338.506308 -285.333186) (xy 338.711286 -284.978348) (xy 338.703412 -284.956504) (xy 338.694834 -284.930085)
			(xy 338.685636 -284.87531) (xy 338.685124 -284.847538) (xy 338.685632 -284.821651) (xy 338.693731 -284.770513)
			(xy 338.70973 -284.721273) (xy 338.733236 -284.675141) (xy 338.763668 -284.633254) (xy 338.800278 -284.596644)
			(xy 338.842165 -284.566212) (xy 338.888297 -284.542706) (xy 338.937537 -284.526707) (xy 338.988675 -284.518608)
			(xy 339.040449 -284.518608) (xy 339.091587 -284.526707) (xy 339.140827 -284.542706) (xy 339.186959 -284.566212)
			(xy 339.228846 -284.596644) (xy 339.265456 -284.633254) (xy 339.295888 -284.675141) (xy 339.319394 -284.721273)
			(xy 339.335393 -284.770513) (xy 339.343492 -284.821651) (xy 339.344 -284.847538) (xy 339.343552 -284.872874)
			(xy 339.335794 -284.922948) (xy 339.320466 -284.971245) (xy 339.29793 -285.016629) (xy 339.268716 -285.058031)
			(xy 339.233511 -285.094476) (xy 339.193146 -285.125106) (xy 339.148569 -285.149199) (xy 339.100831 -285.16619)
			(xy 339.07603 -285.171388) (xy 339.05317 -285.175706) (xy 338.848192 -285.530544) (xy 338.856066 -285.552642)
			(xy 338.86469 -285.578991) (xy 338.874015 -285.633637) (xy 338.874608 -285.661354) (xy 339.155024 -285.661354)
			(xy 339.155532 -285.635447) (xy 339.163638 -285.58427) (xy 339.17965 -285.534991) (xy 339.203173 -285.488824)
			(xy 339.233629 -285.446905) (xy 339.270267 -285.410267) (xy 339.312186 -285.379811) (xy 339.358353 -285.356288)
			(xy 339.407632 -285.340276) (xy 339.458809 -285.33217) (xy 339.510623 -285.33217) (xy 339.5618 -285.340276)
			(xy 339.611079 -285.356288) (xy 339.657246 -285.379811) (xy 339.699165 -285.410267) (xy 339.735803 -285.446905)
			(xy 339.766259 -285.488824) (xy 339.789782 -285.534991) (xy 339.805794 -285.58427) (xy 339.8139 -285.635447)
			(xy 339.814408 -285.661354) (xy 340.094824 -285.661354) (xy 340.095245 -285.636017) (xy 340.103005 -285.585941)
			(xy 340.118335 -285.537642) (xy 340.140875 -285.492257) (xy 340.170092 -285.450854) (xy 340.2053 -285.41441)
			(xy 340.24567 -285.383781) (xy 340.29025 -285.359689) (xy 340.337992 -285.342701) (xy 340.362794 -285.337504)
			(xy 340.385654 -285.333186) (xy 340.590886 -284.97784) (xy 340.583266 -284.955996) (xy 340.574644 -284.929713)
			(xy 340.565327 -284.875193) (xy 340.564724 -284.847538) (xy 340.565232 -284.821631) (xy 340.573338 -284.770454)
			(xy 340.58935 -284.721175) (xy 340.612873 -284.675008) (xy 340.643329 -284.633089) (xy 340.679967 -284.596451)
			(xy 340.721886 -284.565995) (xy 340.768053 -284.542472) (xy 340.817332 -284.52646) (xy 340.868509 -284.518354)
			(xy 340.920323 -284.518354) (xy 340.9715 -284.52646) (xy 341.020779 -284.542472) (xy 341.066946 -284.565995)
			(xy 341.108865 -284.596451) (xy 341.145503 -284.633089) (xy 341.175959 -284.675008) (xy 341.199482 -284.721175)
			(xy 341.215494 -284.770454) (xy 341.2236 -284.821631) (xy 341.224108 -284.847538) (xy 341.223661 -284.872913)
			(xy 341.215887 -284.923064) (xy 341.200514 -284.97143) (xy 341.177905 -285.016866) (xy 341.148596 -285.058297)
			(xy 341.113279 -285.094742) (xy 341.072791 -285.125341) (xy 341.028089 -285.149367) (xy 340.980231 -285.166254)
			(xy 340.955376 -285.171388) (xy 340.932516 -285.175706) (xy 340.727538 -285.530544) (xy 340.735412 -285.552642)
			(xy 340.743983 -285.578997) (xy 340.753175 -285.633645) (xy 340.7537 -285.661354) (xy 341.034624 -285.661354)
			(xy 341.035132 -285.635467) (xy 341.043231 -285.584329) (xy 341.05923 -285.535089) (xy 341.082736 -285.488957)
			(xy 341.113168 -285.44707) (xy 341.149778 -285.41046) (xy 341.191665 -285.380028) (xy 341.237797 -285.356522)
			(xy 341.287037 -285.340523) (xy 341.338175 -285.332424) (xy 341.389949 -285.332424) (xy 341.441087 -285.340523)
			(xy 341.490327 -285.356522) (xy 341.536459 -285.380028) (xy 341.578346 -285.41046) (xy 341.614956 -285.44707)
			(xy 341.645388 -285.488957) (xy 341.668894 -285.535089) (xy 341.684893 -285.584329) (xy 341.692992 -285.635467)
			(xy 341.6935 -285.661354) (xy 341.974424 -285.661354) (xy 341.974845 -285.636017) (xy 341.982605 -285.585941)
			(xy 341.997935 -285.537642) (xy 342.020475 -285.492257) (xy 342.049692 -285.450854) (xy 342.0849 -285.41441)
			(xy 342.12527 -285.383781) (xy 342.16985 -285.359689) (xy 342.217592 -285.342701) (xy 342.242394 -285.337504)
			(xy 342.265254 -285.333186) (xy 342.470486 -284.97784) (xy 342.462866 -284.955996) (xy 342.454244 -284.929713)
			(xy 342.444927 -284.875193) (xy 342.444324 -284.847538) (xy 342.444832 -284.821631) (xy 342.452938 -284.770454)
			(xy 342.46895 -284.721175) (xy 342.492473 -284.675008) (xy 342.522929 -284.633089) (xy 342.559567 -284.596451)
			(xy 342.601486 -284.565995) (xy 342.647653 -284.542472) (xy 342.696932 -284.52646) (xy 342.748109 -284.518354)
			(xy 342.799923 -284.518354) (xy 342.8511 -284.52646) (xy 342.900379 -284.542472) (xy 342.946546 -284.565995)
			(xy 342.988465 -284.596451) (xy 343.025103 -284.633089) (xy 343.055559 -284.675008) (xy 343.079082 -284.721175)
			(xy 343.095094 -284.770454) (xy 343.1032 -284.821631) (xy 343.103708 -284.847538) (xy 343.103261 -284.872913)
			(xy 343.095487 -284.923064) (xy 343.080114 -284.97143) (xy 343.057505 -285.016866) (xy 343.028196 -285.058297)
			(xy 342.992879 -285.094742) (xy 342.952391 -285.125341) (xy 342.907689 -285.149367) (xy 342.859831 -285.166254)
			(xy 342.834976 -285.171388) (xy 342.812116 -285.175706) (xy 342.607138 -285.530544) (xy 342.615012 -285.552642)
			(xy 342.623583 -285.578997) (xy 342.632775 -285.633645) (xy 342.6333 -285.661354) (xy 342.914224 -285.661354)
			(xy 342.914732 -285.635467) (xy 342.922831 -285.584329) (xy 342.93883 -285.535089) (xy 342.962336 -285.488957)
			(xy 342.992768 -285.44707) (xy 343.029378 -285.41046) (xy 343.071265 -285.380028) (xy 343.117397 -285.356522)
			(xy 343.166637 -285.340523) (xy 343.217775 -285.332424) (xy 343.269549 -285.332424) (xy 343.320687 -285.340523)
			(xy 343.369927 -285.356522) (xy 343.416059 -285.380028) (xy 343.457946 -285.41046) (xy 343.494556 -285.44707)
			(xy 343.524988 -285.488957) (xy 343.548494 -285.535089) (xy 343.564493 -285.584329) (xy 343.572592 -285.635467)
			(xy 343.5731 -285.661354) (xy 343.854024 -285.661354) (xy 343.854445 -285.636017) (xy 343.862205 -285.585941)
			(xy 343.877535 -285.537642) (xy 343.900075 -285.492257) (xy 343.929292 -285.450854) (xy 343.9645 -285.41441)
			(xy 344.00487 -285.383781) (xy 344.04945 -285.359689) (xy 344.097192 -285.342701) (xy 344.121994 -285.337504)
			(xy 344.144854 -285.333186) (xy 344.350086 -284.97784) (xy 344.342466 -284.955996) (xy 344.333844 -284.929713)
			(xy 344.324527 -284.875193) (xy 344.323924 -284.847538) (xy 344.324432 -284.821631) (xy 344.332538 -284.770454)
			(xy 344.34855 -284.721175) (xy 344.372073 -284.675008) (xy 344.402529 -284.633089) (xy 344.439167 -284.596451)
			(xy 344.481086 -284.565995) (xy 344.527253 -284.542472) (xy 344.576532 -284.52646) (xy 344.627709 -284.518354)
			(xy 344.679523 -284.518354) (xy 344.7307 -284.52646) (xy 344.779979 -284.542472) (xy 344.826146 -284.565995)
			(xy 344.868065 -284.596451) (xy 344.904703 -284.633089) (xy 344.935159 -284.675008) (xy 344.958682 -284.721175)
			(xy 344.974694 -284.770454) (xy 344.9828 -284.821631) (xy 344.983308 -284.847538) (xy 344.982861 -284.872913)
			(xy 344.975087 -284.923064) (xy 344.959714 -284.97143) (xy 344.937105 -285.016866) (xy 344.907796 -285.058297)
			(xy 344.872479 -285.094742) (xy 344.831991 -285.125341) (xy 344.787289 -285.149367) (xy 344.739431 -285.166254)
			(xy 344.714576 -285.171388) (xy 344.691716 -285.175706) (xy 344.486738 -285.530544) (xy 344.494612 -285.552642)
			(xy 344.503183 -285.578997) (xy 344.512375 -285.633645) (xy 344.5129 -285.661354) (xy 344.793824 -285.661354)
			(xy 344.794332 -285.635467) (xy 344.802431 -285.584329) (xy 344.81843 -285.535089) (xy 344.841936 -285.488957)
			(xy 344.872368 -285.44707) (xy 344.908978 -285.41046) (xy 344.950865 -285.380028) (xy 344.996997 -285.356522)
			(xy 345.046237 -285.340523) (xy 345.097375 -285.332424) (xy 345.149149 -285.332424) (xy 345.200287 -285.340523)
			(xy 345.249527 -285.356522) (xy 345.295659 -285.380028) (xy 345.337546 -285.41046) (xy 345.374156 -285.44707)
			(xy 345.404588 -285.488957) (xy 345.428094 -285.535089) (xy 345.444093 -285.584329) (xy 345.452192 -285.635467)
			(xy 345.4527 -285.661354) (xy 345.733624 -285.661354) (xy 345.734045 -285.636017) (xy 345.741805 -285.585941)
			(xy 345.757135 -285.537642) (xy 345.779675 -285.492257) (xy 345.808892 -285.450854) (xy 345.8441 -285.41441)
			(xy 345.88447 -285.383781) (xy 345.92905 -285.359689) (xy 345.976792 -285.342701) (xy 346.001594 -285.337504)
			(xy 346.024454 -285.333186) (xy 346.229686 -284.97784) (xy 346.222066 -284.955996) (xy 346.213444 -284.929713)
			(xy 346.204127 -284.875193) (xy 346.203524 -284.847538) (xy 346.204032 -284.821631) (xy 346.212138 -284.770454)
			(xy 346.22815 -284.721175) (xy 346.251673 -284.675008) (xy 346.282129 -284.633089) (xy 346.318767 -284.596451)
			(xy 346.360686 -284.565995) (xy 346.406853 -284.542472) (xy 346.456132 -284.52646) (xy 346.507309 -284.518354)
			(xy 346.559123 -284.518354) (xy 346.6103 -284.52646) (xy 346.659579 -284.542472) (xy 346.705746 -284.565995)
			(xy 346.747665 -284.596451) (xy 346.784303 -284.633089) (xy 346.814759 -284.675008) (xy 346.838282 -284.721175)
			(xy 346.854294 -284.770454) (xy 346.8624 -284.821631) (xy 346.862908 -284.847538) (xy 346.862461 -284.872913)
			(xy 346.854687 -284.923064) (xy 346.839314 -284.97143) (xy 346.816705 -285.016866) (xy 346.787396 -285.058297)
			(xy 346.752079 -285.094742) (xy 346.711591 -285.125341) (xy 346.666889 -285.149367) (xy 346.619031 -285.166254)
			(xy 346.594176 -285.171388) (xy 346.571316 -285.175706) (xy 346.366338 -285.530544) (xy 346.374212 -285.552642)
			(xy 346.382783 -285.578997) (xy 346.391975 -285.633645) (xy 346.3925 -285.661354) (xy 346.673424 -285.661354)
			(xy 346.673932 -285.635467) (xy 346.682031 -285.584329) (xy 346.69803 -285.535089) (xy 346.721536 -285.488957)
			(xy 346.751968 -285.44707) (xy 346.788578 -285.41046) (xy 346.830465 -285.380028) (xy 346.876597 -285.356522)
			(xy 346.925837 -285.340523) (xy 346.976975 -285.332424) (xy 347.028749 -285.332424) (xy 347.079887 -285.340523)
			(xy 347.129127 -285.356522) (xy 347.175259 -285.380028) (xy 347.217146 -285.41046) (xy 347.253756 -285.44707)
			(xy 347.284188 -285.488957) (xy 347.307694 -285.535089) (xy 347.323693 -285.584329) (xy 347.331792 -285.635467)
			(xy 347.3323 -285.661354) (xy 347.613224 -285.661354) (xy 347.613645 -285.636017) (xy 347.621405 -285.585941)
			(xy 347.636735 -285.537642) (xy 347.659275 -285.492257) (xy 347.688492 -285.450854) (xy 347.7237 -285.41441)
			(xy 347.76407 -285.383781) (xy 347.80865 -285.359689) (xy 347.856392 -285.342701) (xy 347.881194 -285.337504)
			(xy 347.904054 -285.333186) (xy 348.109286 -284.97784) (xy 348.101666 -284.955996) (xy 348.093044 -284.929713)
			(xy 348.083727 -284.875193) (xy 348.083124 -284.847538) (xy 348.083632 -284.821631) (xy 348.091738 -284.770454)
			(xy 348.10775 -284.721175) (xy 348.131273 -284.675008) (xy 348.161729 -284.633089) (xy 348.198367 -284.596451)
			(xy 348.240286 -284.565995) (xy 348.286453 -284.542472) (xy 348.335732 -284.52646) (xy 348.386909 -284.518354)
			(xy 348.438723 -284.518354) (xy 348.4899 -284.52646) (xy 348.539179 -284.542472) (xy 348.585346 -284.565995)
			(xy 348.627265 -284.596451) (xy 348.663903 -284.633089) (xy 348.694359 -284.675008) (xy 348.717882 -284.721175)
			(xy 348.733894 -284.770454) (xy 348.742 -284.821631) (xy 348.742508 -284.847538) (xy 348.742061 -284.872913)
			(xy 348.734287 -284.923064) (xy 348.718914 -284.97143) (xy 348.696305 -285.016866) (xy 348.666996 -285.058297)
			(xy 348.631679 -285.094742) (xy 348.591191 -285.125341) (xy 348.546489 -285.149367) (xy 348.498631 -285.166254)
			(xy 348.473776 -285.171388) (xy 348.450916 -285.175706) (xy 348.245938 -285.530544) (xy 348.253812 -285.552642)
			(xy 348.262383 -285.578997) (xy 348.271575 -285.633645) (xy 348.2721 -285.661354) (xy 348.553024 -285.661354)
			(xy 348.553532 -285.635467) (xy 348.561631 -285.584329) (xy 348.57763 -285.535089) (xy 348.601136 -285.488957)
			(xy 348.631568 -285.44707) (xy 348.668178 -285.41046) (xy 348.710065 -285.380028) (xy 348.756197 -285.356522)
			(xy 348.805437 -285.340523) (xy 348.856575 -285.332424) (xy 348.908349 -285.332424) (xy 348.959487 -285.340523)
			(xy 349.008727 -285.356522) (xy 349.054859 -285.380028) (xy 349.096746 -285.41046) (xy 349.133356 -285.44707)
			(xy 349.163788 -285.488957) (xy 349.187294 -285.535089) (xy 349.203293 -285.584329) (xy 349.211392 -285.635467)
			(xy 349.2119 -285.661354) (xy 349.492824 -285.661354) (xy 349.493245 -285.636017) (xy 349.501005 -285.585941)
			(xy 349.516335 -285.537642) (xy 349.538875 -285.492257) (xy 349.568092 -285.450854) (xy 349.6033 -285.41441)
			(xy 349.64367 -285.383781) (xy 349.68825 -285.359689) (xy 349.735992 -285.342701) (xy 349.760794 -285.337504)
			(xy 349.783654 -285.333186) (xy 349.988886 -284.97784) (xy 349.981266 -284.955996) (xy 349.972644 -284.929713)
			(xy 349.963327 -284.875193) (xy 349.962724 -284.847538) (xy 349.963232 -284.821631) (xy 349.971338 -284.770454)
			(xy 349.98735 -284.721175) (xy 350.010873 -284.675008) (xy 350.041329 -284.633089) (xy 350.077967 -284.596451)
			(xy 350.119886 -284.565995) (xy 350.166053 -284.542472) (xy 350.215332 -284.52646) (xy 350.266509 -284.518354)
			(xy 350.318323 -284.518354) (xy 350.3695 -284.52646) (xy 350.418779 -284.542472) (xy 350.464946 -284.565995)
			(xy 350.506865 -284.596451) (xy 350.543503 -284.633089) (xy 350.573959 -284.675008) (xy 350.597482 -284.721175)
			(xy 350.613494 -284.770454) (xy 350.6216 -284.821631) (xy 350.622108 -284.847538) (xy 350.621661 -284.872913)
			(xy 350.613887 -284.923064) (xy 350.598514 -284.97143) (xy 350.575905 -285.016866) (xy 350.546596 -285.058297)
			(xy 350.511279 -285.094742) (xy 350.470791 -285.125341) (xy 350.426089 -285.149367) (xy 350.378231 -285.166254)
			(xy 350.353376 -285.171388) (xy 350.330516 -285.175706) (xy 350.125538 -285.530544) (xy 350.133412 -285.552642)
			(xy 350.141983 -285.578997) (xy 350.151175 -285.633645) (xy 350.1517 -285.661354) (xy 350.432624 -285.661354)
			(xy 350.433132 -285.635467) (xy 350.441231 -285.584329) (xy 350.45723 -285.535089) (xy 350.480736 -285.488957)
			(xy 350.511168 -285.44707) (xy 350.547778 -285.41046) (xy 350.589665 -285.380028) (xy 350.635797 -285.356522)
			(xy 350.685037 -285.340523) (xy 350.736175 -285.332424) (xy 350.787949 -285.332424) (xy 350.839087 -285.340523)
			(xy 350.888327 -285.356522) (xy 350.934459 -285.380028) (xy 350.976346 -285.41046) (xy 351.012956 -285.44707)
			(xy 351.043388 -285.488957) (xy 351.066894 -285.535089) (xy 351.082893 -285.584329) (xy 351.090992 -285.635467)
			(xy 351.0915 -285.661354) (xy 351.372424 -285.661354) (xy 351.372845 -285.636017) (xy 351.380605 -285.585941)
			(xy 351.395935 -285.537642) (xy 351.418475 -285.492257) (xy 351.447692 -285.450854) (xy 351.4829 -285.41441)
			(xy 351.52327 -285.383781) (xy 351.56785 -285.359689) (xy 351.615592 -285.342701) (xy 351.640394 -285.337504)
			(xy 351.663254 -285.333186) (xy 351.868486 -284.97784) (xy 351.860866 -284.955996) (xy 351.852244 -284.929713)
			(xy 351.842927 -284.875193) (xy 351.842324 -284.847538) (xy 351.842832 -284.821631) (xy 351.850938 -284.770454)
			(xy 351.86695 -284.721175) (xy 351.890473 -284.675008) (xy 351.920929 -284.633089) (xy 351.957567 -284.596451)
			(xy 351.999486 -284.565995) (xy 352.045653 -284.542472) (xy 352.094932 -284.52646) (xy 352.146109 -284.518354)
			(xy 352.197923 -284.518354) (xy 352.2491 -284.52646) (xy 352.298379 -284.542472) (xy 352.344546 -284.565995)
			(xy 352.386465 -284.596451) (xy 352.423103 -284.633089) (xy 352.453559 -284.675008) (xy 352.477082 -284.721175)
			(xy 352.493094 -284.770454) (xy 352.5012 -284.821631) (xy 352.501708 -284.847538) (xy 366.879124 -284.847538)
			(xy 366.879632 -284.821631) (xy 366.887738 -284.770454) (xy 366.90375 -284.721175) (xy 366.927273 -284.675008)
			(xy 366.957729 -284.633089) (xy 366.994367 -284.596451) (xy 367.036286 -284.565995) (xy 367.082453 -284.542472)
			(xy 367.131732 -284.52646) (xy 367.182909 -284.518354) (xy 367.234723 -284.518354) (xy 367.2859 -284.52646)
			(xy 367.335179 -284.542472) (xy 367.381346 -284.565995) (xy 367.423265 -284.596451) (xy 367.459903 -284.633089)
			(xy 367.490359 -284.675008) (xy 367.513882 -284.721175) (xy 367.529894 -284.770454) (xy 367.538 -284.821631)
			(xy 367.538508 -284.847538) (xy 368.758724 -284.847538) (xy 368.759232 -284.821631) (xy 368.767338 -284.770454)
			(xy 368.78335 -284.721175) (xy 368.806873 -284.675008) (xy 368.837329 -284.633089) (xy 368.873967 -284.596451)
			(xy 368.915886 -284.565995) (xy 368.962053 -284.542472) (xy 369.011332 -284.52646) (xy 369.062509 -284.518354)
			(xy 369.114323 -284.518354) (xy 369.1655 -284.52646) (xy 369.214779 -284.542472) (xy 369.260946 -284.565995)
			(xy 369.302865 -284.596451) (xy 369.339503 -284.633089) (xy 369.369959 -284.675008) (xy 369.393482 -284.721175)
			(xy 369.409494 -284.770454) (xy 369.4176 -284.821631) (xy 369.418108 -284.847538) (xy 370.638324 -284.847538)
			(xy 370.638832 -284.821631) (xy 370.646938 -284.770454) (xy 370.66295 -284.721175) (xy 370.686473 -284.675008)
			(xy 370.716929 -284.633089) (xy 370.753567 -284.596451) (xy 370.795486 -284.565995) (xy 370.841653 -284.542472)
			(xy 370.890932 -284.52646) (xy 370.942109 -284.518354) (xy 370.993923 -284.518354) (xy 371.0451 -284.52646)
			(xy 371.094379 -284.542472) (xy 371.140546 -284.565995) (xy 371.182465 -284.596451) (xy 371.219103 -284.633089)
			(xy 371.249559 -284.675008) (xy 371.273082 -284.721175) (xy 371.289094 -284.770454) (xy 371.2972 -284.821631)
			(xy 371.297708 -284.847538) (xy 372.517924 -284.847538) (xy 372.518432 -284.821631) (xy 372.526538 -284.770454)
			(xy 372.54255 -284.721175) (xy 372.566073 -284.675008) (xy 372.596529 -284.633089) (xy 372.633167 -284.596451)
			(xy 372.675086 -284.565995) (xy 372.721253 -284.542472) (xy 372.770532 -284.52646) (xy 372.821709 -284.518354)
			(xy 372.873523 -284.518354) (xy 372.9247 -284.52646) (xy 372.973979 -284.542472) (xy 373.020146 -284.565995)
			(xy 373.062065 -284.596451) (xy 373.098703 -284.633089) (xy 373.129159 -284.675008) (xy 373.152682 -284.721175)
			(xy 373.168694 -284.770454) (xy 373.1768 -284.821631) (xy 373.177308 -284.847538) (xy 374.397524 -284.847538)
			(xy 374.398032 -284.821631) (xy 374.406138 -284.770454) (xy 374.42215 -284.721175) (xy 374.445673 -284.675008)
			(xy 374.476129 -284.633089) (xy 374.512767 -284.596451) (xy 374.554686 -284.565995) (xy 374.600853 -284.542472)
			(xy 374.650132 -284.52646) (xy 374.701309 -284.518354) (xy 374.753123 -284.518354) (xy 374.8043 -284.52646)
			(xy 374.853579 -284.542472) (xy 374.899746 -284.565995) (xy 374.941665 -284.596451) (xy 374.978303 -284.633089)
			(xy 375.008759 -284.675008) (xy 375.032282 -284.721175) (xy 375.048294 -284.770454) (xy 375.0564 -284.821631)
			(xy 375.056908 -284.847538) (xy 376.277124 -284.847538) (xy 376.277632 -284.821631) (xy 376.285738 -284.770454)
			(xy 376.30175 -284.721175) (xy 376.325273 -284.675008) (xy 376.355729 -284.633089) (xy 376.392367 -284.596451)
			(xy 376.434286 -284.565995) (xy 376.480453 -284.542472) (xy 376.529732 -284.52646) (xy 376.580909 -284.518354)
			(xy 376.632723 -284.518354) (xy 376.6839 -284.52646) (xy 376.733179 -284.542472) (xy 376.779346 -284.565995)
			(xy 376.821265 -284.596451) (xy 376.857903 -284.633089) (xy 376.888359 -284.675008) (xy 376.911882 -284.721175)
			(xy 376.927894 -284.770454) (xy 376.936 -284.821631) (xy 376.936508 -284.847538) (xy 378.156724 -284.847538)
			(xy 378.157232 -284.821631) (xy 378.165338 -284.770454) (xy 378.18135 -284.721175) (xy 378.204873 -284.675008)
			(xy 378.235329 -284.633089) (xy 378.271967 -284.596451) (xy 378.313886 -284.565995) (xy 378.360053 -284.542472)
			(xy 378.409332 -284.52646) (xy 378.460509 -284.518354) (xy 378.512323 -284.518354) (xy 378.5635 -284.52646)
			(xy 378.612779 -284.542472) (xy 378.658946 -284.565995) (xy 378.700865 -284.596451) (xy 378.737503 -284.633089)
			(xy 378.767959 -284.675008) (xy 378.791482 -284.721175) (xy 378.807494 -284.770454) (xy 378.8156 -284.821631)
			(xy 378.816108 -284.847538) (xy 380.036324 -284.847538) (xy 380.036832 -284.821631) (xy 380.044938 -284.770454)
			(xy 380.06095 -284.721175) (xy 380.084473 -284.675008) (xy 380.114929 -284.633089) (xy 380.151567 -284.596451)
			(xy 380.193486 -284.565995) (xy 380.239653 -284.542472) (xy 380.288932 -284.52646) (xy 380.340109 -284.518354)
			(xy 380.391923 -284.518354) (xy 380.4431 -284.52646) (xy 380.492379 -284.542472) (xy 380.538546 -284.565995)
			(xy 380.580465 -284.596451) (xy 380.617103 -284.633089) (xy 380.647559 -284.675008) (xy 380.671082 -284.721175)
			(xy 380.687094 -284.770454) (xy 380.6952 -284.821631) (xy 380.695708 -284.847538) (xy 380.695098 -284.875255)
			(xy 380.685785 -284.929901) (xy 380.677166 -284.95625) (xy 380.669292 -284.978348) (xy 380.87427 -285.333186)
			(xy 380.89713 -285.337504) (xy 380.921947 -285.342634) (xy 380.969689 -285.35963) (xy 381.014267 -285.383731)
			(xy 381.054634 -285.414369) (xy 381.089836 -285.450823) (xy 381.119046 -285.492235) (xy 381.141576 -285.537628)
			(xy 381.156894 -285.585934) (xy 381.16464 -285.636016) (xy 381.1651 -285.661354) (xy 381.164592 -285.687241)
			(xy 381.156493 -285.738379) (xy 381.140494 -285.787619) (xy 381.116988 -285.833751) (xy 381.086556 -285.875638)
			(xy 381.049946 -285.912248) (xy 381.008059 -285.94268) (xy 380.961927 -285.966186) (xy 380.912687 -285.982185)
			(xy 380.861549 -285.990284) (xy 380.809775 -285.990284) (xy 380.758637 -285.982185) (xy 380.709397 -285.966186)
			(xy 380.663265 -285.94268) (xy 380.621378 -285.912248) (xy 380.584768 -285.875638) (xy 380.554336 -285.833751)
			(xy 380.53083 -285.787619) (xy 380.514831 -285.738379) (xy 380.506732 -285.687241) (xy 380.506224 -285.661354)
			(xy 380.506766 -285.633646) (xy 380.515953 -285.579) (xy 380.524512 -285.552642) (xy 380.532386 -285.530544)
			(xy 380.327408 -285.175706) (xy 380.304548 -285.171388) (xy 380.279723 -285.166238) (xy 380.231943 -285.149282)
			(xy 380.187323 -285.125209) (xy 380.146916 -285.094586) (xy 380.111675 -285.058137) (xy 380.082431 -285.016721)
			(xy 380.059876 -284.971315) (xy 380.044539 -284.922991) (xy 380.036785 -284.872888) (xy 380.036324 -284.847538)
			(xy 378.816108 -284.847538) (xy 378.815498 -284.875255) (xy 378.806185 -284.929901) (xy 378.797566 -284.95625)
			(xy 378.789692 -284.978348) (xy 378.99467 -285.333186) (xy 379.01753 -285.337504) (xy 379.042347 -285.342634)
			(xy 379.090089 -285.35963) (xy 379.134667 -285.383731) (xy 379.175034 -285.414369) (xy 379.210236 -285.450823)
			(xy 379.239446 -285.492235) (xy 379.261976 -285.537628) (xy 379.277294 -285.585934) (xy 379.28504 -285.636016)
			(xy 379.2855 -285.661354) (xy 379.284992 -285.687241) (xy 379.276893 -285.738379) (xy 379.260894 -285.787619)
			(xy 379.237388 -285.833751) (xy 379.206956 -285.875638) (xy 379.170346 -285.912248) (xy 379.128459 -285.94268)
			(xy 379.082327 -285.966186) (xy 379.033087 -285.982185) (xy 378.981949 -285.990284) (xy 378.930175 -285.990284)
			(xy 378.879037 -285.982185) (xy 378.829797 -285.966186) (xy 378.783665 -285.94268) (xy 378.741778 -285.912248)
			(xy 378.705168 -285.875638) (xy 378.674736 -285.833751) (xy 378.65123 -285.787619) (xy 378.635231 -285.738379)
			(xy 378.627132 -285.687241) (xy 378.626624 -285.661354) (xy 378.627166 -285.633646) (xy 378.636353 -285.579)
			(xy 378.644912 -285.552642) (xy 378.652786 -285.530544) (xy 378.447808 -285.175706) (xy 378.424948 -285.171388)
			(xy 378.400123 -285.166238) (xy 378.352343 -285.149282) (xy 378.307723 -285.125209) (xy 378.267316 -285.094586)
			(xy 378.232075 -285.058137) (xy 378.202831 -285.016721) (xy 378.180276 -284.971315) (xy 378.164939 -284.922991)
			(xy 378.157185 -284.872888) (xy 378.156724 -284.847538) (xy 376.936508 -284.847538) (xy 376.935898 -284.875255)
			(xy 376.926585 -284.929901) (xy 376.917966 -284.95625) (xy 376.910092 -284.978348) (xy 377.11507 -285.333186)
			(xy 377.13793 -285.337504) (xy 377.162747 -285.342634) (xy 377.210489 -285.35963) (xy 377.255067 -285.383731)
			(xy 377.295434 -285.414369) (xy 377.330636 -285.450823) (xy 377.359846 -285.492235) (xy 377.382376 -285.537628)
			(xy 377.397694 -285.585934) (xy 377.40544 -285.636016) (xy 377.4059 -285.661354) (xy 377.405392 -285.687241)
			(xy 377.397293 -285.738379) (xy 377.381294 -285.787619) (xy 377.357788 -285.833751) (xy 377.327356 -285.875638)
			(xy 377.290746 -285.912248) (xy 377.248859 -285.94268) (xy 377.202727 -285.966186) (xy 377.153487 -285.982185)
			(xy 377.102349 -285.990284) (xy 377.050575 -285.990284) (xy 376.999437 -285.982185) (xy 376.950197 -285.966186)
			(xy 376.904065 -285.94268) (xy 376.862178 -285.912248) (xy 376.825568 -285.875638) (xy 376.795136 -285.833751)
			(xy 376.77163 -285.787619) (xy 376.755631 -285.738379) (xy 376.747532 -285.687241) (xy 376.747024 -285.661354)
			(xy 376.747566 -285.633646) (xy 376.756753 -285.579) (xy 376.765312 -285.552642) (xy 376.773186 -285.530544)
			(xy 376.568208 -285.175706) (xy 376.545348 -285.171388) (xy 376.520523 -285.166238) (xy 376.472743 -285.149282)
			(xy 376.428123 -285.125209) (xy 376.387716 -285.094586) (xy 376.352475 -285.058137) (xy 376.323231 -285.016721)
			(xy 376.300676 -284.971315) (xy 376.285339 -284.922991) (xy 376.277585 -284.872888) (xy 376.277124 -284.847538)
			(xy 375.056908 -284.847538) (xy 375.056298 -284.875255) (xy 375.046985 -284.929901) (xy 375.038366 -284.95625)
			(xy 375.030492 -284.978348) (xy 375.23547 -285.333186) (xy 375.25833 -285.337504) (xy 375.283147 -285.342634)
			(xy 375.330889 -285.35963) (xy 375.375467 -285.383731) (xy 375.415834 -285.414369) (xy 375.451036 -285.450823)
			(xy 375.480246 -285.492235) (xy 375.502776 -285.537628) (xy 375.518094 -285.585934) (xy 375.52584 -285.636016)
			(xy 375.5263 -285.661354) (xy 375.525792 -285.687241) (xy 375.517693 -285.738379) (xy 375.501694 -285.787619)
			(xy 375.478188 -285.833751) (xy 375.447756 -285.875638) (xy 375.411146 -285.912248) (xy 375.369259 -285.94268)
			(xy 375.323127 -285.966186) (xy 375.273887 -285.982185) (xy 375.222749 -285.990284) (xy 375.170975 -285.990284)
			(xy 375.119837 -285.982185) (xy 375.070597 -285.966186) (xy 375.024465 -285.94268) (xy 374.982578 -285.912248)
			(xy 374.945968 -285.875638) (xy 374.915536 -285.833751) (xy 374.89203 -285.787619) (xy 374.876031 -285.738379)
			(xy 374.867932 -285.687241) (xy 374.867424 -285.661354) (xy 374.867966 -285.633646) (xy 374.877153 -285.579)
			(xy 374.885712 -285.552642) (xy 374.893586 -285.530544) (xy 374.688608 -285.175706) (xy 374.665748 -285.171388)
			(xy 374.640923 -285.166238) (xy 374.593143 -285.149282) (xy 374.548523 -285.125209) (xy 374.508116 -285.094586)
			(xy 374.472875 -285.058137) (xy 374.443631 -285.016721) (xy 374.421076 -284.971315) (xy 374.405739 -284.922991)
			(xy 374.397985 -284.872888) (xy 374.397524 -284.847538) (xy 373.177308 -284.847538) (xy 373.176698 -284.875255)
			(xy 373.167385 -284.929901) (xy 373.158766 -284.95625) (xy 373.150892 -284.978348) (xy 373.35587 -285.333186)
			(xy 373.37873 -285.337504) (xy 373.403547 -285.342634) (xy 373.451289 -285.35963) (xy 373.495867 -285.383731)
			(xy 373.536234 -285.414369) (xy 373.571436 -285.450823) (xy 373.600646 -285.492235) (xy 373.623176 -285.537628)
			(xy 373.638494 -285.585934) (xy 373.64624 -285.636016) (xy 373.6467 -285.661354) (xy 373.646192 -285.687241)
			(xy 373.638093 -285.738379) (xy 373.622094 -285.787619) (xy 373.598588 -285.833751) (xy 373.568156 -285.875638)
			(xy 373.531546 -285.912248) (xy 373.489659 -285.94268) (xy 373.443527 -285.966186) (xy 373.394287 -285.982185)
			(xy 373.343149 -285.990284) (xy 373.291375 -285.990284) (xy 373.240237 -285.982185) (xy 373.190997 -285.966186)
			(xy 373.144865 -285.94268) (xy 373.102978 -285.912248) (xy 373.066368 -285.875638) (xy 373.035936 -285.833751)
			(xy 373.01243 -285.787619) (xy 372.996431 -285.738379) (xy 372.988332 -285.687241) (xy 372.987824 -285.661354)
			(xy 372.988366 -285.633646) (xy 372.997553 -285.579) (xy 373.006112 -285.552642) (xy 373.013986 -285.530544)
			(xy 372.809008 -285.175706) (xy 372.786148 -285.171388) (xy 372.761323 -285.166238) (xy 372.713543 -285.149282)
			(xy 372.668923 -285.125209) (xy 372.628516 -285.094586) (xy 372.593275 -285.058137) (xy 372.564031 -285.016721)
			(xy 372.541476 -284.971315) (xy 372.526139 -284.922991) (xy 372.518385 -284.872888) (xy 372.517924 -284.847538)
			(xy 371.297708 -284.847538) (xy 371.297098 -284.875255) (xy 371.287785 -284.929901) (xy 371.279166 -284.95625)
			(xy 371.271292 -284.978348) (xy 371.47627 -285.333186) (xy 371.49913 -285.337504) (xy 371.523947 -285.342634)
			(xy 371.571689 -285.35963) (xy 371.616267 -285.383731) (xy 371.656634 -285.414369) (xy 371.691836 -285.450823)
			(xy 371.721046 -285.492235) (xy 371.743576 -285.537628) (xy 371.758894 -285.585934) (xy 371.76664 -285.636016)
			(xy 371.7671 -285.661354) (xy 371.766592 -285.687241) (xy 371.758493 -285.738379) (xy 371.742494 -285.787619)
			(xy 371.718988 -285.833751) (xy 371.688556 -285.875638) (xy 371.651946 -285.912248) (xy 371.610059 -285.94268)
			(xy 371.563927 -285.966186) (xy 371.514687 -285.982185) (xy 371.463549 -285.990284) (xy 371.411775 -285.990284)
			(xy 371.360637 -285.982185) (xy 371.311397 -285.966186) (xy 371.265265 -285.94268) (xy 371.223378 -285.912248)
			(xy 371.186768 -285.875638) (xy 371.156336 -285.833751) (xy 371.13283 -285.787619) (xy 371.116831 -285.738379)
			(xy 371.108732 -285.687241) (xy 371.108224 -285.661354) (xy 371.108766 -285.633646) (xy 371.117953 -285.579)
			(xy 371.126512 -285.552642) (xy 371.134386 -285.530544) (xy 370.929408 -285.175706) (xy 370.906548 -285.171388)
			(xy 370.881723 -285.166238) (xy 370.833943 -285.149282) (xy 370.789323 -285.125209) (xy 370.748916 -285.094586)
			(xy 370.713675 -285.058137) (xy 370.684431 -285.016721) (xy 370.661876 -284.971315) (xy 370.646539 -284.922991)
			(xy 370.638785 -284.872888) (xy 370.638324 -284.847538) (xy 369.418108 -284.847538) (xy 369.417498 -284.875255)
			(xy 369.408185 -284.929901) (xy 369.399566 -284.95625) (xy 369.391692 -284.978348) (xy 369.59667 -285.333186)
			(xy 369.61953 -285.337504) (xy 369.644347 -285.342634) (xy 369.692089 -285.35963) (xy 369.736667 -285.383731)
			(xy 369.777034 -285.414369) (xy 369.812236 -285.450823) (xy 369.841446 -285.492235) (xy 369.863976 -285.537628)
			(xy 369.879294 -285.585934) (xy 369.88704 -285.636016) (xy 369.8875 -285.661354) (xy 369.886992 -285.687241)
			(xy 369.878893 -285.738379) (xy 369.862894 -285.787619) (xy 369.839388 -285.833751) (xy 369.808956 -285.875638)
			(xy 369.772346 -285.912248) (xy 369.730459 -285.94268) (xy 369.684327 -285.966186) (xy 369.635087 -285.982185)
			(xy 369.583949 -285.990284) (xy 369.532175 -285.990284) (xy 369.481037 -285.982185) (xy 369.431797 -285.966186)
			(xy 369.385665 -285.94268) (xy 369.343778 -285.912248) (xy 369.307168 -285.875638) (xy 369.276736 -285.833751)
			(xy 369.25323 -285.787619) (xy 369.237231 -285.738379) (xy 369.229132 -285.687241) (xy 369.228624 -285.661354)
			(xy 369.229166 -285.633646) (xy 369.238353 -285.579) (xy 369.246912 -285.552642) (xy 369.254786 -285.530544)
			(xy 369.049808 -285.175706) (xy 369.026948 -285.171388) (xy 369.002123 -285.166238) (xy 368.954343 -285.149282)
			(xy 368.909723 -285.125209) (xy 368.869316 -285.094586) (xy 368.834075 -285.058137) (xy 368.804831 -285.016721)
			(xy 368.782276 -284.971315) (xy 368.766939 -284.922991) (xy 368.759185 -284.872888) (xy 368.758724 -284.847538)
			(xy 367.538508 -284.847538) (xy 367.537898 -284.875255) (xy 367.528585 -284.929901) (xy 367.519966 -284.95625)
			(xy 367.512092 -284.978348) (xy 367.71707 -285.333186) (xy 367.73993 -285.337504) (xy 367.764747 -285.342634)
			(xy 367.812489 -285.35963) (xy 367.857067 -285.383731) (xy 367.897434 -285.414369) (xy 367.932636 -285.450823)
			(xy 367.961846 -285.492235) (xy 367.984376 -285.537628) (xy 367.999694 -285.585934) (xy 368.00744 -285.636016)
			(xy 368.0079 -285.661354) (xy 368.007392 -285.687241) (xy 367.999293 -285.738379) (xy 367.983294 -285.787619)
			(xy 367.959788 -285.833751) (xy 367.929356 -285.875638) (xy 367.892746 -285.912248) (xy 367.850859 -285.94268)
			(xy 367.804727 -285.966186) (xy 367.755487 -285.982185) (xy 367.704349 -285.990284) (xy 367.652575 -285.990284)
			(xy 367.601437 -285.982185) (xy 367.552197 -285.966186) (xy 367.506065 -285.94268) (xy 367.464178 -285.912248)
			(xy 367.427568 -285.875638) (xy 367.397136 -285.833751) (xy 367.37363 -285.787619) (xy 367.357631 -285.738379)
			(xy 367.349532 -285.687241) (xy 367.349024 -285.661354) (xy 367.349566 -285.633646) (xy 367.358753 -285.579)
			(xy 367.367312 -285.552642) (xy 367.375186 -285.530544) (xy 367.170208 -285.175706) (xy 367.147348 -285.171388)
			(xy 367.122523 -285.166238) (xy 367.074743 -285.149282) (xy 367.030123 -285.125209) (xy 366.989716 -285.094586)
			(xy 366.954475 -285.058137) (xy 366.925231 -285.016721) (xy 366.902676 -284.971315) (xy 366.887339 -284.922991)
			(xy 366.879585 -284.872888) (xy 366.879124 -284.847538) (xy 352.501708 -284.847538) (xy 352.501261 -284.872913)
			(xy 352.493487 -284.923064) (xy 352.478114 -284.97143) (xy 352.455505 -285.016866) (xy 352.426196 -285.058297)
			(xy 352.390879 -285.094742) (xy 352.350391 -285.125341) (xy 352.305689 -285.149367) (xy 352.257831 -285.166254)
			(xy 352.232976 -285.171388) (xy 352.210116 -285.175706) (xy 352.005138 -285.530544) (xy 352.013012 -285.552642)
			(xy 352.021583 -285.578997) (xy 352.030775 -285.633645) (xy 352.0313 -285.661354) (xy 352.030792 -285.687241)
			(xy 352.022693 -285.738379) (xy 352.006694 -285.787619) (xy 351.983188 -285.833751) (xy 351.952756 -285.875638)
			(xy 351.916146 -285.912248) (xy 351.874259 -285.94268) (xy 351.828127 -285.966186) (xy 351.778887 -285.982185)
			(xy 351.727749 -285.990284) (xy 351.675975 -285.990284) (xy 351.624837 -285.982185) (xy 351.575597 -285.966186)
			(xy 351.529465 -285.94268) (xy 351.487578 -285.912248) (xy 351.450968 -285.875638) (xy 351.420536 -285.833751)
			(xy 351.39703 -285.787619) (xy 351.381031 -285.738379) (xy 351.372932 -285.687241) (xy 351.372424 -285.661354)
			(xy 351.0915 -285.661354) (xy 351.0915 -285.661862) (xy 351.090923 -285.689379) (xy 351.081728 -285.74364)
			(xy 351.073212 -285.769812) (xy 351.065592 -285.79191) (xy 351.270824 -286.147256) (xy 351.293684 -286.151574)
			(xy 351.318506 -286.156737) (xy 351.366283 -286.173695) (xy 351.410901 -286.197768) (xy 351.451306 -286.22839)
			(xy 351.486546 -286.264837) (xy 351.515789 -286.30625) (xy 351.538346 -286.351653) (xy 351.553685 -286.399975)
			(xy 351.561445 -286.450075) (xy 351.561908 -286.475424) (xy 367.818924 -286.475424) (xy 367.819448 -286.45008)
			(xy 367.827216 -286.399991) (xy 367.842559 -286.351681) (xy 367.865115 -286.306288) (xy 367.894351 -286.264882)
			(xy 367.92958 -286.228438) (xy 367.969972 -286.197814) (xy 368.014574 -286.173733) (xy 368.062336 -286.156761)
			(xy 368.087148 -286.151574) (xy 368.110008 -286.147256) (xy 368.314986 -285.792164) (xy 368.307112 -285.77032)
			(xy 368.298538 -285.7439) (xy 368.289338 -285.689126) (xy 368.288824 -285.661354) (xy 368.289332 -285.635467)
			(xy 368.297431 -285.584329) (xy 368.31343 -285.535089) (xy 368.336936 -285.488957) (xy 368.367368 -285.44707)
			(xy 368.403978 -285.41046) (xy 368.445865 -285.380028) (xy 368.491997 -285.356522) (xy 368.541237 -285.340523)
			(xy 368.592375 -285.332424) (xy 368.644149 -285.332424) (xy 368.695287 -285.340523) (xy 368.744527 -285.356522)
			(xy 368.790659 -285.380028) (xy 368.832546 -285.41046) (xy 368.869156 -285.44707) (xy 368.899588 -285.488957)
			(xy 368.923094 -285.535089) (xy 368.939093 -285.584329) (xy 368.947192 -285.635467) (xy 368.9477 -285.661354)
			(xy 368.947266 -285.68669) (xy 368.939506 -285.736765) (xy 368.924176 -285.785062) (xy 368.901638 -285.830446)
			(xy 368.872422 -285.871848) (xy 368.837216 -285.908293) (xy 368.796849 -285.938922) (xy 368.752271 -285.963016)
			(xy 368.704531 -285.980006) (xy 368.67973 -285.985204) (xy 368.65687 -285.989522) (xy 368.451892 -286.344614)
			(xy 368.459766 -286.366458) (xy 368.468419 -286.392864) (xy 368.477734 -286.447642) (xy 368.478308 -286.475424)
			(xy 369.698524 -286.475424) (xy 369.699048 -286.45008) (xy 369.706816 -286.399991) (xy 369.722159 -286.351681)
			(xy 369.744715 -286.306288) (xy 369.773951 -286.264882) (xy 369.80918 -286.228438) (xy 369.849572 -286.197814)
			(xy 369.894174 -286.173733) (xy 369.941936 -286.156761) (xy 369.966748 -286.151574) (xy 369.989608 -286.147256)
			(xy 370.194586 -285.792164) (xy 370.186712 -285.77032) (xy 370.178138 -285.7439) (xy 370.168938 -285.689126)
			(xy 370.168424 -285.661354) (xy 370.168932 -285.635467) (xy 370.177031 -285.584329) (xy 370.19303 -285.535089)
			(xy 370.216536 -285.488957) (xy 370.246968 -285.44707) (xy 370.283578 -285.41046) (xy 370.325465 -285.380028)
			(xy 370.371597 -285.356522) (xy 370.420837 -285.340523) (xy 370.471975 -285.332424) (xy 370.523749 -285.332424)
			(xy 370.574887 -285.340523) (xy 370.624127 -285.356522) (xy 370.670259 -285.380028) (xy 370.712146 -285.41046)
			(xy 370.748756 -285.44707) (xy 370.779188 -285.488957) (xy 370.802694 -285.535089) (xy 370.818693 -285.584329)
			(xy 370.826792 -285.635467) (xy 370.8273 -285.661354) (xy 370.826866 -285.68669) (xy 370.819106 -285.736765)
			(xy 370.803776 -285.785062) (xy 370.781238 -285.830446) (xy 370.752022 -285.871848) (xy 370.716816 -285.908293)
			(xy 370.676449 -285.938922) (xy 370.631871 -285.963016) (xy 370.584131 -285.980006) (xy 370.55933 -285.985204)
			(xy 370.53647 -285.989522) (xy 370.331492 -286.344614) (xy 370.339366 -286.366458) (xy 370.348019 -286.392864)
			(xy 370.357334 -286.447642) (xy 370.357908 -286.475424) (xy 371.578124 -286.475424) (xy 371.578648 -286.45008)
			(xy 371.586416 -286.399991) (xy 371.601759 -286.351681) (xy 371.624315 -286.306288) (xy 371.653551 -286.264882)
			(xy 371.68878 -286.228438) (xy 371.729172 -286.197814) (xy 371.773774 -286.173733) (xy 371.821536 -286.156761)
			(xy 371.846348 -286.151574) (xy 371.869208 -286.147256) (xy 372.074186 -285.792164) (xy 372.066312 -285.77032)
			(xy 372.057738 -285.7439) (xy 372.048538 -285.689126) (xy 372.048024 -285.661354) (xy 372.048532 -285.635467)
			(xy 372.056631 -285.584329) (xy 372.07263 -285.535089) (xy 372.096136 -285.488957) (xy 372.126568 -285.44707)
			(xy 372.163178 -285.41046) (xy 372.205065 -285.380028) (xy 372.251197 -285.356522) (xy 372.300437 -285.340523)
			(xy 372.351575 -285.332424) (xy 372.403349 -285.332424) (xy 372.454487 -285.340523) (xy 372.503727 -285.356522)
			(xy 372.549859 -285.380028) (xy 372.591746 -285.41046) (xy 372.628356 -285.44707) (xy 372.658788 -285.488957)
			(xy 372.682294 -285.535089) (xy 372.698293 -285.584329) (xy 372.706392 -285.635467) (xy 372.7069 -285.661354)
			(xy 372.706466 -285.68669) (xy 372.698706 -285.736765) (xy 372.683376 -285.785062) (xy 372.660838 -285.830446)
			(xy 372.631622 -285.871848) (xy 372.596416 -285.908293) (xy 372.556049 -285.938922) (xy 372.511471 -285.963016)
			(xy 372.463731 -285.980006) (xy 372.43893 -285.985204) (xy 372.41607 -285.989522) (xy 372.211092 -286.344614)
			(xy 372.218966 -286.366458) (xy 372.227619 -286.392864) (xy 372.236934 -286.447642) (xy 372.237508 -286.475424)
			(xy 373.457724 -286.475424) (xy 373.458248 -286.45008) (xy 373.466016 -286.399991) (xy 373.481359 -286.351681)
			(xy 373.503915 -286.306288) (xy 373.533151 -286.264882) (xy 373.56838 -286.228438) (xy 373.608772 -286.197814)
			(xy 373.653374 -286.173733) (xy 373.701136 -286.156761) (xy 373.725948 -286.151574) (xy 373.748808 -286.147256)
			(xy 373.953786 -285.792164) (xy 373.945912 -285.77032) (xy 373.937338 -285.7439) (xy 373.928138 -285.689126)
			(xy 373.927624 -285.661354) (xy 373.928132 -285.635467) (xy 373.936231 -285.584329) (xy 373.95223 -285.535089)
			(xy 373.975736 -285.488957) (xy 374.006168 -285.44707) (xy 374.042778 -285.41046) (xy 374.084665 -285.380028)
			(xy 374.130797 -285.356522) (xy 374.180037 -285.340523) (xy 374.231175 -285.332424) (xy 374.282949 -285.332424)
			(xy 374.334087 -285.340523) (xy 374.383327 -285.356522) (xy 374.429459 -285.380028) (xy 374.471346 -285.41046)
			(xy 374.507956 -285.44707) (xy 374.538388 -285.488957) (xy 374.561894 -285.535089) (xy 374.577893 -285.584329)
			(xy 374.585992 -285.635467) (xy 374.5865 -285.661354) (xy 374.586066 -285.68669) (xy 374.578306 -285.736765)
			(xy 374.562976 -285.785062) (xy 374.540438 -285.830446) (xy 374.511222 -285.871848) (xy 374.476016 -285.908293)
			(xy 374.435649 -285.938922) (xy 374.391071 -285.963016) (xy 374.343331 -285.980006) (xy 374.31853 -285.985204)
			(xy 374.29567 -285.989522) (xy 374.090692 -286.344614) (xy 374.098566 -286.366458) (xy 374.107219 -286.392864)
			(xy 374.116534 -286.447642) (xy 374.117108 -286.475424) (xy 375.337324 -286.475424) (xy 375.337848 -286.45008)
			(xy 375.345616 -286.399991) (xy 375.360959 -286.351681) (xy 375.383515 -286.306288) (xy 375.412751 -286.264882)
			(xy 375.44798 -286.228438) (xy 375.488372 -286.197814) (xy 375.532974 -286.173733) (xy 375.580736 -286.156761)
			(xy 375.605548 -286.151574) (xy 375.628408 -286.147256) (xy 375.833386 -285.792164) (xy 375.825512 -285.77032)
			(xy 375.816938 -285.7439) (xy 375.807738 -285.689126) (xy 375.807224 -285.661354) (xy 375.807732 -285.635467)
			(xy 375.815831 -285.584329) (xy 375.83183 -285.535089) (xy 375.855336 -285.488957) (xy 375.885768 -285.44707)
			(xy 375.922378 -285.41046) (xy 375.964265 -285.380028) (xy 376.010397 -285.356522) (xy 376.059637 -285.340523)
			(xy 376.110775 -285.332424) (xy 376.162549 -285.332424) (xy 376.213687 -285.340523) (xy 376.262927 -285.356522)
			(xy 376.309059 -285.380028) (xy 376.350946 -285.41046) (xy 376.387556 -285.44707) (xy 376.417988 -285.488957)
			(xy 376.441494 -285.535089) (xy 376.457493 -285.584329) (xy 376.465592 -285.635467) (xy 376.4661 -285.661354)
			(xy 376.465666 -285.68669) (xy 376.457906 -285.736765) (xy 376.442576 -285.785062) (xy 376.420038 -285.830446)
			(xy 376.390822 -285.871848) (xy 376.355616 -285.908293) (xy 376.315249 -285.938922) (xy 376.270671 -285.963016)
			(xy 376.222931 -285.980006) (xy 376.19813 -285.985204) (xy 376.17527 -285.989522) (xy 375.970292 -286.344614)
			(xy 375.978166 -286.366458) (xy 375.986819 -286.392864) (xy 375.996134 -286.447642) (xy 375.996708 -286.475424)
			(xy 377.216924 -286.475424) (xy 377.217448 -286.45008) (xy 377.225216 -286.399991) (xy 377.240559 -286.351681)
			(xy 377.263115 -286.306288) (xy 377.292351 -286.264882) (xy 377.32758 -286.228438) (xy 377.367972 -286.197814)
			(xy 377.412574 -286.173733) (xy 377.460336 -286.156761) (xy 377.485148 -286.151574) (xy 377.508008 -286.147256)
			(xy 377.712986 -285.792164) (xy 377.705112 -285.77032) (xy 377.696538 -285.7439) (xy 377.687338 -285.689126)
			(xy 377.686824 -285.661354) (xy 377.687332 -285.635467) (xy 377.695431 -285.584329) (xy 377.71143 -285.535089)
			(xy 377.734936 -285.488957) (xy 377.765368 -285.44707) (xy 377.801978 -285.41046) (xy 377.843865 -285.380028)
			(xy 377.889997 -285.356522) (xy 377.939237 -285.340523) (xy 377.990375 -285.332424) (xy 378.042149 -285.332424)
			(xy 378.093287 -285.340523) (xy 378.142527 -285.356522) (xy 378.188659 -285.380028) (xy 378.230546 -285.41046)
			(xy 378.267156 -285.44707) (xy 378.297588 -285.488957) (xy 378.321094 -285.535089) (xy 378.337093 -285.584329)
			(xy 378.345192 -285.635467) (xy 378.3457 -285.661354) (xy 378.345266 -285.68669) (xy 378.337506 -285.736765)
			(xy 378.322176 -285.785062) (xy 378.299638 -285.830446) (xy 378.270422 -285.871848) (xy 378.235216 -285.908293)
			(xy 378.194849 -285.938922) (xy 378.150271 -285.963016) (xy 378.102531 -285.980006) (xy 378.07773 -285.985204)
			(xy 378.05487 -285.989522) (xy 377.849892 -286.344614) (xy 377.857766 -286.366458) (xy 377.866419 -286.392864)
			(xy 377.875734 -286.447642) (xy 377.876308 -286.475424) (xy 379.096524 -286.475424) (xy 379.097048 -286.45008)
			(xy 379.104816 -286.399991) (xy 379.120159 -286.351681) (xy 379.142715 -286.306288) (xy 379.171951 -286.264882)
			(xy 379.20718 -286.228438) (xy 379.247572 -286.197814) (xy 379.292174 -286.173733) (xy 379.339936 -286.156761)
			(xy 379.364748 -286.151574) (xy 379.387608 -286.147256) (xy 379.592586 -285.792164) (xy 379.584712 -285.77032)
			(xy 379.576138 -285.7439) (xy 379.566938 -285.689126) (xy 379.566424 -285.661354) (xy 379.566932 -285.635467)
			(xy 379.575031 -285.584329) (xy 379.59103 -285.535089) (xy 379.614536 -285.488957) (xy 379.644968 -285.44707)
			(xy 379.681578 -285.41046) (xy 379.723465 -285.380028) (xy 379.769597 -285.356522) (xy 379.818837 -285.340523)
			(xy 379.869975 -285.332424) (xy 379.921749 -285.332424) (xy 379.972887 -285.340523) (xy 380.022127 -285.356522)
			(xy 380.068259 -285.380028) (xy 380.110146 -285.41046) (xy 380.146756 -285.44707) (xy 380.177188 -285.488957)
			(xy 380.200694 -285.535089) (xy 380.216693 -285.584329) (xy 380.224792 -285.635467) (xy 380.2253 -285.661354)
			(xy 380.224866 -285.68669) (xy 380.217106 -285.736765) (xy 380.201776 -285.785062) (xy 380.179238 -285.830446)
			(xy 380.150022 -285.871848) (xy 380.114816 -285.908293) (xy 380.074449 -285.938922) (xy 380.029871 -285.963016)
			(xy 379.982131 -285.980006) (xy 379.95733 -285.985204) (xy 379.93447 -285.989522) (xy 379.729492 -286.344614)
			(xy 379.737366 -286.366458) (xy 379.746019 -286.392864) (xy 379.755334 -286.447642) (xy 379.755908 -286.475424)
			(xy 380.976124 -286.475424) (xy 380.976648 -286.45008) (xy 380.984416 -286.399991) (xy 380.999759 -286.351681)
			(xy 381.022315 -286.306288) (xy 381.051551 -286.264882) (xy 381.08678 -286.228438) (xy 381.127172 -286.197814)
			(xy 381.171774 -286.173733) (xy 381.219536 -286.156761) (xy 381.244348 -286.151574) (xy 381.267208 -286.147256)
			(xy 381.472186 -285.792164) (xy 381.464312 -285.77032) (xy 381.455738 -285.7439) (xy 381.446538 -285.689126)
			(xy 381.446024 -285.661354) (xy 381.446532 -285.635467) (xy 381.454631 -285.584329) (xy 381.47063 -285.535089)
			(xy 381.494136 -285.488957) (xy 381.524568 -285.44707) (xy 381.561178 -285.41046) (xy 381.603065 -285.380028)
			(xy 381.649197 -285.356522) (xy 381.698437 -285.340523) (xy 381.749575 -285.332424) (xy 381.801349 -285.332424)
			(xy 381.852487 -285.340523) (xy 381.901727 -285.356522) (xy 381.947859 -285.380028) (xy 381.989746 -285.41046)
			(xy 382.026356 -285.44707) (xy 382.056788 -285.488957) (xy 382.080294 -285.535089) (xy 382.096293 -285.584329)
			(xy 382.104392 -285.635467) (xy 382.1049 -285.661354) (xy 382.104466 -285.68669) (xy 382.096706 -285.736765)
			(xy 382.081376 -285.785062) (xy 382.058838 -285.830446) (xy 382.029622 -285.871848) (xy 381.994416 -285.908293)
			(xy 381.954049 -285.938922) (xy 381.909471 -285.963016) (xy 381.861731 -285.980006) (xy 381.83693 -285.985204)
			(xy 381.81407 -285.989522) (xy 381.609092 -286.344614) (xy 381.616966 -286.366458) (xy 381.625619 -286.392864)
			(xy 381.634934 -286.447642) (xy 381.635508 -286.475424) (xy 381.635 -286.501331) (xy 381.626894 -286.552508)
			(xy 381.610882 -286.601787) (xy 381.587359 -286.647954) (xy 381.556903 -286.689873) (xy 381.520265 -286.726511)
			(xy 381.478346 -286.756967) (xy 381.432179 -286.78049) (xy 381.3829 -286.796502) (xy 381.331723 -286.804608)
			(xy 381.279909 -286.804608) (xy 381.228732 -286.796502) (xy 381.179453 -286.78049) (xy 381.133286 -286.756967)
			(xy 381.091367 -286.726511) (xy 381.054729 -286.689873) (xy 381.024273 -286.647954) (xy 381.00075 -286.601787)
			(xy 380.984738 -286.552508) (xy 380.976632 -286.501331) (xy 380.976124 -286.475424) (xy 379.755908 -286.475424)
			(xy 379.7554 -286.501331) (xy 379.747294 -286.552508) (xy 379.731282 -286.601787) (xy 379.707759 -286.647954)
			(xy 379.677303 -286.689873) (xy 379.640665 -286.726511) (xy 379.598746 -286.756967) (xy 379.552579 -286.78049)
			(xy 379.5033 -286.796502) (xy 379.452123 -286.804608) (xy 379.400309 -286.804608) (xy 379.349132 -286.796502)
			(xy 379.299853 -286.78049) (xy 379.253686 -286.756967) (xy 379.211767 -286.726511) (xy 379.175129 -286.689873)
			(xy 379.144673 -286.647954) (xy 379.12115 -286.601787) (xy 379.105138 -286.552508) (xy 379.097032 -286.501331)
			(xy 379.096524 -286.475424) (xy 377.876308 -286.475424) (xy 377.8758 -286.501331) (xy 377.867694 -286.552508)
			(xy 377.851682 -286.601787) (xy 377.828159 -286.647954) (xy 377.797703 -286.689873) (xy 377.761065 -286.726511)
			(xy 377.719146 -286.756967) (xy 377.672979 -286.78049) (xy 377.6237 -286.796502) (xy 377.572523 -286.804608)
			(xy 377.520709 -286.804608) (xy 377.469532 -286.796502) (xy 377.420253 -286.78049) (xy 377.374086 -286.756967)
			(xy 377.332167 -286.726511) (xy 377.295529 -286.689873) (xy 377.265073 -286.647954) (xy 377.24155 -286.601787)
			(xy 377.225538 -286.552508) (xy 377.217432 -286.501331) (xy 377.216924 -286.475424) (xy 375.996708 -286.475424)
			(xy 375.9962 -286.501331) (xy 375.988094 -286.552508) (xy 375.972082 -286.601787) (xy 375.948559 -286.647954)
			(xy 375.918103 -286.689873) (xy 375.881465 -286.726511) (xy 375.839546 -286.756967) (xy 375.793379 -286.78049)
			(xy 375.7441 -286.796502) (xy 375.692923 -286.804608) (xy 375.641109 -286.804608) (xy 375.589932 -286.796502)
			(xy 375.540653 -286.78049) (xy 375.494486 -286.756967) (xy 375.452567 -286.726511) (xy 375.415929 -286.689873)
			(xy 375.385473 -286.647954) (xy 375.36195 -286.601787) (xy 375.345938 -286.552508) (xy 375.337832 -286.501331)
			(xy 375.337324 -286.475424) (xy 374.117108 -286.475424) (xy 374.1166 -286.501331) (xy 374.108494 -286.552508)
			(xy 374.092482 -286.601787) (xy 374.068959 -286.647954) (xy 374.038503 -286.689873) (xy 374.001865 -286.726511)
			(xy 373.959946 -286.756967) (xy 373.913779 -286.78049) (xy 373.8645 -286.796502) (xy 373.813323 -286.804608)
			(xy 373.761509 -286.804608) (xy 373.710332 -286.796502) (xy 373.661053 -286.78049) (xy 373.614886 -286.756967)
			(xy 373.572967 -286.726511) (xy 373.536329 -286.689873) (xy 373.505873 -286.647954) (xy 373.48235 -286.601787)
			(xy 373.466338 -286.552508) (xy 373.458232 -286.501331) (xy 373.457724 -286.475424) (xy 372.237508 -286.475424)
			(xy 372.237 -286.501331) (xy 372.228894 -286.552508) (xy 372.212882 -286.601787) (xy 372.189359 -286.647954)
			(xy 372.158903 -286.689873) (xy 372.122265 -286.726511) (xy 372.080346 -286.756967) (xy 372.034179 -286.78049)
			(xy 371.9849 -286.796502) (xy 371.933723 -286.804608) (xy 371.881909 -286.804608) (xy 371.830732 -286.796502)
			(xy 371.781453 -286.78049) (xy 371.735286 -286.756967) (xy 371.693367 -286.726511) (xy 371.656729 -286.689873)
			(xy 371.626273 -286.647954) (xy 371.60275 -286.601787) (xy 371.586738 -286.552508) (xy 371.578632 -286.501331)
			(xy 371.578124 -286.475424) (xy 370.357908 -286.475424) (xy 370.3574 -286.501331) (xy 370.349294 -286.552508)
			(xy 370.333282 -286.601787) (xy 370.309759 -286.647954) (xy 370.279303 -286.689873) (xy 370.242665 -286.726511)
			(xy 370.200746 -286.756967) (xy 370.154579 -286.78049) (xy 370.1053 -286.796502) (xy 370.054123 -286.804608)
			(xy 370.002309 -286.804608) (xy 369.951132 -286.796502) (xy 369.901853 -286.78049) (xy 369.855686 -286.756967)
			(xy 369.813767 -286.726511) (xy 369.777129 -286.689873) (xy 369.746673 -286.647954) (xy 369.72315 -286.601787)
			(xy 369.707138 -286.552508) (xy 369.699032 -286.501331) (xy 369.698524 -286.475424) (xy 368.478308 -286.475424)
			(xy 368.4778 -286.501331) (xy 368.469694 -286.552508) (xy 368.453682 -286.601787) (xy 368.430159 -286.647954)
			(xy 368.399703 -286.689873) (xy 368.363065 -286.726511) (xy 368.321146 -286.756967) (xy 368.274979 -286.78049)
			(xy 368.2257 -286.796502) (xy 368.174523 -286.804608) (xy 368.122709 -286.804608) (xy 368.071532 -286.796502)
			(xy 368.022253 -286.78049) (xy 367.976086 -286.756967) (xy 367.934167 -286.726511) (xy 367.897529 -286.689873)
			(xy 367.867073 -286.647954) (xy 367.84355 -286.601787) (xy 367.827538 -286.552508) (xy 367.819432 -286.501331)
			(xy 367.818924 -286.475424) (xy 351.561908 -286.475424) (xy 351.5614 -286.501331) (xy 351.553294 -286.552508)
			(xy 351.537282 -286.601787) (xy 351.513759 -286.647954) (xy 351.483303 -286.689873) (xy 351.446665 -286.726511)
			(xy 351.404746 -286.756967) (xy 351.358579 -286.78049) (xy 351.3093 -286.796502) (xy 351.258123 -286.804608)
			(xy 351.206309 -286.804608) (xy 351.155132 -286.796502) (xy 351.105853 -286.78049) (xy 351.059686 -286.756967)
			(xy 351.017767 -286.726511) (xy 350.981129 -286.689873) (xy 350.950673 -286.647954) (xy 350.92715 -286.601787)
			(xy 350.911138 -286.552508) (xy 350.903032 -286.501331) (xy 350.902524 -286.475424) (xy 350.903123 -286.447707)
			(xy 350.912443 -286.39306) (xy 350.921066 -286.366712) (xy 350.92894 -286.344614) (xy 350.723962 -285.989522)
			(xy 350.700848 -285.985204) (xy 350.676027 -285.980039) (xy 350.628247 -285.963084) (xy 350.583628 -285.939012)
			(xy 350.543222 -285.908392) (xy 350.507981 -285.871945) (xy 350.478737 -285.830531) (xy 350.45618 -285.785127)
			(xy 350.440843 -285.736804) (xy 350.433086 -285.686703) (xy 350.432624 -285.661354) (xy 350.1517 -285.661354)
			(xy 350.151192 -285.687241) (xy 350.143093 -285.738379) (xy 350.127094 -285.787619) (xy 350.103588 -285.833751)
			(xy 350.073156 -285.875638) (xy 350.036546 -285.912248) (xy 349.994659 -285.94268) (xy 349.948527 -285.966186)
			(xy 349.899287 -285.982185) (xy 349.848149 -285.990284) (xy 349.796375 -285.990284) (xy 349.745237 -285.982185)
			(xy 349.695997 -285.966186) (xy 349.649865 -285.94268) (xy 349.607978 -285.912248) (xy 349.571368 -285.875638)
			(xy 349.540936 -285.833751) (xy 349.51743 -285.787619) (xy 349.501431 -285.738379) (xy 349.493332 -285.687241)
			(xy 349.492824 -285.661354) (xy 349.2119 -285.661354) (xy 349.2119 -285.661862) (xy 349.211323 -285.689379)
			(xy 349.202128 -285.74364) (xy 349.193612 -285.769812) (xy 349.185992 -285.79191) (xy 349.391224 -286.147256)
			(xy 349.414084 -286.151574) (xy 349.438906 -286.156737) (xy 349.486683 -286.173695) (xy 349.531301 -286.197768)
			(xy 349.571706 -286.22839) (xy 349.606946 -286.264837) (xy 349.636189 -286.30625) (xy 349.658746 -286.351653)
			(xy 349.674085 -286.399975) (xy 349.681845 -286.450075) (xy 349.682308 -286.475424) (xy 349.6818 -286.501331)
			(xy 349.673694 -286.552508) (xy 349.657682 -286.601787) (xy 349.634159 -286.647954) (xy 349.603703 -286.689873)
			(xy 349.567065 -286.726511) (xy 349.525146 -286.756967) (xy 349.478979 -286.78049) (xy 349.4297 -286.796502)
			(xy 349.378523 -286.804608) (xy 349.326709 -286.804608) (xy 349.275532 -286.796502) (xy 349.226253 -286.78049)
			(xy 349.180086 -286.756967) (xy 349.138167 -286.726511) (xy 349.101529 -286.689873) (xy 349.071073 -286.647954)
			(xy 349.04755 -286.601787) (xy 349.031538 -286.552508) (xy 349.023432 -286.501331) (xy 349.022924 -286.475424)
			(xy 349.023523 -286.447707) (xy 349.032843 -286.39306) (xy 349.041466 -286.366712) (xy 349.04934 -286.344614)
			(xy 348.844362 -285.989522) (xy 348.821248 -285.985204) (xy 348.796427 -285.980039) (xy 348.748647 -285.963084)
			(xy 348.704028 -285.939012) (xy 348.663622 -285.908392) (xy 348.628381 -285.871945) (xy 348.599137 -285.830531)
			(xy 348.57658 -285.785127) (xy 348.561243 -285.736804) (xy 348.553486 -285.686703) (xy 348.553024 -285.661354)
			(xy 348.2721 -285.661354) (xy 348.271592 -285.687241) (xy 348.263493 -285.738379) (xy 348.247494 -285.787619)
			(xy 348.223988 -285.833751) (xy 348.193556 -285.875638) (xy 348.156946 -285.912248) (xy 348.115059 -285.94268)
			(xy 348.068927 -285.966186) (xy 348.019687 -285.982185) (xy 347.968549 -285.990284) (xy 347.916775 -285.990284)
			(xy 347.865637 -285.982185) (xy 347.816397 -285.966186) (xy 347.770265 -285.94268) (xy 347.728378 -285.912248)
			(xy 347.691768 -285.875638) (xy 347.661336 -285.833751) (xy 347.63783 -285.787619) (xy 347.621831 -285.738379)
			(xy 347.613732 -285.687241) (xy 347.613224 -285.661354) (xy 347.3323 -285.661354) (xy 347.3323 -285.661862)
			(xy 347.331723 -285.689379) (xy 347.322528 -285.74364) (xy 347.314012 -285.769812) (xy 347.306392 -285.79191)
			(xy 347.511624 -286.147256) (xy 347.534484 -286.151574) (xy 347.559306 -286.156737) (xy 347.607083 -286.173695)
			(xy 347.651701 -286.197768) (xy 347.692106 -286.22839) (xy 347.727346 -286.264837) (xy 347.756589 -286.30625)
			(xy 347.779146 -286.351653) (xy 347.794485 -286.399975) (xy 347.802245 -286.450075) (xy 347.802708 -286.475424)
			(xy 347.8022 -286.501331) (xy 347.794094 -286.552508) (xy 347.778082 -286.601787) (xy 347.754559 -286.647954)
			(xy 347.724103 -286.689873) (xy 347.687465 -286.726511) (xy 347.645546 -286.756967) (xy 347.599379 -286.78049)
			(xy 347.5501 -286.796502) (xy 347.498923 -286.804608) (xy 347.447109 -286.804608) (xy 347.395932 -286.796502)
			(xy 347.346653 -286.78049) (xy 347.300486 -286.756967) (xy 347.258567 -286.726511) (xy 347.221929 -286.689873)
			(xy 347.191473 -286.647954) (xy 347.16795 -286.601787) (xy 347.151938 -286.552508) (xy 347.143832 -286.501331)
			(xy 347.143324 -286.475424) (xy 347.143923 -286.447707) (xy 347.153243 -286.39306) (xy 347.161866 -286.366712)
			(xy 347.16974 -286.344614) (xy 346.964762 -285.989522) (xy 346.941648 -285.985204) (xy 346.916827 -285.980039)
			(xy 346.869047 -285.963084) (xy 346.824428 -285.939012) (xy 346.784022 -285.908392) (xy 346.748781 -285.871945)
			(xy 346.719537 -285.830531) (xy 346.69698 -285.785127) (xy 346.681643 -285.736804) (xy 346.673886 -285.686703)
			(xy 346.673424 -285.661354) (xy 346.3925 -285.661354) (xy 346.391992 -285.687241) (xy 346.383893 -285.738379)
			(xy 346.367894 -285.787619) (xy 346.344388 -285.833751) (xy 346.313956 -285.875638) (xy 346.277346 -285.912248)
			(xy 346.235459 -285.94268) (xy 346.189327 -285.966186) (xy 346.140087 -285.982185) (xy 346.088949 -285.990284)
			(xy 346.037175 -285.990284) (xy 345.986037 -285.982185) (xy 345.936797 -285.966186) (xy 345.890665 -285.94268)
			(xy 345.848778 -285.912248) (xy 345.812168 -285.875638) (xy 345.781736 -285.833751) (xy 345.75823 -285.787619)
			(xy 345.742231 -285.738379) (xy 345.734132 -285.687241) (xy 345.733624 -285.661354) (xy 345.4527 -285.661354)
			(xy 345.4527 -285.661862) (xy 345.452123 -285.689379) (xy 345.442928 -285.74364) (xy 345.434412 -285.769812)
			(xy 345.426792 -285.79191) (xy 345.632024 -286.147256) (xy 345.654884 -286.151574) (xy 345.679706 -286.156737)
			(xy 345.727483 -286.173695) (xy 345.772101 -286.197768) (xy 345.812506 -286.22839) (xy 345.847746 -286.264837)
			(xy 345.876989 -286.30625) (xy 345.899546 -286.351653) (xy 345.914885 -286.399975) (xy 345.922645 -286.450075)
			(xy 345.923108 -286.475424) (xy 345.9226 -286.501331) (xy 345.914494 -286.552508) (xy 345.898482 -286.601787)
			(xy 345.874959 -286.647954) (xy 345.844503 -286.689873) (xy 345.807865 -286.726511) (xy 345.765946 -286.756967)
			(xy 345.719779 -286.78049) (xy 345.6705 -286.796502) (xy 345.619323 -286.804608) (xy 345.567509 -286.804608)
			(xy 345.516332 -286.796502) (xy 345.467053 -286.78049) (xy 345.420886 -286.756967) (xy 345.378967 -286.726511)
			(xy 345.342329 -286.689873) (xy 345.311873 -286.647954) (xy 345.28835 -286.601787) (xy 345.272338 -286.552508)
			(xy 345.264232 -286.501331) (xy 345.263724 -286.475424) (xy 345.264323 -286.447707) (xy 345.273643 -286.39306)
			(xy 345.282266 -286.366712) (xy 345.29014 -286.344614) (xy 345.085162 -285.989522) (xy 345.062048 -285.985204)
			(xy 345.037227 -285.980039) (xy 344.989447 -285.963084) (xy 344.944828 -285.939012) (xy 344.904422 -285.908392)
			(xy 344.869181 -285.871945) (xy 344.839937 -285.830531) (xy 344.81738 -285.785127) (xy 344.802043 -285.736804)
			(xy 344.794286 -285.686703) (xy 344.793824 -285.661354) (xy 344.5129 -285.661354) (xy 344.512392 -285.687241)
			(xy 344.504293 -285.738379) (xy 344.488294 -285.787619) (xy 344.464788 -285.833751) (xy 344.434356 -285.875638)
			(xy 344.397746 -285.912248) (xy 344.355859 -285.94268) (xy 344.309727 -285.966186) (xy 344.260487 -285.982185)
			(xy 344.209349 -285.990284) (xy 344.157575 -285.990284) (xy 344.106437 -285.982185) (xy 344.057197 -285.966186)
			(xy 344.011065 -285.94268) (xy 343.969178 -285.912248) (xy 343.932568 -285.875638) (xy 343.902136 -285.833751)
			(xy 343.87863 -285.787619) (xy 343.862631 -285.738379) (xy 343.854532 -285.687241) (xy 343.854024 -285.661354)
			(xy 343.5731 -285.661354) (xy 343.5731 -285.661862) (xy 343.572523 -285.689379) (xy 343.563328 -285.74364)
			(xy 343.554812 -285.769812) (xy 343.547192 -285.79191) (xy 343.752424 -286.147256) (xy 343.775284 -286.151574)
			(xy 343.800106 -286.156737) (xy 343.847883 -286.173695) (xy 343.892501 -286.197768) (xy 343.932906 -286.22839)
			(xy 343.968146 -286.264837) (xy 343.997389 -286.30625) (xy 344.019946 -286.351653) (xy 344.035285 -286.399975)
			(xy 344.043045 -286.450075) (xy 344.043508 -286.475424) (xy 344.043 -286.501331) (xy 344.034894 -286.552508)
			(xy 344.018882 -286.601787) (xy 343.995359 -286.647954) (xy 343.964903 -286.689873) (xy 343.928265 -286.726511)
			(xy 343.886346 -286.756967) (xy 343.840179 -286.78049) (xy 343.7909 -286.796502) (xy 343.739723 -286.804608)
			(xy 343.687909 -286.804608) (xy 343.636732 -286.796502) (xy 343.587453 -286.78049) (xy 343.541286 -286.756967)
			(xy 343.499367 -286.726511) (xy 343.462729 -286.689873) (xy 343.432273 -286.647954) (xy 343.40875 -286.601787)
			(xy 343.392738 -286.552508) (xy 343.384632 -286.501331) (xy 343.384124 -286.475424) (xy 343.384723 -286.447707)
			(xy 343.394043 -286.39306) (xy 343.402666 -286.366712) (xy 343.41054 -286.344614) (xy 343.205562 -285.989522)
			(xy 343.182448 -285.985204) (xy 343.157627 -285.980039) (xy 343.109847 -285.963084) (xy 343.065228 -285.939012)
			(xy 343.024822 -285.908392) (xy 342.989581 -285.871945) (xy 342.960337 -285.830531) (xy 342.93778 -285.785127)
			(xy 342.922443 -285.736804) (xy 342.914686 -285.686703) (xy 342.914224 -285.661354) (xy 342.6333 -285.661354)
			(xy 342.632792 -285.687241) (xy 342.624693 -285.738379) (xy 342.608694 -285.787619) (xy 342.585188 -285.833751)
			(xy 342.554756 -285.875638) (xy 342.518146 -285.912248) (xy 342.476259 -285.94268) (xy 342.430127 -285.966186)
			(xy 342.380887 -285.982185) (xy 342.329749 -285.990284) (xy 342.277975 -285.990284) (xy 342.226837 -285.982185)
			(xy 342.177597 -285.966186) (xy 342.131465 -285.94268) (xy 342.089578 -285.912248) (xy 342.052968 -285.875638)
			(xy 342.022536 -285.833751) (xy 341.99903 -285.787619) (xy 341.983031 -285.738379) (xy 341.974932 -285.687241)
			(xy 341.974424 -285.661354) (xy 341.6935 -285.661354) (xy 341.6935 -285.661862) (xy 341.692923 -285.689379)
			(xy 341.683728 -285.74364) (xy 341.675212 -285.769812) (xy 341.667592 -285.79191) (xy 341.872824 -286.147256)
			(xy 341.895684 -286.151574) (xy 341.920506 -286.156737) (xy 341.968283 -286.173695) (xy 342.012901 -286.197768)
			(xy 342.053306 -286.22839) (xy 342.088546 -286.264837) (xy 342.117789 -286.30625) (xy 342.140346 -286.351653)
			(xy 342.155685 -286.399975) (xy 342.163445 -286.450075) (xy 342.163908 -286.475424) (xy 342.1634 -286.501331)
			(xy 342.155294 -286.552508) (xy 342.139282 -286.601787) (xy 342.115759 -286.647954) (xy 342.085303 -286.689873)
			(xy 342.048665 -286.726511) (xy 342.006746 -286.756967) (xy 341.960579 -286.78049) (xy 341.9113 -286.796502)
			(xy 341.860123 -286.804608) (xy 341.808309 -286.804608) (xy 341.757132 -286.796502) (xy 341.707853 -286.78049)
			(xy 341.661686 -286.756967) (xy 341.619767 -286.726511) (xy 341.583129 -286.689873) (xy 341.552673 -286.647954)
			(xy 341.52915 -286.601787) (xy 341.513138 -286.552508) (xy 341.505032 -286.501331) (xy 341.504524 -286.475424)
			(xy 341.505123 -286.447707) (xy 341.514443 -286.39306) (xy 341.523066 -286.366712) (xy 341.53094 -286.344614)
			(xy 341.325962 -285.989522) (xy 341.302848 -285.985204) (xy 341.278027 -285.980039) (xy 341.230247 -285.963084)
			(xy 341.185628 -285.939012) (xy 341.145222 -285.908392) (xy 341.109981 -285.871945) (xy 341.080737 -285.830531)
			(xy 341.05818 -285.785127) (xy 341.042843 -285.736804) (xy 341.035086 -285.686703) (xy 341.034624 -285.661354)
			(xy 340.7537 -285.661354) (xy 340.753192 -285.687241) (xy 340.745093 -285.738379) (xy 340.729094 -285.787619)
			(xy 340.705588 -285.833751) (xy 340.675156 -285.875638) (xy 340.638546 -285.912248) (xy 340.596659 -285.94268)
			(xy 340.550527 -285.966186) (xy 340.501287 -285.982185) (xy 340.450149 -285.990284) (xy 340.398375 -285.990284)
			(xy 340.347237 -285.982185) (xy 340.297997 -285.966186) (xy 340.251865 -285.94268) (xy 340.209978 -285.912248)
			(xy 340.173368 -285.875638) (xy 340.142936 -285.833751) (xy 340.11943 -285.787619) (xy 340.103431 -285.738379)
			(xy 340.095332 -285.687241) (xy 340.094824 -285.661354) (xy 339.814408 -285.661354) (xy 339.813802 -285.689071)
			(xy 339.804487 -285.743717) (xy 339.795866 -285.770066) (xy 339.787992 -285.792164) (xy 339.993224 -286.147256)
			(xy 340.016084 -286.151574) (xy 340.040906 -286.156737) (xy 340.088683 -286.173695) (xy 340.133301 -286.197768)
			(xy 340.173706 -286.22839) (xy 340.208946 -286.264837) (xy 340.238189 -286.30625) (xy 340.260746 -286.351653)
			(xy 340.276085 -286.399975) (xy 340.283845 -286.450075) (xy 340.284308 -286.475424) (xy 340.2838 -286.501331)
			(xy 340.275694 -286.552508) (xy 340.259682 -286.601787) (xy 340.236159 -286.647954) (xy 340.205703 -286.689873)
			(xy 340.169065 -286.726511) (xy 340.127146 -286.756967) (xy 340.080979 -286.78049) (xy 340.0317 -286.796502)
			(xy 339.980523 -286.804608) (xy 339.928709 -286.804608) (xy 339.877532 -286.796502) (xy 339.828253 -286.78049)
			(xy 339.782086 -286.756967) (xy 339.740167 -286.726511) (xy 339.703529 -286.689873) (xy 339.673073 -286.647954)
			(xy 339.64955 -286.601787) (xy 339.633538 -286.552508) (xy 339.625432 -286.501331) (xy 339.624924 -286.475424)
			(xy 339.625523 -286.447707) (xy 339.634843 -286.39306) (xy 339.643466 -286.366712) (xy 339.65134 -286.344614)
			(xy 339.446108 -285.989522) (xy 339.423248 -285.985204) (xy 339.398427 -285.980039) (xy 339.350647 -285.963084)
			(xy 339.306028 -285.939012) (xy 339.265622 -285.908392) (xy 339.230381 -285.871945) (xy 339.201137 -285.830531)
			(xy 339.17858 -285.785127) (xy 339.163243 -285.736804) (xy 339.155486 -285.686703) (xy 339.155024 -285.661354)
			(xy 338.874608 -285.661354) (xy 338.8741 -285.687261) (xy 338.865994 -285.738438) (xy 338.849982 -285.787717)
			(xy 338.826459 -285.833884) (xy 338.796003 -285.875803) (xy 338.759365 -285.912441) (xy 338.717446 -285.942897)
			(xy 338.671279 -285.96642) (xy 338.622 -285.982432) (xy 338.570823 -285.990538) (xy 338.519009 -285.990538)
			(xy 338.467832 -285.982432) (xy 338.418553 -285.96642) (xy 338.372386 -285.942897) (xy 338.330467 -285.912441)
			(xy 338.293829 -285.875803) (xy 338.263373 -285.833884) (xy 338.23985 -285.787717) (xy 338.223838 -285.738438)
			(xy 338.215732 -285.687261) (xy 338.215224 -285.661354) (xy 337.9343 -285.661354) (xy 337.933759 -285.689062)
			(xy 337.924571 -285.743708) (xy 337.916012 -285.770066) (xy 337.908138 -285.792164) (xy 338.11337 -286.147256)
			(xy 338.13623 -286.151574) (xy 338.16104 -286.156732) (xy 338.20878 -286.173726) (xy 338.253357 -286.197824)
			(xy 338.293722 -286.228459) (xy 338.328925 -286.264909) (xy 338.358136 -286.306317) (xy 338.380667 -286.351707)
			(xy 338.395988 -286.400009) (xy 338.403738 -286.450087) (xy 338.4042 -286.475424) (xy 338.403692 -286.501311)
			(xy 338.395593 -286.552449) (xy 338.379594 -286.601689) (xy 338.356088 -286.647821) (xy 338.325656 -286.689708)
			(xy 338.289046 -286.726318) (xy 338.247159 -286.75675) (xy 338.201027 -286.780256) (xy 338.151787 -286.796255)
			(xy 338.100649 -286.804354) (xy 338.048875 -286.804354) (xy 337.997737 -286.796255) (xy 337.948497 -286.780256)
			(xy 337.902365 -286.75675) (xy 337.860478 -286.726318) (xy 337.823868 -286.689708) (xy 337.793436 -286.647821)
			(xy 337.76993 -286.601689) (xy 337.753931 -286.552449) (xy 337.745832 -286.501311) (xy 337.745324 -286.475424)
			(xy 337.745858 -286.447716) (xy 337.75505 -286.393069) (xy 337.763612 -286.366712) (xy 337.771486 -286.344614)
			(xy 337.566254 -285.989522) (xy 337.543394 -285.985204) (xy 337.518583 -285.980049) (xy 337.470842 -285.963057)
			(xy 337.426263 -285.93896) (xy 337.385896 -285.908325) (xy 337.350693 -285.871874) (xy 337.321482 -285.830466)
			(xy 337.298951 -285.785075) (xy 337.283632 -285.736771) (xy 337.275885 -285.686692) (xy 337.275424 -285.661354)
			(xy 336.081878 -285.661354) (xy 336.081379 -285.688041) (xy 336.073424 -285.74082) (xy 336.057692 -285.791823)
			(xy 336.034534 -285.839912) (xy 336.004467 -285.884012) (xy 335.968163 -285.923139) (xy 335.926433 -285.956417)
			(xy 335.880209 -285.983104) (xy 335.830524 -286.002604) (xy 335.778487 -286.014481) (xy 335.725262 -286.01847)
			(xy 335.672037 -286.014481) (xy 335.62 -286.002604) (xy 335.570315 -285.983104) (xy 335.524091 -285.956417)
			(xy 335.482361 -285.923139) (xy 335.446057 -285.884012) (xy 335.41599 -285.839912) (xy 335.392832 -285.791823)
			(xy 335.3771 -285.74082) (xy 335.369145 -285.688041) (xy 335.368646 -285.661354) (xy 134.164832 -285.661354)
			(xy 134.164372 -285.686689) (xy 134.156613 -285.736761) (xy 134.141285 -285.785057) (xy 134.118749 -285.830439)
			(xy 134.089536 -285.87184) (xy 134.054334 -285.908285) (xy 134.013971 -285.938915) (xy 133.969397 -285.963011)
			(xy 133.921662 -285.980004) (xy 133.896862 -285.985204) (xy 133.874002 -285.989522) (xy 133.669024 -286.344614)
			(xy 133.676898 -286.366458) (xy 133.685549 -286.392865) (xy 133.694866 -286.447642) (xy 133.69544 -286.475424)
			(xy 333.958946 -286.475424) (xy 333.959445 -286.448737) (xy 333.9674 -286.395958) (xy 333.983132 -286.344955)
			(xy 334.00629 -286.296866) (xy 334.036357 -286.252766) (xy 334.072661 -286.213639) (xy 334.114391 -286.180361)
			(xy 334.160615 -286.153674) (xy 334.2103 -286.134174) (xy 334.262337 -286.122297) (xy 334.315562 -286.118308)
			(xy 334.368787 -286.122297) (xy 334.420824 -286.134174) (xy 334.470509 -286.153674) (xy 334.516733 -286.180361)
			(xy 334.558463 -286.213639) (xy 334.594767 -286.252766) (xy 334.624834 -286.296866) (xy 334.647992 -286.344955)
			(xy 334.663724 -286.395958) (xy 334.671679 -286.448737) (xy 334.672178 -286.4754) (xy 334.899325 -286.4754)
			(xy 334.903302 -286.422333) (xy 334.915143 -286.370452) (xy 334.934583 -286.320915) (xy 334.961189 -286.274828)
			(xy 334.994367 -286.233221) (xy 335.033374 -286.197023) (xy 335.077341 -286.167043) (xy 335.125284 -286.14395)
			(xy 335.176134 -286.12826) (xy 335.228754 -286.120324) (xy 335.255362 -286.119824) (xy 335.280307 -286.120247)
			(xy 335.329707 -286.127215) (xy 335.377649 -286.141021) (xy 335.42319 -286.161392) (xy 335.465436 -286.18793)
			(xy 335.503557 -286.220112) (xy 335.536806 -286.257307) (xy 335.551018 -286.277812) (xy 335.899506 -286.277812)
			(xy 335.91373 -286.257317) (xy 335.946981 -286.220126) (xy 335.985102 -286.187945) (xy 336.027345 -286.161408)
			(xy 336.072883 -286.141034) (xy 336.120821 -286.127223) (xy 336.170218 -286.120247) (xy 336.195162 -286.119824)
			(xy 336.221779 -286.120246) (xy 336.274418 -286.128175) (xy 336.325288 -286.143861) (xy 336.373252 -286.166955)
			(xy 336.417237 -286.196939) (xy 336.456262 -286.233145) (xy 336.489455 -286.274763) (xy 336.516073 -286.320864)
			(xy 336.535523 -286.370417) (xy 336.547369 -286.422315) (xy 336.551348 -286.4754) (xy 336.547369 -286.528485)
			(xy 336.535523 -286.580383) (xy 336.516073 -286.629936) (xy 336.489455 -286.676037) (xy 336.456262 -286.717655)
			(xy 336.417237 -286.753861) (xy 336.373252 -286.783845) (xy 336.325288 -286.806939) (xy 336.274418 -286.822625)
			(xy 336.221779 -286.830554) (xy 336.195162 -286.831024) (xy 336.170217 -286.830606) (xy 336.120815 -286.823639)
			(xy 336.072873 -286.809835) (xy 336.027331 -286.789463) (xy 335.985085 -286.762924) (xy 335.946963 -286.73074)
			(xy 335.913716 -286.693542) (xy 335.899506 -286.673036) (xy 335.551018 -286.673036) (xy 335.536761 -286.693508)
			(xy 335.503518 -286.730702) (xy 335.465404 -286.762886) (xy 335.423165 -286.789427) (xy 335.377632 -286.809804)
			(xy 335.329699 -286.823619) (xy 335.280304 -286.830599) (xy 335.255362 -286.831024) (xy 335.228754 -286.830476)
			(xy 335.176134 -286.82254) (xy 335.125284 -286.80685) (xy 335.077341 -286.783757) (xy 335.033374 -286.753777)
			(xy 334.994367 -286.717579) (xy 334.961189 -286.675972) (xy 334.934583 -286.629885) (xy 334.915143 -286.580348)
			(xy 334.903302 -286.528467) (xy 334.899325 -286.4754) (xy 334.672178 -286.4754) (xy 334.672178 -286.475424)
			(xy 334.672178 -286.475932) (xy 334.671795 -286.499134) (xy 334.665728 -286.545141) (xy 334.653752 -286.589975)
			(xy 334.645254 -286.611568) (xy 334.635602 -286.634682) (xy 334.80756 -286.93237) (xy 334.832452 -286.935672)
			(xy 334.857836 -286.939486) (xy 334.90722 -286.953493) (xy 334.954087 -286.974432) (xy 334.997469 -287.001871)
			(xy 335.036471 -287.035244) (xy 335.070287 -287.073863) (xy 335.098221 -287.116929) (xy 335.119693 -287.163553)
			(xy 335.134263 -287.212774) (xy 335.141628 -287.263574) (xy 335.142078 -287.28924) (xy 335.141579 -287.315927)
			(xy 335.133624 -287.368706) (xy 335.117892 -287.419709) (xy 335.094734 -287.467798) (xy 335.064667 -287.511898)
			(xy 335.028363 -287.551025) (xy 334.986633 -287.584303) (xy 334.940409 -287.61099) (xy 334.890724 -287.63049)
			(xy 334.838687 -287.642367) (xy 334.785462 -287.646356) (xy 334.732237 -287.642367) (xy 334.6802 -287.63049)
			(xy 334.630515 -287.61099) (xy 334.584291 -287.584303) (xy 334.542561 -287.551025) (xy 334.506257 -287.511898)
			(xy 334.47619 -287.467798) (xy 334.453032 -287.419709) (xy 334.4373 -287.368706) (xy 334.429345 -287.315927)
			(xy 334.428846 -287.28924) (xy 334.428846 -287.288732) (xy 334.429247 -287.26553) (xy 334.435307 -287.219524)
			(xy 334.447275 -287.17469) (xy 334.45577 -287.153096) (xy 334.465422 -287.129982) (xy 334.293464 -286.832294)
			(xy 334.268572 -286.828992) (xy 334.243184 -286.825193) (xy 334.193798 -286.811189) (xy 334.146929 -286.79025)
			(xy 334.103545 -286.76281) (xy 334.064542 -286.729435) (xy 334.030725 -286.690814) (xy 334.002792 -286.647745)
			(xy 333.981321 -286.601118) (xy 333.966755 -286.551894) (xy 333.959394 -286.501091) (xy 333.958946 -286.475424)
			(xy 133.69544 -286.475424) (xy 133.694932 -286.501331) (xy 133.686826 -286.552508) (xy 133.670814 -286.601787)
			(xy 133.647291 -286.647954) (xy 133.616835 -286.689873) (xy 133.580197 -286.726511) (xy 133.538278 -286.756967)
			(xy 133.492111 -286.78049) (xy 133.442832 -286.796502) (xy 133.391655 -286.804608) (xy 133.339841 -286.804608)
			(xy 133.288664 -286.796502) (xy 133.239385 -286.78049) (xy 133.193218 -286.756967) (xy 133.151299 -286.726511)
			(xy 133.114661 -286.689873) (xy 133.084205 -286.647954) (xy 133.060682 -286.601787) (xy 133.04467 -286.552508)
			(xy 133.036564 -286.501331) (xy 133.036056 -286.475424) (xy 131.81584 -286.475424) (xy 131.815332 -286.501331)
			(xy 131.807226 -286.552508) (xy 131.791214 -286.601787) (xy 131.767691 -286.647954) (xy 131.737235 -286.689873)
			(xy 131.700597 -286.726511) (xy 131.658678 -286.756967) (xy 131.612511 -286.78049) (xy 131.563232 -286.796502)
			(xy 131.512055 -286.804608) (xy 131.460241 -286.804608) (xy 131.409064 -286.796502) (xy 131.359785 -286.78049)
			(xy 131.313618 -286.756967) (xy 131.271699 -286.726511) (xy 131.235061 -286.689873) (xy 131.204605 -286.647954)
			(xy 131.181082 -286.601787) (xy 131.16507 -286.552508) (xy 131.156964 -286.501331) (xy 131.156456 -286.475424)
			(xy 129.93624 -286.475424) (xy 129.935732 -286.501331) (xy 129.927626 -286.552508) (xy 129.911614 -286.601787)
			(xy 129.888091 -286.647954) (xy 129.857635 -286.689873) (xy 129.820997 -286.726511) (xy 129.779078 -286.756967)
			(xy 129.732911 -286.78049) (xy 129.683632 -286.796502) (xy 129.632455 -286.804608) (xy 129.580641 -286.804608)
			(xy 129.529464 -286.796502) (xy 129.480185 -286.78049) (xy 129.434018 -286.756967) (xy 129.392099 -286.726511)
			(xy 129.355461 -286.689873) (xy 129.325005 -286.647954) (xy 129.301482 -286.601787) (xy 129.28547 -286.552508)
			(xy 129.277364 -286.501331) (xy 129.276856 -286.475424) (xy 128.05664 -286.475424) (xy 128.056132 -286.501331)
			(xy 128.048026 -286.552508) (xy 128.032014 -286.601787) (xy 128.008491 -286.647954) (xy 127.978035 -286.689873)
			(xy 127.941397 -286.726511) (xy 127.899478 -286.756967) (xy 127.853311 -286.78049) (xy 127.804032 -286.796502)
			(xy 127.752855 -286.804608) (xy 127.701041 -286.804608) (xy 127.649864 -286.796502) (xy 127.600585 -286.78049)
			(xy 127.554418 -286.756967) (xy 127.512499 -286.726511) (xy 127.475861 -286.689873) (xy 127.445405 -286.647954)
			(xy 127.421882 -286.601787) (xy 127.40587 -286.552508) (xy 127.397764 -286.501331) (xy 127.397256 -286.475424)
			(xy 126.17704 -286.475424) (xy 126.176532 -286.501331) (xy 126.168426 -286.552508) (xy 126.152414 -286.601787)
			(xy 126.128891 -286.647954) (xy 126.098435 -286.689873) (xy 126.061797 -286.726511) (xy 126.019878 -286.756967)
			(xy 125.973711 -286.78049) (xy 125.924432 -286.796502) (xy 125.873255 -286.804608) (xy 125.821441 -286.804608)
			(xy 125.770264 -286.796502) (xy 125.720985 -286.78049) (xy 125.674818 -286.756967) (xy 125.632899 -286.726511)
			(xy 125.596261 -286.689873) (xy 125.565805 -286.647954) (xy 125.542282 -286.601787) (xy 125.52627 -286.552508)
			(xy 125.518164 -286.501331) (xy 125.517656 -286.475424) (xy 124.29744 -286.475424) (xy 124.296932 -286.501331)
			(xy 124.288826 -286.552508) (xy 124.272814 -286.601787) (xy 124.249291 -286.647954) (xy 124.218835 -286.689873)
			(xy 124.182197 -286.726511) (xy 124.140278 -286.756967) (xy 124.094111 -286.78049) (xy 124.044832 -286.796502)
			(xy 123.993655 -286.804608) (xy 123.941841 -286.804608) (xy 123.890664 -286.796502) (xy 123.841385 -286.78049)
			(xy 123.795218 -286.756967) (xy 123.753299 -286.726511) (xy 123.716661 -286.689873) (xy 123.686205 -286.647954)
			(xy 123.662682 -286.601787) (xy 123.64667 -286.552508) (xy 123.638564 -286.501331) (xy 123.638056 -286.475424)
			(xy 122.41784 -286.475424) (xy 122.417332 -286.501331) (xy 122.409226 -286.552508) (xy 122.393214 -286.601787)
			(xy 122.369691 -286.647954) (xy 122.339235 -286.689873) (xy 122.302597 -286.726511) (xy 122.260678 -286.756967)
			(xy 122.214511 -286.78049) (xy 122.165232 -286.796502) (xy 122.114055 -286.804608) (xy 122.062241 -286.804608)
			(xy 122.011064 -286.796502) (xy 121.961785 -286.78049) (xy 121.915618 -286.756967) (xy 121.873699 -286.726511)
			(xy 121.837061 -286.689873) (xy 121.806605 -286.647954) (xy 121.783082 -286.601787) (xy 121.76707 -286.552508)
			(xy 121.758964 -286.501331) (xy 121.758456 -286.475424) (xy 120.53824 -286.475424) (xy 120.537732 -286.501331)
			(xy 120.529626 -286.552508) (xy 120.513614 -286.601787) (xy 120.490091 -286.647954) (xy 120.459635 -286.689873)
			(xy 120.422997 -286.726511) (xy 120.381078 -286.756967) (xy 120.334911 -286.78049) (xy 120.285632 -286.796502)
			(xy 120.234455 -286.804608) (xy 120.182641 -286.804608) (xy 120.131464 -286.796502) (xy 120.082185 -286.78049)
			(xy 120.036018 -286.756967) (xy 119.994099 -286.726511) (xy 119.957461 -286.689873) (xy 119.927005 -286.647954)
			(xy 119.903482 -286.601787) (xy 119.88747 -286.552508) (xy 119.879364 -286.501331) (xy 119.878856 -286.475424)
			(xy 103.62184 -286.475424) (xy 103.621332 -286.501331) (xy 103.613226 -286.552508) (xy 103.597214 -286.601787)
			(xy 103.573691 -286.647954) (xy 103.543235 -286.689873) (xy 103.506597 -286.726511) (xy 103.464678 -286.756967)
			(xy 103.418511 -286.78049) (xy 103.369232 -286.796502) (xy 103.318055 -286.804608) (xy 103.266241 -286.804608)
			(xy 103.215064 -286.796502) (xy 103.165785 -286.78049) (xy 103.119618 -286.756967) (xy 103.077699 -286.726511)
			(xy 103.041061 -286.689873) (xy 103.010605 -286.647954) (xy 102.987082 -286.601787) (xy 102.97107 -286.552508)
			(xy 102.962964 -286.501331) (xy 102.962456 -286.475424) (xy 102.963053 -286.447707) (xy 102.972374 -286.39306)
			(xy 102.980998 -286.366712) (xy 102.988872 -286.344614) (xy 102.783894 -285.989522) (xy 102.76078 -285.985204)
			(xy 102.735964 -285.980016) (xy 102.688184 -285.963065) (xy 102.643565 -285.938998) (xy 102.603157 -285.908381)
			(xy 102.567916 -285.871936) (xy 102.538671 -285.830525) (xy 102.516113 -285.785123) (xy 102.500775 -285.736802)
			(xy 102.493018 -285.686702) (xy 102.492556 -285.661354) (xy 102.211632 -285.661354) (xy 102.211124 -285.687241)
			(xy 102.203025 -285.738379) (xy 102.187026 -285.787619) (xy 102.16352 -285.833751) (xy 102.133088 -285.875638)
			(xy 102.096478 -285.912248) (xy 102.054591 -285.94268) (xy 102.008459 -285.966186) (xy 101.959219 -285.982185)
			(xy 101.908081 -285.990284) (xy 101.856307 -285.990284) (xy 101.805169 -285.982185) (xy 101.755929 -285.966186)
			(xy 101.709797 -285.94268) (xy 101.66791 -285.912248) (xy 101.6313 -285.875638) (xy 101.600868 -285.833751)
			(xy 101.577362 -285.787619) (xy 101.561363 -285.738379) (xy 101.553264 -285.687241) (xy 101.552756 -285.661354)
			(xy 101.271832 -285.661354) (xy 101.271832 -285.661862) (xy 101.271253 -285.689379) (xy 101.262059 -285.74364)
			(xy 101.253544 -285.769812) (xy 101.245924 -285.79191) (xy 101.451156 -286.147256) (xy 101.474016 -286.151574)
			(xy 101.498827 -286.156786) (xy 101.546604 -286.173734) (xy 101.591223 -286.197799) (xy 101.63163 -286.228413)
			(xy 101.666872 -286.264855) (xy 101.696117 -286.306263) (xy 101.718676 -286.351662) (xy 101.734017 -286.399979)
			(xy 101.741777 -286.450077) (xy 101.74224 -286.475424) (xy 101.741732 -286.501331) (xy 101.733626 -286.552508)
			(xy 101.717614 -286.601787) (xy 101.694091 -286.647954) (xy 101.663635 -286.689873) (xy 101.626997 -286.726511)
			(xy 101.585078 -286.756967) (xy 101.538911 -286.78049) (xy 101.489632 -286.796502) (xy 101.438455 -286.804608)
			(xy 101.386641 -286.804608) (xy 101.335464 -286.796502) (xy 101.286185 -286.78049) (xy 101.240018 -286.756967)
			(xy 101.198099 -286.726511) (xy 101.161461 -286.689873) (xy 101.131005 -286.647954) (xy 101.107482 -286.601787)
			(xy 101.09147 -286.552508) (xy 101.083364 -286.501331) (xy 101.082856 -286.475424) (xy 101.083453 -286.447707)
			(xy 101.092774 -286.39306) (xy 101.101398 -286.366712) (xy 101.109272 -286.344614) (xy 100.904294 -285.989522)
			(xy 100.88118 -285.985204) (xy 100.856364 -285.980016) (xy 100.808584 -285.963065) (xy 100.763965 -285.938998)
			(xy 100.723557 -285.908381) (xy 100.688316 -285.871936) (xy 100.659071 -285.830525) (xy 100.636513 -285.785123)
			(xy 100.621175 -285.736802) (xy 100.613418 -285.686702) (xy 100.612956 -285.661354) (xy 100.332032 -285.661354)
			(xy 100.331524 -285.687241) (xy 100.323425 -285.738379) (xy 100.307426 -285.787619) (xy 100.28392 -285.833751)
			(xy 100.253488 -285.875638) (xy 100.216878 -285.912248) (xy 100.174991 -285.94268) (xy 100.128859 -285.966186)
			(xy 100.079619 -285.982185) (xy 100.028481 -285.990284) (xy 99.976707 -285.990284) (xy 99.925569 -285.982185)
			(xy 99.876329 -285.966186) (xy 99.830197 -285.94268) (xy 99.78831 -285.912248) (xy 99.7517 -285.875638)
			(xy 99.721268 -285.833751) (xy 99.697762 -285.787619) (xy 99.681763 -285.738379) (xy 99.673664 -285.687241)
			(xy 99.673156 -285.661354) (xy 99.392232 -285.661354) (xy 99.392232 -285.661862) (xy 99.391653 -285.689379)
			(xy 99.382459 -285.74364) (xy 99.373944 -285.769812) (xy 99.366324 -285.79191) (xy 99.571556 -286.147256)
			(xy 99.594416 -286.151574) (xy 99.619227 -286.156786) (xy 99.667004 -286.173734) (xy 99.711623 -286.197799)
			(xy 99.75203 -286.228413) (xy 99.787272 -286.264855) (xy 99.816517 -286.306263) (xy 99.839076 -286.351662)
			(xy 99.854417 -286.399979) (xy 99.862177 -286.450077) (xy 99.86264 -286.475424) (xy 99.862132 -286.501331)
			(xy 99.854026 -286.552508) (xy 99.838014 -286.601787) (xy 99.814491 -286.647954) (xy 99.784035 -286.689873)
			(xy 99.747397 -286.726511) (xy 99.705478 -286.756967) (xy 99.659311 -286.78049) (xy 99.610032 -286.796502)
			(xy 99.558855 -286.804608) (xy 99.507041 -286.804608) (xy 99.455864 -286.796502) (xy 99.406585 -286.78049)
			(xy 99.360418 -286.756967) (xy 99.318499 -286.726511) (xy 99.281861 -286.689873) (xy 99.251405 -286.647954)
			(xy 99.227882 -286.601787) (xy 99.21187 -286.552508) (xy 99.203764 -286.501331) (xy 99.203256 -286.475424)
			(xy 99.203853 -286.447707) (xy 99.213174 -286.39306) (xy 99.221798 -286.366712) (xy 99.229672 -286.344614)
			(xy 99.024694 -285.989522) (xy 99.00158 -285.985204) (xy 98.976764 -285.980016) (xy 98.928984 -285.963065)
			(xy 98.884365 -285.938998) (xy 98.843957 -285.908381) (xy 98.808716 -285.871936) (xy 98.779471 -285.830525)
			(xy 98.756913 -285.785123) (xy 98.741575 -285.736802) (xy 98.733818 -285.686702) (xy 98.733356 -285.661354)
			(xy 98.452432 -285.661354) (xy 98.451924 -285.687241) (xy 98.443825 -285.738379) (xy 98.427826 -285.787619)
			(xy 98.40432 -285.833751) (xy 98.373888 -285.875638) (xy 98.337278 -285.912248) (xy 98.295391 -285.94268)
			(xy 98.249259 -285.966186) (xy 98.200019 -285.982185) (xy 98.148881 -285.990284) (xy 98.097107 -285.990284)
			(xy 98.045969 -285.982185) (xy 97.996729 -285.966186) (xy 97.950597 -285.94268) (xy 97.90871 -285.912248)
			(xy 97.8721 -285.875638) (xy 97.841668 -285.833751) (xy 97.818162 -285.787619) (xy 97.802163 -285.738379)
			(xy 97.794064 -285.687241) (xy 97.793556 -285.661354) (xy 97.512632 -285.661354) (xy 97.512632 -285.661862)
			(xy 97.512053 -285.689379) (xy 97.502859 -285.74364) (xy 97.494344 -285.769812) (xy 97.486724 -285.79191)
			(xy 97.691956 -286.147256) (xy 97.714816 -286.151574) (xy 97.739627 -286.156786) (xy 97.787404 -286.173734)
			(xy 97.832023 -286.197799) (xy 97.87243 -286.228413) (xy 97.907672 -286.264855) (xy 97.936917 -286.306263)
			(xy 97.959476 -286.351662) (xy 97.974817 -286.399979) (xy 97.982577 -286.450077) (xy 97.98304 -286.475424)
			(xy 97.982532 -286.501331) (xy 97.974426 -286.552508) (xy 97.958414 -286.601787) (xy 97.934891 -286.647954)
			(xy 97.904435 -286.689873) (xy 97.867797 -286.726511) (xy 97.825878 -286.756967) (xy 97.779711 -286.78049)
			(xy 97.730432 -286.796502) (xy 97.679255 -286.804608) (xy 97.627441 -286.804608) (xy 97.576264 -286.796502)
			(xy 97.526985 -286.78049) (xy 97.480818 -286.756967) (xy 97.438899 -286.726511) (xy 97.402261 -286.689873)
			(xy 97.371805 -286.647954) (xy 97.348282 -286.601787) (xy 97.33227 -286.552508) (xy 97.324164 -286.501331)
			(xy 97.323656 -286.475424) (xy 97.324253 -286.447707) (xy 97.333574 -286.39306) (xy 97.342198 -286.366712)
			(xy 97.350072 -286.344614) (xy 97.145094 -285.989522) (xy 97.12198 -285.985204) (xy 97.097164 -285.980016)
			(xy 97.049384 -285.963065) (xy 97.004765 -285.938998) (xy 96.964357 -285.908381) (xy 96.929116 -285.871936)
			(xy 96.899871 -285.830525) (xy 96.877313 -285.785123) (xy 96.861975 -285.736802) (xy 96.854218 -285.686702)
			(xy 96.853756 -285.661354) (xy 96.572832 -285.661354) (xy 96.572324 -285.687241) (xy 96.564225 -285.738379)
			(xy 96.548226 -285.787619) (xy 96.52472 -285.833751) (xy 96.494288 -285.875638) (xy 96.457678 -285.912248)
			(xy 96.415791 -285.94268) (xy 96.369659 -285.966186) (xy 96.320419 -285.982185) (xy 96.269281 -285.990284)
			(xy 96.217507 -285.990284) (xy 96.166369 -285.982185) (xy 96.117129 -285.966186) (xy 96.070997 -285.94268)
			(xy 96.02911 -285.912248) (xy 95.9925 -285.875638) (xy 95.962068 -285.833751) (xy 95.938562 -285.787619)
			(xy 95.922563 -285.738379) (xy 95.914464 -285.687241) (xy 95.913956 -285.661354) (xy 95.633032 -285.661354)
			(xy 95.633032 -285.661862) (xy 95.632453 -285.689379) (xy 95.623259 -285.74364) (xy 95.614744 -285.769812)
			(xy 95.607124 -285.79191) (xy 95.812356 -286.147256) (xy 95.835216 -286.151574) (xy 95.860027 -286.156786)
			(xy 95.907804 -286.173734) (xy 95.952423 -286.197799) (xy 95.99283 -286.228413) (xy 96.028072 -286.264855)
			(xy 96.057317 -286.306263) (xy 96.079876 -286.351662) (xy 96.095217 -286.399979) (xy 96.102977 -286.450077)
			(xy 96.10344 -286.475424) (xy 96.102932 -286.501331) (xy 96.094826 -286.552508) (xy 96.078814 -286.601787)
			(xy 96.055291 -286.647954) (xy 96.024835 -286.689873) (xy 95.988197 -286.726511) (xy 95.946278 -286.756967)
			(xy 95.900111 -286.78049) (xy 95.850832 -286.796502) (xy 95.799655 -286.804608) (xy 95.747841 -286.804608)
			(xy 95.696664 -286.796502) (xy 95.647385 -286.78049) (xy 95.601218 -286.756967) (xy 95.559299 -286.726511)
			(xy 95.522661 -286.689873) (xy 95.492205 -286.647954) (xy 95.468682 -286.601787) (xy 95.45267 -286.552508)
			(xy 95.444564 -286.501331) (xy 95.444056 -286.475424) (xy 95.444653 -286.447707) (xy 95.453974 -286.39306)
			(xy 95.462598 -286.366712) (xy 95.470472 -286.344614) (xy 95.265494 -285.989522) (xy 95.24238 -285.985204)
			(xy 95.217564 -285.980016) (xy 95.169784 -285.963065) (xy 95.125165 -285.938998) (xy 95.084757 -285.908381)
			(xy 95.049516 -285.871936) (xy 95.020271 -285.830525) (xy 94.997713 -285.785123) (xy 94.982375 -285.736802)
			(xy 94.974618 -285.686702) (xy 94.974156 -285.661354) (xy 94.693232 -285.661354) (xy 94.692724 -285.687241)
			(xy 94.684625 -285.738379) (xy 94.668626 -285.787619) (xy 94.64512 -285.833751) (xy 94.614688 -285.875638)
			(xy 94.578078 -285.912248) (xy 94.536191 -285.94268) (xy 94.490059 -285.966186) (xy 94.440819 -285.982185)
			(xy 94.389681 -285.990284) (xy 94.337907 -285.990284) (xy 94.286769 -285.982185) (xy 94.237529 -285.966186)
			(xy 94.191397 -285.94268) (xy 94.14951 -285.912248) (xy 94.1129 -285.875638) (xy 94.082468 -285.833751)
			(xy 94.058962 -285.787619) (xy 94.042963 -285.738379) (xy 94.034864 -285.687241) (xy 94.034356 -285.661354)
			(xy 93.753432 -285.661354) (xy 93.753432 -285.661862) (xy 93.752853 -285.689379) (xy 93.743659 -285.74364)
			(xy 93.735144 -285.769812) (xy 93.727524 -285.79191) (xy 93.932756 -286.147256) (xy 93.955616 -286.151574)
			(xy 93.980427 -286.156786) (xy 94.028204 -286.173734) (xy 94.072823 -286.197799) (xy 94.11323 -286.228413)
			(xy 94.148472 -286.264855) (xy 94.177717 -286.306263) (xy 94.200276 -286.351662) (xy 94.215617 -286.399979)
			(xy 94.223377 -286.450077) (xy 94.22384 -286.475424) (xy 94.223332 -286.501331) (xy 94.215226 -286.552508)
			(xy 94.199214 -286.601787) (xy 94.175691 -286.647954) (xy 94.145235 -286.689873) (xy 94.108597 -286.726511)
			(xy 94.066678 -286.756967) (xy 94.020511 -286.78049) (xy 93.971232 -286.796502) (xy 93.920055 -286.804608)
			(xy 93.868241 -286.804608) (xy 93.817064 -286.796502) (xy 93.767785 -286.78049) (xy 93.721618 -286.756967)
			(xy 93.679699 -286.726511) (xy 93.643061 -286.689873) (xy 93.612605 -286.647954) (xy 93.589082 -286.601787)
			(xy 93.57307 -286.552508) (xy 93.564964 -286.501331) (xy 93.564456 -286.475424) (xy 93.565053 -286.447707)
			(xy 93.574374 -286.39306) (xy 93.582998 -286.366712) (xy 93.590872 -286.344614) (xy 93.385894 -285.989522)
			(xy 93.36278 -285.985204) (xy 93.337964 -285.980016) (xy 93.290184 -285.963065) (xy 93.245565 -285.938998)
			(xy 93.205157 -285.908381) (xy 93.169916 -285.871936) (xy 93.140671 -285.830525) (xy 93.118113 -285.785123)
			(xy 93.102775 -285.736802) (xy 93.095018 -285.686702) (xy 93.094556 -285.661354) (xy 92.813632 -285.661354)
			(xy 92.813124 -285.687241) (xy 92.805025 -285.738379) (xy 92.789026 -285.787619) (xy 92.76552 -285.833751)
			(xy 92.735088 -285.875638) (xy 92.698478 -285.912248) (xy 92.656591 -285.94268) (xy 92.610459 -285.966186)
			(xy 92.561219 -285.982185) (xy 92.510081 -285.990284) (xy 92.458307 -285.990284) (xy 92.407169 -285.982185)
			(xy 92.357929 -285.966186) (xy 92.311797 -285.94268) (xy 92.26991 -285.912248) (xy 92.2333 -285.875638)
			(xy 92.202868 -285.833751) (xy 92.179362 -285.787619) (xy 92.163363 -285.738379) (xy 92.155264 -285.687241)
			(xy 92.154756 -285.661354) (xy 91.87434 -285.661354) (xy 91.873738 -285.689071) (xy 91.86442 -285.743718)
			(xy 91.855798 -285.770066) (xy 91.847924 -285.792164) (xy 92.053156 -286.147256) (xy 92.076016 -286.151574)
			(xy 92.100827 -286.156786) (xy 92.148604 -286.173734) (xy 92.193223 -286.197799) (xy 92.23363 -286.228413)
			(xy 92.268872 -286.264855) (xy 92.298117 -286.306263) (xy 92.320676 -286.351662) (xy 92.336017 -286.399979)
			(xy 92.343777 -286.450077) (xy 92.34424 -286.475424) (xy 92.343732 -286.501331) (xy 92.335626 -286.552508)
			(xy 92.319614 -286.601787) (xy 92.296091 -286.647954) (xy 92.265635 -286.689873) (xy 92.228997 -286.726511)
			(xy 92.187078 -286.756967) (xy 92.140911 -286.78049) (xy 92.091632 -286.796502) (xy 92.040455 -286.804608)
			(xy 91.988641 -286.804608) (xy 91.937464 -286.796502) (xy 91.888185 -286.78049) (xy 91.842018 -286.756967)
			(xy 91.800099 -286.726511) (xy 91.763461 -286.689873) (xy 91.733005 -286.647954) (xy 91.709482 -286.601787)
			(xy 91.69347 -286.552508) (xy 91.685364 -286.501331) (xy 91.684856 -286.475424) (xy 91.685453 -286.447707)
			(xy 91.694774 -286.39306) (xy 91.703398 -286.366712) (xy 91.711272 -286.344614) (xy 91.50604 -285.989522)
			(xy 91.48318 -285.985204) (xy 91.458364 -285.980016) (xy 91.410584 -285.963065) (xy 91.365965 -285.938998)
			(xy 91.325557 -285.908381) (xy 91.290316 -285.871936) (xy 91.261071 -285.830525) (xy 91.238513 -285.785123)
			(xy 91.223175 -285.736802) (xy 91.215418 -285.686702) (xy 91.214956 -285.661354) (xy 90.93454 -285.661354)
			(xy 90.934032 -285.687261) (xy 90.925926 -285.738438) (xy 90.909914 -285.787717) (xy 90.886391 -285.833884)
			(xy 90.855935 -285.875803) (xy 90.819297 -285.912441) (xy 90.777378 -285.942897) (xy 90.731211 -285.96642)
			(xy 90.681932 -285.982432) (xy 90.630755 -285.990538) (xy 90.578941 -285.990538) (xy 90.527764 -285.982432)
			(xy 90.478485 -285.96642) (xy 90.432318 -285.942897) (xy 90.390399 -285.912441) (xy 90.353761 -285.875803)
			(xy 90.323305 -285.833884) (xy 90.299782 -285.787717) (xy 90.28377 -285.738438) (xy 90.275664 -285.687261)
			(xy 90.275156 -285.661354) (xy 89.994232 -285.661354) (xy 89.993689 -285.689062) (xy 89.984503 -285.743708)
			(xy 89.975944 -285.770066) (xy 89.96807 -285.792164) (xy 90.173302 -286.147256) (xy 90.196162 -286.151574)
			(xy 90.220961 -286.156781) (xy 90.268701 -286.173765) (xy 90.31328 -286.197855) (xy 90.353647 -286.228483)
			(xy 90.388851 -286.264927) (xy 90.418064 -286.30633) (xy 90.440597 -286.351715) (xy 90.455919 -286.400014)
			(xy 90.46367 -286.450088) (xy 90.464132 -286.475424) (xy 90.463624 -286.501311) (xy 90.455525 -286.552449)
			(xy 90.439526 -286.601689) (xy 90.41602 -286.647821) (xy 90.385588 -286.689708) (xy 90.348978 -286.726318)
			(xy 90.307091 -286.75675) (xy 90.260959 -286.780256) (xy 90.211719 -286.796255) (xy 90.160581 -286.804354)
			(xy 90.108807 -286.804354) (xy 90.057669 -286.796255) (xy 90.008429 -286.780256) (xy 89.962297 -286.75675)
			(xy 89.92041 -286.726318) (xy 89.8838 -286.689708) (xy 89.853368 -286.647821) (xy 89.829862 -286.601689)
			(xy 89.813863 -286.552449) (xy 89.805764 -286.501311) (xy 89.805256 -286.475424) (xy 89.805793 -286.447716)
			(xy 89.814983 -286.393069) (xy 89.823544 -286.366712) (xy 89.831418 -286.344614) (xy 89.626186 -285.989522)
			(xy 89.603326 -285.985204) (xy 89.57852 -285.980026) (xy 89.530779 -285.963039) (xy 89.486199 -285.938946)
			(xy 89.445832 -285.908314) (xy 89.410627 -285.871866) (xy 89.381416 -285.83046) (xy 89.358884 -285.785071)
			(xy 89.343564 -285.736769) (xy 89.335817 -285.686691) (xy 89.335356 -285.661354) (xy 88.14181 -285.661354)
			(xy 88.141311 -285.688041) (xy 88.133356 -285.74082) (xy 88.117624 -285.791823) (xy 88.094466 -285.839912)
			(xy 88.064399 -285.884012) (xy 88.028095 -285.923139) (xy 87.986365 -285.956417) (xy 87.940141 -285.983104)
			(xy 87.890456 -286.002604) (xy 87.838419 -286.014481) (xy 87.785194 -286.01847) (xy 87.731969 -286.014481)
			(xy 87.679932 -286.002604) (xy 87.630247 -285.983104) (xy 87.584023 -285.956417) (xy 87.542293 -285.923139)
			(xy 87.505989 -285.884012) (xy 87.475922 -285.839912) (xy 87.452764 -285.791823) (xy 87.437032 -285.74082)
			(xy 87.429077 -285.688041) (xy 87.428578 -285.661354) (xy 2.509012 -285.661354) (xy 2.509012 -286.475424)
			(xy 86.018878 -286.475424) (xy 86.019377 -286.448737) (xy 86.027332 -286.395958) (xy 86.043064 -286.344955)
			(xy 86.066222 -286.296866) (xy 86.096289 -286.252766) (xy 86.132593 -286.213639) (xy 86.174323 -286.180361)
			(xy 86.220547 -286.153674) (xy 86.270232 -286.134174) (xy 86.322269 -286.122297) (xy 86.375494 -286.118308)
			(xy 86.428719 -286.122297) (xy 86.480756 -286.134174) (xy 86.530441 -286.153674) (xy 86.576665 -286.180361)
			(xy 86.618395 -286.213639) (xy 86.654699 -286.252766) (xy 86.684766 -286.296866) (xy 86.707924 -286.344955)
			(xy 86.723656 -286.395958) (xy 86.731611 -286.448737) (xy 86.73211 -286.4754) (xy 86.959225 -286.4754)
			(xy 86.963202 -286.42233) (xy 86.975045 -286.370446) (xy 86.994487 -286.320907) (xy 87.021096 -286.274818)
			(xy 87.054277 -286.23321) (xy 87.093288 -286.197012) (xy 87.137259 -286.167032) (xy 87.185207 -286.143941)
			(xy 87.236061 -286.128254) (xy 87.288685 -286.120322) (xy 87.315294 -286.119824) (xy 87.34024 -286.120223)
			(xy 87.389641 -286.127195) (xy 87.437583 -286.141005) (xy 87.483124 -286.161381) (xy 87.52537 -286.187922)
			(xy 87.563491 -286.220107) (xy 87.596739 -286.257306) (xy 87.61095 -286.277812) (xy 87.959438 -286.277812)
			(xy 87.973642 -286.257302) (xy 88.006896 -286.220111) (xy 88.04502 -286.187932) (xy 88.087267 -286.161396)
			(xy 88.132808 -286.141025) (xy 88.180749 -286.127217) (xy 88.230149 -286.120245) (xy 88.255094 -286.119824)
			(xy 88.281709 -286.120248) (xy 88.334345 -286.128181) (xy 88.385211 -286.14387) (xy 88.43317 -286.166965)
			(xy 88.477152 -286.196951) (xy 88.516173 -286.233156) (xy 88.549362 -286.274773) (xy 88.575977 -286.320872)
			(xy 88.595425 -286.370423) (xy 88.60727 -286.422318) (xy 88.611248 -286.4754) (xy 88.60727 -286.528482)
			(xy 88.595425 -286.580377) (xy 88.575977 -286.629928) (xy 88.549362 -286.676027) (xy 88.516173 -286.717644)
			(xy 88.477152 -286.753849) (xy 88.43317 -286.783835) (xy 88.385211 -286.80693) (xy 88.334345 -286.822619)
			(xy 88.281709 -286.830552) (xy 88.255094 -286.831024) (xy 88.23015 -286.830581) (xy 88.180749 -286.823619)
			(xy 88.132807 -286.809819) (xy 88.087265 -286.789451) (xy 88.045019 -286.762916) (xy 88.006897 -286.730736)
			(xy 87.973649 -286.693541) (xy 87.959438 -286.673036) (xy 87.61095 -286.673036) (xy 87.596737 -286.69354)
			(xy 87.563487 -286.730733) (xy 87.525364 -286.762914) (xy 87.483119 -286.789452) (xy 87.437579 -286.809824)
			(xy 87.389638 -286.823632) (xy 87.340239 -286.830604) (xy 87.315294 -286.831024) (xy 87.288685 -286.830478)
			(xy 87.236061 -286.822546) (xy 87.185207 -286.806859) (xy 87.137259 -286.783768) (xy 87.093288 -286.753788)
			(xy 87.054277 -286.71759) (xy 87.021096 -286.675982) (xy 86.994487 -286.629893) (xy 86.975045 -286.580354)
			(xy 86.963202 -286.52847) (xy 86.959225 -286.4754) (xy 86.73211 -286.4754) (xy 86.73211 -286.475424)
			(xy 86.73211 -286.475932) (xy 86.731732 -286.499134) (xy 86.725664 -286.545142) (xy 86.713686 -286.589975)
			(xy 86.705186 -286.611568) (xy 86.695534 -286.634682) (xy 86.867492 -286.93237) (xy 86.892384 -286.935672)
			(xy 86.91776 -286.93954) (xy 86.967143 -286.953537) (xy 87.01401 -286.974468) (xy 87.057393 -287.0019)
			(xy 87.096397 -287.035267) (xy 87.130215 -287.073879) (xy 87.15815 -287.116941) (xy 87.179624 -287.163561)
			(xy 87.194194 -287.212778) (xy 87.201559 -287.263576) (xy 87.20201 -287.28924) (xy 87.201511 -287.315927)
			(xy 87.193556 -287.368706) (xy 87.177824 -287.419709) (xy 87.154666 -287.467798) (xy 87.124599 -287.511898)
			(xy 87.088295 -287.551025) (xy 87.046565 -287.584303) (xy 87.000341 -287.61099) (xy 86.950656 -287.63049)
			(xy 86.898619 -287.642367) (xy 86.845394 -287.646356) (xy 86.792169 -287.642367) (xy 86.740132 -287.63049)
			(xy 86.690447 -287.61099) (xy 86.644223 -287.584303) (xy 86.602493 -287.551025) (xy 86.566189 -287.511898)
			(xy 86.536122 -287.467798) (xy 86.512964 -287.419709) (xy 86.497232 -287.368706) (xy 86.489277 -287.315927)
			(xy 86.488778 -287.28924) (xy 86.488778 -287.288732) (xy 86.489177 -287.26553) (xy 86.495237 -287.219524)
			(xy 86.507206 -287.17469) (xy 86.515702 -287.153096) (xy 86.525354 -287.129982) (xy 86.353396 -286.832294)
			(xy 86.328504 -286.828992) (xy 86.303121 -286.825168) (xy 86.253735 -286.811168) (xy 86.206865 -286.790233)
			(xy 86.163481 -286.762796) (xy 86.124477 -286.729424) (xy 86.090659 -286.690806) (xy 86.062726 -286.647739)
			(xy 86.041254 -286.601114) (xy 86.026687 -286.551892) (xy 86.019326 -286.50109) (xy 86.018878 -286.475424)
			(xy 2.509012 -286.475424) (xy 2.509012 -288.917126) (xy 88.395556 -288.917126) (xy 88.396056 -288.891781)
			(xy 88.403825 -288.84169) (xy 88.419169 -288.793377) (xy 88.441727 -288.747983) (xy 88.470967 -288.706576)
			(xy 88.506199 -288.670131) (xy 88.546595 -288.639509) (xy 88.591201 -288.61543) (xy 88.638966 -288.598461)
			(xy 88.66378 -288.593276) (xy 88.68664 -288.588958) (xy 88.891618 -288.233866) (xy 88.883744 -288.212022)
			(xy 88.875171 -288.185601) (xy 88.86597 -288.130828) (xy 88.865456 -288.103056) (xy 88.865964 -288.077169)
			(xy 88.874063 -288.026031) (xy 88.890062 -287.976791) (xy 88.913568 -287.930659) (xy 88.944 -287.888772)
			(xy 88.98061 -287.852162) (xy 89.022497 -287.82173) (xy 89.068629 -287.798224) (xy 89.117869 -287.782225)
			(xy 89.169007 -287.774126) (xy 89.220781 -287.774126) (xy 89.271919 -287.782225) (xy 89.321159 -287.798224)
			(xy 89.367291 -287.82173) (xy 89.409178 -287.852162) (xy 89.445788 -287.888772) (xy 89.47622 -287.930659)
			(xy 89.499726 -287.976791) (xy 89.515725 -288.026031) (xy 89.523824 -288.077169) (xy 89.524332 -288.103056)
			(xy 89.523874 -288.128391) (xy 89.516115 -288.178463) (xy 89.500786 -288.226759) (xy 89.47825 -288.272141)
			(xy 89.449037 -288.313542) (xy 89.413835 -288.349987) (xy 89.373471 -288.380617) (xy 89.328897 -288.404713)
			(xy 89.281162 -288.421706) (xy 89.256362 -288.426906) (xy 89.233502 -288.431224) (xy 89.028524 -288.786316)
			(xy 89.036398 -288.80816) (xy 89.045049 -288.834567) (xy 89.054366 -288.889344) (xy 89.05494 -288.917126)
			(xy 90.275156 -288.917126) (xy 90.275656 -288.891781) (xy 90.283425 -288.84169) (xy 90.298769 -288.793377)
			(xy 90.321327 -288.747983) (xy 90.350567 -288.706576) (xy 90.385799 -288.670131) (xy 90.426195 -288.639509)
			(xy 90.470801 -288.61543) (xy 90.518566 -288.598461) (xy 90.54338 -288.593276) (xy 90.56624 -288.588958)
			(xy 90.771218 -288.233866) (xy 90.763344 -288.212022) (xy 90.754771 -288.185601) (xy 90.74557 -288.130828)
			(xy 90.745056 -288.103056) (xy 90.745564 -288.077169) (xy 90.753663 -288.026031) (xy 90.769662 -287.976791)
			(xy 90.793168 -287.930659) (xy 90.8236 -287.888772) (xy 90.86021 -287.852162) (xy 90.902097 -287.82173)
			(xy 90.948229 -287.798224) (xy 90.997469 -287.782225) (xy 91.048607 -287.774126) (xy 91.100381 -287.774126)
			(xy 91.151519 -287.782225) (xy 91.200759 -287.798224) (xy 91.246891 -287.82173) (xy 91.288778 -287.852162)
			(xy 91.325388 -287.888772) (xy 91.35582 -287.930659) (xy 91.379326 -287.976791) (xy 91.395325 -288.026031)
			(xy 91.403424 -288.077169) (xy 91.403932 -288.103056) (xy 91.403474 -288.128391) (xy 91.395715 -288.178463)
			(xy 91.380386 -288.226759) (xy 91.35785 -288.272141) (xy 91.328637 -288.313542) (xy 91.293435 -288.349987)
			(xy 91.253071 -288.380617) (xy 91.208497 -288.404713) (xy 91.160762 -288.421706) (xy 91.135962 -288.426906)
			(xy 91.113102 -288.431224) (xy 90.908124 -288.786316) (xy 90.915998 -288.80816) (xy 90.924649 -288.834567)
			(xy 90.933966 -288.889344) (xy 90.93454 -288.917126) (xy 91.214956 -288.917126) (xy 91.215464 -288.891219)
			(xy 91.22357 -288.840042) (xy 91.239582 -288.790763) (xy 91.263105 -288.744596) (xy 91.293561 -288.702677)
			(xy 91.330199 -288.666039) (xy 91.372118 -288.635583) (xy 91.418285 -288.61206) (xy 91.467564 -288.596048)
			(xy 91.518741 -288.587942) (xy 91.570555 -288.587942) (xy 91.621732 -288.596048) (xy 91.671011 -288.61206)
			(xy 91.717178 -288.635583) (xy 91.759097 -288.666039) (xy 91.795735 -288.702677) (xy 91.826191 -288.744596)
			(xy 91.849714 -288.790763) (xy 91.865726 -288.840042) (xy 91.873832 -288.891219) (xy 91.87434 -288.917126)
			(xy 92.154756 -288.917126) (xy 92.155256 -288.891781) (xy 92.163025 -288.84169) (xy 92.178369 -288.793377)
			(xy 92.200927 -288.747983) (xy 92.230167 -288.706576) (xy 92.265399 -288.670131) (xy 92.305795 -288.639509)
			(xy 92.350401 -288.61543) (xy 92.398166 -288.598461) (xy 92.42298 -288.593276) (xy 92.44584 -288.588958)
			(xy 92.651072 -288.233866) (xy 92.643198 -288.211768) (xy 92.634576 -288.185419) (xy 92.625249 -288.130773)
			(xy 92.624656 -288.103056) (xy 92.625164 -288.077149) (xy 92.63327 -288.025972) (xy 92.649282 -287.976693)
			(xy 92.672805 -287.930526) (xy 92.703261 -287.888607) (xy 92.739899 -287.851969) (xy 92.781818 -287.821513)
			(xy 92.827985 -287.79799) (xy 92.877264 -287.781978) (xy 92.928441 -287.773872) (xy 92.980255 -287.773872)
			(xy 93.031432 -287.781978) (xy 93.080711 -287.79799) (xy 93.126878 -287.821513) (xy 93.168797 -287.851969)
			(xy 93.205435 -287.888607) (xy 93.235891 -287.930526) (xy 93.259414 -287.976693) (xy 93.275426 -288.025972)
			(xy 93.283532 -288.077149) (xy 93.28404 -288.103056) (xy 93.283618 -288.128404) (xy 93.275836 -288.178499)
			(xy 93.26048 -288.226813) (xy 93.237912 -288.272208) (xy 93.208662 -288.313614) (xy 93.173421 -288.350057)
			(xy 93.133018 -288.380678) (xy 93.088405 -288.404755) (xy 93.040632 -288.421722) (xy 93.015816 -288.426906)
			(xy 92.992956 -288.431224) (xy 92.787724 -288.786316) (xy 92.795598 -288.808414) (xy 92.80424 -288.834757)
			(xy 92.813554 -288.889407) (xy 92.81414 -288.917126) (xy 93.094556 -288.917126) (xy 93.095064 -288.891219)
			(xy 93.10317 -288.840042) (xy 93.119182 -288.790763) (xy 93.142705 -288.744596) (xy 93.173161 -288.702677)
			(xy 93.209799 -288.666039) (xy 93.251718 -288.635583) (xy 93.297885 -288.61206) (xy 93.347164 -288.596048)
			(xy 93.398341 -288.587942) (xy 93.450155 -288.587942) (xy 93.501332 -288.596048) (xy 93.550611 -288.61206)
			(xy 93.596778 -288.635583) (xy 93.638697 -288.666039) (xy 93.675335 -288.702677) (xy 93.705791 -288.744596)
			(xy 93.729314 -288.790763) (xy 93.745326 -288.840042) (xy 93.753432 -288.891219) (xy 93.75394 -288.917126)
			(xy 94.034356 -288.917126) (xy 94.034856 -288.891781) (xy 94.042625 -288.84169) (xy 94.057969 -288.793377)
			(xy 94.080527 -288.747983) (xy 94.109767 -288.706576) (xy 94.144999 -288.670131) (xy 94.185395 -288.639509)
			(xy 94.230001 -288.61543) (xy 94.277766 -288.598461) (xy 94.30258 -288.593276) (xy 94.32544 -288.588958)
			(xy 94.530672 -288.233866) (xy 94.522798 -288.211768) (xy 94.514176 -288.185419) (xy 94.504849 -288.130773)
			(xy 94.504256 -288.103056) (xy 94.504764 -288.077149) (xy 94.51287 -288.025972) (xy 94.528882 -287.976693)
			(xy 94.552405 -287.930526) (xy 94.582861 -287.888607) (xy 94.619499 -287.851969) (xy 94.661418 -287.821513)
			(xy 94.707585 -287.79799) (xy 94.756864 -287.781978) (xy 94.808041 -287.773872) (xy 94.859855 -287.773872)
			(xy 94.911032 -287.781978) (xy 94.960311 -287.79799) (xy 95.006478 -287.821513) (xy 95.048397 -287.851969)
			(xy 95.085035 -287.888607) (xy 95.115491 -287.930526) (xy 95.139014 -287.976693) (xy 95.155026 -288.025972)
			(xy 95.163132 -288.077149) (xy 95.16364 -288.103056) (xy 95.163218 -288.128404) (xy 95.155436 -288.178499)
			(xy 95.14008 -288.226813) (xy 95.117512 -288.272208) (xy 95.088262 -288.313614) (xy 95.053021 -288.350057)
			(xy 95.012618 -288.380678) (xy 94.968005 -288.404755) (xy 94.920232 -288.421722) (xy 94.895416 -288.426906)
			(xy 94.872556 -288.431224) (xy 94.667324 -288.786316) (xy 94.675198 -288.808414) (xy 94.68384 -288.834757)
			(xy 94.693154 -288.889407) (xy 94.69374 -288.917126) (xy 94.974156 -288.917126) (xy 94.974664 -288.891219)
			(xy 94.98277 -288.840042) (xy 94.998782 -288.790763) (xy 95.022305 -288.744596) (xy 95.052761 -288.702677)
			(xy 95.089399 -288.666039) (xy 95.131318 -288.635583) (xy 95.177485 -288.61206) (xy 95.226764 -288.596048)
			(xy 95.277941 -288.587942) (xy 95.329755 -288.587942) (xy 95.380932 -288.596048) (xy 95.430211 -288.61206)
			(xy 95.476378 -288.635583) (xy 95.518297 -288.666039) (xy 95.554935 -288.702677) (xy 95.585391 -288.744596)
			(xy 95.608914 -288.790763) (xy 95.624926 -288.840042) (xy 95.633032 -288.891219) (xy 95.63354 -288.917126)
			(xy 95.913956 -288.917126) (xy 95.914456 -288.891781) (xy 95.922225 -288.84169) (xy 95.937569 -288.793377)
			(xy 95.960127 -288.747983) (xy 95.989367 -288.706576) (xy 96.024599 -288.670131) (xy 96.064995 -288.639509)
			(xy 96.109601 -288.61543) (xy 96.157366 -288.598461) (xy 96.18218 -288.593276) (xy 96.20504 -288.588958)
			(xy 96.410272 -288.233866) (xy 96.402398 -288.211768) (xy 96.393776 -288.185419) (xy 96.384449 -288.130773)
			(xy 96.383856 -288.103056) (xy 96.384364 -288.077149) (xy 96.39247 -288.025972) (xy 96.408482 -287.976693)
			(xy 96.432005 -287.930526) (xy 96.462461 -287.888607) (xy 96.499099 -287.851969) (xy 96.541018 -287.821513)
			(xy 96.587185 -287.79799) (xy 96.636464 -287.781978) (xy 96.687641 -287.773872) (xy 96.739455 -287.773872)
			(xy 96.790632 -287.781978) (xy 96.839911 -287.79799) (xy 96.886078 -287.821513) (xy 96.927997 -287.851969)
			(xy 96.964635 -287.888607) (xy 96.995091 -287.930526) (xy 97.018614 -287.976693) (xy 97.034626 -288.025972)
			(xy 97.042732 -288.077149) (xy 97.04324 -288.103056) (xy 97.042818 -288.128404) (xy 97.035036 -288.178499)
			(xy 97.01968 -288.226813) (xy 96.997112 -288.272208) (xy 96.967862 -288.313614) (xy 96.932621 -288.350057)
			(xy 96.892218 -288.380678) (xy 96.847605 -288.404755) (xy 96.799832 -288.421722) (xy 96.775016 -288.426906)
			(xy 96.752156 -288.431224) (xy 96.546924 -288.786316) (xy 96.554798 -288.808414) (xy 96.56344 -288.834757)
			(xy 96.572754 -288.889407) (xy 96.57334 -288.917126) (xy 96.853756 -288.917126) (xy 96.854264 -288.891219)
			(xy 96.86237 -288.840042) (xy 96.878382 -288.790763) (xy 96.901905 -288.744596) (xy 96.932361 -288.702677)
			(xy 96.968999 -288.666039) (xy 97.010918 -288.635583) (xy 97.057085 -288.61206) (xy 97.106364 -288.596048)
			(xy 97.157541 -288.587942) (xy 97.209355 -288.587942) (xy 97.260532 -288.596048) (xy 97.309811 -288.61206)
			(xy 97.355978 -288.635583) (xy 97.397897 -288.666039) (xy 97.434535 -288.702677) (xy 97.464991 -288.744596)
			(xy 97.488514 -288.790763) (xy 97.504526 -288.840042) (xy 97.512632 -288.891219) (xy 97.51314 -288.917126)
			(xy 97.793556 -288.917126) (xy 97.794056 -288.891781) (xy 97.801825 -288.84169) (xy 97.817169 -288.793377)
			(xy 97.839727 -288.747983) (xy 97.868967 -288.706576) (xy 97.904199 -288.670131) (xy 97.944595 -288.639509)
			(xy 97.989201 -288.61543) (xy 98.036966 -288.598461) (xy 98.06178 -288.593276) (xy 98.08464 -288.588958)
			(xy 98.289872 -288.233866) (xy 98.281998 -288.211768) (xy 98.273376 -288.185419) (xy 98.264049 -288.130773)
			(xy 98.263456 -288.103056) (xy 98.263964 -288.077149) (xy 98.27207 -288.025972) (xy 98.288082 -287.976693)
			(xy 98.311605 -287.930526) (xy 98.342061 -287.888607) (xy 98.378699 -287.851969) (xy 98.420618 -287.821513)
			(xy 98.466785 -287.79799) (xy 98.516064 -287.781978) (xy 98.567241 -287.773872) (xy 98.619055 -287.773872)
			(xy 98.670232 -287.781978) (xy 98.719511 -287.79799) (xy 98.765678 -287.821513) (xy 98.807597 -287.851969)
			(xy 98.844235 -287.888607) (xy 98.874691 -287.930526) (xy 98.898214 -287.976693) (xy 98.914226 -288.025972)
			(xy 98.922332 -288.077149) (xy 98.92284 -288.103056) (xy 98.922418 -288.128404) (xy 98.914636 -288.178499)
			(xy 98.89928 -288.226813) (xy 98.876712 -288.272208) (xy 98.847462 -288.313614) (xy 98.812221 -288.350057)
			(xy 98.771818 -288.380678) (xy 98.727205 -288.404755) (xy 98.679432 -288.421722) (xy 98.654616 -288.426906)
			(xy 98.631756 -288.431224) (xy 98.426524 -288.786316) (xy 98.434398 -288.808414) (xy 98.44304 -288.834757)
			(xy 98.452354 -288.889407) (xy 98.45294 -288.917126) (xy 98.733356 -288.917126) (xy 98.733864 -288.891219)
			(xy 98.74197 -288.840042) (xy 98.757982 -288.790763) (xy 98.781505 -288.744596) (xy 98.811961 -288.702677)
			(xy 98.848599 -288.666039) (xy 98.890518 -288.635583) (xy 98.936685 -288.61206) (xy 98.985964 -288.596048)
			(xy 99.037141 -288.587942) (xy 99.088955 -288.587942) (xy 99.140132 -288.596048) (xy 99.189411 -288.61206)
			(xy 99.235578 -288.635583) (xy 99.277497 -288.666039) (xy 99.314135 -288.702677) (xy 99.344591 -288.744596)
			(xy 99.368114 -288.790763) (xy 99.384126 -288.840042) (xy 99.392232 -288.891219) (xy 99.39274 -288.917126)
			(xy 99.673156 -288.917126) (xy 99.673656 -288.891781) (xy 99.681425 -288.84169) (xy 99.696769 -288.793377)
			(xy 99.719327 -288.747983) (xy 99.748567 -288.706576) (xy 99.783799 -288.670131) (xy 99.824195 -288.639509)
			(xy 99.868801 -288.61543) (xy 99.916566 -288.598461) (xy 99.94138 -288.593276) (xy 99.96424 -288.588958)
			(xy 100.169472 -288.233866) (xy 100.161598 -288.211768) (xy 100.152976 -288.185419) (xy 100.143649 -288.130773)
			(xy 100.143056 -288.103056) (xy 100.143564 -288.077149) (xy 100.15167 -288.025972) (xy 100.167682 -287.976693)
			(xy 100.191205 -287.930526) (xy 100.221661 -287.888607) (xy 100.258299 -287.851969) (xy 100.300218 -287.821513)
			(xy 100.346385 -287.79799) (xy 100.395664 -287.781978) (xy 100.446841 -287.773872) (xy 100.498655 -287.773872)
			(xy 100.549832 -287.781978) (xy 100.599111 -287.79799) (xy 100.645278 -287.821513) (xy 100.687197 -287.851969)
			(xy 100.723835 -287.888607) (xy 100.754291 -287.930526) (xy 100.777814 -287.976693) (xy 100.793826 -288.025972)
			(xy 100.801932 -288.077149) (xy 100.80244 -288.103056) (xy 100.802018 -288.128404) (xy 100.794236 -288.178499)
			(xy 100.77888 -288.226813) (xy 100.756312 -288.272208) (xy 100.727062 -288.313614) (xy 100.691821 -288.350057)
			(xy 100.651418 -288.380678) (xy 100.606805 -288.404755) (xy 100.559032 -288.421722) (xy 100.534216 -288.426906)
			(xy 100.511356 -288.431224) (xy 100.306124 -288.786316) (xy 100.313998 -288.808414) (xy 100.32264 -288.834757)
			(xy 100.331954 -288.889407) (xy 100.33254 -288.917126) (xy 100.612956 -288.917126) (xy 100.613464 -288.891219)
			(xy 100.62157 -288.840042) (xy 100.637582 -288.790763) (xy 100.661105 -288.744596) (xy 100.691561 -288.702677)
			(xy 100.728199 -288.666039) (xy 100.770118 -288.635583) (xy 100.816285 -288.61206) (xy 100.865564 -288.596048)
			(xy 100.916741 -288.587942) (xy 100.968555 -288.587942) (xy 101.019732 -288.596048) (xy 101.069011 -288.61206)
			(xy 101.115178 -288.635583) (xy 101.157097 -288.666039) (xy 101.193735 -288.702677) (xy 101.224191 -288.744596)
			(xy 101.247714 -288.790763) (xy 101.263726 -288.840042) (xy 101.271832 -288.891219) (xy 101.27234 -288.917126)
			(xy 101.552756 -288.917126) (xy 101.553256 -288.891781) (xy 101.561025 -288.84169) (xy 101.576369 -288.793377)
			(xy 101.598927 -288.747983) (xy 101.628167 -288.706576) (xy 101.663399 -288.670131) (xy 101.703795 -288.639509)
			(xy 101.748401 -288.61543) (xy 101.796166 -288.598461) (xy 101.82098 -288.593276) (xy 101.84384 -288.588958)
			(xy 102.049072 -288.233866) (xy 102.041198 -288.211768) (xy 102.032576 -288.185419) (xy 102.023249 -288.130773)
			(xy 102.022656 -288.103056) (xy 102.023164 -288.077149) (xy 102.03127 -288.025972) (xy 102.047282 -287.976693)
			(xy 102.070805 -287.930526) (xy 102.101261 -287.888607) (xy 102.137899 -287.851969) (xy 102.179818 -287.821513)
			(xy 102.225985 -287.79799) (xy 102.275264 -287.781978) (xy 102.326441 -287.773872) (xy 102.378255 -287.773872)
			(xy 102.429432 -287.781978) (xy 102.478711 -287.79799) (xy 102.524878 -287.821513) (xy 102.566797 -287.851969)
			(xy 102.603435 -287.888607) (xy 102.633891 -287.930526) (xy 102.657414 -287.976693) (xy 102.673426 -288.025972)
			(xy 102.681532 -288.077149) (xy 102.68204 -288.103056) (xy 102.681618 -288.128404) (xy 102.673836 -288.178499)
			(xy 102.65848 -288.226813) (xy 102.635912 -288.272208) (xy 102.606662 -288.313614) (xy 102.571421 -288.350057)
			(xy 102.531018 -288.380678) (xy 102.486405 -288.404755) (xy 102.438632 -288.421722) (xy 102.413816 -288.426906)
			(xy 102.390956 -288.431224) (xy 102.185724 -288.786316) (xy 102.193598 -288.808414) (xy 102.20224 -288.834757)
			(xy 102.211554 -288.889407) (xy 102.21214 -288.917126) (xy 102.492556 -288.917126) (xy 102.493064 -288.891219)
			(xy 102.50117 -288.840042) (xy 102.517182 -288.790763) (xy 102.540705 -288.744596) (xy 102.571161 -288.702677)
			(xy 102.607799 -288.666039) (xy 102.649718 -288.635583) (xy 102.695885 -288.61206) (xy 102.745164 -288.596048)
			(xy 102.796341 -288.587942) (xy 102.848155 -288.587942) (xy 102.899332 -288.596048) (xy 102.948611 -288.61206)
			(xy 102.994778 -288.635583) (xy 103.036697 -288.666039) (xy 103.073335 -288.702677) (xy 103.103791 -288.744596)
			(xy 103.127314 -288.790763) (xy 103.143326 -288.840042) (xy 103.151432 -288.891219) (xy 103.15194 -288.917126)
			(xy 103.432356 -288.917126) (xy 103.432856 -288.891781) (xy 103.440625 -288.84169) (xy 103.455969 -288.793377)
			(xy 103.478527 -288.747983) (xy 103.507767 -288.706576) (xy 103.542999 -288.670131) (xy 103.583395 -288.639509)
			(xy 103.628001 -288.61543) (xy 103.675766 -288.598461) (xy 103.70058 -288.593276) (xy 103.72344 -288.588958)
			(xy 103.928672 -288.233866) (xy 103.920798 -288.211768) (xy 103.912176 -288.185419) (xy 103.902849 -288.130773)
			(xy 103.902256 -288.103056) (xy 103.902764 -288.077149) (xy 103.91087 -288.025972) (xy 103.926882 -287.976693)
			(xy 103.950405 -287.930526) (xy 103.980861 -287.888607) (xy 104.017499 -287.851969) (xy 104.059418 -287.821513)
			(xy 104.105585 -287.79799) (xy 104.154864 -287.781978) (xy 104.206041 -287.773872) (xy 104.257855 -287.773872)
			(xy 104.309032 -287.781978) (xy 104.358311 -287.79799) (xy 104.404478 -287.821513) (xy 104.446397 -287.851969)
			(xy 104.483035 -287.888607) (xy 104.513491 -287.930526) (xy 104.537014 -287.976693) (xy 104.553026 -288.025972)
			(xy 104.561132 -288.077149) (xy 104.56164 -288.103056) (xy 120.818656 -288.103056) (xy 120.819164 -288.077149)
			(xy 120.82727 -288.025972) (xy 120.843282 -287.976693) (xy 120.866805 -287.930526) (xy 120.897261 -287.888607)
			(xy 120.933899 -287.851969) (xy 120.975818 -287.821513) (xy 121.021985 -287.79799) (xy 121.071264 -287.781978)
			(xy 121.122441 -287.773872) (xy 121.174255 -287.773872) (xy 121.225432 -287.781978) (xy 121.274711 -287.79799)
			(xy 121.320878 -287.821513) (xy 121.362797 -287.851969) (xy 121.399435 -287.888607) (xy 121.429891 -287.930526)
			(xy 121.453414 -287.976693) (xy 121.469426 -288.025972) (xy 121.477532 -288.077149) (xy 121.47804 -288.103056)
			(xy 122.698256 -288.103056) (xy 122.698764 -288.077149) (xy 122.70687 -288.025972) (xy 122.722882 -287.976693)
			(xy 122.746405 -287.930526) (xy 122.776861 -287.888607) (xy 122.813499 -287.851969) (xy 122.855418 -287.821513)
			(xy 122.901585 -287.79799) (xy 122.950864 -287.781978) (xy 123.002041 -287.773872) (xy 123.053855 -287.773872)
			(xy 123.105032 -287.781978) (xy 123.154311 -287.79799) (xy 123.200478 -287.821513) (xy 123.242397 -287.851969)
			(xy 123.279035 -287.888607) (xy 123.309491 -287.930526) (xy 123.333014 -287.976693) (xy 123.349026 -288.025972)
			(xy 123.357132 -288.077149) (xy 123.35764 -288.103056) (xy 124.577856 -288.103056) (xy 124.578364 -288.077149)
			(xy 124.58647 -288.025972) (xy 124.602482 -287.976693) (xy 124.626005 -287.930526) (xy 124.656461 -287.888607)
			(xy 124.693099 -287.851969) (xy 124.735018 -287.821513) (xy 124.781185 -287.79799) (xy 124.830464 -287.781978)
			(xy 124.881641 -287.773872) (xy 124.933455 -287.773872) (xy 124.984632 -287.781978) (xy 125.033911 -287.79799)
			(xy 125.080078 -287.821513) (xy 125.121997 -287.851969) (xy 125.158635 -287.888607) (xy 125.189091 -287.930526)
			(xy 125.212614 -287.976693) (xy 125.228626 -288.025972) (xy 125.236732 -288.077149) (xy 125.23724 -288.103056)
			(xy 126.457456 -288.103056) (xy 126.457964 -288.077149) (xy 126.46607 -288.025972) (xy 126.482082 -287.976693)
			(xy 126.505605 -287.930526) (xy 126.536061 -287.888607) (xy 126.572699 -287.851969) (xy 126.614618 -287.821513)
			(xy 126.660785 -287.79799) (xy 126.710064 -287.781978) (xy 126.761241 -287.773872) (xy 126.813055 -287.773872)
			(xy 126.864232 -287.781978) (xy 126.913511 -287.79799) (xy 126.959678 -287.821513) (xy 127.001597 -287.851969)
			(xy 127.038235 -287.888607) (xy 127.068691 -287.930526) (xy 127.092214 -287.976693) (xy 127.108226 -288.025972)
			(xy 127.116332 -288.077149) (xy 127.11684 -288.103056) (xy 128.337056 -288.103056) (xy 128.337564 -288.077149)
			(xy 128.34567 -288.025972) (xy 128.361682 -287.976693) (xy 128.385205 -287.930526) (xy 128.415661 -287.888607)
			(xy 128.452299 -287.851969) (xy 128.494218 -287.821513) (xy 128.540385 -287.79799) (xy 128.589664 -287.781978)
			(xy 128.640841 -287.773872) (xy 128.692655 -287.773872) (xy 128.743832 -287.781978) (xy 128.793111 -287.79799)
			(xy 128.839278 -287.821513) (xy 128.881197 -287.851969) (xy 128.917835 -287.888607) (xy 128.948291 -287.930526)
			(xy 128.971814 -287.976693) (xy 128.987826 -288.025972) (xy 128.995932 -288.077149) (xy 128.99644 -288.103056)
			(xy 130.216656 -288.103056) (xy 130.217164 -288.077149) (xy 130.22527 -288.025972) (xy 130.241282 -287.976693)
			(xy 130.264805 -287.930526) (xy 130.295261 -287.888607) (xy 130.331899 -287.851969) (xy 130.373818 -287.821513)
			(xy 130.419985 -287.79799) (xy 130.469264 -287.781978) (xy 130.520441 -287.773872) (xy 130.572255 -287.773872)
			(xy 130.623432 -287.781978) (xy 130.672711 -287.79799) (xy 130.718878 -287.821513) (xy 130.760797 -287.851969)
			(xy 130.797435 -287.888607) (xy 130.827891 -287.930526) (xy 130.851414 -287.976693) (xy 130.867426 -288.025972)
			(xy 130.875532 -288.077149) (xy 130.87604 -288.103056) (xy 132.096256 -288.103056) (xy 132.096764 -288.077149)
			(xy 132.10487 -288.025972) (xy 132.120882 -287.976693) (xy 132.144405 -287.930526) (xy 132.174861 -287.888607)
			(xy 132.211499 -287.851969) (xy 132.253418 -287.821513) (xy 132.299585 -287.79799) (xy 132.348864 -287.781978)
			(xy 132.400041 -287.773872) (xy 132.451855 -287.773872) (xy 132.503032 -287.781978) (xy 132.552311 -287.79799)
			(xy 132.598478 -287.821513) (xy 132.640397 -287.851969) (xy 132.677035 -287.888607) (xy 132.707491 -287.930526)
			(xy 132.731014 -287.976693) (xy 132.747026 -288.025972) (xy 132.755132 -288.077149) (xy 132.75564 -288.103056)
			(xy 134.915656 -288.103056) (xy 134.916164 -288.077149) (xy 134.92427 -288.025972) (xy 134.940282 -287.976693)
			(xy 134.963805 -287.930526) (xy 134.994261 -287.888607) (xy 135.030899 -287.851969) (xy 135.072818 -287.821513)
			(xy 135.118985 -287.79799) (xy 135.168264 -287.781978) (xy 135.219441 -287.773872) (xy 135.271255 -287.773872)
			(xy 135.322432 -287.781978) (xy 135.371711 -287.79799) (xy 135.417878 -287.821513) (xy 135.459797 -287.851969)
			(xy 135.496435 -287.888607) (xy 135.526891 -287.930526) (xy 135.550414 -287.976693) (xy 135.566426 -288.025972)
			(xy 135.574532 -288.077149) (xy 135.57504 -288.103056) (xy 135.574438 -288.130773) (xy 135.56512 -288.18542)
			(xy 135.556498 -288.211768) (xy 135.548624 -288.233866) (xy 135.753856 -288.588958) (xy 135.776716 -288.593276)
			(xy 135.801527 -288.598486) (xy 135.849305 -288.615434) (xy 135.893924 -288.6395) (xy 135.934331 -288.670114)
			(xy 135.969573 -288.706556) (xy 135.998818 -288.747964) (xy 136.021377 -288.793363) (xy 136.036717 -288.841681)
			(xy 136.044477 -288.891779) (xy 136.04494 -288.917126) (xy 336.335624 -288.917126) (xy 336.336149 -288.891782)
			(xy 336.343918 -288.841693) (xy 336.359261 -288.793383) (xy 336.381816 -288.74799) (xy 336.411052 -288.706584)
			(xy 336.446281 -288.67014) (xy 336.486672 -288.639516) (xy 336.531274 -288.615435) (xy 336.579036 -288.598463)
			(xy 336.603848 -288.593276) (xy 336.626708 -288.588958) (xy 336.831686 -288.233866) (xy 336.823812 -288.212022)
			(xy 336.815238 -288.185602) (xy 336.806038 -288.130828) (xy 336.805524 -288.103056) (xy 336.806032 -288.077169)
			(xy 336.814131 -288.026031) (xy 336.83013 -287.976791) (xy 336.853636 -287.930659) (xy 336.884068 -287.888772)
			(xy 336.920678 -287.852162) (xy 336.962565 -287.82173) (xy 337.008697 -287.798224) (xy 337.057937 -287.782225)
			(xy 337.109075 -287.774126) (xy 337.160849 -287.774126) (xy 337.211987 -287.782225) (xy 337.261227 -287.798224)
			(xy 337.307359 -287.82173) (xy 337.349246 -287.852162) (xy 337.385856 -287.888772) (xy 337.416288 -287.930659)
			(xy 337.439794 -287.976791) (xy 337.455793 -288.026031) (xy 337.463892 -288.077169) (xy 337.4644 -288.103056)
			(xy 337.463968 -288.128392) (xy 337.456207 -288.178467) (xy 337.440877 -288.226765) (xy 337.418339 -288.272149)
			(xy 337.389123 -288.31355) (xy 337.353916 -288.349995) (xy 337.313549 -288.380624) (xy 337.268971 -288.404718)
			(xy 337.221232 -288.421708) (xy 337.19643 -288.426906) (xy 337.17357 -288.431224) (xy 336.968592 -288.786316)
			(xy 336.976466 -288.80816) (xy 336.985119 -288.834566) (xy 336.994435 -288.889344) (xy 336.995008 -288.917126)
			(xy 338.215224 -288.917126) (xy 338.215749 -288.891782) (xy 338.223518 -288.841693) (xy 338.238861 -288.793383)
			(xy 338.261416 -288.74799) (xy 338.290652 -288.706584) (xy 338.325881 -288.67014) (xy 338.366272 -288.639516)
			(xy 338.410874 -288.615435) (xy 338.458636 -288.598463) (xy 338.483448 -288.593276) (xy 338.506308 -288.588958)
			(xy 338.711286 -288.233866) (xy 338.703412 -288.212022) (xy 338.694838 -288.185602) (xy 338.685638 -288.130828)
			(xy 338.685124 -288.103056) (xy 338.685632 -288.077169) (xy 338.693731 -288.026031) (xy 338.70973 -287.976791)
			(xy 338.733236 -287.930659) (xy 338.763668 -287.888772) (xy 338.800278 -287.852162) (xy 338.842165 -287.82173)
			(xy 338.888297 -287.798224) (xy 338.937537 -287.782225) (xy 338.988675 -287.774126) (xy 339.040449 -287.774126)
			(xy 339.091587 -287.782225) (xy 339.140827 -287.798224) (xy 339.186959 -287.82173) (xy 339.228846 -287.852162)
			(xy 339.265456 -287.888772) (xy 339.295888 -287.930659) (xy 339.319394 -287.976791) (xy 339.335393 -288.026031)
			(xy 339.343492 -288.077169) (xy 339.344 -288.103056) (xy 339.343568 -288.128392) (xy 339.335807 -288.178467)
			(xy 339.320477 -288.226765) (xy 339.297939 -288.272149) (xy 339.268723 -288.31355) (xy 339.233516 -288.349995)
			(xy 339.193149 -288.380624) (xy 339.148571 -288.404718) (xy 339.100832 -288.421708) (xy 339.07603 -288.426906)
			(xy 339.05317 -288.431224) (xy 338.848192 -288.786316) (xy 338.856066 -288.80816) (xy 338.864719 -288.834566)
			(xy 338.874035 -288.889344) (xy 338.874608 -288.917126) (xy 339.155024 -288.917126) (xy 339.155532 -288.891219)
			(xy 339.163638 -288.840042) (xy 339.17965 -288.790763) (xy 339.203173 -288.744596) (xy 339.233629 -288.702677)
			(xy 339.270267 -288.666039) (xy 339.312186 -288.635583) (xy 339.358353 -288.61206) (xy 339.407632 -288.596048)
			(xy 339.458809 -288.587942) (xy 339.510623 -288.587942) (xy 339.5618 -288.596048) (xy 339.611079 -288.61206)
			(xy 339.657246 -288.635583) (xy 339.699165 -288.666039) (xy 339.735803 -288.702677) (xy 339.766259 -288.744596)
			(xy 339.789782 -288.790763) (xy 339.805794 -288.840042) (xy 339.8139 -288.891219) (xy 339.814408 -288.917126)
			(xy 340.094824 -288.917126) (xy 340.095349 -288.891782) (xy 340.103118 -288.841693) (xy 340.118461 -288.793383)
			(xy 340.141016 -288.74799) (xy 340.170252 -288.706584) (xy 340.205481 -288.67014) (xy 340.245872 -288.639516)
			(xy 340.290474 -288.615435) (xy 340.338236 -288.598463) (xy 340.363048 -288.593276) (xy 340.385908 -288.588958)
			(xy 340.59114 -288.233866) (xy 340.583266 -288.211768) (xy 340.574642 -288.185419) (xy 340.565317 -288.130773)
			(xy 340.564724 -288.103056) (xy 340.565232 -288.077149) (xy 340.573338 -288.025972) (xy 340.58935 -287.976693)
			(xy 340.612873 -287.930526) (xy 340.643329 -287.888607) (xy 340.679967 -287.851969) (xy 340.721886 -287.821513)
			(xy 340.768053 -287.79799) (xy 340.817332 -287.781978) (xy 340.868509 -287.773872) (xy 340.920323 -287.773872)
			(xy 340.9715 -287.781978) (xy 341.020779 -287.79799) (xy 341.066946 -287.821513) (xy 341.108865 -287.851969)
			(xy 341.145503 -287.888607) (xy 341.175959 -287.930526) (xy 341.199482 -287.976693) (xy 341.215494 -288.025972)
			(xy 341.2236 -288.077149) (xy 341.224108 -288.103056) (xy 341.223631 -288.128401) (xy 341.215851 -288.178491)
			(xy 341.200499 -288.2268) (xy 341.177936 -288.272192) (xy 341.148694 -288.313597) (xy 341.11346 -288.35004)
			(xy 341.073065 -288.380663) (xy 341.028461 -288.404744) (xy 340.980697 -288.421718) (xy 340.955884 -288.426906)
			(xy 340.933024 -288.431224) (xy 340.727792 -288.786316) (xy 340.735666 -288.808414) (xy 340.744307 -288.834758)
			(xy 340.753621 -288.889407) (xy 340.754208 -288.917126) (xy 341.034624 -288.917126) (xy 341.035132 -288.891219)
			(xy 341.043238 -288.840042) (xy 341.05925 -288.790763) (xy 341.082773 -288.744596) (xy 341.113229 -288.702677)
			(xy 341.149867 -288.666039) (xy 341.191786 -288.635583) (xy 341.237953 -288.61206) (xy 341.287232 -288.596048)
			(xy 341.338409 -288.587942) (xy 341.390223 -288.587942) (xy 341.4414 -288.596048) (xy 341.490679 -288.61206)
			(xy 341.536846 -288.635583) (xy 341.578765 -288.666039) (xy 341.615403 -288.702677) (xy 341.645859 -288.744596)
			(xy 341.669382 -288.790763) (xy 341.685394 -288.840042) (xy 341.6935 -288.891219) (xy 341.694008 -288.917126)
			(xy 341.974424 -288.917126) (xy 341.974949 -288.891782) (xy 341.982718 -288.841693) (xy 341.998061 -288.793383)
			(xy 342.020616 -288.74799) (xy 342.049852 -288.706584) (xy 342.085081 -288.67014) (xy 342.125472 -288.639516)
			(xy 342.170074 -288.615435) (xy 342.217836 -288.598463) (xy 342.242648 -288.593276) (xy 342.265508 -288.588958)
			(xy 342.47074 -288.233866) (xy 342.462866 -288.211768) (xy 342.454242 -288.185419) (xy 342.444917 -288.130773)
			(xy 342.444324 -288.103056) (xy 342.444832 -288.077149) (xy 342.452938 -288.025972) (xy 342.46895 -287.976693)
			(xy 342.492473 -287.930526) (xy 342.522929 -287.888607) (xy 342.559567 -287.851969) (xy 342.601486 -287.821513)
			(xy 342.647653 -287.79799) (xy 342.696932 -287.781978) (xy 342.748109 -287.773872) (xy 342.799923 -287.773872)
			(xy 342.8511 -287.781978) (xy 342.900379 -287.79799) (xy 342.946546 -287.821513) (xy 342.988465 -287.851969)
			(xy 343.025103 -287.888607) (xy 343.055559 -287.930526) (xy 343.079082 -287.976693) (xy 343.095094 -288.025972)
			(xy 343.1032 -288.077149) (xy 343.103708 -288.103056) (xy 343.103231 -288.128401) (xy 343.095451 -288.178491)
			(xy 343.080099 -288.2268) (xy 343.057536 -288.272192) (xy 343.028294 -288.313597) (xy 342.99306 -288.35004)
			(xy 342.952665 -288.380663) (xy 342.908061 -288.404744) (xy 342.860297 -288.421718) (xy 342.835484 -288.426906)
			(xy 342.812624 -288.431224) (xy 342.607392 -288.786316) (xy 342.615266 -288.808414) (xy 342.623907 -288.834758)
			(xy 342.633221 -288.889407) (xy 342.633808 -288.917126) (xy 342.914224 -288.917126) (xy 342.914732 -288.891219)
			(xy 342.922838 -288.840042) (xy 342.93885 -288.790763) (xy 342.962373 -288.744596) (xy 342.992829 -288.702677)
			(xy 343.029467 -288.666039) (xy 343.071386 -288.635583) (xy 343.117553 -288.61206) (xy 343.166832 -288.596048)
			(xy 343.218009 -288.587942) (xy 343.269823 -288.587942) (xy 343.321 -288.596048) (xy 343.370279 -288.61206)
			(xy 343.416446 -288.635583) (xy 343.458365 -288.666039) (xy 343.495003 -288.702677) (xy 343.525459 -288.744596)
			(xy 343.548982 -288.790763) (xy 343.564994 -288.840042) (xy 343.5731 -288.891219) (xy 343.573608 -288.917126)
			(xy 343.854024 -288.917126) (xy 343.854549 -288.891782) (xy 343.862318 -288.841693) (xy 343.877661 -288.793383)
			(xy 343.900216 -288.74799) (xy 343.929452 -288.706584) (xy 343.964681 -288.67014) (xy 344.005072 -288.639516)
			(xy 344.049674 -288.615435) (xy 344.097436 -288.598463) (xy 344.122248 -288.593276) (xy 344.145108 -288.588958)
			(xy 344.35034 -288.233866) (xy 344.342466 -288.211768) (xy 344.333842 -288.185419) (xy 344.324517 -288.130773)
			(xy 344.323924 -288.103056) (xy 344.324432 -288.077149) (xy 344.332538 -288.025972) (xy 344.34855 -287.976693)
			(xy 344.372073 -287.930526) (xy 344.402529 -287.888607) (xy 344.439167 -287.851969) (xy 344.481086 -287.821513)
			(xy 344.527253 -287.79799) (xy 344.576532 -287.781978) (xy 344.627709 -287.773872) (xy 344.679523 -287.773872)
			(xy 344.7307 -287.781978) (xy 344.779979 -287.79799) (xy 344.826146 -287.821513) (xy 344.868065 -287.851969)
			(xy 344.904703 -287.888607) (xy 344.935159 -287.930526) (xy 344.958682 -287.976693) (xy 344.974694 -288.025972)
			(xy 344.9828 -288.077149) (xy 344.983308 -288.103056) (xy 344.982831 -288.128401) (xy 344.975051 -288.178491)
			(xy 344.959699 -288.2268) (xy 344.937136 -288.272192) (xy 344.907894 -288.313597) (xy 344.87266 -288.35004)
			(xy 344.832265 -288.380663) (xy 344.787661 -288.404744) (xy 344.739897 -288.421718) (xy 344.715084 -288.426906)
			(xy 344.692224 -288.431224) (xy 344.486992 -288.786316) (xy 344.494866 -288.808414) (xy 344.503507 -288.834758)
			(xy 344.512821 -288.889407) (xy 344.513408 -288.917126) (xy 344.793824 -288.917126) (xy 344.794332 -288.891219)
			(xy 344.802438 -288.840042) (xy 344.81845 -288.790763) (xy 344.841973 -288.744596) (xy 344.872429 -288.702677)
			(xy 344.909067 -288.666039) (xy 344.950986 -288.635583) (xy 344.997153 -288.61206) (xy 345.046432 -288.596048)
			(xy 345.097609 -288.587942) (xy 345.149423 -288.587942) (xy 345.2006 -288.596048) (xy 345.249879 -288.61206)
			(xy 345.296046 -288.635583) (xy 345.337965 -288.666039) (xy 345.374603 -288.702677) (xy 345.405059 -288.744596)
			(xy 345.428582 -288.790763) (xy 345.444594 -288.840042) (xy 345.4527 -288.891219) (xy 345.453208 -288.917126)
			(xy 345.733624 -288.917126) (xy 345.734149 -288.891782) (xy 345.741918 -288.841693) (xy 345.757261 -288.793383)
			(xy 345.779816 -288.74799) (xy 345.809052 -288.706584) (xy 345.844281 -288.67014) (xy 345.884672 -288.639516)
			(xy 345.929274 -288.615435) (xy 345.977036 -288.598463) (xy 346.001848 -288.593276) (xy 346.024708 -288.588958)
			(xy 346.22994 -288.233866) (xy 346.222066 -288.211768) (xy 346.213442 -288.185419) (xy 346.204117 -288.130773)
			(xy 346.203524 -288.103056) (xy 346.204032 -288.077149) (xy 346.212138 -288.025972) (xy 346.22815 -287.976693)
			(xy 346.251673 -287.930526) (xy 346.282129 -287.888607) (xy 346.318767 -287.851969) (xy 346.360686 -287.821513)
			(xy 346.406853 -287.79799) (xy 346.456132 -287.781978) (xy 346.507309 -287.773872) (xy 346.559123 -287.773872)
			(xy 346.6103 -287.781978) (xy 346.659579 -287.79799) (xy 346.705746 -287.821513) (xy 346.747665 -287.851969)
			(xy 346.784303 -287.888607) (xy 346.814759 -287.930526) (xy 346.838282 -287.976693) (xy 346.854294 -288.025972)
			(xy 346.8624 -288.077149) (xy 346.862908 -288.103056) (xy 346.862431 -288.128401) (xy 346.854651 -288.178491)
			(xy 346.839299 -288.2268) (xy 346.816736 -288.272192) (xy 346.787494 -288.313597) (xy 346.75226 -288.35004)
			(xy 346.711865 -288.380663) (xy 346.667261 -288.404744) (xy 346.619497 -288.421718) (xy 346.594684 -288.426906)
			(xy 346.571824 -288.431224) (xy 346.366592 -288.786316) (xy 346.374466 -288.808414) (xy 346.383107 -288.834758)
			(xy 346.392421 -288.889407) (xy 346.393008 -288.917126) (xy 346.673424 -288.917126) (xy 346.673932 -288.891219)
			(xy 346.682038 -288.840042) (xy 346.69805 -288.790763) (xy 346.721573 -288.744596) (xy 346.752029 -288.702677)
			(xy 346.788667 -288.666039) (xy 346.830586 -288.635583) (xy 346.876753 -288.61206) (xy 346.926032 -288.596048)
			(xy 346.977209 -288.587942) (xy 347.029023 -288.587942) (xy 347.0802 -288.596048) (xy 347.129479 -288.61206)
			(xy 347.175646 -288.635583) (xy 347.217565 -288.666039) (xy 347.254203 -288.702677) (xy 347.284659 -288.744596)
			(xy 347.308182 -288.790763) (xy 347.324194 -288.840042) (xy 347.3323 -288.891219) (xy 347.332808 -288.917126)
			(xy 347.613224 -288.917126) (xy 347.613749 -288.891782) (xy 347.621518 -288.841693) (xy 347.636861 -288.793383)
			(xy 347.659416 -288.74799) (xy 347.688652 -288.706584) (xy 347.723881 -288.67014) (xy 347.764272 -288.639516)
			(xy 347.808874 -288.615435) (xy 347.856636 -288.598463) (xy 347.881448 -288.593276) (xy 347.904308 -288.588958)
			(xy 348.10954 -288.233866) (xy 348.101666 -288.211768) (xy 348.093042 -288.185419) (xy 348.083717 -288.130773)
			(xy 348.083124 -288.103056) (xy 348.083632 -288.077149) (xy 348.091738 -288.025972) (xy 348.10775 -287.976693)
			(xy 348.131273 -287.930526) (xy 348.161729 -287.888607) (xy 348.198367 -287.851969) (xy 348.240286 -287.821513)
			(xy 348.286453 -287.79799) (xy 348.335732 -287.781978) (xy 348.386909 -287.773872) (xy 348.438723 -287.773872)
			(xy 348.4899 -287.781978) (xy 348.539179 -287.79799) (xy 348.585346 -287.821513) (xy 348.627265 -287.851969)
			(xy 348.663903 -287.888607) (xy 348.694359 -287.930526) (xy 348.717882 -287.976693) (xy 348.733894 -288.025972)
			(xy 348.742 -288.077149) (xy 348.742508 -288.103056) (xy 348.742031 -288.128401) (xy 348.734251 -288.178491)
			(xy 348.718899 -288.2268) (xy 348.696336 -288.272192) (xy 348.667094 -288.313597) (xy 348.63186 -288.35004)
			(xy 348.591465 -288.380663) (xy 348.546861 -288.404744) (xy 348.499097 -288.421718) (xy 348.474284 -288.426906)
			(xy 348.451424 -288.431224) (xy 348.246192 -288.786316) (xy 348.254066 -288.808414) (xy 348.262707 -288.834758)
			(xy 348.272021 -288.889407) (xy 348.272608 -288.917126) (xy 348.553024 -288.917126) (xy 348.553532 -288.891219)
			(xy 348.561638 -288.840042) (xy 348.57765 -288.790763) (xy 348.601173 -288.744596) (xy 348.631629 -288.702677)
			(xy 348.668267 -288.666039) (xy 348.710186 -288.635583) (xy 348.756353 -288.61206) (xy 348.805632 -288.596048)
			(xy 348.856809 -288.587942) (xy 348.908623 -288.587942) (xy 348.9598 -288.596048) (xy 349.009079 -288.61206)
			(xy 349.055246 -288.635583) (xy 349.097165 -288.666039) (xy 349.133803 -288.702677) (xy 349.164259 -288.744596)
			(xy 349.187782 -288.790763) (xy 349.203794 -288.840042) (xy 349.2119 -288.891219) (xy 349.212408 -288.917126)
			(xy 349.492824 -288.917126) (xy 349.493349 -288.891782) (xy 349.501118 -288.841693) (xy 349.516461 -288.793383)
			(xy 349.539016 -288.74799) (xy 349.568252 -288.706584) (xy 349.603481 -288.67014) (xy 349.643872 -288.639516)
			(xy 349.688474 -288.615435) (xy 349.736236 -288.598463) (xy 349.761048 -288.593276) (xy 349.783908 -288.588958)
			(xy 349.98914 -288.233866) (xy 349.981266 -288.211768) (xy 349.972642 -288.185419) (xy 349.963317 -288.130773)
			(xy 349.962724 -288.103056) (xy 349.963232 -288.077149) (xy 349.971338 -288.025972) (xy 349.98735 -287.976693)
			(xy 350.010873 -287.930526) (xy 350.041329 -287.888607) (xy 350.077967 -287.851969) (xy 350.119886 -287.821513)
			(xy 350.166053 -287.79799) (xy 350.215332 -287.781978) (xy 350.266509 -287.773872) (xy 350.318323 -287.773872)
			(xy 350.3695 -287.781978) (xy 350.418779 -287.79799) (xy 350.464946 -287.821513) (xy 350.506865 -287.851969)
			(xy 350.543503 -287.888607) (xy 350.573959 -287.930526) (xy 350.597482 -287.976693) (xy 350.613494 -288.025972)
			(xy 350.6216 -288.077149) (xy 350.622108 -288.103056) (xy 350.621631 -288.128401) (xy 350.613851 -288.178491)
			(xy 350.598499 -288.2268) (xy 350.575936 -288.272192) (xy 350.546694 -288.313597) (xy 350.51146 -288.35004)
			(xy 350.471065 -288.380663) (xy 350.426461 -288.404744) (xy 350.378697 -288.421718) (xy 350.353884 -288.426906)
			(xy 350.331024 -288.431224) (xy 350.125792 -288.786316) (xy 350.133666 -288.808414) (xy 350.142307 -288.834758)
			(xy 350.151621 -288.889407) (xy 350.152208 -288.917126) (xy 350.432624 -288.917126) (xy 350.433132 -288.891219)
			(xy 350.441238 -288.840042) (xy 350.45725 -288.790763) (xy 350.480773 -288.744596) (xy 350.511229 -288.702677)
			(xy 350.547867 -288.666039) (xy 350.589786 -288.635583) (xy 350.635953 -288.61206) (xy 350.685232 -288.596048)
			(xy 350.736409 -288.587942) (xy 350.788223 -288.587942) (xy 350.8394 -288.596048) (xy 350.888679 -288.61206)
			(xy 350.934846 -288.635583) (xy 350.976765 -288.666039) (xy 351.013403 -288.702677) (xy 351.043859 -288.744596)
			(xy 351.067382 -288.790763) (xy 351.083394 -288.840042) (xy 351.0915 -288.891219) (xy 351.092008 -288.917126)
			(xy 351.372424 -288.917126) (xy 351.372949 -288.891782) (xy 351.380718 -288.841693) (xy 351.396061 -288.793383)
			(xy 351.418616 -288.74799) (xy 351.447852 -288.706584) (xy 351.483081 -288.67014) (xy 351.523472 -288.639516)
			(xy 351.568074 -288.615435) (xy 351.615836 -288.598463) (xy 351.640648 -288.593276) (xy 351.663508 -288.588958)
			(xy 351.86874 -288.233866) (xy 351.860866 -288.211768) (xy 351.852242 -288.185419) (xy 351.842917 -288.130773)
			(xy 351.842324 -288.103056) (xy 351.842832 -288.077149) (xy 351.850938 -288.025972) (xy 351.86695 -287.976693)
			(xy 351.890473 -287.930526) (xy 351.920929 -287.888607) (xy 351.957567 -287.851969) (xy 351.999486 -287.821513)
			(xy 352.045653 -287.79799) (xy 352.094932 -287.781978) (xy 352.146109 -287.773872) (xy 352.197923 -287.773872)
			(xy 352.2491 -287.781978) (xy 352.298379 -287.79799) (xy 352.344546 -287.821513) (xy 352.386465 -287.851969)
			(xy 352.423103 -287.888607) (xy 352.453559 -287.930526) (xy 352.477082 -287.976693) (xy 352.493094 -288.025972)
			(xy 352.5012 -288.077149) (xy 352.501708 -288.103056) (xy 368.758724 -288.103056) (xy 368.759232 -288.077149)
			(xy 368.767338 -288.025972) (xy 368.78335 -287.976693) (xy 368.806873 -287.930526) (xy 368.837329 -287.888607)
			(xy 368.873967 -287.851969) (xy 368.915886 -287.821513) (xy 368.962053 -287.79799) (xy 369.011332 -287.781978)
			(xy 369.062509 -287.773872) (xy 369.114323 -287.773872) (xy 369.1655 -287.781978) (xy 369.214779 -287.79799)
			(xy 369.260946 -287.821513) (xy 369.302865 -287.851969) (xy 369.339503 -287.888607) (xy 369.369959 -287.930526)
			(xy 369.393482 -287.976693) (xy 369.409494 -288.025972) (xy 369.4176 -288.077149) (xy 369.418108 -288.103056)
			(xy 370.638324 -288.103056) (xy 370.638832 -288.077149) (xy 370.646938 -288.025972) (xy 370.66295 -287.976693)
			(xy 370.686473 -287.930526) (xy 370.716929 -287.888607) (xy 370.753567 -287.851969) (xy 370.795486 -287.821513)
			(xy 370.841653 -287.79799) (xy 370.890932 -287.781978) (xy 370.942109 -287.773872) (xy 370.993923 -287.773872)
			(xy 371.0451 -287.781978) (xy 371.094379 -287.79799) (xy 371.140546 -287.821513) (xy 371.182465 -287.851969)
			(xy 371.219103 -287.888607) (xy 371.249559 -287.930526) (xy 371.273082 -287.976693) (xy 371.289094 -288.025972)
			(xy 371.2972 -288.077149) (xy 371.297708 -288.103056) (xy 372.517924 -288.103056) (xy 372.518432 -288.077149)
			(xy 372.526538 -288.025972) (xy 372.54255 -287.976693) (xy 372.566073 -287.930526) (xy 372.596529 -287.888607)
			(xy 372.633167 -287.851969) (xy 372.675086 -287.821513) (xy 372.721253 -287.79799) (xy 372.770532 -287.781978)
			(xy 372.821709 -287.773872) (xy 372.873523 -287.773872) (xy 372.9247 -287.781978) (xy 372.973979 -287.79799)
			(xy 373.020146 -287.821513) (xy 373.062065 -287.851969) (xy 373.098703 -287.888607) (xy 373.129159 -287.930526)
			(xy 373.152682 -287.976693) (xy 373.168694 -288.025972) (xy 373.1768 -288.077149) (xy 373.177308 -288.103056)
			(xy 374.397524 -288.103056) (xy 374.398032 -288.077149) (xy 374.406138 -288.025972) (xy 374.42215 -287.976693)
			(xy 374.445673 -287.930526) (xy 374.476129 -287.888607) (xy 374.512767 -287.851969) (xy 374.554686 -287.821513)
			(xy 374.600853 -287.79799) (xy 374.650132 -287.781978) (xy 374.701309 -287.773872) (xy 374.753123 -287.773872)
			(xy 374.8043 -287.781978) (xy 374.853579 -287.79799) (xy 374.899746 -287.821513) (xy 374.941665 -287.851969)
			(xy 374.978303 -287.888607) (xy 375.008759 -287.930526) (xy 375.032282 -287.976693) (xy 375.048294 -288.025972)
			(xy 375.0564 -288.077149) (xy 375.056908 -288.103056) (xy 376.277124 -288.103056) (xy 376.277632 -288.077149)
			(xy 376.285738 -288.025972) (xy 376.30175 -287.976693) (xy 376.325273 -287.930526) (xy 376.355729 -287.888607)
			(xy 376.392367 -287.851969) (xy 376.434286 -287.821513) (xy 376.480453 -287.79799) (xy 376.529732 -287.781978)
			(xy 376.580909 -287.773872) (xy 376.632723 -287.773872) (xy 376.6839 -287.781978) (xy 376.733179 -287.79799)
			(xy 376.779346 -287.821513) (xy 376.821265 -287.851969) (xy 376.857903 -287.888607) (xy 376.888359 -287.930526)
			(xy 376.911882 -287.976693) (xy 376.927894 -288.025972) (xy 376.936 -288.077149) (xy 376.936508 -288.103056)
			(xy 378.156724 -288.103056) (xy 378.157232 -288.077149) (xy 378.165338 -288.025972) (xy 378.18135 -287.976693)
			(xy 378.204873 -287.930526) (xy 378.235329 -287.888607) (xy 378.271967 -287.851969) (xy 378.313886 -287.821513)
			(xy 378.360053 -287.79799) (xy 378.409332 -287.781978) (xy 378.460509 -287.773872) (xy 378.512323 -287.773872)
			(xy 378.5635 -287.781978) (xy 378.612779 -287.79799) (xy 378.658946 -287.821513) (xy 378.700865 -287.851969)
			(xy 378.737503 -287.888607) (xy 378.767959 -287.930526) (xy 378.791482 -287.976693) (xy 378.807494 -288.025972)
			(xy 378.8156 -288.077149) (xy 378.816108 -288.103056) (xy 380.036324 -288.103056) (xy 380.036832 -288.077149)
			(xy 380.044938 -288.025972) (xy 380.06095 -287.976693) (xy 380.084473 -287.930526) (xy 380.114929 -287.888607)
			(xy 380.151567 -287.851969) (xy 380.193486 -287.821513) (xy 380.239653 -287.79799) (xy 380.288932 -287.781978)
			(xy 380.340109 -287.773872) (xy 380.391923 -287.773872) (xy 380.4431 -287.781978) (xy 380.492379 -287.79799)
			(xy 380.538546 -287.821513) (xy 380.580465 -287.851969) (xy 380.617103 -287.888607) (xy 380.647559 -287.930526)
			(xy 380.671082 -287.976693) (xy 380.687094 -288.025972) (xy 380.6952 -288.077149) (xy 380.695708 -288.103056)
			(xy 382.855724 -288.103056) (xy 382.856232 -288.077149) (xy 382.864338 -288.025972) (xy 382.88035 -287.976693)
			(xy 382.903873 -287.930526) (xy 382.934329 -287.888607) (xy 382.970967 -287.851969) (xy 383.012886 -287.821513)
			(xy 383.059053 -287.79799) (xy 383.108332 -287.781978) (xy 383.159509 -287.773872) (xy 383.211323 -287.773872)
			(xy 383.2625 -287.781978) (xy 383.311779 -287.79799) (xy 383.357946 -287.821513) (xy 383.399865 -287.851969)
			(xy 383.436503 -287.888607) (xy 383.466959 -287.930526) (xy 383.490482 -287.976693) (xy 383.506494 -288.025972)
			(xy 383.5146 -288.077149) (xy 383.515108 -288.103056) (xy 383.514503 -288.130773) (xy 383.505187 -288.185419)
			(xy 383.496566 -288.211768) (xy 383.488692 -288.233866) (xy 383.693924 -288.588958) (xy 383.716784 -288.593276)
			(xy 383.741606 -288.598437) (xy 383.789384 -288.615395) (xy 383.834001 -288.639469) (xy 383.874406 -288.67009)
			(xy 383.909646 -288.706538) (xy 383.93889 -288.747952) (xy 383.961447 -288.793355) (xy 383.976786 -288.841676)
			(xy 383.984545 -288.891777) (xy 383.985008 -288.917126) (xy 383.9845 -288.943033) (xy 383.976394 -288.99421)
			(xy 383.960382 -289.043489) (xy 383.936859 -289.089656) (xy 383.906403 -289.131575) (xy 383.869765 -289.168213)
			(xy 383.827846 -289.198669) (xy 383.781679 -289.222192) (xy 383.7324 -289.238204) (xy 383.681223 -289.24631)
			(xy 383.629409 -289.24631) (xy 383.578232 -289.238204) (xy 383.528953 -289.222192) (xy 383.482786 -289.198669)
			(xy 383.440867 -289.168213) (xy 383.404229 -289.131575) (xy 383.373773 -289.089656) (xy 383.35025 -289.043489)
			(xy 383.334238 -288.99421) (xy 383.326132 -288.943033) (xy 383.325624 -288.917126) (xy 383.326223 -288.889409)
			(xy 383.335543 -288.834762) (xy 383.344166 -288.808414) (xy 383.35204 -288.786316) (xy 383.146808 -288.431224)
			(xy 383.123948 -288.426906) (xy 383.099127 -288.421739) (xy 383.051348 -288.404784) (xy 383.006729 -288.380713)
			(xy 382.966322 -288.350092) (xy 382.931082 -288.313646) (xy 382.901838 -288.272232) (xy 382.879281 -288.226828)
			(xy 382.863943 -288.178506) (xy 382.856186 -288.128405) (xy 382.855724 -288.103056) (xy 380.695708 -288.103056)
			(xy 380.695103 -288.130773) (xy 380.685787 -288.185419) (xy 380.677166 -288.211768) (xy 380.669546 -288.233866)
			(xy 380.874524 -288.588958) (xy 380.897384 -288.593276) (xy 380.922206 -288.598437) (xy 380.969984 -288.615395)
			(xy 381.014601 -288.639469) (xy 381.055006 -288.67009) (xy 381.090246 -288.706538) (xy 381.11949 -288.747952)
			(xy 381.142047 -288.793355) (xy 381.157386 -288.841676) (xy 381.165145 -288.891777) (xy 381.165608 -288.917126)
			(xy 381.1651 -288.943033) (xy 381.156994 -288.99421) (xy 381.140982 -289.043489) (xy 381.117459 -289.089656)
			(xy 381.087003 -289.131575) (xy 381.050365 -289.168213) (xy 381.008446 -289.198669) (xy 380.962279 -289.222192)
			(xy 380.913 -289.238204) (xy 380.861823 -289.24631) (xy 380.810009 -289.24631) (xy 380.758832 -289.238204)
			(xy 380.709553 -289.222192) (xy 380.663386 -289.198669) (xy 380.621467 -289.168213) (xy 380.584829 -289.131575)
			(xy 380.554373 -289.089656) (xy 380.53085 -289.043489) (xy 380.514838 -288.99421) (xy 380.506732 -288.943033)
			(xy 380.506224 -288.917126) (xy 380.506823 -288.889409) (xy 380.516143 -288.834762) (xy 380.524766 -288.808414)
			(xy 380.53264 -288.786316) (xy 380.327662 -288.431224) (xy 380.304802 -288.426906) (xy 380.279961 -288.421779)
			(xy 380.232152 -288.40484) (xy 380.187502 -288.380778) (xy 380.147063 -288.350162) (xy 380.111791 -288.313713)
			(xy 380.082517 -288.272293) (xy 380.059933 -288.226877) (xy 380.044571 -288.178538) (xy 380.036794 -288.128417)
			(xy 380.036324 -288.103056) (xy 378.816108 -288.103056) (xy 378.815503 -288.130773) (xy 378.806187 -288.185419)
			(xy 378.797566 -288.211768) (xy 378.789946 -288.233866) (xy 378.994924 -288.588958) (xy 379.017784 -288.593276)
			(xy 379.042606 -288.598437) (xy 379.090384 -288.615395) (xy 379.135001 -288.639469) (xy 379.175406 -288.67009)
			(xy 379.210646 -288.706538) (xy 379.23989 -288.747952) (xy 379.262447 -288.793355) (xy 379.277786 -288.841676)
			(xy 379.285545 -288.891777) (xy 379.286008 -288.917126) (xy 379.2855 -288.943033) (xy 379.277394 -288.99421)
			(xy 379.261382 -289.043489) (xy 379.237859 -289.089656) (xy 379.207403 -289.131575) (xy 379.170765 -289.168213)
			(xy 379.128846 -289.198669) (xy 379.082679 -289.222192) (xy 379.0334 -289.238204) (xy 378.982223 -289.24631)
			(xy 378.930409 -289.24631) (xy 378.879232 -289.238204) (xy 378.829953 -289.222192) (xy 378.783786 -289.198669)
			(xy 378.741867 -289.168213) (xy 378.705229 -289.131575) (xy 378.674773 -289.089656) (xy 378.65125 -289.043489)
			(xy 378.635238 -288.99421) (xy 378.627132 -288.943033) (xy 378.626624 -288.917126) (xy 378.627223 -288.889409)
			(xy 378.636543 -288.834762) (xy 378.645166 -288.808414) (xy 378.65304 -288.786316) (xy 378.448062 -288.431224)
			(xy 378.425202 -288.426906) (xy 378.400361 -288.421779) (xy 378.352552 -288.40484) (xy 378.307902 -288.380778)
			(xy 378.267463 -288.350162) (xy 378.232191 -288.313713) (xy 378.202917 -288.272293) (xy 378.180333 -288.226877)
			(xy 378.164971 -288.178538) (xy 378.157194 -288.128417) (xy 378.156724 -288.103056) (xy 376.936508 -288.103056)
			(xy 376.935903 -288.130773) (xy 376.926587 -288.185419) (xy 376.917966 -288.211768) (xy 376.910346 -288.233866)
			(xy 377.115324 -288.588958) (xy 377.138184 -288.593276) (xy 377.163006 -288.598437) (xy 377.210784 -288.615395)
			(xy 377.255401 -288.639469) (xy 377.295806 -288.67009) (xy 377.331046 -288.706538) (xy 377.36029 -288.747952)
			(xy 377.382847 -288.793355) (xy 377.398186 -288.841676) (xy 377.405945 -288.891777) (xy 377.406408 -288.917126)
			(xy 377.4059 -288.943033) (xy 377.397794 -288.99421) (xy 377.381782 -289.043489) (xy 377.358259 -289.089656)
			(xy 377.327803 -289.131575) (xy 377.291165 -289.168213) (xy 377.249246 -289.198669) (xy 377.203079 -289.222192)
			(xy 377.1538 -289.238204) (xy 377.102623 -289.24631) (xy 377.050809 -289.24631) (xy 376.999632 -289.238204)
			(xy 376.950353 -289.222192) (xy 376.904186 -289.198669) (xy 376.862267 -289.168213) (xy 376.825629 -289.131575)
			(xy 376.795173 -289.089656) (xy 376.77165 -289.043489) (xy 376.755638 -288.99421) (xy 376.747532 -288.943033)
			(xy 376.747024 -288.917126) (xy 376.747623 -288.889409) (xy 376.756943 -288.834762) (xy 376.765566 -288.808414)
			(xy 376.77344 -288.786316) (xy 376.568462 -288.431224) (xy 376.545602 -288.426906) (xy 376.520761 -288.421779)
			(xy 376.472952 -288.40484) (xy 376.428302 -288.380778) (xy 376.387863 -288.350162) (xy 376.352591 -288.313713)
			(xy 376.323317 -288.272293) (xy 376.300733 -288.226877) (xy 376.285371 -288.178538) (xy 376.277594 -288.128417)
			(xy 376.277124 -288.103056) (xy 375.056908 -288.103056) (xy 375.056303 -288.130773) (xy 375.046987 -288.185419)
			(xy 375.038366 -288.211768) (xy 375.030746 -288.233866) (xy 375.235724 -288.588958) (xy 375.258584 -288.593276)
			(xy 375.283406 -288.598437) (xy 375.331184 -288.615395) (xy 375.375801 -288.639469) (xy 375.416206 -288.67009)
			(xy 375.451446 -288.706538) (xy 375.48069 -288.747952) (xy 375.503247 -288.793355) (xy 375.518586 -288.841676)
			(xy 375.526345 -288.891777) (xy 375.526808 -288.917126) (xy 375.5263 -288.943033) (xy 375.518194 -288.99421)
			(xy 375.502182 -289.043489) (xy 375.478659 -289.089656) (xy 375.448203 -289.131575) (xy 375.411565 -289.168213)
			(xy 375.369646 -289.198669) (xy 375.323479 -289.222192) (xy 375.2742 -289.238204) (xy 375.223023 -289.24631)
			(xy 375.171209 -289.24631) (xy 375.120032 -289.238204) (xy 375.070753 -289.222192) (xy 375.024586 -289.198669)
			(xy 374.982667 -289.168213) (xy 374.946029 -289.131575) (xy 374.915573 -289.089656) (xy 374.89205 -289.043489)
			(xy 374.876038 -288.99421) (xy 374.867932 -288.943033) (xy 374.867424 -288.917126) (xy 374.868023 -288.889409)
			(xy 374.877343 -288.834762) (xy 374.885966 -288.808414) (xy 374.89384 -288.786316) (xy 374.688862 -288.431224)
			(xy 374.666002 -288.426906) (xy 374.641161 -288.421779) (xy 374.593352 -288.40484) (xy 374.548702 -288.380778)
			(xy 374.508263 -288.350162) (xy 374.472991 -288.313713) (xy 374.443717 -288.272293) (xy 374.421133 -288.226877)
			(xy 374.405771 -288.178538) (xy 374.397994 -288.128417) (xy 374.397524 -288.103056) (xy 373.177308 -288.103056)
			(xy 373.176703 -288.130773) (xy 373.167387 -288.185419) (xy 373.158766 -288.211768) (xy 373.151146 -288.233866)
			(xy 373.356124 -288.588958) (xy 373.378984 -288.593276) (xy 373.403806 -288.598437) (xy 373.451584 -288.615395)
			(xy 373.496201 -288.639469) (xy 373.536606 -288.67009) (xy 373.571846 -288.706538) (xy 373.60109 -288.747952)
			(xy 373.623647 -288.793355) (xy 373.638986 -288.841676) (xy 373.646745 -288.891777) (xy 373.647208 -288.917126)
			(xy 373.6467 -288.943033) (xy 373.638594 -288.99421) (xy 373.622582 -289.043489) (xy 373.599059 -289.089656)
			(xy 373.568603 -289.131575) (xy 373.531965 -289.168213) (xy 373.490046 -289.198669) (xy 373.443879 -289.222192)
			(xy 373.3946 -289.238204) (xy 373.343423 -289.24631) (xy 373.291609 -289.24631) (xy 373.240432 -289.238204)
			(xy 373.191153 -289.222192) (xy 373.144986 -289.198669) (xy 373.103067 -289.168213) (xy 373.066429 -289.131575)
			(xy 373.035973 -289.089656) (xy 373.01245 -289.043489) (xy 372.996438 -288.99421) (xy 372.988332 -288.943033)
			(xy 372.987824 -288.917126) (xy 372.988423 -288.889409) (xy 372.997743 -288.834762) (xy 373.006366 -288.808414)
			(xy 373.01424 -288.786316) (xy 372.809262 -288.431224) (xy 372.786402 -288.426906) (xy 372.761561 -288.421779)
			(xy 372.713752 -288.40484) (xy 372.669102 -288.380778) (xy 372.628663 -288.350162) (xy 372.593391 -288.313713)
			(xy 372.564117 -288.272293) (xy 372.541533 -288.226877) (xy 372.526171 -288.178538) (xy 372.518394 -288.128417)
			(xy 372.517924 -288.103056) (xy 371.297708 -288.103056) (xy 371.297103 -288.130773) (xy 371.287787 -288.185419)
			(xy 371.279166 -288.211768) (xy 371.271546 -288.233866) (xy 371.476524 -288.588958) (xy 371.499384 -288.593276)
			(xy 371.524206 -288.598437) (xy 371.571984 -288.615395) (xy 371.616601 -288.639469) (xy 371.657006 -288.67009)
			(xy 371.692246 -288.706538) (xy 371.72149 -288.747952) (xy 371.744047 -288.793355) (xy 371.759386 -288.841676)
			(xy 371.767145 -288.891777) (xy 371.767608 -288.917126) (xy 371.7671 -288.943033) (xy 371.758994 -288.99421)
			(xy 371.742982 -289.043489) (xy 371.719459 -289.089656) (xy 371.689003 -289.131575) (xy 371.652365 -289.168213)
			(xy 371.610446 -289.198669) (xy 371.564279 -289.222192) (xy 371.515 -289.238204) (xy 371.463823 -289.24631)
			(xy 371.412009 -289.24631) (xy 371.360832 -289.238204) (xy 371.311553 -289.222192) (xy 371.265386 -289.198669)
			(xy 371.223467 -289.168213) (xy 371.186829 -289.131575) (xy 371.156373 -289.089656) (xy 371.13285 -289.043489)
			(xy 371.116838 -288.99421) (xy 371.108732 -288.943033) (xy 371.108224 -288.917126) (xy 371.108823 -288.889409)
			(xy 371.118143 -288.834762) (xy 371.126766 -288.808414) (xy 371.13464 -288.786316) (xy 370.929662 -288.431224)
			(xy 370.906802 -288.426906) (xy 370.881961 -288.421779) (xy 370.834152 -288.40484) (xy 370.789502 -288.380778)
			(xy 370.749063 -288.350162) (xy 370.713791 -288.313713) (xy 370.684517 -288.272293) (xy 370.661933 -288.226877)
			(xy 370.646571 -288.178538) (xy 370.638794 -288.128417) (xy 370.638324 -288.103056) (xy 369.418108 -288.103056)
			(xy 369.417503 -288.130773) (xy 369.408187 -288.185419) (xy 369.399566 -288.211768) (xy 369.391692 -288.233866)
			(xy 369.596924 -288.588958) (xy 369.619784 -288.593276) (xy 369.644606 -288.598437) (xy 369.692384 -288.615395)
			(xy 369.737001 -288.639469) (xy 369.777406 -288.67009) (xy 369.812646 -288.706538) (xy 369.84189 -288.747952)
			(xy 369.864447 -288.793355) (xy 369.879786 -288.841676) (xy 369.887545 -288.891777) (xy 369.888008 -288.917126)
			(xy 369.8875 -288.943033) (xy 369.879394 -288.99421) (xy 369.863382 -289.043489) (xy 369.839859 -289.089656)
			(xy 369.809403 -289.131575) (xy 369.772765 -289.168213) (xy 369.730846 -289.198669) (xy 369.684679 -289.222192)
			(xy 369.6354 -289.238204) (xy 369.584223 -289.24631) (xy 369.532409 -289.24631) (xy 369.481232 -289.238204)
			(xy 369.431953 -289.222192) (xy 369.385786 -289.198669) (xy 369.343867 -289.168213) (xy 369.307229 -289.131575)
			(xy 369.276773 -289.089656) (xy 369.25325 -289.043489) (xy 369.237238 -288.99421) (xy 369.229132 -288.943033)
			(xy 369.228624 -288.917126) (xy 369.229223 -288.889409) (xy 369.238543 -288.834762) (xy 369.247166 -288.808414)
			(xy 369.25504 -288.786316) (xy 369.049808 -288.431224) (xy 369.026948 -288.426906) (xy 369.002127 -288.421739)
			(xy 368.954348 -288.404784) (xy 368.909729 -288.380713) (xy 368.869322 -288.350092) (xy 368.834082 -288.313646)
			(xy 368.804838 -288.272232) (xy 368.782281 -288.226828) (xy 368.766943 -288.178506) (xy 368.759186 -288.128405)
			(xy 368.758724 -288.103056) (xy 352.501708 -288.103056) (xy 352.501231 -288.128401) (xy 352.493451 -288.178491)
			(xy 352.478099 -288.2268) (xy 352.455536 -288.272192) (xy 352.426294 -288.313597) (xy 352.39106 -288.35004)
			(xy 352.350665 -288.380663) (xy 352.306061 -288.404744) (xy 352.258297 -288.421718) (xy 352.233484 -288.426906)
			(xy 352.210624 -288.431224) (xy 352.005392 -288.786316) (xy 352.013266 -288.808414) (xy 352.021907 -288.834758)
			(xy 352.031221 -288.889407) (xy 352.031808 -288.917126) (xy 352.0313 -288.943033) (xy 352.023194 -288.99421)
			(xy 352.007182 -289.043489) (xy 351.983659 -289.089656) (xy 351.953203 -289.131575) (xy 351.916565 -289.168213)
			(xy 351.874646 -289.198669) (xy 351.828479 -289.222192) (xy 351.7792 -289.238204) (xy 351.728023 -289.24631)
			(xy 351.676209 -289.24631) (xy 351.625032 -289.238204) (xy 351.575753 -289.222192) (xy 351.529586 -289.198669)
			(xy 351.487667 -289.168213) (xy 351.451029 -289.131575) (xy 351.420573 -289.089656) (xy 351.39705 -289.043489)
			(xy 351.381038 -288.99421) (xy 351.372932 -288.943033) (xy 351.372424 -288.917126) (xy 351.092008 -288.917126)
			(xy 351.091589 -288.940067) (xy 351.08516 -288.985498) (xy 351.072513 -289.029604) (xy 351.06356 -289.05073)
			(xy 351.053654 -289.073336) (xy 351.267522 -289.478466) (xy 351.291652 -289.483038) (xy 351.316573 -289.488138)
			(xy 351.364584 -289.504939) (xy 351.409443 -289.528919) (xy 351.450084 -289.559507) (xy 351.485541 -289.595978)
			(xy 351.514973 -289.637465) (xy 351.537679 -289.682981) (xy 351.553121 -289.731446) (xy 351.560931 -289.781709)
			(xy 351.5614 -289.807142) (xy 367.818924 -289.807142) (xy 367.819411 -289.781712) (xy 367.827244 -289.73146)
			(xy 367.842699 -289.683005) (xy 367.86541 -289.637498) (xy 367.894839 -289.596018) (xy 367.930287 -289.559547)
			(xy 367.970914 -289.528951) (xy 368.015757 -289.504956) (xy 368.063753 -289.48813) (xy 368.088672 -289.483038)
			(xy 368.112802 -289.478466) (xy 368.327178 -289.073082) (xy 368.317272 -289.050476) (xy 368.308309 -289.029398)
			(xy 368.295664 -288.985377) (xy 368.289249 -288.940026) (xy 368.288824 -288.917126) (xy 368.289332 -288.891219)
			(xy 368.297438 -288.840042) (xy 368.31345 -288.790763) (xy 368.336973 -288.744596) (xy 368.367429 -288.702677)
			(xy 368.404067 -288.666039) (xy 368.445986 -288.635583) (xy 368.492153 -288.61206) (xy 368.541432 -288.596048)
			(xy 368.592609 -288.587942) (xy 368.644423 -288.587942) (xy 368.6956 -288.596048) (xy 368.744879 -288.61206)
			(xy 368.791046 -288.635583) (xy 368.832965 -288.666039) (xy 368.869603 -288.702677) (xy 368.900059 -288.744596)
			(xy 368.923582 -288.790763) (xy 368.939594 -288.840042) (xy 368.9477 -288.891219) (xy 368.948208 -288.917126)
			(xy 368.947753 -288.942575) (xy 368.939949 -288.992871) (xy 368.924499 -289.041367) (xy 368.901771 -289.086909)
			(xy 368.872307 -289.128411) (xy 368.836809 -289.164887) (xy 368.796121 -289.195466) (xy 368.751213 -289.21942)
			(xy 368.703153 -289.23618) (xy 368.678206 -289.24123) (xy 368.654076 -289.245802) (xy 368.4397 -289.651186)
			(xy 368.449606 -289.673792) (xy 368.458528 -289.694877) (xy 368.471078 -289.738907) (xy 368.47741 -289.78425)
			(xy 368.4778 -289.807142) (xy 369.698524 -289.807142) (xy 369.699011 -289.781712) (xy 369.706844 -289.73146)
			(xy 369.722299 -289.683005) (xy 369.74501 -289.637498) (xy 369.774439 -289.596018) (xy 369.809887 -289.559547)
			(xy 369.850514 -289.528951) (xy 369.895357 -289.504956) (xy 369.943353 -289.48813) (xy 369.968272 -289.483038)
			(xy 369.992402 -289.478466) (xy 370.206778 -289.073082) (xy 370.196872 -289.050476) (xy 370.187909 -289.029398)
			(xy 370.175264 -288.985377) (xy 370.168849 -288.940026) (xy 370.168424 -288.917126) (xy 370.168932 -288.891219)
			(xy 370.177038 -288.840042) (xy 370.19305 -288.790763) (xy 370.216573 -288.744596) (xy 370.247029 -288.702677)
			(xy 370.283667 -288.666039) (xy 370.325586 -288.635583) (xy 370.371753 -288.61206) (xy 370.421032 -288.596048)
			(xy 370.472209 -288.587942) (xy 370.524023 -288.587942) (xy 370.5752 -288.596048) (xy 370.624479 -288.61206)
			(xy 370.670646 -288.635583) (xy 370.712565 -288.666039) (xy 370.749203 -288.702677) (xy 370.779659 -288.744596)
			(xy 370.803182 -288.790763) (xy 370.819194 -288.840042) (xy 370.8273 -288.891219) (xy 370.827808 -288.917126)
			(xy 370.827353 -288.942575) (xy 370.819549 -288.992871) (xy 370.804099 -289.041367) (xy 370.781371 -289.086909)
			(xy 370.751907 -289.128411) (xy 370.716409 -289.164887) (xy 370.675721 -289.195466) (xy 370.630813 -289.21942)
			(xy 370.582753 -289.23618) (xy 370.557806 -289.24123) (xy 370.533676 -289.245802) (xy 370.3193 -289.651186)
			(xy 370.329206 -289.673792) (xy 370.338128 -289.694877) (xy 370.350678 -289.738907) (xy 370.35701 -289.78425)
			(xy 370.3574 -289.807142) (xy 371.578124 -289.807142) (xy 371.578611 -289.781712) (xy 371.586444 -289.73146)
			(xy 371.601899 -289.683005) (xy 371.62461 -289.637498) (xy 371.654039 -289.596018) (xy 371.689487 -289.559547)
			(xy 371.730114 -289.528951) (xy 371.774957 -289.504956) (xy 371.822953 -289.48813) (xy 371.847872 -289.483038)
			(xy 371.872002 -289.478466) (xy 372.086378 -289.073082) (xy 372.076472 -289.050476) (xy 372.067509 -289.029398)
			(xy 372.054864 -288.985377) (xy 372.048449 -288.940026) (xy 372.048024 -288.917126) (xy 372.048532 -288.891219)
			(xy 372.056638 -288.840042) (xy 372.07265 -288.790763) (xy 372.096173 -288.744596) (xy 372.126629 -288.702677)
			(xy 372.163267 -288.666039) (xy 372.205186 -288.635583) (xy 372.251353 -288.61206) (xy 372.300632 -288.596048)
			(xy 372.351809 -288.587942) (xy 372.403623 -288.587942) (xy 372.4548 -288.596048) (xy 372.504079 -288.61206)
			(xy 372.550246 -288.635583) (xy 372.592165 -288.666039) (xy 372.628803 -288.702677) (xy 372.659259 -288.744596)
			(xy 372.682782 -288.790763) (xy 372.698794 -288.840042) (xy 372.7069 -288.891219) (xy 372.707408 -288.917126)
			(xy 372.706953 -288.942575) (xy 372.699149 -288.992871) (xy 372.683699 -289.041367) (xy 372.660971 -289.086909)
			(xy 372.631507 -289.128411) (xy 372.596009 -289.164887) (xy 372.555321 -289.195466) (xy 372.510413 -289.21942)
			(xy 372.462353 -289.23618) (xy 372.437406 -289.24123) (xy 372.413276 -289.245802) (xy 372.1989 -289.651186)
			(xy 372.208806 -289.673792) (xy 372.217728 -289.694877) (xy 372.230278 -289.738907) (xy 372.23661 -289.78425)
			(xy 372.237 -289.807142) (xy 373.457724 -289.807142) (xy 373.458211 -289.781712) (xy 373.466044 -289.73146)
			(xy 373.481499 -289.683005) (xy 373.50421 -289.637498) (xy 373.533639 -289.596018) (xy 373.569087 -289.559547)
			(xy 373.609714 -289.528951) (xy 373.654557 -289.504956) (xy 373.702553 -289.48813) (xy 373.727472 -289.483038)
			(xy 373.751602 -289.478466) (xy 373.965978 -289.073082) (xy 373.956072 -289.050476) (xy 373.947109 -289.029398)
			(xy 373.934464 -288.985377) (xy 373.928049 -288.940026) (xy 373.927624 -288.917126) (xy 373.928132 -288.891219)
			(xy 373.936238 -288.840042) (xy 373.95225 -288.790763) (xy 373.975773 -288.744596) (xy 374.006229 -288.702677)
			(xy 374.042867 -288.666039) (xy 374.084786 -288.635583) (xy 374.130953 -288.61206) (xy 374.180232 -288.596048)
			(xy 374.231409 -288.587942) (xy 374.283223 -288.587942) (xy 374.3344 -288.596048) (xy 374.383679 -288.61206)
			(xy 374.429846 -288.635583) (xy 374.471765 -288.666039) (xy 374.508403 -288.702677) (xy 374.538859 -288.744596)
			(xy 374.562382 -288.790763) (xy 374.578394 -288.840042) (xy 374.5865 -288.891219) (xy 374.587008 -288.917126)
			(xy 374.586553 -288.942575) (xy 374.578749 -288.992871) (xy 374.563299 -289.041367) (xy 374.540571 -289.086909)
			(xy 374.511107 -289.128411) (xy 374.475609 -289.164887) (xy 374.434921 -289.195466) (xy 374.390013 -289.21942)
			(xy 374.341953 -289.23618) (xy 374.317006 -289.24123) (xy 374.292876 -289.245802) (xy 374.0785 -289.651186)
			(xy 374.088406 -289.673792) (xy 374.097328 -289.694877) (xy 374.109878 -289.738907) (xy 374.11621 -289.78425)
			(xy 374.1166 -289.807142) (xy 375.337324 -289.807142) (xy 375.337811 -289.781712) (xy 375.345644 -289.73146)
			(xy 375.361099 -289.683005) (xy 375.38381 -289.637498) (xy 375.413239 -289.596018) (xy 375.448687 -289.559547)
			(xy 375.489314 -289.528951) (xy 375.534157 -289.504956) (xy 375.582153 -289.48813) (xy 375.607072 -289.483038)
			(xy 375.631202 -289.478466) (xy 375.845578 -289.073082) (xy 375.835672 -289.050476) (xy 375.826709 -289.029398)
			(xy 375.814064 -288.985377) (xy 375.807649 -288.940026) (xy 375.807224 -288.917126) (xy 375.807732 -288.891219)
			(xy 375.815838 -288.840042) (xy 375.83185 -288.790763) (xy 375.855373 -288.744596) (xy 375.885829 -288.702677)
			(xy 375.922467 -288.666039) (xy 375.964386 -288.635583) (xy 376.010553 -288.61206) (xy 376.059832 -288.596048)
			(xy 376.111009 -288.587942) (xy 376.162823 -288.587942) (xy 376.214 -288.596048) (xy 376.263279 -288.61206)
			(xy 376.309446 -288.635583) (xy 376.351365 -288.666039) (xy 376.388003 -288.702677) (xy 376.418459 -288.744596)
			(xy 376.441982 -288.790763) (xy 376.457994 -288.840042) (xy 376.4661 -288.891219) (xy 376.466608 -288.917126)
			(xy 376.466153 -288.942575) (xy 376.458349 -288.992871) (xy 376.442899 -289.041367) (xy 376.420171 -289.086909)
			(xy 376.390707 -289.128411) (xy 376.355209 -289.164887) (xy 376.314521 -289.195466) (xy 376.269613 -289.21942)
			(xy 376.221553 -289.23618) (xy 376.196606 -289.24123) (xy 376.172476 -289.245802) (xy 375.9581 -289.651186)
			(xy 375.968006 -289.673792) (xy 375.976928 -289.694877) (xy 375.989478 -289.738907) (xy 375.99581 -289.78425)
			(xy 375.9962 -289.807142) (xy 377.216924 -289.807142) (xy 377.217411 -289.781712) (xy 377.225244 -289.73146)
			(xy 377.240699 -289.683005) (xy 377.26341 -289.637498) (xy 377.292839 -289.596018) (xy 377.328287 -289.559547)
			(xy 377.368914 -289.528951) (xy 377.413757 -289.504956) (xy 377.461753 -289.48813) (xy 377.486672 -289.483038)
			(xy 377.510802 -289.478466) (xy 377.725178 -289.073082) (xy 377.715272 -289.050476) (xy 377.706309 -289.029398)
			(xy 377.693664 -288.985377) (xy 377.687249 -288.940026) (xy 377.686824 -288.917126) (xy 377.687332 -288.891219)
			(xy 377.695438 -288.840042) (xy 377.71145 -288.790763) (xy 377.734973 -288.744596) (xy 377.765429 -288.702677)
			(xy 377.802067 -288.666039) (xy 377.843986 -288.635583) (xy 377.890153 -288.61206) (xy 377.939432 -288.596048)
			(xy 377.990609 -288.587942) (xy 378.042423 -288.587942) (xy 378.0936 -288.596048) (xy 378.142879 -288.61206)
			(xy 378.189046 -288.635583) (xy 378.230965 -288.666039) (xy 378.267603 -288.702677) (xy 378.298059 -288.744596)
			(xy 378.321582 -288.790763) (xy 378.337594 -288.840042) (xy 378.3457 -288.891219) (xy 378.346208 -288.917126)
			(xy 378.345753 -288.942575) (xy 378.337949 -288.992871) (xy 378.322499 -289.041367) (xy 378.299771 -289.086909)
			(xy 378.270307 -289.128411) (xy 378.234809 -289.164887) (xy 378.194121 -289.195466) (xy 378.149213 -289.21942)
			(xy 378.101153 -289.23618) (xy 378.076206 -289.24123) (xy 378.052076 -289.245802) (xy 377.8377 -289.651186)
			(xy 377.847606 -289.673792) (xy 377.856528 -289.694877) (xy 377.869078 -289.738907) (xy 377.87541 -289.78425)
			(xy 377.8758 -289.807142) (xy 379.096524 -289.807142) (xy 379.097011 -289.781712) (xy 379.104844 -289.73146)
			(xy 379.120299 -289.683005) (xy 379.14301 -289.637498) (xy 379.172439 -289.596018) (xy 379.207887 -289.559547)
			(xy 379.248514 -289.528951) (xy 379.293357 -289.504956) (xy 379.341353 -289.48813) (xy 379.366272 -289.483038)
			(xy 379.390402 -289.478466) (xy 379.604778 -289.073082) (xy 379.594872 -289.050476) (xy 379.585909 -289.029398)
			(xy 379.573264 -288.985377) (xy 379.566849 -288.940026) (xy 379.566424 -288.917126) (xy 379.566932 -288.891219)
			(xy 379.575038 -288.840042) (xy 379.59105 -288.790763) (xy 379.614573 -288.744596) (xy 379.645029 -288.702677)
			(xy 379.681667 -288.666039) (xy 379.723586 -288.635583) (xy 379.769753 -288.61206) (xy 379.819032 -288.596048)
			(xy 379.870209 -288.587942) (xy 379.922023 -288.587942) (xy 379.9732 -288.596048) (xy 380.022479 -288.61206)
			(xy 380.068646 -288.635583) (xy 380.110565 -288.666039) (xy 380.147203 -288.702677) (xy 380.177659 -288.744596)
			(xy 380.201182 -288.790763) (xy 380.217194 -288.840042) (xy 380.2253 -288.891219) (xy 380.225808 -288.917126)
			(xy 380.225353 -288.942575) (xy 380.217549 -288.992871) (xy 380.202099 -289.041367) (xy 380.179371 -289.086909)
			(xy 380.149907 -289.128411) (xy 380.114409 -289.164887) (xy 380.073721 -289.195466) (xy 380.028813 -289.21942)
			(xy 379.980753 -289.23618) (xy 379.955806 -289.24123) (xy 379.931676 -289.245802) (xy 379.7173 -289.651186)
			(xy 379.727206 -289.673792) (xy 379.736128 -289.694877) (xy 379.748678 -289.738907) (xy 379.75501 -289.78425)
			(xy 379.7554 -289.807142) (xy 380.976124 -289.807142) (xy 380.976611 -289.781712) (xy 380.984444 -289.73146)
			(xy 380.999899 -289.683005) (xy 381.02261 -289.637498) (xy 381.052039 -289.596018) (xy 381.087487 -289.559547)
			(xy 381.128114 -289.528951) (xy 381.172957 -289.504956) (xy 381.220953 -289.48813) (xy 381.245872 -289.483038)
			(xy 381.270002 -289.478466) (xy 381.484378 -289.073082) (xy 381.474472 -289.050476) (xy 381.465509 -289.029398)
			(xy 381.452864 -288.985377) (xy 381.446449 -288.940026) (xy 381.446024 -288.917126) (xy 381.446532 -288.891219)
			(xy 381.454638 -288.840042) (xy 381.47065 -288.790763) (xy 381.494173 -288.744596) (xy 381.524629 -288.702677)
			(xy 381.561267 -288.666039) (xy 381.603186 -288.635583) (xy 381.649353 -288.61206) (xy 381.698632 -288.596048)
			(xy 381.749809 -288.587942) (xy 381.801623 -288.587942) (xy 381.8528 -288.596048) (xy 381.902079 -288.61206)
			(xy 381.948246 -288.635583) (xy 381.990165 -288.666039) (xy 382.026803 -288.702677) (xy 382.057259 -288.744596)
			(xy 382.080782 -288.790763) (xy 382.096794 -288.840042) (xy 382.1049 -288.891219) (xy 382.105408 -288.917126)
			(xy 382.104953 -288.942575) (xy 382.097149 -288.992871) (xy 382.081699 -289.041367) (xy 382.058971 -289.086909)
			(xy 382.029507 -289.128411) (xy 381.994009 -289.164887) (xy 381.953321 -289.195466) (xy 381.908413 -289.21942)
			(xy 381.860353 -289.23618) (xy 381.835406 -289.24123) (xy 381.811276 -289.245802) (xy 381.5969 -289.651186)
			(xy 381.606806 -289.673792) (xy 381.615728 -289.694877) (xy 381.628278 -289.738907) (xy 381.63461 -289.78425)
			(xy 381.635 -289.807142) (xy 381.634492 -289.833029) (xy 381.626393 -289.884167) (xy 381.610394 -289.933407)
			(xy 381.586888 -289.979539) (xy 381.556456 -290.021426) (xy 381.519846 -290.058036) (xy 381.477959 -290.088468)
			(xy 381.431827 -290.111974) (xy 381.382587 -290.127973) (xy 381.331449 -290.136072) (xy 381.279675 -290.136072)
			(xy 381.228537 -290.127973) (xy 381.179297 -290.111974) (xy 381.133165 -290.088468) (xy 381.091278 -290.058036)
			(xy 381.054668 -290.021426) (xy 381.024236 -289.979539) (xy 381.00073 -289.933407) (xy 380.984731 -289.884167)
			(xy 380.976632 -289.833029) (xy 380.976124 -289.807142) (xy 379.7554 -289.807142) (xy 379.754892 -289.833029)
			(xy 379.746793 -289.884167) (xy 379.730794 -289.933407) (xy 379.707288 -289.979539) (xy 379.676856 -290.021426)
			(xy 379.640246 -290.058036) (xy 379.598359 -290.088468) (xy 379.552227 -290.111974) (xy 379.502987 -290.127973)
			(xy 379.451849 -290.136072) (xy 379.400075 -290.136072) (xy 379.348937 -290.127973) (xy 379.299697 -290.111974)
			(xy 379.253565 -290.088468) (xy 379.211678 -290.058036) (xy 379.175068 -290.021426) (xy 379.144636 -289.979539)
			(xy 379.12113 -289.933407) (xy 379.105131 -289.884167) (xy 379.097032 -289.833029) (xy 379.096524 -289.807142)
			(xy 377.8758 -289.807142) (xy 377.875292 -289.833029) (xy 377.867193 -289.884167) (xy 377.851194 -289.933407)
			(xy 377.827688 -289.979539) (xy 377.797256 -290.021426) (xy 377.760646 -290.058036) (xy 377.718759 -290.088468)
			(xy 377.672627 -290.111974) (xy 377.623387 -290.127973) (xy 377.572249 -290.136072) (xy 377.520475 -290.136072)
			(xy 377.469337 -290.127973) (xy 377.420097 -290.111974) (xy 377.373965 -290.088468) (xy 377.332078 -290.058036)
			(xy 377.295468 -290.021426) (xy 377.265036 -289.979539) (xy 377.24153 -289.933407) (xy 377.225531 -289.884167)
			(xy 377.217432 -289.833029) (xy 377.216924 -289.807142) (xy 375.9962 -289.807142) (xy 375.995692 -289.833029)
			(xy 375.987593 -289.884167) (xy 375.971594 -289.933407) (xy 375.948088 -289.979539) (xy 375.917656 -290.021426)
			(xy 375.881046 -290.058036) (xy 375.839159 -290.088468) (xy 375.793027 -290.111974) (xy 375.743787 -290.127973)
			(xy 375.692649 -290.136072) (xy 375.640875 -290.136072) (xy 375.589737 -290.127973) (xy 375.540497 -290.111974)
			(xy 375.494365 -290.088468) (xy 375.452478 -290.058036) (xy 375.415868 -290.021426) (xy 375.385436 -289.979539)
			(xy 375.36193 -289.933407) (xy 375.345931 -289.884167) (xy 375.337832 -289.833029) (xy 375.337324 -289.807142)
			(xy 374.1166 -289.807142) (xy 374.116092 -289.833029) (xy 374.107993 -289.884167) (xy 374.091994 -289.933407)
			(xy 374.068488 -289.979539) (xy 374.038056 -290.021426) (xy 374.001446 -290.058036) (xy 373.959559 -290.088468)
			(xy 373.913427 -290.111974) (xy 373.864187 -290.127973) (xy 373.813049 -290.136072) (xy 373.761275 -290.136072)
			(xy 373.710137 -290.127973) (xy 373.660897 -290.111974) (xy 373.614765 -290.088468) (xy 373.572878 -290.058036)
			(xy 373.536268 -290.021426) (xy 373.505836 -289.979539) (xy 373.48233 -289.933407) (xy 373.466331 -289.884167)
			(xy 373.458232 -289.833029) (xy 373.457724 -289.807142) (xy 372.237 -289.807142) (xy 372.236492 -289.833029)
			(xy 372.228393 -289.884167) (xy 372.212394 -289.933407) (xy 372.188888 -289.979539) (xy 372.158456 -290.021426)
			(xy 372.121846 -290.058036) (xy 372.079959 -290.088468) (xy 372.033827 -290.111974) (xy 371.984587 -290.127973)
			(xy 371.933449 -290.136072) (xy 371.881675 -290.136072) (xy 371.830537 -290.127973) (xy 371.781297 -290.111974)
			(xy 371.735165 -290.088468) (xy 371.693278 -290.058036) (xy 371.656668 -290.021426) (xy 371.626236 -289.979539)
			(xy 371.60273 -289.933407) (xy 371.586731 -289.884167) (xy 371.578632 -289.833029) (xy 371.578124 -289.807142)
			(xy 370.3574 -289.807142) (xy 370.356892 -289.833029) (xy 370.348793 -289.884167) (xy 370.332794 -289.933407)
			(xy 370.309288 -289.979539) (xy 370.278856 -290.021426) (xy 370.242246 -290.058036) (xy 370.200359 -290.088468)
			(xy 370.154227 -290.111974) (xy 370.104987 -290.127973) (xy 370.053849 -290.136072) (xy 370.002075 -290.136072)
			(xy 369.950937 -290.127973) (xy 369.901697 -290.111974) (xy 369.855565 -290.088468) (xy 369.813678 -290.058036)
			(xy 369.777068 -290.021426) (xy 369.746636 -289.979539) (xy 369.72313 -289.933407) (xy 369.707131 -289.884167)
			(xy 369.699032 -289.833029) (xy 369.698524 -289.807142) (xy 368.4778 -289.807142) (xy 368.477292 -289.833029)
			(xy 368.469193 -289.884167) (xy 368.453194 -289.933407) (xy 368.429688 -289.979539) (xy 368.399256 -290.021426)
			(xy 368.362646 -290.058036) (xy 368.320759 -290.088468) (xy 368.274627 -290.111974) (xy 368.225387 -290.127973)
			(xy 368.174249 -290.136072) (xy 368.122475 -290.136072) (xy 368.071337 -290.127973) (xy 368.022097 -290.111974)
			(xy 367.975965 -290.088468) (xy 367.934078 -290.058036) (xy 367.897468 -290.021426) (xy 367.867036 -289.979539)
			(xy 367.84353 -289.933407) (xy 367.827531 -289.884167) (xy 367.819432 -289.833029) (xy 367.818924 -289.807142)
			(xy 351.5614 -289.807142) (xy 351.560892 -289.833029) (xy 351.552793 -289.884167) (xy 351.536794 -289.933407)
			(xy 351.513288 -289.979539) (xy 351.482856 -290.021426) (xy 351.446246 -290.058036) (xy 351.404359 -290.088468)
			(xy 351.358227 -290.111974) (xy 351.308987 -290.127973) (xy 351.257849 -290.136072) (xy 351.206075 -290.136072)
			(xy 351.154937 -290.127973) (xy 351.105697 -290.111974) (xy 351.059565 -290.088468) (xy 351.017678 -290.058036)
			(xy 350.981068 -290.021426) (xy 350.950636 -289.979539) (xy 350.92713 -289.933407) (xy 350.911131 -289.884167)
			(xy 350.903032 -289.833029) (xy 350.902524 -289.807142) (xy 350.902524 -289.806634) (xy 350.902922 -289.783785)
			(xy 350.909275 -289.738531) (xy 350.921824 -289.694589) (xy 350.930718 -289.673538) (xy 350.940624 -289.650932)
			(xy 350.726756 -289.245802) (xy 350.702626 -289.24123) (xy 350.677682 -289.236182) (xy 350.629639 -289.219398)
			(xy 350.584746 -289.195428) (xy 350.544072 -289.164843) (xy 350.508582 -289.128369) (xy 350.479121 -289.086873)
			(xy 350.456389 -289.041341) (xy 350.440925 -288.992857) (xy 350.433099 -288.942571) (xy 350.432624 -288.917126)
			(xy 350.152208 -288.917126) (xy 350.1517 -288.943033) (xy 350.143594 -288.99421) (xy 350.127582 -289.043489)
			(xy 350.104059 -289.089656) (xy 350.073603 -289.131575) (xy 350.036965 -289.168213) (xy 349.995046 -289.198669)
			(xy 349.948879 -289.222192) (xy 349.8996 -289.238204) (xy 349.848423 -289.24631) (xy 349.796609 -289.24631)
			(xy 349.745432 -289.238204) (xy 349.696153 -289.222192) (xy 349.649986 -289.198669) (xy 349.608067 -289.168213)
			(xy 349.571429 -289.131575) (xy 349.540973 -289.089656) (xy 349.51745 -289.043489) (xy 349.501438 -288.99421)
			(xy 349.493332 -288.943033) (xy 349.492824 -288.917126) (xy 349.212408 -288.917126) (xy 349.211989 -288.940067)
			(xy 349.20556 -288.985498) (xy 349.192913 -289.029604) (xy 349.18396 -289.05073) (xy 349.174054 -289.073336)
			(xy 349.387922 -289.478466) (xy 349.412052 -289.483038) (xy 349.436973 -289.488138) (xy 349.484984 -289.504939)
			(xy 349.529843 -289.528919) (xy 349.570484 -289.559507) (xy 349.605941 -289.595978) (xy 349.635373 -289.637465)
			(xy 349.658079 -289.682981) (xy 349.673521 -289.731446) (xy 349.681331 -289.781709) (xy 349.6818 -289.807142)
			(xy 349.681292 -289.833029) (xy 349.673193 -289.884167) (xy 349.657194 -289.933407) (xy 349.633688 -289.979539)
			(xy 349.603256 -290.021426) (xy 349.566646 -290.058036) (xy 349.524759 -290.088468) (xy 349.478627 -290.111974)
			(xy 349.429387 -290.127973) (xy 349.378249 -290.136072) (xy 349.326475 -290.136072) (xy 349.275337 -290.127973)
			(xy 349.226097 -290.111974) (xy 349.179965 -290.088468) (xy 349.138078 -290.058036) (xy 349.101468 -290.021426)
			(xy 349.071036 -289.979539) (xy 349.04753 -289.933407) (xy 349.031531 -289.884167) (xy 349.023432 -289.833029)
			(xy 349.022924 -289.807142) (xy 349.022924 -289.806634) (xy 349.023322 -289.783785) (xy 349.029675 -289.738531)
			(xy 349.042224 -289.694589) (xy 349.051118 -289.673538) (xy 349.061024 -289.650932) (xy 348.847156 -289.245802)
			(xy 348.823026 -289.24123) (xy 348.798082 -289.236182) (xy 348.750039 -289.219398) (xy 348.705146 -289.195428)
			(xy 348.664472 -289.164843) (xy 348.628982 -289.128369) (xy 348.599521 -289.086873) (xy 348.576789 -289.041341)
			(xy 348.561325 -288.992857) (xy 348.553499 -288.942571) (xy 348.553024 -288.917126) (xy 348.272608 -288.917126)
			(xy 348.2721 -288.943033) (xy 348.263994 -288.99421) (xy 348.247982 -289.043489) (xy 348.224459 -289.089656)
			(xy 348.194003 -289.131575) (xy 348.157365 -289.168213) (xy 348.115446 -289.198669) (xy 348.069279 -289.222192)
			(xy 348.02 -289.238204) (xy 347.968823 -289.24631) (xy 347.917009 -289.24631) (xy 347.865832 -289.238204)
			(xy 347.816553 -289.222192) (xy 347.770386 -289.198669) (xy 347.728467 -289.168213) (xy 347.691829 -289.131575)
			(xy 347.661373 -289.089656) (xy 347.63785 -289.043489) (xy 347.621838 -288.99421) (xy 347.613732 -288.943033)
			(xy 347.613224 -288.917126) (xy 347.332808 -288.917126) (xy 347.332389 -288.940067) (xy 347.32596 -288.985498)
			(xy 347.313313 -289.029604) (xy 347.30436 -289.05073) (xy 347.294454 -289.073336) (xy 347.508322 -289.478466)
			(xy 347.532452 -289.483038) (xy 347.557373 -289.488138) (xy 347.605384 -289.504939) (xy 347.650243 -289.528919)
			(xy 347.690884 -289.559507) (xy 347.726341 -289.595978) (xy 347.755773 -289.637465) (xy 347.778479 -289.682981)
			(xy 347.793921 -289.731446) (xy 347.801731 -289.781709) (xy 347.8022 -289.807142) (xy 347.801692 -289.833029)
			(xy 347.793593 -289.884167) (xy 347.777594 -289.933407) (xy 347.754088 -289.979539) (xy 347.723656 -290.021426)
			(xy 347.687046 -290.058036) (xy 347.645159 -290.088468) (xy 347.599027 -290.111974) (xy 347.549787 -290.127973)
			(xy 347.498649 -290.136072) (xy 347.446875 -290.136072) (xy 347.395737 -290.127973) (xy 347.346497 -290.111974)
			(xy 347.300365 -290.088468) (xy 347.258478 -290.058036) (xy 347.221868 -290.021426) (xy 347.191436 -289.979539)
			(xy 347.16793 -289.933407) (xy 347.151931 -289.884167) (xy 347.143832 -289.833029) (xy 347.143324 -289.807142)
			(xy 347.143324 -289.806634) (xy 347.143722 -289.783785) (xy 347.150075 -289.738531) (xy 347.162624 -289.694589)
			(xy 347.171518 -289.673538) (xy 347.181424 -289.650932) (xy 346.967556 -289.245802) (xy 346.943426 -289.24123)
			(xy 346.918482 -289.236182) (xy 346.870439 -289.219398) (xy 346.825546 -289.195428) (xy 346.784872 -289.164843)
			(xy 346.749382 -289.128369) (xy 346.719921 -289.086873) (xy 346.697189 -289.041341) (xy 346.681725 -288.992857)
			(xy 346.673899 -288.942571) (xy 346.673424 -288.917126) (xy 346.393008 -288.917126) (xy 346.3925 -288.943033)
			(xy 346.384394 -288.99421) (xy 346.368382 -289.043489) (xy 346.344859 -289.089656) (xy 346.314403 -289.131575)
			(xy 346.277765 -289.168213) (xy 346.235846 -289.198669) (xy 346.189679 -289.222192) (xy 346.1404 -289.238204)
			(xy 346.089223 -289.24631) (xy 346.037409 -289.24631) (xy 345.986232 -289.238204) (xy 345.936953 -289.222192)
			(xy 345.890786 -289.198669) (xy 345.848867 -289.168213) (xy 345.812229 -289.131575) (xy 345.781773 -289.089656)
			(xy 345.75825 -289.043489) (xy 345.742238 -288.99421) (xy 345.734132 -288.943033) (xy 345.733624 -288.917126)
			(xy 345.453208 -288.917126) (xy 345.452789 -288.940067) (xy 345.44636 -288.985498) (xy 345.433713 -289.029604)
			(xy 345.42476 -289.05073) (xy 345.414854 -289.073336) (xy 345.628722 -289.478466) (xy 345.652852 -289.483038)
			(xy 345.677773 -289.488138) (xy 345.725784 -289.504939) (xy 345.770643 -289.528919) (xy 345.811284 -289.559507)
			(xy 345.846741 -289.595978) (xy 345.876173 -289.637465) (xy 345.898879 -289.682981) (xy 345.914321 -289.731446)
			(xy 345.922131 -289.781709) (xy 345.9226 -289.807142) (xy 345.922092 -289.833029) (xy 345.913993 -289.884167)
			(xy 345.897994 -289.933407) (xy 345.874488 -289.979539) (xy 345.844056 -290.021426) (xy 345.807446 -290.058036)
			(xy 345.765559 -290.088468) (xy 345.719427 -290.111974) (xy 345.670187 -290.127973) (xy 345.619049 -290.136072)
			(xy 345.567275 -290.136072) (xy 345.516137 -290.127973) (xy 345.466897 -290.111974) (xy 345.420765 -290.088468)
			(xy 345.378878 -290.058036) (xy 345.342268 -290.021426) (xy 345.311836 -289.979539) (xy 345.28833 -289.933407)
			(xy 345.272331 -289.884167) (xy 345.264232 -289.833029) (xy 345.263724 -289.807142) (xy 345.263724 -289.806634)
			(xy 345.264122 -289.783785) (xy 345.270475 -289.738531) (xy 345.283024 -289.694589) (xy 345.291918 -289.673538)
			(xy 345.301824 -289.650932) (xy 345.087956 -289.245802) (xy 345.063826 -289.24123) (xy 345.038882 -289.236182)
			(xy 344.990839 -289.219398) (xy 344.945946 -289.195428) (xy 344.905272 -289.164843) (xy 344.869782 -289.128369)
			(xy 344.840321 -289.086873) (xy 344.817589 -289.041341) (xy 344.802125 -288.992857) (xy 344.794299 -288.942571)
			(xy 344.793824 -288.917126) (xy 344.513408 -288.917126) (xy 344.5129 -288.943033) (xy 344.504794 -288.99421)
			(xy 344.488782 -289.043489) (xy 344.465259 -289.089656) (xy 344.434803 -289.131575) (xy 344.398165 -289.168213)
			(xy 344.356246 -289.198669) (xy 344.310079 -289.222192) (xy 344.2608 -289.238204) (xy 344.209623 -289.24631)
			(xy 344.157809 -289.24631) (xy 344.106632 -289.238204) (xy 344.057353 -289.222192) (xy 344.011186 -289.198669)
			(xy 343.969267 -289.168213) (xy 343.932629 -289.131575) (xy 343.902173 -289.089656) (xy 343.87865 -289.043489)
			(xy 343.862638 -288.99421) (xy 343.854532 -288.943033) (xy 343.854024 -288.917126) (xy 343.573608 -288.917126)
			(xy 343.573189 -288.940067) (xy 343.56676 -288.985498) (xy 343.554113 -289.029604) (xy 343.54516 -289.05073)
			(xy 343.535254 -289.073336) (xy 343.749122 -289.478466) (xy 343.773252 -289.483038) (xy 343.798173 -289.488138)
			(xy 343.846184 -289.504939) (xy 343.891043 -289.528919) (xy 343.931684 -289.559507) (xy 343.967141 -289.595978)
			(xy 343.996573 -289.637465) (xy 344.019279 -289.682981) (xy 344.034721 -289.731446) (xy 344.042531 -289.781709)
			(xy 344.043 -289.807142) (xy 344.042492 -289.833029) (xy 344.034393 -289.884167) (xy 344.018394 -289.933407)
			(xy 343.994888 -289.979539) (xy 343.964456 -290.021426) (xy 343.927846 -290.058036) (xy 343.885959 -290.088468)
			(xy 343.839827 -290.111974) (xy 343.790587 -290.127973) (xy 343.739449 -290.136072) (xy 343.687675 -290.136072)
			(xy 343.636537 -290.127973) (xy 343.587297 -290.111974) (xy 343.541165 -290.088468) (xy 343.499278 -290.058036)
			(xy 343.462668 -290.021426) (xy 343.432236 -289.979539) (xy 343.40873 -289.933407) (xy 343.392731 -289.884167)
			(xy 343.384632 -289.833029) (xy 343.384124 -289.807142) (xy 343.384124 -289.806634) (xy 343.384522 -289.783785)
			(xy 343.390875 -289.738531) (xy 343.403424 -289.694589) (xy 343.412318 -289.673538) (xy 343.422224 -289.650932)
			(xy 343.208356 -289.245802) (xy 343.184226 -289.24123) (xy 343.159282 -289.236182) (xy 343.111239 -289.219398)
			(xy 343.066346 -289.195428) (xy 343.025672 -289.164843) (xy 342.990182 -289.128369) (xy 342.960721 -289.086873)
			(xy 342.937989 -289.041341) (xy 342.922525 -288.992857) (xy 342.914699 -288.942571) (xy 342.914224 -288.917126)
			(xy 342.633808 -288.917126) (xy 342.6333 -288.943033) (xy 342.625194 -288.99421) (xy 342.609182 -289.043489)
			(xy 342.585659 -289.089656) (xy 342.555203 -289.131575) (xy 342.518565 -289.168213) (xy 342.476646 -289.198669)
			(xy 342.430479 -289.222192) (xy 342.3812 -289.238204) (xy 342.330023 -289.24631) (xy 342.278209 -289.24631)
			(xy 342.227032 -289.238204) (xy 342.177753 -289.222192) (xy 342.131586 -289.198669) (xy 342.089667 -289.168213)
			(xy 342.053029 -289.131575) (xy 342.022573 -289.089656) (xy 341.99905 -289.043489) (xy 341.983038 -288.99421)
			(xy 341.974932 -288.943033) (xy 341.974424 -288.917126) (xy 341.694008 -288.917126) (xy 341.693589 -288.940067)
			(xy 341.68716 -288.985498) (xy 341.674513 -289.029604) (xy 341.66556 -289.05073) (xy 341.655654 -289.073336)
			(xy 341.869522 -289.478466) (xy 341.893652 -289.483038) (xy 341.918573 -289.488138) (xy 341.966584 -289.504939)
			(xy 342.011443 -289.528919) (xy 342.052084 -289.559507) (xy 342.087541 -289.595978) (xy 342.116973 -289.637465)
			(xy 342.139679 -289.682981) (xy 342.155121 -289.731446) (xy 342.162931 -289.781709) (xy 342.1634 -289.807142)
			(xy 342.162892 -289.833029) (xy 342.154793 -289.884167) (xy 342.138794 -289.933407) (xy 342.115288 -289.979539)
			(xy 342.084856 -290.021426) (xy 342.048246 -290.058036) (xy 342.006359 -290.088468) (xy 341.960227 -290.111974)
			(xy 341.910987 -290.127973) (xy 341.859849 -290.136072) (xy 341.808075 -290.136072) (xy 341.756937 -290.127973)
			(xy 341.707697 -290.111974) (xy 341.661565 -290.088468) (xy 341.619678 -290.058036) (xy 341.583068 -290.021426)
			(xy 341.552636 -289.979539) (xy 341.52913 -289.933407) (xy 341.513131 -289.884167) (xy 341.505032 -289.833029)
			(xy 341.504524 -289.807142) (xy 341.504524 -289.806634) (xy 341.504922 -289.783785) (xy 341.511275 -289.738531)
			(xy 341.523824 -289.694589) (xy 341.532718 -289.673538) (xy 341.542624 -289.650932) (xy 341.328756 -289.245802)
			(xy 341.304626 -289.24123) (xy 341.279682 -289.236182) (xy 341.231639 -289.219398) (xy 341.186746 -289.195428)
			(xy 341.146072 -289.164843) (xy 341.110582 -289.128369) (xy 341.081121 -289.086873) (xy 341.058389 -289.041341)
			(xy 341.042925 -288.992857) (xy 341.035099 -288.942571) (xy 341.034624 -288.917126) (xy 340.754208 -288.917126)
			(xy 340.7537 -288.943033) (xy 340.745594 -288.99421) (xy 340.729582 -289.043489) (xy 340.706059 -289.089656)
			(xy 340.675603 -289.131575) (xy 340.638965 -289.168213) (xy 340.597046 -289.198669) (xy 340.550879 -289.222192)
			(xy 340.5016 -289.238204) (xy 340.450423 -289.24631) (xy 340.398609 -289.24631) (xy 340.347432 -289.238204)
			(xy 340.298153 -289.222192) (xy 340.251986 -289.198669) (xy 340.210067 -289.168213) (xy 340.173429 -289.131575)
			(xy 340.142973 -289.089656) (xy 340.11945 -289.043489) (xy 340.103438 -288.99421) (xy 340.095332 -288.943033)
			(xy 340.094824 -288.917126) (xy 339.814408 -288.917126) (xy 339.813989 -288.940067) (xy 339.80756 -288.985498)
			(xy 339.794913 -289.029604) (xy 339.78596 -289.05073) (xy 339.776054 -289.073336) (xy 339.989922 -289.478466)
			(xy 340.014052 -289.483038) (xy 340.038973 -289.488138) (xy 340.086984 -289.504939) (xy 340.131843 -289.528919)
			(xy 340.172484 -289.559507) (xy 340.207941 -289.595978) (xy 340.237373 -289.637465) (xy 340.260079 -289.682981)
			(xy 340.275521 -289.731446) (xy 340.283331 -289.781709) (xy 340.2838 -289.807142) (xy 340.283292 -289.833029)
			(xy 340.275193 -289.884167) (xy 340.259194 -289.933407) (xy 340.235688 -289.979539) (xy 340.205256 -290.021426)
			(xy 340.168646 -290.058036) (xy 340.126759 -290.088468) (xy 340.080627 -290.111974) (xy 340.031387 -290.127973)
			(xy 339.980249 -290.136072) (xy 339.928475 -290.136072) (xy 339.877337 -290.127973) (xy 339.828097 -290.111974)
			(xy 339.781965 -290.088468) (xy 339.740078 -290.058036) (xy 339.703468 -290.021426) (xy 339.673036 -289.979539)
			(xy 339.64953 -289.933407) (xy 339.633531 -289.884167) (xy 339.625432 -289.833029) (xy 339.624924 -289.807142)
			(xy 339.624924 -289.806634) (xy 339.625322 -289.783785) (xy 339.631675 -289.738531) (xy 339.644224 -289.694589)
			(xy 339.653118 -289.673538) (xy 339.663024 -289.650932) (xy 339.449156 -289.245802) (xy 339.425026 -289.24123)
			(xy 339.400082 -289.236182) (xy 339.352039 -289.219398) (xy 339.307146 -289.195428) (xy 339.266472 -289.164843)
			(xy 339.230982 -289.128369) (xy 339.201521 -289.086873) (xy 339.178789 -289.041341) (xy 339.163325 -288.992857)
			(xy 339.155499 -288.942571) (xy 339.155024 -288.917126) (xy 338.874608 -288.917126) (xy 338.8741 -288.943033)
			(xy 338.865994 -288.99421) (xy 338.849982 -289.043489) (xy 338.826459 -289.089656) (xy 338.796003 -289.131575)
			(xy 338.759365 -289.168213) (xy 338.717446 -289.198669) (xy 338.671279 -289.222192) (xy 338.622 -289.238204)
			(xy 338.570823 -289.24631) (xy 338.519009 -289.24631) (xy 338.467832 -289.238204) (xy 338.418553 -289.222192)
			(xy 338.372386 -289.198669) (xy 338.330467 -289.168213) (xy 338.293829 -289.131575) (xy 338.263373 -289.089656)
			(xy 338.23985 -289.043489) (xy 338.223838 -288.99421) (xy 338.215732 -288.943033) (xy 338.215224 -288.917126)
			(xy 336.995008 -288.917126) (xy 336.9945 -288.943033) (xy 336.986394 -288.99421) (xy 336.970382 -289.043489)
			(xy 336.946859 -289.089656) (xy 336.916403 -289.131575) (xy 336.879765 -289.168213) (xy 336.837846 -289.198669)
			(xy 336.791679 -289.222192) (xy 336.7424 -289.238204) (xy 336.691223 -289.24631) (xy 336.639409 -289.24631)
			(xy 336.588232 -289.238204) (xy 336.538953 -289.222192) (xy 336.492786 -289.198669) (xy 336.450867 -289.168213)
			(xy 336.414229 -289.131575) (xy 336.383773 -289.089656) (xy 336.36025 -289.043489) (xy 336.344238 -288.99421)
			(xy 336.336132 -288.943033) (xy 336.335624 -288.917126) (xy 136.04494 -288.917126) (xy 136.044432 -288.943033)
			(xy 136.036326 -288.99421) (xy 136.020314 -289.043489) (xy 135.996791 -289.089656) (xy 135.966335 -289.131575)
			(xy 135.929697 -289.168213) (xy 135.887778 -289.198669) (xy 135.841611 -289.222192) (xy 135.792332 -289.238204)
			(xy 135.741155 -289.24631) (xy 135.689341 -289.24631) (xy 135.638164 -289.238204) (xy 135.588885 -289.222192)
			(xy 135.542718 -289.198669) (xy 135.500799 -289.168213) (xy 135.464161 -289.131575) (xy 135.433705 -289.089656)
			(xy 135.410182 -289.043489) (xy 135.39417 -288.99421) (xy 135.386064 -288.943033) (xy 135.385556 -288.917126)
			(xy 135.386153 -288.889409) (xy 135.395474 -288.834762) (xy 135.404098 -288.808414) (xy 135.411972 -288.786316)
			(xy 135.20674 -288.431224) (xy 135.18388 -288.426906) (xy 135.159064 -288.421716) (xy 135.111285 -288.404766)
			(xy 135.066665 -288.380698) (xy 135.026258 -288.350081) (xy 134.991016 -288.313637) (xy 134.961772 -288.272226)
			(xy 134.939214 -288.226825) (xy 134.923875 -288.178504) (xy 134.916118 -288.128404) (xy 134.915656 -288.103056)
			(xy 132.75564 -288.103056) (xy 132.755038 -288.130773) (xy 132.74572 -288.18542) (xy 132.737098 -288.211768)
			(xy 132.729478 -288.233866) (xy 132.934456 -288.588958) (xy 132.957316 -288.593276) (xy 132.982127 -288.598486)
			(xy 133.029905 -288.615434) (xy 133.074524 -288.6395) (xy 133.114931 -288.670114) (xy 133.150173 -288.706556)
			(xy 133.179418 -288.747964) (xy 133.201977 -288.793363) (xy 133.217317 -288.841681) (xy 133.225077 -288.891779)
			(xy 133.22554 -288.917126) (xy 133.225032 -288.943033) (xy 133.216926 -288.99421) (xy 133.200914 -289.043489)
			(xy 133.177391 -289.089656) (xy 133.146935 -289.131575) (xy 133.110297 -289.168213) (xy 133.068378 -289.198669)
			(xy 133.022211 -289.222192) (xy 132.972932 -289.238204) (xy 132.921755 -289.24631) (xy 132.869941 -289.24631)
			(xy 132.818764 -289.238204) (xy 132.769485 -289.222192) (xy 132.723318 -289.198669) (xy 132.681399 -289.168213)
			(xy 132.644761 -289.131575) (xy 132.614305 -289.089656) (xy 132.590782 -289.043489) (xy 132.57477 -288.99421)
			(xy 132.566664 -288.943033) (xy 132.566156 -288.917126) (xy 132.566753 -288.889409) (xy 132.576074 -288.834762)
			(xy 132.584698 -288.808414) (xy 132.592572 -288.786316) (xy 132.387594 -288.431224) (xy 132.364734 -288.426906)
			(xy 132.339899 -288.421756) (xy 132.292089 -288.404821) (xy 132.247438 -288.380764) (xy 132.206999 -288.350151)
			(xy 132.171726 -288.313705) (xy 132.142451 -288.272287) (xy 132.119866 -288.226873) (xy 132.104504 -288.178536)
			(xy 132.096726 -288.128416) (xy 132.096256 -288.103056) (xy 130.87604 -288.103056) (xy 130.875438 -288.130773)
			(xy 130.86612 -288.18542) (xy 130.857498 -288.211768) (xy 130.849878 -288.233866) (xy 131.054856 -288.588958)
			(xy 131.077716 -288.593276) (xy 131.102527 -288.598486) (xy 131.150305 -288.615434) (xy 131.194924 -288.6395)
			(xy 131.235331 -288.670114) (xy 131.270573 -288.706556) (xy 131.299818 -288.747964) (xy 131.322377 -288.793363)
			(xy 131.337717 -288.841681) (xy 131.345477 -288.891779) (xy 131.34594 -288.917126) (xy 131.345432 -288.943033)
			(xy 131.337326 -288.99421) (xy 131.321314 -289.043489) (xy 131.297791 -289.089656) (xy 131.267335 -289.131575)
			(xy 131.230697 -289.168213) (xy 131.188778 -289.198669) (xy 131.142611 -289.222192) (xy 131.093332 -289.238204)
			(xy 131.042155 -289.24631) (xy 130.990341 -289.24631) (xy 130.939164 -289.238204) (xy 130.889885 -289.222192)
			(xy 130.843718 -289.198669) (xy 130.801799 -289.168213) (xy 130.765161 -289.131575) (xy 130.734705 -289.089656)
			(xy 130.711182 -289.043489) (xy 130.69517 -288.99421) (xy 130.687064 -288.943033) (xy 130.686556 -288.917126)
			(xy 130.687153 -288.889409) (xy 130.696474 -288.834762) (xy 130.705098 -288.808414) (xy 130.712972 -288.786316)
			(xy 130.507994 -288.431224) (xy 130.485134 -288.426906) (xy 130.460299 -288.421756) (xy 130.412489 -288.404821)
			(xy 130.367838 -288.380764) (xy 130.327399 -288.350151) (xy 130.292126 -288.313705) (xy 130.262851 -288.272287)
			(xy 130.240266 -288.226873) (xy 130.224904 -288.178536) (xy 130.217126 -288.128416) (xy 130.216656 -288.103056)
			(xy 128.99644 -288.103056) (xy 128.995838 -288.130773) (xy 128.98652 -288.18542) (xy 128.977898 -288.211768)
			(xy 128.970278 -288.233866) (xy 129.175256 -288.588958) (xy 129.198116 -288.593276) (xy 129.222927 -288.598486)
			(xy 129.270705 -288.615434) (xy 129.315324 -288.6395) (xy 129.355731 -288.670114) (xy 129.390973 -288.706556)
			(xy 129.420218 -288.747964) (xy 129.442777 -288.793363) (xy 129.458117 -288.841681) (xy 129.465877 -288.891779)
			(xy 129.46634 -288.917126) (xy 129.465832 -288.943033) (xy 129.457726 -288.99421) (xy 129.441714 -289.043489)
			(xy 129.418191 -289.089656) (xy 129.387735 -289.131575) (xy 129.351097 -289.168213) (xy 129.309178 -289.198669)
			(xy 129.263011 -289.222192) (xy 129.213732 -289.238204) (xy 129.162555 -289.24631) (xy 129.110741 -289.24631)
			(xy 129.059564 -289.238204) (xy 129.010285 -289.222192) (xy 128.964118 -289.198669) (xy 128.922199 -289.168213)
			(xy 128.885561 -289.131575) (xy 128.855105 -289.089656) (xy 128.831582 -289.043489) (xy 128.81557 -288.99421)
			(xy 128.807464 -288.943033) (xy 128.806956 -288.917126) (xy 128.807553 -288.889409) (xy 128.816874 -288.834762)
			(xy 128.825498 -288.808414) (xy 128.833372 -288.786316) (xy 128.628394 -288.431224) (xy 128.605534 -288.426906)
			(xy 128.580699 -288.421756) (xy 128.532889 -288.404821) (xy 128.488238 -288.380764) (xy 128.447799 -288.350151)
			(xy 128.412526 -288.313705) (xy 128.383251 -288.272287) (xy 128.360666 -288.226873) (xy 128.345304 -288.178536)
			(xy 128.337526 -288.128416) (xy 128.337056 -288.103056) (xy 127.11684 -288.103056) (xy 127.116238 -288.130773)
			(xy 127.10692 -288.18542) (xy 127.098298 -288.211768) (xy 127.090678 -288.233866) (xy 127.295656 -288.588958)
			(xy 127.318516 -288.593276) (xy 127.343327 -288.598486) (xy 127.391105 -288.615434) (xy 127.435724 -288.6395)
			(xy 127.476131 -288.670114) (xy 127.511373 -288.706556) (xy 127.540618 -288.747964) (xy 127.563177 -288.793363)
			(xy 127.578517 -288.841681) (xy 127.586277 -288.891779) (xy 127.58674 -288.917126) (xy 127.586232 -288.943033)
			(xy 127.578126 -288.99421) (xy 127.562114 -289.043489) (xy 127.538591 -289.089656) (xy 127.508135 -289.131575)
			(xy 127.471497 -289.168213) (xy 127.429578 -289.198669) (xy 127.383411 -289.222192) (xy 127.334132 -289.238204)
			(xy 127.282955 -289.24631) (xy 127.231141 -289.24631) (xy 127.179964 -289.238204) (xy 127.130685 -289.222192)
			(xy 127.084518 -289.198669) (xy 127.042599 -289.168213) (xy 127.005961 -289.131575) (xy 126.975505 -289.089656)
			(xy 126.951982 -289.043489) (xy 126.93597 -288.99421) (xy 126.927864 -288.943033) (xy 126.927356 -288.917126)
			(xy 126.927953 -288.889409) (xy 126.937274 -288.834762) (xy 126.945898 -288.808414) (xy 126.953772 -288.786316)
			(xy 126.748794 -288.431224) (xy 126.725934 -288.426906) (xy 126.701099 -288.421756) (xy 126.653289 -288.404821)
			(xy 126.608638 -288.380764) (xy 126.568199 -288.350151) (xy 126.532926 -288.313705) (xy 126.503651 -288.272287)
			(xy 126.481066 -288.226873) (xy 126.465704 -288.178536) (xy 126.457926 -288.128416) (xy 126.457456 -288.103056)
			(xy 125.23724 -288.103056) (xy 125.236638 -288.130773) (xy 125.22732 -288.18542) (xy 125.218698 -288.211768)
			(xy 125.211078 -288.233866) (xy 125.416056 -288.588958) (xy 125.438916 -288.593276) (xy 125.463727 -288.598486)
			(xy 125.511505 -288.615434) (xy 125.556124 -288.6395) (xy 125.596531 -288.670114) (xy 125.631773 -288.706556)
			(xy 125.661018 -288.747964) (xy 125.683577 -288.793363) (xy 125.698917 -288.841681) (xy 125.706677 -288.891779)
			(xy 125.70714 -288.917126) (xy 125.706632 -288.943033) (xy 125.698526 -288.99421) (xy 125.682514 -289.043489)
			(xy 125.658991 -289.089656) (xy 125.628535 -289.131575) (xy 125.591897 -289.168213) (xy 125.549978 -289.198669)
			(xy 125.503811 -289.222192) (xy 125.454532 -289.238204) (xy 125.403355 -289.24631) (xy 125.351541 -289.24631)
			(xy 125.300364 -289.238204) (xy 125.251085 -289.222192) (xy 125.204918 -289.198669) (xy 125.162999 -289.168213)
			(xy 125.126361 -289.131575) (xy 125.095905 -289.089656) (xy 125.072382 -289.043489) (xy 125.05637 -288.99421)
			(xy 125.048264 -288.943033) (xy 125.047756 -288.917126) (xy 125.048353 -288.889409) (xy 125.057674 -288.834762)
			(xy 125.066298 -288.808414) (xy 125.074172 -288.786316) (xy 124.869194 -288.431224) (xy 124.846334 -288.426906)
			(xy 124.821499 -288.421756) (xy 124.773689 -288.404821) (xy 124.729038 -288.380764) (xy 124.688599 -288.350151)
			(xy 124.653326 -288.313705) (xy 124.624051 -288.272287) (xy 124.601466 -288.226873) (xy 124.586104 -288.178536)
			(xy 124.578326 -288.128416) (xy 124.577856 -288.103056) (xy 123.35764 -288.103056) (xy 123.357038 -288.130773)
			(xy 123.34772 -288.18542) (xy 123.339098 -288.211768) (xy 123.331478 -288.233866) (xy 123.536456 -288.588958)
			(xy 123.559316 -288.593276) (xy 123.584127 -288.598486) (xy 123.631905 -288.615434) (xy 123.676524 -288.6395)
			(xy 123.716931 -288.670114) (xy 123.752173 -288.706556) (xy 123.781418 -288.747964) (xy 123.803977 -288.793363)
			(xy 123.819317 -288.841681) (xy 123.827077 -288.891779) (xy 123.82754 -288.917126) (xy 123.827032 -288.943033)
			(xy 123.818926 -288.99421) (xy 123.802914 -289.043489) (xy 123.779391 -289.089656) (xy 123.748935 -289.131575)
			(xy 123.712297 -289.168213) (xy 123.670378 -289.198669) (xy 123.624211 -289.222192) (xy 123.574932 -289.238204)
			(xy 123.523755 -289.24631) (xy 123.471941 -289.24631) (xy 123.420764 -289.238204) (xy 123.371485 -289.222192)
			(xy 123.325318 -289.198669) (xy 123.283399 -289.168213) (xy 123.246761 -289.131575) (xy 123.216305 -289.089656)
			(xy 123.192782 -289.043489) (xy 123.17677 -288.99421) (xy 123.168664 -288.943033) (xy 123.168156 -288.917126)
			(xy 123.168753 -288.889409) (xy 123.178074 -288.834762) (xy 123.186698 -288.808414) (xy 123.194572 -288.786316)
			(xy 122.989594 -288.431224) (xy 122.966734 -288.426906) (xy 122.941899 -288.421756) (xy 122.894089 -288.404821)
			(xy 122.849438 -288.380764) (xy 122.808999 -288.350151) (xy 122.773726 -288.313705) (xy 122.744451 -288.272287)
			(xy 122.721866 -288.226873) (xy 122.706504 -288.178536) (xy 122.698726 -288.128416) (xy 122.698256 -288.103056)
			(xy 121.47804 -288.103056) (xy 121.477438 -288.130773) (xy 121.46812 -288.18542) (xy 121.459498 -288.211768)
			(xy 121.451624 -288.233866) (xy 121.656856 -288.588958) (xy 121.679716 -288.593276) (xy 121.704527 -288.598486)
			(xy 121.752305 -288.615434) (xy 121.796924 -288.6395) (xy 121.837331 -288.670114) (xy 121.872573 -288.706556)
			(xy 121.901818 -288.747964) (xy 121.924377 -288.793363) (xy 121.939717 -288.841681) (xy 121.947477 -288.891779)
			(xy 121.94794 -288.917126) (xy 121.947432 -288.943033) (xy 121.939326 -288.99421) (xy 121.923314 -289.043489)
			(xy 121.899791 -289.089656) (xy 121.869335 -289.131575) (xy 121.832697 -289.168213) (xy 121.790778 -289.198669)
			(xy 121.744611 -289.222192) (xy 121.695332 -289.238204) (xy 121.644155 -289.24631) (xy 121.592341 -289.24631)
			(xy 121.541164 -289.238204) (xy 121.491885 -289.222192) (xy 121.445718 -289.198669) (xy 121.403799 -289.168213)
			(xy 121.367161 -289.131575) (xy 121.336705 -289.089656) (xy 121.313182 -289.043489) (xy 121.29717 -288.99421)
			(xy 121.289064 -288.943033) (xy 121.288556 -288.917126) (xy 121.289153 -288.889409) (xy 121.298474 -288.834762)
			(xy 121.307098 -288.808414) (xy 121.314972 -288.786316) (xy 121.10974 -288.431224) (xy 121.08688 -288.426906)
			(xy 121.062064 -288.421716) (xy 121.014285 -288.404766) (xy 120.969665 -288.380698) (xy 120.929258 -288.350081)
			(xy 120.894016 -288.313637) (xy 120.864772 -288.272226) (xy 120.842214 -288.226825) (xy 120.826875 -288.178504)
			(xy 120.819118 -288.128404) (xy 120.818656 -288.103056) (xy 104.56164 -288.103056) (xy 104.561218 -288.128404)
			(xy 104.553436 -288.178499) (xy 104.53808 -288.226813) (xy 104.515512 -288.272208) (xy 104.486262 -288.313614)
			(xy 104.451021 -288.350057) (xy 104.410618 -288.380678) (xy 104.366005 -288.404755) (xy 104.318232 -288.421722)
			(xy 104.293416 -288.426906) (xy 104.270556 -288.431224) (xy 104.065324 -288.786316) (xy 104.073198 -288.808414)
			(xy 104.08184 -288.834757) (xy 104.091154 -288.889407) (xy 104.09174 -288.917126) (xy 104.091232 -288.943033)
			(xy 104.083126 -288.99421) (xy 104.067114 -289.043489) (xy 104.043591 -289.089656) (xy 104.013135 -289.131575)
			(xy 103.976497 -289.168213) (xy 103.934578 -289.198669) (xy 103.888411 -289.222192) (xy 103.839132 -289.238204)
			(xy 103.787955 -289.24631) (xy 103.736141 -289.24631) (xy 103.684964 -289.238204) (xy 103.635685 -289.222192)
			(xy 103.589518 -289.198669) (xy 103.547599 -289.168213) (xy 103.510961 -289.131575) (xy 103.480505 -289.089656)
			(xy 103.456982 -289.043489) (xy 103.44097 -288.99421) (xy 103.432864 -288.943033) (xy 103.432356 -288.917126)
			(xy 103.15194 -288.917126) (xy 103.151518 -288.940067) (xy 103.14509 -288.985498) (xy 103.132444 -289.029604)
			(xy 103.123492 -289.05073) (xy 103.113586 -289.073336) (xy 103.327454 -289.478466) (xy 103.351584 -289.483038)
			(xy 103.37651 -289.488115) (xy 103.424521 -289.50492) (xy 103.469379 -289.528904) (xy 103.510019 -289.559496)
			(xy 103.545476 -289.59597) (xy 103.574906 -289.637459) (xy 103.597612 -289.682977) (xy 103.613053 -289.731444)
			(xy 103.620863 -289.781708) (xy 103.621332 -289.807142) (xy 119.878856 -289.807142) (xy 119.879399 -289.781715)
			(xy 119.887229 -289.731468) (xy 119.90268 -289.683018) (xy 119.925386 -289.637514) (xy 119.954808 -289.596036)
			(xy 119.990248 -289.559565) (xy 120.030867 -289.528967) (xy 120.075701 -289.504967) (xy 120.123688 -289.488134)
			(xy 120.148604 -289.483038) (xy 120.172734 -289.478466) (xy 120.38711 -289.073082) (xy 120.377204 -289.050476)
			(xy 120.368243 -289.029398) (xy 120.355596 -288.985377) (xy 120.349182 -288.940026) (xy 120.348756 -288.917126)
			(xy 120.349264 -288.891219) (xy 120.35737 -288.840042) (xy 120.373382 -288.790763) (xy 120.396905 -288.744596)
			(xy 120.427361 -288.702677) (xy 120.463999 -288.666039) (xy 120.505918 -288.635583) (xy 120.552085 -288.61206)
			(xy 120.601364 -288.596048) (xy 120.652541 -288.587942) (xy 120.704355 -288.587942) (xy 120.755532 -288.596048)
			(xy 120.804811 -288.61206) (xy 120.850978 -288.635583) (xy 120.892897 -288.666039) (xy 120.929535 -288.702677)
			(xy 120.959991 -288.744596) (xy 120.983514 -288.790763) (xy 120.999526 -288.840042) (xy 121.007632 -288.891219)
			(xy 121.00814 -288.917126) (xy 121.007659 -288.942574) (xy 120.999856 -288.992867) (xy 120.984408 -289.041361)
			(xy 120.961683 -289.086901) (xy 120.932222 -289.128403) (xy 120.896727 -289.164878) (xy 120.856043 -289.195458)
			(xy 120.811139 -289.219415) (xy 120.763084 -289.236178) (xy 120.738138 -289.24123) (xy 120.714008 -289.245802)
			(xy 120.499632 -289.651186) (xy 120.509538 -289.673792) (xy 120.518456 -289.694878) (xy 120.531008 -289.738907)
			(xy 120.537342 -289.78425) (xy 120.537732 -289.807142) (xy 121.758456 -289.807142) (xy 121.758999 -289.781715)
			(xy 121.766829 -289.731468) (xy 121.78228 -289.683018) (xy 121.804986 -289.637514) (xy 121.834408 -289.596036)
			(xy 121.869848 -289.559565) (xy 121.910467 -289.528967) (xy 121.955301 -289.504967) (xy 122.003288 -289.488134)
			(xy 122.028204 -289.483038) (xy 122.052334 -289.478466) (xy 122.26671 -289.073082) (xy 122.256804 -289.050476)
			(xy 122.247843 -289.029398) (xy 122.235196 -288.985377) (xy 122.228782 -288.940026) (xy 122.228356 -288.917126)
			(xy 122.228864 -288.891219) (xy 122.23697 -288.840042) (xy 122.252982 -288.790763) (xy 122.276505 -288.744596)
			(xy 122.306961 -288.702677) (xy 122.343599 -288.666039) (xy 122.385518 -288.635583) (xy 122.431685 -288.61206)
			(xy 122.480964 -288.596048) (xy 122.532141 -288.587942) (xy 122.583955 -288.587942) (xy 122.635132 -288.596048)
			(xy 122.684411 -288.61206) (xy 122.730578 -288.635583) (xy 122.772497 -288.666039) (xy 122.809135 -288.702677)
			(xy 122.839591 -288.744596) (xy 122.863114 -288.790763) (xy 122.879126 -288.840042) (xy 122.887232 -288.891219)
			(xy 122.88774 -288.917126) (xy 122.887259 -288.942574) (xy 122.879456 -288.992867) (xy 122.864008 -289.041361)
			(xy 122.841283 -289.086901) (xy 122.811822 -289.128403) (xy 122.776327 -289.164878) (xy 122.735643 -289.195458)
			(xy 122.690739 -289.219415) (xy 122.642684 -289.236178) (xy 122.617738 -289.24123) (xy 122.593608 -289.245802)
			(xy 122.379232 -289.651186) (xy 122.389138 -289.673792) (xy 122.398056 -289.694878) (xy 122.410608 -289.738907)
			(xy 122.416942 -289.78425) (xy 122.417332 -289.807142) (xy 123.638056 -289.807142) (xy 123.638599 -289.781715)
			(xy 123.646429 -289.731468) (xy 123.66188 -289.683018) (xy 123.684586 -289.637514) (xy 123.714008 -289.596036)
			(xy 123.749448 -289.559565) (xy 123.790067 -289.528967) (xy 123.834901 -289.504967) (xy 123.882888 -289.488134)
			(xy 123.907804 -289.483038) (xy 123.931934 -289.478466) (xy 124.14631 -289.073082) (xy 124.136404 -289.050476)
			(xy 124.127443 -289.029398) (xy 124.114796 -288.985377) (xy 124.108382 -288.940026) (xy 124.107956 -288.917126)
			(xy 124.108464 -288.891219) (xy 124.11657 -288.840042) (xy 124.132582 -288.790763) (xy 124.156105 -288.744596)
			(xy 124.186561 -288.702677) (xy 124.223199 -288.666039) (xy 124.265118 -288.635583) (xy 124.311285 -288.61206)
			(xy 124.360564 -288.596048) (xy 124.411741 -288.587942) (xy 124.463555 -288.587942) (xy 124.514732 -288.596048)
			(xy 124.564011 -288.61206) (xy 124.610178 -288.635583) (xy 124.652097 -288.666039) (xy 124.688735 -288.702677)
			(xy 124.719191 -288.744596) (xy 124.742714 -288.790763) (xy 124.758726 -288.840042) (xy 124.766832 -288.891219)
			(xy 124.76734 -288.917126) (xy 124.766859 -288.942574) (xy 124.759056 -288.992867) (xy 124.743608 -289.041361)
			(xy 124.720883 -289.086901) (xy 124.691422 -289.128403) (xy 124.655927 -289.164878) (xy 124.615243 -289.195458)
			(xy 124.570339 -289.219415) (xy 124.522284 -289.236178) (xy 124.497338 -289.24123) (xy 124.473208 -289.245802)
			(xy 124.258832 -289.651186) (xy 124.268738 -289.673792) (xy 124.277656 -289.694878) (xy 124.290208 -289.738907)
			(xy 124.296542 -289.78425) (xy 124.296932 -289.807142) (xy 125.517656 -289.807142) (xy 125.518199 -289.781715)
			(xy 125.526029 -289.731468) (xy 125.54148 -289.683018) (xy 125.564186 -289.637514) (xy 125.593608 -289.596036)
			(xy 125.629048 -289.559565) (xy 125.669667 -289.528967) (xy 125.714501 -289.504967) (xy 125.762488 -289.488134)
			(xy 125.787404 -289.483038) (xy 125.811534 -289.478466) (xy 126.02591 -289.073082) (xy 126.016004 -289.050476)
			(xy 126.007043 -289.029398) (xy 125.994396 -288.985377) (xy 125.987982 -288.940026) (xy 125.987556 -288.917126)
			(xy 125.988064 -288.891219) (xy 125.99617 -288.840042) (xy 126.012182 -288.790763) (xy 126.035705 -288.744596)
			(xy 126.066161 -288.702677) (xy 126.102799 -288.666039) (xy 126.144718 -288.635583) (xy 126.190885 -288.61206)
			(xy 126.240164 -288.596048) (xy 126.291341 -288.587942) (xy 126.343155 -288.587942) (xy 126.394332 -288.596048)
			(xy 126.443611 -288.61206) (xy 126.489778 -288.635583) (xy 126.531697 -288.666039) (xy 126.568335 -288.702677)
			(xy 126.598791 -288.744596) (xy 126.622314 -288.790763) (xy 126.638326 -288.840042) (xy 126.646432 -288.891219)
			(xy 126.64694 -288.917126) (xy 126.646459 -288.942574) (xy 126.638656 -288.992867) (xy 126.623208 -289.041361)
			(xy 126.600483 -289.086901) (xy 126.571022 -289.128403) (xy 126.535527 -289.164878) (xy 126.494843 -289.195458)
			(xy 126.449939 -289.219415) (xy 126.401884 -289.236178) (xy 126.376938 -289.24123) (xy 126.352808 -289.245802)
			(xy 126.138432 -289.651186) (xy 126.148338 -289.673792) (xy 126.157256 -289.694878) (xy 126.169808 -289.738907)
			(xy 126.176142 -289.78425) (xy 126.176532 -289.807142) (xy 127.397256 -289.807142) (xy 127.397799 -289.781715)
			(xy 127.405629 -289.731468) (xy 127.42108 -289.683018) (xy 127.443786 -289.637514) (xy 127.473208 -289.596036)
			(xy 127.508648 -289.559565) (xy 127.549267 -289.528967) (xy 127.594101 -289.504967) (xy 127.642088 -289.488134)
			(xy 127.667004 -289.483038) (xy 127.691134 -289.478466) (xy 127.90551 -289.073082) (xy 127.895604 -289.050476)
			(xy 127.886643 -289.029398) (xy 127.873996 -288.985377) (xy 127.867582 -288.940026) (xy 127.867156 -288.917126)
			(xy 127.867664 -288.891219) (xy 127.87577 -288.840042) (xy 127.891782 -288.790763) (xy 127.915305 -288.744596)
			(xy 127.945761 -288.702677) (xy 127.982399 -288.666039) (xy 128.024318 -288.635583) (xy 128.070485 -288.61206)
			(xy 128.119764 -288.596048) (xy 128.170941 -288.587942) (xy 128.222755 -288.587942) (xy 128.273932 -288.596048)
			(xy 128.323211 -288.61206) (xy 128.369378 -288.635583) (xy 128.411297 -288.666039) (xy 128.447935 -288.702677)
			(xy 128.478391 -288.744596) (xy 128.501914 -288.790763) (xy 128.517926 -288.840042) (xy 128.526032 -288.891219)
			(xy 128.52654 -288.917126) (xy 128.526059 -288.942574) (xy 128.518256 -288.992867) (xy 128.502808 -289.041361)
			(xy 128.480083 -289.086901) (xy 128.450622 -289.128403) (xy 128.415127 -289.164878) (xy 128.374443 -289.195458)
			(xy 128.329539 -289.219415) (xy 128.281484 -289.236178) (xy 128.256538 -289.24123) (xy 128.232408 -289.245802)
			(xy 128.018032 -289.651186) (xy 128.027938 -289.673792) (xy 128.036856 -289.694878) (xy 128.049408 -289.738907)
			(xy 128.055742 -289.78425) (xy 128.056132 -289.807142) (xy 129.276856 -289.807142) (xy 129.277399 -289.781715)
			(xy 129.285229 -289.731468) (xy 129.30068 -289.683018) (xy 129.323386 -289.637514) (xy 129.352808 -289.596036)
			(xy 129.388248 -289.559565) (xy 129.428867 -289.528967) (xy 129.473701 -289.504967) (xy 129.521688 -289.488134)
			(xy 129.546604 -289.483038) (xy 129.570734 -289.478466) (xy 129.78511 -289.073082) (xy 129.775204 -289.050476)
			(xy 129.766243 -289.029398) (xy 129.753596 -288.985377) (xy 129.747182 -288.940026) (xy 129.746756 -288.917126)
			(xy 129.747264 -288.891219) (xy 129.75537 -288.840042) (xy 129.771382 -288.790763) (xy 129.794905 -288.744596)
			(xy 129.825361 -288.702677) (xy 129.861999 -288.666039) (xy 129.903918 -288.635583) (xy 129.950085 -288.61206)
			(xy 129.999364 -288.596048) (xy 130.050541 -288.587942) (xy 130.102355 -288.587942) (xy 130.153532 -288.596048)
			(xy 130.202811 -288.61206) (xy 130.248978 -288.635583) (xy 130.290897 -288.666039) (xy 130.327535 -288.702677)
			(xy 130.357991 -288.744596) (xy 130.381514 -288.790763) (xy 130.397526 -288.840042) (xy 130.405632 -288.891219)
			(xy 130.40614 -288.917126) (xy 130.405659 -288.942574) (xy 130.397856 -288.992867) (xy 130.382408 -289.041361)
			(xy 130.359683 -289.086901) (xy 130.330222 -289.128403) (xy 130.294727 -289.164878) (xy 130.254043 -289.195458)
			(xy 130.209139 -289.219415) (xy 130.161084 -289.236178) (xy 130.136138 -289.24123) (xy 130.112008 -289.245802)
			(xy 129.897632 -289.651186) (xy 129.907538 -289.673792) (xy 129.916456 -289.694878) (xy 129.929008 -289.738907)
			(xy 129.935342 -289.78425) (xy 129.935732 -289.807142) (xy 131.156456 -289.807142) (xy 131.156999 -289.781715)
			(xy 131.164829 -289.731468) (xy 131.18028 -289.683018) (xy 131.202986 -289.637514) (xy 131.232408 -289.596036)
			(xy 131.267848 -289.559565) (xy 131.308467 -289.528967) (xy 131.353301 -289.504967) (xy 131.401288 -289.488134)
			(xy 131.426204 -289.483038) (xy 131.450334 -289.478466) (xy 131.66471 -289.073082) (xy 131.654804 -289.050476)
			(xy 131.645843 -289.029398) (xy 131.633196 -288.985377) (xy 131.626782 -288.940026) (xy 131.626356 -288.917126)
			(xy 131.626864 -288.891219) (xy 131.63497 -288.840042) (xy 131.650982 -288.790763) (xy 131.674505 -288.744596)
			(xy 131.704961 -288.702677) (xy 131.741599 -288.666039) (xy 131.783518 -288.635583) (xy 131.829685 -288.61206)
			(xy 131.878964 -288.596048) (xy 131.930141 -288.587942) (xy 131.981955 -288.587942) (xy 132.033132 -288.596048)
			(xy 132.082411 -288.61206) (xy 132.128578 -288.635583) (xy 132.170497 -288.666039) (xy 132.207135 -288.702677)
			(xy 132.237591 -288.744596) (xy 132.261114 -288.790763) (xy 132.277126 -288.840042) (xy 132.285232 -288.891219)
			(xy 132.28574 -288.917126) (xy 132.285259 -288.942574) (xy 132.277456 -288.992867) (xy 132.262008 -289.041361)
			(xy 132.239283 -289.086901) (xy 132.209822 -289.128403) (xy 132.174327 -289.164878) (xy 132.133643 -289.195458)
			(xy 132.088739 -289.219415) (xy 132.040684 -289.236178) (xy 132.015738 -289.24123) (xy 131.991608 -289.245802)
			(xy 131.777232 -289.651186) (xy 131.787138 -289.673792) (xy 131.796056 -289.694878) (xy 131.808608 -289.738907)
			(xy 131.814942 -289.78425) (xy 131.815332 -289.807142) (xy 133.036056 -289.807142) (xy 133.036599 -289.781715)
			(xy 133.044429 -289.731468) (xy 133.05988 -289.683018) (xy 133.082586 -289.637514) (xy 133.112008 -289.596036)
			(xy 133.147448 -289.559565) (xy 133.188067 -289.528967) (xy 133.232901 -289.504967) (xy 133.280888 -289.488134)
			(xy 133.305804 -289.483038) (xy 133.329934 -289.478466) (xy 133.54431 -289.073082) (xy 133.534404 -289.050476)
			(xy 133.525443 -289.029398) (xy 133.512796 -288.985377) (xy 133.506382 -288.940026) (xy 133.505956 -288.917126)
			(xy 133.506464 -288.891219) (xy 133.51457 -288.840042) (xy 133.530582 -288.790763) (xy 133.554105 -288.744596)
			(xy 133.584561 -288.702677) (xy 133.621199 -288.666039) (xy 133.663118 -288.635583) (xy 133.709285 -288.61206)
			(xy 133.758564 -288.596048) (xy 133.809741 -288.587942) (xy 133.861555 -288.587942) (xy 133.912732 -288.596048)
			(xy 133.962011 -288.61206) (xy 134.008178 -288.635583) (xy 134.050097 -288.666039) (xy 134.086735 -288.702677)
			(xy 134.117191 -288.744596) (xy 134.140714 -288.790763) (xy 134.156726 -288.840042) (xy 134.164832 -288.891219)
			(xy 134.16534 -288.917126) (xy 134.164859 -288.942574) (xy 134.157056 -288.992867) (xy 134.141608 -289.041361)
			(xy 134.118883 -289.086901) (xy 134.089422 -289.128403) (xy 134.053927 -289.164878) (xy 134.013243 -289.195458)
			(xy 133.968339 -289.219415) (xy 133.920284 -289.236178) (xy 133.895338 -289.24123) (xy 133.871208 -289.245802)
			(xy 133.656832 -289.651186) (xy 133.666738 -289.673792) (xy 133.675656 -289.694878) (xy 133.688208 -289.738907)
			(xy 133.694542 -289.78425) (xy 133.694932 -289.807142) (xy 133.694424 -289.833029) (xy 133.686325 -289.884167)
			(xy 133.670326 -289.933407) (xy 133.64682 -289.979539) (xy 133.616388 -290.021426) (xy 133.579778 -290.058036)
			(xy 133.537891 -290.088468) (xy 133.491759 -290.111974) (xy 133.442519 -290.127973) (xy 133.391381 -290.136072)
			(xy 133.339607 -290.136072) (xy 133.288469 -290.127973) (xy 133.239229 -290.111974) (xy 133.193097 -290.088468)
			(xy 133.15121 -290.058036) (xy 133.1146 -290.021426) (xy 133.084168 -289.979539) (xy 133.060662 -289.933407)
			(xy 133.044663 -289.884167) (xy 133.036564 -289.833029) (xy 133.036056 -289.807142) (xy 131.815332 -289.807142)
			(xy 131.814824 -289.833029) (xy 131.806725 -289.884167) (xy 131.790726 -289.933407) (xy 131.76722 -289.979539)
			(xy 131.736788 -290.021426) (xy 131.700178 -290.058036) (xy 131.658291 -290.088468) (xy 131.612159 -290.111974)
			(xy 131.562919 -290.127973) (xy 131.511781 -290.136072) (xy 131.460007 -290.136072) (xy 131.408869 -290.127973)
			(xy 131.359629 -290.111974) (xy 131.313497 -290.088468) (xy 131.27161 -290.058036) (xy 131.235 -290.021426)
			(xy 131.204568 -289.979539) (xy 131.181062 -289.933407) (xy 131.165063 -289.884167) (xy 131.156964 -289.833029)
			(xy 131.156456 -289.807142) (xy 129.935732 -289.807142) (xy 129.935224 -289.833029) (xy 129.927125 -289.884167)
			(xy 129.911126 -289.933407) (xy 129.88762 -289.979539) (xy 129.857188 -290.021426) (xy 129.820578 -290.058036)
			(xy 129.778691 -290.088468) (xy 129.732559 -290.111974) (xy 129.683319 -290.127973) (xy 129.632181 -290.136072)
			(xy 129.580407 -290.136072) (xy 129.529269 -290.127973) (xy 129.480029 -290.111974) (xy 129.433897 -290.088468)
			(xy 129.39201 -290.058036) (xy 129.3554 -290.021426) (xy 129.324968 -289.979539) (xy 129.301462 -289.933407)
			(xy 129.285463 -289.884167) (xy 129.277364 -289.833029) (xy 129.276856 -289.807142) (xy 128.056132 -289.807142)
			(xy 128.055624 -289.833029) (xy 128.047525 -289.884167) (xy 128.031526 -289.933407) (xy 128.00802 -289.979539)
			(xy 127.977588 -290.021426) (xy 127.940978 -290.058036) (xy 127.899091 -290.088468) (xy 127.852959 -290.111974)
			(xy 127.803719 -290.127973) (xy 127.752581 -290.136072) (xy 127.700807 -290.136072) (xy 127.649669 -290.127973)
			(xy 127.600429 -290.111974) (xy 127.554297 -290.088468) (xy 127.51241 -290.058036) (xy 127.4758 -290.021426)
			(xy 127.445368 -289.979539) (xy 127.421862 -289.933407) (xy 127.405863 -289.884167) (xy 127.397764 -289.833029)
			(xy 127.397256 -289.807142) (xy 126.176532 -289.807142) (xy 126.176024 -289.833029) (xy 126.167925 -289.884167)
			(xy 126.151926 -289.933407) (xy 126.12842 -289.979539) (xy 126.097988 -290.021426) (xy 126.061378 -290.058036)
			(xy 126.019491 -290.088468) (xy 125.973359 -290.111974) (xy 125.924119 -290.127973) (xy 125.872981 -290.136072)
			(xy 125.821207 -290.136072) (xy 125.770069 -290.127973) (xy 125.720829 -290.111974) (xy 125.674697 -290.088468)
			(xy 125.63281 -290.058036) (xy 125.5962 -290.021426) (xy 125.565768 -289.979539) (xy 125.542262 -289.933407)
			(xy 125.526263 -289.884167) (xy 125.518164 -289.833029) (xy 125.517656 -289.807142) (xy 124.296932 -289.807142)
			(xy 124.296424 -289.833029) (xy 124.288325 -289.884167) (xy 124.272326 -289.933407) (xy 124.24882 -289.979539)
			(xy 124.218388 -290.021426) (xy 124.181778 -290.058036) (xy 124.139891 -290.088468) (xy 124.093759 -290.111974)
			(xy 124.044519 -290.127973) (xy 123.993381 -290.136072) (xy 123.941607 -290.136072) (xy 123.890469 -290.127973)
			(xy 123.841229 -290.111974) (xy 123.795097 -290.088468) (xy 123.75321 -290.058036) (xy 123.7166 -290.021426)
			(xy 123.686168 -289.979539) (xy 123.662662 -289.933407) (xy 123.646663 -289.884167) (xy 123.638564 -289.833029)
			(xy 123.638056 -289.807142) (xy 122.417332 -289.807142) (xy 122.416824 -289.833029) (xy 122.408725 -289.884167)
			(xy 122.392726 -289.933407) (xy 122.36922 -289.979539) (xy 122.338788 -290.021426) (xy 122.302178 -290.058036)
			(xy 122.260291 -290.088468) (xy 122.214159 -290.111974) (xy 122.164919 -290.127973) (xy 122.113781 -290.136072)
			(xy 122.062007 -290.136072) (xy 122.010869 -290.127973) (xy 121.961629 -290.111974) (xy 121.915497 -290.088468)
			(xy 121.87361 -290.058036) (xy 121.837 -290.021426) (xy 121.806568 -289.979539) (xy 121.783062 -289.933407)
			(xy 121.767063 -289.884167) (xy 121.758964 -289.833029) (xy 121.758456 -289.807142) (xy 120.537732 -289.807142)
			(xy 120.537224 -289.833029) (xy 120.529125 -289.884167) (xy 120.513126 -289.933407) (xy 120.48962 -289.979539)
			(xy 120.459188 -290.021426) (xy 120.422578 -290.058036) (xy 120.380691 -290.088468) (xy 120.334559 -290.111974)
			(xy 120.285319 -290.127973) (xy 120.234181 -290.136072) (xy 120.182407 -290.136072) (xy 120.131269 -290.127973)
			(xy 120.082029 -290.111974) (xy 120.035897 -290.088468) (xy 119.99401 -290.058036) (xy 119.9574 -290.021426)
			(xy 119.926968 -289.979539) (xy 119.903462 -289.933407) (xy 119.887463 -289.884167) (xy 119.879364 -289.833029)
			(xy 119.878856 -289.807142) (xy 103.621332 -289.807142) (xy 103.620824 -289.833029) (xy 103.612725 -289.884167)
			(xy 103.596726 -289.933407) (xy 103.57322 -289.979539) (xy 103.542788 -290.021426) (xy 103.506178 -290.058036)
			(xy 103.464291 -290.088468) (xy 103.418159 -290.111974) (xy 103.368919 -290.127973) (xy 103.317781 -290.136072)
			(xy 103.266007 -290.136072) (xy 103.214869 -290.127973) (xy 103.165629 -290.111974) (xy 103.119497 -290.088468)
			(xy 103.07761 -290.058036) (xy 103.041 -290.021426) (xy 103.010568 -289.979539) (xy 102.987062 -289.933407)
			(xy 102.971063 -289.884167) (xy 102.962964 -289.833029) (xy 102.962456 -289.807142) (xy 102.962456 -289.806634)
			(xy 102.962859 -289.783785) (xy 102.969212 -289.738531) (xy 102.981758 -289.694589) (xy 102.99065 -289.673538)
			(xy 103.000556 -289.650932) (xy 102.786688 -289.245802) (xy 102.762558 -289.24123) (xy 102.737619 -289.236158)
			(xy 102.689576 -289.219379) (xy 102.644683 -289.195414) (xy 102.604007 -289.164832) (xy 102.568517 -289.12836)
			(xy 102.539055 -289.086867) (xy 102.516322 -289.041337) (xy 102.500858 -288.992854) (xy 102.493031 -288.942571)
			(xy 102.492556 -288.917126) (xy 102.21214 -288.917126) (xy 102.211632 -288.943033) (xy 102.203526 -288.99421)
			(xy 102.187514 -289.043489) (xy 102.163991 -289.089656) (xy 102.133535 -289.131575) (xy 102.096897 -289.168213)
			(xy 102.054978 -289.198669) (xy 102.008811 -289.222192) (xy 101.959532 -289.238204) (xy 101.908355 -289.24631)
			(xy 101.856541 -289.24631) (xy 101.805364 -289.238204) (xy 101.756085 -289.222192) (xy 101.709918 -289.198669)
			(xy 101.667999 -289.168213) (xy 101.631361 -289.131575) (xy 101.600905 -289.089656) (xy 101.577382 -289.043489)
			(xy 101.56137 -288.99421) (xy 101.553264 -288.943033) (xy 101.552756 -288.917126) (xy 101.27234 -288.917126)
			(xy 101.271918 -288.940067) (xy 101.26549 -288.985498) (xy 101.252844 -289.029604) (xy 101.243892 -289.05073)
			(xy 101.233986 -289.073336) (xy 101.447854 -289.478466) (xy 101.471984 -289.483038) (xy 101.49691 -289.488115)
			(xy 101.544921 -289.50492) (xy 101.589779 -289.528904) (xy 101.630419 -289.559496) (xy 101.665876 -289.59597)
			(xy 101.695306 -289.637459) (xy 101.718012 -289.682977) (xy 101.733453 -289.731444) (xy 101.741263 -289.781708)
			(xy 101.741732 -289.807142) (xy 101.741224 -289.833029) (xy 101.733125 -289.884167) (xy 101.717126 -289.933407)
			(xy 101.69362 -289.979539) (xy 101.663188 -290.021426) (xy 101.626578 -290.058036) (xy 101.584691 -290.088468)
			(xy 101.538559 -290.111974) (xy 101.489319 -290.127973) (xy 101.438181 -290.136072) (xy 101.386407 -290.136072)
			(xy 101.335269 -290.127973) (xy 101.286029 -290.111974) (xy 101.239897 -290.088468) (xy 101.19801 -290.058036)
			(xy 101.1614 -290.021426) (xy 101.130968 -289.979539) (xy 101.107462 -289.933407) (xy 101.091463 -289.884167)
			(xy 101.083364 -289.833029) (xy 101.082856 -289.807142) (xy 101.082856 -289.806634) (xy 101.083259 -289.783785)
			(xy 101.089612 -289.738531) (xy 101.102158 -289.694589) (xy 101.11105 -289.673538) (xy 101.120956 -289.650932)
			(xy 100.907088 -289.245802) (xy 100.882958 -289.24123) (xy 100.858019 -289.236158) (xy 100.809976 -289.219379)
			(xy 100.765083 -289.195414) (xy 100.724407 -289.164832) (xy 100.688917 -289.12836) (xy 100.659455 -289.086867)
			(xy 100.636722 -289.041337) (xy 100.621258 -288.992854) (xy 100.613431 -288.942571) (xy 100.612956 -288.917126)
			(xy 100.33254 -288.917126) (xy 100.332032 -288.943033) (xy 100.323926 -288.99421) (xy 100.307914 -289.043489)
			(xy 100.284391 -289.089656) (xy 100.253935 -289.131575) (xy 100.217297 -289.168213) (xy 100.175378 -289.198669)
			(xy 100.129211 -289.222192) (xy 100.079932 -289.238204) (xy 100.028755 -289.24631) (xy 99.976941 -289.24631)
			(xy 99.925764 -289.238204) (xy 99.876485 -289.222192) (xy 99.830318 -289.198669) (xy 99.788399 -289.168213)
			(xy 99.751761 -289.131575) (xy 99.721305 -289.089656) (xy 99.697782 -289.043489) (xy 99.68177 -288.99421)
			(xy 99.673664 -288.943033) (xy 99.673156 -288.917126) (xy 99.39274 -288.917126) (xy 99.392318 -288.940067)
			(xy 99.38589 -288.985498) (xy 99.373244 -289.029604) (xy 99.364292 -289.05073) (xy 99.354386 -289.073336)
			(xy 99.568254 -289.478466) (xy 99.592384 -289.483038) (xy 99.61731 -289.488115) (xy 99.665321 -289.50492)
			(xy 99.710179 -289.528904) (xy 99.750819 -289.559496) (xy 99.786276 -289.59597) (xy 99.815706 -289.637459)
			(xy 99.838412 -289.682977) (xy 99.853853 -289.731444) (xy 99.861663 -289.781708) (xy 99.862132 -289.807142)
			(xy 99.861624 -289.833029) (xy 99.853525 -289.884167) (xy 99.837526 -289.933407) (xy 99.81402 -289.979539)
			(xy 99.783588 -290.021426) (xy 99.746978 -290.058036) (xy 99.705091 -290.088468) (xy 99.658959 -290.111974)
			(xy 99.609719 -290.127973) (xy 99.558581 -290.136072) (xy 99.506807 -290.136072) (xy 99.455669 -290.127973)
			(xy 99.406429 -290.111974) (xy 99.360297 -290.088468) (xy 99.31841 -290.058036) (xy 99.2818 -290.021426)
			(xy 99.251368 -289.979539) (xy 99.227862 -289.933407) (xy 99.211863 -289.884167) (xy 99.203764 -289.833029)
			(xy 99.203256 -289.807142) (xy 99.203256 -289.806634) (xy 99.203659 -289.783785) (xy 99.210012 -289.738531)
			(xy 99.222558 -289.694589) (xy 99.23145 -289.673538) (xy 99.241356 -289.650932) (xy 99.027488 -289.245802)
			(xy 99.003358 -289.24123) (xy 98.978419 -289.236158) (xy 98.930376 -289.219379) (xy 98.885483 -289.195414)
			(xy 98.844807 -289.164832) (xy 98.809317 -289.12836) (xy 98.779855 -289.086867) (xy 98.757122 -289.041337)
			(xy 98.741658 -288.992854) (xy 98.733831 -288.942571) (xy 98.733356 -288.917126) (xy 98.45294 -288.917126)
			(xy 98.452432 -288.943033) (xy 98.444326 -288.99421) (xy 98.428314 -289.043489) (xy 98.404791 -289.089656)
			(xy 98.374335 -289.131575) (xy 98.337697 -289.168213) (xy 98.295778 -289.198669) (xy 98.249611 -289.222192)
			(xy 98.200332 -289.238204) (xy 98.149155 -289.24631) (xy 98.097341 -289.24631) (xy 98.046164 -289.238204)
			(xy 97.996885 -289.222192) (xy 97.950718 -289.198669) (xy 97.908799 -289.168213) (xy 97.872161 -289.131575)
			(xy 97.841705 -289.089656) (xy 97.818182 -289.043489) (xy 97.80217 -288.99421) (xy 97.794064 -288.943033)
			(xy 97.793556 -288.917126) (xy 97.51314 -288.917126) (xy 97.512718 -288.940067) (xy 97.50629 -288.985498)
			(xy 97.493644 -289.029604) (xy 97.484692 -289.05073) (xy 97.474786 -289.073336) (xy 97.688654 -289.478466)
			(xy 97.712784 -289.483038) (xy 97.73771 -289.488115) (xy 97.785721 -289.50492) (xy 97.830579 -289.528904)
			(xy 97.871219 -289.559496) (xy 97.906676 -289.59597) (xy 97.936106 -289.637459) (xy 97.958812 -289.682977)
			(xy 97.974253 -289.731444) (xy 97.982063 -289.781708) (xy 97.982532 -289.807142) (xy 97.982024 -289.833029)
			(xy 97.973925 -289.884167) (xy 97.957926 -289.933407) (xy 97.93442 -289.979539) (xy 97.903988 -290.021426)
			(xy 97.867378 -290.058036) (xy 97.825491 -290.088468) (xy 97.779359 -290.111974) (xy 97.730119 -290.127973)
			(xy 97.678981 -290.136072) (xy 97.627207 -290.136072) (xy 97.576069 -290.127973) (xy 97.526829 -290.111974)
			(xy 97.480697 -290.088468) (xy 97.43881 -290.058036) (xy 97.4022 -290.021426) (xy 97.371768 -289.979539)
			(xy 97.348262 -289.933407) (xy 97.332263 -289.884167) (xy 97.324164 -289.833029) (xy 97.323656 -289.807142)
			(xy 97.323656 -289.806634) (xy 97.324059 -289.783785) (xy 97.330412 -289.738531) (xy 97.342958 -289.694589)
			(xy 97.35185 -289.673538) (xy 97.361756 -289.650932) (xy 97.147888 -289.245802) (xy 97.123758 -289.24123)
			(xy 97.098819 -289.236158) (xy 97.050776 -289.219379) (xy 97.005883 -289.195414) (xy 96.965207 -289.164832)
			(xy 96.929717 -289.12836) (xy 96.900255 -289.086867) (xy 96.877522 -289.041337) (xy 96.862058 -288.992854)
			(xy 96.854231 -288.942571) (xy 96.853756 -288.917126) (xy 96.57334 -288.917126) (xy 96.572832 -288.943033)
			(xy 96.564726 -288.99421) (xy 96.548714 -289.043489) (xy 96.525191 -289.089656) (xy 96.494735 -289.131575)
			(xy 96.458097 -289.168213) (xy 96.416178 -289.198669) (xy 96.370011 -289.222192) (xy 96.320732 -289.238204)
			(xy 96.269555 -289.24631) (xy 96.217741 -289.24631) (xy 96.166564 -289.238204) (xy 96.117285 -289.222192)
			(xy 96.071118 -289.198669) (xy 96.029199 -289.168213) (xy 95.992561 -289.131575) (xy 95.962105 -289.089656)
			(xy 95.938582 -289.043489) (xy 95.92257 -288.99421) (xy 95.914464 -288.943033) (xy 95.913956 -288.917126)
			(xy 95.63354 -288.917126) (xy 95.633118 -288.940067) (xy 95.62669 -288.985498) (xy 95.614044 -289.029604)
			(xy 95.605092 -289.05073) (xy 95.595186 -289.073336) (xy 95.809054 -289.478466) (xy 95.833184 -289.483038)
			(xy 95.85811 -289.488115) (xy 95.906121 -289.50492) (xy 95.950979 -289.528904) (xy 95.991619 -289.559496)
			(xy 96.027076 -289.59597) (xy 96.056506 -289.637459) (xy 96.079212 -289.682977) (xy 96.094653 -289.731444)
			(xy 96.102463 -289.781708) (xy 96.102932 -289.807142) (xy 96.102424 -289.833029) (xy 96.094325 -289.884167)
			(xy 96.078326 -289.933407) (xy 96.05482 -289.979539) (xy 96.024388 -290.021426) (xy 95.987778 -290.058036)
			(xy 95.945891 -290.088468) (xy 95.899759 -290.111974) (xy 95.850519 -290.127973) (xy 95.799381 -290.136072)
			(xy 95.747607 -290.136072) (xy 95.696469 -290.127973) (xy 95.647229 -290.111974) (xy 95.601097 -290.088468)
			(xy 95.55921 -290.058036) (xy 95.5226 -290.021426) (xy 95.492168 -289.979539) (xy 95.468662 -289.933407)
			(xy 95.452663 -289.884167) (xy 95.444564 -289.833029) (xy 95.444056 -289.807142) (xy 95.444056 -289.806634)
			(xy 95.444459 -289.783785) (xy 95.450812 -289.738531) (xy 95.463358 -289.694589) (xy 95.47225 -289.673538)
			(xy 95.482156 -289.650932) (xy 95.268288 -289.245802) (xy 95.244158 -289.24123) (xy 95.219219 -289.236158)
			(xy 95.171176 -289.219379) (xy 95.126283 -289.195414) (xy 95.085607 -289.164832) (xy 95.050117 -289.12836)
			(xy 95.020655 -289.086867) (xy 94.997922 -289.041337) (xy 94.982458 -288.992854) (xy 94.974631 -288.942571)
			(xy 94.974156 -288.917126) (xy 94.69374 -288.917126) (xy 94.693232 -288.943033) (xy 94.685126 -288.99421)
			(xy 94.669114 -289.043489) (xy 94.645591 -289.089656) (xy 94.615135 -289.131575) (xy 94.578497 -289.168213)
			(xy 94.536578 -289.198669) (xy 94.490411 -289.222192) (xy 94.441132 -289.238204) (xy 94.389955 -289.24631)
			(xy 94.338141 -289.24631) (xy 94.286964 -289.238204) (xy 94.237685 -289.222192) (xy 94.191518 -289.198669)
			(xy 94.149599 -289.168213) (xy 94.112961 -289.131575) (xy 94.082505 -289.089656) (xy 94.058982 -289.043489)
			(xy 94.04297 -288.99421) (xy 94.034864 -288.943033) (xy 94.034356 -288.917126) (xy 93.75394 -288.917126)
			(xy 93.753518 -288.940067) (xy 93.74709 -288.985498) (xy 93.734444 -289.029604) (xy 93.725492 -289.05073)
			(xy 93.715586 -289.073336) (xy 93.929454 -289.478466) (xy 93.953584 -289.483038) (xy 93.97851 -289.488115)
			(xy 94.026521 -289.50492) (xy 94.071379 -289.528904) (xy 94.112019 -289.559496) (xy 94.147476 -289.59597)
			(xy 94.176906 -289.637459) (xy 94.199612 -289.682977) (xy 94.215053 -289.731444) (xy 94.222863 -289.781708)
			(xy 94.223332 -289.807142) (xy 94.222824 -289.833029) (xy 94.214725 -289.884167) (xy 94.198726 -289.933407)
			(xy 94.17522 -289.979539) (xy 94.144788 -290.021426) (xy 94.108178 -290.058036) (xy 94.066291 -290.088468)
			(xy 94.020159 -290.111974) (xy 93.970919 -290.127973) (xy 93.919781 -290.136072) (xy 93.868007 -290.136072)
			(xy 93.816869 -290.127973) (xy 93.767629 -290.111974) (xy 93.721497 -290.088468) (xy 93.67961 -290.058036)
			(xy 93.643 -290.021426) (xy 93.612568 -289.979539) (xy 93.589062 -289.933407) (xy 93.573063 -289.884167)
			(xy 93.564964 -289.833029) (xy 93.564456 -289.807142) (xy 93.564456 -289.806634) (xy 93.564859 -289.783785)
			(xy 93.571212 -289.738531) (xy 93.583758 -289.694589) (xy 93.59265 -289.673538) (xy 93.602556 -289.650932)
			(xy 93.388688 -289.245802) (xy 93.364558 -289.24123) (xy 93.339619 -289.236158) (xy 93.291576 -289.219379)
			(xy 93.246683 -289.195414) (xy 93.206007 -289.164832) (xy 93.170517 -289.12836) (xy 93.141055 -289.086867)
			(xy 93.118322 -289.041337) (xy 93.102858 -288.992854) (xy 93.095031 -288.942571) (xy 93.094556 -288.917126)
			(xy 92.81414 -288.917126) (xy 92.813632 -288.943033) (xy 92.805526 -288.99421) (xy 92.789514 -289.043489)
			(xy 92.765991 -289.089656) (xy 92.735535 -289.131575) (xy 92.698897 -289.168213) (xy 92.656978 -289.198669)
			(xy 92.610811 -289.222192) (xy 92.561532 -289.238204) (xy 92.510355 -289.24631) (xy 92.458541 -289.24631)
			(xy 92.407364 -289.238204) (xy 92.358085 -289.222192) (xy 92.311918 -289.198669) (xy 92.269999 -289.168213)
			(xy 92.233361 -289.131575) (xy 92.202905 -289.089656) (xy 92.179382 -289.043489) (xy 92.16337 -288.99421)
			(xy 92.155264 -288.943033) (xy 92.154756 -288.917126) (xy 91.87434 -288.917126) (xy 91.873918 -288.940067)
			(xy 91.86749 -288.985498) (xy 91.854844 -289.029604) (xy 91.845892 -289.05073) (xy 91.835986 -289.073336)
			(xy 92.049854 -289.478466) (xy 92.073984 -289.483038) (xy 92.09891 -289.488115) (xy 92.146921 -289.50492)
			(xy 92.191779 -289.528904) (xy 92.232419 -289.559496) (xy 92.267876 -289.59597) (xy 92.297306 -289.637459)
			(xy 92.320012 -289.682977) (xy 92.335453 -289.731444) (xy 92.343263 -289.781708) (xy 92.343732 -289.807142)
			(xy 92.343224 -289.833029) (xy 92.335125 -289.884167) (xy 92.319126 -289.933407) (xy 92.29562 -289.979539)
			(xy 92.265188 -290.021426) (xy 92.228578 -290.058036) (xy 92.186691 -290.088468) (xy 92.140559 -290.111974)
			(xy 92.091319 -290.127973) (xy 92.040181 -290.136072) (xy 91.988407 -290.136072) (xy 91.937269 -290.127973)
			(xy 91.888029 -290.111974) (xy 91.841897 -290.088468) (xy 91.80001 -290.058036) (xy 91.7634 -290.021426)
			(xy 91.732968 -289.979539) (xy 91.709462 -289.933407) (xy 91.693463 -289.884167) (xy 91.685364 -289.833029)
			(xy 91.684856 -289.807142) (xy 91.684856 -289.806634) (xy 91.685259 -289.783785) (xy 91.691612 -289.738531)
			(xy 91.704158 -289.694589) (xy 91.71305 -289.673538) (xy 91.722956 -289.650932) (xy 91.509088 -289.245802)
			(xy 91.484958 -289.24123) (xy 91.460019 -289.236158) (xy 91.411976 -289.219379) (xy 91.367083 -289.195414)
			(xy 91.326407 -289.164832) (xy 91.290917 -289.12836) (xy 91.261455 -289.086867) (xy 91.238722 -289.041337)
			(xy 91.223258 -288.992854) (xy 91.215431 -288.942571) (xy 91.214956 -288.917126) (xy 90.93454 -288.917126)
			(xy 90.934032 -288.943033) (xy 90.925926 -288.99421) (xy 90.909914 -289.043489) (xy 90.886391 -289.089656)
			(xy 90.855935 -289.131575) (xy 90.819297 -289.168213) (xy 90.777378 -289.198669) (xy 90.731211 -289.222192)
			(xy 90.681932 -289.238204) (xy 90.630755 -289.24631) (xy 90.578941 -289.24631) (xy 90.527764 -289.238204)
			(xy 90.478485 -289.222192) (xy 90.432318 -289.198669) (xy 90.390399 -289.168213) (xy 90.353761 -289.131575)
			(xy 90.323305 -289.089656) (xy 90.299782 -289.043489) (xy 90.28377 -288.99421) (xy 90.275664 -288.943033)
			(xy 90.275156 -288.917126) (xy 89.05494 -288.917126) (xy 89.054432 -288.943033) (xy 89.046326 -288.99421)
			(xy 89.030314 -289.043489) (xy 89.006791 -289.089656) (xy 88.976335 -289.131575) (xy 88.939697 -289.168213)
			(xy 88.897778 -289.198669) (xy 88.851611 -289.222192) (xy 88.802332 -289.238204) (xy 88.751155 -289.24631)
			(xy 88.699341 -289.24631) (xy 88.648164 -289.238204) (xy 88.598885 -289.222192) (xy 88.552718 -289.198669)
			(xy 88.510799 -289.168213) (xy 88.474161 -289.131575) (xy 88.443705 -289.089656) (xy 88.420182 -289.043489)
			(xy 88.40417 -288.99421) (xy 88.396064 -288.943033) (xy 88.395556 -288.917126) (xy 2.509012 -288.917126)
			(xy 2.509012 -297.515026) (xy 88.21548 -297.515026) (xy 88.219461 -297.382006) (xy 88.23139 -297.249461)
			(xy 88.251225 -297.117868) (xy 88.278894 -296.987696) (xy 88.314298 -296.859411) (xy 88.357311 -296.733474)
			(xy 88.407778 -296.610335) (xy 88.465519 -296.490434) (xy 88.530328 -296.374201) (xy 88.601972 -296.262051)
			(xy 88.680194 -296.154387) (xy 88.764715 -296.051594) (xy 88.855233 -295.954039) (xy 88.951422 -295.862073)
			(xy 89.05294 -295.776023) (xy 89.159421 -295.696199) (xy 89.270486 -295.622886) (xy 89.385737 -295.556346)
			(xy 89.504761 -295.496817) (xy 89.627132 -295.444513) (xy 89.752411 -295.399621) (xy 89.880152 -295.362302)
			(xy 90.009895 -295.332689) (xy 90.141177 -295.310888) (xy 90.273528 -295.296978) (xy 90.406474 -295.291007)
			(xy 90.539539 -295.292998) (xy 90.672247 -295.302943) (xy 90.804123 -295.320807) (xy 90.934694 -295.346525)
			(xy 91.063494 -295.380006) (xy 91.19006 -295.42113) (xy 91.313941 -295.46975) (xy 91.434692 -295.525691)
			(xy 91.551882 -295.588753) (xy 91.665091 -295.658711) (xy 91.773913 -295.735315) (xy 91.877959 -295.818289)
			(xy 91.976857 -295.907337) (xy 92.070252 -296.00214) (xy 92.15781 -296.102358) (xy 92.239219 -296.207634)
			(xy 92.314185 -296.31759) (xy 92.382442 -296.431832) (xy 92.443744 -296.549952) (xy 92.497873 -296.671527)
			(xy 92.544634 -296.796121) (xy 92.58386 -296.923289) (xy 92.61541 -297.052575) (xy 92.639173 -297.183516)
			(xy 92.655062 -297.315644) (xy 92.66302 -297.448486) (xy 92.663518 -297.515026) (xy 131.195582 -297.515026)
			(xy 131.199563 -297.382006) (xy 131.211492 -297.249461) (xy 131.231327 -297.117868) (xy 131.258996 -296.987696)
			(xy 131.2944 -296.859411) (xy 131.337413 -296.733474) (xy 131.38788 -296.610335) (xy 131.445621 -296.490434)
			(xy 131.51043 -296.374201) (xy 131.582074 -296.262051) (xy 131.660296 -296.154387) (xy 131.744817 -296.051594)
			(xy 131.835335 -295.954039) (xy 131.931524 -295.862073) (xy 132.033042 -295.776023) (xy 132.139523 -295.696199)
			(xy 132.250588 -295.622886) (xy 132.365839 -295.556346) (xy 132.484863 -295.496817) (xy 132.607234 -295.444513)
			(xy 132.732513 -295.399621) (xy 132.860254 -295.362302) (xy 132.989997 -295.332689) (xy 133.121279 -295.310888)
			(xy 133.25363 -295.296978) (xy 133.386576 -295.291007) (xy 133.519641 -295.292998) (xy 133.652349 -295.302943)
			(xy 133.784225 -295.320807) (xy 133.914796 -295.346525) (xy 134.043596 -295.380006) (xy 134.170162 -295.42113)
			(xy 134.294043 -295.46975) (xy 134.414794 -295.525691) (xy 134.531984 -295.588753) (xy 134.645193 -295.658711)
			(xy 134.754015 -295.735315) (xy 134.858061 -295.818289) (xy 134.956959 -295.907337) (xy 135.050354 -296.00214)
			(xy 135.137912 -296.102358) (xy 135.219321 -296.207634) (xy 135.294287 -296.31759) (xy 135.362544 -296.431832)
			(xy 135.423846 -296.549952) (xy 135.477975 -296.671527) (xy 135.524736 -296.796121) (xy 135.563962 -296.923289)
			(xy 135.595512 -297.052575) (xy 135.619275 -297.183516) (xy 135.635164 -297.315644) (xy 135.643122 -297.448486)
			(xy 135.64362 -297.515026) (xy 336.155548 -297.515026) (xy 336.159529 -297.382006) (xy 336.171458 -297.249461)
			(xy 336.191293 -297.117868) (xy 336.218962 -296.987696) (xy 336.254366 -296.859411) (xy 336.297379 -296.733474)
			(xy 336.347846 -296.610335) (xy 336.405587 -296.490434) (xy 336.470396 -296.374201) (xy 336.54204 -296.262051)
			(xy 336.620262 -296.154387) (xy 336.704783 -296.051594) (xy 336.795301 -295.954039) (xy 336.89149 -295.862073)
			(xy 336.993008 -295.776023) (xy 337.099489 -295.696199) (xy 337.210554 -295.622886) (xy 337.325805 -295.556346)
			(xy 337.444829 -295.496817) (xy 337.5672 -295.444513) (xy 337.692479 -295.399621) (xy 337.82022 -295.362302)
			(xy 337.949963 -295.332689) (xy 338.081245 -295.310888) (xy 338.213596 -295.296978) (xy 338.346542 -295.291007)
			(xy 338.479607 -295.292998) (xy 338.612315 -295.302943) (xy 338.744191 -295.320807) (xy 338.874762 -295.346525)
			(xy 339.003562 -295.380006) (xy 339.130128 -295.42113) (xy 339.254009 -295.46975) (xy 339.37476 -295.525691)
			(xy 339.49195 -295.588753) (xy 339.605159 -295.658711) (xy 339.713981 -295.735315) (xy 339.818027 -295.818289)
			(xy 339.916925 -295.907337) (xy 340.01032 -296.00214) (xy 340.097878 -296.102358) (xy 340.179287 -296.207634)
			(xy 340.254253 -296.31759) (xy 340.32251 -296.431832) (xy 340.383812 -296.549952) (xy 340.437941 -296.671527)
			(xy 340.484702 -296.796121) (xy 340.523928 -296.923289) (xy 340.555478 -297.052575) (xy 340.579241 -297.183516)
			(xy 340.59513 -297.315644) (xy 340.603088 -297.448486) (xy 340.603586 -297.515026) (xy 379.13565 -297.515026)
			(xy 379.139631 -297.382006) (xy 379.15156 -297.249461) (xy 379.171395 -297.117868) (xy 379.199064 -296.987696)
			(xy 379.234468 -296.859411) (xy 379.277481 -296.733474) (xy 379.327948 -296.610335) (xy 379.385689 -296.490434)
			(xy 379.450498 -296.374201) (xy 379.522142 -296.262051) (xy 379.600364 -296.154387) (xy 379.684885 -296.051594)
			(xy 379.775403 -295.954039) (xy 379.871592 -295.862073) (xy 379.97311 -295.776023) (xy 380.079591 -295.696199)
			(xy 380.190656 -295.622886) (xy 380.305907 -295.556346) (xy 380.424931 -295.496817) (xy 380.547302 -295.444513)
			(xy 380.672581 -295.399621) (xy 380.800322 -295.362302) (xy 380.930065 -295.332689) (xy 381.061347 -295.310888)
			(xy 381.193698 -295.296978) (xy 381.326644 -295.291007) (xy 381.459709 -295.292998) (xy 381.592417 -295.302943)
			(xy 381.724293 -295.320807) (xy 381.854864 -295.346525) (xy 381.983664 -295.380006) (xy 382.11023 -295.42113)
			(xy 382.234111 -295.46975) (xy 382.354862 -295.525691) (xy 382.472052 -295.588753) (xy 382.585261 -295.658711)
			(xy 382.694083 -295.735315) (xy 382.798129 -295.818289) (xy 382.897027 -295.907337) (xy 382.990422 -296.00214)
			(xy 383.07798 -296.102358) (xy 383.159389 -296.207634) (xy 383.234355 -296.31759) (xy 383.302612 -296.431832)
			(xy 383.363914 -296.549952) (xy 383.418043 -296.671527) (xy 383.464804 -296.796121) (xy 383.50403 -296.923289)
			(xy 383.53558 -297.052575) (xy 383.559343 -297.183516) (xy 383.575232 -297.315644) (xy 383.58319 -297.448486)
			(xy 383.583688 -297.515026) (xy 383.58319 -297.581566) (xy 383.575232 -297.714408) (xy 383.559343 -297.846536)
			(xy 383.53558 -297.977477) (xy 383.50403 -298.106763) (xy 383.464804 -298.233931) (xy 383.418043 -298.358525)
			(xy 383.363914 -298.4801) (xy 383.302612 -298.59822) (xy 383.234355 -298.712462) (xy 383.159389 -298.822418)
			(xy 383.07798 -298.927694) (xy 382.990422 -299.027912) (xy 382.897027 -299.122715) (xy 382.798129 -299.211763)
			(xy 382.694083 -299.294737) (xy 382.585261 -299.371341) (xy 382.472052 -299.441299) (xy 382.354862 -299.504361)
			(xy 382.234111 -299.560302) (xy 382.11023 -299.608922) (xy 381.983664 -299.650046) (xy 381.854864 -299.683527)
			(xy 381.724293 -299.709245) (xy 381.592417 -299.727109) (xy 381.459709 -299.737054) (xy 381.326644 -299.739045)
			(xy 381.193698 -299.733074) (xy 381.061347 -299.719164) (xy 380.930065 -299.697363) (xy 380.800322 -299.66775)
			(xy 380.672581 -299.630431) (xy 380.547302 -299.585539) (xy 380.424931 -299.533235) (xy 380.305907 -299.473706)
			(xy 380.190656 -299.407166) (xy 380.079591 -299.333853) (xy 379.97311 -299.254029) (xy 379.871592 -299.167979)
			(xy 379.775403 -299.076013) (xy 379.684885 -298.978458) (xy 379.600364 -298.875665) (xy 379.522142 -298.768001)
			(xy 379.450498 -298.655851) (xy 379.385689 -298.539618) (xy 379.327948 -298.419717) (xy 379.277481 -298.296578)
			(xy 379.234468 -298.170641) (xy 379.199064 -298.042356) (xy 379.171395 -297.912184) (xy 379.15156 -297.780591)
			(xy 379.139631 -297.648046) (xy 379.13565 -297.515026) (xy 340.603586 -297.515026) (xy 340.603088 -297.581566)
			(xy 340.59513 -297.714408) (xy 340.579241 -297.846536) (xy 340.555478 -297.977477) (xy 340.523928 -298.106763)
			(xy 340.484702 -298.233931) (xy 340.437941 -298.358525) (xy 340.383812 -298.4801) (xy 340.32251 -298.59822)
			(xy 340.254253 -298.712462) (xy 340.179287 -298.822418) (xy 340.097878 -298.927694) (xy 340.01032 -299.027912)
			(xy 339.916925 -299.122715) (xy 339.818027 -299.211763) (xy 339.713981 -299.294737) (xy 339.605159 -299.371341)
			(xy 339.49195 -299.441299) (xy 339.37476 -299.504361) (xy 339.254009 -299.560302) (xy 339.130128 -299.608922)
			(xy 339.003562 -299.650046) (xy 338.874762 -299.683527) (xy 338.744191 -299.709245) (xy 338.612315 -299.727109)
			(xy 338.479607 -299.737054) (xy 338.346542 -299.739045) (xy 338.213596 -299.733074) (xy 338.081245 -299.719164)
			(xy 337.949963 -299.697363) (xy 337.82022 -299.66775) (xy 337.692479 -299.630431) (xy 337.5672 -299.585539)
			(xy 337.444829 -299.533235) (xy 337.325805 -299.473706) (xy 337.210554 -299.407166) (xy 337.099489 -299.333853)
			(xy 336.993008 -299.254029) (xy 336.89149 -299.167979) (xy 336.795301 -299.076013) (xy 336.704783 -298.978458)
			(xy 336.620262 -298.875665) (xy 336.54204 -298.768001) (xy 336.470396 -298.655851) (xy 336.405587 -298.539618)
			(xy 336.347846 -298.419717) (xy 336.297379 -298.296578) (xy 336.254366 -298.170641) (xy 336.218962 -298.042356)
			(xy 336.191293 -297.912184) (xy 336.171458 -297.780591) (xy 336.159529 -297.648046) (xy 336.155548 -297.515026)
			(xy 135.64362 -297.515026) (xy 135.643122 -297.581566) (xy 135.635164 -297.714408) (xy 135.619275 -297.846536)
			(xy 135.595512 -297.977477) (xy 135.563962 -298.106763) (xy 135.524736 -298.233931) (xy 135.477975 -298.358525)
			(xy 135.423846 -298.4801) (xy 135.362544 -298.59822) (xy 135.294287 -298.712462) (xy 135.219321 -298.822418)
			(xy 135.137912 -298.927694) (xy 135.050354 -299.027912) (xy 134.956959 -299.122715) (xy 134.858061 -299.211763)
			(xy 134.754015 -299.294737) (xy 134.645193 -299.371341) (xy 134.531984 -299.441299) (xy 134.414794 -299.504361)
			(xy 134.294043 -299.560302) (xy 134.170162 -299.608922) (xy 134.043596 -299.650046) (xy 133.914796 -299.683527)
			(xy 133.784225 -299.709245) (xy 133.652349 -299.727109) (xy 133.519641 -299.737054) (xy 133.386576 -299.739045)
			(xy 133.25363 -299.733074) (xy 133.121279 -299.719164) (xy 132.989997 -299.697363) (xy 132.860254 -299.66775)
			(xy 132.732513 -299.630431) (xy 132.607234 -299.585539) (xy 132.484863 -299.533235) (xy 132.365839 -299.473706)
			(xy 132.250588 -299.407166) (xy 132.139523 -299.333853) (xy 132.033042 -299.254029) (xy 131.931524 -299.167979)
			(xy 131.835335 -299.076013) (xy 131.744817 -298.978458) (xy 131.660296 -298.875665) (xy 131.582074 -298.768001)
			(xy 131.51043 -298.655851) (xy 131.445621 -298.539618) (xy 131.38788 -298.419717) (xy 131.337413 -298.296578)
			(xy 131.2944 -298.170641) (xy 131.258996 -298.042356) (xy 131.231327 -297.912184) (xy 131.211492 -297.780591)
			(xy 131.199563 -297.648046) (xy 131.195582 -297.515026) (xy 92.663518 -297.515026) (xy 92.66302 -297.581566)
			(xy 92.655062 -297.714408) (xy 92.639173 -297.846536) (xy 92.61541 -297.977477) (xy 92.58386 -298.106763)
			(xy 92.544634 -298.233931) (xy 92.497873 -298.358525) (xy 92.443744 -298.4801) (xy 92.382442 -298.59822)
			(xy 92.314185 -298.712462) (xy 92.239219 -298.822418) (xy 92.15781 -298.927694) (xy 92.070252 -299.027912)
			(xy 91.976857 -299.122715) (xy 91.877959 -299.211763) (xy 91.773913 -299.294737) (xy 91.665091 -299.371341)
			(xy 91.551882 -299.441299) (xy 91.434692 -299.504361) (xy 91.313941 -299.560302) (xy 91.19006 -299.608922)
			(xy 91.063494 -299.650046) (xy 90.934694 -299.683527) (xy 90.804123 -299.709245) (xy 90.672247 -299.727109)
			(xy 90.539539 -299.737054) (xy 90.406474 -299.739045) (xy 90.273528 -299.733074) (xy 90.141177 -299.719164)
			(xy 90.009895 -299.697363) (xy 89.880152 -299.66775) (xy 89.752411 -299.630431) (xy 89.627132 -299.585539)
			(xy 89.504761 -299.533235) (xy 89.385737 -299.473706) (xy 89.270486 -299.407166) (xy 89.159421 -299.333853)
			(xy 89.05294 -299.254029) (xy 88.951422 -299.167979) (xy 88.855233 -299.076013) (xy 88.764715 -298.978458)
			(xy 88.680194 -298.875665) (xy 88.601972 -298.768001) (xy 88.530328 -298.655851) (xy 88.465519 -298.539618)
			(xy 88.407778 -298.419717) (xy 88.357311 -298.296578) (xy 88.314298 -298.170641) (xy 88.278894 -298.042356)
			(xy 88.251225 -297.912184) (xy 88.23139 -297.780591) (xy 88.219461 -297.648046) (xy 88.21548 -297.515026)
			(xy 2.509012 -297.515026) (xy 2.509012 -360.76382) (xy 4.226823 -360.76382) (xy 4.230819 -360.553934)
			(xy 4.242804 -360.344352) (xy 4.262758 -360.135378) (xy 4.290654 -359.927316) (xy 4.326451 -359.720466)
			(xy 4.370096 -359.515129) (xy 4.421528 -359.311603) (xy 4.48067 -359.110182) (xy 4.547438 -358.911159)
			(xy 4.621734 -358.714822) (xy 4.703452 -358.521456) (xy 4.792471 -358.331341) (xy 4.888664 -358.144753)
			(xy 4.991891 -357.961962) (xy 5.102002 -357.783234) (xy 5.218837 -357.608827) (xy 5.342227 -357.438995)
			(xy 5.471994 -357.273983) (xy 5.607948 -357.114032) (xy 5.749894 -356.959372) (xy 5.897624 -356.810228)
			(xy 6.050926 -356.666817) (xy 6.209576 -356.529346) (xy 6.373345 -356.398014) (xy 6.541995 -356.273013)
			(xy 6.715281 -356.154522) (xy 6.892953 -356.042715) (xy 7.074753 -355.937753) (xy 7.260417 -355.839788)
			(xy 7.449675 -355.748963) (xy 7.642255 -355.665409) (xy 7.837876 -355.589246) (xy 8.036254 -355.520587)
			(xy 8.237103 -355.45953) (xy 8.44013 -355.406163) (xy 8.645043 -355.360565) (xy 8.851542 -355.3228)
			(xy 9.059329 -355.292925) (xy 9.268104 -355.270982) (xy 9.477562 -355.257003) (xy 9.687401 -355.251008)
			(xy 9.897315 -355.253007) (xy 10.107002 -355.262995) (xy 10.316156 -355.28096) (xy 10.524474 -355.306874)
			(xy 10.731655 -355.340699) (xy 10.937399 -355.382388) (xy 11.141405 -355.43188) (xy 11.34338 -355.489102)
			(xy 11.54303 -355.553972) (xy 11.740065 -355.626396) (xy 11.934201 -355.706269) (xy 12.125154 -355.793475)
			(xy 12.31265 -355.887887) (xy 12.496415 -355.989369) (xy 12.676183 -356.097773) (xy 12.851694 -356.212943)
			(xy 13.022693 -356.334711) (xy 13.188933 -356.4629) (xy 13.350172 -356.597326) (xy 13.506176 -356.737793)
			(xy 13.656719 -356.884097) (xy 13.801583 -357.036026) (xy 13.940558 -357.19336) (xy 14.073443 -357.355871)
			(xy 14.200044 -357.523324) (xy 14.320179 -357.695474) (xy 14.433673 -357.872074) (xy 14.540361 -358.052866)
			(xy 14.640088 -358.237589) (xy 14.732711 -358.425975) (xy 14.818095 -358.61775) (xy 14.896116 -358.812637)
			(xy 14.966661 -359.010353) (xy 15.029628 -359.210611) (xy 15.084925 -359.413121) (xy 15.132472 -359.61759)
			(xy 15.1722 -359.823721) (xy 15.204052 -360.031214) (xy 15.227982 -360.23977) (xy 15.243954 -360.449086)
			(xy 15.251946 -360.658858) (xy 15.252446 -360.76382) (xy 15.251946 -360.868782) (xy 15.243954 -361.078554)
			(xy 15.239789 -361.133136) (xy 121.446286 -361.133136) (xy 121.450375 -361.077254) (xy 121.462558 -361.022564)
			(xy 121.482574 -360.97023) (xy 121.509997 -360.921368) (xy 121.544242 -360.87702) (xy 121.584578 -360.83813)
			(xy 121.630148 -360.805528) (xy 121.679979 -360.779909) (xy 121.733009 -360.761817) (xy 121.788107 -360.75164)
			(xy 121.844101 -360.749594) (xy 121.899796 -360.755722) (xy 121.930771 -360.76382) (xy 211.161635 -360.76382)
			(xy 211.16566 -360.621628) (xy 211.177723 -360.479892) (xy 211.197786 -360.339066) (xy 211.225784 -360.1996)
			(xy 211.261628 -360.061941) (xy 211.305202 -359.926531) (xy 211.356367 -359.793803) (xy 211.41496 -359.664182)
			(xy 211.480791 -359.538084) (xy 211.553652 -359.415912) (xy 211.633307 -359.298058) (xy 211.719503 -359.184899)
			(xy 211.811962 -359.076797) (xy 211.91039 -358.9741) (xy 212.014469 -358.877136) (xy 212.123868 -358.786216)
			(xy 212.238236 -358.70163) (xy 212.357205 -358.62365) (xy 212.480396 -358.552526) (xy 212.607413 -358.488485)
			(xy 212.73785 -358.431733) (xy 212.871289 -358.382451) (xy 213.007302 -358.340797) (xy 213.145454 -358.306905)
			(xy 213.285303 -358.280884) (xy 213.426399 -358.262816) (xy 213.568291 -358.252759) (xy 213.710526 -358.250746)
			(xy 213.852646 -358.256783) (xy 213.994197 -358.270851) (xy 214.134726 -358.292905) (xy 214.273781 -358.322874)
			(xy 214.410919 -358.360662) (xy 214.545699 -358.406148) (xy 214.67769 -358.459186) (xy 214.806469 -358.519607)
			(xy 214.931623 -358.587216) (xy 215.052751 -358.661798) (xy 215.169467 -358.743114) (xy 215.281395 -358.830902)
			(xy 215.388177 -358.924882) (xy 215.489471 -359.024752) (xy 215.584952 -359.130194) (xy 215.674316 -359.240868)
			(xy 215.757274 -359.356421) (xy 215.833563 -359.476482) (xy 215.902937 -359.600667) (xy 215.965174 -359.728578)
			(xy 216.020075 -359.859805) (xy 216.067463 -359.993928) (xy 216.107188 -360.130517) (xy 216.139121 -360.269135)
			(xy 216.163162 -360.409337) (xy 216.179231 -360.550675) (xy 216.187279 -360.692696) (xy 216.187782 -360.76382)
			(xy 255.611635 -360.76382) (xy 255.61566 -360.621628) (xy 255.627723 -360.479892) (xy 255.647786 -360.339066)
			(xy 255.675784 -360.1996) (xy 255.711628 -360.061941) (xy 255.755202 -359.926531) (xy 255.806367 -359.793803)
			(xy 255.86496 -359.664182) (xy 255.930791 -359.538084) (xy 256.003652 -359.415912) (xy 256.083307 -359.298058)
			(xy 256.169503 -359.184899) (xy 256.261962 -359.076797) (xy 256.36039 -358.9741) (xy 256.464469 -358.877136)
			(xy 256.573868 -358.786216) (xy 256.688236 -358.70163) (xy 256.807205 -358.62365) (xy 256.930396 -358.552526)
			(xy 257.057413 -358.488485) (xy 257.18785 -358.431733) (xy 257.321289 -358.382451) (xy 257.457302 -358.340797)
			(xy 257.595454 -358.306905) (xy 257.735303 -358.280884) (xy 257.876399 -358.262816) (xy 258.018291 -358.252759)
			(xy 258.160526 -358.250746) (xy 258.302646 -358.256783) (xy 258.444197 -358.270851) (xy 258.584726 -358.292905)
			(xy 258.723781 -358.322874) (xy 258.860919 -358.360662) (xy 258.995699 -358.406148) (xy 259.12769 -358.459186)
			(xy 259.256469 -358.519607) (xy 259.381623 -358.587216) (xy 259.502751 -358.661798) (xy 259.619467 -358.743114)
			(xy 259.731395 -358.830902) (xy 259.838177 -358.924882) (xy 259.939471 -359.024752) (xy 260.034952 -359.130194)
			(xy 260.124316 -359.240868) (xy 260.207274 -359.356421) (xy 260.283563 -359.476482) (xy 260.352937 -359.600667)
			(xy 260.415174 -359.728578) (xy 260.470075 -359.859805) (xy 260.517463 -359.993928) (xy 260.557188 -360.130517)
			(xy 260.589121 -360.269135) (xy 260.613162 -360.409337) (xy 260.629231 -360.550675) (xy 260.637279 -360.692696)
			(xy 260.637782 -360.76382) (xy 260.637279 -360.834944) (xy 260.629231 -360.976965) (xy 260.613162 -361.118303)
			(xy 260.610619 -361.133136) (xy 369.3861 -361.133136) (xy 369.390189 -361.077254) (xy 369.402372 -361.022564)
			(xy 369.422388 -360.97023) (xy 369.449811 -360.921368) (xy 369.484056 -360.87702) (xy 369.524392 -360.83813)
			(xy 369.569962 -360.805528) (xy 369.619793 -360.779909) (xy 369.672823 -360.761817) (xy 369.727921 -360.75164)
			(xy 369.783915 -360.749594) (xy 369.83961 -360.755722) (xy 369.870585 -360.76382) (xy 456.565771 -360.76382)
			(xy 456.569767 -360.553934) (xy 456.581752 -360.344352) (xy 456.601706 -360.135378) (xy 456.629602 -359.927316)
			(xy 456.665399 -359.720466) (xy 456.709044 -359.515129) (xy 456.760476 -359.311603) (xy 456.819618 -359.110182)
			(xy 456.886386 -358.911159) (xy 456.960682 -358.714822) (xy 457.0424 -358.521456) (xy 457.131419 -358.331341)
			(xy 457.227612 -358.144753) (xy 457.330839 -357.961962) (xy 457.44095 -357.783234) (xy 457.557785 -357.608827)
			(xy 457.681175 -357.438995) (xy 457.810942 -357.273983) (xy 457.946896 -357.114032) (xy 458.088842 -356.959372)
			(xy 458.236572 -356.810228) (xy 458.389874 -356.666817) (xy 458.548524 -356.529346) (xy 458.712293 -356.398014)
			(xy 458.880943 -356.273013) (xy 459.054229 -356.154522) (xy 459.231901 -356.042715) (xy 459.413701 -355.937753)
			(xy 459.599365 -355.839788) (xy 459.788623 -355.748963) (xy 459.981203 -355.665409) (xy 460.176824 -355.589246)
			(xy 460.375202 -355.520587) (xy 460.576051 -355.45953) (xy 460.779078 -355.406163) (xy 460.983991 -355.360565)
			(xy 461.19049 -355.3228) (xy 461.398277 -355.292925) (xy 461.607052 -355.270982) (xy 461.81651 -355.257003)
			(xy 462.026349 -355.251008) (xy 462.236263 -355.253007) (xy 462.44595 -355.262995) (xy 462.655104 -355.28096)
			(xy 462.863422 -355.306874) (xy 463.070603 -355.340699) (xy 463.276347 -355.382388) (xy 463.480353 -355.43188)
			(xy 463.682328 -355.489102) (xy 463.881978 -355.553972) (xy 464.079013 -355.626396) (xy 464.273149 -355.706269)
			(xy 464.464102 -355.793475) (xy 464.651598 -355.887887) (xy 464.835363 -355.989369) (xy 465.015131 -356.097773)
			(xy 465.190642 -356.212943) (xy 465.361641 -356.334711) (xy 465.527881 -356.4629) (xy 465.68912 -356.597326)
			(xy 465.845124 -356.737793) (xy 465.995667 -356.884097) (xy 466.140531 -357.036026) (xy 466.279506 -357.19336)
			(xy 466.412391 -357.355871) (xy 466.538992 -357.523324) (xy 466.659127 -357.695474) (xy 466.772621 -357.872074)
			(xy 466.879309 -358.052866) (xy 466.979036 -358.237589) (xy 467.071659 -358.425975) (xy 467.157043 -358.61775)
			(xy 467.235064 -358.812637) (xy 467.305609 -359.010353) (xy 467.368576 -359.210611) (xy 467.423873 -359.413121)
			(xy 467.47142 -359.61759) (xy 467.511148 -359.823721) (xy 467.543 -360.031214) (xy 467.56693 -360.23977)
			(xy 467.582902 -360.449086) (xy 467.590894 -360.658858) (xy 467.591394 -360.76382) (xy 467.590894 -360.868782)
			(xy 467.582902 -361.078554) (xy 467.56693 -361.28787) (xy 467.543 -361.496426) (xy 467.511148 -361.703919)
			(xy 467.47142 -361.91005) (xy 467.423873 -362.114519) (xy 467.368576 -362.317029) (xy 467.305609 -362.517287)
			(xy 467.235064 -362.715003) (xy 467.157043 -362.90989) (xy 467.071659 -363.101665) (xy 466.979036 -363.290051)
			(xy 466.879309 -363.474774) (xy 466.772621 -363.655566) (xy 466.659127 -363.832166) (xy 466.538992 -364.004316)
			(xy 466.412391 -364.171769) (xy 466.279506 -364.33428) (xy 466.140531 -364.491614) (xy 465.995667 -364.643543)
			(xy 465.845124 -364.789847) (xy 465.68912 -364.930314) (xy 465.527881 -365.06474) (xy 465.361641 -365.192929)
			(xy 465.190642 -365.314697) (xy 465.015131 -365.429867) (xy 464.835363 -365.538271) (xy 464.651598 -365.639753)
			(xy 464.464102 -365.734165) (xy 464.273149 -365.821371) (xy 464.079013 -365.901244) (xy 463.881978 -365.973668)
			(xy 463.682328 -366.038538) (xy 463.480353 -366.09576) (xy 463.276347 -366.145252) (xy 463.070603 -366.186941)
			(xy 462.863422 -366.220766) (xy 462.655104 -366.24668) (xy 462.44595 -366.264645) (xy 462.236263 -366.274633)
			(xy 462.026349 -366.276632) (xy 461.81651 -366.270637) (xy 461.607052 -366.256658) (xy 461.398277 -366.234715)
			(xy 461.19049 -366.20484) (xy 460.983991 -366.167075) (xy 460.779078 -366.121477) (xy 460.576051 -366.06811)
			(xy 460.375202 -366.007053) (xy 460.176824 -365.938394) (xy 459.981203 -365.862231) (xy 459.788623 -365.778677)
			(xy 459.599365 -365.687852) (xy 459.413701 -365.589887) (xy 459.231901 -365.484925) (xy 459.054229 -365.373118)
			(xy 458.880943 -365.254627) (xy 458.712293 -365.129626) (xy 458.548524 -364.998294) (xy 458.389874 -364.860823)
			(xy 458.236572 -364.717412) (xy 458.088842 -364.568268) (xy 457.946896 -364.413608) (xy 457.810942 -364.253657)
			(xy 457.681175 -364.088645) (xy 457.557785 -363.918813) (xy 457.44095 -363.744406) (xy 457.330839 -363.565678)
			(xy 457.227612 -363.382887) (xy 457.131419 -363.196299) (xy 457.0424 -363.006184) (xy 456.960682 -362.812818)
			(xy 456.886386 -362.616481) (xy 456.819618 -362.417458) (xy 456.760476 -362.216037) (xy 456.709044 -362.012511)
			(xy 456.665399 -361.807174) (xy 456.629602 -361.600324) (xy 456.601706 -361.392262) (xy 456.581752 -361.183288)
			(xy 456.569767 -360.973706) (xy 456.565771 -360.76382) (xy 369.870585 -360.76382) (xy 369.893819 -360.769894)
			(xy 369.945387 -360.791808) (xy 369.993215 -360.820997) (xy 370.036283 -360.856838) (xy 370.073673 -360.898568)
			(xy 370.104589 -360.945298) (xy 370.128372 -360.996031) (xy 370.144514 -361.049687) (xy 370.152673 -361.105121)
			(xy 370.153184 -361.133136) (xy 370.152673 -361.161151) (xy 370.144514 -361.216585) (xy 370.128372 -361.270241)
			(xy 370.104589 -361.320974) (xy 370.073673 -361.367704) (xy 370.036283 -361.409434) (xy 369.993215 -361.445275)
			(xy 369.945387 -361.474464) (xy 369.893819 -361.496378) (xy 369.83961 -361.51055) (xy 369.783915 -361.516678)
			(xy 369.727921 -361.514632) (xy 369.672823 -361.504455) (xy 369.619793 -361.486363) (xy 369.569962 -361.460744)
			(xy 369.524392 -361.428142) (xy 369.484056 -361.389252) (xy 369.449811 -361.344904) (xy 369.422388 -361.296042)
			(xy 369.402372 -361.243708) (xy 369.390189 -361.189018) (xy 369.3861 -361.133136) (xy 260.610619 -361.133136)
			(xy 260.589121 -361.258505) (xy 260.557188 -361.397123) (xy 260.517463 -361.533712) (xy 260.470075 -361.667835)
			(xy 260.415174 -361.799062) (xy 260.352937 -361.926973) (xy 260.283563 -362.051158) (xy 260.207274 -362.171219)
			(xy 260.124316 -362.286772) (xy 260.034952 -362.397446) (xy 259.939471 -362.502888) (xy 259.838177 -362.602758)
			(xy 259.731395 -362.696738) (xy 259.619467 -362.784526) (xy 259.502751 -362.865842) (xy 259.381623 -362.940424)
			(xy 259.256469 -363.008033) (xy 259.12769 -363.068454) (xy 258.995699 -363.121492) (xy 258.860919 -363.166978)
			(xy 258.723781 -363.204766) (xy 258.584726 -363.234735) (xy 258.444197 -363.256789) (xy 258.302646 -363.270857)
			(xy 258.160526 -363.276894) (xy 258.018291 -363.274881) (xy 257.876399 -363.264824) (xy 257.735303 -363.246756)
			(xy 257.595454 -363.220735) (xy 257.457302 -363.186843) (xy 257.321289 -363.145189) (xy 257.18785 -363.095907)
			(xy 257.057413 -363.039155) (xy 256.930396 -362.975114) (xy 256.807205 -362.90399) (xy 256.688236 -362.82601)
			(xy 256.573868 -362.741424) (xy 256.464469 -362.650504) (xy 256.36039 -362.55354) (xy 256.261962 -362.450843)
			(xy 256.169503 -362.342741) (xy 256.083307 -362.229582) (xy 256.003652 -362.111728) (xy 255.930791 -361.989556)
			(xy 255.86496 -361.863458) (xy 255.806367 -361.733837) (xy 255.755202 -361.601109) (xy 255.711628 -361.465699)
			(xy 255.675784 -361.32804) (xy 255.647786 -361.188574) (xy 255.627723 -361.047748) (xy 255.61566 -360.906012)
			(xy 255.611635 -360.76382) (xy 216.187782 -360.76382) (xy 216.187279 -360.834944) (xy 216.179231 -360.976965)
			(xy 216.163162 -361.118303) (xy 216.139121 -361.258505) (xy 216.107188 -361.397123) (xy 216.067463 -361.533712)
			(xy 216.020075 -361.667835) (xy 215.965174 -361.799062) (xy 215.902937 -361.926973) (xy 215.833563 -362.051158)
			(xy 215.757274 -362.171219) (xy 215.674316 -362.286772) (xy 215.584952 -362.397446) (xy 215.489471 -362.502888)
			(xy 215.388177 -362.602758) (xy 215.281395 -362.696738) (xy 215.169467 -362.784526) (xy 215.052751 -362.865842)
			(xy 214.931623 -362.940424) (xy 214.806469 -363.008033) (xy 214.67769 -363.068454) (xy 214.545699 -363.121492)
			(xy 214.410919 -363.166978) (xy 214.273781 -363.204766) (xy 214.134726 -363.234735) (xy 213.994197 -363.256789)
			(xy 213.852646 -363.270857) (xy 213.710526 -363.276894) (xy 213.568291 -363.274881) (xy 213.426399 -363.264824)
			(xy 213.285303 -363.246756) (xy 213.145454 -363.220735) (xy 213.007302 -363.186843) (xy 212.871289 -363.145189)
			(xy 212.73785 -363.095907) (xy 212.607413 -363.039155) (xy 212.480396 -362.975114) (xy 212.357205 -362.90399)
			(xy 212.238236 -362.82601) (xy 212.123868 -362.741424) (xy 212.014469 -362.650504) (xy 211.91039 -362.55354)
			(xy 211.811962 -362.450843) (xy 211.719503 -362.342741) (xy 211.633307 -362.229582) (xy 211.553652 -362.111728)
			(xy 211.480791 -361.989556) (xy 211.41496 -361.863458) (xy 211.356367 -361.733837) (xy 211.305202 -361.601109)
			(xy 211.261628 -361.465699) (xy 211.225784 -361.32804) (xy 211.197786 -361.188574) (xy 211.177723 -361.047748)
			(xy 211.16566 -360.906012) (xy 211.161635 -360.76382) (xy 121.930771 -360.76382) (xy 121.954005 -360.769894)
			(xy 122.005573 -360.791808) (xy 122.053401 -360.820997) (xy 122.096469 -360.856838) (xy 122.133859 -360.898568)
			(xy 122.164775 -360.945298) (xy 122.188558 -360.996031) (xy 122.2047 -361.049687) (xy 122.212859 -361.105121)
			(xy 122.21337 -361.133136) (xy 122.212859 -361.161151) (xy 122.2047 -361.216585) (xy 122.188558 -361.270241)
			(xy 122.164775 -361.320974) (xy 122.133859 -361.367704) (xy 122.096469 -361.409434) (xy 122.053401 -361.445275)
			(xy 122.005573 -361.474464) (xy 121.954005 -361.496378) (xy 121.899796 -361.51055) (xy 121.844101 -361.516678)
			(xy 121.788107 -361.514632) (xy 121.733009 -361.504455) (xy 121.679979 -361.486363) (xy 121.630148 -361.460744)
			(xy 121.584578 -361.428142) (xy 121.544242 -361.389252) (xy 121.509997 -361.344904) (xy 121.482574 -361.296042)
			(xy 121.462558 -361.243708) (xy 121.450375 -361.189018) (xy 121.446286 -361.133136) (xy 15.239789 -361.133136)
			(xy 15.227982 -361.28787) (xy 15.204052 -361.496426) (xy 15.1722 -361.703919) (xy 15.132472 -361.91005)
			(xy 15.084925 -362.114519) (xy 15.029628 -362.317029) (xy 14.966661 -362.517287) (xy 14.896116 -362.715003)
			(xy 14.818095 -362.90989) (xy 14.732711 -363.101665) (xy 14.640088 -363.290051) (xy 14.540361 -363.474774)
			(xy 14.433673 -363.655566) (xy 14.320179 -363.832166) (xy 14.200044 -364.004316) (xy 14.073443 -364.171769)
			(xy 13.940558 -364.33428) (xy 13.801583 -364.491614) (xy 13.656719 -364.643543) (xy 13.506176 -364.789847)
			(xy 13.350172 -364.930314) (xy 13.188933 -365.06474) (xy 13.022693 -365.192929) (xy 12.851694 -365.314697)
			(xy 12.676183 -365.429867) (xy 12.496415 -365.538271) (xy 12.31265 -365.639753) (xy 12.125154 -365.734165)
			(xy 11.934201 -365.821371) (xy 11.740065 -365.901244) (xy 11.54303 -365.973668) (xy 11.34338 -366.038538)
			(xy 11.141405 -366.09576) (xy 10.937399 -366.145252) (xy 10.731655 -366.186941) (xy 10.524474 -366.220766)
			(xy 10.316156 -366.24668) (xy 10.107002 -366.264645) (xy 9.897315 -366.274633) (xy 9.687401 -366.276632)
			(xy 9.477562 -366.270637) (xy 9.268104 -366.256658) (xy 9.059329 -366.234715) (xy 8.851542 -366.20484)
			(xy 8.645043 -366.167075) (xy 8.44013 -366.121477) (xy 8.237103 -366.06811) (xy 8.036254 -366.007053)
			(xy 7.837876 -365.938394) (xy 7.642255 -365.862231) (xy 7.449675 -365.778677) (xy 7.260417 -365.687852)
			(xy 7.074753 -365.589887) (xy 6.892953 -365.484925) (xy 6.715281 -365.373118) (xy 6.541995 -365.254627)
			(xy 6.373345 -365.129626) (xy 6.209576 -364.998294) (xy 6.050926 -364.860823) (xy 5.897624 -364.717412)
			(xy 5.749894 -364.568268) (xy 5.607948 -364.413608) (xy 5.471994 -364.253657) (xy 5.342227 -364.088645)
			(xy 5.218837 -363.918813) (xy 5.102002 -363.744406) (xy 4.991891 -363.565678) (xy 4.888664 -363.382887)
			(xy 4.792471 -363.196299) (xy 4.703452 -363.006184) (xy 4.621734 -362.812818) (xy 4.547438 -362.616481)
			(xy 4.48067 -362.417458) (xy 4.421528 -362.216037) (xy 4.370096 -362.012511) (xy 4.326451 -361.807174)
			(xy 4.290654 -361.600324) (xy 4.262758 -361.392262) (xy 4.242804 -361.183288) (xy 4.230819 -360.973706)
			(xy 4.226823 -360.76382) (xy 2.509012 -360.76382) (xy 2.509012 -383.932484) (xy 8.539215 -383.932484)
			(xy 8.539215 -383.803344) (xy 8.547165 -383.674449) (xy 8.563035 -383.546289) (xy 8.586764 -383.419348)
			(xy 8.618263 -383.294109) (xy 8.657412 -383.171046) (xy 8.704063 -383.050627) (xy 8.758038 -382.933308)
			(xy 8.819133 -382.819534) (xy 8.887116 -382.709737) (xy 8.96173 -382.604334) (xy 9.042691 -382.503724)
			(xy 9.129691 -382.408289) (xy 9.222402 -382.31839) (xy 9.320472 -382.234369) (xy 9.423527 -382.156545)
			(xy 9.531178 -382.085213) (xy 9.643017 -382.020643) (xy 9.758618 -381.963081) (xy 9.877543 -381.912744)
			(xy 9.999342 -381.869824) (xy 10.123552 -381.834483) (xy 10.249701 -381.806856) (xy 10.377313 -381.787047)
			(xy 10.505902 -381.775131) (xy 10.63498 -381.771155) (xy 10.764058 -381.775131) (xy 10.892647 -381.787047)
			(xy 11.020259 -381.806856) (xy 11.146408 -381.834483) (xy 11.270618 -381.869824) (xy 11.392417 -381.912744)
			(xy 11.511342 -381.963081) (xy 11.626943 -382.020643) (xy 11.738782 -382.085213) (xy 11.846433 -382.156545)
			(xy 11.949488 -382.234369) (xy 12.047558 -382.31839) (xy 12.140269 -382.408289) (xy 12.227269 -382.503724)
			(xy 12.30823 -382.604334) (xy 12.382844 -382.709737) (xy 12.450827 -382.819534) (xy 12.505341 -382.921052)
			(xy 19.016679 -382.921052) (xy 19.016679 -382.866548) (xy 19.024437 -382.812598) (xy 19.039793 -382.760301)
			(xy 19.062436 -382.710722) (xy 19.091904 -382.664871) (xy 19.127599 -382.62368) (xy 19.168792 -382.587989)
			(xy 19.214645 -382.558523) (xy 19.264226 -382.535884) (xy 19.316523 -382.520531) (xy 19.370474 -382.512778)
			(xy 19.397726 -382.512316) (xy 20.261326 -382.512316) (xy 20.288578 -382.512756) (xy 20.342526 -382.520516)
			(xy 20.394821 -382.535874) (xy 20.444398 -382.558518) (xy 20.490248 -382.587987) (xy 20.531438 -382.623681)
			(xy 20.567129 -382.664873) (xy 20.596594 -382.710725) (xy 20.619235 -382.760303) (xy 20.63459 -382.812599)
			(xy 20.642346 -382.866548) (xy 20.642346 -382.921052) (xy 20.636681 -382.960459) (xy 22.291788 -382.960459)
			(xy 22.291788 -382.905921) (xy 22.29955 -382.851938) (xy 22.314915 -382.79961) (xy 22.337571 -382.75)
			(xy 22.367056 -382.70412) (xy 22.40277 -382.662903) (xy 22.443987 -382.627188) (xy 22.489867 -382.597702)
			(xy 22.539476 -382.575046) (xy 22.591804 -382.559681) (xy 22.645787 -382.551919) (xy 22.673056 -382.551432)
			(xy 23.536656 -382.551432) (xy 23.563927 -382.551887) (xy 23.617915 -382.559649) (xy 23.670249 -382.575015)
			(xy 23.719863 -382.597673) (xy 23.765748 -382.62716) (xy 23.806969 -382.662878) (xy 23.842687 -382.704099)
			(xy 23.872175 -382.749983) (xy 23.894834 -382.799597) (xy 23.9102 -382.851931) (xy 23.917962 -382.905919)
			(xy 23.917962 -382.960461) (xy 23.9102 -383.014449) (xy 23.894834 -383.066783) (xy 23.872175 -383.116397)
			(xy 23.842687 -383.162281) (xy 23.806969 -383.203502) (xy 23.765748 -383.23922) (xy 23.719863 -383.268707)
			(xy 23.670249 -383.291365) (xy 23.617915 -383.306731) (xy 23.563927 -383.314493) (xy 23.536656 -383.314956)
			(xy 22.673056 -383.314956) (xy 22.645787 -383.314461) (xy 22.591804 -383.306699) (xy 22.539476 -383.291334)
			(xy 22.489867 -383.268678) (xy 22.443987 -383.239192) (xy 22.40277 -383.203477) (xy 22.367056 -383.16226)
			(xy 22.337571 -383.11638) (xy 22.314915 -383.06677) (xy 22.29955 -383.014442) (xy 22.291788 -382.960459)
			(xy 20.636681 -382.960459) (xy 20.63459 -382.975001) (xy 20.619235 -383.027297) (xy 20.596594 -383.076875)
			(xy 20.567129 -383.122727) (xy 20.531438 -383.163919) (xy 20.490248 -383.199613) (xy 20.444398 -383.229082)
			(xy 20.394821 -383.251726) (xy 20.342526 -383.267084) (xy 20.288578 -383.274844) (xy 20.261326 -383.275332)
			(xy 19.397726 -383.275332) (xy 19.370474 -383.274822) (xy 19.316523 -383.267069) (xy 19.264226 -383.251716)
			(xy 19.214645 -383.229077) (xy 19.168792 -383.199611) (xy 19.127599 -383.16392) (xy 19.091904 -383.122729)
			(xy 19.062436 -383.076878) (xy 19.039793 -383.027299) (xy 19.024437 -382.975002) (xy 19.016679 -382.921052)
			(xy 12.505341 -382.921052) (xy 12.511922 -382.933308) (xy 12.565897 -383.050627) (xy 12.612548 -383.171046)
			(xy 12.651697 -383.294109) (xy 12.683196 -383.419348) (xy 12.706925 -383.546289) (xy 12.722795 -383.674449)
			(xy 12.730745 -383.803344) (xy 12.731242 -383.867914) (xy 12.730745 -383.932484) (xy 12.722795 -384.061379)
			(xy 12.706925 -384.189539) (xy 12.683196 -384.31648) (xy 12.651697 -384.441719) (xy 12.612548 -384.564782)
			(xy 12.565897 -384.685201) (xy 12.511922 -384.80252) (xy 12.450827 -384.916294) (xy 12.382844 -385.026091)
			(xy 12.30823 -385.131494) (xy 12.227269 -385.232104) (xy 12.140269 -385.327539) (xy 12.047558 -385.417438)
			(xy 11.949488 -385.501459) (xy 11.846433 -385.579283) (xy 11.738782 -385.650615) (xy 11.626943 -385.715185)
			(xy 11.511342 -385.772747) (xy 11.483943 -385.784344) (xy 19.460972 -385.784344) (xy 19.460972 -384.920744)
			(xy 19.461458 -384.893493) (xy 19.469214 -384.839545) (xy 19.484569 -384.78725) (xy 19.507211 -384.737673)
			(xy 19.536677 -384.691823) (xy 19.572368 -384.650632) (xy 19.613559 -384.614941) (xy 19.659409 -384.585475)
			(xy 19.708986 -384.562833) (xy 19.761281 -384.547478) (xy 19.815229 -384.539722) (xy 19.869731 -384.539722)
			(xy 19.923679 -384.547478) (xy 19.975974 -384.562833) (xy 20.025551 -384.585475) (xy 20.071401 -384.614941)
			(xy 20.112592 -384.650632) (xy 20.148283 -384.691823) (xy 20.177749 -384.737673) (xy 20.200391 -384.78725)
			(xy 20.215746 -384.839545) (xy 20.223502 -384.893493) (xy 20.223988 -384.920744) (xy 20.223988 -385.784344)
			(xy 20.22353 -385.809998) (xy 22.731984 -385.809998) (xy 22.731984 -384.946398) (xy 22.73247 -384.919147)
			(xy 22.740226 -384.865199) (xy 22.755581 -384.812904) (xy 22.778223 -384.763327) (xy 22.807689 -384.717477)
			(xy 22.84338 -384.676286) (xy 22.884571 -384.640595) (xy 22.930421 -384.611129) (xy 22.979998 -384.588487)
			(xy 23.032293 -384.573132) (xy 23.086241 -384.565376) (xy 23.140743 -384.565376) (xy 23.194691 -384.573132)
			(xy 23.246986 -384.588487) (xy 23.296563 -384.611129) (xy 23.342413 -384.640595) (xy 23.383604 -384.676286)
			(xy 23.419295 -384.717477) (xy 23.448761 -384.763327) (xy 23.471403 -384.812904) (xy 23.486758 -384.865199)
			(xy 23.494514 -384.919147) (xy 23.495 -384.946398) (xy 23.495 -385.440249) (xy 36.585674 -385.440249)
			(xy 36.585674 -385.385751) (xy 36.593429 -385.331807) (xy 36.608782 -385.279515) (xy 36.63142 -385.229941)
			(xy 36.660882 -385.184092) (xy 36.696569 -385.142903) (xy 36.737753 -385.107211) (xy 36.783598 -385.077743)
			(xy 36.83317 -385.055099) (xy 36.88546 -385.039739) (xy 36.939403 -385.031977) (xy 36.966652 -385.031488)
			(xy 37.830252 -385.031488) (xy 37.857507 -385.031956) (xy 37.911462 -385.039707) (xy 37.963765 -385.055059)
			(xy 38.013351 -385.077699) (xy 38.05921 -385.107165) (xy 38.100408 -385.142858) (xy 38.136106 -385.184052)
			(xy 38.165578 -385.229907) (xy 38.188224 -385.27949) (xy 38.203582 -385.331791) (xy 38.211341 -385.385745)
			(xy 38.211341 -385.440255) (xy 38.203582 -385.494209) (xy 38.188224 -385.54651) (xy 38.165578 -385.596093)
			(xy 38.16123 -385.602858) (xy 41.455211 -385.602858) (xy 41.455211 -385.548342) (xy 41.46297 -385.494381)
			(xy 41.47833 -385.442074) (xy 41.500978 -385.392486) (xy 41.530453 -385.346625) (xy 41.566155 -385.305427)
			(xy 41.607357 -385.269729) (xy 41.653221 -385.240259) (xy 41.702812 -385.217616) (xy 41.755121 -385.202261)
			(xy 41.809082 -385.194508) (xy 41.83634 -385.194048) (xy 42.69994 -385.194048) (xy 42.727186 -385.194625)
			(xy 42.781123 -385.202385) (xy 42.833407 -385.217742) (xy 42.882974 -385.240383) (xy 42.928814 -385.269847)
			(xy 42.969994 -385.305534) (xy 43.005677 -385.346718) (xy 43.035136 -385.392562) (xy 43.057772 -385.44213)
			(xy 43.073123 -385.494416) (xy 43.080878 -385.548354) (xy 43.080878 -385.602846) (xy 43.073123 -385.656784)
			(xy 43.057772 -385.70907) (xy 43.035136 -385.758638) (xy 43.005677 -385.804482) (xy 42.969994 -385.845666)
			(xy 42.928814 -385.881353) (xy 42.882974 -385.910817) (xy 42.833407 -385.933458) (xy 42.781123 -385.948815)
			(xy 42.727186 -385.956575) (xy 42.69994 -385.957064) (xy 41.83634 -385.957064) (xy 41.809082 -385.956692)
			(xy 41.755121 -385.948939) (xy 41.702812 -385.933584) (xy 41.653221 -385.910941) (xy 41.607357 -385.881471)
			(xy 41.566155 -385.845773) (xy 41.530453 -385.804575) (xy 41.500978 -385.758714) (xy 41.47833 -385.709126)
			(xy 41.46297 -385.656819) (xy 41.455211 -385.602858) (xy 38.16123 -385.602858) (xy 38.136106 -385.641948)
			(xy 38.100408 -385.683142) (xy 38.05921 -385.718835) (xy 38.013351 -385.748301) (xy 37.963765 -385.770941)
			(xy 37.911462 -385.786293) (xy 37.857507 -385.794044) (xy 37.830252 -385.794504) (xy 36.966652 -385.794504)
			(xy 36.939403 -385.794023) (xy 36.88546 -385.786261) (xy 36.83317 -385.770901) (xy 36.783598 -385.748257)
			(xy 36.737753 -385.718789) (xy 36.696569 -385.683097) (xy 36.660882 -385.641908) (xy 36.63142 -385.596059)
			(xy 36.608782 -385.546485) (xy 36.593429 -385.494193) (xy 36.585674 -385.440249) (xy 23.495 -385.440249)
			(xy 23.495 -385.809998) (xy 23.494514 -385.837249) (xy 23.486758 -385.891197) (xy 23.471403 -385.943492)
			(xy 23.448761 -385.993069) (xy 23.419295 -386.038919) (xy 23.383604 -386.08011) (xy 23.342413 -386.115801)
			(xy 23.296563 -386.145267) (xy 23.246986 -386.167909) (xy 23.194691 -386.183264) (xy 23.140743 -386.19102)
			(xy 23.086241 -386.19102) (xy 23.032293 -386.183264) (xy 22.979998 -386.167909) (xy 22.930421 -386.145267)
			(xy 22.884571 -386.115801) (xy 22.84338 -386.08011) (xy 22.807689 -386.038919) (xy 22.778223 -385.993069)
			(xy 22.755581 -385.943492) (xy 22.740226 -385.891197) (xy 22.73247 -385.837249) (xy 22.731984 -385.809998)
			(xy 20.22353 -385.809998) (xy 20.223502 -385.811595) (xy 20.215746 -385.865543) (xy 20.200391 -385.917838)
			(xy 20.177749 -385.967415) (xy 20.148283 -386.013265) (xy 20.112592 -386.054456) (xy 20.071401 -386.090147)
			(xy 20.025551 -386.119613) (xy 19.975974 -386.142255) (xy 19.923679 -386.15761) (xy 19.869731 -386.165366)
			(xy 19.815229 -386.165366) (xy 19.761281 -386.15761) (xy 19.708986 -386.142255) (xy 19.659409 -386.119613)
			(xy 19.613559 -386.090147) (xy 19.572368 -386.054456) (xy 19.536677 -386.013265) (xy 19.507211 -385.967415)
			(xy 19.484569 -385.917838) (xy 19.469214 -385.865543) (xy 19.461458 -385.811595) (xy 19.460972 -385.784344)
			(xy 11.483943 -385.784344) (xy 11.392417 -385.823084) (xy 11.270618 -385.866004) (xy 11.146408 -385.901345)
			(xy 11.020259 -385.928972) (xy 10.892647 -385.948781) (xy 10.764058 -385.960697) (xy 10.63498 -385.964674)
			(xy 10.505902 -385.960697) (xy 10.377313 -385.948781) (xy 10.249701 -385.928972) (xy 10.123552 -385.901345)
			(xy 9.999342 -385.866004) (xy 9.877543 -385.823084) (xy 9.758618 -385.772747) (xy 9.643017 -385.715185)
			(xy 9.531178 -385.650615) (xy 9.423527 -385.579283) (xy 9.320472 -385.501459) (xy 9.222402 -385.417438)
			(xy 9.129691 -385.327539) (xy 9.042691 -385.232104) (xy 8.96173 -385.131494) (xy 8.887116 -385.026091)
			(xy 8.819133 -384.916294) (xy 8.758038 -384.80252) (xy 8.704063 -384.685201) (xy 8.657412 -384.564782)
			(xy 8.618263 -384.441719) (xy 8.586764 -384.31648) (xy 8.563035 -384.189539) (xy 8.547165 -384.061379)
			(xy 8.539215 -383.932484) (xy 2.509012 -383.932484) (xy 2.509012 -389.402275) (xy 286.566098 -389.402275)
			(xy 286.566098 -389.317529) (xy 286.574154 -389.233168) (xy 286.590192 -389.149954) (xy 286.614067 -389.068641)
			(xy 286.645564 -388.989966) (xy 286.684397 -388.914642) (xy 286.730213 -388.843349) (xy 286.7826 -388.776735)
			(xy 286.84108 -388.715402) (xy 286.905127 -388.659906) (xy 286.974158 -388.610748) (xy 287.04755 -388.568376)
			(xy 287.124637 -388.533171) (xy 287.204721 -388.505454) (xy 287.287078 -388.485474) (xy 287.370961 -388.473414)
			(xy 287.45561 -388.469382) (xy 287.540259 -388.473414) (xy 287.624142 -388.485474) (xy 287.706499 -388.505454)
			(xy 287.786583 -388.533171) (xy 287.86367 -388.568376) (xy 287.937062 -388.610748) (xy 288.006093 -388.659906)
			(xy 288.07014 -388.715402) (xy 288.12862 -388.776735) (xy 288.181007 -388.843349) (xy 288.226823 -388.914642)
			(xy 288.265656 -388.989966) (xy 288.297153 -389.068641) (xy 288.321028 -389.149954) (xy 288.337066 -389.233168)
			(xy 288.345122 -389.317529) (xy 288.345626 -389.359902) (xy 288.345122 -389.402275) (xy 297.615098 -389.402275)
			(xy 297.615098 -389.317529) (xy 297.623154 -389.233168) (xy 297.639192 -389.149954) (xy 297.663067 -389.068641)
			(xy 297.694564 -388.989966) (xy 297.733397 -388.914642) (xy 297.779213 -388.843349) (xy 297.8316 -388.776735)
			(xy 297.89008 -388.715402) (xy 297.954127 -388.659906) (xy 298.023158 -388.610748) (xy 298.09655 -388.568376)
			(xy 298.173637 -388.533171) (xy 298.253721 -388.505454) (xy 298.336078 -388.485474) (xy 298.419961 -388.473414)
			(xy 298.50461 -388.469382) (xy 298.589259 -388.473414) (xy 298.673142 -388.485474) (xy 298.755499 -388.505454)
			(xy 298.835583 -388.533171) (xy 298.91267 -388.568376) (xy 298.986062 -388.610748) (xy 299.055093 -388.659906)
			(xy 299.11914 -388.715402) (xy 299.17762 -388.776735) (xy 299.230007 -388.843349) (xy 299.275823 -388.914642)
			(xy 299.314656 -388.989966) (xy 299.346153 -389.068641) (xy 299.370028 -389.149954) (xy 299.386066 -389.233168)
			(xy 299.394122 -389.317529) (xy 299.394626 -389.359902) (xy 299.394122 -389.402275) (xy 299.386066 -389.486636)
			(xy 299.370028 -389.56985) (xy 299.346153 -389.651163) (xy 299.314656 -389.729838) (xy 299.275823 -389.805162)
			(xy 299.230007 -389.876455) (xy 299.17762 -389.943069) (xy 299.11914 -390.004402) (xy 299.055093 -390.059898)
			(xy 298.986062 -390.109056) (xy 298.91267 -390.151428) (xy 298.835583 -390.186633) (xy 298.755499 -390.21435)
			(xy 298.673142 -390.23433) (xy 298.589259 -390.24639) (xy 298.50461 -390.250423) (xy 298.419961 -390.24639)
			(xy 298.336078 -390.23433) (xy 298.253721 -390.21435) (xy 298.173637 -390.186633) (xy 298.09655 -390.151428)
			(xy 298.023158 -390.109056) (xy 297.954127 -390.059898) (xy 297.89008 -390.004402) (xy 297.8316 -389.943069)
			(xy 297.779213 -389.876455) (xy 297.733397 -389.805162) (xy 297.694564 -389.729838) (xy 297.663067 -389.651163)
			(xy 297.639192 -389.56985) (xy 297.623154 -389.486636) (xy 297.615098 -389.402275) (xy 288.345122 -389.402275)
			(xy 288.337066 -389.486636) (xy 288.321028 -389.56985) (xy 288.297153 -389.651163) (xy 288.265656 -389.729838)
			(xy 288.226823 -389.805162) (xy 288.181007 -389.876455) (xy 288.12862 -389.943069) (xy 288.07014 -390.004402)
			(xy 288.006093 -390.059898) (xy 287.937062 -390.109056) (xy 287.86367 -390.151428) (xy 287.786583 -390.186633)
			(xy 287.706499 -390.21435) (xy 287.624142 -390.23433) (xy 287.540259 -390.24639) (xy 287.45561 -390.250423)
			(xy 287.370961 -390.24639) (xy 287.287078 -390.23433) (xy 287.204721 -390.21435) (xy 287.124637 -390.186633)
			(xy 287.04755 -390.151428) (xy 286.974158 -390.109056) (xy 286.905127 -390.059898) (xy 286.84108 -390.004402)
			(xy 286.7826 -389.943069) (xy 286.730213 -389.876455) (xy 286.684397 -389.805162) (xy 286.645564 -389.729838)
			(xy 286.614067 -389.651163) (xy 286.590192 -389.56985) (xy 286.574154 -389.486636) (xy 286.566098 -389.402275)
			(xy 2.509012 -389.402275) (xy 2.509012 -390.74852) (xy 289.828732 -390.74852) (xy 289.829157 -390.717787)
			(xy 289.836564 -390.656768) (xy 289.851272 -390.597088) (xy 289.873068 -390.539615) (xy 289.901633 -390.485189)
			(xy 289.93655 -390.434604) (xy 289.97731 -390.388596) (xy 290.023319 -390.347837) (xy 290.073907 -390.312922)
			(xy 290.128334 -390.28436) (xy 290.185807 -390.262566) (xy 290.245488 -390.24786) (xy 290.306507 -390.240455)
			(xy 290.33724 -390.240012) (xy 290.369283 -390.240508) (xy 290.432859 -390.248584) (xy 290.494917 -390.264579)
			(xy 290.554476 -390.288239) (xy 290.610594 -390.31919) (xy 290.662381 -390.356941) (xy 290.709019 -390.400896)
			(xy 290.749768 -390.450359) (xy 290.783985 -390.504546) (xy 290.811128 -390.562601) (xy 290.830767 -390.623604)
			(xy 290.842591 -390.686591) (xy 290.844986 -390.718548) (xy 290.846452 -390.733661) (xy 290.857061 -390.762093)
			(xy 290.875562 -390.786147) (xy 290.900318 -390.803698) (xy 290.929141 -390.813192) (xy 290.9443 -390.814052)
			(xy 290.977155 -390.815239) (xy 291.042167 -390.825028) (xy 291.105376 -390.843112) (xy 291.165728 -390.86919)
			(xy 291.222216 -390.902827) (xy 291.2739 -390.943462) (xy 291.319917 -390.990417) (xy 291.359501 -391.04291)
			(xy 291.391992 -391.100065) (xy 291.416847 -391.160931) (xy 291.433653 -391.224491) (xy 291.442129 -391.289688)
			(xy 291.442648 -391.32256) (xy 291.442106 -391.353289) (xy 291.434703 -391.414298) (xy 291.42 -391.473971)
			(xy 291.398212 -391.531436) (xy 291.369656 -391.585856) (xy 291.334748 -391.636437) (xy 291.293998 -391.682441)
			(xy 291.248 -391.723199) (xy 291.197424 -391.758114) (xy 291.143009 -391.786679) (xy 291.085547 -391.808477)
			(xy 291.025877 -391.823189) (xy 290.964869 -391.830602) (xy 290.93414 -391.831068) (xy 290.902098 -391.830516)
			(xy 290.838523 -391.822449) (xy 290.776465 -391.806463) (xy 290.716905 -391.78281) (xy 290.660787 -391.751866)
			(xy 290.608999 -391.71412) (xy 290.56236 -391.670169) (xy 290.521609 -391.620711) (xy 290.487392 -391.566526)
			(xy 290.460249 -391.508474) (xy 290.440611 -391.447473) (xy 290.428788 -391.384488) (xy 290.426394 -391.352532)
			(xy 290.424962 -391.337414) (xy 290.414346 -391.308979) (xy 290.395837 -391.284924) (xy 290.371072 -391.267376)
			(xy 290.342242 -391.257886) (xy 290.32708 -391.257028) (xy 290.294229 -391.25578) (xy 290.229223 -391.24599)
			(xy 290.166019 -391.227907) (xy 290.105673 -391.201832) (xy 290.049188 -391.1682) (xy 289.997507 -391.127571)
			(xy 289.95149 -391.080623) (xy 289.911906 -391.028137) (xy 289.879413 -390.97099) (xy 289.854553 -390.910132)
			(xy 289.837741 -390.846579) (xy 289.829256 -390.78139) (xy 289.828732 -390.74852) (xy 2.509012 -390.74852)
			(xy 2.509012 -394.8085) (xy 243.179528 -394.8085) (xy 243.183558 -394.723892) (xy 243.195613 -394.640051)
			(xy 243.215583 -394.557735) (xy 243.243287 -394.47769) (xy 243.278475 -394.400641) (xy 243.320827 -394.327286)
			(xy 243.36996 -394.258289) (xy 243.42543 -394.194274) (xy 243.486733 -394.135823) (xy 243.553315 -394.083463)
			(xy 243.624573 -394.03767) (xy 243.699861 -393.998857) (xy 243.778498 -393.967377) (xy 243.859771 -393.943515)
			(xy 243.942944 -393.927486) (xy 244.027264 -393.919435) (xy 244.069616 -393.918948) (xy 244.11084 -393.919417)
			(xy 244.192933 -393.927053) (xy 244.273968 -393.94225) (xy 244.35325 -393.964876) (xy 244.430099 -393.994739)
			(xy 244.503857 -394.031582) (xy 244.573891 -394.075088) (xy 244.639601 -394.124886) (xy 244.670326 -394.152374)
			(xy 244.677558 -394.158461) (xy 244.695171 -394.165287) (xy 244.714061 -394.165287) (xy 244.731674 -394.158461)
			(xy 244.738906 -394.152374) (xy 244.769639 -394.124894) (xy 244.835341 -394.075085) (xy 244.905371 -394.03157)
			(xy 244.979128 -393.994723) (xy 245.055977 -393.964858) (xy 245.13526 -393.942233) (xy 245.216297 -393.927041)
			(xy 245.298392 -393.919413) (xy 245.339616 -393.918948) (xy 245.380184 -393.919416) (xy 245.460981 -393.926807)
			(xy 245.54077 -393.941524) (xy 245.618888 -393.963447) (xy 245.694684 -393.992392) (xy 245.767529 -394.02812)
			(xy 245.836818 -394.070333) (xy 245.901975 -394.118681) (xy 245.962458 -394.172761) (xy 246.017765 -394.232125)
			(xy 246.067436 -394.296278) (xy 246.111059 -394.364689) (xy 246.130064 -394.400532) (xy 246.157157 -394.401367)
			(xy 246.21073 -394.409598) (xy 246.262601 -394.42532) (xy 246.31173 -394.448214) (xy 246.357129 -394.477824)
			(xy 246.397887 -394.513553) (xy 246.433186 -394.554684) (xy 246.462317 -394.600391) (xy 246.484695 -394.649758)
			(xy 246.499871 -394.701791) (xy 246.507539 -394.755447) (xy 246.508016 -394.782548) (xy 246.507582 -394.8085)
			(xy 249.114543 -394.8085) (xy 249.118574 -394.723896) (xy 249.130628 -394.640058) (xy 249.150596 -394.557746)
			(xy 249.178298 -394.477704) (xy 249.213483 -394.400658) (xy 249.255833 -394.327305) (xy 249.304963 -394.25831)
			(xy 249.360429 -394.194298) (xy 249.421729 -394.135847) (xy 249.488307 -394.083488) (xy 249.55956 -394.037695)
			(xy 249.634844 -393.998882) (xy 249.713476 -393.967401) (xy 249.794745 -393.943537) (xy 249.877914 -393.927506)
			(xy 249.96223 -393.919453) (xy 250.00458 -393.918948) (xy 250.045803 -393.919439) (xy 250.127896 -393.927072)
			(xy 250.20893 -393.942266) (xy 250.288212 -393.964889) (xy 250.365061 -393.994749) (xy 250.438819 -394.031588)
			(xy 250.508854 -394.075092) (xy 250.574564 -394.124887) (xy 250.60529 -394.152374) (xy 250.612522 -394.158461)
			(xy 250.630135 -394.165287) (xy 250.649025 -394.165287) (xy 250.666638 -394.158461) (xy 250.67387 -394.152374)
			(xy 250.704576 -394.124863) (xy 250.770283 -394.075057) (xy 250.840317 -394.031545) (xy 250.914078 -393.994701)
			(xy 250.990931 -393.96484) (xy 251.070218 -393.942219) (xy 251.151257 -393.927032) (xy 251.233355 -393.91941)
			(xy 251.27458 -393.918948) (xy 251.315219 -393.919386) (xy 251.396157 -393.926808) (xy 251.47608 -393.941582)
			(xy 251.554323 -393.963585) (xy 251.630232 -393.992634) (xy 251.703174 -394.028487) (xy 251.772542 -394.070844)
			(xy 251.837756 -394.119353) (xy 251.898274 -394.173608) (xy 251.95359 -394.233158) (xy 252.003243 -394.297505)
			(xy 252.046819 -394.366114) (xy 252.06579 -394.402056) (xy 252.086364 -394.401548) (xy 252.113582 -394.401996)
			(xy 252.167464 -394.409739) (xy 252.219695 -394.425073) (xy 252.269213 -394.447684) (xy 252.315007 -394.477114)
			(xy 252.356147 -394.512762) (xy 252.391793 -394.553902) (xy 252.421221 -394.599698) (xy 252.443832 -394.649216)
			(xy 252.459163 -394.701448) (xy 252.466905 -394.75533) (xy 252.467364 -394.782548) (xy 252.466916 -394.8085)
			(xy 255.049428 -394.8085) (xy 255.053459 -394.723891) (xy 255.065514 -394.640048) (xy 255.085484 -394.55773)
			(xy 255.11319 -394.477684) (xy 255.148379 -394.400634) (xy 255.190732 -394.327277) (xy 255.239868 -394.258279)
			(xy 255.295339 -394.194265) (xy 255.356645 -394.135813) (xy 255.423229 -394.083453) (xy 255.494489 -394.03766)
			(xy 255.56978 -393.998849) (xy 255.648419 -393.96737) (xy 255.729694 -393.943509) (xy 255.812869 -393.927482)
			(xy 255.897191 -393.919434) (xy 255.939544 -393.918948) (xy 255.980768 -393.919399) (xy 256.062862 -393.927038)
			(xy 256.143897 -393.942237) (xy 256.223179 -393.964866) (xy 256.300029 -393.994731) (xy 256.373786 -394.031576)
			(xy 256.44382 -394.075085) (xy 256.509529 -394.124885) (xy 256.540254 -394.152374) (xy 256.547486 -394.158461)
			(xy 256.565099 -394.165287) (xy 256.583989 -394.165287) (xy 256.601602 -394.158461) (xy 256.608834 -394.152374)
			(xy 256.639555 -394.12488) (xy 256.70526 -394.075073) (xy 256.775292 -394.031559) (xy 256.849049 -393.994713)
			(xy 256.925901 -393.96485) (xy 257.005185 -393.942227) (xy 257.086223 -393.927037) (xy 257.168319 -393.919412)
			(xy 257.209544 -393.918948) (xy 257.250365 -393.919407) (xy 257.331665 -393.926876) (xy 257.411938 -393.941765)
			(xy 257.490509 -393.963948) (xy 257.566715 -393.993239) (xy 257.639917 -394.029392) (xy 257.709496 -394.072102)
			(xy 257.774868 -394.121009) (xy 257.835483 -394.175702) (xy 257.890829 -394.235721) (xy 257.940442 -394.300559)
			(xy 257.983902 -394.369672) (xy 258.002786 -394.405866) (xy 258.01873 -394.403337) (xy 258.050905 -394.400664)
			(xy 258.067048 -394.400532) (xy 258.094337 -394.400926) (xy 258.148358 -394.408699) (xy 258.200723 -394.424081)
			(xy 258.250366 -394.446758) (xy 258.296278 -394.476268) (xy 258.337522 -394.512012) (xy 258.37326 -394.553261)
			(xy 258.402765 -394.599176) (xy 258.425436 -394.648822) (xy 258.440811 -394.701189) (xy 258.448577 -394.755211)
			(xy 258.448577 -394.8085) (xy 260.984428 -394.8085) (xy 260.988458 -394.723893) (xy 261.000513 -394.640052)
			(xy 261.020483 -394.557736) (xy 261.048186 -394.477692) (xy 261.083374 -394.400643) (xy 261.125725 -394.327288)
			(xy 261.174858 -394.258291) (xy 261.230327 -394.194277) (xy 261.29163 -394.135826) (xy 261.358212 -394.083466)
			(xy 261.429469 -394.037672) (xy 261.504756 -393.99886) (xy 261.583392 -393.967379) (xy 261.664664 -393.943516)
			(xy 261.747837 -393.927487) (xy 261.832156 -393.919436) (xy 261.874508 -393.918948) (xy 261.915732 -393.919422)
			(xy 261.997825 -393.927057) (xy 262.078859 -393.942253) (xy 262.158141 -393.964879) (xy 262.234991 -393.994741)
			(xy 262.308749 -394.031583) (xy 262.378783 -394.075089) (xy 262.444493 -394.124886) (xy 262.475218 -394.152374)
			(xy 262.48245 -394.158461) (xy 262.500063 -394.165287) (xy 262.518953 -394.165287) (xy 262.536566 -394.158461)
			(xy 262.543798 -394.152374) (xy 262.574534 -394.124897) (xy 262.640236 -394.075089) (xy 262.710266 -394.031574)
			(xy 262.784021 -393.994725) (xy 262.86087 -393.96486) (xy 262.940153 -393.942234) (xy 263.021189 -393.927042)
			(xy 263.103284 -393.919413) (xy 263.144508 -393.918948) (xy 263.185239 -393.919443) (xy 263.26636 -393.9269)
			(xy 263.346458 -393.941743) (xy 263.424865 -393.963847) (xy 263.500922 -393.993026) (xy 263.573993 -394.029037)
			(xy 263.643465 -394.071577) (xy 263.708758 -394.120291) (xy 263.769323 -394.174771) (xy 263.824654 -394.234559)
			(xy 263.874287 -394.299155) (xy 263.917806 -394.368019) (xy 263.936734 -394.404088) (xy 263.947933 -394.402872)
			(xy 263.970427 -394.401601) (xy 263.981692 -394.401548) (xy 264.008912 -394.401914) (xy 264.062799 -394.409661)
			(xy 264.115035 -394.424998) (xy 264.164556 -394.447612) (xy 264.210355 -394.477045) (xy 264.251499 -394.512695)
			(xy 264.287151 -394.553838) (xy 264.316584 -394.599637) (xy 264.3392 -394.649158) (xy 264.354537 -394.701393)
			(xy 264.362285 -394.75528) (xy 264.362285 -394.8085) (xy 266.919443 -394.8085) (xy 266.923474 -394.723896)
			(xy 266.935527 -394.640059) (xy 266.955496 -394.557747) (xy 266.983198 -394.477706) (xy 267.018382 -394.40066)
			(xy 267.060731 -394.327308) (xy 267.109861 -394.258313) (xy 267.165326 -394.194301) (xy 267.226625 -394.13585)
			(xy 267.293203 -394.083491) (xy 267.364456 -394.037698) (xy 267.439739 -393.998885) (xy 267.51837 -393.967403)
			(xy 267.599638 -393.943538) (xy 267.682807 -393.927507) (xy 267.767122 -393.919453) (xy 267.809472 -393.918948)
			(xy 267.850695 -393.919444) (xy 267.932787 -393.927077) (xy 268.013822 -393.942269) (xy 268.093103 -393.964892)
			(xy 268.169953 -393.994751) (xy 268.243711 -394.03159) (xy 268.313746 -394.075093) (xy 268.379456 -394.124888)
			(xy 268.410182 -394.152374) (xy 268.417414 -394.158461) (xy 268.435027 -394.165287) (xy 268.453917 -394.165287)
			(xy 268.47153 -394.158461) (xy 268.478762 -394.152374) (xy 268.509471 -394.124866) (xy 268.575178 -394.07506)
			(xy 268.645212 -394.031548) (xy 268.718971 -393.994703) (xy 268.795824 -393.964842) (xy 268.87511 -393.942221)
			(xy 268.95615 -393.927033) (xy 269.038247 -393.91941) (xy 269.079472 -393.918948) (xy 269.120039 -393.919454)
			(xy 269.200835 -393.92684) (xy 269.280624 -393.941554) (xy 269.35874 -393.963472) (xy 269.434536 -393.992414)
			(xy 269.507381 -394.028138) (xy 269.576671 -394.070348) (xy 269.641828 -394.118693) (xy 269.702312 -394.17277)
			(xy 269.757619 -394.232131) (xy 269.807291 -394.296282) (xy 269.850914 -394.36469) (xy 269.86992 -394.400532)
			(xy 269.897015 -394.401316) (xy 269.95059 -394.409555) (xy 270.002462 -394.425283) (xy 270.051591 -394.448184)
			(xy 270.096989 -394.477799) (xy 270.137747 -394.513533) (xy 270.173045 -394.554669) (xy 270.202175 -394.60038)
			(xy 270.224552 -394.64975) (xy 270.239727 -394.701787) (xy 270.247395 -394.755446) (xy 270.247872 -394.782548)
			(xy 270.24739 -394.8085) (xy 272.854328 -394.8085) (xy 272.858359 -394.723891) (xy 272.870414 -394.640048)
			(xy 272.890384 -394.557731) (xy 272.918089 -394.477686) (xy 272.953277 -394.400636) (xy 272.995631 -394.32728)
			(xy 273.044766 -394.258282) (xy 273.100237 -394.194267) (xy 273.161542 -394.135816) (xy 273.228125 -394.083456)
			(xy 273.299385 -394.037663) (xy 273.374675 -393.998851) (xy 273.453313 -393.967372) (xy 273.534587 -393.943511)
			(xy 273.617762 -393.927483) (xy 273.702084 -393.919434) (xy 273.744436 -393.918948) (xy 273.78566 -393.919404)
			(xy 273.867754 -393.927042) (xy 273.948789 -393.942241) (xy 274.028071 -393.964869) (xy 274.10492 -393.994734)
			(xy 274.178678 -394.031578) (xy 274.248712 -394.075086) (xy 274.314421 -394.124886) (xy 274.345146 -394.152374)
			(xy 274.352378 -394.158461) (xy 274.369991 -394.165287) (xy 274.388881 -394.165287) (xy 274.406494 -394.158461)
			(xy 274.413726 -394.152374) (xy 274.44445 -394.124884) (xy 274.510154 -394.075076) (xy 274.580186 -394.031562)
			(xy 274.653943 -393.994716) (xy 274.730794 -393.964852) (xy 274.810078 -393.942228) (xy 274.891116 -393.927038)
			(xy 274.973211 -393.919412) (xy 275.014436 -393.918948) (xy 275.055004 -393.9194) (xy 275.135802 -393.926792)
			(xy 275.215592 -393.941511) (xy 275.293709 -393.963435) (xy 275.369506 -393.992382) (xy 275.442351 -394.028112)
			(xy 275.51164 -394.070326) (xy 275.576797 -394.118675) (xy 275.63728 -394.172757) (xy 275.692586 -394.232122)
			(xy 275.742257 -394.296277) (xy 275.785879 -394.364688) (xy 275.804884 -394.400532) (xy 275.831978 -394.401349)
			(xy 275.885551 -394.409583) (xy 275.937423 -394.425306) (xy 275.986552 -394.448204) (xy 276.031951 -394.477815)
			(xy 276.072709 -394.513546) (xy 276.108007 -394.554678) (xy 276.137138 -394.600387) (xy 276.159515 -394.649755)
			(xy 276.174691 -394.70179) (xy 276.182359 -394.755447) (xy 276.182836 -394.782548) (xy 276.182385 -394.808456)
			(xy 278.916892 -394.808456) (xy 278.917356 -394.766262) (xy 278.925335 -394.682252) (xy 278.941234 -394.599376)
			(xy 278.964912 -394.518378) (xy 278.996156 -394.439987) (xy 279.034684 -394.364908) (xy 279.08015 -394.293815)
			(xy 279.132146 -394.227349) (xy 279.190203 -394.166106) (xy 279.2538 -394.110638) (xy 279.322365 -394.061443)
			(xy 279.395282 -394.018964) (xy 279.471894 -393.983582) (xy 279.551513 -393.955615) (xy 279.633423 -393.935316)
			(xy 279.675082 -393.9286) (xy 279.689459 -393.925944) (xy 279.715949 -393.913606) (xy 279.737852 -393.894262)
			(xy 279.753368 -393.869499) (xy 279.761223 -393.841352) (xy 279.760772 -393.812133) (xy 279.75687 -393.798044)
			(xy 279.744165 -393.755179) (xy 279.726399 -393.667554) (xy 279.717507 -393.578589) (xy 279.716992 -393.533884)
			(xy 279.717496 -393.491536) (xy 279.725547 -393.407222) (xy 279.741576 -393.324056) (xy 279.765437 -393.242789)
			(xy 279.796916 -393.164159) (xy 279.835727 -393.088878) (xy 279.881517 -393.017626) (xy 279.933873 -392.95105)
			(xy 279.992321 -392.889752) (xy 280.056331 -392.834287) (xy 280.125323 -392.785158) (xy 280.198673 -392.742809)
			(xy 280.275716 -392.707625) (xy 280.355755 -392.679923) (xy 280.438064 -392.659955) (xy 280.521899 -392.647902)
			(xy 280.6065 -392.643872) (xy 280.691101 -392.647902) (xy 280.774936 -392.659955) (xy 280.857245 -392.679923)
			(xy 280.937284 -392.707625) (xy 281.014327 -392.742809) (xy 281.087677 -392.785158) (xy 281.156669 -392.834287)
			(xy 281.220679 -392.889752) (xy 281.279127 -392.95105) (xy 281.331483 -393.017626) (xy 281.377273 -393.088878)
			(xy 281.416084 -393.164159) (xy 281.447563 -393.242789) (xy 281.471424 -393.324056) (xy 281.487453 -393.407222)
			(xy 281.495504 -393.491536) (xy 281.496008 -393.533884) (xy 281.495487 -393.576077) (xy 281.487514 -393.660085)
			(xy 281.47162 -393.74296) (xy 281.461756 -393.776708) (xy 289.471608 -393.776708) (xy 289.471608 -393.776454)
			(xy 289.47211 -393.744493) (xy 289.480121 -393.681075) (xy 289.496018 -393.619161) (xy 289.51955 -393.559728)
			(xy 289.550344 -393.503713) (xy 289.587917 -393.451998) (xy 289.631674 -393.405401) (xy 289.680927 -393.364656)
			(xy 289.734898 -393.330405) (xy 289.792737 -393.303188) (xy 289.85353 -393.283435) (xy 289.91632 -393.271457)
			(xy 289.980116 -393.267444) (xy 290.043912 -393.271457) (xy 290.106702 -393.283435) (xy 290.167495 -393.303188)
			(xy 290.225334 -393.330405) (xy 290.279305 -393.364656) (xy 290.328558 -393.405401) (xy 290.372315 -393.451998)
			(xy 290.409888 -393.503713) (xy 290.440682 -393.559728) (xy 290.464214 -393.619161) (xy 290.480111 -393.681075)
			(xy 290.488122 -393.744493) (xy 290.488624 -393.776454) (xy 290.488624 -393.7765) (xy 291.470768 -393.7765)
			(xy 291.474784 -393.712663) (xy 291.48677 -393.649832) (xy 291.506536 -393.589) (xy 291.533771 -393.531124)
			(xy 291.568045 -393.477118) (xy 291.608817 -393.427834) (xy 291.655445 -393.384049) (xy 291.707193 -393.346453)
			(xy 291.763245 -393.315639) (xy 291.822717 -393.292094) (xy 291.884671 -393.276188) (xy 291.94813 -393.268172)
			(xy 291.980112 -393.267692) (xy 292.010658 -393.268138) (xy 292.071311 -393.275449) (xy 292.13065 -393.289975)
			(xy 292.187822 -393.311508) (xy 292.242001 -393.339737) (xy 292.292406 -393.374254) (xy 292.338312 -393.414564)
			(xy 292.379057 -393.460084) (xy 292.396926 -393.484862) (xy 292.405296 -393.496027) (xy 292.426903 -393.51367)
			(xy 292.452477 -393.52481) (xy 292.480111 -393.528618) (xy 292.507745 -393.52481) (xy 292.533319 -393.51367)
			(xy 292.554926 -393.496027) (xy 292.563296 -393.484862) (xy 292.582389 -393.458454) (xy 292.626241 -393.410247)
			(xy 292.675892 -393.368039) (xy 292.730528 -393.332518) (xy 292.789254 -393.304269) (xy 292.851108 -393.283754)
			(xy 292.915076 -393.271309) (xy 292.98011 -393.267138) (xy 293.045144 -393.271309) (xy 293.109112 -393.283754)
			(xy 293.170966 -393.304269) (xy 293.229692 -393.332518) (xy 293.284328 -393.368039) (xy 293.333979 -393.410247)
			(xy 293.377831 -393.458454) (xy 293.396924 -393.484862) (xy 293.405294 -393.496027) (xy 293.426901 -393.51367)
			(xy 293.452475 -393.52481) (xy 293.480109 -393.528618) (xy 293.507743 -393.52481) (xy 293.533317 -393.51367)
			(xy 293.554924 -393.496027) (xy 293.563294 -393.484862) (xy 293.582387 -393.458454) (xy 293.626239 -393.410247)
			(xy 293.67589 -393.368039) (xy 293.730526 -393.332518) (xy 293.789252 -393.304269) (xy 293.851106 -393.283754)
			(xy 293.915074 -393.271309) (xy 293.980108 -393.267138) (xy 294.045142 -393.271309) (xy 294.10911 -393.283754)
			(xy 294.170964 -393.304269) (xy 294.22969 -393.332518) (xy 294.284326 -393.368039) (xy 294.333977 -393.410247)
			(xy 294.377829 -393.458454) (xy 294.396922 -393.484862) (xy 294.405292 -393.496027) (xy 294.426899 -393.51367)
			(xy 294.452473 -393.52481) (xy 294.480107 -393.528618) (xy 294.507741 -393.52481) (xy 294.533315 -393.51367)
			(xy 294.554922 -393.496027) (xy 294.563292 -393.484862) (xy 294.582385 -393.458454) (xy 294.626237 -393.410247)
			(xy 294.675888 -393.368039) (xy 294.730524 -393.332518) (xy 294.78925 -393.304269) (xy 294.851104 -393.283754)
			(xy 294.915072 -393.271309) (xy 294.980106 -393.267138) (xy 295.04514 -393.271309) (xy 295.109108 -393.283754)
			(xy 295.170962 -393.304269) (xy 295.229688 -393.332518) (xy 295.284324 -393.368039) (xy 295.333975 -393.410247)
			(xy 295.377827 -393.458454) (xy 295.39692 -393.484862) (xy 295.40529 -393.496027) (xy 295.426897 -393.51367)
			(xy 295.452471 -393.52481) (xy 295.480105 -393.528618) (xy 295.507739 -393.52481) (xy 295.533313 -393.51367)
			(xy 295.55492 -393.496027) (xy 295.56329 -393.484862) (xy 295.582383 -393.458454) (xy 295.626235 -393.410247)
			(xy 295.675886 -393.368039) (xy 295.730522 -393.332518) (xy 295.789248 -393.304269) (xy 295.851102 -393.283754)
			(xy 295.91507 -393.271309) (xy 295.980104 -393.267138) (xy 296.045138 -393.271309) (xy 296.109106 -393.283754)
			(xy 296.17096 -393.304269) (xy 296.229686 -393.332518) (xy 296.284322 -393.368039) (xy 296.333973 -393.410247)
			(xy 296.377825 -393.458454) (xy 296.396918 -393.484862) (xy 296.405288 -393.496027) (xy 296.426895 -393.51367)
			(xy 296.452469 -393.52481) (xy 296.480103 -393.528618) (xy 296.507737 -393.52481) (xy 296.533311 -393.51367)
			(xy 296.554918 -393.496027) (xy 296.563288 -393.484862) (xy 296.581151 -393.46008) (xy 296.621903 -393.414568)
			(xy 296.667813 -393.374265) (xy 296.71822 -393.339752) (xy 296.772399 -393.311525) (xy 296.829568 -393.289992)
			(xy 296.888906 -393.275462) (xy 296.949557 -393.268144) (xy 296.980102 -393.267692) (xy 297.012076 -393.268286)
			(xy 297.07552 -393.276301) (xy 297.137459 -393.292204) (xy 297.196916 -393.315745) (xy 297.252954 -393.346553)
			(xy 297.304689 -393.384141) (xy 297.351305 -393.427916) (xy 297.392067 -393.477189) (xy 297.426332 -393.531182)
			(xy 297.45356 -393.589044) (xy 297.473321 -393.649863) (xy 297.485304 -393.712678) (xy 297.489319 -393.7765)
			(xy 297.485304 -393.840322) (xy 297.473321 -393.903137) (xy 297.45356 -393.963956) (xy 297.426332 -394.021818)
			(xy 297.392067 -394.075811) (xy 297.351305 -394.125084) (xy 297.304689 -394.168859) (xy 297.252954 -394.206447)
			(xy 297.196916 -394.237255) (xy 297.137459 -394.260796) (xy 297.07552 -394.276699) (xy 297.012076 -394.284714)
			(xy 296.980102 -394.285216) (xy 296.949556 -394.284756) (xy 296.888904 -394.277447) (xy 296.829565 -394.262922)
			(xy 296.772394 -394.241392) (xy 296.718215 -394.213165) (xy 296.667809 -394.178649) (xy 296.621903 -394.138341)
			(xy 296.581158 -394.092823) (xy 296.563288 -394.068046) (xy 296.554946 -394.056837) (xy 296.53336 -394.03911)
			(xy 296.507771 -394.027912) (xy 296.480103 -394.024083) (xy 296.452435 -394.027912) (xy 296.426846 -394.03911)
			(xy 296.40526 -394.056837) (xy 296.396918 -394.068046) (xy 296.377825 -394.094454) (xy 296.333973 -394.142661)
			(xy 296.284322 -394.184869) (xy 296.229686 -394.22039) (xy 296.17096 -394.248639) (xy 296.109106 -394.269154)
			(xy 296.045138 -394.281599) (xy 295.980104 -394.28577) (xy 295.91507 -394.281599) (xy 295.851102 -394.269154)
			(xy 295.789248 -394.248639) (xy 295.730522 -394.22039) (xy 295.675886 -394.184869) (xy 295.626235 -394.142661)
			(xy 295.582383 -394.094454) (xy 295.56329 -394.068046) (xy 295.554948 -394.056837) (xy 295.533362 -394.03911)
			(xy 295.507773 -394.027912) (xy 295.480105 -394.024083) (xy 295.452437 -394.027912) (xy 295.426848 -394.03911)
			(xy 295.405262 -394.056837) (xy 295.39692 -394.068046) (xy 295.377827 -394.094454) (xy 295.333975 -394.142661)
			(xy 295.284324 -394.184869) (xy 295.229688 -394.22039) (xy 295.170962 -394.248639) (xy 295.109108 -394.269154)
			(xy 295.04514 -394.281599) (xy 294.980106 -394.28577) (xy 294.915072 -394.281599) (xy 294.851104 -394.269154)
			(xy 294.78925 -394.248639) (xy 294.730524 -394.22039) (xy 294.675888 -394.184869) (xy 294.626237 -394.142661)
			(xy 294.582385 -394.094454) (xy 294.563292 -394.068046) (xy 294.55495 -394.056837) (xy 294.533364 -394.03911)
			(xy 294.507775 -394.027912) (xy 294.480107 -394.024083) (xy 294.452439 -394.027912) (xy 294.42685 -394.03911)
			(xy 294.405264 -394.056837) (xy 294.396922 -394.068046) (xy 294.377829 -394.094454) (xy 294.333977 -394.142661)
			(xy 294.284326 -394.184869) (xy 294.22969 -394.22039) (xy 294.170964 -394.248639) (xy 294.10911 -394.269154)
			(xy 294.045142 -394.281599) (xy 293.980108 -394.28577) (xy 293.915074 -394.281599) (xy 293.851106 -394.269154)
			(xy 293.789252 -394.248639) (xy 293.730526 -394.22039) (xy 293.67589 -394.184869) (xy 293.626239 -394.142661)
			(xy 293.582387 -394.094454) (xy 293.563294 -394.068046) (xy 293.554952 -394.056837) (xy 293.533366 -394.03911)
			(xy 293.507777 -394.027912) (xy 293.480109 -394.024083) (xy 293.452441 -394.027912) (xy 293.426852 -394.03911)
			(xy 293.405266 -394.056837) (xy 293.396924 -394.068046) (xy 293.377831 -394.094454) (xy 293.333979 -394.142661)
			(xy 293.284328 -394.184869) (xy 293.229692 -394.22039) (xy 293.170966 -394.248639) (xy 293.109112 -394.269154)
			(xy 293.045144 -394.281599) (xy 292.98011 -394.28577) (xy 292.915076 -394.281599) (xy 292.851108 -394.269154)
			(xy 292.789254 -394.248639) (xy 292.730528 -394.22039) (xy 292.675892 -394.184869) (xy 292.626241 -394.142661)
			(xy 292.582389 -394.094454) (xy 292.563296 -394.068046) (xy 292.554954 -394.056837) (xy 292.533368 -394.03911)
			(xy 292.507779 -394.027912) (xy 292.480111 -394.024083) (xy 292.452443 -394.027912) (xy 292.426854 -394.03911)
			(xy 292.405268 -394.056837) (xy 292.396926 -394.068046) (xy 292.379057 -394.092823) (xy 292.338306 -394.138335)
			(xy 292.292396 -394.178638) (xy 292.24199 -394.213151) (xy 292.187812 -394.241378) (xy 292.130644 -394.262913)
			(xy 292.071307 -394.277444) (xy 292.010657 -394.284763) (xy 291.980112 -394.285216) (xy 291.94813 -394.284828)
			(xy 291.884671 -394.276812) (xy 291.822717 -394.260906) (xy 291.763245 -394.237361) (xy 291.707193 -394.206547)
			(xy 291.655445 -394.168951) (xy 291.608817 -394.125166) (xy 291.568045 -394.075882) (xy 291.533771 -394.021876)
			(xy 291.506536 -393.964) (xy 291.48677 -393.903168) (xy 291.474784 -393.840337) (xy 291.470768 -393.7765)
			(xy 290.488624 -393.7765) (xy 290.488624 -393.776962) (xy 290.488202 -393.806564) (xy 290.481324 -393.865367)
			(xy 290.467658 -393.922971) (xy 290.447389 -393.978597) (xy 290.420792 -394.03149) (xy 290.388226 -394.080932)
			(xy 290.369498 -394.10386) (xy 290.389588 -394.127178) (xy 290.424612 -394.17779) (xy 290.453267 -394.232263)
			(xy 290.475133 -394.289797) (xy 290.48989 -394.349552) (xy 290.497321 -394.410651) (xy 290.497768 -394.441426)
			(xy 290.497768 -394.44168) (xy 290.497266 -394.473641) (xy 290.489255 -394.537059) (xy 290.473358 -394.598973)
			(xy 290.449826 -394.658406) (xy 290.419032 -394.714421) (xy 290.381459 -394.766136) (xy 290.337702 -394.812733)
			(xy 290.288449 -394.853478) (xy 290.234478 -394.887729) (xy 290.176639 -394.914946) (xy 290.115846 -394.934699)
			(xy 290.053056 -394.946677) (xy 289.98926 -394.950691) (xy 289.925464 -394.946677) (xy 289.862674 -394.934699)
			(xy 289.801881 -394.914946) (xy 289.744042 -394.887729) (xy 289.690071 -394.853478) (xy 289.640818 -394.812733)
			(xy 289.597061 -394.766136) (xy 289.559488 -394.714421) (xy 289.528694 -394.658406) (xy 289.505162 -394.598973)
			(xy 289.489265 -394.537059) (xy 289.481254 -394.473641) (xy 289.480752 -394.44168) (xy 289.480752 -394.441172)
			(xy 289.481141 -394.411569) (xy 289.488026 -394.352765) (xy 289.501699 -394.29516) (xy 289.521974 -394.239535)
			(xy 289.548577 -394.186643) (xy 289.581148 -394.137202) (xy 289.599878 -394.114274) (xy 289.579769 -394.090972)
			(xy 289.544745 -394.040357) (xy 289.516091 -393.985882) (xy 289.494228 -393.928344) (xy 289.479476 -393.868586)
			(xy 289.472051 -393.807484) (xy 289.471608 -393.776708) (xy 281.461756 -393.776708) (xy 281.447947 -393.823957)
			(xy 281.416708 -393.902348) (xy 281.378185 -393.977427) (xy 281.332723 -394.04852) (xy 281.280732 -394.114986)
			(xy 281.222678 -394.176229) (xy 281.159084 -394.231698) (xy 281.090523 -394.280894) (xy 281.017609 -394.323374)
			(xy 280.941 -394.358757) (xy 280.861383 -394.386724) (xy 280.779476 -394.407024) (xy 280.737818 -394.41374)
			(xy 280.72343 -394.416347) (xy 280.696933 -394.428691) (xy 280.675026 -394.448046) (xy 280.659511 -394.472819)
			(xy 280.651661 -394.500977) (xy 280.652122 -394.530204) (xy 280.65603 -394.544296) (xy 280.668744 -394.587158)
			(xy 280.686507 -394.674785) (xy 280.695395 -394.763751) (xy 280.695908 -394.808456) (xy 280.695404 -394.850804)
			(xy 280.687353 -394.935118) (xy 280.671324 -395.018284) (xy 280.647463 -395.099551) (xy 280.615984 -395.178181)
			(xy 280.577173 -395.253462) (xy 280.531383 -395.324714) (xy 280.479027 -395.39129) (xy 280.420579 -395.452588)
			(xy 280.356569 -395.508053) (xy 280.287577 -395.557182) (xy 280.214227 -395.599531) (xy 280.137184 -395.634715)
			(xy 280.057145 -395.662417) (xy 279.974836 -395.682385) (xy 279.891001 -395.694438) (xy 279.8064 -395.698469)
			(xy 279.721799 -395.694438) (xy 279.637964 -395.682385) (xy 279.555655 -395.662417) (xy 279.475616 -395.634715)
			(xy 279.398573 -395.599531) (xy 279.325223 -395.557182) (xy 279.256231 -395.508053) (xy 279.192221 -395.452588)
			(xy 279.133773 -395.39129) (xy 279.081417 -395.324714) (xy 279.035627 -395.253462) (xy 278.996816 -395.178181)
			(xy 278.965337 -395.099551) (xy 278.941476 -395.018284) (xy 278.925447 -394.935118) (xy 278.917396 -394.850804)
			(xy 278.916892 -394.808456) (xy 276.182385 -394.808456) (xy 276.182339 -394.81111) (xy 276.173854 -394.867601)
			(xy 276.157051 -394.922198) (xy 276.132304 -394.973684) (xy 276.100165 -395.02091) (xy 276.061351 -395.062822)
			(xy 276.016728 -395.098487) (xy 275.967291 -395.127109) (xy 275.914142 -395.148048) (xy 275.858468 -395.160839)
			(xy 275.83003 -395.163548) (xy 275.812369 -395.202766) (xy 275.770577 -395.277947) (xy 275.721724 -395.348744)
			(xy 275.666266 -395.414494) (xy 275.60472 -395.474584) (xy 275.537661 -395.528453) (xy 275.465716 -395.575598)
			(xy 275.389556 -395.615578) (xy 275.309893 -395.648021) (xy 275.22747 -395.672622) (xy 275.143058 -395.689153)
			(xy 275.057444 -395.697459) (xy 275.014436 -395.697964) (xy 274.973213 -395.69746) (xy 274.891121 -395.689828)
			(xy 274.810087 -395.674636) (xy 274.730806 -395.652015) (xy 274.653956 -395.622157) (xy 274.580198 -395.585319)
			(xy 274.510163 -395.541817) (xy 274.444452 -395.492024) (xy 274.413726 -395.464538) (xy 274.406494 -395.458451)
			(xy 274.388881 -395.451625) (xy 274.369991 -395.451625) (xy 274.352378 -395.458451) (xy 274.345146 -395.464538)
			(xy 274.314435 -395.492044) (xy 274.248729 -395.54185) (xy 274.178695 -395.585362) (xy 274.104936 -395.622207)
			(xy 274.028083 -395.652068) (xy 273.948797 -395.67469) (xy 273.867758 -395.689878) (xy 273.785661 -395.697501)
			(xy 273.744436 -395.697964) (xy 273.702084 -395.697566) (xy 273.617762 -395.689517) (xy 273.534587 -395.673489)
			(xy 273.453313 -395.649628) (xy 273.374675 -395.618149) (xy 273.299385 -395.579337) (xy 273.228125 -395.533544)
			(xy 273.161542 -395.481184) (xy 273.100237 -395.422733) (xy 273.044766 -395.358718) (xy 272.995631 -395.28972)
			(xy 272.953277 -395.216364) (xy 272.918089 -395.139314) (xy 272.890384 -395.059269) (xy 272.870414 -394.976952)
			(xy 272.858359 -394.893109) (xy 272.854328 -394.8085) (xy 270.24739 -394.8085) (xy 270.247342 -394.811109)
			(xy 270.238858 -394.867596) (xy 270.222057 -394.922191) (xy 270.197312 -394.973674) (xy 270.165177 -395.020899)
			(xy 270.126367 -395.062811) (xy 270.081748 -395.098476) (xy 270.032316 -395.127099) (xy 269.979172 -395.148042)
			(xy 269.923503 -395.160836) (xy 269.895066 -395.163548) (xy 269.877376 -395.202752) (xy 269.835586 -395.277933)
			(xy 269.786736 -395.348729) (xy 269.73128 -395.414479) (xy 269.669737 -395.474569) (xy 269.602681 -395.528439)
			(xy 269.530739 -395.575585) (xy 269.454582 -395.615566) (xy 269.374921 -395.648011) (xy 269.292501 -395.672615)
			(xy 269.208091 -395.689148) (xy 269.122479 -395.697457) (xy 269.079472 -395.697964) (xy 269.038248 -395.6975)
			(xy 268.956155 -395.689862) (xy 268.87512 -395.674665) (xy 268.795838 -395.652037) (xy 268.718989 -395.622174)
			(xy 268.645231 -395.585331) (xy 268.575197 -395.541824) (xy 268.509487 -395.492026) (xy 268.478762 -395.464538)
			(xy 268.47153 -395.458451) (xy 268.453917 -395.451625) (xy 268.435027 -395.451625) (xy 268.417414 -395.458451)
			(xy 268.410182 -395.464538) (xy 268.379456 -395.492026) (xy 268.313752 -395.541834) (xy 268.243721 -395.585348)
			(xy 268.169964 -395.622194) (xy 268.093113 -395.652058) (xy 268.013829 -395.674682) (xy 267.932792 -395.689873)
			(xy 267.850696 -395.6975) (xy 267.809472 -395.697964) (xy 267.767122 -395.697547) (xy 267.682807 -395.689493)
			(xy 267.599638 -395.673462) (xy 267.51837 -395.649597) (xy 267.439739 -395.618115) (xy 267.364456 -395.579302)
			(xy 267.293203 -395.533509) (xy 267.226625 -395.48115) (xy 267.165326 -395.422699) (xy 267.109861 -395.358687)
			(xy 267.060731 -395.289692) (xy 267.018382 -395.21634) (xy 266.983198 -395.139294) (xy 266.955496 -395.059253)
			(xy 266.935527 -394.976941) (xy 266.923474 -394.893104) (xy 266.919443 -394.8085) (xy 264.362285 -394.8085)
			(xy 264.362285 -394.80972) (xy 264.354537 -394.863607) (xy 264.3392 -394.915842) (xy 264.316584 -394.965363)
			(xy 264.287151 -395.011162) (xy 264.251499 -395.052305) (xy 264.210355 -395.087955) (xy 264.164556 -395.117388)
			(xy 264.115035 -395.140002) (xy 264.062799 -395.155339) (xy 264.008912 -395.163086) (xy 263.981692 -395.163548)
			(xy 263.960356 -395.16304) (xy 263.942674 -395.202274) (xy 263.9009 -395.277517) (xy 263.852055 -395.348375)
			(xy 263.796597 -395.414185) (xy 263.735042 -395.474332) (xy 263.667968 -395.528254) (xy 263.596 -395.575447)
			(xy 263.519811 -395.61547) (xy 263.440113 -395.647949) (xy 263.357652 -395.67258) (xy 263.273197 -395.689134)
			(xy 263.187539 -395.697455) (xy 263.144508 -395.697964) (xy 263.103285 -395.697477) (xy 263.021192 -395.689843)
			(xy 262.940158 -395.674649) (xy 262.860876 -395.652025) (xy 262.784027 -395.622164) (xy 262.710269 -395.585324)
			(xy 262.640234 -395.54182) (xy 262.574524 -395.492025) (xy 262.543798 -395.464538) (xy 262.536566 -395.458451)
			(xy 262.518953 -395.451625) (xy 262.500063 -395.451625) (xy 262.48245 -395.458451) (xy 262.475218 -395.464538)
			(xy 262.444477 -395.492009) (xy 262.378775 -395.541818) (xy 262.308747 -395.585333) (xy 262.234992 -395.622182)
			(xy 262.158144 -395.652048) (xy 262.078861 -395.674675) (xy 261.997826 -395.689868) (xy 261.915732 -395.697498)
			(xy 261.874508 -395.697964) (xy 261.832156 -395.697564) (xy 261.747837 -395.689513) (xy 261.664664 -395.673484)
			(xy 261.583392 -395.649621) (xy 261.504756 -395.61814) (xy 261.429469 -395.579328) (xy 261.358212 -395.533534)
			(xy 261.29163 -395.481174) (xy 261.230327 -395.422723) (xy 261.174858 -395.358709) (xy 261.125725 -395.289712)
			(xy 261.083374 -395.216357) (xy 261.048186 -395.139308) (xy 261.020483 -395.059264) (xy 261.000513 -394.976948)
			(xy 260.988458 -394.893107) (xy 260.984428 -394.8085) (xy 258.448577 -394.8085) (xy 258.448577 -394.809789)
			(xy 258.440811 -394.863811) (xy 258.425436 -394.916178) (xy 258.402765 -394.965824) (xy 258.37326 -395.011739)
			(xy 258.337522 -395.052988) (xy 258.296278 -395.088732) (xy 258.250366 -395.118242) (xy 258.200723 -395.140919)
			(xy 258.148358 -395.156301) (xy 258.094337 -395.164074) (xy 258.067048 -395.164564) (xy 258.056676 -395.164479)
			(xy 258.035964 -395.163337) (xy 258.025646 -395.162278) (xy 258.008 -395.201564) (xy 257.966267 -395.276906)
			(xy 257.917448 -395.347861) (xy 257.861999 -395.413765) (xy 257.80044 -395.474001) (xy 257.733346 -395.528004)
			(xy 257.661347 -395.575269) (xy 257.585116 -395.615354) (xy 257.505368 -395.647883) (xy 257.422848 -395.672551)
			(xy 257.338331 -395.689127) (xy 257.252608 -395.697456) (xy 257.209544 -395.697964) (xy 257.168321 -395.697455)
			(xy 257.08623 -395.689824) (xy 257.005196 -395.674633) (xy 256.925914 -395.652012) (xy 256.849065 -395.622155)
			(xy 256.775306 -395.585317) (xy 256.705271 -395.541816) (xy 256.63956 -395.492023) (xy 256.608834 -395.464538)
			(xy 256.601602 -395.458451) (xy 256.583989 -395.451625) (xy 256.565099 -395.451625) (xy 256.547486 -395.458451)
			(xy 256.540254 -395.464538) (xy 256.50954 -395.49204) (xy 256.443834 -395.541846) (xy 256.373801 -395.585359)
			(xy 256.300042 -395.622204) (xy 256.22319 -395.652066) (xy 256.143904 -395.674688) (xy 256.062865 -395.689877)
			(xy 255.980769 -395.697501) (xy 255.939544 -395.697964) (xy 255.897191 -395.697566) (xy 255.812869 -395.689518)
			(xy 255.729694 -395.673491) (xy 255.648419 -395.64963) (xy 255.56978 -395.618151) (xy 255.494489 -395.57934)
			(xy 255.423229 -395.533547) (xy 255.356645 -395.481187) (xy 255.295339 -395.422735) (xy 255.239868 -395.358721)
			(xy 255.190732 -395.289723) (xy 255.148379 -395.216366) (xy 255.11319 -395.139316) (xy 255.085484 -395.05927)
			(xy 255.065514 -394.976952) (xy 255.053459 -394.893109) (xy 255.049428 -394.8085) (xy 252.466916 -394.8085)
			(xy 252.466897 -394.809592) (xy 252.459254 -394.863136) (xy 252.444116 -394.915061) (xy 252.421785 -394.964324)
			(xy 252.392711 -395.009932) (xy 252.357479 -395.05097) (xy 252.316797 -395.086613) (xy 252.271483 -395.116143)
			(xy 252.222447 -395.138967) (xy 252.170677 -395.154627) (xy 252.117212 -395.162807) (xy 252.090174 -395.163548)
			(xy 252.072477 -395.202749) (xy 252.030688 -395.27793) (xy 251.981838 -395.348725) (xy 251.926383 -395.414475)
			(xy 251.864841 -395.474566) (xy 251.797785 -395.528436) (xy 251.725844 -395.575582) (xy 251.649687 -395.615564)
			(xy 251.570027 -395.648009) (xy 251.487608 -395.672613) (xy 251.403198 -395.689147) (xy 251.317587 -395.697457)
			(xy 251.27458 -395.697964) (xy 251.233356 -395.697495) (xy 251.151263 -395.689858) (xy 251.070228 -395.674661)
			(xy 250.990947 -395.652035) (xy 250.914097 -395.622172) (xy 250.840339 -395.58533) (xy 250.770305 -395.541823)
			(xy 250.704595 -395.492026) (xy 250.67387 -395.464538) (xy 250.666638 -395.458451) (xy 250.649025 -395.451625)
			(xy 250.630135 -395.451625) (xy 250.612522 -395.458451) (xy 250.60529 -395.464538) (xy 250.574561 -395.492023)
			(xy 250.508857 -395.54183) (xy 250.438827 -395.585344) (xy 250.36507 -395.622192) (xy 250.28822 -395.652056)
			(xy 250.208936 -395.67468) (xy 250.127899 -395.689872) (xy 250.045804 -395.697499) (xy 250.00458 -395.697964)
			(xy 249.96223 -395.697547) (xy 249.877914 -395.689494) (xy 249.794745 -395.673463) (xy 249.713476 -395.649599)
			(xy 249.634844 -395.618118) (xy 249.55956 -395.579305) (xy 249.488307 -395.533512) (xy 249.421729 -395.481153)
			(xy 249.360429 -395.422702) (xy 249.304963 -395.35869) (xy 249.255833 -395.289695) (xy 249.213483 -395.216342)
			(xy 249.178298 -395.139296) (xy 249.150596 -395.059254) (xy 249.130628 -394.976942) (xy 249.118574 -394.893104)
			(xy 249.114543 -394.8085) (xy 246.507582 -394.8085) (xy 246.507538 -394.811111) (xy 246.499052 -394.867604)
			(xy 246.482248 -394.922202) (xy 246.457499 -394.973689) (xy 246.425358 -395.020916) (xy 246.386542 -395.062829)
			(xy 246.341916 -395.098493) (xy 246.292476 -395.127114) (xy 246.239326 -395.148052) (xy 246.183649 -395.16084)
			(xy 246.15521 -395.163548) (xy 246.137565 -395.202774) (xy 246.095772 -395.277955) (xy 246.046918 -395.348752)
			(xy 245.991458 -395.414502) (xy 245.929911 -395.474592) (xy 245.86285 -395.528461) (xy 245.790904 -395.575605)
			(xy 245.714742 -395.615585) (xy 245.635078 -395.648026) (xy 245.552653 -395.672626) (xy 245.46824 -395.689156)
			(xy 245.382624 -395.69746) (xy 245.339616 -395.697964) (xy 245.298393 -395.697472) (xy 245.216301 -395.689839)
			(xy 245.135266 -395.674645) (xy 245.055985 -395.652022) (xy 244.979135 -395.622162) (xy 244.905377 -395.585323)
			(xy 244.835342 -395.541819) (xy 244.769632 -395.492024) (xy 244.738906 -395.464538) (xy 244.731674 -395.458451)
			(xy 244.714061 -395.451625) (xy 244.695171 -395.451625) (xy 244.677558 -395.458451) (xy 244.670326 -395.464538)
			(xy 244.639624 -395.492053) (xy 244.573916 -395.541859) (xy 244.503881 -395.58537) (xy 244.43012 -395.622214)
			(xy 244.353266 -395.652074) (xy 244.273979 -395.674694) (xy 244.192939 -395.68988) (xy 244.110841 -395.697502)
			(xy 244.069616 -395.697964) (xy 244.027264 -395.697565) (xy 243.942944 -395.689514) (xy 243.859771 -395.673485)
			(xy 243.778498 -395.649623) (xy 243.699861 -395.618143) (xy 243.624573 -395.57933) (xy 243.553315 -395.533537)
			(xy 243.486733 -395.481177) (xy 243.42543 -395.422726) (xy 243.36996 -395.358711) (xy 243.320827 -395.289714)
			(xy 243.278475 -395.216359) (xy 243.243287 -395.13931) (xy 243.215583 -395.059265) (xy 243.195613 -394.976949)
			(xy 243.183558 -394.893108) (xy 243.179528 -394.8085) (xy 2.509012 -394.8085) (xy 2.509012 -396.842996)
			(xy 18.90268 -396.842996) (xy 18.90268 -395.979396) (xy 18.903166 -395.952145) (xy 18.910922 -395.898197)
			(xy 18.926277 -395.845902) (xy 18.948919 -395.796325) (xy 18.978385 -395.750475) (xy 19.014076 -395.709284)
			(xy 19.055267 -395.673593) (xy 19.101117 -395.644127) (xy 19.150694 -395.621485) (xy 19.202989 -395.60613)
			(xy 19.256937 -395.598374) (xy 19.311439 -395.598374) (xy 19.365387 -395.60613) (xy 19.417682 -395.621485)
			(xy 19.467259 -395.644127) (xy 19.513109 -395.673593) (xy 19.5543 -395.709284) (xy 19.589991 -395.750475)
			(xy 19.601933 -395.769057) (xy 288.471858 -395.769057) (xy 288.471858 -395.705103) (xy 288.479873 -395.641653)
			(xy 288.495778 -395.579708) (xy 288.519321 -395.520246) (xy 288.550131 -395.464202) (xy 288.587723 -395.412462)
			(xy 288.631502 -395.365842) (xy 288.68078 -395.325076) (xy 288.734778 -395.290808) (xy 288.792645 -395.263577)
			(xy 288.853469 -395.243814) (xy 288.91629 -395.231831) (xy 288.980118 -395.227815) (xy 289.043946 -395.231831)
			(xy 289.106767 -395.243814) (xy 289.167591 -395.263577) (xy 289.225458 -395.290808) (xy 289.279456 -395.325076)
			(xy 289.328734 -395.365842) (xy 289.372513 -395.412462) (xy 289.410105 -395.464202) (xy 289.440915 -395.520246)
			(xy 289.464458 -395.579708) (xy 289.480363 -395.641653) (xy 289.488378 -395.705103) (xy 289.48888 -395.73708)
			(xy 289.488378 -395.769057) (xy 289.480363 -395.832507) (xy 289.464458 -395.894452) (xy 289.440915 -395.953914)
			(xy 289.410105 -396.009958) (xy 289.372513 -396.061698) (xy 289.328734 -396.108318) (xy 289.279456 -396.149084)
			(xy 289.225458 -396.183352) (xy 289.167591 -396.210583) (xy 289.106767 -396.230346) (xy 289.043946 -396.242329)
			(xy 288.980118 -396.246345) (xy 288.91629 -396.242329) (xy 288.853469 -396.230346) (xy 288.792645 -396.210583)
			(xy 288.734778 -396.183352) (xy 288.68078 -396.149084) (xy 288.631502 -396.108318) (xy 288.587723 -396.061698)
			(xy 288.550131 -396.009958) (xy 288.519321 -395.953914) (xy 288.495778 -395.894452) (xy 288.479873 -395.832507)
			(xy 288.471858 -395.769057) (xy 19.601933 -395.769057) (xy 19.619457 -395.796325) (xy 19.642099 -395.845902)
			(xy 19.657454 -395.898197) (xy 19.66521 -395.952145) (xy 19.665696 -395.979396) (xy 19.665696 -396.842996)
			(xy 19.66521 -396.870247) (xy 19.657454 -396.924195) (xy 19.642099 -396.97649) (xy 19.619457 -397.026067)
			(xy 19.589991 -397.071917) (xy 19.5543 -397.113108) (xy 19.513109 -397.148799) (xy 19.467259 -397.178265)
			(xy 19.417682 -397.200907) (xy 19.365387 -397.216262) (xy 19.311439 -397.224018) (xy 19.256937 -397.224018)
			(xy 19.202989 -397.216262) (xy 19.150694 -397.200907) (xy 19.101117 -397.178265) (xy 19.055267 -397.148799)
			(xy 19.014076 -397.113108) (xy 18.978385 -397.071917) (xy 18.948919 -397.026067) (xy 18.926277 -396.97649)
			(xy 18.910922 -396.924195) (xy 18.903166 -396.870247) (xy 18.90268 -396.842996) (xy 2.509012 -396.842996)
			(xy 2.509012 -397.606012) (xy 24.954992 -397.606012) (xy 24.954992 -396.742412) (xy 24.955478 -396.715161)
			(xy 24.963234 -396.661213) (xy 24.978589 -396.608918) (xy 25.001231 -396.559341) (xy 25.030697 -396.513491)
			(xy 25.066388 -396.4723) (xy 25.107579 -396.436609) (xy 25.153429 -396.407143) (xy 25.203006 -396.384501)
			(xy 25.255301 -396.369146) (xy 25.309249 -396.36139) (xy 25.363751 -396.36139) (xy 25.417699 -396.369146)
			(xy 25.469994 -396.384501) (xy 25.519571 -396.407143) (xy 25.565421 -396.436609) (xy 25.606612 -396.4723)
			(xy 25.642303 -396.513491) (xy 25.671769 -396.559341) (xy 25.694411 -396.608918) (xy 25.709766 -396.661213)
			(xy 25.717522 -396.715161) (xy 25.718008 -396.742412) (xy 25.718008 -397.606012) (xy 25.717522 -397.633263)
			(xy 25.709766 -397.687211) (xy 25.694411 -397.739506) (xy 25.671769 -397.789083) (xy 25.642303 -397.834933)
			(xy 25.606612 -397.876124) (xy 25.565421 -397.911815) (xy 25.519571 -397.941281) (xy 25.469994 -397.963923)
			(xy 25.417699 -397.979278) (xy 25.363751 -397.987034) (xy 25.309249 -397.987034) (xy 25.255301 -397.979278)
			(xy 25.203006 -397.963923) (xy 25.153429 -397.941281) (xy 25.107579 -397.911815) (xy 25.066388 -397.876124)
			(xy 25.030697 -397.834933) (xy 25.001231 -397.789083) (xy 24.978589 -397.739506) (xy 24.963234 -397.687211)
			(xy 24.955478 -397.633263) (xy 24.954992 -397.606012) (xy 2.509012 -397.606012) (xy 2.509012 -398.68657)
			(xy 36.781952 -398.68657) (xy 36.781952 -398.63203) (xy 36.789714 -398.578046) (xy 36.805081 -398.525717)
			(xy 36.827739 -398.476107) (xy 36.857227 -398.430227) (xy 36.892945 -398.389011) (xy 36.934165 -398.353298)
			(xy 36.980049 -398.323816) (xy 37.029662 -398.301164) (xy 37.081993 -398.285804) (xy 37.135978 -398.278048)
			(xy 37.163248 -398.277588) (xy 38.026848 -398.277588) (xy 38.054119 -398.277978) (xy 38.108104 -398.285746)
			(xy 38.160435 -398.301118) (xy 38.210045 -398.323779) (xy 38.255926 -398.353271) (xy 38.297144 -398.38899)
			(xy 38.332858 -398.430212) (xy 38.362344 -398.476097) (xy 38.384999 -398.52571) (xy 38.400364 -398.578043)
			(xy 38.408126 -398.632029) (xy 38.408126 -398.686571) (xy 38.400364 -398.740557) (xy 38.384999 -398.79289)
			(xy 38.38214 -398.799152) (xy 42.10455 -398.799152) (xy 42.10455 -398.744648) (xy 42.112306 -398.6907)
			(xy 42.12766 -398.638404) (xy 42.150301 -398.588826) (xy 42.179766 -398.542974) (xy 42.215456 -398.501781)
			(xy 42.256645 -398.466087) (xy 42.302494 -398.436618) (xy 42.35207 -398.413973) (xy 42.404365 -398.398614)
			(xy 42.458312 -398.390852) (xy 42.485564 -398.390364) (xy 43.349164 -398.390364) (xy 43.376417 -398.390881)
			(xy 43.430367 -398.398633) (xy 43.482666 -398.413985) (xy 43.532247 -398.436624) (xy 43.578101 -398.466088)
			(xy 43.619295 -398.50178) (xy 43.65499 -398.54297) (xy 43.684459 -398.588822) (xy 43.707103 -398.638401)
			(xy 43.722459 -398.690697) (xy 43.730217 -398.744648) (xy 43.730217 -398.799152) (xy 43.722459 -398.853103)
			(xy 43.707103 -398.9054) (xy 43.684459 -398.954978) (xy 43.65499 -399.00083) (xy 43.619295 -399.04202)
			(xy 43.578101 -399.077712) (xy 43.532247 -399.107176) (xy 43.482666 -399.129815) (xy 43.430367 -399.145167)
			(xy 43.376417 -399.152919) (xy 43.349164 -399.15338) (xy 42.485564 -399.15338) (xy 42.458312 -399.152948)
			(xy 42.404365 -399.145186) (xy 42.35207 -399.129827) (xy 42.302494 -399.107182) (xy 42.256645 -399.077713)
			(xy 42.215456 -399.042019) (xy 42.179766 -399.000826) (xy 42.150301 -398.954974) (xy 42.12766 -398.905396)
			(xy 42.112306 -398.8531) (xy 42.10455 -398.799152) (xy 38.38214 -398.799152) (xy 38.362344 -398.842503)
			(xy 38.332858 -398.888388) (xy 38.297144 -398.92961) (xy 38.255926 -398.965329) (xy 38.210045 -398.994821)
			(xy 38.160435 -399.017482) (xy 38.108104 -399.032854) (xy 38.054119 -399.040622) (xy 38.026848 -399.041112)
			(xy 37.163248 -399.041112) (xy 37.135978 -399.040552) (xy 37.081993 -399.032796) (xy 37.029662 -399.017436)
			(xy 36.980049 -398.994784) (xy 36.934165 -398.965302) (xy 36.892945 -398.929589) (xy 36.857227 -398.888373)
			(xy 36.827739 -398.842493) (xy 36.805081 -398.792883) (xy 36.789714 -398.740554) (xy 36.781952 -398.68657)
			(xy 2.509012 -398.68657) (xy 2.509012 -399.443249) (xy 18.470394 -399.443249) (xy 18.470394 -399.388751)
			(xy 18.47815 -399.334808) (xy 18.493503 -399.282518) (xy 18.516141 -399.232945) (xy 18.545603 -399.187098)
			(xy 18.58129 -399.14591) (xy 18.622475 -399.11022) (xy 18.66832 -399.080754) (xy 18.717892 -399.058112)
			(xy 18.770181 -399.042756) (xy 18.824123 -399.034996) (xy 18.851372 -399.034508) (xy 19.714972 -399.034508)
			(xy 19.742227 -399.034937) (xy 19.796184 -399.042691) (xy 19.848487 -399.058045) (xy 19.898073 -399.080687)
			(xy 19.943931 -399.110156) (xy 19.985129 -399.145851) (xy 20.020827 -399.187046) (xy 20.050299 -399.232903)
			(xy 20.072945 -399.282487) (xy 20.088303 -399.334789) (xy 20.096061 -399.388745) (xy 20.096061 -399.443255)
			(xy 20.088303 -399.497211) (xy 20.072945 -399.549513) (xy 20.050299 -399.599097) (xy 20.020828 -399.644954)
			(xy 19.985129 -399.686149) (xy 19.943931 -399.721844) (xy 19.898073 -399.751313) (xy 19.848487 -399.773955)
			(xy 19.796184 -399.789309) (xy 19.742227 -399.797063) (xy 19.714972 -399.797524) (xy 18.851372 -399.797524)
			(xy 18.824123 -399.797004) (xy 18.770181 -399.789244) (xy 18.717892 -399.773888) (xy 18.66832 -399.751246)
			(xy 18.622475 -399.72178) (xy 18.58129 -399.68609) (xy 18.545603 -399.644902) (xy 18.516141 -399.599055)
			(xy 18.493503 -399.549482) (xy 18.47815 -399.497192) (xy 18.470394 -399.443249) (xy 2.509012 -399.443249)
			(xy 2.509012 -400.459248) (xy 25.590794 -400.459248) (xy 25.590794 -400.404752) (xy 25.598549 -400.350811)
			(xy 25.613901 -400.298522) (xy 25.636538 -400.24895) (xy 25.665999 -400.203104) (xy 25.701684 -400.161916)
			(xy 25.742867 -400.126226) (xy 25.788709 -400.09676) (xy 25.838279 -400.074117) (xy 25.890566 -400.058759)
			(xy 25.944506 -400.050997) (xy 25.971754 -400.050508) (xy 26.835354 -400.050508) (xy 26.86261 -400.050936)
			(xy 26.916568 -400.058688) (xy 26.968874 -400.07404) (xy 27.018462 -400.096681) (xy 27.064323 -400.126149)
			(xy 27.105523 -400.161845) (xy 27.141223 -400.20304) (xy 27.170697 -400.248897) (xy 27.193343 -400.298483)
			(xy 27.208702 -400.350787) (xy 27.216461 -400.404744) (xy 27.216461 -400.459256) (xy 27.208702 -400.513213)
			(xy 27.193343 -400.565517) (xy 27.170697 -400.615103) (xy 27.141223 -400.66096) (xy 27.105523 -400.702155)
			(xy 27.064323 -400.737851) (xy 27.018462 -400.767319) (xy 26.968874 -400.78996) (xy 26.916568 -400.805312)
			(xy 26.86261 -400.813064) (xy 26.835354 -400.813524) (xy 25.971754 -400.813524) (xy 25.944506 -400.813003)
			(xy 25.890566 -400.805241) (xy 25.838279 -400.789883) (xy 25.788709 -400.76724) (xy 25.742867 -400.737774)
			(xy 25.701684 -400.702084) (xy 25.665999 -400.660896) (xy 25.636538 -400.61505) (xy 25.613901 -400.565478)
			(xy 25.598549 -400.513189) (xy 25.590794 -400.459248) (xy 2.509012 -400.459248) (xy 2.509012 -400.885453)
			(xy 47.598783 -400.885453) (xy 47.598783 -400.830947) (xy 47.606541 -400.776997) (xy 47.621898 -400.7247)
			(xy 47.644541 -400.675121) (xy 47.674011 -400.629269) (xy 47.709706 -400.588079) (xy 47.7509 -400.552388)
			(xy 47.796754 -400.522923) (xy 47.846336 -400.500284) (xy 47.898634 -400.484933) (xy 47.952585 -400.477181)
			(xy 47.979838 -400.47672) (xy 48.843438 -400.47672) (xy 48.870689 -400.477152) (xy 48.924637 -400.484914)
			(xy 48.976931 -400.500273) (xy 49.026507 -400.522918) (xy 49.072356 -400.552388) (xy 49.113545 -400.588082)
			(xy 49.149235 -400.629274) (xy 49.1787 -400.675126) (xy 49.20134 -400.724705) (xy 49.216694 -400.777)
			(xy 49.22445 -400.830948) (xy 49.22445 -400.885448) (xy 50.662106 -400.885448) (xy 50.662106 -400.830952)
			(xy 50.669862 -400.77701) (xy 50.685214 -400.724721) (xy 50.707852 -400.675149) (xy 50.737314 -400.629303)
			(xy 50.773001 -400.588116) (xy 50.814185 -400.552427) (xy 50.86003 -400.522963) (xy 50.9096 -400.500322)
			(xy 50.961888 -400.484966) (xy 51.01583 -400.477208) (xy 51.043078 -400.47672) (xy 51.906678 -400.47672)
			(xy 51.933934 -400.477125) (xy 51.987891 -400.48488) (xy 52.040196 -400.500236) (xy 52.089782 -400.522879)
			(xy 52.135642 -400.552348) (xy 52.17684 -400.588045) (xy 52.212539 -400.629241) (xy 52.242011 -400.675098)
			(xy 52.264657 -400.724684) (xy 52.280015 -400.776987) (xy 52.287773 -400.830944) (xy 52.287773 -400.885452)
			(xy 53.725283 -400.885452) (xy 53.725283 -400.830948) (xy 53.73304 -400.777) (xy 53.748396 -400.724704)
			(xy 53.771038 -400.675127) (xy 53.800506 -400.629276) (xy 53.836199 -400.588086) (xy 53.87739 -400.552395)
			(xy 53.923242 -400.52293) (xy 53.972821 -400.50029) (xy 54.025117 -400.484936) (xy 54.079066 -400.477182)
			(xy 54.106318 -400.47672) (xy 54.969918 -400.47672) (xy 54.99717 -400.477151) (xy 55.05112 -400.48491)
			(xy 55.103417 -400.500268) (xy 55.152995 -400.522912) (xy 55.198847 -400.552381) (xy 55.240038 -400.588075)
			(xy 55.27573 -400.629268) (xy 55.305197 -400.675121) (xy 55.327838 -400.7247) (xy 55.343194 -400.776997)
			(xy 55.35095 -400.830948) (xy 55.35095 -400.885447) (xy 56.788606 -400.885447) (xy 56.788606 -400.830953)
			(xy 56.796361 -400.777013) (xy 56.811713 -400.724725) (xy 56.834349 -400.675154) (xy 56.863809 -400.629309)
			(xy 56.899494 -400.588123) (xy 56.940676 -400.552435) (xy 56.986518 -400.522969) (xy 57.036086 -400.500327)
			(xy 57.088372 -400.48497) (xy 57.142311 -400.477209) (xy 57.169558 -400.47672) (xy 58.033158 -400.47672)
			(xy 58.060415 -400.477124) (xy 58.114374 -400.484877) (xy 58.166681 -400.50023) (xy 58.21627 -400.522872)
			(xy 58.262132 -400.552341) (xy 58.303333 -400.588037) (xy 58.339034 -400.629234) (xy 58.368508 -400.675093)
			(xy 58.391155 -400.724679) (xy 58.406514 -400.776985) (xy 58.414273 -400.830943) (xy 58.414273 -400.885449)
			(xy 59.851806 -400.885449) (xy 59.851806 -400.830951) (xy 59.859562 -400.777007) (xy 59.874916 -400.724717)
			(xy 59.897555 -400.675143) (xy 59.927019 -400.629296) (xy 59.962708 -400.588109) (xy 60.003895 -400.55242)
			(xy 60.049742 -400.522956) (xy 60.099315 -400.500317) (xy 60.151605 -400.484963) (xy 60.205549 -400.477206)
			(xy 60.232798 -400.47672) (xy 61.096398 -400.47672) (xy 61.123653 -400.477127) (xy 61.177608 -400.484884)
			(xy 61.22991 -400.500241) (xy 61.279494 -400.522885) (xy 61.325351 -400.552355) (xy 61.366547 -400.588052)
			(xy 61.402243 -400.629247) (xy 61.431714 -400.675104) (xy 61.454358 -400.724688) (xy 61.469715 -400.77699)
			(xy 61.477473 -400.830945) (xy 61.477473 -400.885453) (xy 62.914983 -400.885453) (xy 62.914983 -400.830947)
			(xy 62.922741 -400.776997) (xy 62.938098 -400.7247) (xy 62.960741 -400.675121) (xy 62.990211 -400.629269)
			(xy 63.025906 -400.588079) (xy 63.0671 -400.552388) (xy 63.112954 -400.522923) (xy 63.162536 -400.500284)
			(xy 63.214834 -400.484933) (xy 63.268785 -400.477181) (xy 63.296038 -400.47672) (xy 64.159638 -400.47672)
			(xy 64.186889 -400.477152) (xy 64.240837 -400.484914) (xy 64.293131 -400.500273) (xy 64.342707 -400.522918)
			(xy 64.388556 -400.552388) (xy 64.429745 -400.588082) (xy 64.465435 -400.629274) (xy 64.4949 -400.675126)
			(xy 64.51754 -400.724705) (xy 64.532894 -400.777) (xy 64.54065 -400.830948) (xy 64.54065 -400.885448)
			(xy 65.978306 -400.885448) (xy 65.978306 -400.830952) (xy 65.986062 -400.77701) (xy 66.001414 -400.724721)
			(xy 66.024052 -400.675149) (xy 66.053514 -400.629303) (xy 66.089201 -400.588116) (xy 66.130385 -400.552427)
			(xy 66.17623 -400.522963) (xy 66.2258 -400.500322) (xy 66.278088 -400.484966) (xy 66.33203 -400.477208)
			(xy 66.359278 -400.47672) (xy 67.222878 -400.47672) (xy 67.250134 -400.477125) (xy 67.304091 -400.48488)
			(xy 67.356396 -400.500236) (xy 67.405982 -400.522879) (xy 67.451842 -400.552348) (xy 67.49304 -400.588045)
			(xy 67.528739 -400.629241) (xy 67.558211 -400.675098) (xy 67.580857 -400.724684) (xy 67.596215 -400.776987)
			(xy 67.603973 -400.830944) (xy 67.603973 -400.885452) (xy 69.041483 -400.885452) (xy 69.041483 -400.830948)
			(xy 69.04924 -400.777) (xy 69.064596 -400.724704) (xy 69.087238 -400.675127) (xy 69.116706 -400.629276)
			(xy 69.152399 -400.588086) (xy 69.19359 -400.552395) (xy 69.239442 -400.52293) (xy 69.289021 -400.50029)
			(xy 69.341317 -400.484936) (xy 69.395266 -400.477182) (xy 69.422518 -400.47672) (xy 70.286118 -400.47672)
			(xy 70.31337 -400.477151) (xy 70.36732 -400.48491) (xy 70.419617 -400.500268) (xy 70.469195 -400.522912)
			(xy 70.515047 -400.552381) (xy 70.556238 -400.588075) (xy 70.59193 -400.629268) (xy 70.621397 -400.675121)
			(xy 70.644038 -400.7247) (xy 70.659394 -400.776997) (xy 70.66715 -400.830948) (xy 70.66715 -400.885447)
			(xy 72.104806 -400.885447) (xy 72.104806 -400.830953) (xy 72.112561 -400.777013) (xy 72.127913 -400.724725)
			(xy 72.150549 -400.675154) (xy 72.180009 -400.629309) (xy 72.215694 -400.588123) (xy 72.256876 -400.552435)
			(xy 72.302718 -400.522969) (xy 72.352286 -400.500327) (xy 72.404572 -400.48497) (xy 72.458511 -400.477209)
			(xy 72.485758 -400.47672) (xy 73.349358 -400.47672) (xy 73.376615 -400.477124) (xy 73.430574 -400.484877)
			(xy 73.482881 -400.50023) (xy 73.53247 -400.522872) (xy 73.578332 -400.552341) (xy 73.619533 -400.588037)
			(xy 73.655234 -400.629234) (xy 73.684708 -400.675093) (xy 73.707355 -400.724679) (xy 73.722714 -400.776985)
			(xy 73.730473 -400.830943) (xy 73.730473 -400.885449) (xy 75.168006 -400.885449) (xy 75.168006 -400.830951)
			(xy 75.175762 -400.777007) (xy 75.191116 -400.724717) (xy 75.213755 -400.675143) (xy 75.243219 -400.629296)
			(xy 75.278908 -400.588109) (xy 75.320095 -400.55242) (xy 75.365942 -400.522956) (xy 75.415515 -400.500317)
			(xy 75.467805 -400.484963) (xy 75.521749 -400.477206) (xy 75.548998 -400.47672) (xy 76.412598 -400.47672)
			(xy 76.439853 -400.477127) (xy 76.493808 -400.484884) (xy 76.54611 -400.500241) (xy 76.595694 -400.522885)
			(xy 76.641551 -400.552355) (xy 76.682747 -400.588052) (xy 76.718443 -400.629247) (xy 76.747914 -400.675104)
			(xy 76.770558 -400.724688) (xy 76.785915 -400.77699) (xy 76.793673 -400.830945) (xy 76.793673 -400.885453)
			(xy 78.231183 -400.885453) (xy 78.231183 -400.830947) (xy 78.238941 -400.776997) (xy 78.254298 -400.7247)
			(xy 78.276941 -400.675121) (xy 78.306411 -400.629269) (xy 78.342106 -400.588079) (xy 78.3833 -400.552388)
			(xy 78.429154 -400.522923) (xy 78.478736 -400.500284) (xy 78.531034 -400.484933) (xy 78.584985 -400.477181)
			(xy 78.612238 -400.47672) (xy 79.475838 -400.47672) (xy 79.503089 -400.477152) (xy 79.557037 -400.484914)
			(xy 79.609331 -400.500273) (xy 79.658907 -400.522918) (xy 79.704756 -400.552388) (xy 79.745945 -400.588082)
			(xy 79.781635 -400.629274) (xy 79.8111 -400.675126) (xy 79.83374 -400.724705) (xy 79.849094 -400.777)
			(xy 79.85685 -400.830948) (xy 79.85685 -400.885448) (xy 81.294506 -400.885448) (xy 81.294506 -400.830952)
			(xy 81.302262 -400.77701) (xy 81.317614 -400.724721) (xy 81.340252 -400.675149) (xy 81.369714 -400.629303)
			(xy 81.405401 -400.588116) (xy 81.446585 -400.552427) (xy 81.49243 -400.522963) (xy 81.542 -400.500322)
			(xy 81.594288 -400.484966) (xy 81.64823 -400.477208) (xy 81.675478 -400.47672) (xy 82.539078 -400.47672)
			(xy 82.566334 -400.477125) (xy 82.620291 -400.48488) (xy 82.672596 -400.500236) (xy 82.722182 -400.522879)
			(xy 82.768042 -400.552348) (xy 82.80924 -400.588045) (xy 82.844939 -400.629241) (xy 82.874411 -400.675098)
			(xy 82.897057 -400.724684) (xy 82.912415 -400.776987) (xy 82.920173 -400.830944) (xy 82.920173 -400.885452)
			(xy 84.357683 -400.885452) (xy 84.357683 -400.830948) (xy 84.36544 -400.777) (xy 84.380796 -400.724704)
			(xy 84.403438 -400.675127) (xy 84.432906 -400.629276) (xy 84.468599 -400.588086) (xy 84.50979 -400.552395)
			(xy 84.555642 -400.52293) (xy 84.605221 -400.50029) (xy 84.657517 -400.484936) (xy 84.711466 -400.477182)
			(xy 84.738718 -400.47672) (xy 85.602318 -400.47672) (xy 85.62957 -400.477151) (xy 85.68352 -400.48491)
			(xy 85.735817 -400.500268) (xy 85.785395 -400.522912) (xy 85.831247 -400.552381) (xy 85.872438 -400.588075)
			(xy 85.90813 -400.629268) (xy 85.937597 -400.675121) (xy 85.960238 -400.7247) (xy 85.975594 -400.776997)
			(xy 85.98335 -400.830948) (xy 85.98335 -400.885447) (xy 87.421006 -400.885447) (xy 87.421006 -400.830953)
			(xy 87.428761 -400.777013) (xy 87.444113 -400.724725) (xy 87.466749 -400.675154) (xy 87.496209 -400.629309)
			(xy 87.531894 -400.588123) (xy 87.573076 -400.552435) (xy 87.618918 -400.522969) (xy 87.668486 -400.500327)
			(xy 87.720772 -400.48497) (xy 87.774711 -400.477209) (xy 87.801958 -400.47672) (xy 88.665558 -400.47672)
			(xy 88.692815 -400.477124) (xy 88.746774 -400.484877) (xy 88.799081 -400.50023) (xy 88.84867 -400.522872)
			(xy 88.894532 -400.552341) (xy 88.935733 -400.588037) (xy 88.971434 -400.629234) (xy 89.000908 -400.675093)
			(xy 89.023555 -400.724679) (xy 89.038914 -400.776985) (xy 89.046673 -400.830943) (xy 89.046673 -400.885449)
			(xy 90.484206 -400.885449) (xy 90.484206 -400.830951) (xy 90.491962 -400.777007) (xy 90.507316 -400.724717)
			(xy 90.529955 -400.675143) (xy 90.559419 -400.629296) (xy 90.595108 -400.588109) (xy 90.636295 -400.55242)
			(xy 90.682142 -400.522956) (xy 90.731715 -400.500317) (xy 90.784005 -400.484963) (xy 90.837949 -400.477206)
			(xy 90.865198 -400.47672) (xy 91.728798 -400.47672) (xy 91.756053 -400.477127) (xy 91.810008 -400.484884)
			(xy 91.86231 -400.500241) (xy 91.911894 -400.522885) (xy 91.957751 -400.552355) (xy 91.998947 -400.588052)
			(xy 92.034643 -400.629247) (xy 92.064114 -400.675104) (xy 92.086758 -400.724688) (xy 92.102115 -400.77699)
			(xy 92.109873 -400.830945) (xy 92.109873 -400.885453) (xy 93.547383 -400.885453) (xy 93.547383 -400.830947)
			(xy 93.555141 -400.776997) (xy 93.570498 -400.7247) (xy 93.593141 -400.675121) (xy 93.622611 -400.629269)
			(xy 93.658306 -400.588079) (xy 93.6995 -400.552388) (xy 93.745354 -400.522923) (xy 93.794936 -400.500284)
			(xy 93.847234 -400.484933) (xy 93.901185 -400.477181) (xy 93.928438 -400.47672) (xy 94.792038 -400.47672)
			(xy 94.819289 -400.477152) (xy 94.873237 -400.484914) (xy 94.925531 -400.500273) (xy 94.975107 -400.522918)
			(xy 95.020956 -400.552388) (xy 95.062145 -400.588082) (xy 95.097835 -400.629274) (xy 95.1273 -400.675126)
			(xy 95.14994 -400.724705) (xy 95.165294 -400.777) (xy 95.17305 -400.830948) (xy 95.17305 -400.885447)
			(xy 119.774006 -400.885447) (xy 119.774006 -400.830953) (xy 119.781761 -400.777013) (xy 119.797112 -400.724726)
			(xy 119.819749 -400.675156) (xy 119.849208 -400.629311) (xy 119.884892 -400.588125) (xy 119.926074 -400.552436)
			(xy 119.971915 -400.522971) (xy 120.021483 -400.500329) (xy 120.073768 -400.484971) (xy 120.127707 -400.477209)
			(xy 120.154954 -400.47672) (xy 121.018554 -400.47672) (xy 121.045811 -400.477124) (xy 121.099771 -400.484876)
			(xy 121.152078 -400.500229) (xy 121.201668 -400.522871) (xy 121.24753 -400.55234) (xy 121.288731 -400.588036)
			(xy 121.324433 -400.629233) (xy 121.353907 -400.675092) (xy 121.376555 -400.724679) (xy 121.391914 -400.776984)
			(xy 121.399673 -400.830943) (xy 121.399673 -400.885449) (xy 122.837206 -400.885449) (xy 122.837206 -400.830951)
			(xy 122.844962 -400.777008) (xy 122.860316 -400.724717) (xy 122.882955 -400.675144) (xy 122.912418 -400.629298)
			(xy 122.948106 -400.588111) (xy 122.989293 -400.552422) (xy 123.035139 -400.522958) (xy 123.084712 -400.500318)
			(xy 123.137002 -400.484963) (xy 123.190945 -400.477207) (xy 123.218194 -400.47672) (xy 124.081794 -400.47672)
			(xy 124.109049 -400.477127) (xy 124.163005 -400.484883) (xy 124.215307 -400.50024) (xy 124.264892 -400.522884)
			(xy 124.310749 -400.552354) (xy 124.351946 -400.58805) (xy 124.387643 -400.629246) (xy 124.417113 -400.675103)
			(xy 124.439758 -400.724687) (xy 124.455115 -400.776989) (xy 124.462873 -400.830945) (xy 124.462873 -400.885452)
			(xy 125.900383 -400.885452) (xy 125.900383 -400.830948) (xy 125.908141 -400.776998) (xy 125.923497 -400.724701)
			(xy 125.946141 -400.675122) (xy 125.97561 -400.629271) (xy 126.011304 -400.58808) (xy 126.052498 -400.552389)
			(xy 126.098352 -400.522924) (xy 126.147933 -400.500285) (xy 126.200231 -400.484933) (xy 126.254182 -400.477181)
			(xy 126.281434 -400.47672) (xy 127.145034 -400.47672) (xy 127.172286 -400.477152) (xy 127.226234 -400.484913)
			(xy 127.278528 -400.500272) (xy 127.328105 -400.522917) (xy 127.373954 -400.552386) (xy 127.415143 -400.588081)
			(xy 127.450834 -400.629273) (xy 127.480299 -400.675125) (xy 127.50294 -400.724704) (xy 127.518294 -400.777)
			(xy 127.52605 -400.830948) (xy 127.52605 -400.885448) (xy 128.963706 -400.885448) (xy 128.963706 -400.830952)
			(xy 128.971461 -400.777011) (xy 128.986814 -400.724722) (xy 129.009452 -400.67515) (xy 129.038913 -400.629304)
			(xy 129.074599 -400.588118) (xy 129.115783 -400.552429) (xy 129.161627 -400.522964) (xy 129.211197 -400.500323)
			(xy 129.263485 -400.484967) (xy 129.317426 -400.477208) (xy 129.344674 -400.47672) (xy 130.208274 -400.47672)
			(xy 130.23553 -400.477125) (xy 130.289488 -400.48488) (xy 130.341793 -400.500235) (xy 130.39138 -400.522877)
			(xy 130.43724 -400.552347) (xy 130.478438 -400.588043) (xy 130.514138 -400.62924) (xy 130.54361 -400.675097)
			(xy 130.566256 -400.724683) (xy 130.581615 -400.776987) (xy 130.589373 -400.830944) (xy 130.589373 -400.885451)
			(xy 132.026883 -400.885451) (xy 132.026883 -400.830949) (xy 132.03464 -400.777) (xy 132.049996 -400.724705)
			(xy 132.072638 -400.675128) (xy 132.102105 -400.629277) (xy 132.137797 -400.588087) (xy 132.178989 -400.552396)
			(xy 132.22484 -400.522931) (xy 132.274418 -400.500291) (xy 132.326714 -400.484937) (xy 132.380662 -400.477182)
			(xy 132.407914 -400.47672) (xy 133.271514 -400.47672) (xy 133.298767 -400.477151) (xy 133.352717 -400.48491)
			(xy 133.405014 -400.500267) (xy 133.454593 -400.522911) (xy 133.500445 -400.552379) (xy 133.541636 -400.588074)
			(xy 133.577329 -400.629266) (xy 133.606796 -400.67512) (xy 133.629438 -400.724699) (xy 133.644793 -400.776997)
			(xy 133.65255 -400.830947) (xy 133.65255 -400.885447) (xy 135.090206 -400.885447) (xy 135.090206 -400.830953)
			(xy 135.097961 -400.777013) (xy 135.113312 -400.724726) (xy 135.135949 -400.675156) (xy 135.165408 -400.629311)
			(xy 135.201092 -400.588125) (xy 135.242274 -400.552436) (xy 135.288115 -400.522971) (xy 135.337683 -400.500329)
			(xy 135.389968 -400.484971) (xy 135.443907 -400.477209) (xy 135.471154 -400.47672) (xy 136.334754 -400.47672)
			(xy 136.362011 -400.477124) (xy 136.415971 -400.484876) (xy 136.468278 -400.500229) (xy 136.517868 -400.522871)
			(xy 136.56373 -400.55234) (xy 136.604931 -400.588036) (xy 136.640633 -400.629233) (xy 136.670107 -400.675092)
			(xy 136.692755 -400.724679) (xy 136.708114 -400.776984) (xy 136.715873 -400.830943) (xy 136.715873 -400.885449)
			(xy 138.153406 -400.885449) (xy 138.153406 -400.830951) (xy 138.161162 -400.777008) (xy 138.176516 -400.724717)
			(xy 138.199155 -400.675144) (xy 138.228618 -400.629298) (xy 138.264306 -400.588111) (xy 138.305493 -400.552422)
			(xy 138.351339 -400.522958) (xy 138.400912 -400.500318) (xy 138.453202 -400.484963) (xy 138.507145 -400.477207)
			(xy 138.534394 -400.47672) (xy 139.397994 -400.47672) (xy 139.425249 -400.477127) (xy 139.479205 -400.484883)
			(xy 139.531507 -400.50024) (xy 139.581092 -400.522884) (xy 139.626949 -400.552354) (xy 139.668146 -400.58805)
			(xy 139.703843 -400.629246) (xy 139.733313 -400.675103) (xy 139.755958 -400.724687) (xy 139.771315 -400.776989)
			(xy 139.779073 -400.830945) (xy 139.779073 -400.885452) (xy 141.216583 -400.885452) (xy 141.216583 -400.830948)
			(xy 141.224341 -400.776998) (xy 141.239697 -400.724701) (xy 141.262341 -400.675122) (xy 141.29181 -400.629271)
			(xy 141.327504 -400.58808) (xy 141.368698 -400.552389) (xy 141.414552 -400.522924) (xy 141.464133 -400.500285)
			(xy 141.516431 -400.484933) (xy 141.570382 -400.477181) (xy 141.597634 -400.47672) (xy 142.461234 -400.47672)
			(xy 142.488486 -400.477152) (xy 142.542434 -400.484913) (xy 142.594728 -400.500272) (xy 142.644305 -400.522917)
			(xy 142.690154 -400.552386) (xy 142.731343 -400.588081) (xy 142.767034 -400.629273) (xy 142.796499 -400.675125)
			(xy 142.81914 -400.724704) (xy 142.834494 -400.777) (xy 142.84225 -400.830948) (xy 142.84225 -400.885448)
			(xy 144.279906 -400.885448) (xy 144.279906 -400.830952) (xy 144.287661 -400.777011) (xy 144.303014 -400.724722)
			(xy 144.325652 -400.67515) (xy 144.355113 -400.629304) (xy 144.390799 -400.588118) (xy 144.431983 -400.552429)
			(xy 144.477827 -400.522964) (xy 144.527397 -400.500323) (xy 144.579685 -400.484967) (xy 144.633626 -400.477208)
			(xy 144.660874 -400.47672) (xy 145.524474 -400.47672) (xy 145.55173 -400.477125) (xy 145.605688 -400.48488)
			(xy 145.657993 -400.500235) (xy 145.70758 -400.522877) (xy 145.75344 -400.552347) (xy 145.794638 -400.588043)
			(xy 145.830338 -400.62924) (xy 145.85981 -400.675097) (xy 145.882456 -400.724683) (xy 145.897815 -400.776987)
			(xy 145.905573 -400.830944) (xy 145.905573 -400.885451) (xy 147.343083 -400.885451) (xy 147.343083 -400.830949)
			(xy 147.35084 -400.777) (xy 147.366196 -400.724705) (xy 147.388838 -400.675128) (xy 147.418305 -400.629277)
			(xy 147.453997 -400.588087) (xy 147.495189 -400.552396) (xy 147.54104 -400.522931) (xy 147.590618 -400.500291)
			(xy 147.642914 -400.484937) (xy 147.696862 -400.477182) (xy 147.724114 -400.47672) (xy 148.587714 -400.47672)
			(xy 148.614967 -400.477151) (xy 148.668917 -400.48491) (xy 148.721214 -400.500267) (xy 148.770793 -400.522911)
			(xy 148.816645 -400.552379) (xy 148.857836 -400.588074) (xy 148.893529 -400.629266) (xy 148.922996 -400.67512)
			(xy 148.945638 -400.724699) (xy 148.960993 -400.776997) (xy 148.96875 -400.830947) (xy 148.96875 -400.885447)
			(xy 150.406406 -400.885447) (xy 150.406406 -400.830953) (xy 150.414161 -400.777013) (xy 150.429512 -400.724726)
			(xy 150.452149 -400.675156) (xy 150.481608 -400.629311) (xy 150.517292 -400.588125) (xy 150.558474 -400.552436)
			(xy 150.604315 -400.522971) (xy 150.653883 -400.500329) (xy 150.706168 -400.484971) (xy 150.760107 -400.477209)
			(xy 150.787354 -400.47672) (xy 151.650954 -400.47672) (xy 151.678211 -400.477124) (xy 151.732171 -400.484876)
			(xy 151.784478 -400.500229) (xy 151.834068 -400.522871) (xy 151.87993 -400.55234) (xy 151.921131 -400.588036)
			(xy 151.956833 -400.629233) (xy 151.986307 -400.675092) (xy 152.008955 -400.724679) (xy 152.024314 -400.776984)
			(xy 152.032073 -400.830943) (xy 152.032073 -400.885449) (xy 153.469606 -400.885449) (xy 153.469606 -400.830951)
			(xy 153.477362 -400.777008) (xy 153.492716 -400.724717) (xy 153.515355 -400.675144) (xy 153.544818 -400.629298)
			(xy 153.580506 -400.588111) (xy 153.621693 -400.552422) (xy 153.667539 -400.522958) (xy 153.717112 -400.500318)
			(xy 153.769402 -400.484963) (xy 153.823345 -400.477207) (xy 153.850594 -400.47672) (xy 154.714194 -400.47672)
			(xy 154.741449 -400.477127) (xy 154.795405 -400.484883) (xy 154.847707 -400.50024) (xy 154.897292 -400.522884)
			(xy 154.943149 -400.552354) (xy 154.984346 -400.58805) (xy 155.020043 -400.629246) (xy 155.049513 -400.675103)
			(xy 155.072158 -400.724687) (xy 155.087515 -400.776989) (xy 155.095273 -400.830945) (xy 155.095273 -400.885452)
			(xy 156.532783 -400.885452) (xy 156.532783 -400.830948) (xy 156.540541 -400.776998) (xy 156.555897 -400.724701)
			(xy 156.578541 -400.675122) (xy 156.60801 -400.629271) (xy 156.643704 -400.58808) (xy 156.684898 -400.552389)
			(xy 156.730752 -400.522924) (xy 156.780333 -400.500285) (xy 156.832631 -400.484933) (xy 156.886582 -400.477181)
			(xy 156.913834 -400.47672) (xy 157.777434 -400.47672) (xy 157.804686 -400.477152) (xy 157.858634 -400.484913)
			(xy 157.910928 -400.500272) (xy 157.960505 -400.522917) (xy 158.006354 -400.552386) (xy 158.047543 -400.588081)
			(xy 158.083234 -400.629273) (xy 158.112699 -400.675125) (xy 158.13534 -400.724704) (xy 158.150694 -400.777)
			(xy 158.15845 -400.830948) (xy 158.15845 -400.885448) (xy 159.596106 -400.885448) (xy 159.596106 -400.830952)
			(xy 159.603861 -400.777011) (xy 159.619214 -400.724722) (xy 159.641852 -400.67515) (xy 159.671313 -400.629304)
			(xy 159.706999 -400.588118) (xy 159.748183 -400.552429) (xy 159.794027 -400.522964) (xy 159.843597 -400.500323)
			(xy 159.895885 -400.484967) (xy 159.949826 -400.477208) (xy 159.977074 -400.47672) (xy 160.840674 -400.47672)
			(xy 160.86793 -400.477125) (xy 160.921888 -400.48488) (xy 160.974193 -400.500235) (xy 161.02378 -400.522877)
			(xy 161.06964 -400.552347) (xy 161.110838 -400.588043) (xy 161.146538 -400.62924) (xy 161.17601 -400.675097)
			(xy 161.198656 -400.724683) (xy 161.214015 -400.776987) (xy 161.221773 -400.830944) (xy 161.221773 -400.885451)
			(xy 162.659283 -400.885451) (xy 162.659283 -400.830949) (xy 162.66704 -400.777) (xy 162.682396 -400.724705)
			(xy 162.705038 -400.675128) (xy 162.734505 -400.629277) (xy 162.770197 -400.588087) (xy 162.811389 -400.552396)
			(xy 162.85724 -400.522931) (xy 162.906818 -400.500291) (xy 162.959114 -400.484937) (xy 163.013062 -400.477182)
			(xy 163.040314 -400.47672) (xy 163.903914 -400.47672) (xy 163.931167 -400.477151) (xy 163.985117 -400.48491)
			(xy 164.037414 -400.500267) (xy 164.086993 -400.522911) (xy 164.132845 -400.552379) (xy 164.174036 -400.588074)
			(xy 164.209729 -400.629266) (xy 164.239196 -400.67512) (xy 164.261838 -400.724699) (xy 164.277193 -400.776997)
			(xy 164.28495 -400.830947) (xy 164.28495 -400.885447) (xy 165.722606 -400.885447) (xy 165.722606 -400.830953)
			(xy 165.730361 -400.777013) (xy 165.745712 -400.724726) (xy 165.768349 -400.675156) (xy 165.797808 -400.629311)
			(xy 165.833492 -400.588125) (xy 165.874674 -400.552436) (xy 165.920515 -400.522971) (xy 165.970083 -400.500329)
			(xy 166.022368 -400.484971) (xy 166.076307 -400.477209) (xy 166.103554 -400.47672) (xy 166.967154 -400.47672)
			(xy 166.994411 -400.477124) (xy 167.048371 -400.484876) (xy 167.100678 -400.500229) (xy 167.150268 -400.522871)
			(xy 167.19613 -400.55234) (xy 167.237331 -400.588036) (xy 167.273033 -400.629233) (xy 167.302507 -400.675092)
			(xy 167.325155 -400.724679) (xy 167.340514 -400.776984) (xy 167.348273 -400.830943) (xy 167.348273 -400.885457)
			(xy 167.340514 -400.939416) (xy 167.325155 -400.991721) (xy 167.302507 -401.041308) (xy 167.273033 -401.087167)
			(xy 167.237331 -401.128364) (xy 167.19613 -401.16406) (xy 167.150268 -401.193529) (xy 167.100678 -401.216171)
			(xy 167.048371 -401.231524) (xy 166.994411 -401.239276) (xy 166.967154 -401.239736) (xy 166.103554 -401.239736)
			(xy 166.076307 -401.239191) (xy 166.022368 -401.231429) (xy 165.970083 -401.216071) (xy 165.920515 -401.193429)
			(xy 165.874674 -401.163964) (xy 165.833492 -401.128275) (xy 165.797808 -401.087089) (xy 165.768349 -401.041244)
			(xy 165.745712 -400.991674) (xy 165.730361 -400.939387) (xy 165.722606 -400.885447) (xy 164.28495 -400.885447)
			(xy 164.28495 -400.885453) (xy 164.277193 -400.939403) (xy 164.261838 -400.991701) (xy 164.239196 -401.04128)
			(xy 164.209729 -401.087134) (xy 164.174036 -401.128326) (xy 164.132845 -401.164021) (xy 164.086993 -401.193489)
			(xy 164.037414 -401.216133) (xy 163.985117 -401.23149) (xy 163.931167 -401.239249) (xy 163.903914 -401.239736)
			(xy 163.040314 -401.239736) (xy 163.013062 -401.239218) (xy 162.959114 -401.231463) (xy 162.906818 -401.216109)
			(xy 162.85724 -401.193469) (xy 162.811389 -401.164004) (xy 162.770197 -401.128313) (xy 162.734505 -401.087123)
			(xy 162.705038 -401.041272) (xy 162.682396 -400.991695) (xy 162.66704 -400.9394) (xy 162.659283 -400.885451)
			(xy 161.221773 -400.885451) (xy 161.221773 -400.885456) (xy 161.214015 -400.939413) (xy 161.198656 -400.991717)
			(xy 161.17601 -401.041303) (xy 161.146538 -401.08716) (xy 161.110838 -401.128357) (xy 161.06964 -401.164053)
			(xy 161.02378 -401.193523) (xy 160.974193 -401.216165) (xy 160.921888 -401.23152) (xy 160.86793 -401.239275)
			(xy 160.840674 -401.239736) (xy 159.977074 -401.239736) (xy 159.949826 -401.239192) (xy 159.895885 -401.231433)
			(xy 159.843597 -401.216077) (xy 159.794027 -401.193436) (xy 159.748183 -401.163971) (xy 159.706999 -401.128282)
			(xy 159.671313 -401.087096) (xy 159.641852 -401.04125) (xy 159.619214 -400.991678) (xy 159.603861 -400.939389)
			(xy 159.596106 -400.885448) (xy 158.15845 -400.885448) (xy 158.15845 -400.885452) (xy 158.150694 -400.9394)
			(xy 158.13534 -400.991696) (xy 158.112699 -401.041275) (xy 158.083234 -401.087127) (xy 158.047543 -401.128319)
			(xy 158.006354 -401.164014) (xy 157.960505 -401.193483) (xy 157.910928 -401.216128) (xy 157.858634 -401.231487)
			(xy 157.804686 -401.239248) (xy 157.777434 -401.239736) (xy 156.913834 -401.239736) (xy 156.886582 -401.239219)
			(xy 156.832631 -401.231467) (xy 156.780333 -401.216115) (xy 156.730752 -401.193476) (xy 156.684898 -401.164011)
			(xy 156.643704 -401.12832) (xy 156.60801 -401.087129) (xy 156.578541 -401.041278) (xy 156.555897 -400.991699)
			(xy 156.540541 -400.939402) (xy 156.532783 -400.885452) (xy 155.095273 -400.885452) (xy 155.095273 -400.885455)
			(xy 155.087515 -400.939411) (xy 155.072158 -400.991713) (xy 155.049513 -401.041297) (xy 155.020043 -401.087154)
			(xy 154.984346 -401.12835) (xy 154.943149 -401.164046) (xy 154.897292 -401.193516) (xy 154.847707 -401.21616)
			(xy 154.795405 -401.231517) (xy 154.741449 -401.239273) (xy 154.714194 -401.239736) (xy 153.850594 -401.239736)
			(xy 153.823345 -401.239193) (xy 153.769402 -401.231437) (xy 153.717112 -401.216082) (xy 153.667539 -401.193442)
			(xy 153.621693 -401.163978) (xy 153.580506 -401.128289) (xy 153.544818 -401.087102) (xy 153.515355 -401.041256)
			(xy 153.492716 -400.991683) (xy 153.477362 -400.939392) (xy 153.469606 -400.885449) (xy 152.032073 -400.885449)
			(xy 152.032073 -400.885457) (xy 152.024314 -400.939416) (xy 152.008955 -400.991721) (xy 151.986307 -401.041308)
			(xy 151.956833 -401.087167) (xy 151.921131 -401.128364) (xy 151.87993 -401.16406) (xy 151.834068 -401.193529)
			(xy 151.784478 -401.216171) (xy 151.732171 -401.231524) (xy 151.678211 -401.239276) (xy 151.650954 -401.239736)
			(xy 150.787354 -401.239736) (xy 150.760107 -401.239191) (xy 150.706168 -401.231429) (xy 150.653883 -401.216071)
			(xy 150.604315 -401.193429) (xy 150.558474 -401.163964) (xy 150.517292 -401.128275) (xy 150.481608 -401.087089)
			(xy 150.452149 -401.041244) (xy 150.429512 -400.991674) (xy 150.414161 -400.939387) (xy 150.406406 -400.885447)
			(xy 148.96875 -400.885447) (xy 148.96875 -400.885453) (xy 148.960993 -400.939403) (xy 148.945638 -400.991701)
			(xy 148.922996 -401.04128) (xy 148.893529 -401.087134) (xy 148.857836 -401.128326) (xy 148.816645 -401.164021)
			(xy 148.770793 -401.193489) (xy 148.721214 -401.216133) (xy 148.668917 -401.23149) (xy 148.614967 -401.239249)
			(xy 148.587714 -401.239736) (xy 147.724114 -401.239736) (xy 147.696862 -401.239218) (xy 147.642914 -401.231463)
			(xy 147.590618 -401.216109) (xy 147.54104 -401.193469) (xy 147.495189 -401.164004) (xy 147.453997 -401.128313)
			(xy 147.418305 -401.087123) (xy 147.388838 -401.041272) (xy 147.366196 -400.991695) (xy 147.35084 -400.9394)
			(xy 147.343083 -400.885451) (xy 145.905573 -400.885451) (xy 145.905573 -400.885456) (xy 145.897815 -400.939413)
			(xy 145.882456 -400.991717) (xy 145.85981 -401.041303) (xy 145.830338 -401.08716) (xy 145.794638 -401.128357)
			(xy 145.75344 -401.164053) (xy 145.70758 -401.193523) (xy 145.657993 -401.216165) (xy 145.605688 -401.23152)
			(xy 145.55173 -401.239275) (xy 145.524474 -401.239736) (xy 144.660874 -401.239736) (xy 144.633626 -401.239192)
			(xy 144.579685 -401.231433) (xy 144.527397 -401.216077) (xy 144.477827 -401.193436) (xy 144.431983 -401.163971)
			(xy 144.390799 -401.128282) (xy 144.355113 -401.087096) (xy 144.325652 -401.04125) (xy 144.303014 -400.991678)
			(xy 144.287661 -400.939389) (xy 144.279906 -400.885448) (xy 142.84225 -400.885448) (xy 142.84225 -400.885452)
			(xy 142.834494 -400.9394) (xy 142.81914 -400.991696) (xy 142.796499 -401.041275) (xy 142.767034 -401.087127)
			(xy 142.731343 -401.128319) (xy 142.690154 -401.164014) (xy 142.644305 -401.193483) (xy 142.594728 -401.216128)
			(xy 142.542434 -401.231487) (xy 142.488486 -401.239248) (xy 142.461234 -401.239736) (xy 141.597634 -401.239736)
			(xy 141.570382 -401.239219) (xy 141.516431 -401.231467) (xy 141.464133 -401.216115) (xy 141.414552 -401.193476)
			(xy 141.368698 -401.164011) (xy 141.327504 -401.12832) (xy 141.29181 -401.087129) (xy 141.262341 -401.041278)
			(xy 141.239697 -400.991699) (xy 141.224341 -400.939402) (xy 141.216583 -400.885452) (xy 139.779073 -400.885452)
			(xy 139.779073 -400.885455) (xy 139.771315 -400.939411) (xy 139.755958 -400.991713) (xy 139.733313 -401.041297)
			(xy 139.703843 -401.087154) (xy 139.668146 -401.12835) (xy 139.626949 -401.164046) (xy 139.581092 -401.193516)
			(xy 139.531507 -401.21616) (xy 139.479205 -401.231517) (xy 139.425249 -401.239273) (xy 139.397994 -401.239736)
			(xy 138.534394 -401.239736) (xy 138.507145 -401.239193) (xy 138.453202 -401.231437) (xy 138.400912 -401.216082)
			(xy 138.351339 -401.193442) (xy 138.305493 -401.163978) (xy 138.264306 -401.128289) (xy 138.228618 -401.087102)
			(xy 138.199155 -401.041256) (xy 138.176516 -400.991683) (xy 138.161162 -400.939392) (xy 138.153406 -400.885449)
			(xy 136.715873 -400.885449) (xy 136.715873 -400.885457) (xy 136.708114 -400.939416) (xy 136.692755 -400.991721)
			(xy 136.670107 -401.041308) (xy 136.640633 -401.087167) (xy 136.604931 -401.128364) (xy 136.56373 -401.16406)
			(xy 136.517868 -401.193529) (xy 136.468278 -401.216171) (xy 136.415971 -401.231524) (xy 136.362011 -401.239276)
			(xy 136.334754 -401.239736) (xy 135.471154 -401.239736) (xy 135.443907 -401.239191) (xy 135.389968 -401.231429)
			(xy 135.337683 -401.216071) (xy 135.288115 -401.193429) (xy 135.242274 -401.163964) (xy 135.201092 -401.128275)
			(xy 135.165408 -401.087089) (xy 135.135949 -401.041244) (xy 135.113312 -400.991674) (xy 135.097961 -400.939387)
			(xy 135.090206 -400.885447) (xy 133.65255 -400.885447) (xy 133.65255 -400.885453) (xy 133.644793 -400.939403)
			(xy 133.629438 -400.991701) (xy 133.606796 -401.04128) (xy 133.577329 -401.087134) (xy 133.541636 -401.128326)
			(xy 133.500445 -401.164021) (xy 133.454593 -401.193489) (xy 133.405014 -401.216133) (xy 133.352717 -401.23149)
			(xy 133.298767 -401.239249) (xy 133.271514 -401.239736) (xy 132.407914 -401.239736) (xy 132.380662 -401.239218)
			(xy 132.326714 -401.231463) (xy 132.274418 -401.216109) (xy 132.22484 -401.193469) (xy 132.178989 -401.164004)
			(xy 132.137797 -401.128313) (xy 132.102105 -401.087123) (xy 132.072638 -401.041272) (xy 132.049996 -400.991695)
			(xy 132.03464 -400.9394) (xy 132.026883 -400.885451) (xy 130.589373 -400.885451) (xy 130.589373 -400.885456)
			(xy 130.581615 -400.939413) (xy 130.566256 -400.991717) (xy 130.54361 -401.041303) (xy 130.514138 -401.08716)
			(xy 130.478438 -401.128357) (xy 130.43724 -401.164053) (xy 130.39138 -401.193523) (xy 130.341793 -401.216165)
			(xy 130.289488 -401.23152) (xy 130.23553 -401.239275) (xy 130.208274 -401.239736) (xy 129.344674 -401.239736)
			(xy 129.317426 -401.239192) (xy 129.263485 -401.231433) (xy 129.211197 -401.216077) (xy 129.161627 -401.193436)
			(xy 129.115783 -401.163971) (xy 129.074599 -401.128282) (xy 129.038913 -401.087096) (xy 129.009452 -401.04125)
			(xy 128.986814 -400.991678) (xy 128.971461 -400.939389) (xy 128.963706 -400.885448) (xy 127.52605 -400.885448)
			(xy 127.52605 -400.885452) (xy 127.518294 -400.9394) (xy 127.50294 -400.991696) (xy 127.480299 -401.041275)
			(xy 127.450834 -401.087127) (xy 127.415143 -401.128319) (xy 127.373954 -401.164014) (xy 127.328105 -401.193483)
			(xy 127.278528 -401.216128) (xy 127.226234 -401.231487) (xy 127.172286 -401.239248) (xy 127.145034 -401.239736)
			(xy 126.281434 -401.239736) (xy 126.254182 -401.239219) (xy 126.200231 -401.231467) (xy 126.147933 -401.216115)
			(xy 126.098352 -401.193476) (xy 126.052498 -401.164011) (xy 126.011304 -401.12832) (xy 125.97561 -401.087129)
			(xy 125.946141 -401.041278) (xy 125.923497 -400.991699) (xy 125.908141 -400.939402) (xy 125.900383 -400.885452)
			(xy 124.462873 -400.885452) (xy 124.462873 -400.885455) (xy 124.455115 -400.939411) (xy 124.439758 -400.991713)
			(xy 124.417113 -401.041297) (xy 124.387643 -401.087154) (xy 124.351946 -401.12835) (xy 124.310749 -401.164046)
			(xy 124.264892 -401.193516) (xy 124.215307 -401.21616) (xy 124.163005 -401.231517) (xy 124.109049 -401.239273)
			(xy 124.081794 -401.239736) (xy 123.218194 -401.239736) (xy 123.190945 -401.239193) (xy 123.137002 -401.231437)
			(xy 123.084712 -401.216082) (xy 123.035139 -401.193442) (xy 122.989293 -401.163978) (xy 122.948106 -401.128289)
			(xy 122.912418 -401.087102) (xy 122.882955 -401.041256) (xy 122.860316 -400.991683) (xy 122.844962 -400.939392)
			(xy 122.837206 -400.885449) (xy 121.399673 -400.885449) (xy 121.399673 -400.885457) (xy 121.391914 -400.939416)
			(xy 121.376555 -400.991721) (xy 121.353907 -401.041308) (xy 121.324433 -401.087167) (xy 121.288731 -401.128364)
			(xy 121.24753 -401.16406) (xy 121.201668 -401.193529) (xy 121.152078 -401.216171) (xy 121.099771 -401.231524)
			(xy 121.045811 -401.239276) (xy 121.018554 -401.239736) (xy 120.154954 -401.239736) (xy 120.127707 -401.239191)
			(xy 120.073768 -401.231429) (xy 120.021483 -401.216071) (xy 119.971915 -401.193429) (xy 119.926074 -401.163964)
			(xy 119.884892 -401.128275) (xy 119.849208 -401.087089) (xy 119.819749 -401.041244) (xy 119.797112 -400.991674)
			(xy 119.781761 -400.939387) (xy 119.774006 -400.885447) (xy 95.17305 -400.885447) (xy 95.17305 -400.885452)
			(xy 95.165294 -400.9394) (xy 95.14994 -400.991695) (xy 95.1273 -401.041274) (xy 95.097835 -401.087126)
			(xy 95.062145 -401.128318) (xy 95.020956 -401.164012) (xy 94.975107 -401.193482) (xy 94.925531 -401.216127)
			(xy 94.873237 -401.231486) (xy 94.819289 -401.239248) (xy 94.792038 -401.239736) (xy 93.928438 -401.239736)
			(xy 93.901185 -401.239219) (xy 93.847234 -401.231467) (xy 93.794936 -401.216116) (xy 93.745354 -401.193477)
			(xy 93.6995 -401.164012) (xy 93.658306 -401.128321) (xy 93.622611 -401.087131) (xy 93.593141 -401.041279)
			(xy 93.570498 -400.9917) (xy 93.555141 -400.939403) (xy 93.547383 -400.885453) (xy 92.109873 -400.885453)
			(xy 92.109873 -400.885455) (xy 92.102115 -400.93941) (xy 92.086758 -400.991712) (xy 92.064114 -401.041296)
			(xy 92.034643 -401.087153) (xy 91.998947 -401.128348) (xy 91.957751 -401.164045) (xy 91.911894 -401.193515)
			(xy 91.86231 -401.216159) (xy 91.810008 -401.231516) (xy 91.756053 -401.239273) (xy 91.728798 -401.239736)
			(xy 90.865198 -401.239736) (xy 90.837949 -401.239194) (xy 90.784005 -401.231437) (xy 90.731715 -401.216083)
			(xy 90.682142 -401.193444) (xy 90.636295 -401.16398) (xy 90.595108 -401.128291) (xy 90.559419 -401.087104)
			(xy 90.529955 -401.041257) (xy 90.507316 -400.991683) (xy 90.491962 -400.939393) (xy 90.484206 -400.885449)
			(xy 89.046673 -400.885449) (xy 89.046673 -400.885457) (xy 89.038914 -400.939415) (xy 89.023555 -400.991721)
			(xy 89.000908 -401.041307) (xy 88.971434 -401.087166) (xy 88.935733 -401.128363) (xy 88.894532 -401.164059)
			(xy 88.84867 -401.193528) (xy 88.799081 -401.21617) (xy 88.746774 -401.231523) (xy 88.692815 -401.239276)
			(xy 88.665558 -401.239736) (xy 87.801958 -401.239736) (xy 87.774711 -401.239191) (xy 87.720772 -401.23143)
			(xy 87.668486 -401.216073) (xy 87.618918 -401.193431) (xy 87.573076 -401.163965) (xy 87.531894 -401.128277)
			(xy 87.496209 -401.087091) (xy 87.466749 -401.041246) (xy 87.444113 -400.991675) (xy 87.428761 -400.939387)
			(xy 87.421006 -400.885447) (xy 85.98335 -400.885447) (xy 85.98335 -400.885452) (xy 85.975594 -400.939403)
			(xy 85.960238 -400.9917) (xy 85.937597 -401.041279) (xy 85.90813 -401.087132) (xy 85.872438 -401.128325)
			(xy 85.831247 -401.164019) (xy 85.785395 -401.193488) (xy 85.735817 -401.216132) (xy 85.68352 -401.23149)
			(xy 85.62957 -401.239249) (xy 85.602318 -401.239736) (xy 84.738718 -401.239736) (xy 84.711466 -401.239218)
			(xy 84.657517 -401.231464) (xy 84.605221 -401.21611) (xy 84.555642 -401.19347) (xy 84.50979 -401.164005)
			(xy 84.468599 -401.128314) (xy 84.432906 -401.087124) (xy 84.403438 -401.041273) (xy 84.380796 -400.991696)
			(xy 84.36544 -400.9394) (xy 84.357683 -400.885452) (xy 82.920173 -400.885452) (xy 82.920173 -400.885456)
			(xy 82.912415 -400.939413) (xy 82.897057 -400.991716) (xy 82.874411 -401.041302) (xy 82.844939 -401.087159)
			(xy 82.80924 -401.128355) (xy 82.768042 -401.164052) (xy 82.722182 -401.193521) (xy 82.672596 -401.216164)
			(xy 82.620291 -401.23152) (xy 82.566334 -401.239275) (xy 82.539078 -401.239736) (xy 81.675478 -401.239736)
			(xy 81.64823 -401.239192) (xy 81.594288 -401.231434) (xy 81.542 -401.216078) (xy 81.49243 -401.193437)
			(xy 81.446585 -401.163973) (xy 81.405401 -401.128284) (xy 81.369714 -401.087097) (xy 81.340252 -401.041251)
			(xy 81.317614 -400.991679) (xy 81.302262 -400.93939) (xy 81.294506 -400.885448) (xy 79.85685 -400.885448)
			(xy 79.85685 -400.885452) (xy 79.849094 -400.9394) (xy 79.83374 -400.991695) (xy 79.8111 -401.041274)
			(xy 79.781635 -401.087126) (xy 79.745945 -401.128318) (xy 79.704756 -401.164012) (xy 79.658907 -401.193482)
			(xy 79.609331 -401.216127) (xy 79.557037 -401.231486) (xy 79.503089 -401.239248) (xy 79.475838 -401.239736)
			(xy 78.612238 -401.239736) (xy 78.584985 -401.239219) (xy 78.531034 -401.231467) (xy 78.478736 -401.216116)
			(xy 78.429154 -401.193477) (xy 78.3833 -401.164012) (xy 78.342106 -401.128321) (xy 78.306411 -401.087131)
			(xy 78.276941 -401.041279) (xy 78.254298 -400.9917) (xy 78.238941 -400.939403) (xy 78.231183 -400.885453)
			(xy 76.793673 -400.885453) (xy 76.793673 -400.885455) (xy 76.785915 -400.93941) (xy 76.770558 -400.991712)
			(xy 76.747914 -401.041296) (xy 76.718443 -401.087153) (xy 76.682747 -401.128348) (xy 76.641551 -401.164045)
			(xy 76.595694 -401.193515) (xy 76.54611 -401.216159) (xy 76.493808 -401.231516) (xy 76.439853 -401.239273)
			(xy 76.412598 -401.239736) (xy 75.548998 -401.239736) (xy 75.521749 -401.239194) (xy 75.467805 -401.231437)
			(xy 75.415515 -401.216083) (xy 75.365942 -401.193444) (xy 75.320095 -401.16398) (xy 75.278908 -401.128291)
			(xy 75.243219 -401.087104) (xy 75.213755 -401.041257) (xy 75.191116 -400.991683) (xy 75.175762 -400.939393)
			(xy 75.168006 -400.885449) (xy 73.730473 -400.885449) (xy 73.730473 -400.885457) (xy 73.722714 -400.939415)
			(xy 73.707355 -400.991721) (xy 73.684708 -401.041307) (xy 73.655234 -401.087166) (xy 73.619533 -401.128363)
			(xy 73.578332 -401.164059) (xy 73.53247 -401.193528) (xy 73.482881 -401.21617) (xy 73.430574 -401.231523)
			(xy 73.376615 -401.239276) (xy 73.349358 -401.239736) (xy 72.485758 -401.239736) (xy 72.458511 -401.239191)
			(xy 72.404572 -401.23143) (xy 72.352286 -401.216073) (xy 72.302718 -401.193431) (xy 72.256876 -401.163965)
			(xy 72.215694 -401.128277) (xy 72.180009 -401.087091) (xy 72.150549 -401.041246) (xy 72.127913 -400.991675)
			(xy 72.112561 -400.939387) (xy 72.104806 -400.885447) (xy 70.66715 -400.885447) (xy 70.66715 -400.885452)
			(xy 70.659394 -400.939403) (xy 70.644038 -400.9917) (xy 70.621397 -401.041279) (xy 70.59193 -401.087132)
			(xy 70.556238 -401.128325) (xy 70.515047 -401.164019) (xy 70.469195 -401.193488) (xy 70.419617 -401.216132)
			(xy 70.36732 -401.23149) (xy 70.31337 -401.239249) (xy 70.286118 -401.239736) (xy 69.422518 -401.239736)
			(xy 69.395266 -401.239218) (xy 69.341317 -401.231464) (xy 69.289021 -401.21611) (xy 69.239442 -401.19347)
			(xy 69.19359 -401.164005) (xy 69.152399 -401.128314) (xy 69.116706 -401.087124) (xy 69.087238 -401.041273)
			(xy 69.064596 -400.991696) (xy 69.04924 -400.9394) (xy 69.041483 -400.885452) (xy 67.603973 -400.885452)
			(xy 67.603973 -400.885456) (xy 67.596215 -400.939413) (xy 67.580857 -400.991716) (xy 67.558211 -401.041302)
			(xy 67.528739 -401.087159) (xy 67.49304 -401.128355) (xy 67.451842 -401.164052) (xy 67.405982 -401.193521)
			(xy 67.356396 -401.216164) (xy 67.304091 -401.23152) (xy 67.250134 -401.239275) (xy 67.222878 -401.239736)
			(xy 66.359278 -401.239736) (xy 66.33203 -401.239192) (xy 66.278088 -401.231434) (xy 66.2258 -401.216078)
			(xy 66.17623 -401.193437) (xy 66.130385 -401.163973) (xy 66.089201 -401.128284) (xy 66.053514 -401.087097)
			(xy 66.024052 -401.041251) (xy 66.001414 -400.991679) (xy 65.986062 -400.93939) (xy 65.978306 -400.885448)
			(xy 64.54065 -400.885448) (xy 64.54065 -400.885452) (xy 64.532894 -400.9394) (xy 64.51754 -400.991695)
			(xy 64.4949 -401.041274) (xy 64.465435 -401.087126) (xy 64.429745 -401.128318) (xy 64.388556 -401.164012)
			(xy 64.342707 -401.193482) (xy 64.293131 -401.216127) (xy 64.240837 -401.231486) (xy 64.186889 -401.239248)
			(xy 64.159638 -401.239736) (xy 63.296038 -401.239736) (xy 63.268785 -401.239219) (xy 63.214834 -401.231467)
			(xy 63.162536 -401.216116) (xy 63.112954 -401.193477) (xy 63.0671 -401.164012) (xy 63.025906 -401.128321)
			(xy 62.990211 -401.087131) (xy 62.960741 -401.041279) (xy 62.938098 -400.9917) (xy 62.922741 -400.939403)
			(xy 62.914983 -400.885453) (xy 61.477473 -400.885453) (xy 61.477473 -400.885455) (xy 61.469715 -400.93941)
			(xy 61.454358 -400.991712) (xy 61.431714 -401.041296) (xy 61.402243 -401.087153) (xy 61.366547 -401.128348)
			(xy 61.325351 -401.164045) (xy 61.279494 -401.193515) (xy 61.22991 -401.216159) (xy 61.177608 -401.231516)
			(xy 61.123653 -401.239273) (xy 61.096398 -401.239736) (xy 60.232798 -401.239736) (xy 60.205549 -401.239194)
			(xy 60.151605 -401.231437) (xy 60.099315 -401.216083) (xy 60.049742 -401.193444) (xy 60.003895 -401.16398)
			(xy 59.962708 -401.128291) (xy 59.927019 -401.087104) (xy 59.897555 -401.041257) (xy 59.874916 -400.991683)
			(xy 59.859562 -400.939393) (xy 59.851806 -400.885449) (xy 58.414273 -400.885449) (xy 58.414273 -400.885457)
			(xy 58.406514 -400.939415) (xy 58.391155 -400.991721) (xy 58.368508 -401.041307) (xy 58.339034 -401.087166)
			(xy 58.303333 -401.128363) (xy 58.262132 -401.164059) (xy 58.21627 -401.193528) (xy 58.166681 -401.21617)
			(xy 58.114374 -401.231523) (xy 58.060415 -401.239276) (xy 58.033158 -401.239736) (xy 57.169558 -401.239736)
			(xy 57.142311 -401.239191) (xy 57.088372 -401.23143) (xy 57.036086 -401.216073) (xy 56.986518 -401.193431)
			(xy 56.940676 -401.163965) (xy 56.899494 -401.128277) (xy 56.863809 -401.087091) (xy 56.834349 -401.041246)
			(xy 56.811713 -400.991675) (xy 56.796361 -400.939387) (xy 56.788606 -400.885447) (xy 55.35095 -400.885447)
			(xy 55.35095 -400.885452) (xy 55.343194 -400.939403) (xy 55.327838 -400.9917) (xy 55.305197 -401.041279)
			(xy 55.27573 -401.087132) (xy 55.240038 -401.128325) (xy 55.198847 -401.164019) (xy 55.152995 -401.193488)
			(xy 55.103417 -401.216132) (xy 55.05112 -401.23149) (xy 54.99717 -401.239249) (xy 54.969918 -401.239736)
			(xy 54.106318 -401.239736) (xy 54.079066 -401.239218) (xy 54.025117 -401.231464) (xy 53.972821 -401.21611)
			(xy 53.923242 -401.19347) (xy 53.87739 -401.164005) (xy 53.836199 -401.128314) (xy 53.800506 -401.087124)
			(xy 53.771038 -401.041273) (xy 53.748396 -400.991696) (xy 53.73304 -400.9394) (xy 53.725283 -400.885452)
			(xy 52.287773 -400.885452) (xy 52.287773 -400.885456) (xy 52.280015 -400.939413) (xy 52.264657 -400.991716)
			(xy 52.242011 -401.041302) (xy 52.212539 -401.087159) (xy 52.17684 -401.128355) (xy 52.135642 -401.164052)
			(xy 52.089782 -401.193521) (xy 52.040196 -401.216164) (xy 51.987891 -401.23152) (xy 51.933934 -401.239275)
			(xy 51.906678 -401.239736) (xy 51.043078 -401.239736) (xy 51.01583 -401.239192) (xy 50.961888 -401.231434)
			(xy 50.9096 -401.216078) (xy 50.86003 -401.193437) (xy 50.814185 -401.163973) (xy 50.773001 -401.128284)
			(xy 50.737314 -401.087097) (xy 50.707852 -401.041251) (xy 50.685214 -400.991679) (xy 50.669862 -400.93939)
			(xy 50.662106 -400.885448) (xy 49.22445 -400.885448) (xy 49.22445 -400.885452) (xy 49.216694 -400.9394)
			(xy 49.20134 -400.991695) (xy 49.1787 -401.041274) (xy 49.149235 -401.087126) (xy 49.113545 -401.128318)
			(xy 49.072356 -401.164012) (xy 49.026507 -401.193482) (xy 48.976931 -401.216127) (xy 48.924637 -401.231486)
			(xy 48.870689 -401.239248) (xy 48.843438 -401.239736) (xy 47.979838 -401.239736) (xy 47.952585 -401.239219)
			(xy 47.898634 -401.231467) (xy 47.846336 -401.216116) (xy 47.796754 -401.193477) (xy 47.7509 -401.164012)
			(xy 47.709706 -401.128321) (xy 47.674011 -401.087131) (xy 47.644541 -401.041279) (xy 47.621898 -400.9917)
			(xy 47.606541 -400.939403) (xy 47.598783 -400.885453) (xy 2.509012 -400.885453) (xy 2.509012 -402.656674)
			(xy 98.152872 -402.656674) (xy 98.152872 -402.602126) (xy 98.160635 -402.548133) (xy 98.176003 -402.495795)
			(xy 98.198664 -402.446176) (xy 98.228156 -402.400288) (xy 98.263878 -402.359064) (xy 98.305104 -402.323344)
			(xy 98.350994 -402.293855) (xy 98.400613 -402.271196) (xy 98.452953 -402.255831) (xy 98.506946 -402.24807)
			(xy 98.53422 -402.247608) (xy 99.39782 -402.247608) (xy 99.425086 -402.248156) (xy 99.479063 -402.255919)
			(xy 99.531387 -402.271285) (xy 99.58099 -402.293941) (xy 99.626865 -402.323425) (xy 99.668077 -402.359137)
			(xy 99.703787 -402.400351) (xy 99.733269 -402.446227) (xy 99.755922 -402.495832) (xy 99.771285 -402.548156)
			(xy 99.779046 -402.602134) (xy 99.779046 -402.656666) (xy 99.771285 -402.710644) (xy 99.755922 -402.762968)
			(xy 99.733269 -402.812573) (xy 99.703787 -402.858449) (xy 99.668077 -402.899663) (xy 99.626865 -402.935375)
			(xy 99.58099 -402.964859) (xy 99.531387 -402.987515) (xy 99.479063 -403.002881) (xy 99.425086 -403.010644)
			(xy 99.39782 -403.011132) (xy 98.53422 -403.011132) (xy 98.506946 -403.01073) (xy 98.452953 -403.002969)
			(xy 98.400613 -402.987604) (xy 98.350994 -402.964945) (xy 98.305104 -402.935456) (xy 98.263878 -402.899736)
			(xy 98.228156 -402.858512) (xy 98.198664 -402.812624) (xy 98.176003 -402.763005) (xy 98.160635 -402.710667)
			(xy 98.152872 -402.656674) (xy 2.509012 -402.656674) (xy 2.509012 -403.371812) (xy 2.5095 -403.425034)
			(xy 2.517117 -403.531207) (xy 2.532283 -403.636566) (xy 2.554922 -403.740575) (xy 2.584919 -403.842706)
			(xy 2.610452 -403.911156) (xy 47.598731 -403.911156) (xy 47.598731 -403.856644) (xy 47.606489 -403.802686)
			(xy 47.621848 -403.750382) (xy 47.644495 -403.700796) (xy 47.673969 -403.654938) (xy 47.709669 -403.613742)
			(xy 47.750868 -403.578046) (xy 47.796729 -403.548577) (xy 47.846317 -403.525935) (xy 47.898623 -403.510581)
			(xy 47.952582 -403.502828) (xy 47.979838 -403.502368) (xy 48.843438 -403.502368) (xy 48.870686 -403.502905)
			(xy 48.924626 -403.510665) (xy 48.976913 -403.526023) (xy 49.026482 -403.548665) (xy 49.072325 -403.57813)
			(xy 49.113508 -403.613819) (xy 49.149193 -403.655006) (xy 49.178654 -403.700851) (xy 49.201291 -403.750423)
			(xy 49.216643 -403.802711) (xy 49.224398 -403.856652) (xy 49.224398 -403.911148) (xy 49.224397 -403.911152)
			(xy 50.662054 -403.911152) (xy 50.662054 -403.856648) (xy 50.66981 -403.802699) (xy 50.685165 -403.750403)
			(xy 50.707806 -403.700824) (xy 50.737272 -403.654971) (xy 50.772964 -403.613779) (xy 50.814154 -403.578085)
			(xy 50.860004 -403.548617) (xy 50.909582 -403.525973) (xy 50.961877 -403.510615) (xy 51.015826 -403.502855)
			(xy 51.043078 -403.502368) (xy 51.906678 -403.502368) (xy 51.93393 -403.502878) (xy 51.98788 -403.510632)
			(xy 52.040177 -403.525985) (xy 52.089757 -403.548625) (xy 52.13561 -403.57809) (xy 52.176803 -403.613782)
			(xy 52.212497 -403.654972) (xy 52.241965 -403.700824) (xy 52.264607 -403.750402) (xy 52.279964 -403.802698)
			(xy 52.287721 -403.856648) (xy 52.287721 -403.911152) (xy 52.287721 -403.911155) (xy 53.725231 -403.911155)
			(xy 53.725231 -403.856645) (xy 53.732989 -403.802689) (xy 53.748347 -403.750386) (xy 53.770992 -403.700801)
			(xy 53.800464 -403.654945) (xy 53.836162 -403.613749) (xy 53.877359 -403.578053) (xy 53.923217 -403.548583)
			(xy 53.972803 -403.525941) (xy 54.025106 -403.510585) (xy 54.079063 -403.50283) (xy 54.106318 -403.502368)
			(xy 54.969918 -403.502368) (xy 54.997167 -403.502903) (xy 55.051109 -403.510662) (xy 55.103398 -403.526017)
			(xy 55.15297 -403.548658) (xy 55.198815 -403.578123) (xy 55.240001 -403.613812) (xy 55.275688 -403.654999)
			(xy 55.305151 -403.700846) (xy 55.327789 -403.750419) (xy 55.343142 -403.802709) (xy 55.350898 -403.856651)
			(xy 55.350898 -403.911149) (xy 55.350898 -403.911151) (xy 56.788554 -403.911151) (xy 56.788554 -403.856649)
			(xy 56.79631 -403.802702) (xy 56.811664 -403.750407) (xy 56.834303 -403.700829) (xy 56.863767 -403.654978)
			(xy 56.899457 -403.613786) (xy 56.940644 -403.578093) (xy 56.986492 -403.548623) (xy 57.036067 -403.525978)
			(xy 57.08836 -403.510619) (xy 57.142307 -403.502857) (xy 57.169558 -403.502368) (xy 58.033158 -403.502368)
			(xy 58.060411 -403.502876) (xy 58.114363 -403.510628) (xy 58.166663 -403.525979) (xy 58.216245 -403.548618)
			(xy 58.262101 -403.578083) (xy 58.303296 -403.613775) (xy 58.338992 -403.654966) (xy 58.368462 -403.700818)
			(xy 58.391106 -403.750398) (xy 58.406463 -403.802696) (xy 58.414221 -403.856647) (xy 58.414221 -403.911153)
			(xy 59.851754 -403.911153) (xy 59.851754 -403.856647) (xy 59.859511 -403.802696) (xy 59.874867 -403.750398)
			(xy 59.897509 -403.700818) (xy 59.926977 -403.654965) (xy 59.962671 -403.613772) (xy 60.003863 -403.578078)
			(xy 60.049716 -403.54861) (xy 60.099296 -403.525967) (xy 60.151594 -403.510611) (xy 60.205545 -403.502854)
			(xy 60.232798 -403.502368) (xy 61.096398 -403.502368) (xy 61.123649 -403.502879) (xy 61.177597 -403.510635)
			(xy 61.229892 -403.52599) (xy 61.279469 -403.548631) (xy 61.32532 -403.578097) (xy 61.36651 -403.613789)
			(xy 61.402201 -403.654979) (xy 61.431668 -403.700829) (xy 61.454309 -403.750406) (xy 61.469664 -403.802701)
			(xy 61.477421 -403.856649) (xy 61.477421 -403.911151) (xy 61.47742 -403.911156) (xy 62.914931 -403.911156)
			(xy 62.914931 -403.856644) (xy 62.922689 -403.802686) (xy 62.938048 -403.750382) (xy 62.960695 -403.700796)
			(xy 62.990169 -403.654938) (xy 63.025869 -403.613742) (xy 63.067068 -403.578046) (xy 63.112929 -403.548577)
			(xy 63.162517 -403.525935) (xy 63.214823 -403.510581) (xy 63.268782 -403.502828) (xy 63.296038 -403.502368)
			(xy 64.159638 -403.502368) (xy 64.186886 -403.502905) (xy 64.240826 -403.510665) (xy 64.293113 -403.526023)
			(xy 64.342682 -403.548665) (xy 64.388525 -403.57813) (xy 64.429708 -403.613819) (xy 64.465393 -403.655006)
			(xy 64.494854 -403.700851) (xy 64.517491 -403.750423) (xy 64.532843 -403.802711) (xy 64.540598 -403.856652)
			(xy 64.540598 -403.911148) (xy 64.540597 -403.911152) (xy 65.978254 -403.911152) (xy 65.978254 -403.856648)
			(xy 65.98601 -403.802699) (xy 66.001365 -403.750403) (xy 66.024006 -403.700824) (xy 66.053472 -403.654971)
			(xy 66.089164 -403.613779) (xy 66.130354 -403.578085) (xy 66.176204 -403.548617) (xy 66.225782 -403.525973)
			(xy 66.278077 -403.510615) (xy 66.332026 -403.502855) (xy 66.359278 -403.502368) (xy 67.222878 -403.502368)
			(xy 67.25013 -403.502878) (xy 67.30408 -403.510632) (xy 67.356377 -403.525985) (xy 67.405957 -403.548625)
			(xy 67.45181 -403.57809) (xy 67.493003 -403.613782) (xy 67.528697 -403.654972) (xy 67.558165 -403.700824)
			(xy 67.580807 -403.750402) (xy 67.596164 -403.802698) (xy 67.603921 -403.856648) (xy 67.603921 -403.911152)
			(xy 67.603921 -403.911155) (xy 69.041431 -403.911155) (xy 69.041431 -403.856645) (xy 69.049189 -403.802689)
			(xy 69.064547 -403.750386) (xy 69.087192 -403.700801) (xy 69.116664 -403.654945) (xy 69.152362 -403.613749)
			(xy 69.193559 -403.578053) (xy 69.239417 -403.548583) (xy 69.289003 -403.525941) (xy 69.341306 -403.510585)
			(xy 69.395263 -403.50283) (xy 69.422518 -403.502368) (xy 70.286118 -403.502368) (xy 70.313367 -403.502903)
			(xy 70.367309 -403.510662) (xy 70.419598 -403.526017) (xy 70.46917 -403.548658) (xy 70.515015 -403.578123)
			(xy 70.556201 -403.613812) (xy 70.591888 -403.654999) (xy 70.621351 -403.700846) (xy 70.643989 -403.750419)
			(xy 70.659342 -403.802709) (xy 70.667098 -403.856651) (xy 70.667098 -403.911149) (xy 70.667098 -403.911151)
			(xy 72.104754 -403.911151) (xy 72.104754 -403.856649) (xy 72.11251 -403.802702) (xy 72.127864 -403.750407)
			(xy 72.150503 -403.700829) (xy 72.179967 -403.654978) (xy 72.215657 -403.613786) (xy 72.256844 -403.578093)
			(xy 72.302692 -403.548623) (xy 72.352267 -403.525978) (xy 72.40456 -403.510619) (xy 72.458507 -403.502857)
			(xy 72.485758 -403.502368) (xy 73.349358 -403.502368) (xy 73.376611 -403.502876) (xy 73.430563 -403.510628)
			(xy 73.482863 -403.525979) (xy 73.532445 -403.548618) (xy 73.578301 -403.578083) (xy 73.619496 -403.613775)
			(xy 73.655192 -403.654966) (xy 73.684662 -403.700818) (xy 73.707306 -403.750398) (xy 73.722663 -403.802696)
			(xy 73.730421 -403.856647) (xy 73.730421 -403.911153) (xy 75.167954 -403.911153) (xy 75.167954 -403.856647)
			(xy 75.175711 -403.802696) (xy 75.191067 -403.750398) (xy 75.213709 -403.700818) (xy 75.243177 -403.654965)
			(xy 75.278871 -403.613772) (xy 75.320063 -403.578078) (xy 75.365916 -403.54861) (xy 75.415496 -403.525967)
			(xy 75.467794 -403.510611) (xy 75.521745 -403.502854) (xy 75.548998 -403.502368) (xy 76.412598 -403.502368)
			(xy 76.439849 -403.502879) (xy 76.493797 -403.510635) (xy 76.546092 -403.52599) (xy 76.595669 -403.548631)
			(xy 76.64152 -403.578097) (xy 76.68271 -403.613789) (xy 76.718401 -403.654979) (xy 76.747868 -403.700829)
			(xy 76.770509 -403.750406) (xy 76.785864 -403.802701) (xy 76.793621 -403.856649) (xy 76.793621 -403.911151)
			(xy 76.79362 -403.911156) (xy 78.231131 -403.911156) (xy 78.231131 -403.856644) (xy 78.238889 -403.802686)
			(xy 78.254248 -403.750382) (xy 78.276895 -403.700796) (xy 78.306369 -403.654938) (xy 78.342069 -403.613742)
			(xy 78.383268 -403.578046) (xy 78.429129 -403.548577) (xy 78.478717 -403.525935) (xy 78.531023 -403.510581)
			(xy 78.584982 -403.502828) (xy 78.612238 -403.502368) (xy 79.475838 -403.502368) (xy 79.503086 -403.502905)
			(xy 79.557026 -403.510665) (xy 79.609313 -403.526023) (xy 79.658882 -403.548665) (xy 79.704725 -403.57813)
			(xy 79.745908 -403.613819) (xy 79.781593 -403.655006) (xy 79.811054 -403.700851) (xy 79.833691 -403.750423)
			(xy 79.849043 -403.802711) (xy 79.856798 -403.856652) (xy 79.856798 -403.911148) (xy 79.856797 -403.911152)
			(xy 81.294454 -403.911152) (xy 81.294454 -403.856648) (xy 81.30221 -403.802699) (xy 81.317565 -403.750403)
			(xy 81.340206 -403.700824) (xy 81.369672 -403.654971) (xy 81.405364 -403.613779) (xy 81.446554 -403.578085)
			(xy 81.492404 -403.548617) (xy 81.541982 -403.525973) (xy 81.594277 -403.510615) (xy 81.648226 -403.502855)
			(xy 81.675478 -403.502368) (xy 82.539078 -403.502368) (xy 82.56633 -403.502878) (xy 82.62028 -403.510632)
			(xy 82.672577 -403.525985) (xy 82.722157 -403.548625) (xy 82.76801 -403.57809) (xy 82.809203 -403.613782)
			(xy 82.844897 -403.654972) (xy 82.874365 -403.700824) (xy 82.897007 -403.750402) (xy 82.912364 -403.802698)
			(xy 82.920121 -403.856648) (xy 82.920121 -403.911152) (xy 82.920121 -403.911155) (xy 84.357631 -403.911155)
			(xy 84.357631 -403.856645) (xy 84.365389 -403.802689) (xy 84.380747 -403.750386) (xy 84.403392 -403.700801)
			(xy 84.432864 -403.654945) (xy 84.468562 -403.613749) (xy 84.509759 -403.578053) (xy 84.555617 -403.548583)
			(xy 84.605203 -403.525941) (xy 84.657506 -403.510585) (xy 84.711463 -403.50283) (xy 84.738718 -403.502368)
			(xy 85.602318 -403.502368) (xy 85.629567 -403.502903) (xy 85.683509 -403.510662) (xy 85.735798 -403.526017)
			(xy 85.78537 -403.548658) (xy 85.831215 -403.578123) (xy 85.872401 -403.613812) (xy 85.908088 -403.654999)
			(xy 85.937551 -403.700846) (xy 85.960189 -403.750419) (xy 85.975542 -403.802709) (xy 85.983298 -403.856651)
			(xy 85.983298 -403.911149) (xy 85.983298 -403.911151) (xy 87.420954 -403.911151) (xy 87.420954 -403.856649)
			(xy 87.42871 -403.802702) (xy 87.444064 -403.750407) (xy 87.466703 -403.700829) (xy 87.496167 -403.654978)
			(xy 87.531857 -403.613786) (xy 87.573044 -403.578093) (xy 87.618892 -403.548623) (xy 87.668467 -403.525978)
			(xy 87.72076 -403.510619) (xy 87.774707 -403.502857) (xy 87.801958 -403.502368) (xy 88.665558 -403.502368)
			(xy 88.692811 -403.502876) (xy 88.746763 -403.510628) (xy 88.799063 -403.525979) (xy 88.848645 -403.548618)
			(xy 88.894501 -403.578083) (xy 88.935696 -403.613775) (xy 88.971392 -403.654966) (xy 89.000862 -403.700818)
			(xy 89.023506 -403.750398) (xy 89.038863 -403.802696) (xy 89.046621 -403.856647) (xy 89.046621 -403.911153)
			(xy 90.484154 -403.911153) (xy 90.484154 -403.856647) (xy 90.491911 -403.802696) (xy 90.507267 -403.750398)
			(xy 90.529909 -403.700818) (xy 90.559377 -403.654965) (xy 90.595071 -403.613772) (xy 90.636263 -403.578078)
			(xy 90.682116 -403.54861) (xy 90.731696 -403.525967) (xy 90.783994 -403.510611) (xy 90.837945 -403.502854)
			(xy 90.865198 -403.502368) (xy 91.728798 -403.502368) (xy 91.756049 -403.502879) (xy 91.809997 -403.510635)
			(xy 91.862292 -403.52599) (xy 91.911869 -403.548631) (xy 91.95772 -403.578097) (xy 91.99891 -403.613789)
			(xy 92.034601 -403.654979) (xy 92.064068 -403.700829) (xy 92.086709 -403.750406) (xy 92.102064 -403.802701)
			(xy 92.109821 -403.856649) (xy 92.109821 -403.911151) (xy 92.10982 -403.911156) (xy 93.547331 -403.911156)
			(xy 93.547331 -403.856644) (xy 93.555089 -403.802686) (xy 93.570448 -403.750382) (xy 93.593095 -403.700796)
			(xy 93.622569 -403.654938) (xy 93.658269 -403.613742) (xy 93.699468 -403.578046) (xy 93.745329 -403.548577)
			(xy 93.794917 -403.525935) (xy 93.847223 -403.510581) (xy 93.901182 -403.502828) (xy 93.928438 -403.502368)
			(xy 94.792038 -403.502368) (xy 94.819286 -403.502905) (xy 94.873226 -403.510665) (xy 94.925513 -403.526023)
			(xy 94.975082 -403.548665) (xy 95.020925 -403.57813) (xy 95.062108 -403.613819) (xy 95.097793 -403.655006)
			(xy 95.127254 -403.700851) (xy 95.149891 -403.750423) (xy 95.165243 -403.802711) (xy 95.172998 -403.856652)
			(xy 95.172998 -403.911148) (xy 95.172998 -403.911151) (xy 119.773954 -403.911151) (xy 119.773954 -403.856649)
			(xy 119.78171 -403.802702) (xy 119.797063 -403.750408) (xy 119.819702 -403.70083) (xy 119.849166 -403.654979)
			(xy 119.884855 -403.613788) (xy 119.926042 -403.578094) (xy 119.97189 -403.548625) (xy 120.021465 -403.525979)
			(xy 120.073757 -403.510619) (xy 120.127703 -403.502857) (xy 120.154954 -403.502368) (xy 121.018554 -403.502368)
			(xy 121.045807 -403.502876) (xy 121.09976 -403.510627) (xy 121.15206 -403.525978) (xy 121.201643 -403.548617)
			(xy 121.247499 -403.578082) (xy 121.288694 -403.613773) (xy 121.324391 -403.654964) (xy 121.353861 -403.700817)
			(xy 121.376506 -403.750397) (xy 121.391863 -403.802695) (xy 121.399621 -403.856647) (xy 121.399621 -403.911153)
			(xy 122.837154 -403.911153) (xy 122.837154 -403.856647) (xy 122.844911 -403.802697) (xy 122.860266 -403.750399)
			(xy 122.882909 -403.700819) (xy 122.912376 -403.654966) (xy 122.948069 -403.613774) (xy 122.989261 -403.57808)
			(xy 123.035114 -403.548611) (xy 123.084694 -403.525969) (xy 123.136991 -403.510612) (xy 123.190941 -403.502854)
			(xy 123.218194 -403.502368) (xy 124.081794 -403.502368) (xy 124.109045 -403.502879) (xy 124.162994 -403.510635)
			(xy 124.215289 -403.525989) (xy 124.264867 -403.54863) (xy 124.310718 -403.578096) (xy 124.351908 -403.613787)
			(xy 124.3876 -403.654978) (xy 124.417067 -403.700828) (xy 124.439709 -403.750406) (xy 124.455064 -403.802701)
			(xy 124.462821 -403.856649) (xy 124.462821 -403.911151) (xy 124.46282 -403.911156) (xy 125.900331 -403.911156)
			(xy 125.900331 -403.856644) (xy 125.908089 -403.802686) (xy 125.923448 -403.750383) (xy 125.946095 -403.700797)
			(xy 125.975568 -403.654939) (xy 126.011267 -403.613743) (xy 126.052467 -403.578047) (xy 126.098327 -403.548578)
			(xy 126.147914 -403.525936) (xy 126.20022 -403.510582) (xy 126.254178 -403.502829) (xy 126.281434 -403.502368)
			(xy 127.145034 -403.502368) (xy 127.172282 -403.502905) (xy 127.226223 -403.510664) (xy 127.27851 -403.526022)
			(xy 127.32808 -403.548663) (xy 127.373923 -403.578129) (xy 127.415106 -403.613818) (xy 127.450792 -403.655004)
			(xy 127.480253 -403.70085) (xy 127.50289 -403.750422) (xy 127.518243 -403.802711) (xy 127.525998 -403.856652)
			(xy 127.525998 -403.911148) (xy 127.525997 -403.911152) (xy 128.963654 -403.911152) (xy 128.963654 -403.856648)
			(xy 128.97141 -403.802699) (xy 128.986765 -403.750403) (xy 129.009406 -403.700825) (xy 129.038871 -403.654973)
			(xy 129.074562 -403.613781) (xy 129.115752 -403.578087) (xy 129.161602 -403.548618) (xy 129.211179 -403.525974)
			(xy 129.263474 -403.510616) (xy 129.317422 -403.502856) (xy 129.344674 -403.502368) (xy 130.208274 -403.502368)
			(xy 130.235526 -403.502878) (xy 130.289477 -403.510631) (xy 130.341774 -403.525984) (xy 130.391355 -403.548623)
			(xy 130.437208 -403.578089) (xy 130.478401 -403.61378) (xy 130.514096 -403.654971) (xy 130.543564 -403.700822)
			(xy 130.566207 -403.750401) (xy 130.581563 -403.802698) (xy 130.589321 -403.856648) (xy 130.589321 -403.911152)
			(xy 130.589321 -403.911155) (xy 132.026831 -403.911155) (xy 132.026831 -403.856645) (xy 132.034589 -403.802689)
			(xy 132.049946 -403.750387) (xy 132.072591 -403.700803) (xy 132.102063 -403.654946) (xy 132.13776 -403.61375)
			(xy 132.178957 -403.578054) (xy 132.224815 -403.548585) (xy 132.2744 -403.525942) (xy 132.326703 -403.510586)
			(xy 132.380659 -403.50283) (xy 132.407914 -403.502368) (xy 133.271514 -403.502368) (xy 133.298763 -403.502903)
			(xy 133.352706 -403.510661) (xy 133.404995 -403.526016) (xy 133.454568 -403.548657) (xy 133.500413 -403.578121)
			(xy 133.541599 -403.613811) (xy 133.577287 -403.654998) (xy 133.60675 -403.700845) (xy 133.629389 -403.750418)
			(xy 133.644742 -403.802708) (xy 133.652498 -403.856651) (xy 133.652498 -403.911149) (xy 133.652498 -403.911151)
			(xy 135.090154 -403.911151) (xy 135.090154 -403.856649) (xy 135.09791 -403.802702) (xy 135.113263 -403.750408)
			(xy 135.135902 -403.70083) (xy 135.165366 -403.654979) (xy 135.201055 -403.613788) (xy 135.242242 -403.578094)
			(xy 135.28809 -403.548625) (xy 135.337665 -403.525979) (xy 135.389957 -403.510619) (xy 135.443903 -403.502857)
			(xy 135.471154 -403.502368) (xy 136.334754 -403.502368) (xy 136.362007 -403.502876) (xy 136.41596 -403.510627)
			(xy 136.46826 -403.525978) (xy 136.517843 -403.548617) (xy 136.563699 -403.578082) (xy 136.604894 -403.613773)
			(xy 136.640591 -403.654964) (xy 136.670061 -403.700817) (xy 136.692706 -403.750397) (xy 136.708063 -403.802695)
			(xy 136.715821 -403.856647) (xy 136.715821 -403.911153) (xy 138.153354 -403.911153) (xy 138.153354 -403.856647)
			(xy 138.161111 -403.802697) (xy 138.176466 -403.750399) (xy 138.199109 -403.700819) (xy 138.228576 -403.654966)
			(xy 138.264269 -403.613774) (xy 138.305461 -403.57808) (xy 138.351314 -403.548611) (xy 138.400894 -403.525969)
			(xy 138.453191 -403.510612) (xy 138.507141 -403.502854) (xy 138.534394 -403.502368) (xy 139.397994 -403.502368)
			(xy 139.425245 -403.502879) (xy 139.479194 -403.510635) (xy 139.531489 -403.525989) (xy 139.581067 -403.54863)
			(xy 139.626918 -403.578096) (xy 139.668108 -403.613787) (xy 139.7038 -403.654978) (xy 139.733267 -403.700828)
			(xy 139.755909 -403.750406) (xy 139.771264 -403.802701) (xy 139.779021 -403.856649) (xy 139.779021 -403.911151)
			(xy 139.77902 -403.911156) (xy 141.216531 -403.911156) (xy 141.216531 -403.856644) (xy 141.224289 -403.802686)
			(xy 141.239648 -403.750383) (xy 141.262295 -403.700797) (xy 141.291768 -403.654939) (xy 141.327467 -403.613743)
			(xy 141.368667 -403.578047) (xy 141.414527 -403.548578) (xy 141.464114 -403.525936) (xy 141.51642 -403.510582)
			(xy 141.570378 -403.502829) (xy 141.597634 -403.502368) (xy 142.461234 -403.502368) (xy 142.488482 -403.502905)
			(xy 142.542423 -403.510664) (xy 142.59471 -403.526022) (xy 142.64428 -403.548663) (xy 142.690123 -403.578129)
			(xy 142.731306 -403.613818) (xy 142.766992 -403.655004) (xy 142.796453 -403.70085) (xy 142.81909 -403.750422)
			(xy 142.834443 -403.802711) (xy 142.842198 -403.856652) (xy 142.842198 -403.911148) (xy 142.842197 -403.911152)
			(xy 144.279854 -403.911152) (xy 144.279854 -403.856648) (xy 144.28761 -403.802699) (xy 144.302965 -403.750403)
			(xy 144.325606 -403.700825) (xy 144.355071 -403.654973) (xy 144.390762 -403.613781) (xy 144.431952 -403.578087)
			(xy 144.477802 -403.548618) (xy 144.527379 -403.525974) (xy 144.579674 -403.510616) (xy 144.633622 -403.502856)
			(xy 144.660874 -403.502368) (xy 145.524474 -403.502368) (xy 145.551726 -403.502878) (xy 145.605677 -403.510631)
			(xy 145.657974 -403.525984) (xy 145.707555 -403.548623) (xy 145.753408 -403.578089) (xy 145.794601 -403.61378)
			(xy 145.830296 -403.654971) (xy 145.859764 -403.700822) (xy 145.882407 -403.750401) (xy 145.897763 -403.802698)
			(xy 145.905521 -403.856648) (xy 145.905521 -403.911152) (xy 145.905521 -403.911155) (xy 147.343031 -403.911155)
			(xy 147.343031 -403.856645) (xy 147.350789 -403.802689) (xy 147.366146 -403.750387) (xy 147.388791 -403.700803)
			(xy 147.418263 -403.654946) (xy 147.45396 -403.61375) (xy 147.495157 -403.578054) (xy 147.541015 -403.548585)
			(xy 147.5906 -403.525942) (xy 147.642903 -403.510586) (xy 147.696859 -403.50283) (xy 147.724114 -403.502368)
			(xy 148.587714 -403.502368) (xy 148.614963 -403.502903) (xy 148.668906 -403.510661) (xy 148.721195 -403.526016)
			(xy 148.770768 -403.548657) (xy 148.816613 -403.578121) (xy 148.857799 -403.613811) (xy 148.893487 -403.654998)
			(xy 148.92295 -403.700845) (xy 148.945589 -403.750418) (xy 148.960942 -403.802708) (xy 148.968698 -403.856651)
			(xy 148.968698 -403.911149) (xy 148.968698 -403.911151) (xy 150.406354 -403.911151) (xy 150.406354 -403.856649)
			(xy 150.41411 -403.802702) (xy 150.429463 -403.750408) (xy 150.452102 -403.70083) (xy 150.481566 -403.654979)
			(xy 150.517255 -403.613788) (xy 150.558442 -403.578094) (xy 150.60429 -403.548625) (xy 150.653865 -403.525979)
			(xy 150.706157 -403.510619) (xy 150.760103 -403.502857) (xy 150.787354 -403.502368) (xy 151.650954 -403.502368)
			(xy 151.678207 -403.502876) (xy 151.73216 -403.510627) (xy 151.78446 -403.525978) (xy 151.834043 -403.548617)
			(xy 151.879899 -403.578082) (xy 151.921094 -403.613773) (xy 151.956791 -403.654964) (xy 151.986261 -403.700817)
			(xy 152.008906 -403.750397) (xy 152.024263 -403.802695) (xy 152.032021 -403.856647) (xy 152.032021 -403.911153)
			(xy 153.469554 -403.911153) (xy 153.469554 -403.856647) (xy 153.477311 -403.802697) (xy 153.492666 -403.750399)
			(xy 153.515309 -403.700819) (xy 153.544776 -403.654966) (xy 153.580469 -403.613774) (xy 153.621661 -403.57808)
			(xy 153.667514 -403.548611) (xy 153.717094 -403.525969) (xy 153.769391 -403.510612) (xy 153.823341 -403.502854)
			(xy 153.850594 -403.502368) (xy 154.714194 -403.502368) (xy 154.741445 -403.502879) (xy 154.795394 -403.510635)
			(xy 154.847689 -403.525989) (xy 154.897267 -403.54863) (xy 154.943118 -403.578096) (xy 154.984308 -403.613787)
			(xy 155.02 -403.654978) (xy 155.049467 -403.700828) (xy 155.072109 -403.750406) (xy 155.087464 -403.802701)
			(xy 155.095221 -403.856649) (xy 155.095221 -403.911151) (xy 155.09522 -403.911156) (xy 156.532731 -403.911156)
			(xy 156.532731 -403.856644) (xy 156.540489 -403.802686) (xy 156.555848 -403.750383) (xy 156.578495 -403.700797)
			(xy 156.607968 -403.654939) (xy 156.643667 -403.613743) (xy 156.684867 -403.578047) (xy 156.730727 -403.548578)
			(xy 156.780314 -403.525936) (xy 156.83262 -403.510582) (xy 156.886578 -403.502829) (xy 156.913834 -403.502368)
			(xy 157.777434 -403.502368) (xy 157.804682 -403.502905) (xy 157.858623 -403.510664) (xy 157.91091 -403.526022)
			(xy 157.96048 -403.548663) (xy 158.006323 -403.578129) (xy 158.047506 -403.613818) (xy 158.083192 -403.655004)
			(xy 158.112653 -403.70085) (xy 158.13529 -403.750422) (xy 158.150643 -403.802711) (xy 158.158398 -403.856652)
			(xy 158.158398 -403.911148) (xy 158.158397 -403.911152) (xy 159.596054 -403.911152) (xy 159.596054 -403.856648)
			(xy 159.60381 -403.802699) (xy 159.619165 -403.750403) (xy 159.641806 -403.700825) (xy 159.671271 -403.654973)
			(xy 159.706962 -403.613781) (xy 159.748152 -403.578087) (xy 159.794002 -403.548618) (xy 159.843579 -403.525974)
			(xy 159.895874 -403.510616) (xy 159.949822 -403.502856) (xy 159.977074 -403.502368) (xy 160.840674 -403.502368)
			(xy 160.867926 -403.502878) (xy 160.921877 -403.510631) (xy 160.974174 -403.525984) (xy 161.023755 -403.548623)
			(xy 161.069608 -403.578089) (xy 161.110801 -403.61378) (xy 161.146496 -403.654971) (xy 161.175964 -403.700822)
			(xy 161.198607 -403.750401) (xy 161.213963 -403.802698) (xy 161.221721 -403.856648) (xy 161.221721 -403.911152)
			(xy 161.221721 -403.911155) (xy 162.659231 -403.911155) (xy 162.659231 -403.856645) (xy 162.666989 -403.802689)
			(xy 162.682346 -403.750387) (xy 162.704991 -403.700803) (xy 162.734463 -403.654946) (xy 162.77016 -403.61375)
			(xy 162.811357 -403.578054) (xy 162.857215 -403.548585) (xy 162.9068 -403.525942) (xy 162.959103 -403.510586)
			(xy 163.013059 -403.50283) (xy 163.040314 -403.502368) (xy 163.903914 -403.502368) (xy 163.931163 -403.502903)
			(xy 163.985106 -403.510661) (xy 164.037395 -403.526016) (xy 164.086968 -403.548657) (xy 164.132813 -403.578121)
			(xy 164.173999 -403.613811) (xy 164.209687 -403.654998) (xy 164.23915 -403.700845) (xy 164.261789 -403.750418)
			(xy 164.277142 -403.802708) (xy 164.284898 -403.856651) (xy 164.284898 -403.911149) (xy 164.284898 -403.911151)
			(xy 165.722554 -403.911151) (xy 165.722554 -403.856649) (xy 165.73031 -403.802702) (xy 165.745663 -403.750408)
			(xy 165.768302 -403.70083) (xy 165.797766 -403.654979) (xy 165.833455 -403.613788) (xy 165.874642 -403.578094)
			(xy 165.92049 -403.548625) (xy 165.970065 -403.525979) (xy 166.022357 -403.510619) (xy 166.076303 -403.502857)
			(xy 166.103554 -403.502368) (xy 166.967154 -403.502368) (xy 166.994407 -403.502876) (xy 167.04836 -403.510627)
			(xy 167.10066 -403.525978) (xy 167.150243 -403.548617) (xy 167.196099 -403.578082) (xy 167.237294 -403.613773)
			(xy 167.272991 -403.654964) (xy 167.302461 -403.700817) (xy 167.325106 -403.750397) (xy 167.340463 -403.802695)
			(xy 167.348221 -403.856647) (xy 167.348221 -403.911153) (xy 167.340463 -403.965105) (xy 167.325106 -404.017403)
			(xy 167.302461 -404.066983) (xy 167.272991 -404.112836) (xy 167.237294 -404.154027) (xy 167.196099 -404.189718)
			(xy 167.150243 -404.219183) (xy 167.10066 -404.241822) (xy 167.04836 -404.257173) (xy 166.994407 -404.264924)
			(xy 166.967154 -404.265384) (xy 166.103554 -404.265384) (xy 166.076303 -404.264943) (xy 166.022357 -404.257181)
			(xy 165.970065 -404.241821) (xy 165.92049 -404.219175) (xy 165.874642 -404.189706) (xy 165.833455 -404.154012)
			(xy 165.797766 -404.112821) (xy 165.768302 -404.06697) (xy 165.745663 -404.017392) (xy 165.73031 -403.965098)
			(xy 165.722554 -403.911151) (xy 164.284898 -403.911151) (xy 164.277142 -403.965092) (xy 164.261789 -404.017382)
			(xy 164.23915 -404.066955) (xy 164.209687 -404.112802) (xy 164.173999 -404.153989) (xy 164.132813 -404.189679)
			(xy 164.086968 -404.219143) (xy 164.037395 -404.241784) (xy 163.985106 -404.257139) (xy 163.931163 -404.264897)
			(xy 163.903914 -404.265384) (xy 163.040314 -404.265384) (xy 163.013059 -404.26497) (xy 162.959103 -404.257214)
			(xy 162.9068 -404.241858) (xy 162.857215 -404.219215) (xy 162.811357 -404.189746) (xy 162.77016 -404.15405)
			(xy 162.734463 -404.112854) (xy 162.704991 -404.066997) (xy 162.682346 -404.017413) (xy 162.666989 -403.965111)
			(xy 162.659231 -403.911155) (xy 161.221721 -403.911155) (xy 161.213963 -403.965102) (xy 161.198607 -404.017399)
			(xy 161.175964 -404.066978) (xy 161.146496 -404.112829) (xy 161.110801 -404.15402) (xy 161.069608 -404.189711)
			(xy 161.023755 -404.219177) (xy 160.974174 -404.241816) (xy 160.921877 -404.257169) (xy 160.867926 -404.264922)
			(xy 160.840674 -404.265384) (xy 159.977074 -404.265384) (xy 159.949822 -404.264944) (xy 159.895874 -404.257184)
			(xy 159.843579 -404.241826) (xy 159.794002 -404.219182) (xy 159.748152 -404.189713) (xy 159.706962 -404.154019)
			(xy 159.671271 -404.112827) (xy 159.641806 -404.066975) (xy 159.619165 -404.017397) (xy 159.60381 -403.965101)
			(xy 159.596054 -403.911152) (xy 158.158397 -403.911152) (xy 158.150643 -403.965089) (xy 158.13529 -404.017378)
			(xy 158.112653 -404.06695) (xy 158.083192 -404.112796) (xy 158.047506 -404.153982) (xy 158.006323 -404.189671)
			(xy 157.96048 -404.219137) (xy 157.91091 -404.241778) (xy 157.858623 -404.257136) (xy 157.804682 -404.264895)
			(xy 157.777434 -404.265384) (xy 156.913834 -404.265384) (xy 156.886578 -404.264971) (xy 156.83262 -404.257218)
			(xy 156.780314 -404.241864) (xy 156.730727 -404.219222) (xy 156.684867 -404.189753) (xy 156.643667 -404.154057)
			(xy 156.607968 -404.112861) (xy 156.578495 -404.067003) (xy 156.555848 -404.017417) (xy 156.540489 -403.965114)
			(xy 156.532731 -403.911156) (xy 155.09522 -403.911156) (xy 155.087464 -403.965099) (xy 155.072109 -404.017394)
			(xy 155.049467 -404.066972) (xy 155.02 -404.112822) (xy 154.984308 -404.154013) (xy 154.943118 -404.189704)
			(xy 154.897267 -404.21917) (xy 154.847689 -404.241811) (xy 154.795394 -404.257165) (xy 154.741445 -404.264921)
			(xy 154.714194 -404.265384) (xy 153.850594 -404.265384) (xy 153.823341 -404.264946) (xy 153.769391 -404.257188)
			(xy 153.717094 -404.241831) (xy 153.667514 -404.219189) (xy 153.621661 -404.18972) (xy 153.580469 -404.154026)
			(xy 153.544776 -404.112834) (xy 153.515309 -404.066981) (xy 153.492666 -404.017401) (xy 153.477311 -403.965103)
			(xy 153.469554 -403.911153) (xy 152.032021 -403.911153) (xy 152.024263 -403.965105) (xy 152.008906 -404.017403)
			(xy 151.986261 -404.066983) (xy 151.956791 -404.112836) (xy 151.921094 -404.154027) (xy 151.879899 -404.189718)
			(xy 151.834043 -404.219183) (xy 151.78446 -404.241822) (xy 151.73216 -404.257173) (xy 151.678207 -404.264924)
			(xy 151.650954 -404.265384) (xy 150.787354 -404.265384) (xy 150.760103 -404.264943) (xy 150.706157 -404.257181)
			(xy 150.653865 -404.241821) (xy 150.60429 -404.219175) (xy 150.558442 -404.189706) (xy 150.517255 -404.154012)
			(xy 150.481566 -404.112821) (xy 150.452102 -404.06697) (xy 150.429463 -404.017392) (xy 150.41411 -403.965098)
			(xy 150.406354 -403.911151) (xy 148.968698 -403.911151) (xy 148.960942 -403.965092) (xy 148.945589 -404.017382)
			(xy 148.92295 -404.066955) (xy 148.893487 -404.112802) (xy 148.857799 -404.153989) (xy 148.816613 -404.189679)
			(xy 148.770768 -404.219143) (xy 148.721195 -404.241784) (xy 148.668906 -404.257139) (xy 148.614963 -404.264897)
			(xy 148.587714 -404.265384) (xy 147.724114 -404.265384) (xy 147.696859 -404.26497) (xy 147.642903 -404.257214)
			(xy 147.5906 -404.241858) (xy 147.541015 -404.219215) (xy 147.495157 -404.189746) (xy 147.45396 -404.15405)
			(xy 147.418263 -404.112854) (xy 147.388791 -404.066997) (xy 147.366146 -404.017413) (xy 147.350789 -403.965111)
			(xy 147.343031 -403.911155) (xy 145.905521 -403.911155) (xy 145.897763 -403.965102) (xy 145.882407 -404.017399)
			(xy 145.859764 -404.066978) (xy 145.830296 -404.112829) (xy 145.794601 -404.15402) (xy 145.753408 -404.189711)
			(xy 145.707555 -404.219177) (xy 145.657974 -404.241816) (xy 145.605677 -404.257169) (xy 145.551726 -404.264922)
			(xy 145.524474 -404.265384) (xy 144.660874 -404.265384) (xy 144.633622 -404.264944) (xy 144.579674 -404.257184)
			(xy 144.527379 -404.241826) (xy 144.477802 -404.219182) (xy 144.431952 -404.189713) (xy 144.390762 -404.154019)
			(xy 144.355071 -404.112827) (xy 144.325606 -404.066975) (xy 144.302965 -404.017397) (xy 144.28761 -403.965101)
			(xy 144.279854 -403.911152) (xy 142.842197 -403.911152) (xy 142.834443 -403.965089) (xy 142.81909 -404.017378)
			(xy 142.796453 -404.06695) (xy 142.766992 -404.112796) (xy 142.731306 -404.153982) (xy 142.690123 -404.189671)
			(xy 142.64428 -404.219137) (xy 142.59471 -404.241778) (xy 142.542423 -404.257136) (xy 142.488482 -404.264895)
			(xy 142.461234 -404.265384) (xy 141.597634 -404.265384) (xy 141.570378 -404.264971) (xy 141.51642 -404.257218)
			(xy 141.464114 -404.241864) (xy 141.414527 -404.219222) (xy 141.368667 -404.189753) (xy 141.327467 -404.154057)
			(xy 141.291768 -404.112861) (xy 141.262295 -404.067003) (xy 141.239648 -404.017417) (xy 141.224289 -403.965114)
			(xy 141.216531 -403.911156) (xy 139.77902 -403.911156) (xy 139.771264 -403.965099) (xy 139.755909 -404.017394)
			(xy 139.733267 -404.066972) (xy 139.7038 -404.112822) (xy 139.668108 -404.154013) (xy 139.626918 -404.189704)
			(xy 139.581067 -404.21917) (xy 139.531489 -404.241811) (xy 139.479194 -404.257165) (xy 139.425245 -404.264921)
			(xy 139.397994 -404.265384) (xy 138.534394 -404.265384) (xy 138.507141 -404.264946) (xy 138.453191 -404.257188)
			(xy 138.400894 -404.241831) (xy 138.351314 -404.219189) (xy 138.305461 -404.18972) (xy 138.264269 -404.154026)
			(xy 138.228576 -404.112834) (xy 138.199109 -404.066981) (xy 138.176466 -404.017401) (xy 138.161111 -403.965103)
			(xy 138.153354 -403.911153) (xy 136.715821 -403.911153) (xy 136.708063 -403.965105) (xy 136.692706 -404.017403)
			(xy 136.670061 -404.066983) (xy 136.640591 -404.112836) (xy 136.604894 -404.154027) (xy 136.563699 -404.189718)
			(xy 136.517843 -404.219183) (xy 136.46826 -404.241822) (xy 136.41596 -404.257173) (xy 136.362007 -404.264924)
			(xy 136.334754 -404.265384) (xy 135.471154 -404.265384) (xy 135.443903 -404.264943) (xy 135.389957 -404.257181)
			(xy 135.337665 -404.241821) (xy 135.28809 -404.219175) (xy 135.242242 -404.189706) (xy 135.201055 -404.154012)
			(xy 135.165366 -404.112821) (xy 135.135902 -404.06697) (xy 135.113263 -404.017392) (xy 135.09791 -403.965098)
			(xy 135.090154 -403.911151) (xy 133.652498 -403.911151) (xy 133.644742 -403.965092) (xy 133.629389 -404.017382)
			(xy 133.60675 -404.066955) (xy 133.577287 -404.112802) (xy 133.541599 -404.153989) (xy 133.500413 -404.189679)
			(xy 133.454568 -404.219143) (xy 133.404995 -404.241784) (xy 133.352706 -404.257139) (xy 133.298763 -404.264897)
			(xy 133.271514 -404.265384) (xy 132.407914 -404.265384) (xy 132.380659 -404.26497) (xy 132.326703 -404.257214)
			(xy 132.2744 -404.241858) (xy 132.224815 -404.219215) (xy 132.178957 -404.189746) (xy 132.13776 -404.15405)
			(xy 132.102063 -404.112854) (xy 132.072591 -404.066997) (xy 132.049946 -404.017413) (xy 132.034589 -403.965111)
			(xy 132.026831 -403.911155) (xy 130.589321 -403.911155) (xy 130.581563 -403.965102) (xy 130.566207 -404.017399)
			(xy 130.543564 -404.066978) (xy 130.514096 -404.112829) (xy 130.478401 -404.15402) (xy 130.437208 -404.189711)
			(xy 130.391355 -404.219177) (xy 130.341774 -404.241816) (xy 130.289477 -404.257169) (xy 130.235526 -404.264922)
			(xy 130.208274 -404.265384) (xy 129.344674 -404.265384) (xy 129.317422 -404.264944) (xy 129.263474 -404.257184)
			(xy 129.211179 -404.241826) (xy 129.161602 -404.219182) (xy 129.115752 -404.189713) (xy 129.074562 -404.154019)
			(xy 129.038871 -404.112827) (xy 129.009406 -404.066975) (xy 128.986765 -404.017397) (xy 128.97141 -403.965101)
			(xy 128.963654 -403.911152) (xy 127.525997 -403.911152) (xy 127.518243 -403.965089) (xy 127.50289 -404.017378)
			(xy 127.480253 -404.06695) (xy 127.450792 -404.112796) (xy 127.415106 -404.153982) (xy 127.373923 -404.189671)
			(xy 127.32808 -404.219137) (xy 127.27851 -404.241778) (xy 127.226223 -404.257136) (xy 127.172282 -404.264895)
			(xy 127.145034 -404.265384) (xy 126.281434 -404.265384) (xy 126.254178 -404.264971) (xy 126.20022 -404.257218)
			(xy 126.147914 -404.241864) (xy 126.098327 -404.219222) (xy 126.052467 -404.189753) (xy 126.011267 -404.154057)
			(xy 125.975568 -404.112861) (xy 125.946095 -404.067003) (xy 125.923448 -404.017417) (xy 125.908089 -403.965114)
			(xy 125.900331 -403.911156) (xy 124.46282 -403.911156) (xy 124.455064 -403.965099) (xy 124.439709 -404.017394)
			(xy 124.417067 -404.066972) (xy 124.3876 -404.112822) (xy 124.351908 -404.154013) (xy 124.310718 -404.189704)
			(xy 124.264867 -404.21917) (xy 124.215289 -404.241811) (xy 124.162994 -404.257165) (xy 124.109045 -404.264921)
			(xy 124.081794 -404.265384) (xy 123.218194 -404.265384) (xy 123.190941 -404.264946) (xy 123.136991 -404.257188)
			(xy 123.084694 -404.241831) (xy 123.035114 -404.219189) (xy 122.989261 -404.18972) (xy 122.948069 -404.154026)
			(xy 122.912376 -404.112834) (xy 122.882909 -404.066981) (xy 122.860266 -404.017401) (xy 122.844911 -403.965103)
			(xy 122.837154 -403.911153) (xy 121.399621 -403.911153) (xy 121.391863 -403.965105) (xy 121.376506 -404.017403)
			(xy 121.353861 -404.066983) (xy 121.324391 -404.112836) (xy 121.288694 -404.154027) (xy 121.247499 -404.189718)
			(xy 121.201643 -404.219183) (xy 121.15206 -404.241822) (xy 121.09976 -404.257173) (xy 121.045807 -404.264924)
			(xy 121.018554 -404.265384) (xy 120.154954 -404.265384) (xy 120.127703 -404.264943) (xy 120.073757 -404.257181)
			(xy 120.021465 -404.241821) (xy 119.97189 -404.219175) (xy 119.926042 -404.189706) (xy 119.884855 -404.154012)
			(xy 119.849166 -404.112821) (xy 119.819702 -404.06697) (xy 119.797063 -404.017392) (xy 119.78171 -403.965098)
			(xy 119.773954 -403.911151) (xy 95.172998 -403.911151) (xy 95.165243 -403.965089) (xy 95.149891 -404.017377)
			(xy 95.127254 -404.066949) (xy 95.097793 -404.112794) (xy 95.062108 -404.153981) (xy 95.020925 -404.18967)
			(xy 94.975082 -404.219135) (xy 94.925513 -404.241777) (xy 94.873226 -404.257135) (xy 94.819286 -404.264895)
			(xy 94.792038 -404.265384) (xy 93.928438 -404.265384) (xy 93.901182 -404.264972) (xy 93.847223 -404.257219)
			(xy 93.794917 -404.241865) (xy 93.745329 -404.219223) (xy 93.699468 -404.189754) (xy 93.658269 -404.154058)
			(xy 93.622569 -404.112862) (xy 93.593095 -404.067004) (xy 93.570448 -404.017418) (xy 93.555089 -403.965114)
			(xy 93.547331 -403.911156) (xy 92.10982 -403.911156) (xy 92.102064 -403.965099) (xy 92.086709 -404.017394)
			(xy 92.064068 -404.066971) (xy 92.034601 -404.112821) (xy 91.99891 -404.154011) (xy 91.95772 -404.189703)
			(xy 91.911869 -404.219169) (xy 91.862292 -404.24181) (xy 91.809997 -404.257165) (xy 91.756049 -404.264921)
			(xy 91.728798 -404.265384) (xy 90.865198 -404.265384) (xy 90.837945 -404.264946) (xy 90.783994 -404.257189)
			(xy 90.731696 -404.241833) (xy 90.682116 -404.21919) (xy 90.636263 -404.189722) (xy 90.595071 -404.154028)
			(xy 90.559377 -404.112835) (xy 90.529909 -404.066982) (xy 90.507267 -404.017402) (xy 90.491911 -403.965104)
			(xy 90.484154 -403.911153) (xy 89.046621 -403.911153) (xy 89.038863 -403.965104) (xy 89.023506 -404.017402)
			(xy 89.000862 -404.066982) (xy 88.971392 -404.112834) (xy 88.935696 -404.154025) (xy 88.894501 -404.189717)
			(xy 88.848645 -404.219182) (xy 88.799063 -404.241821) (xy 88.746763 -404.257172) (xy 88.692811 -404.264924)
			(xy 88.665558 -404.265384) (xy 87.801958 -404.265384) (xy 87.774707 -404.264943) (xy 87.72076 -404.257181)
			(xy 87.668467 -404.241822) (xy 87.618892 -404.219177) (xy 87.573044 -404.189707) (xy 87.531857 -404.154014)
			(xy 87.496167 -404.112822) (xy 87.466703 -404.066971) (xy 87.444064 -404.017393) (xy 87.42871 -403.965098)
			(xy 87.420954 -403.911151) (xy 85.983298 -403.911151) (xy 85.975542 -403.965091) (xy 85.960189 -404.017381)
			(xy 85.937551 -404.066954) (xy 85.908088 -404.112801) (xy 85.872401 -404.153988) (xy 85.831215 -404.189677)
			(xy 85.78537 -404.219142) (xy 85.735798 -404.241783) (xy 85.683509 -404.257138) (xy 85.629567 -404.264897)
			(xy 85.602318 -404.265384) (xy 84.738718 -404.265384) (xy 84.711463 -404.26497) (xy 84.657506 -404.257215)
			(xy 84.605203 -404.241859) (xy 84.555617 -404.219217) (xy 84.509759 -404.189747) (xy 84.468562 -404.154051)
			(xy 84.432864 -404.112855) (xy 84.403392 -404.066999) (xy 84.380747 -404.017414) (xy 84.365389 -403.965111)
			(xy 84.357631 -403.911155) (xy 82.920121 -403.911155) (xy 82.912364 -403.965102) (xy 82.897007 -404.017398)
			(xy 82.874365 -404.066976) (xy 82.844897 -404.112828) (xy 82.809203 -404.154018) (xy 82.76801 -404.18971)
			(xy 82.722157 -404.219175) (xy 82.672577 -404.241815) (xy 82.62028 -404.257168) (xy 82.56633 -404.264922)
			(xy 82.539078 -404.265384) (xy 81.675478 -404.265384) (xy 81.648226 -404.264945) (xy 81.594277 -404.257185)
			(xy 81.541982 -404.241827) (xy 81.492404 -404.219183) (xy 81.446554 -404.189715) (xy 81.405364 -404.154021)
			(xy 81.369672 -404.112829) (xy 81.340206 -404.066976) (xy 81.317565 -404.017397) (xy 81.30221 -403.965101)
			(xy 81.294454 -403.911152) (xy 79.856797 -403.911152) (xy 79.849043 -403.965089) (xy 79.833691 -404.017377)
			(xy 79.811054 -404.066949) (xy 79.781593 -404.112794) (xy 79.745908 -404.153981) (xy 79.704725 -404.18967)
			(xy 79.658882 -404.219135) (xy 79.609313 -404.241777) (xy 79.557026 -404.257135) (xy 79.503086 -404.264895)
			(xy 79.475838 -404.265384) (xy 78.612238 -404.265384) (xy 78.584982 -404.264972) (xy 78.531023 -404.257219)
			(xy 78.478717 -404.241865) (xy 78.429129 -404.219223) (xy 78.383268 -404.189754) (xy 78.342069 -404.154058)
			(xy 78.306369 -404.112862) (xy 78.276895 -404.067004) (xy 78.254248 -404.017418) (xy 78.238889 -403.965114)
			(xy 78.231131 -403.911156) (xy 76.79362 -403.911156) (xy 76.785864 -403.965099) (xy 76.770509 -404.017394)
			(xy 76.747868 -404.066971) (xy 76.718401 -404.112821) (xy 76.68271 -404.154011) (xy 76.64152 -404.189703)
			(xy 76.595669 -404.219169) (xy 76.546092 -404.24181) (xy 76.493797 -404.257165) (xy 76.439849 -404.264921)
			(xy 76.412598 -404.265384) (xy 75.548998 -404.265384) (xy 75.521745 -404.264946) (xy 75.467794 -404.257189)
			(xy 75.415496 -404.241833) (xy 75.365916 -404.21919) (xy 75.320063 -404.189722) (xy 75.278871 -404.154028)
			(xy 75.243177 -404.112835) (xy 75.213709 -404.066982) (xy 75.191067 -404.017402) (xy 75.175711 -403.965104)
			(xy 75.167954 -403.911153) (xy 73.730421 -403.911153) (xy 73.722663 -403.965104) (xy 73.707306 -404.017402)
			(xy 73.684662 -404.066982) (xy 73.655192 -404.112834) (xy 73.619496 -404.154025) (xy 73.578301 -404.189717)
			(xy 73.532445 -404.219182) (xy 73.482863 -404.241821) (xy 73.430563 -404.257172) (xy 73.376611 -404.264924)
			(xy 73.349358 -404.265384) (xy 72.485758 -404.265384) (xy 72.458507 -404.264943) (xy 72.40456 -404.257181)
			(xy 72.352267 -404.241822) (xy 72.302692 -404.219177) (xy 72.256844 -404.189707) (xy 72.215657 -404.154014)
			(xy 72.179967 -404.112822) (xy 72.150503 -404.066971) (xy 72.127864 -404.017393) (xy 72.11251 -403.965098)
			(xy 72.104754 -403.911151) (xy 70.667098 -403.911151) (xy 70.659342 -403.965091) (xy 70.643989 -404.017381)
			(xy 70.621351 -404.066954) (xy 70.591888 -404.112801) (xy 70.556201 -404.153988) (xy 70.515015 -404.189677)
			(xy 70.46917 -404.219142) (xy 70.419598 -404.241783) (xy 70.367309 -404.257138) (xy 70.313367 -404.264897)
			(xy 70.286118 -404.265384) (xy 69.422518 -404.265384) (xy 69.395263 -404.26497) (xy 69.341306 -404.257215)
			(xy 69.289003 -404.241859) (xy 69.239417 -404.219217) (xy 69.193559 -404.189747) (xy 69.152362 -404.154051)
			(xy 69.116664 -404.112855) (xy 69.087192 -404.066999) (xy 69.064547 -404.017414) (xy 69.049189 -403.965111)
			(xy 69.041431 -403.911155) (xy 67.603921 -403.911155) (xy 67.596164 -403.965102) (xy 67.580807 -404.017398)
			(xy 67.558165 -404.066976) (xy 67.528697 -404.112828) (xy 67.493003 -404.154018) (xy 67.45181 -404.18971)
			(xy 67.405957 -404.219175) (xy 67.356377 -404.241815) (xy 67.30408 -404.257168) (xy 67.25013 -404.264922)
			(xy 67.222878 -404.265384) (xy 66.359278 -404.265384) (xy 66.332026 -404.264945) (xy 66.278077 -404.257185)
			(xy 66.225782 -404.241827) (xy 66.176204 -404.219183) (xy 66.130354 -404.189715) (xy 66.089164 -404.154021)
			(xy 66.053472 -404.112829) (xy 66.024006 -404.066976) (xy 66.001365 -404.017397) (xy 65.98601 -403.965101)
			(xy 65.978254 -403.911152) (xy 64.540597 -403.911152) (xy 64.532843 -403.965089) (xy 64.517491 -404.017377)
			(xy 64.494854 -404.066949) (xy 64.465393 -404.112794) (xy 64.429708 -404.153981) (xy 64.388525 -404.18967)
			(xy 64.342682 -404.219135) (xy 64.293113 -404.241777) (xy 64.240826 -404.257135) (xy 64.186886 -404.264895)
			(xy 64.159638 -404.265384) (xy 63.296038 -404.265384) (xy 63.268782 -404.264972) (xy 63.214823 -404.257219)
			(xy 63.162517 -404.241865) (xy 63.112929 -404.219223) (xy 63.067068 -404.189754) (xy 63.025869 -404.154058)
			(xy 62.990169 -404.112862) (xy 62.960695 -404.067004) (xy 62.938048 -404.017418) (xy 62.922689 -403.965114)
			(xy 62.914931 -403.911156) (xy 61.47742 -403.911156) (xy 61.469664 -403.965099) (xy 61.454309 -404.017394)
			(xy 61.431668 -404.066971) (xy 61.402201 -404.112821) (xy 61.36651 -404.154011) (xy 61.32532 -404.189703)
			(xy 61.279469 -404.219169) (xy 61.229892 -404.24181) (xy 61.177597 -404.257165) (xy 61.123649 -404.264921)
			(xy 61.096398 -404.265384) (xy 60.232798 -404.265384) (xy 60.205545 -404.264946) (xy 60.151594 -404.257189)
			(xy 60.099296 -404.241833) (xy 60.049716 -404.21919) (xy 60.003863 -404.189722) (xy 59.962671 -404.154028)
			(xy 59.926977 -404.112835) (xy 59.897509 -404.066982) (xy 59.874867 -404.017402) (xy 59.859511 -403.965104)
			(xy 59.851754 -403.911153) (xy 58.414221 -403.911153) (xy 58.406463 -403.965104) (xy 58.391106 -404.017402)
			(xy 58.368462 -404.066982) (xy 58.338992 -404.112834) (xy 58.303296 -404.154025) (xy 58.262101 -404.189717)
			(xy 58.216245 -404.219182) (xy 58.166663 -404.241821) (xy 58.114363 -404.257172) (xy 58.060411 -404.264924)
			(xy 58.033158 -404.265384) (xy 57.169558 -404.265384) (xy 57.142307 -404.264943) (xy 57.08836 -404.257181)
			(xy 57.036067 -404.241822) (xy 56.986492 -404.219177) (xy 56.940644 -404.189707) (xy 56.899457 -404.154014)
			(xy 56.863767 -404.112822) (xy 56.834303 -404.066971) (xy 56.811664 -404.017393) (xy 56.79631 -403.965098)
			(xy 56.788554 -403.911151) (xy 55.350898 -403.911151) (xy 55.343142 -403.965091) (xy 55.327789 -404.017381)
			(xy 55.305151 -404.066954) (xy 55.275688 -404.112801) (xy 55.240001 -404.153988) (xy 55.198815 -404.189677)
			(xy 55.15297 -404.219142) (xy 55.103398 -404.241783) (xy 55.051109 -404.257138) (xy 54.997167 -404.264897)
			(xy 54.969918 -404.265384) (xy 54.106318 -404.265384) (xy 54.079063 -404.26497) (xy 54.025106 -404.257215)
			(xy 53.972803 -404.241859) (xy 53.923217 -404.219217) (xy 53.877359 -404.189747) (xy 53.836162 -404.154051)
			(xy 53.800464 -404.112855) (xy 53.770992 -404.066999) (xy 53.748347 -404.017414) (xy 53.732989 -403.965111)
			(xy 53.725231 -403.911155) (xy 52.287721 -403.911155) (xy 52.279964 -403.965102) (xy 52.264607 -404.017398)
			(xy 52.241965 -404.066976) (xy 52.212497 -404.112828) (xy 52.176803 -404.154018) (xy 52.13561 -404.18971)
			(xy 52.089757 -404.219175) (xy 52.040177 -404.241815) (xy 51.98788 -404.257168) (xy 51.93393 -404.264922)
			(xy 51.906678 -404.265384) (xy 51.043078 -404.265384) (xy 51.015826 -404.264945) (xy 50.961877 -404.257185)
			(xy 50.909582 -404.241827) (xy 50.860004 -404.219183) (xy 50.814154 -404.189715) (xy 50.772964 -404.154021)
			(xy 50.737272 -404.112829) (xy 50.707806 -404.066976) (xy 50.685165 -404.017397) (xy 50.66981 -403.965101)
			(xy 50.662054 -403.911152) (xy 49.224397 -403.911152) (xy 49.216643 -403.965089) (xy 49.201291 -404.017377)
			(xy 49.178654 -404.066949) (xy 49.149193 -404.112794) (xy 49.113508 -404.153981) (xy 49.072325 -404.18967)
			(xy 49.026482 -404.219135) (xy 48.976913 -404.241777) (xy 48.924626 -404.257135) (xy 48.870686 -404.264895)
			(xy 48.843438 -404.265384) (xy 47.979838 -404.265384) (xy 47.952582 -404.264972) (xy 47.898623 -404.257219)
			(xy 47.846317 -404.241865) (xy 47.796729 -404.219223) (xy 47.750868 -404.189754) (xy 47.709669 -404.154058)
			(xy 47.673969 -404.112862) (xy 47.644495 -404.067004) (xy 47.621848 -404.017418) (xy 47.606489 -403.965114)
			(xy 47.598731 -403.911156) (xy 2.610452 -403.911156) (xy 2.622121 -403.942439) (xy 2.666338 -404.039266)
			(xy 2.717346 -404.132693) (xy 2.774884 -404.222247) (xy 2.838661 -404.307471) (xy 2.908351 -404.387931)
			(xy 2.945638 -404.425912) (xy 3.748786 -405.22906) (xy 102.242112 -405.22906) (xy 102.242112 -404.36546)
			(xy 102.242598 -404.338209) (xy 102.250354 -404.284261) (xy 102.265709 -404.231966) (xy 102.288351 -404.182389)
			(xy 102.317817 -404.136539) (xy 102.353508 -404.095348) (xy 102.394699 -404.059657) (xy 102.440549 -404.030191)
			(xy 102.490126 -404.007549) (xy 102.542421 -403.992194) (xy 102.596369 -403.984438) (xy 102.650871 -403.984438)
			(xy 102.704819 -403.992194) (xy 102.757114 -404.007549) (xy 102.806691 -404.030191) (xy 102.852541 -404.059657)
			(xy 102.893732 -404.095348) (xy 102.929423 -404.136539) (xy 102.958889 -404.182389) (xy 102.981531 -404.231966)
			(xy 102.996886 -404.284261) (xy 103.004642 -404.338209) (xy 103.005128 -404.36546) (xy 103.005128 -405.22906)
			(xy 103.004642 -405.256311) (xy 102.996886 -405.310259) (xy 102.981531 -405.362554) (xy 102.958889 -405.412131)
			(xy 102.929423 -405.457981) (xy 102.893732 -405.499172) (xy 102.852541 -405.534863) (xy 102.806691 -405.564329)
			(xy 102.757114 -405.586971) (xy 102.704819 -405.602326) (xy 102.650871 -405.610082) (xy 102.596369 -405.610082)
			(xy 102.542421 -405.602326) (xy 102.490126 -405.586971) (xy 102.440549 -405.564329) (xy 102.394699 -405.534863)
			(xy 102.353508 -405.499172) (xy 102.317817 -405.457981) (xy 102.288351 -405.412131) (xy 102.265709 -405.362554)
			(xy 102.250354 -405.310259) (xy 102.242598 -405.256311) (xy 102.242112 -405.22906) (xy 3.748786 -405.22906)
			(xy 5.555234 -407.035508) (xy 15.978632 -407.035508) (xy 15.978632 -406.171908) (xy 15.979118 -406.144657)
			(xy 15.986874 -406.090709) (xy 16.002229 -406.038414) (xy 16.024871 -405.988837) (xy 16.054337 -405.942987)
			(xy 16.090028 -405.901796) (xy 16.131219 -405.866105) (xy 16.177069 -405.836639) (xy 16.226646 -405.813997)
			(xy 16.278941 -405.798642) (xy 16.332889 -405.790886) (xy 16.387391 -405.790886) (xy 16.441339 -405.798642)
			(xy 16.493634 -405.813997) (xy 16.543211 -405.836639) (xy 16.589061 -405.866105) (xy 16.630252 -405.901796)
			(xy 16.665943 -405.942987) (xy 16.695409 -405.988837) (xy 16.718051 -406.038414) (xy 16.733406 -406.090709)
			(xy 16.741162 -406.144657) (xy 16.741648 -406.171908) (xy 16.741648 -406.620726) (xy 184.561988 -406.620726)
			(xy 184.561988 -400.685254) (xy 184.562447 -400.660304) (xy 184.570259 -400.611019) (xy 184.585684 -400.563563)
			(xy 184.608342 -400.519104) (xy 184.637676 -400.478736) (xy 184.672962 -400.443454) (xy 184.713333 -400.414125)
			(xy 184.757795 -400.391471) (xy 184.805253 -400.376051) (xy 184.854538 -400.368244) (xy 184.879488 -400.367754)
			(xy 188.73343 -400.367754) (xy 188.758609 -400.368272) (xy 188.808334 -400.376233) (xy 188.856176 -400.39195)
			(xy 188.900934 -400.415029) (xy 188.941484 -400.444889) (xy 188.95949 -400.462496) (xy 189.16142 -400.667474)
			(xy 189.178411 -400.68542) (xy 189.207232 -400.725562) (xy 189.229493 -400.76968) (xy 189.244658 -400.816712)
			(xy 189.252363 -400.865524) (xy 189.25286 -400.890232) (xy 189.25286 -403.517354) (xy 189.46876 -403.517354)
			(xy 189.49371 -403.51783) (xy 189.542993 -403.525649) (xy 189.590451 -403.541071) (xy 189.634916 -403.563718)
			(xy 189.675298 -403.593032) (xy 189.693296 -403.610318) (xy 189.904624 -403.821646) (xy 189.921945 -403.839613)
			(xy 189.951264 -403.879997) (xy 189.973905 -403.92447) (xy 189.989312 -403.971937) (xy 189.997105 -404.021229)
			(xy 189.997588 -404.046182) (xy 189.997588 -404.34641) (xy 190.325756 -404.674832) (xy 190.350648 -404.671276)
			(xy 190.363288 -404.669701) (xy 190.38871 -404.668051) (xy 190.401448 -404.667974) (xy 190.4287 -404.668433)
			(xy 190.482647 -404.676196) (xy 190.534941 -404.691556) (xy 190.584518 -404.714201) (xy 190.630367 -404.743671)
			(xy 190.671556 -404.779365) (xy 190.707247 -404.820557) (xy 190.736713 -404.866409) (xy 190.759355 -404.915987)
			(xy 190.774711 -404.968282) (xy 190.782469 -405.02223) (xy 190.782956 -405.049482) (xy 190.782871 -405.06222)
			(xy 190.781219 -405.087641) (xy 190.779654 -405.100282) (xy 190.776098 -405.125174) (xy 191.001904 -405.35098)
			(xy 196.838316 -405.35098) (xy 197.83298 -404.356316) (xy 197.83298 -400.893788) (xy 197.833478 -400.868839)
			(xy 197.841291 -400.819556) (xy 197.856708 -400.772099) (xy 197.879349 -400.727633) (xy 197.908659 -400.68725)
			(xy 197.925944 -400.669252) (xy 198.116952 -400.478244) (xy 198.134911 -400.460913) (xy 198.175295 -400.431588)
			(xy 198.219769 -400.408941) (xy 198.267238 -400.393531) (xy 198.316534 -400.385737) (xy 198.341488 -400.38528)
			(xy 201.995532 -400.38528) (xy 202.020482 -400.385766) (xy 202.069765 -400.393582) (xy 202.117222 -400.409001)
			(xy 202.161688 -400.431645) (xy 202.20207 -400.460958) (xy 202.220068 -400.478244) (xy 202.418696 -400.676872)
			(xy 202.435977 -400.694876) (xy 202.465302 -400.73525) (xy 202.487952 -400.779713) (xy 202.503368 -400.827172)
			(xy 202.511171 -400.876458) (xy 202.51166 -400.901408) (xy 202.51166 -404.330916) (xy 202.604624 -404.42388)
			(xy 202.621913 -404.441876) (xy 202.651236 -404.482252) (xy 202.673884 -404.526718) (xy 202.689298 -404.574178)
			(xy 202.6971 -404.623466) (xy 202.697588 -404.648416) (xy 202.697588 -407.475436) (xy 204.291692 -409.06954)
			(xy 206.414116 -409.06954) (xy 208.310988 -407.172668) (xy 208.310988 -404.642828) (xy 208.311509 -404.61788)
			(xy 208.319316 -404.568598) (xy 208.334727 -404.521141) (xy 208.357363 -404.476674) (xy 208.386669 -404.436291)
			(xy 208.403952 -404.418292) (xy 208.50098 -404.321264) (xy 208.50098 -400.893788) (xy 208.501478 -400.868839)
			(xy 208.509291 -400.819556) (xy 208.524708 -400.772099) (xy 208.547349 -400.727633) (xy 208.576659 -400.68725)
			(xy 208.593944 -400.669252) (xy 208.784952 -400.478244) (xy 208.802911 -400.460913) (xy 208.843295 -400.431588)
			(xy 208.887769 -400.408941) (xy 208.935238 -400.393531) (xy 208.984534 -400.385737) (xy 209.009488 -400.38528)
			(xy 212.668612 -400.38528) (xy 212.693561 -400.385778) (xy 212.742844 -400.393591) (xy 212.790301 -400.409008)
			(xy 212.834767 -400.431649) (xy 212.87515 -400.460959) (xy 212.893148 -400.478244) (xy 213.084156 -400.669252)
			(xy 213.101487 -400.687211) (xy 213.130812 -400.727595) (xy 213.153459 -400.772069) (xy 213.168869 -400.819538)
			(xy 213.176663 -400.868834) (xy 213.17712 -400.893788) (xy 213.17712 -404.353776) (xy 213.261956 -404.438612)
			(xy 213.279249 -404.456605) (xy 213.308574 -404.496981) (xy 213.331222 -404.541447) (xy 213.346636 -404.588909)
			(xy 213.354434 -404.638197) (xy 213.35492 -404.663148) (xy 213.35492 -407.394156) (xy 214.926164 -408.9654)
			(xy 217.141044 -408.9654) (xy 218.978988 -407.127456) (xy 218.978988 -404.673308) (xy 218.979496 -404.648359)
			(xy 218.987307 -404.599077) (xy 219.00272 -404.55162) (xy 219.02536 -404.507153) (xy 219.054668 -404.46677)
			(xy 219.071952 -404.448772) (xy 219.16136 -404.359364) (xy 219.16136 -400.906488) (xy 219.161864 -400.881539)
			(xy 219.169676 -400.832257) (xy 219.185092 -400.7848) (xy 219.207732 -400.740334) (xy 219.23704 -400.699951)
			(xy 219.254324 -400.681952) (xy 219.458032 -400.478244) (xy 219.476 -400.460922) (xy 219.516381 -400.431596)
			(xy 219.560853 -400.408948) (xy 219.60832 -400.393535) (xy 219.657614 -400.385739) (xy 219.682568 -400.38528)
			(xy 223.323912 -400.38528) (xy 223.348861 -400.385778) (xy 223.398144 -400.393591) (xy 223.445601 -400.409008)
			(xy 223.490067 -400.431649) (xy 223.53045 -400.460959) (xy 223.548448 -400.478244) (xy 223.759776 -400.689572)
			(xy 223.777053 -400.707579) (xy 223.80638 -400.747952) (xy 223.82903 -400.792414) (xy 223.844447 -400.839873)
			(xy 223.852251 -400.889158) (xy 223.85274 -400.914108) (xy 223.85274 -404.348188) (xy 223.940624 -404.436072)
			(xy 223.957909 -404.454071) (xy 223.987233 -404.494447) (xy 224.009881 -404.538912) (xy 224.025297 -404.586371)
			(xy 224.0331 -404.635658) (xy 224.033588 -404.660608) (xy 224.033588 -407.272236) (xy 225.838512 -409.07716)
			(xy 227.803456 -409.07716) (xy 229.621588 -407.259028) (xy 229.621588 -404.678388) (xy 229.622084 -404.653439)
			(xy 229.629897 -404.604156) (xy 229.645314 -404.556698) (xy 229.667956 -404.512233) (xy 229.697267 -404.47185)
			(xy 229.714552 -404.453852) (xy 229.82682 -404.341584) (xy 229.82682 -400.901408) (xy 229.827348 -400.87646)
			(xy 229.835156 -400.82718) (xy 229.850567 -400.779723) (xy 229.873201 -400.735257) (xy 229.902503 -400.694872)
			(xy 229.919784 -400.676872) (xy 230.120952 -400.475704) (xy 230.138921 -400.458385) (xy 230.179304 -400.429065)
			(xy 230.223776 -400.406422) (xy 230.271243 -400.391015) (xy 230.320536 -400.383222) (xy 230.345488 -400.38274)
			(xy 233.996992 -400.38274) (xy 234.02194 -400.383262) (xy 234.071221 -400.391071) (xy 234.118678 -400.406483)
			(xy 234.163144 -400.429118) (xy 234.203528 -400.458422) (xy 234.221528 -400.475704) (xy 234.422696 -400.676872)
			(xy 234.439977 -400.694876) (xy 234.469302 -400.73525) (xy 234.491952 -400.779713) (xy 234.507368 -400.827172)
			(xy 234.515171 -400.876458) (xy 234.51566 -400.901408) (xy 234.51566 -404.346156) (xy 235.652564 -405.48306)
			(xy 237.746032 -405.48306) (xy 237.770981 -405.483551) (xy 237.820264 -405.491367) (xy 237.867721 -405.506785)
			(xy 237.912187 -405.529428) (xy 237.95257 -405.558739) (xy 237.970568 -405.576024) (xy 238.814356 -406.419812)
			(xy 238.968788 -406.419812) (xy 239.014 -406.3746) (xy 239.014 -397.839946) (xy 239.014705 -397.809318)
			(xy 239.02648 -397.749203) (xy 239.037368 -397.720566) (xy 239.093502 -397.582136) (xy 239.102124 -397.561821)
			(xy 239.124183 -397.523596) (xy 239.151323 -397.488796) (xy 239.166908 -397.47317) (xy 239.218978 -397.423132)
			(xy 239.692688 -396.949422) (xy 239.720237 -396.922524) (xy 239.780375 -396.87444) (xy 239.845524 -396.833399)
			(xy 239.914862 -396.799918) (xy 239.987515 -396.774419) (xy 240.062568 -396.757222) (xy 240.139075 -396.748545)
			(xy 240.177574 -396.748) (xy 274.117054 -396.748) (xy 274.147682 -396.748705) (xy 274.207797 -396.76048)
			(xy 274.236434 -396.771368) (xy 274.374864 -396.827502) (xy 274.395179 -396.836124) (xy 274.433404 -396.858183)
			(xy 274.468204 -396.885323) (xy 274.48383 -396.900908) (xy 274.533868 -396.952978) (xy 274.753578 -397.172688)
			(xy 274.777454 -397.19758) (xy 274.787032 -397.207432) (xy 274.810234 -397.222125) (xy 274.836515 -397.230094)
			(xy 274.86397 -397.230762) (xy 274.890608 -397.22408) (xy 274.914497 -397.210532) (xy 274.92452 -397.201136)
			(xy 275.284692 -396.840964) (xy 275.302681 -396.823665) (xy 275.343056 -396.794335) (xy 275.387522 -396.771682)
			(xy 275.434985 -396.756264) (xy 275.484276 -396.748462) (xy 275.509228 -396.748) (xy 280.83764 -396.748)
			(xy 280.86259 -396.748475) (xy 280.911874 -396.756293) (xy 280.959332 -396.771714) (xy 281.003797 -396.794361)
			(xy 281.044179 -396.823677) (xy 281.062176 -396.840964) (xy 281.593544 -397.372332) (xy 281.610864 -397.390302)
			(xy 281.640191 -397.430682) (xy 281.66284 -397.475154) (xy 281.678252 -397.522621) (xy 281.686049 -397.571915)
			(xy 281.686508 -397.596868) (xy 281.686508 -398.65534) (xy 457.185003 -398.65534) (xy 457.185003 -398.5262)
			(xy 457.192953 -398.397305) (xy 457.208823 -398.269145) (xy 457.232552 -398.142204) (xy 457.264051 -398.016965)
			(xy 457.3032 -397.893902) (xy 457.349851 -397.773483) (xy 457.403826 -397.656164) (xy 457.464921 -397.54239)
			(xy 457.532904 -397.432593) (xy 457.607518 -397.32719) (xy 457.688479 -397.22658) (xy 457.775479 -397.131145)
			(xy 457.86819 -397.041246) (xy 457.96626 -396.957225) (xy 458.069315 -396.879401) (xy 458.176966 -396.808069)
			(xy 458.288805 -396.743499) (xy 458.404406 -396.685937) (xy 458.523331 -396.6356) (xy 458.64513 -396.59268)
			(xy 458.76934 -396.557339) (xy 458.895489 -396.529712) (xy 459.023101 -396.509903) (xy 459.15169 -396.497987)
			(xy 459.280768 -396.494011) (xy 459.409846 -396.497987) (xy 459.538435 -396.509903) (xy 459.666047 -396.529712)
			(xy 459.792196 -396.557339) (xy 459.916406 -396.59268) (xy 460.038205 -396.6356) (xy 460.15713 -396.685937)
			(xy 460.272731 -396.743499) (xy 460.38457 -396.808069) (xy 460.492221 -396.879401) (xy 460.595276 -396.957225)
			(xy 460.693346 -397.041246) (xy 460.786057 -397.131145) (xy 460.873057 -397.22658) (xy 460.954018 -397.32719)
			(xy 461.028632 -397.432593) (xy 461.096615 -397.54239) (xy 461.15771 -397.656164) (xy 461.211685 -397.773483)
			(xy 461.258336 -397.893902) (xy 461.297485 -398.016965) (xy 461.328984 -398.142204) (xy 461.352713 -398.269145)
			(xy 461.368583 -398.397305) (xy 461.376533 -398.5262) (xy 461.37703 -398.59077) (xy 461.376533 -398.65534)
			(xy 461.368583 -398.784235) (xy 461.352713 -398.912395) (xy 461.328984 -399.039336) (xy 461.297485 -399.164575)
			(xy 461.258336 -399.287638) (xy 461.211685 -399.408057) (xy 461.15771 -399.525376) (xy 461.096615 -399.63915)
			(xy 461.028632 -399.748947) (xy 460.954018 -399.85435) (xy 460.873057 -399.95496) (xy 460.786057 -400.050395)
			(xy 460.693346 -400.140294) (xy 460.595276 -400.224315) (xy 460.492221 -400.302139) (xy 460.38457 -400.373471)
			(xy 460.272731 -400.438041) (xy 460.15713 -400.495603) (xy 460.038205 -400.54594) (xy 459.916406 -400.58886)
			(xy 459.792196 -400.624201) (xy 459.666047 -400.651828) (xy 459.538435 -400.671637) (xy 459.409846 -400.683553)
			(xy 459.280768 -400.68753) (xy 459.15169 -400.683553) (xy 459.023101 -400.671637) (xy 458.895489 -400.651828)
			(xy 458.76934 -400.624201) (xy 458.64513 -400.58886) (xy 458.523331 -400.54594) (xy 458.404406 -400.495603)
			(xy 458.288805 -400.438041) (xy 458.176966 -400.373471) (xy 458.069315 -400.302139) (xy 457.96626 -400.224315)
			(xy 457.86819 -400.140294) (xy 457.775479 -400.050395) (xy 457.688479 -399.95496) (xy 457.607518 -399.85435)
			(xy 457.532904 -399.748947) (xy 457.464921 -399.63915) (xy 457.403826 -399.525376) (xy 457.349851 -399.408057)
			(xy 457.3032 -399.287638) (xy 457.264051 -399.164575) (xy 457.232552 -399.039336) (xy 457.208823 -398.912395)
			(xy 457.192953 -398.784235) (xy 457.185003 -398.65534) (xy 281.686508 -398.65534) (xy 281.686508 -399.9835)
			(xy 289.606441 -399.9835) (xy 289.610455 -399.919698) (xy 289.622434 -399.856902) (xy 289.642189 -399.796103)
			(xy 289.669408 -399.73826) (xy 289.703662 -399.684283) (xy 289.744411 -399.635026) (xy 289.791013 -399.591264)
			(xy 289.842731 -399.553688) (xy 289.898752 -399.52289) (xy 289.958191 -399.499357) (xy 290.02011 -399.483458)
			(xy 290.083534 -399.475446) (xy 290.115498 -399.474944) (xy 290.115752 -399.474944) (xy 290.147498 -399.475464)
			(xy 290.210494 -399.483393) (xy 290.272014 -399.499096) (xy 290.331102 -399.52233) (xy 290.386842 -399.552733)
			(xy 290.438367 -399.589834) (xy 290.461954 -399.611088) (xy 290.469217 -399.617272) (xy 290.486967 -399.624223)
			(xy 290.506029 -399.624223) (xy 290.523779 -399.617272) (xy 290.531042 -399.611088) (xy 290.554631 -399.589832)
			(xy 290.60614 -399.5527) (xy 290.661874 -399.522276) (xy 290.720965 -399.499035) (xy 290.782492 -399.483338)
			(xy 290.845495 -399.475431) (xy 290.877244 -399.474944) (xy 290.877498 -399.474944) (xy 290.909457 -399.475521)
			(xy 290.972872 -399.483532) (xy 291.034783 -399.499427) (xy 291.094213 -399.522957) (xy 291.150226 -399.55375)
			(xy 291.201937 -399.591321) (xy 291.248532 -399.635076) (xy 291.289276 -399.684326) (xy 291.323525 -399.738295)
			(xy 291.350741 -399.79613) (xy 291.370493 -399.856921) (xy 291.38247 -399.919707) (xy 291.386484 -399.9835)
			(xy 292.146441 -399.9835) (xy 292.150455 -399.919698) (xy 292.162434 -399.856902) (xy 292.182189 -399.796103)
			(xy 292.209408 -399.73826) (xy 292.243662 -399.684283) (xy 292.284411 -399.635026) (xy 292.331013 -399.591264)
			(xy 292.382731 -399.553688) (xy 292.438752 -399.52289) (xy 292.498191 -399.499357) (xy 292.56011 -399.483458)
			(xy 292.623534 -399.475446) (xy 292.655498 -399.474944) (xy 292.655752 -399.474944) (xy 292.687498 -399.475464)
			(xy 292.750494 -399.483393) (xy 292.812014 -399.499096) (xy 292.871102 -399.52233) (xy 292.926842 -399.552733)
			(xy 292.978367 -399.589834) (xy 293.001954 -399.611088) (xy 293.009217 -399.617272) (xy 293.026967 -399.624223)
			(xy 293.046029 -399.624223) (xy 293.063779 -399.617272) (xy 293.071042 -399.611088) (xy 293.094631 -399.589832)
			(xy 293.14614 -399.5527) (xy 293.201874 -399.522276) (xy 293.260965 -399.499035) (xy 293.322492 -399.483338)
			(xy 293.385495 -399.475431) (xy 293.417244 -399.474944) (xy 293.417498 -399.474944) (xy 293.449457 -399.475521)
			(xy 293.512872 -399.483532) (xy 293.574783 -399.499427) (xy 293.634213 -399.522957) (xy 293.690226 -399.55375)
			(xy 293.741937 -399.591321) (xy 293.788532 -399.635076) (xy 293.829276 -399.684326) (xy 293.863525 -399.738295)
			(xy 293.890741 -399.79613) (xy 293.910493 -399.856921) (xy 293.92247 -399.919707) (xy 293.926484 -399.9835)
			(xy 294.53602 -399.9835) (xy 294.540035 -399.919693) (xy 294.552015 -399.856892) (xy 294.571773 -399.796089)
			(xy 294.598995 -399.738241) (xy 294.633253 -399.684261) (xy 294.674007 -399.635001) (xy 294.720613 -399.591237)
			(xy 294.772338 -399.55366) (xy 294.828364 -399.522862) (xy 294.887809 -399.499329) (xy 294.949734 -399.483433)
			(xy 295.013163 -399.475423) (xy 295.04513 -399.474944) (xy 295.045384 -399.474944) (xy 295.077131 -399.475444)
			(xy 295.140127 -399.483377) (xy 295.201647 -399.499084) (xy 295.260736 -399.522322) (xy 295.316476 -399.552728)
			(xy 295.368 -399.589832) (xy 295.391586 -399.611088) (xy 295.398849 -399.617272) (xy 295.416599 -399.624223)
			(xy 295.435661 -399.624223) (xy 295.453411 -399.617272) (xy 295.460674 -399.611088) (xy 295.48425 -399.589817)
			(xy 295.535761 -399.552686) (xy 295.591498 -399.522265) (xy 295.650592 -399.499026) (xy 295.712121 -399.483332)
			(xy 295.775126 -399.475429) (xy 295.806876 -399.474944) (xy 295.80713 -399.474944) (xy 295.839087 -399.475544)
			(xy 295.902496 -399.483558) (xy 295.964401 -399.499455) (xy 296.023825 -399.522986) (xy 296.079832 -399.553779)
			(xy 296.131538 -399.591348) (xy 296.178128 -399.635102) (xy 296.218866 -399.684349) (xy 296.253112 -399.738314)
			(xy 296.280324 -399.796145) (xy 296.300074 -399.856931) (xy 296.312049 -399.919712) (xy 296.316063 -399.9835)
			(xy 297.07602 -399.9835) (xy 297.080035 -399.919693) (xy 297.092015 -399.856892) (xy 297.111773 -399.796089)
			(xy 297.138995 -399.738241) (xy 297.173253 -399.684261) (xy 297.214007 -399.635001) (xy 297.260613 -399.591237)
			(xy 297.312338 -399.55366) (xy 297.368364 -399.522862) (xy 297.427809 -399.499329) (xy 297.489734 -399.483433)
			(xy 297.553163 -399.475423) (xy 297.58513 -399.474944) (xy 297.585384 -399.474944) (xy 297.617131 -399.475444)
			(xy 297.680127 -399.483377) (xy 297.741647 -399.499084) (xy 297.800736 -399.522322) (xy 297.856476 -399.552728)
			(xy 297.908 -399.589832) (xy 297.931586 -399.611088) (xy 297.938849 -399.617272) (xy 297.956599 -399.624223)
			(xy 297.975661 -399.624223) (xy 297.993411 -399.617272) (xy 298.000674 -399.611088) (xy 298.02425 -399.589817)
			(xy 298.075761 -399.552686) (xy 298.131498 -399.522265) (xy 298.190592 -399.499026) (xy 298.252121 -399.483332)
			(xy 298.315126 -399.475429) (xy 298.346876 -399.474944) (xy 298.34713 -399.474944) (xy 298.379087 -399.475544)
			(xy 298.442496 -399.483558) (xy 298.504401 -399.499455) (xy 298.563825 -399.522986) (xy 298.619832 -399.553779)
			(xy 298.671538 -399.591348) (xy 298.718128 -399.635102) (xy 298.758866 -399.684349) (xy 298.793112 -399.738314)
			(xy 298.820324 -399.796145) (xy 298.840074 -399.856931) (xy 298.852049 -399.919712) (xy 298.856063 -399.9835)
			(xy 298.852049 -400.047288) (xy 298.840074 -400.110069) (xy 298.820324 -400.170855) (xy 298.793112 -400.228686)
			(xy 298.758866 -400.282651) (xy 298.718128 -400.331898) (xy 298.671538 -400.375652) (xy 298.619832 -400.413221)
			(xy 298.563825 -400.444014) (xy 298.504401 -400.467545) (xy 298.442496 -400.483442) (xy 298.379087 -400.491456)
			(xy 298.34713 -400.49196) (xy 298.346876 -400.49196) (xy 298.315131 -400.491422) (xy 298.252136 -400.483497)
			(xy 298.190616 -400.467797) (xy 298.131527 -400.444566) (xy 298.075787 -400.414166) (xy 298.024261 -400.377069)
			(xy 298.000674 -400.355816) (xy 297.993411 -400.349632) (xy 297.975661 -400.342681) (xy 297.956599 -400.342681)
			(xy 297.938849 -400.349632) (xy 297.931586 -400.355816) (xy 297.908028 -400.377107) (xy 297.856512 -400.414235)
			(xy 297.800771 -400.444654) (xy 297.741674 -400.467889) (xy 297.680142 -400.483579) (xy 297.617135 -400.491478)
			(xy 297.585384 -400.49196) (xy 297.58513 -400.49196) (xy 297.553163 -400.491577) (xy 297.489734 -400.483567)
			(xy 297.427809 -400.467671) (xy 297.368364 -400.444138) (xy 297.312338 -400.41334) (xy 297.260613 -400.375763)
			(xy 297.214007 -400.331999) (xy 297.173253 -400.282739) (xy 297.138995 -400.228759) (xy 297.111773 -400.170911)
			(xy 297.092015 -400.110108) (xy 297.080035 -400.047307) (xy 297.07602 -399.9835) (xy 296.316063 -399.9835)
			(xy 296.312049 -400.047288) (xy 296.300074 -400.110069) (xy 296.280324 -400.170855) (xy 296.253112 -400.228686)
			(xy 296.218866 -400.282651) (xy 296.178128 -400.331898) (xy 296.131538 -400.375652) (xy 296.079832 -400.413221)
			(xy 296.023825 -400.444014) (xy 295.964401 -400.467545) (xy 295.902496 -400.483442) (xy 295.839087 -400.491456)
			(xy 295.80713 -400.49196) (xy 295.806876 -400.49196) (xy 295.775131 -400.491422) (xy 295.712136 -400.483497)
			(xy 295.650616 -400.467797) (xy 295.591527 -400.444566) (xy 295.535787 -400.414166) (xy 295.484261 -400.377069)
			(xy 295.460674 -400.355816) (xy 295.453411 -400.349632) (xy 295.435661 -400.342681) (xy 295.416599 -400.342681)
			(xy 295.398849 -400.349632) (xy 295.391586 -400.355816) (xy 295.368028 -400.377107) (xy 295.316512 -400.414235)
			(xy 295.260771 -400.444654) (xy 295.201674 -400.467889) (xy 295.140142 -400.483579) (xy 295.077135 -400.491478)
			(xy 295.045384 -400.49196) (xy 295.04513 -400.49196) (xy 295.013163 -400.491577) (xy 294.949734 -400.483567)
			(xy 294.887809 -400.467671) (xy 294.828364 -400.444138) (xy 294.772338 -400.41334) (xy 294.720613 -400.375763)
			(xy 294.674007 -400.331999) (xy 294.633253 -400.282739) (xy 294.598995 -400.228759) (xy 294.571773 -400.170911)
			(xy 294.552015 -400.110108) (xy 294.540035 -400.047307) (xy 294.53602 -399.9835) (xy 293.926484 -399.9835)
			(xy 293.92247 -400.047293) (xy 293.910493 -400.110079) (xy 293.890741 -400.17087) (xy 293.863525 -400.228705)
			(xy 293.829276 -400.282674) (xy 293.788532 -400.331924) (xy 293.741937 -400.375679) (xy 293.690226 -400.41325)
			(xy 293.634213 -400.444043) (xy 293.574783 -400.467573) (xy 293.512872 -400.483468) (xy 293.449457 -400.491479)
			(xy 293.417498 -400.49196) (xy 293.417244 -400.49196) (xy 293.385498 -400.491442) (xy 293.322502 -400.483512)
			(xy 293.260982 -400.467809) (xy 293.201894 -400.444575) (xy 293.146154 -400.414171) (xy 293.094629 -400.37707)
			(xy 293.071042 -400.355816) (xy 293.063779 -400.349632) (xy 293.046029 -400.342681) (xy 293.026967 -400.342681)
			(xy 293.009217 -400.349632) (xy 293.001954 -400.355816) (xy 292.978367 -400.377074) (xy 292.926858 -400.414206)
			(xy 292.871123 -400.44463) (xy 292.812032 -400.467871) (xy 292.750504 -400.483567) (xy 292.687501 -400.491474)
			(xy 292.655752 -400.49196) (xy 292.655498 -400.49196) (xy 292.623534 -400.491554) (xy 292.56011 -400.483542)
			(xy 292.498191 -400.467643) (xy 292.438752 -400.44411) (xy 292.382731 -400.413312) (xy 292.331013 -400.375736)
			(xy 292.284411 -400.331974) (xy 292.243662 -400.282717) (xy 292.209408 -400.22874) (xy 292.182189 -400.170897)
			(xy 292.162434 -400.110098) (xy 292.150455 -400.047302) (xy 292.146441 -399.9835) (xy 291.386484 -399.9835)
			(xy 291.38247 -400.047293) (xy 291.370493 -400.110079) (xy 291.350741 -400.17087) (xy 291.323525 -400.228705)
			(xy 291.289276 -400.282674) (xy 291.248532 -400.331924) (xy 291.201937 -400.375679) (xy 291.150226 -400.41325)
			(xy 291.094213 -400.444043) (xy 291.034783 -400.467573) (xy 290.972872 -400.483468) (xy 290.909457 -400.491479)
			(xy 290.877498 -400.49196) (xy 290.877244 -400.49196) (xy 290.845498 -400.491442) (xy 290.782502 -400.483512)
			(xy 290.720982 -400.467809) (xy 290.661894 -400.444575) (xy 290.606154 -400.414171) (xy 290.554629 -400.37707)
			(xy 290.531042 -400.355816) (xy 290.523779 -400.349632) (xy 290.506029 -400.342681) (xy 290.486967 -400.342681)
			(xy 290.469217 -400.349632) (xy 290.461954 -400.355816) (xy 290.438367 -400.377074) (xy 290.386858 -400.414206)
			(xy 290.331123 -400.44463) (xy 290.272032 -400.467871) (xy 290.210504 -400.483567) (xy 290.147501 -400.491474)
			(xy 290.115752 -400.49196) (xy 290.115498 -400.49196) (xy 290.083534 -400.491554) (xy 290.02011 -400.483542)
			(xy 289.958191 -400.467643) (xy 289.898752 -400.44411) (xy 289.842731 -400.413312) (xy 289.791013 -400.375736)
			(xy 289.744411 -400.331974) (xy 289.703662 -400.282717) (xy 289.669408 -400.22874) (xy 289.642189 -400.170897)
			(xy 289.622434 -400.110098) (xy 289.610455 -400.047302) (xy 289.606441 -399.9835) (xy 281.686508 -399.9835)
			(xy 281.686508 -400.885449) (xy 303.599106 -400.885449) (xy 303.599106 -400.830951) (xy 303.606862 -400.777009)
			(xy 303.622215 -400.724719) (xy 303.644854 -400.675146) (xy 303.674317 -400.6293) (xy 303.710004 -400.588113)
			(xy 303.75119 -400.552424) (xy 303.797036 -400.52296) (xy 303.846608 -400.500319) (xy 303.898897 -400.484964)
			(xy 303.952839 -400.477207) (xy 303.980088 -400.47672) (xy 304.843688 -400.47672) (xy 304.870943 -400.477126)
			(xy 304.9249 -400.484882) (xy 304.977203 -400.500238) (xy 305.026788 -400.522882) (xy 305.072646 -400.552352)
			(xy 305.113843 -400.588048) (xy 305.149541 -400.629244) (xy 305.179012 -400.675101) (xy 305.201657 -400.724686)
			(xy 305.217015 -400.776989) (xy 305.224773 -400.830945) (xy 305.224773 -400.885452) (xy 306.662283 -400.885452)
			(xy 306.662283 -400.830948) (xy 306.67004 -400.776998) (xy 306.685397 -400.724702) (xy 306.70804 -400.675124)
			(xy 306.737508 -400.629273) (xy 306.773202 -400.588082) (xy 306.814395 -400.552391) (xy 306.860248 -400.522926)
			(xy 306.909828 -400.500287) (xy 306.962126 -400.484935) (xy 307.016076 -400.477181) (xy 307.043328 -400.47672)
			(xy 307.906928 -400.47672) (xy 307.93418 -400.477152) (xy 307.988129 -400.484912) (xy 308.040424 -400.500271)
			(xy 308.090001 -400.522915) (xy 308.135851 -400.552384) (xy 308.177041 -400.588079) (xy 308.212732 -400.629271)
			(xy 308.242198 -400.675123) (xy 308.264839 -400.724702) (xy 308.280194 -400.776999) (xy 308.28795 -400.830948)
			(xy 308.28795 -400.885448) (xy 309.725606 -400.885448) (xy 309.725606 -400.830952) (xy 309.733361 -400.777011)
			(xy 309.748714 -400.724723) (xy 309.771351 -400.675152) (xy 309.800812 -400.629306) (xy 309.836497 -400.58812)
			(xy 309.877681 -400.552431) (xy 309.923524 -400.522966) (xy 309.973093 -400.500325) (xy 310.02538 -400.484968)
			(xy 310.07932 -400.477208) (xy 310.106568 -400.47672) (xy 310.970168 -400.47672) (xy 310.997424 -400.477125)
			(xy 311.051383 -400.484879) (xy 311.103688 -400.500233) (xy 311.153276 -400.522875) (xy 311.199137 -400.552345)
			(xy 311.240336 -400.588041) (xy 311.276036 -400.629238) (xy 311.305509 -400.675096) (xy 311.328156 -400.724682)
			(xy 311.343515 -400.776986) (xy 311.351273 -400.830944) (xy 311.351273 -400.885451) (xy 312.788783 -400.885451)
			(xy 312.788783 -400.830949) (xy 312.79654 -400.777001) (xy 312.811895 -400.724706) (xy 312.834537 -400.675129)
			(xy 312.864003 -400.629279) (xy 312.899695 -400.588089) (xy 312.940886 -400.552398) (xy 312.986736 -400.522933)
			(xy 313.036314 -400.500292) (xy 313.088609 -400.484938) (xy 313.142557 -400.477183) (xy 313.169808 -400.47672)
			(xy 314.033408 -400.47672) (xy 314.060661 -400.47715) (xy 314.114612 -400.484908) (xy 314.166909 -400.500265)
			(xy 314.216489 -400.522909) (xy 314.262342 -400.552377) (xy 314.303534 -400.588071) (xy 314.339228 -400.629264)
			(xy 314.368695 -400.675118) (xy 314.391337 -400.724698) (xy 314.406693 -400.776996) (xy 314.41445 -400.830947)
			(xy 314.41445 -400.885453) (xy 315.851983 -400.885453) (xy 315.851983 -400.830947) (xy 315.859741 -400.776996)
			(xy 315.875098 -400.724698) (xy 315.897743 -400.675118) (xy 315.927213 -400.629266) (xy 315.962909 -400.588075)
			(xy 316.004105 -400.552384) (xy 316.04996 -400.52292) (xy 316.099543 -400.500282) (xy 316.151843 -400.484931)
			(xy 316.205795 -400.47718) (xy 316.233048 -400.47672) (xy 317.096648 -400.47672) (xy 317.123899 -400.477153)
			(xy 317.177846 -400.484916) (xy 317.230138 -400.500276) (xy 317.279713 -400.522922) (xy 317.325561 -400.552391)
			(xy 317.366748 -400.588086) (xy 317.402437 -400.629278) (xy 317.431901 -400.675129) (xy 317.454541 -400.724707)
			(xy 317.469894 -400.777001) (xy 317.47765 -400.830949) (xy 317.47765 -400.885449) (xy 318.915306 -400.885449)
			(xy 318.915306 -400.830951) (xy 318.923062 -400.777009) (xy 318.938415 -400.724719) (xy 318.961054 -400.675146)
			(xy 318.990517 -400.6293) (xy 319.026204 -400.588113) (xy 319.06739 -400.552424) (xy 319.113236 -400.52296)
			(xy 319.162808 -400.500319) (xy 319.215097 -400.484964) (xy 319.269039 -400.477207) (xy 319.296288 -400.47672)
			(xy 320.159888 -400.47672) (xy 320.187143 -400.477126) (xy 320.2411 -400.484882) (xy 320.293403 -400.500238)
			(xy 320.342988 -400.522882) (xy 320.388846 -400.552352) (xy 320.430043 -400.588048) (xy 320.465741 -400.629244)
			(xy 320.495212 -400.675101) (xy 320.517857 -400.724686) (xy 320.533215 -400.776989) (xy 320.540973 -400.830945)
			(xy 320.540973 -400.885452) (xy 321.978483 -400.885452) (xy 321.978483 -400.830948) (xy 321.98624 -400.776998)
			(xy 322.001597 -400.724702) (xy 322.02424 -400.675124) (xy 322.053708 -400.629273) (xy 322.089402 -400.588082)
			(xy 322.130595 -400.552391) (xy 322.176448 -400.522926) (xy 322.226028 -400.500287) (xy 322.278326 -400.484935)
			(xy 322.332276 -400.477181) (xy 322.359528 -400.47672) (xy 323.223128 -400.47672) (xy 323.25038 -400.477152)
			(xy 323.304329 -400.484912) (xy 323.356624 -400.500271) (xy 323.406201 -400.522915) (xy 323.452051 -400.552384)
			(xy 323.493241 -400.588079) (xy 323.528932 -400.629271) (xy 323.558398 -400.675123) (xy 323.581039 -400.724702)
			(xy 323.596394 -400.776999) (xy 323.60415 -400.830948) (xy 323.60415 -400.885448) (xy 325.041806 -400.885448)
			(xy 325.041806 -400.830952) (xy 325.049561 -400.777011) (xy 325.064914 -400.724723) (xy 325.087551 -400.675152)
			(xy 325.117012 -400.629306) (xy 325.152697 -400.58812) (xy 325.193881 -400.552431) (xy 325.239724 -400.522966)
			(xy 325.289293 -400.500325) (xy 325.34158 -400.484968) (xy 325.39552 -400.477208) (xy 325.422768 -400.47672)
			(xy 326.286368 -400.47672) (xy 326.313624 -400.477125) (xy 326.367583 -400.484879) (xy 326.419888 -400.500233)
			(xy 326.469476 -400.522875) (xy 326.515337 -400.552345) (xy 326.556536 -400.588041) (xy 326.592236 -400.629238)
			(xy 326.621709 -400.675096) (xy 326.644356 -400.724682) (xy 326.659715 -400.776986) (xy 326.667473 -400.830944)
			(xy 326.667473 -400.885451) (xy 328.104983 -400.885451) (xy 328.104983 -400.830949) (xy 328.11274 -400.777001)
			(xy 328.128095 -400.724706) (xy 328.150737 -400.675129) (xy 328.180203 -400.629279) (xy 328.215895 -400.588089)
			(xy 328.257086 -400.552398) (xy 328.302936 -400.522933) (xy 328.352514 -400.500292) (xy 328.404809 -400.484938)
			(xy 328.458757 -400.477183) (xy 328.486008 -400.47672) (xy 329.349608 -400.47672) (xy 329.376861 -400.47715)
			(xy 329.430812 -400.484908) (xy 329.483109 -400.500265) (xy 329.532689 -400.522909) (xy 329.578542 -400.552377)
			(xy 329.619734 -400.588071) (xy 329.655428 -400.629264) (xy 329.684895 -400.675118) (xy 329.707537 -400.724698)
			(xy 329.722893 -400.776996) (xy 329.73065 -400.830947) (xy 329.73065 -400.885453) (xy 331.168183 -400.885453)
			(xy 331.168183 -400.830947) (xy 331.175941 -400.776996) (xy 331.191298 -400.724698) (xy 331.213943 -400.675118)
			(xy 331.243413 -400.629266) (xy 331.279109 -400.588075) (xy 331.320305 -400.552384) (xy 331.36616 -400.52292)
			(xy 331.415743 -400.500282) (xy 331.468043 -400.484931) (xy 331.521995 -400.47718) (xy 331.549248 -400.47672)
			(xy 332.412848 -400.47672) (xy 332.440099 -400.477153) (xy 332.494046 -400.484916) (xy 332.546338 -400.500276)
			(xy 332.595913 -400.522922) (xy 332.641761 -400.552391) (xy 332.682948 -400.588086) (xy 332.718637 -400.629278)
			(xy 332.748101 -400.675129) (xy 332.770741 -400.724707) (xy 332.786094 -400.777001) (xy 332.79385 -400.830949)
			(xy 332.79385 -400.885449) (xy 334.231506 -400.885449) (xy 334.231506 -400.830951) (xy 334.239262 -400.777009)
			(xy 334.254615 -400.724719) (xy 334.277254 -400.675146) (xy 334.306717 -400.6293) (xy 334.342404 -400.588113)
			(xy 334.38359 -400.552424) (xy 334.429436 -400.52296) (xy 334.479008 -400.500319) (xy 334.531297 -400.484964)
			(xy 334.585239 -400.477207) (xy 334.612488 -400.47672) (xy 335.476088 -400.47672) (xy 335.503343 -400.477126)
			(xy 335.5573 -400.484882) (xy 335.609603 -400.500238) (xy 335.659188 -400.522882) (xy 335.705046 -400.552352)
			(xy 335.746243 -400.588048) (xy 335.781941 -400.629244) (xy 335.811412 -400.675101) (xy 335.834057 -400.724686)
			(xy 335.849415 -400.776989) (xy 335.857173 -400.830945) (xy 335.857173 -400.885452) (xy 337.294683 -400.885452)
			(xy 337.294683 -400.830948) (xy 337.30244 -400.776998) (xy 337.317797 -400.724702) (xy 337.34044 -400.675124)
			(xy 337.369908 -400.629273) (xy 337.405602 -400.588082) (xy 337.446795 -400.552391) (xy 337.492648 -400.522926)
			(xy 337.542228 -400.500287) (xy 337.594526 -400.484935) (xy 337.648476 -400.477181) (xy 337.675728 -400.47672)
			(xy 338.539328 -400.47672) (xy 338.56658 -400.477152) (xy 338.620529 -400.484912) (xy 338.672824 -400.500271)
			(xy 338.722401 -400.522915) (xy 338.768251 -400.552384) (xy 338.809441 -400.588079) (xy 338.845132 -400.629271)
			(xy 338.874598 -400.675123) (xy 338.897239 -400.724702) (xy 338.912594 -400.776999) (xy 338.92035 -400.830948)
			(xy 338.92035 -400.885448) (xy 340.358006 -400.885448) (xy 340.358006 -400.830952) (xy 340.365761 -400.777011)
			(xy 340.381114 -400.724723) (xy 340.403751 -400.675152) (xy 340.433212 -400.629306) (xy 340.468897 -400.58812)
			(xy 340.510081 -400.552431) (xy 340.555924 -400.522966) (xy 340.605493 -400.500325) (xy 340.65778 -400.484968)
			(xy 340.71172 -400.477208) (xy 340.738968 -400.47672) (xy 341.602568 -400.47672) (xy 341.629824 -400.477125)
			(xy 341.683783 -400.484879) (xy 341.736088 -400.500233) (xy 341.785676 -400.522875) (xy 341.831537 -400.552345)
			(xy 341.872736 -400.588041) (xy 341.908436 -400.629238) (xy 341.937909 -400.675096) (xy 341.960556 -400.724682)
			(xy 341.975915 -400.776986) (xy 341.983673 -400.830944) (xy 341.983673 -400.885451) (xy 343.421183 -400.885451)
			(xy 343.421183 -400.830949) (xy 343.42894 -400.777001) (xy 343.444295 -400.724706) (xy 343.466937 -400.675129)
			(xy 343.496403 -400.629279) (xy 343.532095 -400.588089) (xy 343.573286 -400.552398) (xy 343.619136 -400.522933)
			(xy 343.668714 -400.500292) (xy 343.721009 -400.484938) (xy 343.774957 -400.477183) (xy 343.802208 -400.47672)
			(xy 344.665808 -400.47672) (xy 344.693061 -400.47715) (xy 344.747012 -400.484908) (xy 344.799309 -400.500265)
			(xy 344.848889 -400.522909) (xy 344.894742 -400.552377) (xy 344.935934 -400.588071) (xy 344.971628 -400.629264)
			(xy 345.001095 -400.675118) (xy 345.023737 -400.724698) (xy 345.039093 -400.776996) (xy 345.04685 -400.830947)
			(xy 345.04685 -400.885453) (xy 346.484383 -400.885453) (xy 346.484383 -400.830947) (xy 346.492141 -400.776996)
			(xy 346.507498 -400.724698) (xy 346.530143 -400.675118) (xy 346.559613 -400.629266) (xy 346.595309 -400.588075)
			(xy 346.636505 -400.552384) (xy 346.68236 -400.52292) (xy 346.731943 -400.500282) (xy 346.784243 -400.484931)
			(xy 346.838195 -400.47718) (xy 346.865448 -400.47672) (xy 347.729048 -400.47672) (xy 347.756299 -400.477153)
			(xy 347.810246 -400.484916) (xy 347.862538 -400.500276) (xy 347.912113 -400.522922) (xy 347.957961 -400.552391)
			(xy 347.999148 -400.588086) (xy 348.034837 -400.629278) (xy 348.064301 -400.675129) (xy 348.086941 -400.724707)
			(xy 348.102294 -400.777001) (xy 348.11005 -400.830949) (xy 348.11005 -400.885449) (xy 349.547706 -400.885449)
			(xy 349.547706 -400.830951) (xy 349.555462 -400.777009) (xy 349.570815 -400.724719) (xy 349.593454 -400.675146)
			(xy 349.622917 -400.6293) (xy 349.658604 -400.588113) (xy 349.69979 -400.552424) (xy 349.745636 -400.52296)
			(xy 349.795208 -400.500319) (xy 349.847497 -400.484964) (xy 349.901439 -400.477207) (xy 349.928688 -400.47672)
			(xy 350.792288 -400.47672) (xy 350.819543 -400.477126) (xy 350.8735 -400.484882) (xy 350.925803 -400.500238)
			(xy 350.975388 -400.522882) (xy 351.021246 -400.552352) (xy 351.062443 -400.588048) (xy 351.098141 -400.629244)
			(xy 351.127612 -400.675101) (xy 351.150257 -400.724686) (xy 351.165615 -400.776989) (xy 351.173373 -400.830945)
			(xy 351.173373 -400.885452) (xy 371.041883 -400.885452) (xy 371.041883 -400.830948) (xy 371.049641 -400.776998)
			(xy 371.064997 -400.724702) (xy 371.08764 -400.675123) (xy 371.117109 -400.629272) (xy 371.152803 -400.588082)
			(xy 371.193996 -400.552391) (xy 371.23985 -400.522926) (xy 371.28943 -400.500286) (xy 371.341728 -400.484934)
			(xy 371.395678 -400.477181) (xy 371.42293 -400.47672) (xy 372.28653 -400.47672) (xy 372.313782 -400.477152)
			(xy 372.36773 -400.484912) (xy 372.420025 -400.500271) (xy 372.469602 -400.522916) (xy 372.515452 -400.552385)
			(xy 372.556642 -400.588079) (xy 372.592333 -400.629272) (xy 372.621799 -400.675124) (xy 372.644439 -400.724703)
			(xy 372.659794 -400.776999) (xy 372.66755 -400.830948) (xy 372.66755 -400.885448) (xy 374.105206 -400.885448)
			(xy 374.105206 -400.830952) (xy 374.112961 -400.777011) (xy 374.128314 -400.724723) (xy 374.150951 -400.675151)
			(xy 374.180412 -400.629306) (xy 374.216098 -400.588119) (xy 374.257281 -400.55243) (xy 374.303125 -400.522965)
			(xy 374.352694 -400.500324) (xy 374.404982 -400.484968) (xy 374.458922 -400.477208) (xy 374.48617 -400.47672)
			(xy 375.34977 -400.47672) (xy 375.377026 -400.477125) (xy 375.430984 -400.484879) (xy 375.48329 -400.500234)
			(xy 375.532877 -400.522876) (xy 375.578738 -400.552345) (xy 375.619937 -400.588042) (xy 375.655637 -400.629238)
			(xy 375.68511 -400.675096) (xy 375.707756 -400.724682) (xy 375.723115 -400.776986) (xy 375.730873 -400.830944)
			(xy 375.730873 -400.885451) (xy 377.168383 -400.885451) (xy 377.168383 -400.830949) (xy 377.17614 -400.777001)
			(xy 377.191495 -400.724706) (xy 377.214137 -400.675129) (xy 377.243604 -400.629279) (xy 377.279296 -400.588089)
			(xy 377.320487 -400.552398) (xy 377.366338 -400.522932) (xy 377.415915 -400.500292) (xy 377.468211 -400.484938)
			(xy 377.522159 -400.477183) (xy 377.54941 -400.47672) (xy 378.41301 -400.47672) (xy 378.440263 -400.477151)
			(xy 378.494213 -400.484909) (xy 378.546511 -400.500266) (xy 378.59609 -400.522909) (xy 378.641943 -400.552378)
			(xy 378.683135 -400.588072) (xy 378.718828 -400.629265) (xy 378.748296 -400.675118) (xy 378.770938 -400.724699)
			(xy 378.786293 -400.776996) (xy 378.79405 -400.830947) (xy 378.79405 -400.885447) (xy 380.231706 -400.885447)
			(xy 380.231706 -400.830953) (xy 380.239461 -400.777014) (xy 380.254812 -400.724727) (xy 380.277448 -400.675157)
			(xy 380.306907 -400.629312) (xy 380.342591 -400.588126) (xy 380.383772 -400.552437) (xy 380.429613 -400.522972)
			(xy 380.47918 -400.50033) (xy 380.531465 -400.484971) (xy 380.585403 -400.47721) (xy 380.61265 -400.47672)
			(xy 381.47625 -400.47672) (xy 381.503507 -400.477124) (xy 381.557468 -400.484875) (xy 381.609775 -400.500228)
			(xy 381.659365 -400.522869) (xy 381.705228 -400.552338) (xy 381.74643 -400.588035) (xy 381.782132 -400.629232)
			(xy 381.811607 -400.675091) (xy 381.834254 -400.724678) (xy 381.849614 -400.776983) (xy 381.857373 -400.830943)
			(xy 381.857373 -400.885449) (xy 383.294906 -400.885449) (xy 383.294906 -400.830951) (xy 383.302662 -400.777008)
			(xy 383.318015 -400.724718) (xy 383.340654 -400.675145) (xy 383.370117 -400.629299) (xy 383.405805 -400.588112)
			(xy 383.446991 -400.552423) (xy 383.492837 -400.522959) (xy 383.542409 -400.500319) (xy 383.594699 -400.484964)
			(xy 383.648641 -400.477207) (xy 383.67589 -400.47672) (xy 384.53949 -400.47672) (xy 384.566745 -400.477126)
			(xy 384.620701 -400.484883) (xy 384.673004 -400.500239) (xy 384.722589 -400.522883) (xy 384.768447 -400.552352)
			(xy 384.809644 -400.588049) (xy 384.845342 -400.629245) (xy 384.874813 -400.675102) (xy 384.897458 -400.724686)
			(xy 384.912815 -400.776989) (xy 384.920573 -400.830945) (xy 384.920573 -400.885452) (xy 386.358083 -400.885452)
			(xy 386.358083 -400.830948) (xy 386.365841 -400.776998) (xy 386.381197 -400.724702) (xy 386.40384 -400.675123)
			(xy 386.433309 -400.629272) (xy 386.469003 -400.588082) (xy 386.510196 -400.552391) (xy 386.55605 -400.522926)
			(xy 386.60563 -400.500286) (xy 386.657928 -400.484934) (xy 386.711878 -400.477181) (xy 386.73913 -400.47672)
			(xy 387.60273 -400.47672) (xy 387.629982 -400.477152) (xy 387.68393 -400.484912) (xy 387.736225 -400.500271)
			(xy 387.785802 -400.522916) (xy 387.831652 -400.552385) (xy 387.872842 -400.588079) (xy 387.908533 -400.629272)
			(xy 387.937999 -400.675124) (xy 387.960639 -400.724703) (xy 387.975994 -400.776999) (xy 387.98375 -400.830948)
			(xy 387.98375 -400.885448) (xy 389.421406 -400.885448) (xy 389.421406 -400.830952) (xy 389.429161 -400.777011)
			(xy 389.444514 -400.724723) (xy 389.467151 -400.675151) (xy 389.496612 -400.629306) (xy 389.532298 -400.588119)
			(xy 389.573481 -400.55243) (xy 389.619325 -400.522965) (xy 389.668894 -400.500324) (xy 389.721182 -400.484968)
			(xy 389.775122 -400.477208) (xy 389.80237 -400.47672) (xy 390.66597 -400.47672) (xy 390.693226 -400.477125)
			(xy 390.747184 -400.484879) (xy 390.79949 -400.500234) (xy 390.849077 -400.522876) (xy 390.894938 -400.552345)
			(xy 390.936137 -400.588042) (xy 390.971837 -400.629238) (xy 391.00131 -400.675096) (xy 391.023956 -400.724682)
			(xy 391.039315 -400.776986) (xy 391.047073 -400.830944) (xy 391.047073 -400.885451) (xy 392.484583 -400.885451)
			(xy 392.484583 -400.830949) (xy 392.49234 -400.777001) (xy 392.507695 -400.724706) (xy 392.530337 -400.675129)
			(xy 392.559804 -400.629279) (xy 392.595496 -400.588089) (xy 392.636687 -400.552398) (xy 392.682538 -400.522932)
			(xy 392.732115 -400.500292) (xy 392.784411 -400.484938) (xy 392.838359 -400.477183) (xy 392.86561 -400.47672)
			(xy 393.72921 -400.47672) (xy 393.756463 -400.477151) (xy 393.810413 -400.484909) (xy 393.862711 -400.500266)
			(xy 393.91229 -400.522909) (xy 393.958143 -400.552378) (xy 393.999335 -400.588072) (xy 394.035028 -400.629265)
			(xy 394.064496 -400.675118) (xy 394.087138 -400.724699) (xy 394.102493 -400.776996) (xy 394.11025 -400.830947)
			(xy 394.11025 -400.885447) (xy 395.547906 -400.885447) (xy 395.547906 -400.830953) (xy 395.555661 -400.777014)
			(xy 395.571012 -400.724727) (xy 395.593648 -400.675157) (xy 395.623107 -400.629312) (xy 395.658791 -400.588126)
			(xy 395.699972 -400.552437) (xy 395.745813 -400.522972) (xy 395.79538 -400.50033) (xy 395.847665 -400.484971)
			(xy 395.901603 -400.47721) (xy 395.92885 -400.47672) (xy 396.79245 -400.47672) (xy 396.819707 -400.477124)
			(xy 396.873668 -400.484875) (xy 396.925975 -400.500228) (xy 396.975565 -400.522869) (xy 397.021428 -400.552338)
			(xy 397.06263 -400.588035) (xy 397.098332 -400.629232) (xy 397.127807 -400.675091) (xy 397.150454 -400.724678)
			(xy 397.165814 -400.776983) (xy 397.173573 -400.830943) (xy 397.173573 -400.885449) (xy 398.611106 -400.885449)
			(xy 398.611106 -400.830951) (xy 398.618862 -400.777008) (xy 398.634215 -400.724718) (xy 398.656854 -400.675145)
			(xy 398.686317 -400.629299) (xy 398.722005 -400.588112) (xy 398.763191 -400.552423) (xy 398.809037 -400.522959)
			(xy 398.858609 -400.500319) (xy 398.910899 -400.484964) (xy 398.964841 -400.477207) (xy 398.99209 -400.47672)
			(xy 399.85569 -400.47672) (xy 399.882945 -400.477126) (xy 399.936901 -400.484883) (xy 399.989204 -400.500239)
			(xy 400.038789 -400.522883) (xy 400.084647 -400.552352) (xy 400.125844 -400.588049) (xy 400.161542 -400.629245)
			(xy 400.191013 -400.675102) (xy 400.213658 -400.724686) (xy 400.229015 -400.776989) (xy 400.236773 -400.830945)
			(xy 400.236773 -400.885452) (xy 401.674283 -400.885452) (xy 401.674283 -400.830948) (xy 401.682041 -400.776998)
			(xy 401.697397 -400.724702) (xy 401.72004 -400.675123) (xy 401.749509 -400.629272) (xy 401.785203 -400.588082)
			(xy 401.826396 -400.552391) (xy 401.87225 -400.522926) (xy 401.92183 -400.500286) (xy 401.974128 -400.484934)
			(xy 402.028078 -400.477181) (xy 402.05533 -400.47672) (xy 402.91893 -400.47672) (xy 402.946182 -400.477152)
			(xy 403.00013 -400.484912) (xy 403.052425 -400.500271) (xy 403.102002 -400.522916) (xy 403.147852 -400.552385)
			(xy 403.189042 -400.588079) (xy 403.224733 -400.629272) (xy 403.254199 -400.675124) (xy 403.276839 -400.724703)
			(xy 403.292194 -400.776999) (xy 403.29995 -400.830948) (xy 403.29995 -400.885448) (xy 404.737606 -400.885448)
			(xy 404.737606 -400.830952) (xy 404.745361 -400.777011) (xy 404.760714 -400.724723) (xy 404.783351 -400.675151)
			(xy 404.812812 -400.629306) (xy 404.848498 -400.588119) (xy 404.889681 -400.55243) (xy 404.935525 -400.522965)
			(xy 404.985094 -400.500324) (xy 405.037382 -400.484968) (xy 405.091322 -400.477208) (xy 405.11857 -400.47672)
			(xy 405.98217 -400.47672) (xy 406.009426 -400.477125) (xy 406.063384 -400.484879) (xy 406.11569 -400.500234)
			(xy 406.165277 -400.522876) (xy 406.211138 -400.552345) (xy 406.252337 -400.588042) (xy 406.288037 -400.629238)
			(xy 406.31751 -400.675096) (xy 406.340156 -400.724682) (xy 406.355515 -400.776986) (xy 406.363273 -400.830944)
			(xy 406.363273 -400.885451) (xy 407.800783 -400.885451) (xy 407.800783 -400.830949) (xy 407.80854 -400.777001)
			(xy 407.823895 -400.724706) (xy 407.846537 -400.675129) (xy 407.876004 -400.629279) (xy 407.911696 -400.588089)
			(xy 407.952887 -400.552398) (xy 407.998738 -400.522932) (xy 408.048315 -400.500292) (xy 408.100611 -400.484938)
			(xy 408.154559 -400.477183) (xy 408.18181 -400.47672) (xy 409.04541 -400.47672) (xy 409.072663 -400.477151)
			(xy 409.126613 -400.484909) (xy 409.178911 -400.500266) (xy 409.22849 -400.522909) (xy 409.274343 -400.552378)
			(xy 409.315535 -400.588072) (xy 409.351228 -400.629265) (xy 409.380696 -400.675118) (xy 409.403338 -400.724699)
			(xy 409.418693 -400.776996) (xy 409.42645 -400.830947) (xy 409.42645 -400.885447) (xy 410.864106 -400.885447)
			(xy 410.864106 -400.830953) (xy 410.871861 -400.777014) (xy 410.887212 -400.724727) (xy 410.909848 -400.675157)
			(xy 410.939307 -400.629312) (xy 410.974991 -400.588126) (xy 411.016172 -400.552437) (xy 411.062013 -400.522972)
			(xy 411.11158 -400.50033) (xy 411.163865 -400.484971) (xy 411.217803 -400.47721) (xy 411.24505 -400.47672)
			(xy 412.10865 -400.47672) (xy 412.135907 -400.477124) (xy 412.189868 -400.484875) (xy 412.242175 -400.500228)
			(xy 412.291765 -400.522869) (xy 412.337628 -400.552338) (xy 412.37883 -400.588035) (xy 412.414532 -400.629232)
			(xy 412.444007 -400.675091) (xy 412.466654 -400.724678) (xy 412.482014 -400.776983) (xy 412.489773 -400.830943)
			(xy 412.489773 -400.885449) (xy 413.927306 -400.885449) (xy 413.927306 -400.830951) (xy 413.935062 -400.777008)
			(xy 413.950415 -400.724718) (xy 413.973054 -400.675145) (xy 414.002517 -400.629299) (xy 414.038205 -400.588112)
			(xy 414.079391 -400.552423) (xy 414.125237 -400.522959) (xy 414.174809 -400.500319) (xy 414.227099 -400.484964)
			(xy 414.281041 -400.477207) (xy 414.30829 -400.47672) (xy 415.17189 -400.47672) (xy 415.199145 -400.477126)
			(xy 415.253101 -400.484883) (xy 415.305404 -400.500239) (xy 415.354989 -400.522883) (xy 415.400847 -400.552352)
			(xy 415.442044 -400.588049) (xy 415.477742 -400.629245) (xy 415.507213 -400.675102) (xy 415.529858 -400.724686)
			(xy 415.545215 -400.776989) (xy 415.552973 -400.830945) (xy 415.552973 -400.885452) (xy 416.990483 -400.885452)
			(xy 416.990483 -400.830948) (xy 416.998241 -400.776998) (xy 417.013597 -400.724702) (xy 417.03624 -400.675123)
			(xy 417.065709 -400.629272) (xy 417.101403 -400.588082) (xy 417.142596 -400.552391) (xy 417.18845 -400.522926)
			(xy 417.23803 -400.500286) (xy 417.290328 -400.484934) (xy 417.344278 -400.477181) (xy 417.37153 -400.47672)
			(xy 418.23513 -400.47672) (xy 418.262382 -400.477152) (xy 418.31633 -400.484912) (xy 418.368625 -400.500271)
			(xy 418.418202 -400.522916) (xy 418.464052 -400.552385) (xy 418.505242 -400.588079) (xy 418.540933 -400.629272)
			(xy 418.570399 -400.675124) (xy 418.593039 -400.724703) (xy 418.608394 -400.776999) (xy 418.61615 -400.830948)
			(xy 418.61615 -400.885452) (xy 418.608394 -400.939401) (xy 418.593039 -400.991697) (xy 418.570399 -401.041276)
			(xy 418.540933 -401.087128) (xy 418.505242 -401.128321) (xy 418.464052 -401.164015) (xy 418.418202 -401.193484)
			(xy 418.368625 -401.216129) (xy 418.31633 -401.231488) (xy 418.262382 -401.239248) (xy 418.23513 -401.239736)
			(xy 417.37153 -401.239736) (xy 417.344278 -401.239219) (xy 417.290328 -401.231466) (xy 417.23803 -401.216114)
			(xy 417.18845 -401.193474) (xy 417.142596 -401.164009) (xy 417.101403 -401.128318) (xy 417.065709 -401.087128)
			(xy 417.03624 -401.041277) (xy 417.013597 -400.991698) (xy 416.998241 -400.939402) (xy 416.990483 -400.885452)
			(xy 415.552973 -400.885452) (xy 415.552973 -400.885455) (xy 415.545215 -400.939411) (xy 415.529858 -400.991714)
			(xy 415.507213 -401.041298) (xy 415.477742 -401.087155) (xy 415.442044 -401.128351) (xy 415.400847 -401.164048)
			(xy 415.354989 -401.193517) (xy 415.305404 -401.216161) (xy 415.253101 -401.231517) (xy 415.199145 -401.239274)
			(xy 415.17189 -401.239736) (xy 414.30829 -401.239736) (xy 414.281041 -401.239193) (xy 414.227099 -401.231436)
			(xy 414.174809 -401.216081) (xy 414.125237 -401.193441) (xy 414.079391 -401.163977) (xy 414.038205 -401.128288)
			(xy 414.002517 -401.087101) (xy 413.973054 -401.041255) (xy 413.950415 -400.991682) (xy 413.935062 -400.939392)
			(xy 413.927306 -400.885449) (xy 412.489773 -400.885449) (xy 412.489773 -400.885457) (xy 412.482014 -400.939416)
			(xy 412.466654 -400.991722) (xy 412.444007 -401.041309) (xy 412.414532 -401.087168) (xy 412.37883 -401.128365)
			(xy 412.337628 -401.164062) (xy 412.291765 -401.193531) (xy 412.242175 -401.216172) (xy 412.189868 -401.231525)
			(xy 412.135907 -401.239276) (xy 412.10865 -401.239736) (xy 411.24505 -401.239736) (xy 411.217803 -401.23919)
			(xy 411.163865 -401.231429) (xy 411.11158 -401.21607) (xy 411.062013 -401.193428) (xy 411.016172 -401.163963)
			(xy 410.974991 -401.128274) (xy 410.939307 -401.087088) (xy 410.909848 -401.041243) (xy 410.887212 -400.991673)
			(xy 410.871861 -400.939386) (xy 410.864106 -400.885447) (xy 409.42645 -400.885447) (xy 409.42645 -400.885453)
			(xy 409.418693 -400.939404) (xy 409.403338 -400.991701) (xy 409.380696 -401.041282) (xy 409.351228 -401.087135)
			(xy 409.315535 -401.128328) (xy 409.274343 -401.164022) (xy 409.22849 -401.193491) (xy 409.178911 -401.216134)
			(xy 409.126613 -401.231491) (xy 409.072663 -401.239249) (xy 409.04541 -401.239736) (xy 408.18181 -401.239736)
			(xy 408.154559 -401.239217) (xy 408.100611 -401.231462) (xy 408.048315 -401.216108) (xy 407.998738 -401.193468)
			(xy 407.952887 -401.164002) (xy 407.911696 -401.128311) (xy 407.876004 -401.087121) (xy 407.846537 -401.041271)
			(xy 407.823895 -400.991694) (xy 407.80854 -400.939399) (xy 407.800783 -400.885451) (xy 406.363273 -400.885451)
			(xy 406.363273 -400.885456) (xy 406.355515 -400.939414) (xy 406.340156 -400.991718) (xy 406.31751 -401.041304)
			(xy 406.288037 -401.087162) (xy 406.252337 -401.128358) (xy 406.211138 -401.164055) (xy 406.165277 -401.193524)
			(xy 406.11569 -401.216166) (xy 406.063384 -401.231521) (xy 406.009426 -401.239275) (xy 405.98217 -401.239736)
			(xy 405.11857 -401.239736) (xy 405.091322 -401.239192) (xy 405.037382 -401.231432) (xy 404.985094 -401.216076)
			(xy 404.935525 -401.193435) (xy 404.889682 -401.16397) (xy 404.848498 -401.128281) (xy 404.812812 -401.087094)
			(xy 404.783351 -401.041249) (xy 404.760714 -400.991677) (xy 404.745361 -400.939389) (xy 404.737606 -400.885448)
			(xy 403.29995 -400.885448) (xy 403.29995 -400.885452) (xy 403.292194 -400.939401) (xy 403.276839 -400.991697)
			(xy 403.254199 -401.041276) (xy 403.224733 -401.087128) (xy 403.189042 -401.128321) (xy 403.147852 -401.164015)
			(xy 403.102002 -401.193484) (xy 403.052425 -401.216129) (xy 403.00013 -401.231488) (xy 402.946182 -401.239248)
			(xy 402.91893 -401.239736) (xy 402.05533 -401.239736) (xy 402.028078 -401.239219) (xy 401.974128 -401.231466)
			(xy 401.92183 -401.216114) (xy 401.87225 -401.193474) (xy 401.826396 -401.164009) (xy 401.785203 -401.128318)
			(xy 401.749509 -401.087128) (xy 401.72004 -401.041277) (xy 401.697397 -400.991698) (xy 401.682041 -400.939402)
			(xy 401.674283 -400.885452) (xy 400.236773 -400.885452) (xy 400.236773 -400.885455) (xy 400.229015 -400.939411)
			(xy 400.213658 -400.991714) (xy 400.191013 -401.041298) (xy 400.161542 -401.087155) (xy 400.125844 -401.128351)
			(xy 400.084647 -401.164048) (xy 400.038789 -401.193517) (xy 399.989204 -401.216161) (xy 399.936901 -401.231517)
			(xy 399.882945 -401.239274) (xy 399.85569 -401.239736) (xy 398.99209 -401.239736) (xy 398.964841 -401.239193)
			(xy 398.910899 -401.231436) (xy 398.858609 -401.216081) (xy 398.809037 -401.193441) (xy 398.763191 -401.163977)
			(xy 398.722005 -401.128288) (xy 398.686317 -401.087101) (xy 398.656854 -401.041255) (xy 398.634215 -400.991682)
			(xy 398.618862 -400.939392) (xy 398.611106 -400.885449) (xy 397.173573 -400.885449) (xy 397.173573 -400.885457)
			(xy 397.165814 -400.939416) (xy 397.150454 -400.991722) (xy 397.127807 -401.041309) (xy 397.098332 -401.087168)
			(xy 397.06263 -401.128365) (xy 397.021428 -401.164062) (xy 396.975565 -401.193531) (xy 396.925975 -401.216172)
			(xy 396.873668 -401.231525) (xy 396.819707 -401.239276) (xy 396.79245 -401.239736) (xy 395.92885 -401.239736)
			(xy 395.901603 -401.23919) (xy 395.847665 -401.231429) (xy 395.79538 -401.21607) (xy 395.745813 -401.193428)
			(xy 395.699972 -401.163963) (xy 395.658791 -401.128274) (xy 395.623107 -401.087088) (xy 395.593648 -401.041243)
			(xy 395.571012 -400.991673) (xy 395.555661 -400.939386) (xy 395.547906 -400.885447) (xy 394.11025 -400.885447)
			(xy 394.11025 -400.885453) (xy 394.102493 -400.939404) (xy 394.087138 -400.991701) (xy 394.064496 -401.041282)
			(xy 394.035028 -401.087135) (xy 393.999335 -401.128328) (xy 393.958143 -401.164022) (xy 393.91229 -401.193491)
			(xy 393.862711 -401.216134) (xy 393.810413 -401.231491) (xy 393.756463 -401.239249) (xy 393.72921 -401.239736)
			(xy 392.86561 -401.239736) (xy 392.838359 -401.239217) (xy 392.784411 -401.231462) (xy 392.732115 -401.216108)
			(xy 392.682538 -401.193468) (xy 392.636687 -401.164002) (xy 392.595496 -401.128311) (xy 392.559804 -401.087121)
			(xy 392.530337 -401.041271) (xy 392.507695 -400.991694) (xy 392.49234 -400.939399) (xy 392.484583 -400.885451)
			(xy 391.047073 -400.885451) (xy 391.047073 -400.885456) (xy 391.039315 -400.939414) (xy 391.023956 -400.991718)
			(xy 391.00131 -401.041304) (xy 390.971837 -401.087162) (xy 390.936137 -401.128358) (xy 390.894938 -401.164055)
			(xy 390.849077 -401.193524) (xy 390.79949 -401.216166) (xy 390.747184 -401.231521) (xy 390.693226 -401.239275)
			(xy 390.66597 -401.239736) (xy 389.80237 -401.239736) (xy 389.775122 -401.239192) (xy 389.721182 -401.231432)
			(xy 389.668894 -401.216076) (xy 389.619325 -401.193435) (xy 389.573482 -401.16397) (xy 389.532298 -401.128281)
			(xy 389.496612 -401.087094) (xy 389.467151 -401.041249) (xy 389.444514 -400.991677) (xy 389.429161 -400.939389)
			(xy 389.421406 -400.885448) (xy 387.98375 -400.885448) (xy 387.98375 -400.885452) (xy 387.975994 -400.939401)
			(xy 387.960639 -400.991697) (xy 387.937999 -401.041276) (xy 387.908533 -401.087128) (xy 387.872842 -401.128321)
			(xy 387.831652 -401.164015) (xy 387.785802 -401.193484) (xy 387.736225 -401.216129) (xy 387.68393 -401.231488)
			(xy 387.629982 -401.239248) (xy 387.60273 -401.239736) (xy 386.73913 -401.239736) (xy 386.711878 -401.239219)
			(xy 386.657928 -401.231466) (xy 386.60563 -401.216114) (xy 386.55605 -401.193474) (xy 386.510196 -401.164009)
			(xy 386.469003 -401.128318) (xy 386.433309 -401.087128) (xy 386.40384 -401.041277) (xy 386.381197 -400.991698)
			(xy 386.365841 -400.939402) (xy 386.358083 -400.885452) (xy 384.920573 -400.885452) (xy 384.920573 -400.885455)
			(xy 384.912815 -400.939411) (xy 384.897458 -400.991714) (xy 384.874813 -401.041298) (xy 384.845342 -401.087155)
			(xy 384.809644 -401.128351) (xy 384.768447 -401.164048) (xy 384.722589 -401.193517) (xy 384.673004 -401.216161)
			(xy 384.620701 -401.231517) (xy 384.566745 -401.239274) (xy 384.53949 -401.239736) (xy 383.67589 -401.239736)
			(xy 383.648641 -401.239193) (xy 383.594699 -401.231436) (xy 383.542409 -401.216081) (xy 383.492837 -401.193441)
			(xy 383.446991 -401.163977) (xy 383.405805 -401.128288) (xy 383.370117 -401.087101) (xy 383.340654 -401.041255)
			(xy 383.318015 -400.991682) (xy 383.302662 -400.939392) (xy 383.294906 -400.885449) (xy 381.857373 -400.885449)
			(xy 381.857373 -400.885457) (xy 381.849614 -400.939416) (xy 381.834254 -400.991722) (xy 381.811607 -401.041309)
			(xy 381.782132 -401.087168) (xy 381.74643 -401.128365) (xy 381.705228 -401.164062) (xy 381.659365 -401.193531)
			(xy 381.609775 -401.216172) (xy 381.557468 -401.231525) (xy 381.503507 -401.239276) (xy 381.47625 -401.239736)
			(xy 380.61265 -401.239736) (xy 380.585403 -401.23919) (xy 380.531465 -401.231429) (xy 380.47918 -401.21607)
			(xy 380.429613 -401.193428) (xy 380.383772 -401.163963) (xy 380.342591 -401.128274) (xy 380.306907 -401.087088)
			(xy 380.277448 -401.041243) (xy 380.254812 -400.991673) (xy 380.239461 -400.939386) (xy 380.231706 -400.885447)
			(xy 378.79405 -400.885447) (xy 378.79405 -400.885453) (xy 378.786293 -400.939404) (xy 378.770938 -400.991701)
			(xy 378.748296 -401.041282) (xy 378.718828 -401.087135) (xy 378.683135 -401.128328) (xy 378.641943 -401.164022)
			(xy 378.59609 -401.193491) (xy 378.546511 -401.216134) (xy 378.494213 -401.231491) (xy 378.440263 -401.239249)
			(xy 378.41301 -401.239736) (xy 377.54941 -401.239736) (xy 377.522159 -401.239217) (xy 377.468211 -401.231462)
			(xy 377.415915 -401.216108) (xy 377.366338 -401.193468) (xy 377.320487 -401.164002) (xy 377.279296 -401.128311)
			(xy 377.243604 -401.087121) (xy 377.214137 -401.041271) (xy 377.191495 -400.991694) (xy 377.17614 -400.939399)
			(xy 377.168383 -400.885451) (xy 375.730873 -400.885451) (xy 375.730873 -400.885456) (xy 375.723115 -400.939414)
			(xy 375.707756 -400.991718) (xy 375.68511 -401.041304) (xy 375.655637 -401.087162) (xy 375.619937 -401.128358)
			(xy 375.578738 -401.164055) (xy 375.532877 -401.193524) (xy 375.48329 -401.216166) (xy 375.430984 -401.231521)
			(xy 375.377026 -401.239275) (xy 375.34977 -401.239736) (xy 374.48617 -401.239736) (xy 374.458922 -401.239192)
			(xy 374.404982 -401.231432) (xy 374.352694 -401.216076) (xy 374.303125 -401.193435) (xy 374.257282 -401.16397)
			(xy 374.216098 -401.128281) (xy 374.180412 -401.087094) (xy 374.150951 -401.041249) (xy 374.128314 -400.991677)
			(xy 374.112961 -400.939389) (xy 374.105206 -400.885448) (xy 372.66755 -400.885448) (xy 372.66755 -400.885452)
			(xy 372.659794 -400.939401) (xy 372.644439 -400.991697) (xy 372.621799 -401.041276) (xy 372.592333 -401.087128)
			(xy 372.556642 -401.128321) (xy 372.515452 -401.164015) (xy 372.469602 -401.193484) (xy 372.420025 -401.216129)
			(xy 372.36773 -401.231488) (xy 372.313782 -401.239248) (xy 372.28653 -401.239736) (xy 371.42293 -401.239736)
			(xy 371.395678 -401.239219) (xy 371.341728 -401.231466) (xy 371.28943 -401.216114) (xy 371.23985 -401.193474)
			(xy 371.193996 -401.164009) (xy 371.152803 -401.128318) (xy 371.117109 -401.087128) (xy 371.08764 -401.041277)
			(xy 371.064997 -400.991698) (xy 371.049641 -400.939402) (xy 371.041883 -400.885452) (xy 351.173373 -400.885452)
			(xy 351.173373 -400.885455) (xy 351.165615 -400.939411) (xy 351.150257 -400.991714) (xy 351.127612 -401.041299)
			(xy 351.098141 -401.087156) (xy 351.062443 -401.128352) (xy 351.021246 -401.164048) (xy 350.975388 -401.193518)
			(xy 350.925803 -401.216162) (xy 350.8735 -401.231518) (xy 350.819543 -401.239274) (xy 350.792288 -401.239736)
			(xy 349.928688 -401.239736) (xy 349.901439 -401.239193) (xy 349.847497 -401.231436) (xy 349.795208 -401.216081)
			(xy 349.745636 -401.19344) (xy 349.69979 -401.163976) (xy 349.658604 -401.128287) (xy 349.622917 -401.0871)
			(xy 349.593454 -401.041254) (xy 349.570815 -400.991681) (xy 349.555462 -400.939391) (xy 349.547706 -400.885449)
			(xy 348.11005 -400.885449) (xy 348.11005 -400.885451) (xy 348.102294 -400.939399) (xy 348.086941 -400.991693)
			(xy 348.064301 -401.041271) (xy 348.034837 -401.087122) (xy 347.999148 -401.128314) (xy 347.957961 -401.164009)
			(xy 347.912113 -401.193478) (xy 347.862538 -401.216124) (xy 347.810245 -401.231484) (xy 347.756299 -401.239247)
			(xy 347.729048 -401.239736) (xy 346.865448 -401.239736) (xy 346.838195 -401.23922) (xy 346.784243 -401.231469)
			(xy 346.731943 -401.216118) (xy 346.68236 -401.19348) (xy 346.636505 -401.164016) (xy 346.595309 -401.128325)
			(xy 346.559613 -401.087134) (xy 346.530143 -401.041282) (xy 346.507498 -400.991702) (xy 346.492141 -400.939404)
			(xy 346.484383 -400.885453) (xy 345.04685 -400.885453) (xy 345.039093 -400.939404) (xy 345.023737 -400.991702)
			(xy 345.001095 -401.041282) (xy 344.971628 -401.087136) (xy 344.935934 -401.128329) (xy 344.894742 -401.164023)
			(xy 344.848889 -401.193491) (xy 344.799309 -401.216135) (xy 344.747012 -401.231492) (xy 344.693061 -401.23925)
			(xy 344.665808 -401.239736) (xy 343.802208 -401.239736) (xy 343.774957 -401.239217) (xy 343.721009 -401.231462)
			(xy 343.668714 -401.216108) (xy 343.619136 -401.193467) (xy 343.573286 -401.164002) (xy 343.532095 -401.128311)
			(xy 343.496403 -401.087121) (xy 343.466937 -401.041271) (xy 343.444295 -400.991694) (xy 343.42894 -400.939399)
			(xy 343.421183 -400.885451) (xy 341.983673 -400.885451) (xy 341.983673 -400.885456) (xy 341.975915 -400.939414)
			(xy 341.960556 -400.991718) (xy 341.937909 -401.041304) (xy 341.908436 -401.087162) (xy 341.872736 -401.128359)
			(xy 341.831537 -401.164055) (xy 341.785676 -401.193525) (xy 341.736088 -401.216167) (xy 341.683783 -401.231521)
			(xy 341.629824 -401.239275) (xy 341.602568 -401.239736) (xy 340.738968 -401.239736) (xy 340.71172 -401.239192)
			(xy 340.65778 -401.231432) (xy 340.605493 -401.216075) (xy 340.555924 -401.193434) (xy 340.510081 -401.163969)
			(xy 340.468897 -401.12828) (xy 340.433212 -401.087094) (xy 340.403751 -401.041248) (xy 340.381114 -400.991677)
			(xy 340.365761 -400.939389) (xy 340.358006 -400.885448) (xy 338.92035 -400.885448) (xy 338.92035 -400.885452)
			(xy 338.912594 -400.939401) (xy 338.897239 -400.991698) (xy 338.874598 -401.041277) (xy 338.845132 -401.087129)
			(xy 338.809441 -401.128321) (xy 338.768251 -401.164016) (xy 338.722401 -401.193485) (xy 338.672824 -401.216129)
			(xy 338.620529 -401.231488) (xy 338.56658 -401.239248) (xy 338.539328 -401.239736) (xy 337.675728 -401.239736)
			(xy 337.648476 -401.239219) (xy 337.594526 -401.231465) (xy 337.542228 -401.216113) (xy 337.492648 -401.193474)
			(xy 337.446795 -401.164009) (xy 337.405602 -401.128318) (xy 337.369908 -401.087127) (xy 337.34044 -401.041276)
			(xy 337.317797 -400.991698) (xy 337.30244 -400.939402) (xy 337.294683 -400.885452) (xy 335.857173 -400.885452)
			(xy 335.857173 -400.885455) (xy 335.849415 -400.939411) (xy 335.834057 -400.991714) (xy 335.811412 -401.041299)
			(xy 335.781941 -401.087156) (xy 335.746243 -401.128352) (xy 335.705046 -401.164048) (xy 335.659188 -401.193518)
			(xy 335.609603 -401.216162) (xy 335.5573 -401.231518) (xy 335.503343 -401.239274) (xy 335.476088 -401.239736)
			(xy 334.612488 -401.239736) (xy 334.585239 -401.239193) (xy 334.531297 -401.231436) (xy 334.479008 -401.216081)
			(xy 334.429436 -401.19344) (xy 334.38359 -401.163976) (xy 334.342404 -401.128287) (xy 334.306717 -401.0871)
			(xy 334.277254 -401.041254) (xy 334.254615 -400.991681) (xy 334.239262 -400.939391) (xy 334.231506 -400.885449)
			(xy 332.79385 -400.885449) (xy 332.79385 -400.885451) (xy 332.786094 -400.939399) (xy 332.770741 -400.991693)
			(xy 332.748101 -401.041271) (xy 332.718637 -401.087122) (xy 332.682948 -401.128314) (xy 332.641761 -401.164009)
			(xy 332.595913 -401.193478) (xy 332.546338 -401.216124) (xy 332.494045 -401.231484) (xy 332.440099 -401.239247)
			(xy 332.412848 -401.239736) (xy 331.549248 -401.239736) (xy 331.521995 -401.23922) (xy 331.468043 -401.231469)
			(xy 331.415743 -401.216118) (xy 331.36616 -401.19348) (xy 331.320305 -401.164016) (xy 331.279109 -401.128325)
			(xy 331.243413 -401.087134) (xy 331.213943 -401.041282) (xy 331.191298 -400.991702) (xy 331.175941 -400.939404)
			(xy 331.168183 -400.885453) (xy 329.73065 -400.885453) (xy 329.722893 -400.939404) (xy 329.707537 -400.991702)
			(xy 329.684895 -401.041282) (xy 329.655428 -401.087136) (xy 329.619734 -401.128329) (xy 329.578542 -401.164023)
			(xy 329.532689 -401.193491) (xy 329.483109 -401.216135) (xy 329.430812 -401.231492) (xy 329.376861 -401.23925)
			(xy 329.349608 -401.239736) (xy 328.486008 -401.239736) (xy 328.458757 -401.239217) (xy 328.404809 -401.231462)
			(xy 328.352514 -401.216108) (xy 328.302936 -401.193467) (xy 328.257086 -401.164002) (xy 328.215895 -401.128311)
			(xy 328.180203 -401.087121) (xy 328.150737 -401.041271) (xy 328.128095 -400.991694) (xy 328.11274 -400.939399)
			(xy 328.104983 -400.885451) (xy 326.667473 -400.885451) (xy 326.667473 -400.885456) (xy 326.659715 -400.939414)
			(xy 326.644356 -400.991718) (xy 326.621709 -401.041304) (xy 326.592236 -401.087162) (xy 326.556536 -401.128359)
			(xy 326.515337 -401.164055) (xy 326.469476 -401.193525) (xy 326.419888 -401.216167) (xy 326.367583 -401.231521)
			(xy 326.313624 -401.239275) (xy 326.286368 -401.239736) (xy 325.422768 -401.239736) (xy 325.39552 -401.239192)
			(xy 325.34158 -401.231432) (xy 325.289293 -401.216075) (xy 325.239724 -401.193434) (xy 325.193881 -401.163969)
			(xy 325.152697 -401.12828) (xy 325.117012 -401.087094) (xy 325.087551 -401.041248) (xy 325.064914 -400.991677)
			(xy 325.049561 -400.939389) (xy 325.041806 -400.885448) (xy 323.60415 -400.885448) (xy 323.60415 -400.885452)
			(xy 323.596394 -400.939401) (xy 323.581039 -400.991698) (xy 323.558398 -401.041277) (xy 323.528932 -401.087129)
			(xy 323.493241 -401.128321) (xy 323.452051 -401.164016) (xy 323.406201 -401.193485) (xy 323.356624 -401.216129)
			(xy 323.304329 -401.231488) (xy 323.25038 -401.239248) (xy 323.223128 -401.239736) (xy 322.359528 -401.239736)
			(xy 322.332276 -401.239219) (xy 322.278326 -401.231465) (xy 322.226028 -401.216113) (xy 322.176448 -401.193474)
			(xy 322.130595 -401.164009) (xy 322.089402 -401.128318) (xy 322.053708 -401.087127) (xy 322.02424 -401.041276)
			(xy 322.001597 -400.991698) (xy 321.98624 -400.939402) (xy 321.978483 -400.885452) (xy 320.540973 -400.885452)
			(xy 320.540973 -400.885455) (xy 320.533215 -400.939411) (xy 320.517857 -400.991714) (xy 320.495212 -401.041299)
			(xy 320.465741 -401.087156) (xy 320.430043 -401.128352) (xy 320.388846 -401.164048) (xy 320.342988 -401.193518)
			(xy 320.293403 -401.216162) (xy 320.2411 -401.231518) (xy 320.187143 -401.239274) (xy 320.159888 -401.239736)
			(xy 319.296288 -401.239736) (xy 319.269039 -401.239193) (xy 319.215097 -401.231436) (xy 319.162808 -401.216081)
			(xy 319.113236 -401.19344) (xy 319.06739 -401.163976) (xy 319.026204 -401.128287) (xy 318.990517 -401.0871)
			(xy 318.961054 -401.041254) (xy 318.938415 -400.991681) (xy 318.923062 -400.939391) (xy 318.915306 -400.885449)
			(xy 317.47765 -400.885449) (xy 317.47765 -400.885451) (xy 317.469894 -400.939399) (xy 317.454541 -400.991693)
			(xy 317.431901 -401.041271) (xy 317.402437 -401.087122) (xy 317.366748 -401.128314) (xy 317.325561 -401.164009)
			(xy 317.279713 -401.193478) (xy 317.230138 -401.216124) (xy 317.177845 -401.231484) (xy 317.123899 -401.239247)
			(xy 317.096648 -401.239736) (xy 316.233048 -401.239736) (xy 316.205795 -401.23922) (xy 316.151843 -401.231469)
			(xy 316.099543 -401.216118) (xy 316.04996 -401.19348) (xy 316.004105 -401.164016) (xy 315.962909 -401.128325)
			(xy 315.927213 -401.087134) (xy 315.897743 -401.041282) (xy 315.875098 -400.991702) (xy 315.859741 -400.939404)
			(xy 315.851983 -400.885453) (xy 314.41445 -400.885453) (xy 314.406693 -400.939404) (xy 314.391337 -400.991702)
			(xy 314.368695 -401.041282) (xy 314.339228 -401.087136) (xy 314.303534 -401.128329) (xy 314.262342 -401.164023)
			(xy 314.216489 -401.193491) (xy 314.166909 -401.216135) (xy 314.114612 -401.231492) (xy 314.060661 -401.23925)
			(xy 314.033408 -401.239736) (xy 313.169808 -401.239736) (xy 313.142557 -401.239217) (xy 313.088609 -401.231462)
			(xy 313.036314 -401.216108) (xy 312.986736 -401.193467) (xy 312.940886 -401.164002) (xy 312.899695 -401.128311)
			(xy 312.864003 -401.087121) (xy 312.834537 -401.041271) (xy 312.811895 -400.991694) (xy 312.79654 -400.939399)
			(xy 312.788783 -400.885451) (xy 311.351273 -400.885451) (xy 311.351273 -400.885456) (xy 311.343515 -400.939414)
			(xy 311.328156 -400.991718) (xy 311.305509 -401.041304) (xy 311.276036 -401.087162) (xy 311.240336 -401.128359)
			(xy 311.199137 -401.164055) (xy 311.153276 -401.193525) (xy 311.103688 -401.216167) (xy 311.051383 -401.231521)
			(xy 310.997424 -401.239275) (xy 310.970168 -401.239736) (xy 310.106568 -401.239736) (xy 310.07932 -401.239192)
			(xy 310.02538 -401.231432) (xy 309.973093 -401.216075) (xy 309.923524 -401.193434) (xy 309.877681 -401.163969)
			(xy 309.836497 -401.12828) (xy 309.800812 -401.087094) (xy 309.771351 -401.041248) (xy 309.748714 -400.991677)
			(xy 309.733361 -400.939389) (xy 309.725606 -400.885448) (xy 308.28795 -400.885448) (xy 308.28795 -400.885452)
			(xy 308.280194 -400.939401) (xy 308.264839 -400.991698) (xy 308.242198 -401.041277) (xy 308.212732 -401.087129)
			(xy 308.177041 -401.128321) (xy 308.135851 -401.164016) (xy 308.090001 -401.193485) (xy 308.040424 -401.216129)
			(xy 307.988129 -401.231488) (xy 307.93418 -401.239248) (xy 307.906928 -401.239736) (xy 307.043328 -401.239736)
			(xy 307.016076 -401.239219) (xy 306.962126 -401.231465) (xy 306.909828 -401.216113) (xy 306.860248 -401.193474)
			(xy 306.814395 -401.164009) (xy 306.773202 -401.128318) (xy 306.737508 -401.087127) (xy 306.70804 -401.041276)
			(xy 306.685397 -400.991698) (xy 306.67004 -400.939402) (xy 306.662283 -400.885452) (xy 305.224773 -400.885452)
			(xy 305.224773 -400.885455) (xy 305.217015 -400.939411) (xy 305.201657 -400.991714) (xy 305.179012 -401.041299)
			(xy 305.149541 -401.087156) (xy 305.113843 -401.128352) (xy 305.072646 -401.164048) (xy 305.026788 -401.193518)
			(xy 304.977203 -401.216162) (xy 304.9249 -401.231518) (xy 304.870943 -401.239274) (xy 304.843688 -401.239736)
			(xy 303.980088 -401.239736) (xy 303.952839 -401.239193) (xy 303.898897 -401.231436) (xy 303.846608 -401.216081)
			(xy 303.797036 -401.19344) (xy 303.75119 -401.163976) (xy 303.710004 -401.128287) (xy 303.674317 -401.0871)
			(xy 303.644854 -401.041254) (xy 303.622215 -400.991681) (xy 303.606862 -400.939391) (xy 303.599106 -400.885449)
			(xy 281.686508 -400.885449) (xy 281.686508 -402.0155) (xy 287.066441 -402.0155) (xy 287.070455 -401.951698)
			(xy 287.082434 -401.888902) (xy 287.102189 -401.828103) (xy 287.129408 -401.77026) (xy 287.163662 -401.716283)
			(xy 287.204411 -401.667026) (xy 287.251013 -401.623264) (xy 287.302731 -401.585688) (xy 287.358752 -401.55489)
			(xy 287.418191 -401.531357) (xy 287.48011 -401.515458) (xy 287.543534 -401.507446) (xy 287.575498 -401.506944)
			(xy 287.575752 -401.506944) (xy 287.607498 -401.507464) (xy 287.670494 -401.515393) (xy 287.732014 -401.531096)
			(xy 287.791102 -401.55433) (xy 287.846842 -401.584733) (xy 287.898367 -401.621834) (xy 287.921954 -401.643088)
			(xy 287.929217 -401.649272) (xy 287.946967 -401.656223) (xy 287.966029 -401.656223) (xy 287.983779 -401.649272)
			(xy 287.991042 -401.643088) (xy 288.014631 -401.621832) (xy 288.06614 -401.5847) (xy 288.121874 -401.554276)
			(xy 288.180965 -401.531035) (xy 288.242492 -401.515338) (xy 288.305495 -401.507431) (xy 288.337244 -401.506944)
			(xy 288.337498 -401.506944) (xy 288.369457 -401.507521) (xy 288.432872 -401.515532) (xy 288.494783 -401.531427)
			(xy 288.554213 -401.554957) (xy 288.610226 -401.58575) (xy 288.661937 -401.623321) (xy 288.708532 -401.667076)
			(xy 288.749276 -401.716326) (xy 288.783525 -401.770295) (xy 288.810741 -401.82813) (xy 288.830493 -401.888921)
			(xy 288.84247 -401.951707) (xy 288.846484 -402.0155) (xy 289.606441 -402.0155) (xy 289.610455 -401.951698)
			(xy 289.622434 -401.888902) (xy 289.642189 -401.828103) (xy 289.669408 -401.77026) (xy 289.703662 -401.716283)
			(xy 289.744411 -401.667026) (xy 289.791013 -401.623264) (xy 289.842731 -401.585688) (xy 289.898752 -401.55489)
			(xy 289.958191 -401.531357) (xy 290.02011 -401.515458) (xy 290.083534 -401.507446) (xy 290.115498 -401.506944)
			(xy 290.115752 -401.506944) (xy 290.147498 -401.507464) (xy 290.210494 -401.515393) (xy 290.272014 -401.531096)
			(xy 290.331102 -401.55433) (xy 290.386842 -401.584733) (xy 290.438367 -401.621834) (xy 290.461954 -401.643088)
			(xy 290.469217 -401.649272) (xy 290.486967 -401.656223) (xy 290.506029 -401.656223) (xy 290.523779 -401.649272)
			(xy 290.531042 -401.643088) (xy 290.554631 -401.621832) (xy 290.60614 -401.5847) (xy 290.661874 -401.554276)
			(xy 290.720965 -401.531035) (xy 290.782492 -401.515338) (xy 290.845495 -401.507431) (xy 290.877244 -401.506944)
			(xy 290.877498 -401.506944) (xy 290.909457 -401.507521) (xy 290.972872 -401.515532) (xy 291.034783 -401.531427)
			(xy 291.094213 -401.554957) (xy 291.150226 -401.58575) (xy 291.201937 -401.623321) (xy 291.248532 -401.667076)
			(xy 291.289276 -401.716326) (xy 291.323525 -401.770295) (xy 291.350741 -401.82813) (xy 291.370493 -401.888921)
			(xy 291.38247 -401.951707) (xy 291.386484 -402.0155) (xy 292.146441 -402.0155) (xy 292.150455 -401.951698)
			(xy 292.162434 -401.888902) (xy 292.182189 -401.828103) (xy 292.209408 -401.77026) (xy 292.243662 -401.716283)
			(xy 292.284411 -401.667026) (xy 292.331013 -401.623264) (xy 292.382731 -401.585688) (xy 292.438752 -401.55489)
			(xy 292.498191 -401.531357) (xy 292.56011 -401.515458) (xy 292.623534 -401.507446) (xy 292.655498 -401.506944)
			(xy 292.655752 -401.506944) (xy 292.687498 -401.507464) (xy 292.750494 -401.515393) (xy 292.812014 -401.531096)
			(xy 292.871102 -401.55433) (xy 292.926842 -401.584733) (xy 292.978367 -401.621834) (xy 293.001954 -401.643088)
			(xy 293.009217 -401.649272) (xy 293.026967 -401.656223) (xy 293.046029 -401.656223) (xy 293.063779 -401.649272)
			(xy 293.071042 -401.643088) (xy 293.094631 -401.621832) (xy 293.14614 -401.5847) (xy 293.201874 -401.554276)
			(xy 293.260965 -401.531035) (xy 293.322492 -401.515338) (xy 293.385495 -401.507431) (xy 293.417244 -401.506944)
			(xy 293.417498 -401.506944) (xy 293.449457 -401.507521) (xy 293.512872 -401.515532) (xy 293.574783 -401.531427)
			(xy 293.634213 -401.554957) (xy 293.690226 -401.58575) (xy 293.741937 -401.623321) (xy 293.788532 -401.667076)
			(xy 293.829276 -401.716326) (xy 293.863525 -401.770295) (xy 293.890741 -401.82813) (xy 293.910493 -401.888921)
			(xy 293.92247 -401.951707) (xy 293.926484 -402.0155) (xy 294.53602 -402.0155) (xy 294.540035 -401.951693)
			(xy 294.552015 -401.888892) (xy 294.571773 -401.828089) (xy 294.598995 -401.770241) (xy 294.633253 -401.716261)
			(xy 294.674007 -401.667001) (xy 294.720613 -401.623237) (xy 294.772338 -401.58566) (xy 294.828364 -401.554862)
			(xy 294.887809 -401.531329) (xy 294.949734 -401.515433) (xy 295.013163 -401.507423) (xy 295.04513 -401.506944)
			(xy 295.045384 -401.506944) (xy 295.077131 -401.507444) (xy 295.140127 -401.515377) (xy 295.201647 -401.531084)
			(xy 295.260736 -401.554322) (xy 295.316476 -401.584728) (xy 295.368 -401.621832) (xy 295.391586 -401.643088)
			(xy 295.398849 -401.649272) (xy 295.416599 -401.656223) (xy 295.435661 -401.656223) (xy 295.453411 -401.649272)
			(xy 295.460674 -401.643088) (xy 295.48425 -401.621817) (xy 295.535761 -401.584686) (xy 295.591498 -401.554265)
			(xy 295.650592 -401.531026) (xy 295.712121 -401.515332) (xy 295.775126 -401.507429) (xy 295.806876 -401.506944)
			(xy 295.80713 -401.506944) (xy 295.839087 -401.507544) (xy 295.902496 -401.515558) (xy 295.964401 -401.531455)
			(xy 296.023825 -401.554986) (xy 296.079832 -401.585779) (xy 296.131538 -401.623348) (xy 296.178128 -401.667102)
			(xy 296.218866 -401.716349) (xy 296.253112 -401.770314) (xy 296.280324 -401.828145) (xy 296.300074 -401.888931)
			(xy 296.312049 -401.951712) (xy 296.316063 -402.0155) (xy 297.07602 -402.0155) (xy 297.080035 -401.951693)
			(xy 297.092015 -401.888892) (xy 297.111773 -401.828089) (xy 297.138995 -401.770241) (xy 297.173253 -401.716261)
			(xy 297.214007 -401.667001) (xy 297.260613 -401.623237) (xy 297.312338 -401.58566) (xy 297.368364 -401.554862)
			(xy 297.427809 -401.531329) (xy 297.489734 -401.515433) (xy 297.553163 -401.507423) (xy 297.58513 -401.506944)
			(xy 297.585384 -401.506944) (xy 297.617131 -401.507444) (xy 297.680127 -401.515377) (xy 297.741647 -401.531084)
			(xy 297.800736 -401.554322) (xy 297.856476 -401.584728) (xy 297.908 -401.621832) (xy 297.931586 -401.643088)
			(xy 297.938849 -401.649272) (xy 297.956599 -401.656223) (xy 297.975661 -401.656223) (xy 297.993411 -401.649272)
			(xy 298.000674 -401.643088) (xy 298.02425 -401.621817) (xy 298.075761 -401.584686) (xy 298.131498 -401.554265)
			(xy 298.190592 -401.531026) (xy 298.252121 -401.515332) (xy 298.315126 -401.507429) (xy 298.346876 -401.506944)
			(xy 298.34713 -401.506944) (xy 298.379087 -401.507544) (xy 298.442496 -401.515558) (xy 298.504401 -401.531455)
			(xy 298.563825 -401.554986) (xy 298.619832 -401.585779) (xy 298.671538 -401.623348) (xy 298.718128 -401.667102)
			(xy 298.758866 -401.716349) (xy 298.793112 -401.770314) (xy 298.820324 -401.828145) (xy 298.840074 -401.888931)
			(xy 298.852049 -401.951712) (xy 298.856063 -402.0155) (xy 298.852049 -402.079288) (xy 298.840074 -402.142069)
			(xy 298.820324 -402.202855) (xy 298.793112 -402.260686) (xy 298.758866 -402.314651) (xy 298.718128 -402.363898)
			(xy 298.671538 -402.407652) (xy 298.619832 -402.445221) (xy 298.563825 -402.476014) (xy 298.504401 -402.499545)
			(xy 298.442496 -402.515442) (xy 298.379087 -402.523456) (xy 298.34713 -402.52396) (xy 298.346876 -402.52396)
			(xy 298.315131 -402.523422) (xy 298.252136 -402.515497) (xy 298.190616 -402.499797) (xy 298.131527 -402.476566)
			(xy 298.075787 -402.446166) (xy 298.024261 -402.409069) (xy 298.000674 -402.387816) (xy 297.993411 -402.381632)
			(xy 297.975661 -402.374681) (xy 297.956599 -402.374681) (xy 297.938849 -402.381632) (xy 297.931586 -402.387816)
			(xy 297.908028 -402.409107) (xy 297.856512 -402.446235) (xy 297.800771 -402.476654) (xy 297.741674 -402.499889)
			(xy 297.680142 -402.515579) (xy 297.617135 -402.523478) (xy 297.585384 -402.52396) (xy 297.58513 -402.52396)
			(xy 297.553163 -402.523577) (xy 297.489734 -402.515567) (xy 297.427809 -402.499671) (xy 297.368364 -402.476138)
			(xy 297.312338 -402.44534) (xy 297.260613 -402.407763) (xy 297.214007 -402.363999) (xy 297.173253 -402.314739)
			(xy 297.138995 -402.260759) (xy 297.111773 -402.202911) (xy 297.092015 -402.142108) (xy 297.080035 -402.079307)
			(xy 297.07602 -402.0155) (xy 296.316063 -402.0155) (xy 296.312049 -402.079288) (xy 296.300074 -402.142069)
			(xy 296.280324 -402.202855) (xy 296.253112 -402.260686) (xy 296.218866 -402.314651) (xy 296.178128 -402.363898)
			(xy 296.131538 -402.407652) (xy 296.079832 -402.445221) (xy 296.023825 -402.476014) (xy 295.964401 -402.499545)
			(xy 295.902496 -402.515442) (xy 295.839087 -402.523456) (xy 295.80713 -402.52396) (xy 295.806876 -402.52396)
			(xy 295.775131 -402.523422) (xy 295.712136 -402.515497) (xy 295.650616 -402.499797) (xy 295.591527 -402.476566)
			(xy 295.535787 -402.446166) (xy 295.484261 -402.409069) (xy 295.460674 -402.387816) (xy 295.453411 -402.381632)
			(xy 295.435661 -402.374681) (xy 295.416599 -402.374681) (xy 295.398849 -402.381632) (xy 295.391586 -402.387816)
			(xy 295.368028 -402.409107) (xy 295.316512 -402.446235) (xy 295.260771 -402.476654) (xy 295.201674 -402.499889)
			(xy 295.140142 -402.515579) (xy 295.077135 -402.523478) (xy 295.045384 -402.52396) (xy 295.04513 -402.52396)
			(xy 295.013163 -402.523577) (xy 294.949734 -402.515567) (xy 294.887809 -402.499671) (xy 294.828364 -402.476138)
			(xy 294.772338 -402.44534) (xy 294.720613 -402.407763) (xy 294.674007 -402.363999) (xy 294.633253 -402.314739)
			(xy 294.598995 -402.260759) (xy 294.571773 -402.202911) (xy 294.552015 -402.142108) (xy 294.540035 -402.079307)
			(xy 294.53602 -402.0155) (xy 293.926484 -402.0155) (xy 293.92247 -402.079293) (xy 293.910493 -402.142079)
			(xy 293.890741 -402.20287) (xy 293.863525 -402.260705) (xy 293.829276 -402.314674) (xy 293.788532 -402.363924)
			(xy 293.741937 -402.407679) (xy 293.690226 -402.44525) (xy 293.634213 -402.476043) (xy 293.574783 -402.499573)
			(xy 293.512872 -402.515468) (xy 293.449457 -402.523479) (xy 293.417498 -402.52396) (xy 293.417244 -402.52396)
			(xy 293.385498 -402.523442) (xy 293.322502 -402.515512) (xy 293.260982 -402.499809) (xy 293.201894 -402.476575)
			(xy 293.146154 -402.446171) (xy 293.094629 -402.40907) (xy 293.071042 -402.387816) (xy 293.063779 -402.381632)
			(xy 293.046029 -402.374681) (xy 293.026967 -402.374681) (xy 293.009217 -402.381632) (xy 293.001954 -402.387816)
			(xy 292.978367 -402.409074) (xy 292.926858 -402.446206) (xy 292.871123 -402.47663) (xy 292.812032 -402.499871)
			(xy 292.750504 -402.515567) (xy 292.687501 -402.523474) (xy 292.655752 -402.52396) (xy 292.655498 -402.52396)
			(xy 292.623534 -402.523554) (xy 292.56011 -402.515542) (xy 292.498191 -402.499643) (xy 292.438752 -402.47611)
			(xy 292.382731 -402.445312) (xy 292.331013 -402.407736) (xy 292.284411 -402.363974) (xy 292.243662 -402.314717)
			(xy 292.209408 -402.26074) (xy 292.182189 -402.202897) (xy 292.162434 -402.142098) (xy 292.150455 -402.079302)
			(xy 292.146441 -402.0155) (xy 291.386484 -402.0155) (xy 291.38247 -402.079293) (xy 291.370493 -402.142079)
			(xy 291.350741 -402.20287) (xy 291.323525 -402.260705) (xy 291.289276 -402.314674) (xy 291.248532 -402.363924)
			(xy 291.201937 -402.407679) (xy 291.150226 -402.44525) (xy 291.094213 -402.476043) (xy 291.034783 -402.499573)
			(xy 290.972872 -402.515468) (xy 290.909457 -402.523479) (xy 290.877498 -402.52396) (xy 290.877244 -402.52396)
			(xy 290.845498 -402.523442) (xy 290.782502 -402.515512) (xy 290.720982 -402.499809) (xy 290.661894 -402.476575)
			(xy 290.606154 -402.446171) (xy 290.554629 -402.40907) (xy 290.531042 -402.387816) (xy 290.523779 -402.381632)
			(xy 290.506029 -402.374681) (xy 290.486967 -402.374681) (xy 290.469217 -402.381632) (xy 290.461954 -402.387816)
			(xy 290.438367 -402.409074) (xy 290.386858 -402.446206) (xy 290.331123 -402.47663) (xy 290.272032 -402.499871)
			(xy 290.210504 -402.515567) (xy 290.147501 -402.523474) (xy 290.115752 -402.52396) (xy 290.115498 -402.52396)
			(xy 290.083534 -402.523554) (xy 290.02011 -402.515542) (xy 289.958191 -402.499643) (xy 289.898752 -402.47611)
			(xy 289.842731 -402.445312) (xy 289.791013 -402.407736) (xy 289.744411 -402.363974) (xy 289.703662 -402.314717)
			(xy 289.669408 -402.26074) (xy 289.642189 -402.202897) (xy 289.622434 -402.142098) (xy 289.610455 -402.079302)
			(xy 289.606441 -402.0155) (xy 288.846484 -402.0155) (xy 288.84247 -402.079293) (xy 288.830493 -402.142079)
			(xy 288.810741 -402.20287) (xy 288.783525 -402.260705) (xy 288.749276 -402.314674) (xy 288.708532 -402.363924)
			(xy 288.661937 -402.407679) (xy 288.610226 -402.44525) (xy 288.554213 -402.476043) (xy 288.494783 -402.499573)
			(xy 288.432872 -402.515468) (xy 288.369457 -402.523479) (xy 288.337498 -402.52396) (xy 288.337244 -402.52396)
			(xy 288.305498 -402.523442) (xy 288.242502 -402.515512) (xy 288.180982 -402.499809) (xy 288.121894 -402.476575)
			(xy 288.066154 -402.446171) (xy 288.014629 -402.40907) (xy 287.991042 -402.387816) (xy 287.983779 -402.381632)
			(xy 287.966029 -402.374681) (xy 287.946967 -402.374681) (xy 287.929217 -402.381632) (xy 287.921954 -402.387816)
			(xy 287.898367 -402.409074) (xy 287.846858 -402.446206) (xy 287.791123 -402.47663) (xy 287.732032 -402.499871)
			(xy 287.670504 -402.515567) (xy 287.607501 -402.523474) (xy 287.575752 -402.52396) (xy 287.575498 -402.52396)
			(xy 287.543534 -402.523554) (xy 287.48011 -402.515542) (xy 287.418191 -402.499643) (xy 287.358752 -402.47611)
			(xy 287.302731 -402.445312) (xy 287.251013 -402.407736) (xy 287.204411 -402.363974) (xy 287.163662 -402.314717)
			(xy 287.129408 -402.26074) (xy 287.102189 -402.202897) (xy 287.082434 -402.142098) (xy 287.070455 -402.079302)
			(xy 287.066441 -402.0155) (xy 281.686508 -402.0155) (xy 281.686508 -404.0475) (xy 287.066441 -404.0475)
			(xy 287.070455 -403.983698) (xy 287.082434 -403.920902) (xy 287.102189 -403.860103) (xy 287.129408 -403.80226)
			(xy 287.163662 -403.748283) (xy 287.204411 -403.699026) (xy 287.251013 -403.655264) (xy 287.302731 -403.617688)
			(xy 287.358752 -403.58689) (xy 287.418191 -403.563357) (xy 287.48011 -403.547458) (xy 287.543534 -403.539446)
			(xy 287.575498 -403.538944) (xy 287.575752 -403.538944) (xy 287.607498 -403.539464) (xy 287.670494 -403.547393)
			(xy 287.732014 -403.563096) (xy 287.791102 -403.58633) (xy 287.846842 -403.616733) (xy 287.898367 -403.653834)
			(xy 287.921954 -403.675088) (xy 287.929217 -403.681272) (xy 287.946967 -403.688223) (xy 287.966029 -403.688223)
			(xy 287.983779 -403.681272) (xy 287.991042 -403.675088) (xy 288.014631 -403.653832) (xy 288.06614 -403.6167)
			(xy 288.121874 -403.586276) (xy 288.180965 -403.563035) (xy 288.242492 -403.547338) (xy 288.305495 -403.539431)
			(xy 288.337244 -403.538944) (xy 288.337498 -403.538944) (xy 288.369457 -403.539521) (xy 288.432872 -403.547532)
			(xy 288.494783 -403.563427) (xy 288.554213 -403.586957) (xy 288.610226 -403.61775) (xy 288.661937 -403.655321)
			(xy 288.708532 -403.699076) (xy 288.749276 -403.748326) (xy 288.783525 -403.802295) (xy 288.810741 -403.86013)
			(xy 288.830493 -403.920921) (xy 288.84247 -403.983707) (xy 288.846484 -404.0475) (xy 289.606441 -404.0475)
			(xy 289.610455 -403.983698) (xy 289.622434 -403.920902) (xy 289.642189 -403.860103) (xy 289.669408 -403.80226)
			(xy 289.703662 -403.748283) (xy 289.744411 -403.699026) (xy 289.791013 -403.655264) (xy 289.842731 -403.617688)
			(xy 289.898752 -403.58689) (xy 289.958191 -403.563357) (xy 290.02011 -403.547458) (xy 290.083534 -403.539446)
			(xy 290.115498 -403.538944) (xy 290.115752 -403.538944) (xy 290.147498 -403.539464) (xy 290.210494 -403.547393)
			(xy 290.272014 -403.563096) (xy 290.331102 -403.58633) (xy 290.386842 -403.616733) (xy 290.438367 -403.653834)
			(xy 290.461954 -403.675088) (xy 290.469217 -403.681272) (xy 290.486967 -403.688223) (xy 290.506029 -403.688223)
			(xy 290.523779 -403.681272) (xy 290.531042 -403.675088) (xy 290.554631 -403.653832) (xy 290.60614 -403.6167)
			(xy 290.661874 -403.586276) (xy 290.720965 -403.563035) (xy 290.782492 -403.547338) (xy 290.845495 -403.539431)
			(xy 290.877244 -403.538944) (xy 290.877498 -403.538944) (xy 290.909457 -403.539521) (xy 290.972872 -403.547532)
			(xy 291.034783 -403.563427) (xy 291.094213 -403.586957) (xy 291.150226 -403.61775) (xy 291.201937 -403.655321)
			(xy 291.248532 -403.699076) (xy 291.289276 -403.748326) (xy 291.323525 -403.802295) (xy 291.350741 -403.86013)
			(xy 291.370493 -403.920921) (xy 291.38247 -403.983707) (xy 291.386484 -404.0475) (xy 292.146441 -404.0475)
			(xy 292.150455 -403.983698) (xy 292.162434 -403.920902) (xy 292.182189 -403.860103) (xy 292.209408 -403.80226)
			(xy 292.243662 -403.748283) (xy 292.284411 -403.699026) (xy 292.331013 -403.655264) (xy 292.382731 -403.617688)
			(xy 292.438752 -403.58689) (xy 292.498191 -403.563357) (xy 292.56011 -403.547458) (xy 292.623534 -403.539446)
			(xy 292.655498 -403.538944) (xy 292.655752 -403.538944) (xy 292.687498 -403.539464) (xy 292.750494 -403.547393)
			(xy 292.812014 -403.563096) (xy 292.871102 -403.58633) (xy 292.926842 -403.616733) (xy 292.978367 -403.653834)
			(xy 293.001954 -403.675088) (xy 293.009217 -403.681272) (xy 293.026967 -403.688223) (xy 293.046029 -403.688223)
			(xy 293.063779 -403.681272) (xy 293.071042 -403.675088) (xy 293.094631 -403.653832) (xy 293.14614 -403.6167)
			(xy 293.201874 -403.586276) (xy 293.260965 -403.563035) (xy 293.322492 -403.547338) (xy 293.385495 -403.539431)
			(xy 293.417244 -403.538944) (xy 293.417498 -403.538944) (xy 293.449457 -403.539521) (xy 293.512872 -403.547532)
			(xy 293.574783 -403.563427) (xy 293.634213 -403.586957) (xy 293.690226 -403.61775) (xy 293.741937 -403.655321)
			(xy 293.788532 -403.699076) (xy 293.829276 -403.748326) (xy 293.863525 -403.802295) (xy 293.890741 -403.86013)
			(xy 293.910493 -403.920921) (xy 293.92247 -403.983707) (xy 293.926484 -404.0475) (xy 294.53602 -404.0475)
			(xy 294.540035 -403.983693) (xy 294.552015 -403.920892) (xy 294.571773 -403.860089) (xy 294.598995 -403.802241)
			(xy 294.633253 -403.748261) (xy 294.674007 -403.699001) (xy 294.720613 -403.655237) (xy 294.772338 -403.61766)
			(xy 294.828364 -403.586862) (xy 294.887809 -403.563329) (xy 294.949734 -403.547433) (xy 295.013163 -403.539423)
			(xy 295.04513 -403.538944) (xy 295.045384 -403.538944) (xy 295.077131 -403.539444) (xy 295.140127 -403.547377)
			(xy 295.201647 -403.563084) (xy 295.260736 -403.586322) (xy 295.316476 -403.616728) (xy 295.368 -403.653832)
			(xy 295.391586 -403.675088) (xy 295.398849 -403.681272) (xy 295.416599 -403.688223) (xy 295.435661 -403.688223)
			(xy 295.453411 -403.681272) (xy 295.460674 -403.675088) (xy 295.48425 -403.653817) (xy 295.535761 -403.616686)
			(xy 295.591498 -403.586265) (xy 295.650592 -403.563026) (xy 295.712121 -403.547332) (xy 295.775126 -403.539429)
			(xy 295.806876 -403.538944) (xy 295.80713 -403.538944) (xy 295.839087 -403.539544) (xy 295.902496 -403.547558)
			(xy 295.964401 -403.563455) (xy 296.023825 -403.586986) (xy 296.079832 -403.617779) (xy 296.131538 -403.655348)
			(xy 296.178128 -403.699102) (xy 296.218866 -403.748349) (xy 296.253112 -403.802314) (xy 296.280324 -403.860145)
			(xy 296.300074 -403.920931) (xy 296.312049 -403.983712) (xy 296.316063 -404.0475) (xy 297.07602 -404.0475)
			(xy 297.080035 -403.983693) (xy 297.092015 -403.920892) (xy 297.111773 -403.860089) (xy 297.138995 -403.802241)
			(xy 297.173253 -403.748261) (xy 297.214007 -403.699001) (xy 297.260613 -403.655237) (xy 297.312338 -403.61766)
			(xy 297.368364 -403.586862) (xy 297.427809 -403.563329) (xy 297.489734 -403.547433) (xy 297.553163 -403.539423)
			(xy 297.58513 -403.538944) (xy 297.585384 -403.538944) (xy 297.617131 -403.539444) (xy 297.680127 -403.547377)
			(xy 297.741647 -403.563084) (xy 297.800736 -403.586322) (xy 297.856476 -403.616728) (xy 297.908 -403.653832)
			(xy 297.931586 -403.675088) (xy 297.938849 -403.681272) (xy 297.956599 -403.688223) (xy 297.975661 -403.688223)
			(xy 297.993411 -403.681272) (xy 298.000674 -403.675088) (xy 298.02425 -403.653817) (xy 298.075761 -403.616686)
			(xy 298.131498 -403.586265) (xy 298.190592 -403.563026) (xy 298.252121 -403.547332) (xy 298.315126 -403.539429)
			(xy 298.346876 -403.538944) (xy 298.34713 -403.538944) (xy 298.379087 -403.539544) (xy 298.442496 -403.547558)
			(xy 298.504401 -403.563455) (xy 298.563825 -403.586986) (xy 298.619832 -403.617779) (xy 298.671538 -403.655348)
			(xy 298.718128 -403.699102) (xy 298.758866 -403.748349) (xy 298.793112 -403.802314) (xy 298.820324 -403.860145)
			(xy 298.836897 -403.911152) (xy 303.599054 -403.911152) (xy 303.599054 -403.856648) (xy 303.60681 -403.802698)
			(xy 303.622166 -403.7504) (xy 303.644808 -403.700821) (xy 303.674275 -403.654968) (xy 303.709967 -403.613776)
			(xy 303.751159 -403.578082) (xy 303.79701 -403.548613) (xy 303.846589 -403.52597) (xy 303.898886 -403.510613)
			(xy 303.952836 -403.502855) (xy 303.980088 -403.502368) (xy 304.843688 -403.502368) (xy 304.87094 -403.502878)
			(xy 304.924889 -403.510634) (xy 304.977185 -403.525988) (xy 305.026763 -403.548628) (xy 305.072615 -403.578094)
			(xy 305.113806 -403.613785) (xy 305.149499 -403.654976) (xy 305.178966 -403.700826) (xy 305.201608 -403.750404)
			(xy 305.216964 -403.8027) (xy 305.224721 -403.856648) (xy 305.224721 -403.911152) (xy 305.22472 -403.911156)
			(xy 306.662231 -403.911156) (xy 306.662231 -403.856644) (xy 306.669989 -403.802687) (xy 306.685348 -403.750384)
			(xy 306.707994 -403.700799) (xy 306.737466 -403.654941) (xy 306.773165 -403.613745) (xy 306.814364 -403.578049)
			(xy 306.860223 -403.54858) (xy 306.90981 -403.525938) (xy 306.962115 -403.510583) (xy 307.016072 -403.502829)
			(xy 307.043328 -403.502368) (xy 307.906928 -403.502368) (xy 307.934176 -403.502904) (xy 307.988117 -403.510663)
			(xy 308.040405 -403.52602) (xy 308.089976 -403.548661) (xy 308.13582 -403.578126) (xy 308.177004 -403.613816)
			(xy 308.21269 -403.655002) (xy 308.242152 -403.700849) (xy 308.26479 -403.750421) (xy 308.280143 -403.80271)
			(xy 308.287898 -403.856652) (xy 308.287898 -403.911148) (xy 308.287897 -403.911152) (xy 309.725554 -403.911152)
			(xy 309.725554 -403.856648) (xy 309.73331 -403.8027) (xy 309.748664 -403.750405) (xy 309.771305 -403.700826)
			(xy 309.80077 -403.654975) (xy 309.83646 -403.613783) (xy 309.877649 -403.578089) (xy 309.923498 -403.54862)
			(xy 309.973075 -403.525976) (xy 310.025369 -403.510617) (xy 310.079317 -403.502856) (xy 310.106568 -403.502368)
			(xy 310.970168 -403.502368) (xy 310.997421 -403.502877) (xy 311.051372 -403.51063) (xy 311.10367 -403.525982)
			(xy 311.153251 -403.548621) (xy 311.199105 -403.578087) (xy 311.240299 -403.613778) (xy 311.275994 -403.654969)
			(xy 311.305463 -403.700821) (xy 311.328107 -403.7504) (xy 311.343463 -403.802697) (xy 311.351221 -403.856647)
			(xy 311.351221 -403.911153) (xy 311.351221 -403.911155) (xy 312.788731 -403.911155) (xy 312.788731 -403.856645)
			(xy 312.796489 -403.80269) (xy 312.811846 -403.750388) (xy 312.834491 -403.700804) (xy 312.863961 -403.654948)
			(xy 312.899658 -403.613752) (xy 312.940854 -403.578056) (xy 312.986711 -403.548587) (xy 313.036296 -403.525943)
			(xy 313.088598 -403.510587) (xy 313.142553 -403.50283) (xy 313.169808 -403.502368) (xy 314.033408 -403.502368)
			(xy 314.060657 -403.502903) (xy 314.114601 -403.51066) (xy 314.166891 -403.526015) (xy 314.216464 -403.548655)
			(xy 314.26231 -403.578119) (xy 314.303497 -403.613809) (xy 314.339186 -403.654996) (xy 314.368649 -403.700843)
			(xy 314.391288 -403.750417) (xy 314.406642 -403.802707) (xy 314.414398 -403.856651) (xy 314.414398 -403.911149)
			(xy 314.414397 -403.911157) (xy 315.851931 -403.911157) (xy 315.851931 -403.856643) (xy 315.85969 -403.802685)
			(xy 315.875049 -403.75038) (xy 315.897697 -403.700793) (xy 315.927171 -403.654935) (xy 315.962872 -403.613738)
			(xy 316.004073 -403.578042) (xy 316.049935 -403.548574) (xy 316.099525 -403.525932) (xy 316.151832 -403.51058)
			(xy 316.205791 -403.502828) (xy 316.233048 -403.502368) (xy 317.096648 -403.502368) (xy 317.123895 -403.502905)
			(xy 317.177834 -403.510667) (xy 317.23012 -403.526025) (xy 317.279688 -403.548668) (xy 317.325529 -403.578133)
			(xy 317.366711 -403.613823) (xy 317.402395 -403.655009) (xy 317.431855 -403.700854) (xy 317.454491 -403.750425)
			(xy 317.469843 -403.802713) (xy 317.477598 -403.856653) (xy 317.477598 -403.911147) (xy 317.477597 -403.911152)
			(xy 318.915254 -403.911152) (xy 318.915254 -403.856648) (xy 318.92301 -403.802698) (xy 318.938366 -403.7504)
			(xy 318.961008 -403.700821) (xy 318.990475 -403.654968) (xy 319.026167 -403.613776) (xy 319.067359 -403.578082)
			(xy 319.11321 -403.548613) (xy 319.162789 -403.52597) (xy 319.215086 -403.510613) (xy 319.269036 -403.502855)
			(xy 319.296288 -403.502368) (xy 320.159888 -403.502368) (xy 320.18714 -403.502878) (xy 320.241089 -403.510634)
			(xy 320.293385 -403.525988) (xy 320.342963 -403.548628) (xy 320.388815 -403.578094) (xy 320.430006 -403.613785)
			(xy 320.465699 -403.654976) (xy 320.495166 -403.700826) (xy 320.517808 -403.750404) (xy 320.533164 -403.8027)
			(xy 320.540921 -403.856648) (xy 320.540921 -403.911152) (xy 320.54092 -403.911156) (xy 321.978431 -403.911156)
			(xy 321.978431 -403.856644) (xy 321.986189 -403.802687) (xy 322.001548 -403.750384) (xy 322.024194 -403.700799)
			(xy 322.053666 -403.654941) (xy 322.089365 -403.613745) (xy 322.130564 -403.578049) (xy 322.176423 -403.54858)
			(xy 322.22601 -403.525938) (xy 322.278315 -403.510583) (xy 322.332272 -403.502829) (xy 322.359528 -403.502368)
			(xy 323.223128 -403.502368) (xy 323.250376 -403.502904) (xy 323.304317 -403.510663) (xy 323.356605 -403.52602)
			(xy 323.406176 -403.548661) (xy 323.45202 -403.578126) (xy 323.493204 -403.613816) (xy 323.52889 -403.655002)
			(xy 323.558352 -403.700849) (xy 323.58099 -403.750421) (xy 323.596343 -403.80271) (xy 323.604098 -403.856652)
			(xy 323.604098 -403.911148) (xy 323.604097 -403.911152) (xy 325.041754 -403.911152) (xy 325.041754 -403.856648)
			(xy 325.04951 -403.8027) (xy 325.064864 -403.750405) (xy 325.087505 -403.700826) (xy 325.11697 -403.654975)
			(xy 325.15266 -403.613783) (xy 325.193849 -403.578089) (xy 325.239698 -403.54862) (xy 325.289275 -403.525976)
			(xy 325.341569 -403.510617) (xy 325.395517 -403.502856) (xy 325.422768 -403.502368) (xy 326.286368 -403.502368)
			(xy 326.313621 -403.502877) (xy 326.367572 -403.51063) (xy 326.41987 -403.525982) (xy 326.469451 -403.548621)
			(xy 326.515305 -403.578087) (xy 326.556499 -403.613778) (xy 326.592194 -403.654969) (xy 326.621663 -403.700821)
			(xy 326.644307 -403.7504) (xy 326.659663 -403.802697) (xy 326.667421 -403.856647) (xy 326.667421 -403.911153)
			(xy 326.667421 -403.911155) (xy 328.104931 -403.911155) (xy 328.104931 -403.856645) (xy 328.112689 -403.80269)
			(xy 328.128046 -403.750388) (xy 328.150691 -403.700804) (xy 328.180161 -403.654948) (xy 328.215858 -403.613752)
			(xy 328.257054 -403.578056) (xy 328.302911 -403.548587) (xy 328.352496 -403.525943) (xy 328.404798 -403.510587)
			(xy 328.458753 -403.50283) (xy 328.486008 -403.502368) (xy 329.349608 -403.502368) (xy 329.376857 -403.502903)
			(xy 329.430801 -403.51066) (xy 329.483091 -403.526015) (xy 329.532664 -403.548655) (xy 329.57851 -403.578119)
			(xy 329.619697 -403.613809) (xy 329.655386 -403.654996) (xy 329.684849 -403.700843) (xy 329.707488 -403.750417)
			(xy 329.722842 -403.802707) (xy 329.730598 -403.856651) (xy 329.730598 -403.911149) (xy 329.730597 -403.911157)
			(xy 331.168131 -403.911157) (xy 331.168131 -403.856643) (xy 331.17589 -403.802685) (xy 331.191249 -403.75038)
			(xy 331.213897 -403.700793) (xy 331.243371 -403.654935) (xy 331.279072 -403.613738) (xy 331.320273 -403.578042)
			(xy 331.366135 -403.548574) (xy 331.415725 -403.525932) (xy 331.468032 -403.51058) (xy 331.521991 -403.502828)
			(xy 331.549248 -403.502368) (xy 332.412848 -403.502368) (xy 332.440095 -403.502905) (xy 332.494034 -403.510667)
			(xy 332.54632 -403.526025) (xy 332.595888 -403.548668) (xy 332.641729 -403.578133) (xy 332.682911 -403.613823)
			(xy 332.718595 -403.655009) (xy 332.748055 -403.700854) (xy 332.770691 -403.750425) (xy 332.786043 -403.802713)
			(xy 332.793798 -403.856653) (xy 332.793798 -403.911147) (xy 332.793797 -403.911152) (xy 334.231454 -403.911152)
			(xy 334.231454 -403.856648) (xy 334.23921 -403.802698) (xy 334.254566 -403.7504) (xy 334.277208 -403.700821)
			(xy 334.306675 -403.654968) (xy 334.342367 -403.613776) (xy 334.383559 -403.578082) (xy 334.42941 -403.548613)
			(xy 334.478989 -403.52597) (xy 334.531286 -403.510613) (xy 334.585236 -403.502855) (xy 334.612488 -403.502368)
			(xy 335.476088 -403.502368) (xy 335.50334 -403.502878) (xy 335.557289 -403.510634) (xy 335.609585 -403.525988)
			(xy 335.659163 -403.548628) (xy 335.705015 -403.578094) (xy 335.746206 -403.613785) (xy 335.781899 -403.654976)
			(xy 335.811366 -403.700826) (xy 335.834008 -403.750404) (xy 335.849364 -403.8027) (xy 335.857121 -403.856648)
			(xy 335.857121 -403.911152) (xy 335.85712 -403.911156) (xy 337.294631 -403.911156) (xy 337.294631 -403.856644)
			(xy 337.302389 -403.802687) (xy 337.317748 -403.750384) (xy 337.340394 -403.700799) (xy 337.369866 -403.654941)
			(xy 337.405565 -403.613745) (xy 337.446764 -403.578049) (xy 337.492623 -403.54858) (xy 337.54221 -403.525938)
			(xy 337.594515 -403.510583) (xy 337.648472 -403.502829) (xy 337.675728 -403.502368) (xy 338.539328 -403.502368)
			(xy 338.566576 -403.502904) (xy 338.620517 -403.510663) (xy 338.672805 -403.52602) (xy 338.722376 -403.548661)
			(xy 338.76822 -403.578126) (xy 338.809404 -403.613816) (xy 338.84509 -403.655002) (xy 338.874552 -403.700849)
			(xy 338.89719 -403.750421) (xy 338.912543 -403.80271) (xy 338.920298 -403.856652) (xy 338.920298 -403.911148)
			(xy 338.920297 -403.911152) (xy 340.357954 -403.911152) (xy 340.357954 -403.856648) (xy 340.36571 -403.8027)
			(xy 340.381064 -403.750405) (xy 340.403705 -403.700826) (xy 340.43317 -403.654975) (xy 340.46886 -403.613783)
			(xy 340.510049 -403.578089) (xy 340.555898 -403.54862) (xy 340.605475 -403.525976) (xy 340.657769 -403.510617)
			(xy 340.711717 -403.502856) (xy 340.738968 -403.502368) (xy 341.602568 -403.502368) (xy 341.629821 -403.502877)
			(xy 341.683772 -403.51063) (xy 341.73607 -403.525982) (xy 341.785651 -403.548621) (xy 341.831505 -403.578087)
			(xy 341.872699 -403.613778) (xy 341.908394 -403.654969) (xy 341.937863 -403.700821) (xy 341.960507 -403.7504)
			(xy 341.975863 -403.802697) (xy 341.983621 -403.856647) (xy 341.983621 -403.911153) (xy 341.983621 -403.911155)
			(xy 343.421131 -403.911155) (xy 343.421131 -403.856645) (xy 343.428889 -403.80269) (xy 343.444246 -403.750388)
			(xy 343.466891 -403.700804) (xy 343.496361 -403.654948) (xy 343.532058 -403.613752) (xy 343.573254 -403.578056)
			(xy 343.619111 -403.548587) (xy 343.668696 -403.525943) (xy 343.720998 -403.510587) (xy 343.774953 -403.50283)
			(xy 343.802208 -403.502368) (xy 344.665808 -403.502368) (xy 344.693057 -403.502903) (xy 344.747001 -403.51066)
			(xy 344.799291 -403.526015) (xy 344.848864 -403.548655) (xy 344.89471 -403.578119) (xy 344.935897 -403.613809)
			(xy 344.971586 -403.654996) (xy 345.001049 -403.700843) (xy 345.023688 -403.750417) (xy 345.039042 -403.802707)
			(xy 345.046798 -403.856651) (xy 345.046798 -403.911149) (xy 345.046797 -403.911157) (xy 346.484331 -403.911157)
			(xy 346.484331 -403.856643) (xy 346.49209 -403.802685) (xy 346.507449 -403.75038) (xy 346.530097 -403.700793)
			(xy 346.559571 -403.654935) (xy 346.595272 -403.613738) (xy 346.636473 -403.578042) (xy 346.682335 -403.548574)
			(xy 346.731925 -403.525932) (xy 346.784232 -403.51058) (xy 346.838191 -403.502828) (xy 346.865448 -403.502368)
			(xy 347.729048 -403.502368) (xy 347.756295 -403.502905) (xy 347.810234 -403.510667) (xy 347.86252 -403.526025)
			(xy 347.912088 -403.548668) (xy 347.957929 -403.578133) (xy 347.999111 -403.613823) (xy 348.034795 -403.655009)
			(xy 348.064255 -403.700854) (xy 348.086891 -403.750425) (xy 348.102243 -403.802713) (xy 348.109998 -403.856653)
			(xy 348.109998 -403.911147) (xy 348.109997 -403.911152) (xy 349.547654 -403.911152) (xy 349.547654 -403.856648)
			(xy 349.55541 -403.802698) (xy 349.570766 -403.7504) (xy 349.593408 -403.700821) (xy 349.622875 -403.654968)
			(xy 349.658567 -403.613776) (xy 349.699759 -403.578082) (xy 349.74561 -403.548613) (xy 349.795189 -403.52597)
			(xy 349.847486 -403.510613) (xy 349.901436 -403.502855) (xy 349.928688 -403.502368) (xy 350.792288 -403.502368)
			(xy 350.81954 -403.502878) (xy 350.873489 -403.510634) (xy 350.925785 -403.525988) (xy 350.975363 -403.548628)
			(xy 351.021215 -403.578094) (xy 351.062406 -403.613785) (xy 351.098099 -403.654976) (xy 351.127566 -403.700826)
			(xy 351.150208 -403.750404) (xy 351.165564 -403.8027) (xy 351.173321 -403.856648) (xy 351.173321 -403.911152)
			(xy 351.17332 -403.911156) (xy 371.041831 -403.911156) (xy 371.041831 -403.856644) (xy 371.049589 -403.802687)
			(xy 371.064948 -403.750383) (xy 371.087594 -403.700798) (xy 371.117067 -403.654941) (xy 371.152766 -403.613745)
			(xy 371.193965 -403.578049) (xy 371.239824 -403.54858) (xy 371.289412 -403.525937) (xy 371.341716 -403.510583)
			(xy 371.395674 -403.502829) (xy 371.42293 -403.502368) (xy 372.28653 -403.502368) (xy 372.313778 -403.502904)
			(xy 372.367719 -403.510664) (xy 372.420007 -403.52602) (xy 372.469577 -403.548662) (xy 372.515421 -403.578127)
			(xy 372.556605 -403.613816) (xy 372.592291 -403.655003) (xy 372.621753 -403.700849) (xy 372.64439 -403.750421)
			(xy 372.659743 -403.80271) (xy 372.667498 -403.856652) (xy 372.667498 -403.911148) (xy 372.667497 -403.911152)
			(xy 374.105154 -403.911152) (xy 374.105154 -403.856648) (xy 374.11291 -403.8027) (xy 374.128265 -403.750404)
			(xy 374.150905 -403.700826) (xy 374.18037 -403.654974) (xy 374.216061 -403.613782) (xy 374.25725 -403.578088)
			(xy 374.3031 -403.548619) (xy 374.352676 -403.525975) (xy 374.404971 -403.510616) (xy 374.458918 -403.502856)
			(xy 374.48617 -403.502368) (xy 375.34977 -403.502368) (xy 375.377023 -403.502877) (xy 375.430973 -403.51063)
			(xy 375.483271 -403.525983) (xy 375.532852 -403.548622) (xy 375.578706 -403.578087) (xy 375.6199 -403.613779)
			(xy 375.655595 -403.65497) (xy 375.685064 -403.700821) (xy 375.707707 -403.7504) (xy 375.723063 -403.802697)
			(xy 375.730821 -403.856647) (xy 375.730821 -403.911153) (xy 375.730821 -403.911155) (xy 377.168331 -403.911155)
			(xy 377.168331 -403.856645) (xy 377.176089 -403.80269) (xy 377.191446 -403.750388) (xy 377.214091 -403.700804)
			(xy 377.243562 -403.654947) (xy 377.279259 -403.613752) (xy 377.320455 -403.578056) (xy 377.366313 -403.548586)
			(xy 377.415897 -403.525943) (xy 377.468199 -403.510587) (xy 377.522155 -403.50283) (xy 377.54941 -403.502368)
			(xy 378.41301 -403.502368) (xy 378.440259 -403.502903) (xy 378.494202 -403.51066) (xy 378.546492 -403.526015)
			(xy 378.596065 -403.548655) (xy 378.641911 -403.57812) (xy 378.683098 -403.613809) (xy 378.718786 -403.654997)
			(xy 378.748249 -403.700844) (xy 378.770888 -403.750417) (xy 378.786242 -403.802708) (xy 378.793998 -403.856651)
			(xy 378.793998 -403.911149) (xy 378.793998 -403.911151) (xy 380.231654 -403.911151) (xy 380.231654 -403.856649)
			(xy 380.239409 -403.802703) (xy 380.254763 -403.750409) (xy 380.277402 -403.700832) (xy 380.306865 -403.654981)
			(xy 380.342554 -403.613789) (xy 380.383741 -403.578095) (xy 380.429588 -403.548626) (xy 380.479162 -403.52598)
			(xy 380.531454 -403.51062) (xy 380.585399 -403.502857) (xy 380.61265 -403.502368) (xy 381.47625 -403.502368)
			(xy 381.503503 -403.502876) (xy 381.557456 -403.510627) (xy 381.609757 -403.525977) (xy 381.65934 -403.548616)
			(xy 381.705197 -403.57808) (xy 381.746393 -403.613772) (xy 381.78209 -403.654963) (xy 381.81156 -403.700816)
			(xy 381.834205 -403.750396) (xy 381.849563 -403.802695) (xy 381.857321 -403.856647) (xy 381.857321 -403.911153)
			(xy 383.294854 -403.911153) (xy 383.294854 -403.856647) (xy 383.302611 -403.802697) (xy 383.317966 -403.7504)
			(xy 383.340608 -403.70082) (xy 383.370075 -403.654968) (xy 383.405768 -403.613775) (xy 383.44696 -403.578081)
			(xy 383.492812 -403.548613) (xy 383.542391 -403.52597) (xy 383.594687 -403.510613) (xy 383.648638 -403.502855)
			(xy 383.67589 -403.502368) (xy 384.53949 -403.502368) (xy 384.566742 -403.502879) (xy 384.62069 -403.510634)
			(xy 384.672986 -403.525988) (xy 384.722564 -403.548629) (xy 384.768416 -403.578095) (xy 384.809607 -403.613786)
			(xy 384.845299 -403.654976) (xy 384.874767 -403.700827) (xy 384.897408 -403.750405) (xy 384.912764 -403.8027)
			(xy 384.920521 -403.856648) (xy 384.920521 -403.911152) (xy 384.92052 -403.911156) (xy 386.358031 -403.911156)
			(xy 386.358031 -403.856644) (xy 386.365789 -403.802687) (xy 386.381148 -403.750383) (xy 386.403794 -403.700798)
			(xy 386.433267 -403.654941) (xy 386.468966 -403.613745) (xy 386.510165 -403.578049) (xy 386.556024 -403.54858)
			(xy 386.605612 -403.525937) (xy 386.657916 -403.510583) (xy 386.711874 -403.502829) (xy 386.73913 -403.502368)
			(xy 387.60273 -403.502368) (xy 387.629978 -403.502904) (xy 387.683919 -403.510664) (xy 387.736207 -403.52602)
			(xy 387.785777 -403.548662) (xy 387.831621 -403.578127) (xy 387.872805 -403.613816) (xy 387.908491 -403.655003)
			(xy 387.937953 -403.700849) (xy 387.96059 -403.750421) (xy 387.975943 -403.80271) (xy 387.983698 -403.856652)
			(xy 387.983698 -403.911148) (xy 387.983697 -403.911152) (xy 389.421354 -403.911152) (xy 389.421354 -403.856648)
			(xy 389.42911 -403.8027) (xy 389.444465 -403.750404) (xy 389.467105 -403.700826) (xy 389.49657 -403.654974)
			(xy 389.532261 -403.613782) (xy 389.57345 -403.578088) (xy 389.6193 -403.548619) (xy 389.668876 -403.525975)
			(xy 389.721171 -403.510616) (xy 389.775118 -403.502856) (xy 389.80237 -403.502368) (xy 390.66597 -403.502368)
			(xy 390.693223 -403.502877) (xy 390.747173 -403.51063) (xy 390.799471 -403.525983) (xy 390.849052 -403.548622)
			(xy 390.894906 -403.578087) (xy 390.9361 -403.613779) (xy 390.971795 -403.65497) (xy 391.001264 -403.700821)
			(xy 391.023907 -403.7504) (xy 391.039263 -403.802697) (xy 391.047021 -403.856647) (xy 391.047021 -403.911153)
			(xy 391.047021 -403.911155) (xy 392.484531 -403.911155) (xy 392.484531 -403.856645) (xy 392.492289 -403.80269)
			(xy 392.507646 -403.750388) (xy 392.530291 -403.700804) (xy 392.559762 -403.654947) (xy 392.595459 -403.613752)
			(xy 392.636655 -403.578056) (xy 392.682513 -403.548586) (xy 392.732097 -403.525943) (xy 392.784399 -403.510587)
			(xy 392.838355 -403.50283) (xy 392.86561 -403.502368) (xy 393.72921 -403.502368) (xy 393.756459 -403.502903)
			(xy 393.810402 -403.51066) (xy 393.862692 -403.526015) (xy 393.912265 -403.548655) (xy 393.958111 -403.57812)
			(xy 393.999298 -403.613809) (xy 394.034986 -403.654997) (xy 394.064449 -403.700844) (xy 394.087088 -403.750417)
			(xy 394.102442 -403.802708) (xy 394.110198 -403.856651) (xy 394.110198 -403.911149) (xy 394.110198 -403.911151)
			(xy 395.547854 -403.911151) (xy 395.547854 -403.856649) (xy 395.555609 -403.802703) (xy 395.570963 -403.750409)
			(xy 395.593602 -403.700832) (xy 395.623065 -403.654981) (xy 395.658754 -403.613789) (xy 395.699941 -403.578095)
			(xy 395.745788 -403.548626) (xy 395.795362 -403.52598) (xy 395.847654 -403.51062) (xy 395.901599 -403.502857)
			(xy 395.92885 -403.502368) (xy 396.79245 -403.502368) (xy 396.819703 -403.502876) (xy 396.873656 -403.510627)
			(xy 396.925957 -403.525977) (xy 396.97554 -403.548616) (xy 397.021397 -403.57808) (xy 397.062593 -403.613772)
			(xy 397.09829 -403.654963) (xy 397.12776 -403.700816) (xy 397.150405 -403.750396) (xy 397.165763 -403.802695)
			(xy 397.173521 -403.856647) (xy 397.173521 -403.911153) (xy 398.611054 -403.911153) (xy 398.611054 -403.856647)
			(xy 398.618811 -403.802697) (xy 398.634166 -403.7504) (xy 398.656808 -403.70082) (xy 398.686275 -403.654968)
			(xy 398.721968 -403.613775) (xy 398.76316 -403.578081) (xy 398.809012 -403.548613) (xy 398.858591 -403.52597)
			(xy 398.910887 -403.510613) (xy 398.964838 -403.502855) (xy 398.99209 -403.502368) (xy 399.85569 -403.502368)
			(xy 399.882942 -403.502879) (xy 399.93689 -403.510634) (xy 399.989186 -403.525988) (xy 400.038764 -403.548629)
			(xy 400.084616 -403.578095) (xy 400.125807 -403.613786) (xy 400.161499 -403.654976) (xy 400.190967 -403.700827)
			(xy 400.213608 -403.750405) (xy 400.228964 -403.8027) (xy 400.236721 -403.856648) (xy 400.236721 -403.911152)
			(xy 400.23672 -403.911156) (xy 401.674231 -403.911156) (xy 401.674231 -403.856644) (xy 401.681989 -403.802687)
			(xy 401.697348 -403.750383) (xy 401.719994 -403.700798) (xy 401.749467 -403.654941) (xy 401.785166 -403.613745)
			(xy 401.826365 -403.578049) (xy 401.872224 -403.54858) (xy 401.921812 -403.525937) (xy 401.974116 -403.510583)
			(xy 402.028074 -403.502829) (xy 402.05533 -403.502368) (xy 402.91893 -403.502368) (xy 402.946178 -403.502904)
			(xy 403.000119 -403.510664) (xy 403.052407 -403.52602) (xy 403.101977 -403.548662) (xy 403.147821 -403.578127)
			(xy 403.189005 -403.613816) (xy 403.224691 -403.655003) (xy 403.254153 -403.700849) (xy 403.27679 -403.750421)
			(xy 403.292143 -403.80271) (xy 403.299898 -403.856652) (xy 403.299898 -403.911148) (xy 403.299897 -403.911152)
			(xy 404.737554 -403.911152) (xy 404.737554 -403.856648) (xy 404.74531 -403.8027) (xy 404.760665 -403.750404)
			(xy 404.783305 -403.700826) (xy 404.81277 -403.654974) (xy 404.848461 -403.613782) (xy 404.88965 -403.578088)
			(xy 404.9355 -403.548619) (xy 404.985076 -403.525975) (xy 405.037371 -403.510616) (xy 405.091318 -403.502856)
			(xy 405.11857 -403.502368) (xy 405.98217 -403.502368) (xy 406.009423 -403.502877) (xy 406.063373 -403.51063)
			(xy 406.115671 -403.525983) (xy 406.165252 -403.548622) (xy 406.211106 -403.578087) (xy 406.2523 -403.613779)
			(xy 406.287995 -403.65497) (xy 406.317464 -403.700821) (xy 406.340107 -403.7504) (xy 406.355463 -403.802697)
			(xy 406.363221 -403.856647) (xy 406.363221 -403.911153) (xy 406.363221 -403.911155) (xy 407.800731 -403.911155)
			(xy 407.800731 -403.856645) (xy 407.808489 -403.80269) (xy 407.823846 -403.750388) (xy 407.846491 -403.700804)
			(xy 407.875962 -403.654947) (xy 407.911659 -403.613752) (xy 407.952855 -403.578056) (xy 407.998713 -403.548586)
			(xy 408.048297 -403.525943) (xy 408.100599 -403.510587) (xy 408.154555 -403.50283) (xy 408.18181 -403.502368)
			(xy 409.04541 -403.502368) (xy 409.072659 -403.502903) (xy 409.126602 -403.51066) (xy 409.178892 -403.526015)
			(xy 409.228465 -403.548655) (xy 409.274311 -403.57812) (xy 409.315498 -403.613809) (xy 409.351186 -403.654997)
			(xy 409.380649 -403.700844) (xy 409.403288 -403.750417) (xy 409.418642 -403.802708) (xy 409.426398 -403.856651)
			(xy 409.426398 -403.911149) (xy 409.426398 -403.911151) (xy 410.864054 -403.911151) (xy 410.864054 -403.856649)
			(xy 410.871809 -403.802703) (xy 410.887163 -403.750409) (xy 410.909802 -403.700832) (xy 410.939265 -403.654981)
			(xy 410.974954 -403.613789) (xy 411.016141 -403.578095) (xy 411.061988 -403.548626) (xy 411.111562 -403.52598)
			(xy 411.163854 -403.51062) (xy 411.217799 -403.502857) (xy 411.24505 -403.502368) (xy 412.10865 -403.502368)
			(xy 412.135903 -403.502876) (xy 412.189856 -403.510627) (xy 412.242157 -403.525977) (xy 412.29174 -403.548616)
			(xy 412.337597 -403.57808) (xy 412.378793 -403.613772) (xy 412.41449 -403.654963) (xy 412.44396 -403.700816)
			(xy 412.466605 -403.750396) (xy 412.481963 -403.802695) (xy 412.489721 -403.856647) (xy 412.489721 -403.911153)
			(xy 413.927254 -403.911153) (xy 413.927254 -403.856647) (xy 413.935011 -403.802697) (xy 413.950366 -403.7504)
			(xy 413.973008 -403.70082) (xy 414.002475 -403.654968) (xy 414.038168 -403.613775) (xy 414.07936 -403.578081)
			(xy 414.125212 -403.548613) (xy 414.174791 -403.52597) (xy 414.227087 -403.510613) (xy 414.281038 -403.502855)
			(xy 414.30829 -403.502368) (xy 415.17189 -403.502368) (xy 415.199142 -403.502879) (xy 415.25309 -403.510634)
			(xy 415.305386 -403.525988) (xy 415.354964 -403.548629) (xy 415.400816 -403.578095) (xy 415.442007 -403.613786)
			(xy 415.477699 -403.654976) (xy 415.507167 -403.700827) (xy 415.529808 -403.750405) (xy 415.545164 -403.8027)
			(xy 415.552921 -403.856648) (xy 415.552921 -403.911152) (xy 415.55292 -403.911156) (xy 416.990431 -403.911156)
			(xy 416.990431 -403.856644) (xy 416.998189 -403.802687) (xy 417.013548 -403.750383) (xy 417.036194 -403.700798)
			(xy 417.065667 -403.654941) (xy 417.101366 -403.613745) (xy 417.142565 -403.578049) (xy 417.188424 -403.54858)
			(xy 417.238012 -403.525937) (xy 417.290316 -403.510583) (xy 417.344274 -403.502829) (xy 417.37153 -403.502368)
			(xy 418.23513 -403.502368) (xy 418.262378 -403.502904) (xy 418.316319 -403.510664) (xy 418.368607 -403.52602)
			(xy 418.418177 -403.548662) (xy 418.464021 -403.578127) (xy 418.505205 -403.613816) (xy 418.540891 -403.655003)
			(xy 418.570353 -403.700849) (xy 418.59299 -403.750421) (xy 418.608343 -403.80271) (xy 418.616098 -403.856652)
			(xy 418.616098 -403.911148) (xy 418.608343 -403.96509) (xy 418.59299 -404.017379) (xy 418.570353 -404.066951)
			(xy 418.540891 -404.112797) (xy 418.505205 -404.153984) (xy 418.464021 -404.189673) (xy 418.418177 -404.219138)
			(xy 418.368607 -404.24178) (xy 418.316319 -404.257136) (xy 418.262378 -404.264896) (xy 418.23513 -404.265384)
			(xy 417.37153 -404.265384) (xy 417.344274 -404.264971) (xy 417.290316 -404.257217) (xy 417.238012 -404.241863)
			(xy 417.188424 -404.21922) (xy 417.142565 -404.189751) (xy 417.101366 -404.154055) (xy 417.065667 -404.112859)
			(xy 417.036194 -404.067002) (xy 417.013548 -404.017417) (xy 416.998189 -403.965113) (xy 416.990431 -403.911156)
			(xy 415.55292 -403.911156) (xy 415.545164 -403.9651) (xy 415.529808 -404.017395) (xy 415.507167 -404.066973)
			(xy 415.477699 -404.112824) (xy 415.442007 -404.154014) (xy 415.400816 -404.189705) (xy 415.354964 -404.219171)
			(xy 415.305386 -404.241812) (xy 415.25309 -404.257166) (xy 415.199142 -404.264921) (xy 415.17189 -404.265384)
			(xy 414.30829 -404.265384) (xy 414.281038 -404.264945) (xy 414.227087 -404.257187) (xy 414.174791 -404.24183)
			(xy 414.125212 -404.219187) (xy 414.07936 -404.189719) (xy 414.038168 -404.154025) (xy 414.002475 -404.112832)
			(xy 413.973008 -404.06698) (xy 413.950366 -404.0174) (xy 413.935011 -403.965103) (xy 413.927254 -403.911153)
			(xy 412.489721 -403.911153) (xy 412.481963 -403.965105) (xy 412.466605 -404.017404) (xy 412.44396 -404.066984)
			(xy 412.41449 -404.112837) (xy 412.378793 -404.154028) (xy 412.337597 -404.18972) (xy 412.29174 -404.219184)
			(xy 412.242157 -404.241823) (xy 412.189856 -404.257173) (xy 412.135903 -404.264924) (xy 412.10865 -404.265384)
			(xy 411.24505 -404.265384) (xy 411.217799 -404.264943) (xy 411.163854 -404.25718) (xy 411.111562 -404.24182)
			(xy 411.061988 -404.219174) (xy 411.016141 -404.189705) (xy 410.974954 -404.154011) (xy 410.939265 -404.112819)
			(xy 410.909802 -404.066968) (xy 410.887163 -404.017391) (xy 410.871809 -403.965097) (xy 410.864054 -403.911151)
			(xy 409.426398 -403.911151) (xy 409.418642 -403.965092) (xy 409.403288 -404.017383) (xy 409.380649 -404.066956)
			(xy 409.351186 -404.112803) (xy 409.315498 -404.153991) (xy 409.274311 -404.18968) (xy 409.228465 -404.219145)
			(xy 409.178892 -404.241785) (xy 409.126602 -404.25714) (xy 409.072659 -404.264897) (xy 409.04541 -404.265384)
			(xy 408.18181 -404.265384) (xy 408.154555 -404.26497) (xy 408.100599 -404.257213) (xy 408.048297 -404.241857)
			(xy 407.998713 -404.219214) (xy 407.952855 -404.189744) (xy 407.911659 -404.154048) (xy 407.875962 -404.112853)
			(xy 407.846491 -404.066996) (xy 407.823846 -404.017412) (xy 407.808489 -403.96511) (xy 407.800731 -403.911155)
			(xy 406.363221 -403.911155) (xy 406.355463 -403.965103) (xy 406.340107 -404.0174) (xy 406.317464 -404.066979)
			(xy 406.287995 -404.11283) (xy 406.2523 -404.154021) (xy 406.211106 -404.189713) (xy 406.165252 -404.219178)
			(xy 406.115671 -404.241817) (xy 406.063373 -404.25717) (xy 406.009423 -404.264923) (xy 405.98217 -404.265384)
			(xy 405.11857 -404.265384) (xy 405.091318 -404.264944) (xy 405.037371 -404.257184) (xy 404.985076 -404.241825)
			(xy 404.9355 -404.219181) (xy 404.88965 -404.189712) (xy 404.848461 -404.154018) (xy 404.81277 -404.112826)
			(xy 404.783305 -404.066974) (xy 404.760665 -404.017396) (xy 404.74531 -403.9651) (xy 404.737554 -403.911152)
			(xy 403.299897 -403.911152) (xy 403.292143 -403.96509) (xy 403.27679 -404.017379) (xy 403.254153 -404.066951)
			(xy 403.224691 -404.112797) (xy 403.189005 -404.153984) (xy 403.147821 -404.189673) (xy 403.101977 -404.219138)
			(xy 403.052407 -404.24178) (xy 403.000119 -404.257136) (xy 402.946178 -404.264896) (xy 402.91893 -404.265384)
			(xy 402.05533 -404.265384) (xy 402.028074 -404.264971) (xy 401.974116 -404.257217) (xy 401.921812 -404.241863)
			(xy 401.872224 -404.21922) (xy 401.826365 -404.189751) (xy 401.785166 -404.154055) (xy 401.749467 -404.112859)
			(xy 401.719994 -404.067002) (xy 401.697348 -404.017417) (xy 401.681989 -403.965113) (xy 401.674231 -403.911156)
			(xy 400.23672 -403.911156) (xy 400.228964 -403.9651) (xy 400.213608 -404.017395) (xy 400.190967 -404.066973)
			(xy 400.161499 -404.112824) (xy 400.125807 -404.154014) (xy 400.084616 -404.189705) (xy 400.038764 -404.219171)
			(xy 399.989186 -404.241812) (xy 399.93689 -404.257166) (xy 399.882942 -404.264921) (xy 399.85569 -404.265384)
			(xy 398.99209 -404.265384) (xy 398.964838 -404.264945) (xy 398.910887 -404.257187) (xy 398.858591 -404.24183)
			(xy 398.809012 -404.219187) (xy 398.76316 -404.189719) (xy 398.721968 -404.154025) (xy 398.686275 -404.112832)
			(xy 398.656808 -404.06698) (xy 398.634166 -404.0174) (xy 398.618811 -403.965103) (xy 398.611054 -403.911153)
			(xy 397.173521 -403.911153) (xy 397.165763 -403.965105) (xy 397.150405 -404.017404) (xy 397.12776 -404.066984)
			(xy 397.09829 -404.112837) (xy 397.062593 -404.154028) (xy 397.021397 -404.18972) (xy 396.97554 -404.219184)
			(xy 396.925957 -404.241823) (xy 396.873656 -404.257173) (xy 396.819703 -404.264924) (xy 396.79245 -404.265384)
			(xy 395.92885 -404.265384) (xy 395.901599 -404.264943) (xy 395.847654 -404.25718) (xy 395.795362 -404.24182)
			(xy 395.745788 -404.219174) (xy 395.699941 -404.189705) (xy 395.658754 -404.154011) (xy 395.623065 -404.112819)
			(xy 395.593602 -404.066968) (xy 395.570963 -404.017391) (xy 395.555609 -403.965097) (xy 395.547854 -403.911151)
			(xy 394.110198 -403.911151) (xy 394.102442 -403.965092) (xy 394.087088 -404.017383) (xy 394.064449 -404.066956)
			(xy 394.034986 -404.112803) (xy 393.999298 -404.153991) (xy 393.958111 -404.18968) (xy 393.912265 -404.219145)
			(xy 393.862692 -404.241785) (xy 393.810402 -404.25714) (xy 393.756459 -404.264897) (xy 393.72921 -404.265384)
			(xy 392.86561 -404.265384) (xy 392.838355 -404.26497) (xy 392.784399 -404.257213) (xy 392.732097 -404.241857)
			(xy 392.682513 -404.219214) (xy 392.636655 -404.189744) (xy 392.595459 -404.154048) (xy 392.559762 -404.112853)
			(xy 392.530291 -404.066996) (xy 392.507646 -404.017412) (xy 392.492289 -403.96511) (xy 392.484531 -403.911155)
			(xy 391.047021 -403.911155) (xy 391.039263 -403.965103) (xy 391.023907 -404.0174) (xy 391.001264 -404.066979)
			(xy 390.971795 -404.11283) (xy 390.9361 -404.154021) (xy 390.894906 -404.189713) (xy 390.849052 -404.219178)
			(xy 390.799471 -404.241817) (xy 390.747173 -404.25717) (xy 390.693223 -404.264923) (xy 390.66597 -404.265384)
			(xy 389.80237 -404.265384) (xy 389.775118 -404.264944) (xy 389.721171 -404.257184) (xy 389.668876 -404.241825)
			(xy 389.6193 -404.219181) (xy 389.57345 -404.189712) (xy 389.532261 -404.154018) (xy 389.49657 -404.112826)
			(xy 389.467105 -404.066974) (xy 389.444465 -404.017396) (xy 389.42911 -403.9651) (xy 389.421354 -403.911152)
			(xy 387.983697 -403.911152) (xy 387.975943 -403.96509) (xy 387.96059 -404.017379) (xy 387.937953 -404.066951)
			(xy 387.908491 -404.112797) (xy 387.872805 -404.153984) (xy 387.831621 -404.189673) (xy 387.785777 -404.219138)
			(xy 387.736207 -404.24178) (xy 387.683919 -404.257136) (xy 387.629978 -404.264896) (xy 387.60273 -404.265384)
			(xy 386.73913 -404.265384) (xy 386.711874 -404.264971) (xy 386.657916 -404.257217) (xy 386.605612 -404.241863)
			(xy 386.556024 -404.21922) (xy 386.510165 -404.189751) (xy 386.468966 -404.154055) (xy 386.433267 -404.112859)
			(xy 386.403794 -404.067002) (xy 386.381148 -404.017417) (xy 386.365789 -403.965113) (xy 386.358031 -403.911156)
			(xy 384.92052 -403.911156) (xy 384.912764 -403.9651) (xy 384.897408 -404.017395) (xy 384.874767 -404.066973)
			(xy 384.845299 -404.112824) (xy 384.809607 -404.154014) (xy 384.768416 -404.189705) (xy 384.722564 -404.219171)
			(xy 384.672986 -404.241812) (xy 384.62069 -404.257166) (xy 384.566742 -404.264921) (xy 384.53949 -404.265384)
			(xy 383.67589 -404.265384) (xy 383.648638 -404.264945) (xy 383.594687 -404.257187) (xy 383.542391 -404.24183)
			(xy 383.492812 -404.219187) (xy 383.44696 -404.189719) (xy 383.405768 -404.154025) (xy 383.370075 -404.112832)
			(xy 383.340608 -404.06698) (xy 383.317966 -404.0174) (xy 383.302611 -403.965103) (xy 383.294854 -403.911153)
			(xy 381.857321 -403.911153) (xy 381.849563 -403.965105) (xy 381.834205 -404.017404) (xy 381.81156 -404.066984)
			(xy 381.78209 -404.112837) (xy 381.746393 -404.154028) (xy 381.705197 -404.18972) (xy 381.65934 -404.219184)
			(xy 381.609757 -404.241823) (xy 381.557456 -404.257173) (xy 381.503503 -404.264924) (xy 381.47625 -404.265384)
			(xy 380.61265 -404.265384) (xy 380.585399 -404.264943) (xy 380.531454 -404.25718) (xy 380.479162 -404.24182)
			(xy 380.429588 -404.219174) (xy 380.383741 -404.189705) (xy 380.342554 -404.154011) (xy 380.306865 -404.112819)
			(xy 380.277402 -404.066968) (xy 380.254763 -404.017391) (xy 380.239409 -403.965097) (xy 380.231654 -403.911151)
			(xy 378.793998 -403.911151) (xy 378.786242 -403.965092) (xy 378.770888 -404.017383) (xy 378.748249 -404.066956)
			(xy 378.718786 -404.112803) (xy 378.683098 -404.153991) (xy 378.641911 -404.18968) (xy 378.596065 -404.219145)
			(xy 378.546492 -404.241785) (xy 378.494202 -404.25714) (xy 378.440259 -404.264897) (xy 378.41301 -404.265384)
			(xy 377.54941 -404.265384) (xy 377.522155 -404.26497) (xy 377.468199 -404.257213) (xy 377.415897 -404.241857)
			(xy 377.366313 -404.219214) (xy 377.320455 -404.189744) (xy 377.279259 -404.154048) (xy 377.243562 -404.112853)
			(xy 377.214091 -404.066996) (xy 377.191446 -404.017412) (xy 377.176089 -403.96511) (xy 377.168331 -403.911155)
			(xy 375.730821 -403.911155) (xy 375.723063 -403.965103) (xy 375.707707 -404.0174) (xy 375.685064 -404.066979)
			(xy 375.655595 -404.11283) (xy 375.6199 -404.154021) (xy 375.578706 -404.189713) (xy 375.532852 -404.219178)
			(xy 375.483271 -404.241817) (xy 375.430973 -404.25717) (xy 375.377023 -404.264923) (xy 375.34977 -404.265384)
			(xy 374.48617 -404.265384) (xy 374.458918 -404.264944) (xy 374.404971 -404.257184) (xy 374.352676 -404.241825)
			(xy 374.3031 -404.219181) (xy 374.25725 -404.189712) (xy 374.216061 -404.154018) (xy 374.18037 -404.112826)
			(xy 374.150905 -404.066974) (xy 374.128265 -404.017396) (xy 374.11291 -403.9651) (xy 374.105154 -403.911152)
			(xy 372.667497 -403.911152) (xy 372.659743 -403.96509) (xy 372.64439 -404.017379) (xy 372.621753 -404.066951)
			(xy 372.592291 -404.112797) (xy 372.556605 -404.153984) (xy 372.515421 -404.189673) (xy 372.469577 -404.219138)
			(xy 372.420007 -404.24178) (xy 372.367719 -404.257136) (xy 372.313778 -404.264896) (xy 372.28653 -404.265384)
			(xy 371.42293 -404.265384) (xy 371.395674 -404.264971) (xy 371.341716 -404.257217) (xy 371.289412 -404.241863)
			(xy 371.239824 -404.21922) (xy 371.193965 -404.189751) (xy 371.152766 -404.154055) (xy 371.117067 -404.112859)
			(xy 371.087594 -404.067002) (xy 371.064948 -404.017417) (xy 371.049589 -403.965113) (xy 371.041831 -403.911156)
			(xy 351.17332 -403.911156) (xy 351.165564 -403.9651) (xy 351.150208 -404.017396) (xy 351.127566 -404.066974)
			(xy 351.098099 -404.112824) (xy 351.062406 -404.154015) (xy 351.021215 -404.189706) (xy 350.975363 -404.219172)
			(xy 350.925785 -404.241812) (xy 350.873489 -404.257166) (xy 350.81954 -404.264922) (xy 350.792288 -404.265384)
			(xy 349.928688 -404.265384) (xy 349.901436 -404.264945) (xy 349.847486 -404.257187) (xy 349.795189 -404.24183)
			(xy 349.74561 -404.219187) (xy 349.699759 -404.189718) (xy 349.658567 -404.154024) (xy 349.622875 -404.112832)
			(xy 349.593408 -404.066979) (xy 349.570766 -404.0174) (xy 349.55541 -403.965102) (xy 349.547654 -403.911152)
			(xy 348.109997 -403.911152) (xy 348.102243 -403.965087) (xy 348.086891 -404.017375) (xy 348.064255 -404.066946)
			(xy 348.034795 -404.112791) (xy 347.999111 -404.153977) (xy 347.957929 -404.189667) (xy 347.912088 -404.219132)
			(xy 347.86252 -404.241775) (xy 347.810234 -404.257133) (xy 347.756295 -404.264895) (xy 347.729048 -404.265384)
			(xy 346.865448 -404.265384) (xy 346.838191 -404.264972) (xy 346.784232 -404.25722) (xy 346.731925 -404.241868)
			(xy 346.682335 -404.219226) (xy 346.636473 -404.189758) (xy 346.595272 -404.154062) (xy 346.559571 -404.112865)
			(xy 346.530097 -404.067007) (xy 346.507449 -404.01742) (xy 346.49209 -403.965115) (xy 346.484331 -403.911157)
			(xy 345.046797 -403.911157) (xy 345.039042 -403.965093) (xy 345.023688 -404.017383) (xy 345.001049 -404.066957)
			(xy 344.971586 -404.112804) (xy 344.935897 -404.153991) (xy 344.89471 -404.189681) (xy 344.848864 -404.219145)
			(xy 344.799291 -404.241785) (xy 344.747001 -404.25714) (xy 344.693057 -404.264897) (xy 344.665808 -404.265384)
			(xy 343.802208 -404.265384) (xy 343.774953 -404.26497) (xy 343.720998 -404.257213) (xy 343.668696 -404.241857)
			(xy 343.619111 -404.219213) (xy 343.573254 -404.189744) (xy 343.532058 -404.154048) (xy 343.496361 -404.112852)
			(xy 343.466891 -404.066996) (xy 343.444246 -404.017412) (xy 343.428889 -403.96511) (xy 343.421131 -403.911155)
			(xy 341.983621 -403.911155) (xy 341.975863 -403.965103) (xy 341.960507 -404.0174) (xy 341.937863 -404.066979)
			(xy 341.908394 -404.112831) (xy 341.872699 -404.154022) (xy 341.831505 -404.189713) (xy 341.785651 -404.219179)
			(xy 341.73607 -404.241818) (xy 341.683772 -404.25717) (xy 341.629821 -404.264923) (xy 341.602568 -404.265384)
			(xy 340.738968 -404.265384) (xy 340.711717 -404.264944) (xy 340.657769 -404.257183) (xy 340.605475 -404.241824)
			(xy 340.555898 -404.21918) (xy 340.510049 -404.189711) (xy 340.46886 -404.154017) (xy 340.43317 -404.112825)
			(xy 340.403705 -404.066974) (xy 340.381064 -404.017395) (xy 340.36571 -403.9651) (xy 340.357954 -403.911152)
			(xy 338.920297 -403.911152) (xy 338.912543 -403.96509) (xy 338.89719 -404.017379) (xy 338.874552 -404.066951)
			(xy 338.84509 -404.112798) (xy 338.809404 -404.153984) (xy 338.76822 -404.189674) (xy 338.722376 -404.219139)
			(xy 338.672805 -404.24178) (xy 338.620517 -404.257137) (xy 338.566576 -404.264896) (xy 338.539328 -404.265384)
			(xy 337.675728 -404.265384) (xy 337.648472 -404.264971) (xy 337.594515 -404.257217) (xy 337.54221 -404.241862)
			(xy 337.492623 -404.21922) (xy 337.446764 -404.189751) (xy 337.405565 -404.154055) (xy 337.369866 -404.112859)
			(xy 337.340394 -404.067001) (xy 337.317748 -404.017416) (xy 337.302389 -403.965113) (xy 337.294631 -403.911156)
			(xy 335.85712 -403.911156) (xy 335.849364 -403.9651) (xy 335.834008 -404.017396) (xy 335.811366 -404.066974)
			(xy 335.781899 -404.112824) (xy 335.746206 -404.154015) (xy 335.705015 -404.189706) (xy 335.659163 -404.219172)
			(xy 335.609585 -404.241812) (xy 335.557289 -404.257166) (xy 335.50334 -404.264922) (xy 335.476088 -404.265384)
			(xy 334.612488 -404.265384) (xy 334.585236 -404.264945) (xy 334.531286 -404.257187) (xy 334.478989 -404.24183)
			(xy 334.42941 -404.219187) (xy 334.383559 -404.189718) (xy 334.342367 -404.154024) (xy 334.306675 -404.112832)
			(xy 334.277208 -404.066979) (xy 334.254566 -404.0174) (xy 334.23921 -403.965102) (xy 334.231454 -403.911152)
			(xy 332.793797 -403.911152) (xy 332.786043 -403.965087) (xy 332.770691 -404.017375) (xy 332.748055 -404.066946)
			(xy 332.718595 -404.112791) (xy 332.682911 -404.153977) (xy 332.641729 -404.189667) (xy 332.595888 -404.219132)
			(xy 332.54632 -404.241775) (xy 332.494034 -404.257133) (xy 332.440095 -404.264895) (xy 332.412848 -404.265384)
			(xy 331.549248 -404.265384) (xy 331.521991 -404.264972) (xy 331.468032 -404.25722) (xy 331.415725 -404.241868)
			(xy 331.366135 -404.219226) (xy 331.320273 -404.189758) (xy 331.279072 -404.154062) (xy 331.243371 -404.112865)
			(xy 331.213897 -404.067007) (xy 331.191249 -404.01742) (xy 331.17589 -403.965115) (xy 331.168131 -403.911157)
			(xy 329.730597 -403.911157) (xy 329.722842 -403.965093) (xy 329.707488 -404.017383) (xy 329.684849 -404.066957)
			(xy 329.655386 -404.112804) (xy 329.619697 -404.153991) (xy 329.57851 -404.189681) (xy 329.532664 -404.219145)
			(xy 329.483091 -404.241785) (xy 329.430801 -404.25714) (xy 329.376857 -404.264897) (xy 329.349608 -404.265384)
			(xy 328.486008 -404.265384) (xy 328.458753 -404.26497) (xy 328.404798 -404.257213) (xy 328.352496 -404.241857)
			(xy 328.302911 -404.219213) (xy 328.257054 -404.189744) (xy 328.215858 -404.154048) (xy 328.180161 -404.112852)
			(xy 328.150691 -404.066996) (xy 328.128046 -404.017412) (xy 328.112689 -403.96511) (xy 328.104931 -403.911155)
			(xy 326.667421 -403.911155) (xy 326.659663 -403.965103) (xy 326.644307 -404.0174) (xy 326.621663 -404.066979)
			(xy 326.592194 -404.112831) (xy 326.556499 -404.154022) (xy 326.515305 -404.189713) (xy 326.469451 -404.219179)
			(xy 326.41987 -404.241818) (xy 326.367572 -404.25717) (xy 326.313621 -404.264923) (xy 326.286368 -404.265384)
			(xy 325.422768 -404.265384) (xy 325.395517 -404.264944) (xy 325.341569 -404.257183) (xy 325.289275 -404.241824)
			(xy 325.239698 -404.21918) (xy 325.193849 -404.189711) (xy 325.15266 -404.154017) (xy 325.11697 -404.112825)
			(xy 325.087505 -404.066974) (xy 325.064864 -404.017395) (xy 325.04951 -403.9651) (xy 325.041754 -403.911152)
			(xy 323.604097 -403.911152) (xy 323.596343 -403.96509) (xy 323.58099 -404.017379) (xy 323.558352 -404.066951)
			(xy 323.52889 -404.112798) (xy 323.493204 -404.153984) (xy 323.45202 -404.189674) (xy 323.406176 -404.219139)
			(xy 323.356605 -404.24178) (xy 323.304317 -404.257137) (xy 323.250376 -404.264896) (xy 323.223128 -404.265384)
			(xy 322.359528 -404.265384) (xy 322.332272 -404.264971) (xy 322.278315 -404.257217) (xy 322.22601 -404.241862)
			(xy 322.176423 -404.21922) (xy 322.130564 -404.189751) (xy 322.089365 -404.154055) (xy 322.053666 -404.112859)
			(xy 322.024194 -404.067001) (xy 322.001548 -404.017416) (xy 321.986189 -403.965113) (xy 321.978431 -403.911156)
			(xy 320.54092 -403.911156) (xy 320.533164 -403.9651) (xy 320.517808 -404.017396) (xy 320.495166 -404.066974)
			(xy 320.465699 -404.112824) (xy 320.430006 -404.154015) (xy 320.388815 -404.189706) (xy 320.342963 -404.219172)
			(xy 320.293385 -404.241812) (xy 320.241089 -404.257166) (xy 320.18714 -404.264922) (xy 320.159888 -404.265384)
			(xy 319.296288 -404.265384) (xy 319.269036 -404.264945) (xy 319.215086 -404.257187) (xy 319.162789 -404.24183)
			(xy 319.11321 -404.219187) (xy 319.067359 -404.189718) (xy 319.026167 -404.154024) (xy 318.990475 -404.112832)
			(xy 318.961008 -404.066979) (xy 318.938366 -404.0174) (xy 318.92301 -403.965102) (xy 318.915254 -403.911152)
			(xy 317.477597 -403.911152) (xy 317.469843 -403.965087) (xy 317.454491 -404.017375) (xy 317.431855 -404.066946)
			(xy 317.402395 -404.112791) (xy 317.366711 -404.153977) (xy 317.325529 -404.189667) (xy 317.279688 -404.219132)
			(xy 317.23012 -404.241775) (xy 317.177834 -404.257133) (xy 317.123895 -404.264895) (xy 317.096648 -404.265384)
			(xy 316.233048 -404.265384) (xy 316.205791 -404.264972) (xy 316.151832 -404.25722) (xy 316.099525 -404.241868)
			(xy 316.049935 -404.219226) (xy 316.004073 -404.189758) (xy 315.962872 -404.154062) (xy 315.927171 -404.112865)
			(xy 315.897697 -404.067007) (xy 315.875049 -404.01742) (xy 315.85969 -403.965115) (xy 315.851931 -403.911157)
			(xy 314.414397 -403.911157) (xy 314.406642 -403.965093) (xy 314.391288 -404.017383) (xy 314.368649 -404.066957)
			(xy 314.339186 -404.112804) (xy 314.303497 -404.153991) (xy 314.26231 -404.189681) (xy 314.216464 -404.219145)
			(xy 314.166891 -404.241785) (xy 314.114601 -404.25714) (xy 314.060657 -404.264897) (xy 314.033408 -404.265384)
			(xy 313.169808 -404.265384) (xy 313.142553 -404.26497) (xy 313.088598 -404.257213) (xy 313.036296 -404.241857)
			(xy 312.986711 -404.219213) (xy 312.940854 -404.189744) (xy 312.899658 -404.154048) (xy 312.863961 -404.112852)
			(xy 312.834491 -404.066996) (xy 312.811846 -404.017412) (xy 312.796489 -403.96511) (xy 312.788731 -403.911155)
			(xy 311.351221 -403.911155) (xy 311.343463 -403.965103) (xy 311.328107 -404.0174) (xy 311.305463 -404.066979)
			(xy 311.275994 -404.112831) (xy 311.240299 -404.154022) (xy 311.199105 -404.189713) (xy 311.153251 -404.219179)
			(xy 311.10367 -404.241818) (xy 311.051372 -404.25717) (xy 310.997421 -404.264923) (xy 310.970168 -404.265384)
			(xy 310.106568 -404.265384) (xy 310.079317 -404.264944) (xy 310.025369 -404.257183) (xy 309.973075 -404.241824)
			(xy 309.923498 -404.21918) (xy 309.877649 -404.189711) (xy 309.83646 -404.154017) (xy 309.80077 -404.112825)
			(xy 309.771305 -404.066974) (xy 309.748664 -404.017395) (xy 309.73331 -403.9651) (xy 309.725554 -403.911152)
			(xy 308.287897 -403.911152) (xy 308.280143 -403.96509) (xy 308.26479 -404.017379) (xy 308.242152 -404.066951)
			(xy 308.21269 -404.112798) (xy 308.177004 -404.153984) (xy 308.13582 -404.189674) (xy 308.089976 -404.219139)
			(xy 308.040405 -404.24178) (xy 307.988117 -404.257137) (xy 307.934176 -404.264896) (xy 307.906928 -404.265384)
			(xy 307.043328 -404.265384) (xy 307.016072 -404.264971) (xy 306.962115 -404.257217) (xy 306.90981 -404.241862)
			(xy 306.860223 -404.21922) (xy 306.814364 -404.189751) (xy 306.773165 -404.154055) (xy 306.737466 -404.112859)
			(xy 306.707994 -404.067001) (xy 306.685348 -404.017416) (xy 306.669989 -403.965113) (xy 306.662231 -403.911156)
			(xy 305.22472 -403.911156) (xy 305.216964 -403.9651) (xy 305.201608 -404.017396) (xy 305.178966 -404.066974)
			(xy 305.149499 -404.112824) (xy 305.113806 -404.154015) (xy 305.072615 -404.189706) (xy 305.026763 -404.219172)
			(xy 304.977185 -404.241812) (xy 304.924889 -404.257166) (xy 304.87094 -404.264922) (xy 304.843688 -404.265384)
			(xy 303.980088 -404.265384) (xy 303.952836 -404.264945) (xy 303.898886 -404.257187) (xy 303.846589 -404.24183)
			(xy 303.79701 -404.219187) (xy 303.751159 -404.189718) (xy 303.709967 -404.154024) (xy 303.674275 -404.112832)
			(xy 303.644808 -404.066979) (xy 303.622166 -404.0174) (xy 303.60681 -403.965102) (xy 303.599054 -403.911152)
			(xy 298.836897 -403.911152) (xy 298.840074 -403.920931) (xy 298.852049 -403.983712) (xy 298.856063 -404.0475)
			(xy 298.852049 -404.111288) (xy 298.840074 -404.174069) (xy 298.820324 -404.234855) (xy 298.793112 -404.292686)
			(xy 298.758866 -404.346651) (xy 298.718128 -404.395898) (xy 298.671538 -404.439652) (xy 298.619832 -404.477221)
			(xy 298.563825 -404.508014) (xy 298.504401 -404.531545) (xy 298.442496 -404.547442) (xy 298.379087 -404.555456)
			(xy 298.34713 -404.55596) (xy 298.346876 -404.55596) (xy 298.315131 -404.555422) (xy 298.252136 -404.547497)
			(xy 298.190616 -404.531797) (xy 298.131527 -404.508566) (xy 298.075787 -404.478166) (xy 298.024261 -404.441069)
			(xy 298.000674 -404.419816) (xy 297.993411 -404.413632) (xy 297.975661 -404.406681) (xy 297.956599 -404.406681)
			(xy 297.938849 -404.413632) (xy 297.931586 -404.419816) (xy 297.908028 -404.441107) (xy 297.856512 -404.478235)
			(xy 297.800771 -404.508654) (xy 297.741674 -404.531889) (xy 297.680142 -404.547579) (xy 297.617135 -404.555478)
			(xy 297.585384 -404.55596) (xy 297.58513 -404.55596) (xy 297.553163 -404.555577) (xy 297.489734 -404.547567)
			(xy 297.427809 -404.531671) (xy 297.368364 -404.508138) (xy 297.312338 -404.47734) (xy 297.260613 -404.439763)
			(xy 297.214007 -404.395999) (xy 297.173253 -404.346739) (xy 297.138995 -404.292759) (xy 297.111773 -404.234911)
			(xy 297.092015 -404.174108) (xy 297.080035 -404.111307) (xy 297.07602 -404.0475) (xy 296.316063 -404.0475)
			(xy 296.312049 -404.111288) (xy 296.300074 -404.174069) (xy 296.280324 -404.234855) (xy 296.253112 -404.292686)
			(xy 296.218866 -404.346651) (xy 296.178128 -404.395898) (xy 296.131538 -404.439652) (xy 296.079832 -404.477221)
			(xy 296.023825 -404.508014) (xy 295.964401 -404.531545) (xy 295.902496 -404.547442) (xy 295.839087 -404.555456)
			(xy 295.80713 -404.55596) (xy 295.806876 -404.55596) (xy 295.775131 -404.555422) (xy 295.712136 -404.547497)
			(xy 295.650616 -404.531797) (xy 295.591527 -404.508566) (xy 295.535787 -404.478166) (xy 295.484261 -404.441069)
			(xy 295.460674 -404.419816) (xy 295.453411 -404.413632) (xy 295.435661 -404.406681) (xy 295.416599 -404.406681)
			(xy 295.398849 -404.413632) (xy 295.391586 -404.419816) (xy 295.368028 -404.441107) (xy 295.316512 -404.478235)
			(xy 295.260771 -404.508654) (xy 295.201674 -404.531889) (xy 295.140142 -404.547579) (xy 295.077135 -404.555478)
			(xy 295.045384 -404.55596) (xy 295.04513 -404.55596) (xy 295.013163 -404.555577) (xy 294.949734 -404.547567)
			(xy 294.887809 -404.531671) (xy 294.828364 -404.508138) (xy 294.772338 -404.47734) (xy 294.720613 -404.439763)
			(xy 294.674007 -404.395999) (xy 294.633253 -404.346739) (xy 294.598995 -404.292759) (xy 294.571773 -404.234911)
			(xy 294.552015 -404.174108) (xy 294.540035 -404.111307) (xy 294.53602 -404.0475) (xy 293.926484 -404.0475)
			(xy 293.92247 -404.111293) (xy 293.910493 -404.174079) (xy 293.890741 -404.23487) (xy 293.863525 -404.292705)
			(xy 293.829276 -404.346674) (xy 293.788532 -404.395924) (xy 293.741937 -404.439679) (xy 293.690226 -404.47725)
			(xy 293.634213 -404.508043) (xy 293.574783 -404.531573) (xy 293.512872 -404.547468) (xy 293.449457 -404.555479)
			(xy 293.417498 -404.55596) (xy 293.417244 -404.55596) (xy 293.385498 -404.555442) (xy 293.322502 -404.547512)
			(xy 293.260982 -404.531809) (xy 293.201894 -404.508575) (xy 293.146154 -404.478171) (xy 293.094629 -404.44107)
			(xy 293.071042 -404.419816) (xy 293.063779 -404.413632) (xy 293.046029 -404.406681) (xy 293.026967 -404.406681)
			(xy 293.009217 -404.413632) (xy 293.001954 -404.419816) (xy 292.978367 -404.441074) (xy 292.926858 -404.478206)
			(xy 292.871123 -404.50863) (xy 292.812032 -404.531871) (xy 292.750504 -404.547567) (xy 292.687501 -404.555474)
			(xy 292.655752 -404.55596) (xy 292.655498 -404.55596) (xy 292.623534 -404.555554) (xy 292.56011 -404.547542)
			(xy 292.498191 -404.531643) (xy 292.438752 -404.50811) (xy 292.382731 -404.477312) (xy 292.331013 -404.439736)
			(xy 292.284411 -404.395974) (xy 292.243662 -404.346717) (xy 292.209408 -404.29274) (xy 292.182189 -404.234897)
			(xy 292.162434 -404.174098) (xy 292.150455 -404.111302) (xy 292.146441 -404.0475) (xy 291.386484 -404.0475)
			(xy 291.38247 -404.111293) (xy 291.370493 -404.174079) (xy 291.350741 -404.23487) (xy 291.323525 -404.292705)
			(xy 291.289276 -404.346674) (xy 291.248532 -404.395924) (xy 291.201937 -404.439679) (xy 291.150226 -404.47725)
			(xy 291.094213 -404.508043) (xy 291.034783 -404.531573) (xy 290.972872 -404.547468) (xy 290.909457 -404.555479)
			(xy 290.877498 -404.55596) (xy 290.877244 -404.55596) (xy 290.845498 -404.555442) (xy 290.782502 -404.547512)
			(xy 290.720982 -404.531809) (xy 290.661894 -404.508575) (xy 290.606154 -404.478171) (xy 290.554629 -404.44107)
			(xy 290.531042 -404.419816) (xy 290.523779 -404.413632) (xy 290.506029 -404.406681) (xy 290.486967 -404.406681)
			(xy 290.469217 -404.413632) (xy 290.461954 -404.419816) (xy 290.438367 -404.441074) (xy 290.386858 -404.478206)
			(xy 290.331123 -404.50863) (xy 290.272032 -404.531871) (xy 290.210504 -404.547567) (xy 290.147501 -404.555474)
			(xy 290.115752 -404.55596) (xy 290.115498 -404.55596) (xy 290.083534 -404.555554) (xy 290.02011 -404.547542)
			(xy 289.958191 -404.531643) (xy 289.898752 -404.50811) (xy 289.842731 -404.477312) (xy 289.791013 -404.439736)
			(xy 289.744411 -404.395974) (xy 289.703662 -404.346717) (xy 289.669408 -404.29274) (xy 289.642189 -404.234897)
			(xy 289.622434 -404.174098) (xy 289.610455 -404.111302) (xy 289.606441 -404.0475) (xy 288.846484 -404.0475)
			(xy 288.84247 -404.111293) (xy 288.830493 -404.174079) (xy 288.810741 -404.23487) (xy 288.783525 -404.292705)
			(xy 288.749276 -404.346674) (xy 288.708532 -404.395924) (xy 288.661937 -404.439679) (xy 288.610226 -404.47725)
			(xy 288.554213 -404.508043) (xy 288.494783 -404.531573) (xy 288.432872 -404.547468) (xy 288.369457 -404.555479)
			(xy 288.337498 -404.55596) (xy 288.337244 -404.55596) (xy 288.305498 -404.555442) (xy 288.242502 -404.547512)
			(xy 288.180982 -404.531809) (xy 288.121894 -404.508575) (xy 288.066154 -404.478171) (xy 288.014629 -404.44107)
			(xy 287.991042 -404.419816) (xy 287.983779 -404.413632) (xy 287.966029 -404.406681) (xy 287.946967 -404.406681)
			(xy 287.929217 -404.413632) (xy 287.921954 -404.419816) (xy 287.898367 -404.441074) (xy 287.846858 -404.478206)
			(xy 287.791123 -404.50863) (xy 287.732032 -404.531871) (xy 287.670504 -404.547567) (xy 287.607501 -404.555474)
			(xy 287.575752 -404.55596) (xy 287.575498 -404.55596) (xy 287.543534 -404.555554) (xy 287.48011 -404.547542)
			(xy 287.418191 -404.531643) (xy 287.358752 -404.50811) (xy 287.302731 -404.477312) (xy 287.251013 -404.439736)
			(xy 287.204411 -404.395974) (xy 287.163662 -404.346717) (xy 287.129408 -404.29274) (xy 287.102189 -404.234897)
			(xy 287.082434 -404.174098) (xy 287.070455 -404.111302) (xy 287.066441 -404.0475) (xy 281.686508 -404.0475)
			(xy 281.686508 -405.908764) (xy 281.686046 -405.933715) (xy 281.678225 -405.982999) (xy 281.6628 -406.030457)
			(xy 281.64015 -406.074922) (xy 281.610832 -406.115303) (xy 281.593544 -406.1333) (xy 281.262328 -406.464516)
			(xy 281.244327 -406.4818) (xy 281.203952 -406.511124) (xy 281.159488 -406.533773) (xy 281.112029 -406.549188)
			(xy 281.062742 -406.556992) (xy 281.037792 -406.55748) (xy 278.18334 -406.55748) (xy 278.180546 -406.557734)
			(xy 278.171247 -406.558785) (xy 278.152566 -406.559928) (xy 278.143208 -406.56002) (xy 275.351748 -406.56002)
			(xy 275.326798 -406.559547) (xy 275.277514 -406.551728) (xy 275.230056 -406.536305) (xy 275.185591 -406.513658)
			(xy 275.145209 -406.484343) (xy 275.127212 -406.467056) (xy 275.08835 -406.428194) (xy 275.077488 -406.4181)
			(xy 275.051415 -406.404014) (xy 275.022395 -406.398003) (xy 274.992872 -406.400573) (xy 274.965328 -406.411507)
			(xy 274.94208 -406.429886) (xy 274.925085 -406.454164) (xy 274.919948 -406.468072) (xy 274.906846 -406.505801)
			(xy 274.873042 -406.578165) (xy 274.831055 -406.646108) (xy 274.781453 -406.70871) (xy 274.753578 -406.737312)
			(xy 274.459335 -407.031749) (xy 304.945298 -407.031749) (xy 304.945298 -406.977251) (xy 304.953054 -406.923307)
			(xy 304.968408 -406.871016) (xy 304.991047 -406.821442) (xy 305.02051 -406.775595) (xy 305.056199 -406.734407)
			(xy 305.097385 -406.698718) (xy 305.143232 -406.669252) (xy 305.192805 -406.646612) (xy 305.245095 -406.631257)
			(xy 305.299039 -406.623499) (xy 305.326288 -406.623012) (xy 306.189888 -406.623012) (xy 306.217143 -406.623434)
			(xy 306.271098 -406.63119) (xy 306.3234 -406.646546) (xy 306.372984 -406.669189) (xy 306.418841 -406.698658)
			(xy 306.460038 -406.734354) (xy 306.495735 -406.775549) (xy 306.525205 -406.821405) (xy 306.54785 -406.870989)
			(xy 306.563207 -406.92329) (xy 306.570965 -406.977245) (xy 306.570965 -407.031753) (xy 308.008475 -407.031753)
			(xy 308.008475 -406.977247) (xy 308.016233 -406.923297) (xy 308.031589 -406.870999) (xy 308.054233 -406.82142)
			(xy 308.083702 -406.775568) (xy 308.119397 -406.734377) (xy 308.16059 -406.698685) (xy 308.206445 -406.669219)
			(xy 308.256026 -406.64658) (xy 308.308324 -406.631227) (xy 308.362275 -406.623473) (xy 308.389528 -406.623012)
			(xy 309.253128 -406.623012) (xy 309.280379 -406.62346) (xy 309.334327 -406.63122) (xy 309.386621 -406.646578)
			(xy 309.436197 -406.669222) (xy 309.482047 -406.698691) (xy 309.523236 -406.734384) (xy 309.558926 -406.775576)
			(xy 309.588391 -406.821427) (xy 309.611032 -406.871005) (xy 309.626386 -406.923301) (xy 309.634142 -406.977249)
			(xy 309.634142 -407.031748) (xy 311.071798 -407.031748) (xy 311.071798 -406.977252) (xy 311.079553 -406.92331)
			(xy 311.094906 -406.87102) (xy 311.117544 -406.821448) (xy 311.147005 -406.775601) (xy 311.182692 -406.734414)
			(xy 311.223876 -406.698725) (xy 311.26972 -406.669259) (xy 311.31929 -406.646617) (xy 311.371578 -406.63126)
			(xy 311.42552 -406.6235) (xy 311.452768 -406.623012) (xy 312.316368 -406.623012) (xy 312.343624 -406.623433)
			(xy 312.397581 -406.631186) (xy 312.449886 -406.64654) (xy 312.499472 -406.669182) (xy 312.545332 -406.698651)
			(xy 312.586531 -406.734347) (xy 312.62223 -406.775542) (xy 312.651702 -406.821399) (xy 312.674348 -406.870984)
			(xy 312.689707 -406.923288) (xy 312.697465 -406.977244) (xy 312.697465 -407.031752) (xy 314.134975 -407.031752)
			(xy 314.134975 -406.977248) (xy 314.142732 -406.923299) (xy 314.158088 -406.871004) (xy 314.18073 -406.821426)
			(xy 314.210197 -406.775575) (xy 314.245889 -406.734384) (xy 314.287081 -406.698692) (xy 314.332933 -406.669226)
			(xy 314.382511 -406.646585) (xy 314.434807 -406.63123) (xy 314.488756 -406.623475) (xy 314.516008 -406.623012)
			(xy 315.379608 -406.623012) (xy 315.40686 -406.623458) (xy 315.46081 -406.631216) (xy 315.513107 -406.646573)
			(xy 315.562685 -406.669216) (xy 315.608537 -406.698684) (xy 315.649729 -406.734377) (xy 315.685421 -406.775569)
			(xy 315.714888 -406.821422) (xy 315.73753 -406.871001) (xy 315.752885 -406.923298) (xy 315.760642 -406.977248)
			(xy 315.760642 -407.031752) (xy 315.760642 -407.031754) (xy 317.198175 -407.031754) (xy 317.198175 -406.977246)
			(xy 317.205933 -406.923294) (xy 317.221291 -406.870995) (xy 317.243936 -406.821414) (xy 317.273407 -406.775561)
			(xy 317.309104 -406.73437) (xy 317.3503 -406.698678) (xy 317.396157 -406.669213) (xy 317.44574 -406.646574)
			(xy 317.498041 -406.631223) (xy 317.551994 -406.623472) (xy 317.579248 -406.623012) (xy 318.442848 -406.623012)
			(xy 318.470098 -406.623461) (xy 318.524044 -406.631224) (xy 318.576336 -406.646584) (xy 318.625909 -406.669229)
			(xy 318.671756 -406.698698) (xy 318.712943 -406.734391) (xy 318.748631 -406.775582) (xy 318.778094 -406.821433)
			(xy 318.800733 -406.87101) (xy 318.816087 -406.923303) (xy 318.823842 -406.97725) (xy 318.823842 -407.031749)
			(xy 320.261498 -407.031749) (xy 320.261498 -406.977251) (xy 320.269254 -406.923307) (xy 320.284608 -406.871016)
			(xy 320.307247 -406.821442) (xy 320.33671 -406.775595) (xy 320.372399 -406.734407) (xy 320.413585 -406.698718)
			(xy 320.459432 -406.669252) (xy 320.509005 -406.646612) (xy 320.561295 -406.631257) (xy 320.615239 -406.623499)
			(xy 320.642488 -406.623012) (xy 321.506088 -406.623012) (xy 321.533343 -406.623434) (xy 321.587298 -406.63119)
			(xy 321.6396 -406.646546) (xy 321.689184 -406.669189) (xy 321.735041 -406.698658) (xy 321.776238 -406.734354)
			(xy 321.811935 -406.775549) (xy 321.841405 -406.821405) (xy 321.86405 -406.870989) (xy 321.879407 -406.92329)
			(xy 321.887165 -406.977245) (xy 321.887165 -407.031753) (xy 323.324675 -407.031753) (xy 323.324675 -406.977247)
			(xy 323.332433 -406.923297) (xy 323.347789 -406.870999) (xy 323.370433 -406.82142) (xy 323.399902 -406.775568)
			(xy 323.435597 -406.734377) (xy 323.47679 -406.698685) (xy 323.522645 -406.669219) (xy 323.572226 -406.64658)
			(xy 323.624524 -406.631227) (xy 323.678475 -406.623473) (xy 323.705728 -406.623012) (xy 324.569328 -406.623012)
			(xy 324.596579 -406.62346) (xy 324.650527 -406.63122) (xy 324.702821 -406.646578) (xy 324.752397 -406.669222)
			(xy 324.798247 -406.698691) (xy 324.839436 -406.734384) (xy 324.875126 -406.775576) (xy 324.904591 -406.821427)
			(xy 324.927232 -406.871005) (xy 324.942586 -406.923301) (xy 324.950342 -406.977249) (xy 324.950342 -407.031748)
			(xy 326.387998 -407.031748) (xy 326.387998 -406.977252) (xy 326.395753 -406.92331) (xy 326.411106 -406.87102)
			(xy 326.433744 -406.821448) (xy 326.463205 -406.775601) (xy 326.498892 -406.734414) (xy 326.540076 -406.698725)
			(xy 326.58592 -406.669259) (xy 326.63549 -406.646617) (xy 326.687778 -406.63126) (xy 326.74172 -406.6235)
			(xy 326.768968 -406.623012) (xy 327.632568 -406.623012) (xy 327.659824 -406.623433) (xy 327.713781 -406.631186)
			(xy 327.766086 -406.64654) (xy 327.815672 -406.669182) (xy 327.861532 -406.698651) (xy 327.902731 -406.734347)
			(xy 327.93843 -406.775542) (xy 327.967902 -406.821399) (xy 327.990548 -406.870984) (xy 328.005907 -406.923288)
			(xy 328.013665 -406.977244) (xy 328.013665 -407.031752) (xy 329.451175 -407.031752) (xy 329.451175 -406.977248)
			(xy 329.458932 -406.923299) (xy 329.474288 -406.871004) (xy 329.49693 -406.821426) (xy 329.526397 -406.775575)
			(xy 329.562089 -406.734384) (xy 329.603281 -406.698692) (xy 329.649133 -406.669226) (xy 329.698711 -406.646585)
			(xy 329.751007 -406.63123) (xy 329.804956 -406.623475) (xy 329.832208 -406.623012) (xy 330.695808 -406.623012)
			(xy 330.72306 -406.623458) (xy 330.77701 -406.631216) (xy 330.829307 -406.646573) (xy 330.878885 -406.669216)
			(xy 330.924737 -406.698684) (xy 330.965929 -406.734377) (xy 331.001621 -406.775569) (xy 331.031088 -406.821422)
			(xy 331.05373 -406.871001) (xy 331.069085 -406.923298) (xy 331.076842 -406.977248) (xy 331.076842 -407.031752)
			(xy 331.076842 -407.031754) (xy 332.514375 -407.031754) (xy 332.514375 -406.977246) (xy 332.522133 -406.923294)
			(xy 332.537491 -406.870995) (xy 332.560136 -406.821414) (xy 332.589607 -406.775561) (xy 332.625304 -406.73437)
			(xy 332.6665 -406.698678) (xy 332.712357 -406.669213) (xy 332.76194 -406.646574) (xy 332.814241 -406.631223)
			(xy 332.868194 -406.623472) (xy 332.895448 -406.623012) (xy 333.759048 -406.623012) (xy 333.786298 -406.623461)
			(xy 333.840244 -406.631224) (xy 333.892536 -406.646584) (xy 333.942109 -406.669229) (xy 333.987956 -406.698698)
			(xy 334.029143 -406.734391) (xy 334.064831 -406.775582) (xy 334.094294 -406.821433) (xy 334.116933 -406.87101)
			(xy 334.132287 -406.923303) (xy 334.140042 -406.97725) (xy 334.140042 -407.031749) (xy 335.577698 -407.031749)
			(xy 335.577698 -406.977251) (xy 335.585454 -406.923307) (xy 335.600808 -406.871016) (xy 335.623447 -406.821442)
			(xy 335.65291 -406.775595) (xy 335.688599 -406.734407) (xy 335.729785 -406.698718) (xy 335.775632 -406.669252)
			(xy 335.825205 -406.646612) (xy 335.877495 -406.631257) (xy 335.931439 -406.623499) (xy 335.958688 -406.623012)
			(xy 336.822288 -406.623012) (xy 336.849543 -406.623434) (xy 336.903498 -406.63119) (xy 336.9558 -406.646546)
			(xy 337.005384 -406.669189) (xy 337.051241 -406.698658) (xy 337.092438 -406.734354) (xy 337.128135 -406.775549)
			(xy 337.157605 -406.821405) (xy 337.18025 -406.870989) (xy 337.195607 -406.92329) (xy 337.203365 -406.977245)
			(xy 337.203365 -407.031753) (xy 338.640875 -407.031753) (xy 338.640875 -406.977247) (xy 338.648633 -406.923297)
			(xy 338.663989 -406.870999) (xy 338.686633 -406.82142) (xy 338.716102 -406.775568) (xy 338.751797 -406.734377)
			(xy 338.79299 -406.698685) (xy 338.838845 -406.669219) (xy 338.888426 -406.64658) (xy 338.940724 -406.631227)
			(xy 338.994675 -406.623473) (xy 339.021928 -406.623012) (xy 339.885528 -406.623012) (xy 339.912779 -406.62346)
			(xy 339.966727 -406.63122) (xy 340.019021 -406.646578) (xy 340.068597 -406.669222) (xy 340.114447 -406.698691)
			(xy 340.155636 -406.734384) (xy 340.191326 -406.775576) (xy 340.220791 -406.821427) (xy 340.243432 -406.871005)
			(xy 340.258786 -406.923301) (xy 340.266542 -406.977249) (xy 340.266542 -407.031748) (xy 341.704198 -407.031748)
			(xy 341.704198 -406.977252) (xy 341.711953 -406.92331) (xy 341.727306 -406.87102) (xy 341.749944 -406.821448)
			(xy 341.779405 -406.775601) (xy 341.815092 -406.734414) (xy 341.856276 -406.698725) (xy 341.90212 -406.669259)
			(xy 341.95169 -406.646617) (xy 342.003978 -406.63126) (xy 342.05792 -406.6235) (xy 342.085168 -406.623012)
			(xy 342.948768 -406.623012) (xy 342.976024 -406.623433) (xy 343.029981 -406.631186) (xy 343.082286 -406.64654)
			(xy 343.131872 -406.669182) (xy 343.177732 -406.698651) (xy 343.218931 -406.734347) (xy 343.25463 -406.775542)
			(xy 343.284102 -406.821399) (xy 343.306748 -406.870984) (xy 343.322107 -406.923288) (xy 343.329865 -406.977244)
			(xy 343.329865 -407.031752) (xy 344.767375 -407.031752) (xy 344.767375 -406.977248) (xy 344.775132 -406.923299)
			(xy 344.790488 -406.871004) (xy 344.81313 -406.821426) (xy 344.842597 -406.775575) (xy 344.878289 -406.734384)
			(xy 344.919481 -406.698692) (xy 344.965333 -406.669226) (xy 345.014911 -406.646585) (xy 345.067207 -406.63123)
			(xy 345.121156 -406.623475) (xy 345.148408 -406.623012) (xy 346.012008 -406.623012) (xy 346.03926 -406.623458)
			(xy 346.09321 -406.631216) (xy 346.145507 -406.646573) (xy 346.195085 -406.669216) (xy 346.240937 -406.698684)
			(xy 346.282129 -406.734377) (xy 346.317821 -406.775569) (xy 346.347288 -406.821422) (xy 346.36993 -406.871001)
			(xy 346.385285 -406.923298) (xy 346.393042 -406.977248) (xy 346.393042 -407.031752) (xy 346.393042 -407.031754)
			(xy 347.830575 -407.031754) (xy 347.830575 -406.977246) (xy 347.838333 -406.923294) (xy 347.853691 -406.870995)
			(xy 347.876336 -406.821414) (xy 347.905807 -406.775561) (xy 347.941504 -406.73437) (xy 347.9827 -406.698678)
			(xy 348.028557 -406.669213) (xy 348.07814 -406.646574) (xy 348.130441 -406.631223) (xy 348.184394 -406.623472)
			(xy 348.211648 -406.623012) (xy 349.075248 -406.623012) (xy 349.102498 -406.623461) (xy 349.156444 -406.631224)
			(xy 349.208736 -406.646584) (xy 349.258309 -406.669229) (xy 349.304156 -406.698698) (xy 349.345343 -406.734391)
			(xy 349.381031 -406.775582) (xy 349.410494 -406.821433) (xy 349.433133 -406.87101) (xy 349.448487 -406.923303)
			(xy 349.456242 -406.97725) (xy 349.456242 -407.031749) (xy 350.893898 -407.031749) (xy 350.893898 -406.977251)
			(xy 350.901654 -406.923307) (xy 350.917008 -406.871016) (xy 350.939647 -406.821442) (xy 350.96911 -406.775595)
			(xy 351.004799 -406.734407) (xy 351.045985 -406.698718) (xy 351.091832 -406.669252) (xy 351.141405 -406.646612)
			(xy 351.193695 -406.631257) (xy 351.247639 -406.623499) (xy 351.274888 -406.623012) (xy 352.138488 -406.623012)
			(xy 352.165743 -406.623434) (xy 352.219698 -406.63119) (xy 352.272 -406.646546) (xy 352.321584 -406.669189)
			(xy 352.367441 -406.698658) (xy 352.408638 -406.734354) (xy 352.444335 -406.775549) (xy 352.473805 -406.821405)
			(xy 352.49645 -406.870989) (xy 352.511807 -406.92329) (xy 352.519565 -406.977245) (xy 352.519565 -407.031753)
			(xy 372.388075 -407.031753) (xy 372.388075 -406.977247) (xy 372.395833 -406.923296) (xy 372.411189 -406.870999)
			(xy 372.433833 -406.821419) (xy 372.463302 -406.775567) (xy 372.498997 -406.734376) (xy 372.540191 -406.698684)
			(xy 372.586046 -406.669219) (xy 372.635627 -406.646579) (xy 372.687926 -406.631226) (xy 372.741877 -406.623473)
			(xy 372.76913 -406.623012) (xy 373.63273 -406.623012) (xy 373.659981 -406.62346) (xy 373.713929 -406.63122)
			(xy 373.766222 -406.646579) (xy 373.815799 -406.669223) (xy 373.861648 -406.698691) (xy 373.902836 -406.734385)
			(xy 373.938527 -406.775576) (xy 373.967992 -406.821428) (xy 373.990632 -406.871006) (xy 374.005986 -406.923301)
			(xy 374.013742 -406.977249) (xy 374.013742 -407.031748) (xy 375.451398 -407.031748) (xy 375.451398 -406.977252)
			(xy 375.459153 -406.923309) (xy 375.474506 -406.87102) (xy 375.497144 -406.821447) (xy 375.526606 -406.775601)
			(xy 375.562292 -406.734414) (xy 375.603477 -406.698724) (xy 375.649321 -406.669258) (xy 375.698892 -406.646617)
			(xy 375.75118 -406.63126) (xy 375.805122 -406.6235) (xy 375.83237 -406.623012) (xy 376.69597 -406.623012)
			(xy 376.723226 -406.623433) (xy 376.777183 -406.631187) (xy 376.829487 -406.646541) (xy 376.879074 -406.669183)
			(xy 376.924933 -406.698652) (xy 376.966131 -406.734347) (xy 377.00183 -406.775543) (xy 377.031303 -406.8214)
			(xy 377.053948 -406.870985) (xy 377.069307 -406.923288) (xy 377.077065 -406.977244) (xy 377.077065 -407.031752)
			(xy 378.514575 -407.031752) (xy 378.514575 -406.977248) (xy 378.522332 -406.923299) (xy 378.537688 -406.871003)
			(xy 378.56033 -406.821425) (xy 378.589797 -406.775574) (xy 378.62549 -406.734383) (xy 378.666682 -406.698691)
			(xy 378.712534 -406.669225) (xy 378.762113 -406.646584) (xy 378.814409 -406.63123) (xy 378.868358 -406.623475)
			(xy 378.89561 -406.623012) (xy 379.75921 -406.623012) (xy 379.786462 -406.623459) (xy 379.840412 -406.631217)
			(xy 379.892708 -406.646573) (xy 379.942287 -406.669216) (xy 379.988138 -406.698684) (xy 380.029329 -406.734378)
			(xy 380.065022 -406.77557) (xy 380.094489 -406.821422) (xy 380.11713 -406.871001) (xy 380.132486 -406.923298)
			(xy 380.140242 -406.977248) (xy 380.140242 -407.031748) (xy 381.577898 -407.031748) (xy 381.577898 -406.977252)
			(xy 381.585653 -406.923312) (xy 381.601005 -406.871024) (xy 381.623641 -406.821453) (xy 381.653101 -406.775607)
			(xy 381.688785 -406.734421) (xy 381.729967 -406.698731) (xy 381.775809 -406.669265) (xy 381.825377 -406.646622)
			(xy 381.877663 -406.631264) (xy 381.931603 -406.623502) (xy 381.95885 -406.623012) (xy 382.82245 -406.623012)
			(xy 382.849707 -406.623431) (xy 382.903666 -406.631183) (xy 382.955973 -406.646536) (xy 383.005562 -406.669176)
			(xy 383.051423 -406.698645) (xy 383.092624 -406.73434) (xy 383.128325 -406.775536) (xy 383.1578 -406.821394)
			(xy 383.180447 -406.870981) (xy 383.195806 -406.923285) (xy 383.203565 -406.977243) (xy 383.203565 -407.031749)
			(xy 384.641098 -407.031749) (xy 384.641098 -406.977251) (xy 384.648854 -406.923307) (xy 384.664208 -406.871016)
			(xy 384.686847 -406.821442) (xy 384.716311 -406.775594) (xy 384.751999 -406.734406) (xy 384.793186 -406.698717)
			(xy 384.839033 -406.669252) (xy 384.888606 -406.646611) (xy 384.940897 -406.631256) (xy 384.994841 -406.623499)
			(xy 385.02209 -406.623012) (xy 385.88569 -406.623012) (xy 385.912945 -406.623434) (xy 385.9669 -406.63119)
			(xy 386.019202 -406.646546) (xy 386.068786 -406.66919) (xy 386.114642 -406.698659) (xy 386.155838 -406.734354)
			(xy 386.191535 -406.77555) (xy 386.221006 -406.821406) (xy 386.24365 -406.870989) (xy 386.259007 -406.923291)
			(xy 386.266765 -406.977245) (xy 386.266765 -407.031753) (xy 387.704275 -407.031753) (xy 387.704275 -406.977247)
			(xy 387.712033 -406.923296) (xy 387.727389 -406.870999) (xy 387.750033 -406.821419) (xy 387.779502 -406.775567)
			(xy 387.815197 -406.734376) (xy 387.856391 -406.698684) (xy 387.902246 -406.669219) (xy 387.951827 -406.646579)
			(xy 388.004126 -406.631226) (xy 388.058077 -406.623473) (xy 388.08533 -406.623012) (xy 388.94893 -406.623012)
			(xy 388.976181 -406.62346) (xy 389.030129 -406.63122) (xy 389.082422 -406.646579) (xy 389.131999 -406.669223)
			(xy 389.177848 -406.698691) (xy 389.219036 -406.734385) (xy 389.254727 -406.775576) (xy 389.284192 -406.821428)
			(xy 389.306832 -406.871006) (xy 389.322186 -406.923301) (xy 389.329942 -406.977249) (xy 389.329942 -407.031748)
			(xy 390.767598 -407.031748) (xy 390.767598 -406.977252) (xy 390.775353 -406.923309) (xy 390.790706 -406.87102)
			(xy 390.813344 -406.821447) (xy 390.842806 -406.775601) (xy 390.878492 -406.734414) (xy 390.919677 -406.698724)
			(xy 390.965521 -406.669258) (xy 391.015092 -406.646617) (xy 391.06738 -406.63126) (xy 391.121322 -406.6235)
			(xy 391.14857 -406.623012) (xy 392.01217 -406.623012) (xy 392.039426 -406.623433) (xy 392.093383 -406.631187)
			(xy 392.145687 -406.646541) (xy 392.195274 -406.669183) (xy 392.241133 -406.698652) (xy 392.282331 -406.734347)
			(xy 392.31803 -406.775543) (xy 392.347503 -406.8214) (xy 392.370148 -406.870985) (xy 392.385507 -406.923288)
			(xy 392.393265 -406.977244) (xy 392.393265 -407.031752) (xy 393.830775 -407.031752) (xy 393.830775 -406.977248)
			(xy 393.838532 -406.923299) (xy 393.853888 -406.871003) (xy 393.87653 -406.821425) (xy 393.905997 -406.775574)
			(xy 393.94169 -406.734383) (xy 393.982882 -406.698691) (xy 394.028734 -406.669225) (xy 394.078313 -406.646584)
			(xy 394.130609 -406.63123) (xy 394.184558 -406.623475) (xy 394.21181 -406.623012) (xy 395.07541 -406.623012)
			(xy 395.102662 -406.623459) (xy 395.156612 -406.631217) (xy 395.208908 -406.646573) (xy 395.258487 -406.669216)
			(xy 395.304338 -406.698684) (xy 395.345529 -406.734378) (xy 395.381222 -406.77557) (xy 395.410689 -406.821422)
			(xy 395.43333 -406.871001) (xy 395.448686 -406.923298) (xy 395.456442 -406.977248) (xy 395.456442 -407.031748)
			(xy 396.894098 -407.031748) (xy 396.894098 -406.977252) (xy 396.901853 -406.923312) (xy 396.917205 -406.871024)
			(xy 396.939841 -406.821453) (xy 396.969301 -406.775607) (xy 397.004985 -406.734421) (xy 397.046167 -406.698731)
			(xy 397.092009 -406.669265) (xy 397.141577 -406.646622) (xy 397.193863 -406.631264) (xy 397.247803 -406.623502)
			(xy 397.27505 -406.623012) (xy 398.13865 -406.623012) (xy 398.165907 -406.623431) (xy 398.219866 -406.631183)
			(xy 398.272173 -406.646536) (xy 398.321762 -406.669176) (xy 398.367623 -406.698645) (xy 398.408824 -406.73434)
			(xy 398.444525 -406.775536) (xy 398.474 -406.821394) (xy 398.496647 -406.870981) (xy 398.512006 -406.923285)
			(xy 398.519765 -406.977243) (xy 398.519765 -407.031749) (xy 399.957298 -407.031749) (xy 399.957298 -406.977251)
			(xy 399.965054 -406.923307) (xy 399.980408 -406.871016) (xy 400.003047 -406.821442) (xy 400.032511 -406.775594)
			(xy 400.068199 -406.734406) (xy 400.109386 -406.698717) (xy 400.155233 -406.669252) (xy 400.204806 -406.646611)
			(xy 400.257097 -406.631256) (xy 400.311041 -406.623499) (xy 400.33829 -406.623012) (xy 401.20189 -406.623012)
			(xy 401.229145 -406.623434) (xy 401.2831 -406.63119) (xy 401.335402 -406.646546) (xy 401.384986 -406.66919)
			(xy 401.430842 -406.698659) (xy 401.472038 -406.734354) (xy 401.507735 -406.77555) (xy 401.537206 -406.821406)
			(xy 401.55985 -406.870989) (xy 401.575207 -406.923291) (xy 401.582965 -406.977245) (xy 401.582965 -407.031753)
			(xy 403.020475 -407.031753) (xy 403.020475 -406.977247) (xy 403.028233 -406.923296) (xy 403.043589 -406.870999)
			(xy 403.066233 -406.821419) (xy 403.095702 -406.775567) (xy 403.131397 -406.734376) (xy 403.172591 -406.698684)
			(xy 403.218446 -406.669219) (xy 403.268027 -406.646579) (xy 403.320326 -406.631226) (xy 403.374277 -406.623473)
			(xy 403.40153 -406.623012) (xy 404.26513 -406.623012) (xy 404.292381 -406.62346) (xy 404.346329 -406.63122)
			(xy 404.398622 -406.646579) (xy 404.448199 -406.669223) (xy 404.494048 -406.698691) (xy 404.535236 -406.734385)
			(xy 404.570927 -406.775576) (xy 404.600392 -406.821428) (xy 404.623032 -406.871006) (xy 404.638386 -406.923301)
			(xy 404.646142 -406.977249) (xy 404.646142 -407.031748) (xy 406.083798 -407.031748) (xy 406.083798 -406.977252)
			(xy 406.091553 -406.923309) (xy 406.106906 -406.87102) (xy 406.129544 -406.821447) (xy 406.159006 -406.775601)
			(xy 406.194692 -406.734414) (xy 406.235877 -406.698724) (xy 406.281721 -406.669258) (xy 406.331292 -406.646617)
			(xy 406.38358 -406.63126) (xy 406.437522 -406.6235) (xy 406.46477 -406.623012) (xy 407.32837 -406.623012)
			(xy 407.355626 -406.623433) (xy 407.409583 -406.631187) (xy 407.461887 -406.646541) (xy 407.511474 -406.669183)
			(xy 407.557333 -406.698652) (xy 407.598531 -406.734347) (xy 407.63423 -406.775543) (xy 407.663703 -406.8214)
			(xy 407.686348 -406.870985) (xy 407.701707 -406.923288) (xy 407.709465 -406.977244) (xy 407.709465 -407.031752)
			(xy 409.146975 -407.031752) (xy 409.146975 -406.977248) (xy 409.154732 -406.923299) (xy 409.170088 -406.871003)
			(xy 409.19273 -406.821425) (xy 409.222197 -406.775574) (xy 409.25789 -406.734383) (xy 409.299082 -406.698691)
			(xy 409.344934 -406.669225) (xy 409.394513 -406.646584) (xy 409.446809 -406.63123) (xy 409.500758 -406.623475)
			(xy 409.52801 -406.623012) (xy 410.39161 -406.623012) (xy 410.418862 -406.623459) (xy 410.472812 -406.631217)
			(xy 410.525108 -406.646573) (xy 410.574687 -406.669216) (xy 410.620538 -406.698684) (xy 410.661729 -406.734378)
			(xy 410.697422 -406.77557) (xy 410.726889 -406.821422) (xy 410.74953 -406.871001) (xy 410.764886 -406.923298)
			(xy 410.772642 -406.977248) (xy 410.772642 -407.031748) (xy 412.210298 -407.031748) (xy 412.210298 -406.977252)
			(xy 412.218053 -406.923312) (xy 412.233405 -406.871024) (xy 412.256041 -406.821453) (xy 412.285501 -406.775607)
			(xy 412.321185 -406.734421) (xy 412.362367 -406.698731) (xy 412.408209 -406.669265) (xy 412.457777 -406.646622)
			(xy 412.510063 -406.631264) (xy 412.564003 -406.623502) (xy 412.59125 -406.623012) (xy 413.45485 -406.623012)
			(xy 413.482107 -406.623431) (xy 413.536066 -406.631183) (xy 413.588373 -406.646536) (xy 413.637962 -406.669176)
			(xy 413.683823 -406.698645) (xy 413.725024 -406.73434) (xy 413.760725 -406.775536) (xy 413.7902 -406.821394)
			(xy 413.812847 -406.870981) (xy 413.828206 -406.923285) (xy 413.835965 -406.977243) (xy 413.835965 -407.031749)
			(xy 415.273498 -407.031749) (xy 415.273498 -406.977251) (xy 415.281254 -406.923307) (xy 415.296608 -406.871016)
			(xy 415.319247 -406.821442) (xy 415.348711 -406.775594) (xy 415.384399 -406.734406) (xy 415.425586 -406.698717)
			(xy 415.471433 -406.669252) (xy 415.521006 -406.646611) (xy 415.573297 -406.631256) (xy 415.627241 -406.623499)
			(xy 415.65449 -406.623012) (xy 416.51809 -406.623012) (xy 416.545345 -406.623434) (xy 416.5993 -406.63119)
			(xy 416.651602 -406.646546) (xy 416.701186 -406.66919) (xy 416.747042 -406.698659) (xy 416.788238 -406.734354)
			(xy 416.823935 -406.77555) (xy 416.853406 -406.821406) (xy 416.87605 -406.870989) (xy 416.891407 -406.923291)
			(xy 416.899165 -406.977245) (xy 416.899165 -407.031753) (xy 418.336675 -407.031753) (xy 418.336675 -406.977247)
			(xy 418.344433 -406.923296) (xy 418.359789 -406.870999) (xy 418.382433 -406.821419) (xy 418.411902 -406.775567)
			(xy 418.447597 -406.734376) (xy 418.488791 -406.698684) (xy 418.534646 -406.669219) (xy 418.584227 -406.646579)
			(xy 418.636526 -406.631226) (xy 418.690477 -406.623473) (xy 418.71773 -406.623012) (xy 419.58133 -406.623012)
			(xy 419.608581 -406.62346) (xy 419.662529 -406.63122) (xy 419.714822 -406.646579) (xy 419.764399 -406.669223)
			(xy 419.810248 -406.698691) (xy 419.851436 -406.734385) (xy 419.887127 -406.775576) (xy 419.916592 -406.821428)
			(xy 419.939232 -406.871006) (xy 419.954586 -406.923301) (xy 419.962342 -406.977249) (xy 419.962342 -407.031751)
			(xy 419.954586 -407.085699) (xy 419.939232 -407.137994) (xy 419.916592 -407.187572) (xy 419.887127 -407.233424)
			(xy 419.851436 -407.274615) (xy 419.810248 -407.310309) (xy 419.764399 -407.339777) (xy 419.714822 -407.362421)
			(xy 419.662529 -407.37778) (xy 419.608581 -407.38554) (xy 419.58133 -407.386028) (xy 418.71773 -407.386028)
			(xy 418.690477 -407.385527) (xy 418.636526 -407.377774) (xy 418.584227 -407.362421) (xy 418.534646 -407.339781)
			(xy 418.488791 -407.310316) (xy 418.447597 -407.274624) (xy 418.411902 -407.233433) (xy 418.382433 -407.187581)
			(xy 418.359789 -407.138001) (xy 418.344433 -407.085704) (xy 418.336675 -407.031753) (xy 416.899165 -407.031753)
			(xy 416.899165 -407.031755) (xy 416.891407 -407.085709) (xy 416.87605 -407.138011) (xy 416.853406 -407.187594)
			(xy 416.823935 -407.23345) (xy 416.788238 -407.274646) (xy 416.747042 -407.310341) (xy 416.701186 -407.33981)
			(xy 416.651602 -407.362454) (xy 416.5993 -407.37781) (xy 416.545345 -407.385566) (xy 416.51809 -407.386028)
			(xy 415.65449 -407.386028) (xy 415.627241 -407.385501) (xy 415.573297 -407.377744) (xy 415.521006 -407.362389)
			(xy 415.471433 -407.339748) (xy 415.425586 -407.310283) (xy 415.384399 -407.274594) (xy 415.348711 -407.233406)
			(xy 415.319247 -407.187558) (xy 415.296608 -407.137984) (xy 415.281254 -407.085693) (xy 415.273498 -407.031749)
			(xy 413.835965 -407.031749) (xy 413.835965 -407.031757) (xy 413.828206 -407.085715) (xy 413.812847 -407.138019)
			(xy 413.7902 -407.187606) (xy 413.760725 -407.233464) (xy 413.725024 -407.27466) (xy 413.683823 -407.310355)
			(xy 413.637962 -407.339824) (xy 413.588373 -407.362464) (xy 413.536066 -407.377817) (xy 413.482107 -407.385569)
			(xy 413.45485 -407.386028) (xy 412.59125 -407.386028) (xy 412.564003 -407.385498) (xy 412.510063 -407.377736)
			(xy 412.457777 -407.362378) (xy 412.408209 -407.339735) (xy 412.362367 -407.310269) (xy 412.321185 -407.274579)
			(xy 412.285501 -407.233393) (xy 412.256041 -407.187547) (xy 412.233405 -407.137976) (xy 412.218053 -407.085688)
			(xy 412.210298 -407.031748) (xy 410.772642 -407.031748) (xy 410.772642 -407.031752) (xy 410.764886 -407.085702)
			(xy 410.74953 -407.137999) (xy 410.726889 -407.187578) (xy 410.697422 -407.23343) (xy 410.661729 -407.274622)
			(xy 410.620538 -407.310316) (xy 410.574687 -407.339784) (xy 410.525108 -407.362427) (xy 410.472812 -407.377783)
			(xy 410.418862 -407.385541) (xy 410.39161 -407.386028) (xy 409.52801 -407.386028) (xy 409.500758 -407.385525)
			(xy 409.446809 -407.37777) (xy 409.394513 -407.362416) (xy 409.344934 -407.339775) (xy 409.299082 -407.310309)
			(xy 409.25789 -407.274617) (xy 409.222197 -407.233426) (xy 409.19273 -407.187575) (xy 409.170088 -407.137997)
			(xy 409.154732 -407.085701) (xy 409.146975 -407.031752) (xy 407.709465 -407.031752) (xy 407.709465 -407.031756)
			(xy 407.701707 -407.085712) (xy 407.686348 -407.138015) (xy 407.663703 -407.1876) (xy 407.63423 -407.233457)
			(xy 407.598531 -407.274653) (xy 407.557333 -407.310348) (xy 407.511474 -407.339817) (xy 407.461887 -407.362459)
			(xy 407.409583 -407.377813) (xy 407.355626 -407.385567) (xy 407.32837 -407.386028) (xy 406.46477 -407.386028)
			(xy 406.437522 -407.3855) (xy 406.38358 -407.37774) (xy 406.331292 -407.362383) (xy 406.281721 -407.339742)
			(xy 406.235877 -407.310276) (xy 406.194692 -407.274586) (xy 406.159006 -407.233399) (xy 406.129544 -407.187553)
			(xy 406.106906 -407.13798) (xy 406.091553 -407.085691) (xy 406.083798 -407.031748) (xy 404.646142 -407.031748)
			(xy 404.646142 -407.031751) (xy 404.638386 -407.085699) (xy 404.623032 -407.137994) (xy 404.600392 -407.187572)
			(xy 404.570927 -407.233424) (xy 404.535236 -407.274615) (xy 404.494048 -407.310309) (xy 404.448199 -407.339777)
			(xy 404.398622 -407.362421) (xy 404.346329 -407.37778) (xy 404.292381 -407.38554) (xy 404.26513 -407.386028)
			(xy 403.40153 -407.386028) (xy 403.374277 -407.385527) (xy 403.320326 -407.377774) (xy 403.268027 -407.362421)
			(xy 403.218446 -407.339781) (xy 403.172591 -407.310316) (xy 403.131397 -407.274624) (xy 403.095702 -407.233433)
			(xy 403.066233 -407.187581) (xy 403.043589 -407.138001) (xy 403.028233 -407.085704) (xy 403.020475 -407.031753)
			(xy 401.582965 -407.031753) (xy 401.582965 -407.031755) (xy 401.575207 -407.085709) (xy 401.55985 -407.138011)
			(xy 401.537206 -407.187594) (xy 401.507735 -407.23345) (xy 401.472038 -407.274646) (xy 401.430842 -407.310341)
			(xy 401.384986 -407.33981) (xy 401.335402 -407.362454) (xy 401.2831 -407.37781) (xy 401.229145 -407.385566)
			(xy 401.20189 -407.386028) (xy 400.33829 -407.386028) (xy 400.311041 -407.385501) (xy 400.257097 -407.377744)
			(xy 400.204806 -407.362389) (xy 400.155233 -407.339748) (xy 400.109386 -407.310283) (xy 400.068199 -407.274594)
			(xy 400.032511 -407.233406) (xy 400.003047 -407.187558) (xy 399.980408 -407.137984) (xy 399.965054 -407.085693)
			(xy 399.957298 -407.031749) (xy 398.519765 -407.031749) (xy 398.519765 -407.031757) (xy 398.512006 -407.085715)
			(xy 398.496647 -407.138019) (xy 398.474 -407.187606) (xy 398.444525 -407.233464) (xy 398.408824 -407.27466)
			(xy 398.367623 -407.310355) (xy 398.321762 -407.339824) (xy 398.272173 -407.362464) (xy 398.219866 -407.377817)
			(xy 398.165907 -407.385569) (xy 398.13865 -407.386028) (xy 397.27505 -407.386028) (xy 397.247803 -407.385498)
			(xy 397.193863 -407.377736) (xy 397.141577 -407.362378) (xy 397.092009 -407.339735) (xy 397.046167 -407.310269)
			(xy 397.004985 -407.274579) (xy 396.969301 -407.233393) (xy 396.939841 -407.187547) (xy 396.917205 -407.137976)
			(xy 396.901853 -407.085688) (xy 396.894098 -407.031748) (xy 395.456442 -407.031748) (xy 395.456442 -407.031752)
			(xy 395.448686 -407.085702) (xy 395.43333 -407.137999) (xy 395.410689 -407.187578) (xy 395.381222 -407.23343)
			(xy 395.345529 -407.274622) (xy 395.304338 -407.310316) (xy 395.258487 -407.339784) (xy 395.208908 -407.362427)
			(xy 395.156612 -407.377783) (xy 395.102662 -407.385541) (xy 395.07541 -407.386028) (xy 394.21181 -407.386028)
			(xy 394.184558 -407.385525) (xy 394.130609 -407.37777) (xy 394.078313 -407.362416) (xy 394.028734 -407.339775)
			(xy 393.982882 -407.310309) (xy 393.94169 -407.274617) (xy 393.905997 -407.233426) (xy 393.87653 -407.187575)
			(xy 393.853888 -407.137997) (xy 393.838532 -407.085701) (xy 393.830775 -407.031752) (xy 392.393265 -407.031752)
			(xy 392.393265 -407.031756) (xy 392.385507 -407.085712) (xy 392.370148 -407.138015) (xy 392.347503 -407.1876)
			(xy 392.31803 -407.233457) (xy 392.282331 -407.274653) (xy 392.241133 -407.310348) (xy 392.195274 -407.339817)
			(xy 392.145687 -407.362459) (xy 392.093383 -407.377813) (xy 392.039426 -407.385567) (xy 392.01217 -407.386028)
			(xy 391.14857 -407.386028) (xy 391.121322 -407.3855) (xy 391.06738 -407.37774) (xy 391.015092 -407.362383)
			(xy 390.965521 -407.339742) (xy 390.919677 -407.310276) (xy 390.878492 -407.274586) (xy 390.842806 -407.233399)
			(xy 390.813344 -407.187553) (xy 390.790706 -407.13798) (xy 390.775353 -407.085691) (xy 390.767598 -407.031748)
			(xy 389.329942 -407.031748) (xy 389.329942 -407.031751) (xy 389.322186 -407.085699) (xy 389.306832 -407.137994)
			(xy 389.284192 -407.187572) (xy 389.254727 -407.233424) (xy 389.219036 -407.274615) (xy 389.177848 -407.310309)
			(xy 389.131999 -407.339777) (xy 389.082422 -407.362421) (xy 389.030129 -407.37778) (xy 388.976181 -407.38554)
			(xy 388.94893 -407.386028) (xy 388.08533 -407.386028) (xy 388.058077 -407.385527) (xy 388.004126 -407.377774)
			(xy 387.951827 -407.362421) (xy 387.902246 -407.339781) (xy 387.856391 -407.310316) (xy 387.815197 -407.274624)
			(xy 387.779502 -407.233433) (xy 387.750033 -407.187581) (xy 387.727389 -407.138001) (xy 387.712033 -407.085704)
			(xy 387.704275 -407.031753) (xy 386.266765 -407.031753) (xy 386.266765 -407.031755) (xy 386.259007 -407.085709)
			(xy 386.24365 -407.138011) (xy 386.221006 -407.187594) (xy 386.191535 -407.23345) (xy 386.155838 -407.274646)
			(xy 386.114642 -407.310341) (xy 386.068786 -407.33981) (xy 386.019202 -407.362454) (xy 385.9669 -407.37781)
			(xy 385.912945 -407.385566) (xy 385.88569 -407.386028) (xy 385.02209 -407.386028) (xy 384.994841 -407.385501)
			(xy 384.940897 -407.377744) (xy 384.888606 -407.362389) (xy 384.839033 -407.339748) (xy 384.793186 -407.310283)
			(xy 384.751999 -407.274594) (xy 384.716311 -407.233406) (xy 384.686847 -407.187558) (xy 384.664208 -407.137984)
			(xy 384.648854 -407.085693) (xy 384.641098 -407.031749) (xy 383.203565 -407.031749) (xy 383.203565 -407.031757)
			(xy 383.195806 -407.085715) (xy 383.180447 -407.138019) (xy 383.1578 -407.187606) (xy 383.128325 -407.233464)
			(xy 383.092624 -407.27466) (xy 383.051423 -407.310355) (xy 383.005562 -407.339824) (xy 382.955973 -407.362464)
			(xy 382.903666 -407.377817) (xy 382.849707 -407.385569) (xy 382.82245 -407.386028) (xy 381.95885 -407.386028)
			(xy 381.931603 -407.385498) (xy 381.877663 -407.377736) (xy 381.825377 -407.362378) (xy 381.775809 -407.339735)
			(xy 381.729967 -407.310269) (xy 381.688785 -407.274579) (xy 381.653101 -407.233393) (xy 381.623641 -407.187547)
			(xy 381.601005 -407.137976) (xy 381.585653 -407.085688) (xy 381.577898 -407.031748) (xy 380.140242 -407.031748)
			(xy 380.140242 -407.031752) (xy 380.132486 -407.085702) (xy 380.11713 -407.137999) (xy 380.094489 -407.187578)
			(xy 380.065022 -407.23343) (xy 380.029329 -407.274622) (xy 379.988138 -407.310316) (xy 379.942287 -407.339784)
			(xy 379.892708 -407.362427) (xy 379.840412 -407.377783) (xy 379.786462 -407.385541) (xy 379.75921 -407.386028)
			(xy 378.89561 -407.386028) (xy 378.868358 -407.385525) (xy 378.814409 -407.37777) (xy 378.762113 -407.362416)
			(xy 378.712534 -407.339775) (xy 378.666682 -407.310309) (xy 378.62549 -407.274617) (xy 378.589797 -407.233426)
			(xy 378.56033 -407.187575) (xy 378.537688 -407.137997) (xy 378.522332 -407.085701) (xy 378.514575 -407.031752)
			(xy 377.077065 -407.031752) (xy 377.077065 -407.031756) (xy 377.069307 -407.085712) (xy 377.053948 -407.138015)
			(xy 377.031303 -407.1876) (xy 377.00183 -407.233457) (xy 376.966131 -407.274653) (xy 376.924933 -407.310348)
			(xy 376.879074 -407.339817) (xy 376.829487 -407.362459) (xy 376.777183 -407.377813) (xy 376.723226 -407.385567)
			(xy 376.69597 -407.386028) (xy 375.83237 -407.386028) (xy 375.805122 -407.3855) (xy 375.75118 -407.37774)
			(xy 375.698892 -407.362383) (xy 375.649321 -407.339742) (xy 375.603477 -407.310276) (xy 375.562292 -407.274586)
			(xy 375.526606 -407.233399) (xy 375.497144 -407.187553) (xy 375.474506 -407.13798) (xy 375.459153 -407.085691)
			(xy 375.451398 -407.031748) (xy 374.013742 -407.031748) (xy 374.013742 -407.031751) (xy 374.005986 -407.085699)
			(xy 373.990632 -407.137994) (xy 373.967992 -407.187572) (xy 373.938527 -407.233424) (xy 373.902836 -407.274615)
			(xy 373.861648 -407.310309) (xy 373.815799 -407.339777) (xy 373.766222 -407.362421) (xy 373.713929 -407.37778)
			(xy 373.659981 -407.38554) (xy 373.63273 -407.386028) (xy 372.76913 -407.386028) (xy 372.741877 -407.385527)
			(xy 372.687926 -407.377774) (xy 372.635627 -407.362421) (xy 372.586046 -407.339781) (xy 372.540191 -407.310316)
			(xy 372.498997 -407.274624) (xy 372.463302 -407.233433) (xy 372.433833 -407.187581) (xy 372.411189 -407.138001)
			(xy 372.395833 -407.085704) (xy 372.388075 -407.031753) (xy 352.519565 -407.031753) (xy 352.519565 -407.031755)
			(xy 352.511807 -407.08571) (xy 352.49645 -407.138011) (xy 352.473805 -407.187595) (xy 352.444335 -407.233451)
			(xy 352.408638 -407.274646) (xy 352.367441 -407.310342) (xy 352.321584 -407.339811) (xy 352.272 -407.362454)
			(xy 352.219698 -407.37781) (xy 352.165743 -407.385566) (xy 352.138488 -407.386028) (xy 351.274888 -407.386028)
			(xy 351.247639 -407.385501) (xy 351.193695 -407.377743) (xy 351.141405 -407.362388) (xy 351.091832 -407.339748)
			(xy 351.045985 -407.310282) (xy 351.004799 -407.274593) (xy 350.96911 -407.233405) (xy 350.939647 -407.187558)
			(xy 350.917008 -407.137984) (xy 350.901654 -407.085693) (xy 350.893898 -407.031749) (xy 349.456242 -407.031749)
			(xy 349.456242 -407.03175) (xy 349.448487 -407.085697) (xy 349.433133 -407.137991) (xy 349.410494 -407.187567)
			(xy 349.381031 -407.233418) (xy 349.345343 -407.274609) (xy 349.304156 -407.310302) (xy 349.258309 -407.339771)
			(xy 349.208736 -407.362416) (xy 349.156444 -407.377776) (xy 349.102498 -407.385539) (xy 349.075248 -407.386028)
			(xy 348.211648 -407.386028) (xy 348.184394 -407.385528) (xy 348.130441 -407.377777) (xy 348.07814 -407.362426)
			(xy 348.028557 -407.339787) (xy 347.9827 -407.310322) (xy 347.941504 -407.27463) (xy 347.905807 -407.233439)
			(xy 347.876336 -407.187586) (xy 347.853691 -407.138005) (xy 347.838333 -407.085706) (xy 347.830575 -407.031754)
			(xy 346.393042 -407.031754) (xy 346.385285 -407.085702) (xy 346.36993 -407.137999) (xy 346.347288 -407.187578)
			(xy 346.317821 -407.233431) (xy 346.282129 -407.274623) (xy 346.240937 -407.310316) (xy 346.195085 -407.339784)
			(xy 346.145507 -407.362427) (xy 346.09321 -407.377784) (xy 346.03926 -407.385542) (xy 346.012008 -407.386028)
			(xy 345.148408 -407.386028) (xy 345.121156 -407.385525) (xy 345.067207 -407.37777) (xy 345.014911 -407.362415)
			(xy 344.965333 -407.339774) (xy 344.919481 -407.310308) (xy 344.878289 -407.274616) (xy 344.842597 -407.233425)
			(xy 344.81313 -407.187574) (xy 344.790488 -407.137996) (xy 344.775132 -407.085701) (xy 344.767375 -407.031752)
			(xy 343.329865 -407.031752) (xy 343.329865 -407.031756) (xy 343.322107 -407.085712) (xy 343.306748 -407.138016)
			(xy 343.284102 -407.187601) (xy 343.25463 -407.233458) (xy 343.218931 -407.274653) (xy 343.177732 -407.310349)
			(xy 343.131872 -407.339818) (xy 343.082286 -407.36246) (xy 343.029981 -407.377814) (xy 342.976024 -407.385567)
			(xy 342.948768 -407.386028) (xy 342.085168 -407.386028) (xy 342.05792 -407.3855) (xy 342.003978 -407.37774)
			(xy 341.95169 -407.362383) (xy 341.90212 -407.339741) (xy 341.856276 -407.310275) (xy 341.815092 -407.274586)
			(xy 341.779405 -407.233399) (xy 341.749944 -407.187552) (xy 341.727306 -407.13798) (xy 341.711953 -407.08569)
			(xy 341.704198 -407.031748) (xy 340.266542 -407.031748) (xy 340.266542 -407.031751) (xy 340.258786 -407.0857)
			(xy 340.243432 -407.137995) (xy 340.220791 -407.187573) (xy 340.191326 -407.233424) (xy 340.155636 -407.274616)
			(xy 340.114447 -407.310309) (xy 340.068597 -407.339778) (xy 340.019021 -407.362422) (xy 339.966727 -407.37778)
			(xy 339.912779 -407.38554) (xy 339.885528 -407.386028) (xy 339.021928 -407.386028) (xy 338.994675 -407.385527)
			(xy 338.940724 -407.377773) (xy 338.888426 -407.36242) (xy 338.838845 -407.339781) (xy 338.79299 -407.310315)
			(xy 338.751797 -407.274623) (xy 338.716102 -407.233432) (xy 338.686633 -407.18758) (xy 338.663989 -407.138001)
			(xy 338.648633 -407.085703) (xy 338.640875 -407.031753) (xy 337.203365 -407.031753) (xy 337.203365 -407.031755)
			(xy 337.195607 -407.08571) (xy 337.18025 -407.138011) (xy 337.157605 -407.187595) (xy 337.128135 -407.233451)
			(xy 337.092438 -407.274646) (xy 337.051241 -407.310342) (xy 337.005384 -407.339811) (xy 336.9558 -407.362454)
			(xy 336.903498 -407.37781) (xy 336.849543 -407.385566) (xy 336.822288 -407.386028) (xy 335.958688 -407.386028)
			(xy 335.931439 -407.385501) (xy 335.877495 -407.377743) (xy 335.825205 -407.362388) (xy 335.775632 -407.339748)
			(xy 335.729785 -407.310282) (xy 335.688599 -407.274593) (xy 335.65291 -407.233405) (xy 335.623447 -407.187558)
			(xy 335.600808 -407.137984) (xy 335.585454 -407.085693) (xy 335.577698 -407.031749) (xy 334.140042 -407.031749)
			(xy 334.140042 -407.03175) (xy 334.132287 -407.085697) (xy 334.116933 -407.137991) (xy 334.094294 -407.187567)
			(xy 334.064831 -407.233418) (xy 334.029143 -407.274609) (xy 333.987956 -407.310302) (xy 333.942109 -407.339771)
			(xy 333.892536 -407.362416) (xy 333.840244 -407.377776) (xy 333.786298 -407.385539) (xy 333.759048 -407.386028)
			(xy 332.895448 -407.386028) (xy 332.868194 -407.385528) (xy 332.814241 -407.377777) (xy 332.76194 -407.362426)
			(xy 332.712357 -407.339787) (xy 332.6665 -407.310322) (xy 332.625304 -407.27463) (xy 332.589607 -407.233439)
			(xy 332.560136 -407.187586) (xy 332.537491 -407.138005) (xy 332.522133 -407.085706) (xy 332.514375 -407.031754)
			(xy 331.076842 -407.031754) (xy 331.069085 -407.085702) (xy 331.05373 -407.137999) (xy 331.031088 -407.187578)
			(xy 331.001621 -407.233431) (xy 330.965929 -407.274623) (xy 330.924737 -407.310316) (xy 330.878885 -407.339784)
			(xy 330.829307 -407.362427) (xy 330.77701 -407.377784) (xy 330.72306 -407.385542) (xy 330.695808 -407.386028)
			(xy 329.832208 -407.386028) (xy 329.804956 -407.385525) (xy 329.751007 -407.37777) (xy 329.698711 -407.362415)
			(xy 329.649133 -407.339774) (xy 329.603281 -407.310308) (xy 329.562089 -407.274616) (xy 329.526397 -407.233425)
			(xy 329.49693 -407.187574) (xy 329.474288 -407.137996) (xy 329.458932 -407.085701) (xy 329.451175 -407.031752)
			(xy 328.013665 -407.031752) (xy 328.013665 -407.031756) (xy 328.005907 -407.085712) (xy 327.990548 -407.138016)
			(xy 327.967902 -407.187601) (xy 327.93843 -407.233458) (xy 327.902731 -407.274653) (xy 327.861532 -407.310349)
			(xy 327.815672 -407.339818) (xy 327.766086 -407.36246) (xy 327.713781 -407.377814) (xy 327.659824 -407.385567)
			(xy 327.632568 -407.386028) (xy 326.768968 -407.386028) (xy 326.74172 -407.3855) (xy 326.687778 -407.37774)
			(xy 326.63549 -407.362383) (xy 326.58592 -407.339741) (xy 326.540076 -407.310275) (xy 326.498892 -407.274586)
			(xy 326.463205 -407.233399) (xy 326.433744 -407.187552) (xy 326.411106 -407.13798) (xy 326.395753 -407.08569)
			(xy 326.387998 -407.031748) (xy 324.950342 -407.031748) (xy 324.950342 -407.031751) (xy 324.942586 -407.0857)
			(xy 324.927232 -407.137995) (xy 324.904591 -407.187573) (xy 324.875126 -407.233424) (xy 324.839436 -407.274616)
			(xy 324.798247 -407.310309) (xy 324.752397 -407.339778) (xy 324.702821 -407.362422) (xy 324.650527 -407.37778)
			(xy 324.596579 -407.38554) (xy 324.569328 -407.386028) (xy 323.705728 -407.386028) (xy 323.678475 -407.385527)
			(xy 323.624524 -407.377773) (xy 323.572226 -407.36242) (xy 323.522645 -407.339781) (xy 323.47679 -407.310315)
			(xy 323.435597 -407.274623) (xy 323.399902 -407.233432) (xy 323.370433 -407.18758) (xy 323.347789 -407.138001)
			(xy 323.332433 -407.085703) (xy 323.324675 -407.031753) (xy 321.887165 -407.031753) (xy 321.887165 -407.031755)
			(xy 321.879407 -407.08571) (xy 321.86405 -407.138011) (xy 321.841405 -407.187595) (xy 321.811935 -407.233451)
			(xy 321.776238 -407.274646) (xy 321.735041 -407.310342) (xy 321.689184 -407.339811) (xy 321.6396 -407.362454)
			(xy 321.587298 -407.37781) (xy 321.533343 -407.385566) (xy 321.506088 -407.386028) (xy 320.642488 -407.386028)
			(xy 320.615239 -407.385501) (xy 320.561295 -407.377743) (xy 320.509005 -407.362388) (xy 320.459432 -407.339748)
			(xy 320.413585 -407.310282) (xy 320.372399 -407.274593) (xy 320.33671 -407.233405) (xy 320.307247 -407.187558)
			(xy 320.284608 -407.137984) (xy 320.269254 -407.085693) (xy 320.261498 -407.031749) (xy 318.823842 -407.031749)
			(xy 318.823842 -407.03175) (xy 318.816087 -407.085697) (xy 318.800733 -407.137991) (xy 318.778094 -407.187567)
			(xy 318.748631 -407.233418) (xy 318.712943 -407.274609) (xy 318.671756 -407.310302) (xy 318.625909 -407.339771)
			(xy 318.576336 -407.362416) (xy 318.524044 -407.377776) (xy 318.470098 -407.385539) (xy 318.442848 -407.386028)
			(xy 317.579248 -407.386028) (xy 317.551994 -407.385528) (xy 317.498041 -407.377777) (xy 317.44574 -407.362426)
			(xy 317.396157 -407.339787) (xy 317.3503 -407.310322) (xy 317.309104 -407.27463) (xy 317.273407 -407.233439)
			(xy 317.243936 -407.187586) (xy 317.221291 -407.138005) (xy 317.205933 -407.085706) (xy 317.198175 -407.031754)
			(xy 315.760642 -407.031754) (xy 315.752885 -407.085702) (xy 315.73753 -407.137999) (xy 315.714888 -407.187578)
			(xy 315.685421 -407.233431) (xy 315.649729 -407.274623) (xy 315.608537 -407.310316) (xy 315.562685 -407.339784)
			(xy 315.513107 -407.362427) (xy 315.46081 -407.377784) (xy 315.40686 -407.385542) (xy 315.379608 -407.386028)
			(xy 314.516008 -407.386028) (xy 314.488756 -407.385525) (xy 314.434807 -407.37777) (xy 314.382511 -407.362415)
			(xy 314.332933 -407.339774) (xy 314.287081 -407.310308) (xy 314.245889 -407.274616) (xy 314.210197 -407.233425)
			(xy 314.18073 -407.187574) (xy 314.158088 -407.137996) (xy 314.142732 -407.085701) (xy 314.134975 -407.031752)
			(xy 312.697465 -407.031752) (xy 312.697465 -407.031756) (xy 312.689707 -407.085712) (xy 312.674348 -407.138016)
			(xy 312.651702 -407.187601) (xy 312.62223 -407.233458) (xy 312.586531 -407.274653) (xy 312.545332 -407.310349)
			(xy 312.499472 -407.339818) (xy 312.449886 -407.36246) (xy 312.397581 -407.377814) (xy 312.343624 -407.385567)
			(xy 312.316368 -407.386028) (xy 311.452768 -407.386028) (xy 311.42552 -407.3855) (xy 311.371578 -407.37774)
			(xy 311.31929 -407.362383) (xy 311.26972 -407.339741) (xy 311.223876 -407.310275) (xy 311.182692 -407.274586)
			(xy 311.147005 -407.233399) (xy 311.117544 -407.187552) (xy 311.094906 -407.13798) (xy 311.079553 -407.08569)
			(xy 311.071798 -407.031748) (xy 309.634142 -407.031748) (xy 309.634142 -407.031751) (xy 309.626386 -407.0857)
			(xy 309.611032 -407.137995) (xy 309.588391 -407.187573) (xy 309.558926 -407.233424) (xy 309.523236 -407.274616)
			(xy 309.482047 -407.310309) (xy 309.436197 -407.339778) (xy 309.386621 -407.362422) (xy 309.334327 -407.37778)
			(xy 309.280379 -407.38554) (xy 309.253128 -407.386028) (xy 308.389528 -407.386028) (xy 308.362275 -407.385527)
			(xy 308.308324 -407.377773) (xy 308.256026 -407.36242) (xy 308.206445 -407.339781) (xy 308.16059 -407.310315)
			(xy 308.119397 -407.274623) (xy 308.083702 -407.233432) (xy 308.054233 -407.18758) (xy 308.031589 -407.138001)
			(xy 308.016233 -407.085703) (xy 308.008475 -407.031753) (xy 306.570965 -407.031753) (xy 306.570965 -407.031755)
			(xy 306.563207 -407.08571) (xy 306.54785 -407.138011) (xy 306.525205 -407.187595) (xy 306.495735 -407.233451)
			(xy 306.460038 -407.274646) (xy 306.418841 -407.310342) (xy 306.372984 -407.339811) (xy 306.3234 -407.362454)
			(xy 306.271098 -407.37781) (xy 306.217143 -407.385566) (xy 306.189888 -407.386028) (xy 305.326288 -407.386028)
			(xy 305.299039 -407.385501) (xy 305.245095 -407.377743) (xy 305.192805 -407.362388) (xy 305.143232 -407.339748)
			(xy 305.097385 -407.310282) (xy 305.056199 -407.274593) (xy 305.02051 -407.233405) (xy 304.991047 -407.187558)
			(xy 304.968408 -407.137984) (xy 304.953054 -407.085693) (xy 304.945298 -407.031749) (xy 274.459335 -407.031749)
			(xy 274.369276 -407.121868) (xy 274.369276 -407.203148) (xy 274.602448 -407.43632) (xy 280.100532 -407.43632)
			(xy 280.125481 -407.436823) (xy 280.174763 -407.444637) (xy 280.222219 -407.460054) (xy 280.266685 -407.482694)
			(xy 280.307069 -407.512001) (xy 280.325068 -407.529284) (xy 280.739596 -407.943812) (xy 280.756896 -407.961798)
			(xy 280.786219 -408.002177) (xy 280.808865 -408.046645) (xy 280.824276 -408.094108) (xy 280.832075 -408.143397)
			(xy 280.83256 -408.168348) (xy 280.83256 -410.057453) (xy 304.945246 -410.057453) (xy 304.945246 -410.002947)
			(xy 304.953003 -409.948996) (xy 304.968358 -409.896698) (xy 304.991001 -409.847117) (xy 305.020468 -409.801263)
			(xy 305.056162 -409.76007) (xy 305.097354 -409.724375) (xy 305.143207 -409.694906) (xy 305.192786 -409.672263)
			(xy 305.245084 -409.656905) (xy 305.299035 -409.649147) (xy 305.326288 -409.64866) (xy 306.189888 -409.64866)
			(xy 306.217139 -409.649186) (xy 306.271087 -409.656941) (xy 306.323382 -409.672295) (xy 306.372959 -409.694935)
			(xy 306.41881 -409.7244) (xy 306.460001 -409.760091) (xy 306.495693 -409.80128) (xy 306.525159 -409.84713)
			(xy 306.547801 -409.896707) (xy 306.563156 -409.949001) (xy 306.570913 -410.002949) (xy 306.570913 -410.057451)
			(xy 306.570912 -410.057456) (xy 308.008423 -410.057456) (xy 308.008423 -410.002944) (xy 308.016181 -409.948986)
			(xy 308.03154 -409.896681) (xy 308.054187 -409.847095) (xy 308.08366 -409.801236) (xy 308.119359 -409.76004)
			(xy 308.160559 -409.724343) (xy 308.206419 -409.694873) (xy 308.256007 -409.67223) (xy 308.308313 -409.656875)
			(xy 308.362272 -409.649121) (xy 308.389528 -409.64866) (xy 309.253128 -409.64866) (xy 309.280376 -409.649212)
			(xy 309.334316 -409.656971) (xy 309.386603 -409.672327) (xy 309.436172 -409.694968) (xy 309.482015 -409.724433)
			(xy 309.523199 -409.760121) (xy 309.558884 -409.801307) (xy 309.588345 -409.847152) (xy 309.610982 -409.896724)
			(xy 309.626335 -409.949012) (xy 309.63409 -410.002952) (xy 309.63409 -410.057448) (xy 309.634089 -410.057452)
			(xy 311.071746 -410.057452) (xy 311.071746 -410.002948) (xy 311.079502 -409.948998) (xy 311.094857 -409.896702)
			(xy 311.117498 -409.847123) (xy 311.146963 -409.80127) (xy 311.182654 -409.760077) (xy 311.223844 -409.724383)
			(xy 311.269695 -409.694913) (xy 311.319272 -409.672268) (xy 311.371567 -409.656909) (xy 311.425516 -409.649148)
			(xy 311.452768 -409.64866) (xy 312.316368 -409.64866) (xy 312.34362 -409.649185) (xy 312.39757 -409.656938)
			(xy 312.449867 -409.67229) (xy 312.499447 -409.694928) (xy 312.545301 -409.724393) (xy 312.586494 -409.760084)
			(xy 312.622188 -409.801274) (xy 312.651656 -409.847125) (xy 312.674299 -409.896703) (xy 312.689655 -409.948999)
			(xy 312.697413 -410.002948) (xy 312.697413 -410.057452) (xy 312.697412 -410.057456) (xy 314.134923 -410.057456)
			(xy 314.134923 -410.002944) (xy 314.142681 -409.948988) (xy 314.158039 -409.896685) (xy 314.180684 -409.8471)
			(xy 314.210155 -409.801243) (xy 314.245852 -409.760047) (xy 314.287049 -409.72435) (xy 314.332907 -409.69488)
			(xy 314.382493 -409.672236) (xy 314.434796 -409.656879) (xy 314.488752 -409.649122) (xy 314.516008 -409.64866)
			(xy 315.379608 -409.64866) (xy 315.406857 -409.649211) (xy 315.460799 -409.656968) (xy 315.513088 -409.672322)
			(xy 315.56266 -409.694962) (xy 315.608506 -409.724426) (xy 315.649691 -409.760114) (xy 315.685379 -409.801301)
			(xy 315.714842 -409.847147) (xy 315.737481 -409.896719) (xy 315.752834 -409.949009) (xy 315.76059 -410.002951)
			(xy 315.76059 -410.057449) (xy 315.760589 -410.057457) (xy 317.198123 -410.057457) (xy 317.198123 -410.002943)
			(xy 317.205882 -409.948983) (xy 317.221242 -409.896677) (xy 317.24389 -409.847089) (xy 317.273365 -409.80123)
			(xy 317.309066 -409.760033) (xy 317.350268 -409.724336) (xy 317.396131 -409.694867) (xy 317.445722 -409.672225)
			(xy 317.49803 -409.656872) (xy 317.551991 -409.64912) (xy 317.579248 -409.64866) (xy 318.442848 -409.64866)
			(xy 318.470095 -409.649213) (xy 318.524033 -409.656975) (xy 318.576317 -409.672333) (xy 318.625884 -409.694975)
			(xy 318.671725 -409.72444) (xy 318.712906 -409.760128) (xy 318.748589 -409.801314) (xy 318.778048 -409.847158)
			(xy 318.800684 -409.896728) (xy 318.816035 -409.949014) (xy 318.82379 -410.002953) (xy 318.82379 -410.057447)
			(xy 318.823789 -410.057453) (xy 320.261446 -410.057453) (xy 320.261446 -410.002947) (xy 320.269203 -409.948996)
			(xy 320.284558 -409.896698) (xy 320.307201 -409.847117) (xy 320.336668 -409.801263) (xy 320.372362 -409.76007)
			(xy 320.413554 -409.724375) (xy 320.459407 -409.694906) (xy 320.508986 -409.672263) (xy 320.561284 -409.656905)
			(xy 320.615235 -409.649147) (xy 320.642488 -409.64866) (xy 321.506088 -409.64866) (xy 321.533339 -409.649186)
			(xy 321.587287 -409.656941) (xy 321.639582 -409.672295) (xy 321.689159 -409.694935) (xy 321.73501 -409.7244)
			(xy 321.776201 -409.760091) (xy 321.811893 -409.80128) (xy 321.841359 -409.84713) (xy 321.864001 -409.896707)
			(xy 321.879356 -409.949001) (xy 321.887113 -410.002949) (xy 321.887113 -410.057451) (xy 321.887112 -410.057456)
			(xy 323.324623 -410.057456) (xy 323.324623 -410.002944) (xy 323.332381 -409.948986) (xy 323.34774 -409.896681)
			(xy 323.370387 -409.847095) (xy 323.39986 -409.801236) (xy 323.435559 -409.76004) (xy 323.476759 -409.724343)
			(xy 323.522619 -409.694873) (xy 323.572207 -409.67223) (xy 323.624513 -409.656875) (xy 323.678472 -409.649121)
			(xy 323.705728 -409.64866) (xy 324.569328 -409.64866) (xy 324.596576 -409.649212) (xy 324.650516 -409.656971)
			(xy 324.702803 -409.672327) (xy 324.752372 -409.694968) (xy 324.798215 -409.724433) (xy 324.839399 -409.760121)
			(xy 324.875084 -409.801307) (xy 324.904545 -409.847152) (xy 324.927182 -409.896724) (xy 324.942535 -409.949012)
			(xy 324.95029 -410.002952) (xy 324.95029 -410.057448) (xy 324.950289 -410.057452) (xy 326.387946 -410.057452)
			(xy 326.387946 -410.002948) (xy 326.395702 -409.948998) (xy 326.411057 -409.896702) (xy 326.433698 -409.847123)
			(xy 326.463163 -409.80127) (xy 326.498854 -409.760077) (xy 326.540044 -409.724383) (xy 326.585895 -409.694913)
			(xy 326.635472 -409.672268) (xy 326.687767 -409.656909) (xy 326.741716 -409.649148) (xy 326.768968 -409.64866)
			(xy 327.632568 -409.64866) (xy 327.65982 -409.649185) (xy 327.71377 -409.656938) (xy 327.766067 -409.67229)
			(xy 327.815647 -409.694928) (xy 327.861501 -409.724393) (xy 327.902694 -409.760084) (xy 327.938388 -409.801274)
			(xy 327.967856 -409.847125) (xy 327.990499 -409.896703) (xy 328.005855 -409.948999) (xy 328.013613 -410.002948)
			(xy 328.013613 -410.057452) (xy 328.013612 -410.057456) (xy 329.451123 -410.057456) (xy 329.451123 -410.002944)
			(xy 329.458881 -409.948988) (xy 329.474239 -409.896685) (xy 329.496884 -409.8471) (xy 329.526355 -409.801243)
			(xy 329.562052 -409.760047) (xy 329.603249 -409.72435) (xy 329.649107 -409.69488) (xy 329.698693 -409.672236)
			(xy 329.750996 -409.656879) (xy 329.804952 -409.649122) (xy 329.832208 -409.64866) (xy 330.695808 -409.64866)
			(xy 330.723057 -409.649211) (xy 330.776999 -409.656968) (xy 330.829288 -409.672322) (xy 330.87886 -409.694962)
			(xy 330.924706 -409.724426) (xy 330.965891 -409.760114) (xy 331.001579 -409.801301) (xy 331.031042 -409.847147)
			(xy 331.053681 -409.896719) (xy 331.069034 -409.949009) (xy 331.07679 -410.002951) (xy 331.07679 -410.057449)
			(xy 331.076789 -410.057457) (xy 332.514323 -410.057457) (xy 332.514323 -410.002943) (xy 332.522082 -409.948983)
			(xy 332.537442 -409.896677) (xy 332.56009 -409.847089) (xy 332.589565 -409.80123) (xy 332.625266 -409.760033)
			(xy 332.666468 -409.724336) (xy 332.712331 -409.694867) (xy 332.761922 -409.672225) (xy 332.81423 -409.656872)
			(xy 332.868191 -409.64912) (xy 332.895448 -409.64866) (xy 333.759048 -409.64866) (xy 333.786295 -409.649213)
			(xy 333.840233 -409.656975) (xy 333.892517 -409.672333) (xy 333.942084 -409.694975) (xy 333.987925 -409.72444)
			(xy 334.029106 -409.760128) (xy 334.064789 -409.801314) (xy 334.094248 -409.847158) (xy 334.116884 -409.896728)
			(xy 334.132235 -409.949014) (xy 334.13999 -410.002953) (xy 334.13999 -410.057447) (xy 334.139989 -410.057453)
			(xy 335.577646 -410.057453) (xy 335.577646 -410.002947) (xy 335.585403 -409.948996) (xy 335.600758 -409.896698)
			(xy 335.623401 -409.847117) (xy 335.652868 -409.801263) (xy 335.688562 -409.76007) (xy 335.729754 -409.724375)
			(xy 335.775607 -409.694906) (xy 335.825186 -409.672263) (xy 335.877484 -409.656905) (xy 335.931435 -409.649147)
			(xy 335.958688 -409.64866) (xy 336.822288 -409.64866) (xy 336.849539 -409.649186) (xy 336.903487 -409.656941)
			(xy 336.955782 -409.672295) (xy 337.005359 -409.694935) (xy 337.05121 -409.7244) (xy 337.092401 -409.760091)
			(xy 337.128093 -409.80128) (xy 337.157559 -409.84713) (xy 337.180201 -409.896707) (xy 337.195556 -409.949001)
			(xy 337.203313 -410.002949) (xy 337.203313 -410.057451) (xy 337.203312 -410.057456) (xy 338.640823 -410.057456)
			(xy 338.640823 -410.002944) (xy 338.648581 -409.948986) (xy 338.66394 -409.896681) (xy 338.686587 -409.847095)
			(xy 338.71606 -409.801236) (xy 338.751759 -409.76004) (xy 338.792959 -409.724343) (xy 338.838819 -409.694873)
			(xy 338.888407 -409.67223) (xy 338.940713 -409.656875) (xy 338.994672 -409.649121) (xy 339.021928 -409.64866)
			(xy 339.885528 -409.64866) (xy 339.912776 -409.649212) (xy 339.966716 -409.656971) (xy 340.019003 -409.672327)
			(xy 340.068572 -409.694968) (xy 340.114415 -409.724433) (xy 340.155599 -409.760121) (xy 340.191284 -409.801307)
			(xy 340.220745 -409.847152) (xy 340.243382 -409.896724) (xy 340.258735 -409.949012) (xy 340.26649 -410.002952)
			(xy 340.26649 -410.057448) (xy 340.266489 -410.057452) (xy 341.704146 -410.057452) (xy 341.704146 -410.002948)
			(xy 341.711902 -409.948998) (xy 341.727257 -409.896702) (xy 341.749898 -409.847123) (xy 341.779363 -409.80127)
			(xy 341.815054 -409.760077) (xy 341.856244 -409.724383) (xy 341.902095 -409.694913) (xy 341.951672 -409.672268)
			(xy 342.003967 -409.656909) (xy 342.057916 -409.649148) (xy 342.085168 -409.64866) (xy 342.948768 -409.64866)
			(xy 342.97602 -409.649185) (xy 343.02997 -409.656938) (xy 343.082267 -409.67229) (xy 343.131847 -409.694928)
			(xy 343.177701 -409.724393) (xy 343.218894 -409.760084) (xy 343.254588 -409.801274) (xy 343.284056 -409.847125)
			(xy 343.306699 -409.896703) (xy 343.322055 -409.948999) (xy 343.329813 -410.002948) (xy 343.329813 -410.057452)
			(xy 343.329812 -410.057456) (xy 344.767323 -410.057456) (xy 344.767323 -410.002944) (xy 344.775081 -409.948988)
			(xy 344.790439 -409.896685) (xy 344.813084 -409.8471) (xy 344.842555 -409.801243) (xy 344.878252 -409.760047)
			(xy 344.919449 -409.72435) (xy 344.965307 -409.69488) (xy 345.014893 -409.672236) (xy 345.067196 -409.656879)
			(xy 345.121152 -409.649122) (xy 345.148408 -409.64866) (xy 346.012008 -409.64866) (xy 346.039257 -409.649211)
			(xy 346.093199 -409.656968) (xy 346.145488 -409.672322) (xy 346.19506 -409.694962) (xy 346.240906 -409.724426)
			(xy 346.282091 -409.760114) (xy 346.317779 -409.801301) (xy 346.347242 -409.847147) (xy 346.369881 -409.896719)
			(xy 346.385234 -409.949009) (xy 346.39299 -410.002951) (xy 346.39299 -410.057449) (xy 346.392989 -410.057457)
			(xy 347.830523 -410.057457) (xy 347.830523 -410.002943) (xy 347.838282 -409.948983) (xy 347.853642 -409.896677)
			(xy 347.87629 -409.847089) (xy 347.905765 -409.80123) (xy 347.941466 -409.760033) (xy 347.982668 -409.724336)
			(xy 348.028531 -409.694867) (xy 348.078122 -409.672225) (xy 348.13043 -409.656872) (xy 348.184391 -409.64912)
			(xy 348.211648 -409.64866) (xy 349.075248 -409.64866) (xy 349.102495 -409.649213) (xy 349.156433 -409.656975)
			(xy 349.208717 -409.672333) (xy 349.258284 -409.694975) (xy 349.304125 -409.72444) (xy 349.345306 -409.760128)
			(xy 349.380989 -409.801314) (xy 349.410448 -409.847158) (xy 349.433084 -409.896728) (xy 349.448435 -409.949014)
			(xy 349.45619 -410.002953) (xy 349.45619 -410.057447) (xy 349.456189 -410.057453) (xy 350.893846 -410.057453)
			(xy 350.893846 -410.002947) (xy 350.901603 -409.948996) (xy 350.916958 -409.896698) (xy 350.939601 -409.847117)
			(xy 350.969068 -409.801263) (xy 351.004762 -409.76007) (xy 351.045954 -409.724375) (xy 351.091807 -409.694906)
			(xy 351.141386 -409.672263) (xy 351.193684 -409.656905) (xy 351.247635 -409.649147) (xy 351.274888 -409.64866)
			(xy 352.138488 -409.64866) (xy 352.165739 -409.649186) (xy 352.219687 -409.656941) (xy 352.271982 -409.672295)
			(xy 352.321559 -409.694935) (xy 352.36741 -409.7244) (xy 352.408601 -409.760091) (xy 352.444293 -409.80128)
			(xy 352.473759 -409.84713) (xy 352.496401 -409.896707) (xy 352.511756 -409.949001) (xy 352.519513 -410.002949)
			(xy 352.519513 -410.057451) (xy 352.519512 -410.057457) (xy 372.388023 -410.057457) (xy 372.388023 -410.002943)
			(xy 372.395781 -409.948985) (xy 372.41114 -409.896681) (xy 372.433787 -409.847094) (xy 372.46326 -409.801236)
			(xy 372.49896 -409.760039) (xy 372.54016 -409.724342) (xy 372.586021 -409.694872) (xy 372.635609 -409.67223)
			(xy 372.687915 -409.656875) (xy 372.741873 -409.649121) (xy 372.76913 -409.64866) (xy 373.63273 -409.64866)
			(xy 373.659978 -409.649212) (xy 373.713917 -409.656972) (xy 373.766204 -409.672328) (xy 373.815773 -409.694969)
			(xy 373.861616 -409.724434) (xy 373.902799 -409.760122) (xy 373.938484 -409.801308) (xy 373.967945 -409.847153)
			(xy 373.990583 -409.896724) (xy 374.005935 -409.949012) (xy 374.01369 -410.002952) (xy 374.01369 -410.057448)
			(xy 374.013689 -410.057452) (xy 375.451346 -410.057452) (xy 375.451346 -410.002948) (xy 375.459102 -409.948998)
			(xy 375.474457 -409.896701) (xy 375.497098 -409.847122) (xy 375.526564 -409.801269) (xy 375.562255 -409.760076)
			(xy 375.603445 -409.724382) (xy 375.649296 -409.694912) (xy 375.698873 -409.672268) (xy 375.751169 -409.656909)
			(xy 375.805118 -409.649148) (xy 375.83237 -409.64866) (xy 376.69597 -409.64866) (xy 376.723222 -409.649185)
			(xy 376.777172 -409.656938) (xy 376.829469 -409.67229) (xy 376.879048 -409.694929) (xy 376.924901 -409.724394)
			(xy 376.966094 -409.760084) (xy 377.001788 -409.801274) (xy 377.031257 -409.847125) (xy 377.053899 -409.896703)
			(xy 377.069256 -409.948999) (xy 377.077013 -410.002948) (xy 377.077013 -410.057452) (xy 377.077012 -410.057456)
			(xy 378.514523 -410.057456) (xy 378.514523 -410.002944) (xy 378.522281 -409.948988) (xy 378.537639 -409.896685)
			(xy 378.560284 -409.8471) (xy 378.589755 -409.801242) (xy 378.625453 -409.760046) (xy 378.66665 -409.724349)
			(xy 378.712509 -409.694879) (xy 378.762094 -409.672235) (xy 378.814398 -409.656879) (xy 378.868354 -409.649122)
			(xy 378.89561 -409.64866) (xy 379.75921 -409.64866) (xy 379.786458 -409.649211) (xy 379.840401 -409.656968)
			(xy 379.89269 -409.672323) (xy 379.942261 -409.694962) (xy 379.988107 -409.724426) (xy 380.029292 -409.760115)
			(xy 380.06498 -409.801301) (xy 380.094442 -409.847147) (xy 380.117081 -409.89672) (xy 380.132434 -409.949009)
			(xy 380.14019 -410.002952) (xy 380.14019 -410.057448) (xy 380.14019 -410.057451) (xy 381.577846 -410.057451)
			(xy 381.577846 -410.002949) (xy 381.585602 -409.949001) (xy 381.600955 -409.896706) (xy 381.623595 -409.847128)
			(xy 381.653059 -409.801276) (xy 381.688748 -409.760083) (xy 381.729936 -409.724389) (xy 381.775784 -409.694919)
			(xy 381.825359 -409.672273) (xy 381.877652 -409.656912) (xy 381.931599 -409.649149) (xy 381.95885 -409.64866)
			(xy 382.82245 -409.64866) (xy 382.849703 -409.649184) (xy 382.903655 -409.656934) (xy 382.955954 -409.672285)
			(xy 383.005536 -409.694923) (xy 383.051392 -409.724387) (xy 383.092587 -409.760077) (xy 383.128283 -409.801268)
			(xy 383.157753 -409.84712) (xy 383.180398 -409.896699) (xy 383.195755 -409.948996) (xy 383.203513 -410.002947)
			(xy 383.203513 -410.057453) (xy 384.641046 -410.057453) (xy 384.641046 -410.002947) (xy 384.648803 -409.948996)
			(xy 384.664159 -409.896697) (xy 384.686801 -409.847117) (xy 384.716269 -409.801263) (xy 384.751962 -409.760069)
			(xy 384.793155 -409.724375) (xy 384.839008 -409.694906) (xy 384.888588 -409.672262) (xy 384.940886 -409.656905)
			(xy 384.994837 -409.649147) (xy 385.02209 -409.64866) (xy 385.88569 -409.64866) (xy 385.912941 -409.649187)
			(xy 385.966889 -409.656942) (xy 386.019183 -409.672296) (xy 386.06876 -409.694936) (xy 386.114611 -409.724401)
			(xy 386.155801 -409.760092) (xy 386.191493 -409.801281) (xy 386.22096 -409.847131) (xy 386.243601 -409.896707)
			(xy 386.258956 -409.949002) (xy 386.266713 -410.002949) (xy 386.266713 -410.057451) (xy 386.266712 -410.057457)
			(xy 387.704223 -410.057457) (xy 387.704223 -410.002943) (xy 387.711981 -409.948985) (xy 387.72734 -409.896681)
			(xy 387.749987 -409.847094) (xy 387.77946 -409.801236) (xy 387.81516 -409.760039) (xy 387.85636 -409.724342)
			(xy 387.902221 -409.694872) (xy 387.951809 -409.67223) (xy 388.004115 -409.656875) (xy 388.058073 -409.649121)
			(xy 388.08533 -409.64866) (xy 388.94893 -409.64866) (xy 388.976178 -409.649212) (xy 389.030117 -409.656972)
			(xy 389.082404 -409.672328) (xy 389.131973 -409.694969) (xy 389.177816 -409.724434) (xy 389.218999 -409.760122)
			(xy 389.254684 -409.801308) (xy 389.284145 -409.847153) (xy 389.306783 -409.896724) (xy 389.322135 -409.949012)
			(xy 389.32989 -410.002952) (xy 389.32989 -410.057448) (xy 389.329889 -410.057452) (xy 390.767546 -410.057452)
			(xy 390.767546 -410.002948) (xy 390.775302 -409.948998) (xy 390.790657 -409.896701) (xy 390.813298 -409.847122)
			(xy 390.842764 -409.801269) (xy 390.878455 -409.760076) (xy 390.919645 -409.724382) (xy 390.965496 -409.694912)
			(xy 391.015073 -409.672268) (xy 391.067369 -409.656909) (xy 391.121318 -409.649148) (xy 391.14857 -409.64866)
			(xy 392.01217 -409.64866) (xy 392.039422 -409.649185) (xy 392.093372 -409.656938) (xy 392.145669 -409.67229)
			(xy 392.195248 -409.694929) (xy 392.241101 -409.724394) (xy 392.282294 -409.760084) (xy 392.317988 -409.801274)
			(xy 392.347457 -409.847125) (xy 392.370099 -409.896703) (xy 392.385456 -409.948999) (xy 392.393213 -410.002948)
			(xy 392.393213 -410.057452) (xy 392.393212 -410.057456) (xy 393.830723 -410.057456) (xy 393.830723 -410.002944)
			(xy 393.838481 -409.948988) (xy 393.853839 -409.896685) (xy 393.876484 -409.8471) (xy 393.905955 -409.801242)
			(xy 393.941653 -409.760046) (xy 393.98285 -409.724349) (xy 394.028709 -409.694879) (xy 394.078294 -409.672235)
			(xy 394.130598 -409.656879) (xy 394.184554 -409.649122) (xy 394.21181 -409.64866) (xy 395.07541 -409.64866)
			(xy 395.102658 -409.649211) (xy 395.156601 -409.656968) (xy 395.20889 -409.672323) (xy 395.258461 -409.694962)
			(xy 395.304307 -409.724426) (xy 395.345492 -409.760115) (xy 395.38118 -409.801301) (xy 395.410642 -409.847147)
			(xy 395.433281 -409.89672) (xy 395.448634 -409.949009) (xy 395.45639 -410.002952) (xy 395.45639 -410.057448)
			(xy 395.45639 -410.057451) (xy 396.894046 -410.057451) (xy 396.894046 -410.002949) (xy 396.901802 -409.949001)
			(xy 396.917155 -409.896706) (xy 396.939795 -409.847128) (xy 396.969259 -409.801276) (xy 397.004948 -409.760083)
			(xy 397.046136 -409.724389) (xy 397.091984 -409.694919) (xy 397.141559 -409.672273) (xy 397.193852 -409.656912)
			(xy 397.247799 -409.649149) (xy 397.27505 -409.64866) (xy 398.13865 -409.64866) (xy 398.165903 -409.649184)
			(xy 398.219855 -409.656934) (xy 398.272154 -409.672285) (xy 398.321736 -409.694923) (xy 398.367592 -409.724387)
			(xy 398.408787 -409.760077) (xy 398.444483 -409.801268) (xy 398.473953 -409.84712) (xy 398.496598 -409.896699)
			(xy 398.511955 -409.948996) (xy 398.519713 -410.002947) (xy 398.519713 -410.057453) (xy 399.957246 -410.057453)
			(xy 399.957246 -410.002947) (xy 399.965003 -409.948996) (xy 399.980359 -409.896697) (xy 400.003001 -409.847117)
			(xy 400.032469 -409.801263) (xy 400.068162 -409.760069) (xy 400.109355 -409.724375) (xy 400.155208 -409.694906)
			(xy 400.204788 -409.672262) (xy 400.257086 -409.656905) (xy 400.311037 -409.649147) (xy 400.33829 -409.64866)
			(xy 401.20189 -409.64866) (xy 401.229141 -409.649187) (xy 401.283089 -409.656942) (xy 401.335383 -409.672296)
			(xy 401.38496 -409.694936) (xy 401.430811 -409.724401) (xy 401.472001 -409.760092) (xy 401.507693 -409.801281)
			(xy 401.53716 -409.847131) (xy 401.559801 -409.896707) (xy 401.575156 -409.949002) (xy 401.582913 -410.002949)
			(xy 401.582913 -410.057451) (xy 401.582912 -410.057457) (xy 403.020423 -410.057457) (xy 403.020423 -410.002943)
			(xy 403.028181 -409.948985) (xy 403.04354 -409.896681) (xy 403.066187 -409.847094) (xy 403.09566 -409.801236)
			(xy 403.13136 -409.760039) (xy 403.17256 -409.724342) (xy 403.218421 -409.694872) (xy 403.268009 -409.67223)
			(xy 403.320315 -409.656875) (xy 403.374273 -409.649121) (xy 403.40153 -409.64866) (xy 404.26513 -409.64866)
			(xy 404.292378 -409.649212) (xy 404.346317 -409.656972) (xy 404.398604 -409.672328) (xy 404.448173 -409.694969)
			(xy 404.494016 -409.724434) (xy 404.535199 -409.760122) (xy 404.570884 -409.801308) (xy 404.600345 -409.847153)
			(xy 404.622983 -409.896724) (xy 404.638335 -409.949012) (xy 404.64609 -410.002952) (xy 404.64609 -410.057448)
			(xy 404.646089 -410.057452) (xy 406.083746 -410.057452) (xy 406.083746 -410.002948) (xy 406.091502 -409.948998)
			(xy 406.106857 -409.896701) (xy 406.129498 -409.847122) (xy 406.158964 -409.801269) (xy 406.194655 -409.760076)
			(xy 406.235845 -409.724382) (xy 406.281696 -409.694912) (xy 406.331273 -409.672268) (xy 406.383569 -409.656909)
			(xy 406.437518 -409.649148) (xy 406.46477 -409.64866) (xy 407.32837 -409.64866) (xy 407.355622 -409.649185)
			(xy 407.409572 -409.656938) (xy 407.461869 -409.67229) (xy 407.511448 -409.694929) (xy 407.557301 -409.724394)
			(xy 407.598494 -409.760084) (xy 407.634188 -409.801274) (xy 407.663657 -409.847125) (xy 407.686299 -409.896703)
			(xy 407.701656 -409.948999) (xy 407.709413 -410.002948) (xy 407.709413 -410.057452) (xy 407.709412 -410.057456)
			(xy 409.146923 -410.057456) (xy 409.146923 -410.002944) (xy 409.154681 -409.948988) (xy 409.170039 -409.896685)
			(xy 409.192684 -409.8471) (xy 409.222155 -409.801242) (xy 409.257853 -409.760046) (xy 409.29905 -409.724349)
			(xy 409.344909 -409.694879) (xy 409.394494 -409.672235) (xy 409.446798 -409.656879) (xy 409.500754 -409.649122)
			(xy 409.52801 -409.64866) (xy 410.39161 -409.64866) (xy 410.418858 -409.649211) (xy 410.472801 -409.656968)
			(xy 410.52509 -409.672323) (xy 410.574661 -409.694962) (xy 410.620507 -409.724426) (xy 410.661692 -409.760115)
			(xy 410.69738 -409.801301) (xy 410.726842 -409.847147) (xy 410.749481 -409.89672) (xy 410.764834 -409.949009)
			(xy 410.77259 -410.002952) (xy 410.77259 -410.057448) (xy 410.77259 -410.057451) (xy 412.210246 -410.057451)
			(xy 412.210246 -410.002949) (xy 412.218002 -409.949001) (xy 412.233355 -409.896706) (xy 412.255995 -409.847128)
			(xy 412.285459 -409.801276) (xy 412.321148 -409.760083) (xy 412.362336 -409.724389) (xy 412.408184 -409.694919)
			(xy 412.457759 -409.672273) (xy 412.510052 -409.656912) (xy 412.563999 -409.649149) (xy 412.59125 -409.64866)
			(xy 413.45485 -409.64866) (xy 413.482103 -409.649184) (xy 413.536055 -409.656934) (xy 413.588354 -409.672285)
			(xy 413.637936 -409.694923) (xy 413.683792 -409.724387) (xy 413.724987 -409.760077) (xy 413.760683 -409.801268)
			(xy 413.790153 -409.84712) (xy 413.812798 -409.896699) (xy 413.828155 -409.948996) (xy 413.835913 -410.002947)
			(xy 413.835913 -410.057453) (xy 415.273446 -410.057453) (xy 415.273446 -410.002947) (xy 415.281203 -409.948996)
			(xy 415.296559 -409.896697) (xy 415.319201 -409.847117) (xy 415.348669 -409.801263) (xy 415.384362 -409.760069)
			(xy 415.425555 -409.724375) (xy 415.471408 -409.694906) (xy 415.520988 -409.672262) (xy 415.573286 -409.656905)
			(xy 415.627237 -409.649147) (xy 415.65449 -409.64866) (xy 416.51809 -409.64866) (xy 416.545341 -409.649187)
			(xy 416.599289 -409.656942) (xy 416.651583 -409.672296) (xy 416.70116 -409.694936) (xy 416.747011 -409.724401)
			(xy 416.788201 -409.760092) (xy 416.823893 -409.801281) (xy 416.85336 -409.847131) (xy 416.876001 -409.896707)
			(xy 416.891356 -409.949002) (xy 416.899113 -410.002949) (xy 416.899113 -410.057451) (xy 416.899112 -410.057457)
			(xy 418.336623 -410.057457) (xy 418.336623 -410.002943) (xy 418.344381 -409.948985) (xy 418.35974 -409.896681)
			(xy 418.382387 -409.847094) (xy 418.41186 -409.801236) (xy 418.44756 -409.760039) (xy 418.48876 -409.724342)
			(xy 418.534621 -409.694872) (xy 418.584209 -409.67223) (xy 418.636515 -409.656875) (xy 418.690473 -409.649121)
			(xy 418.71773 -409.64866) (xy 419.58133 -409.64866) (xy 419.608578 -409.649212) (xy 419.662517 -409.656972)
			(xy 419.714804 -409.672328) (xy 419.764373 -409.694969) (xy 419.810216 -409.724434) (xy 419.851399 -409.760122)
			(xy 419.887084 -409.801308) (xy 419.916545 -409.847153) (xy 419.939183 -409.896724) (xy 419.954535 -409.949012)
			(xy 419.96229 -410.002952) (xy 419.96229 -410.057448) (xy 419.954535 -410.111388) (xy 419.939183 -410.163676)
			(xy 419.916545 -410.213247) (xy 419.887084 -410.259092) (xy 419.851399 -410.300278) (xy 419.810216 -410.335966)
			(xy 419.764373 -410.365431) (xy 419.714804 -410.388072) (xy 419.662517 -410.403428) (xy 419.608578 -410.411188)
			(xy 419.58133 -410.411676) (xy 418.71773 -410.411676) (xy 418.690473 -410.411279) (xy 418.636515 -410.403525)
			(xy 418.584209 -410.38817) (xy 418.534621 -410.365528) (xy 418.48876 -410.336058) (xy 418.44756 -410.300361)
			(xy 418.41186 -410.259164) (xy 418.382387 -410.213306) (xy 418.35974 -410.163719) (xy 418.344381 -410.111415)
			(xy 418.336623 -410.057457) (xy 416.899112 -410.057457) (xy 416.891356 -410.111398) (xy 416.876001 -410.163693)
			(xy 416.85336 -410.213269) (xy 416.823893 -410.259119) (xy 416.788201 -410.300308) (xy 416.747011 -410.335999)
			(xy 416.70116 -410.365464) (xy 416.651583 -410.388104) (xy 416.599289 -410.403458) (xy 416.545341 -410.411213)
			(xy 416.51809 -410.411676) (xy 415.65449 -410.411676) (xy 415.627237 -410.411253) (xy 415.573286 -410.403495)
			(xy 415.520988 -410.388138) (xy 415.471408 -410.365494) (xy 415.425555 -410.336025) (xy 415.384362 -410.300331)
			(xy 415.348669 -410.259137) (xy 415.319201 -410.213283) (xy 415.296559 -410.163703) (xy 415.281203 -410.111404)
			(xy 415.273446 -410.057453) (xy 413.835913 -410.057453) (xy 413.828155 -410.111404) (xy 413.812798 -410.163701)
			(xy 413.790153 -410.21328) (xy 413.760683 -410.259132) (xy 413.724987 -410.300323) (xy 413.683792 -410.336013)
			(xy 413.637936 -410.365477) (xy 413.588354 -410.388115) (xy 413.536055 -410.403466) (xy 413.482103 -410.411216)
			(xy 413.45485 -410.411676) (xy 412.59125 -410.411676) (xy 412.563999 -410.411251) (xy 412.510052 -410.403488)
			(xy 412.457759 -410.388127) (xy 412.408184 -410.365481) (xy 412.362336 -410.336011) (xy 412.321148 -410.300317)
			(xy 412.285459 -410.259124) (xy 412.255995 -410.213272) (xy 412.233355 -410.163694) (xy 412.218002 -410.111399)
			(xy 412.210246 -410.057451) (xy 410.77259 -410.057451) (xy 410.764834 -410.111391) (xy 410.749481 -410.16368)
			(xy 410.726842 -410.213253) (xy 410.69738 -410.259099) (xy 410.661692 -410.300285) (xy 410.620507 -410.335974)
			(xy 410.574661 -410.365438) (xy 410.52509 -410.388077) (xy 410.472801 -410.403432) (xy 410.418858 -410.411189)
			(xy 410.39161 -410.411676) (xy 409.52801 -410.411676) (xy 409.500754 -410.411278) (xy 409.446798 -410.403521)
			(xy 409.394494 -410.388165) (xy 409.344909 -410.365521) (xy 409.29905 -410.336051) (xy 409.257853 -410.300354)
			(xy 409.222155 -410.259158) (xy 409.192684 -410.2133) (xy 409.170039 -410.163715) (xy 409.154681 -410.111412)
			(xy 409.146923 -410.057456) (xy 407.709412 -410.057456) (xy 407.701656 -410.111401) (xy 407.686299 -410.163697)
			(xy 407.663657 -410.213275) (xy 407.634188 -410.259126) (xy 407.598494 -410.300316) (xy 407.557301 -410.336006)
			(xy 407.511448 -410.365471) (xy 407.461869 -410.38811) (xy 407.409572 -410.403462) (xy 407.355622 -410.411215)
			(xy 407.32837 -410.411676) (xy 406.46477 -410.411676) (xy 406.437518 -410.411252) (xy 406.383569 -410.403491)
			(xy 406.331273 -410.388132) (xy 406.281696 -410.365488) (xy 406.235845 -410.336018) (xy 406.194655 -410.300324)
			(xy 406.158964 -410.259131) (xy 406.129498 -410.213278) (xy 406.106857 -410.163699) (xy 406.091502 -410.111402)
			(xy 406.083746 -410.057452) (xy 404.646089 -410.057452) (xy 404.638335 -410.111388) (xy 404.622983 -410.163676)
			(xy 404.600345 -410.213247) (xy 404.570884 -410.259092) (xy 404.535199 -410.300278) (xy 404.494016 -410.335966)
			(xy 404.448173 -410.365431) (xy 404.398604 -410.388072) (xy 404.346317 -410.403428) (xy 404.292378 -410.411188)
			(xy 404.26513 -410.411676) (xy 403.40153 -410.411676) (xy 403.374273 -410.411279) (xy 403.320315 -410.403525)
			(xy 403.268009 -410.38817) (xy 403.218421 -410.365528) (xy 403.17256 -410.336058) (xy 403.13136 -410.300361)
			(xy 403.09566 -410.259164) (xy 403.066187 -410.213306) (xy 403.04354 -410.163719) (xy 403.028181 -410.111415)
			(xy 403.020423 -410.057457) (xy 401.582912 -410.057457) (xy 401.575156 -410.111398) (xy 401.559801 -410.163693)
			(xy 401.53716 -410.213269) (xy 401.507693 -410.259119) (xy 401.472001 -410.300308) (xy 401.430811 -410.335999)
			(xy 401.38496 -410.365464) (xy 401.335383 -410.388104) (xy 401.283089 -410.403458) (xy 401.229141 -410.411213)
			(xy 401.20189 -410.411676) (xy 400.33829 -410.411676) (xy 400.311037 -410.411253) (xy 400.257086 -410.403495)
			(xy 400.204788 -410.388138) (xy 400.155208 -410.365494) (xy 400.109355 -410.336025) (xy 400.068162 -410.300331)
			(xy 400.032469 -410.259137) (xy 400.003001 -410.213283) (xy 399.980359 -410.163703) (xy 399.965003 -410.111404)
			(xy 399.957246 -410.057453) (xy 398.519713 -410.057453) (xy 398.511955 -410.111404) (xy 398.496598 -410.163701)
			(xy 398.473953 -410.21328) (xy 398.444483 -410.259132) (xy 398.408787 -410.300323) (xy 398.367592 -410.336013)
			(xy 398.321736 -410.365477) (xy 398.272154 -410.388115) (xy 398.219855 -410.403466) (xy 398.165903 -410.411216)
			(xy 398.13865 -410.411676) (xy 397.27505 -410.411676) (xy 397.247799 -410.411251) (xy 397.193852 -410.403488)
			(xy 397.141559 -410.388127) (xy 397.091984 -410.365481) (xy 397.046136 -410.336011) (xy 397.004948 -410.300317)
			(xy 396.969259 -410.259124) (xy 396.939795 -410.213272) (xy 396.917155 -410.163694) (xy 396.901802 -410.111399)
			(xy 396.894046 -410.057451) (xy 395.45639 -410.057451) (xy 395.448634 -410.111391) (xy 395.433281 -410.16368)
			(xy 395.410642 -410.213253) (xy 395.38118 -410.259099) (xy 395.345492 -410.300285) (xy 395.304307 -410.335974)
			(xy 395.258461 -410.365438) (xy 395.20889 -410.388077) (xy 395.156601 -410.403432) (xy 395.102658 -410.411189)
			(xy 395.07541 -410.411676) (xy 394.21181 -410.411676) (xy 394.184554 -410.411278) (xy 394.130598 -410.403521)
			(xy 394.078294 -410.388165) (xy 394.028709 -410.365521) (xy 393.98285 -410.336051) (xy 393.941653 -410.300354)
			(xy 393.905955 -410.259158) (xy 393.876484 -410.2133) (xy 393.853839 -410.163715) (xy 393.838481 -410.111412)
			(xy 393.830723 -410.057456) (xy 392.393212 -410.057456) (xy 392.385456 -410.111401) (xy 392.370099 -410.163697)
			(xy 392.347457 -410.213275) (xy 392.317988 -410.259126) (xy 392.282294 -410.300316) (xy 392.241101 -410.336006)
			(xy 392.195248 -410.365471) (xy 392.145669 -410.38811) (xy 392.093372 -410.403462) (xy 392.039422 -410.411215)
			(xy 392.01217 -410.411676) (xy 391.14857 -410.411676) (xy 391.121318 -410.411252) (xy 391.067369 -410.403491)
			(xy 391.015073 -410.388132) (xy 390.965496 -410.365488) (xy 390.919645 -410.336018) (xy 390.878455 -410.300324)
			(xy 390.842764 -410.259131) (xy 390.813298 -410.213278) (xy 390.790657 -410.163699) (xy 390.775302 -410.111402)
			(xy 390.767546 -410.057452) (xy 389.329889 -410.057452) (xy 389.322135 -410.111388) (xy 389.306783 -410.163676)
			(xy 389.284145 -410.213247) (xy 389.254684 -410.259092) (xy 389.218999 -410.300278) (xy 389.177816 -410.335966)
			(xy 389.131973 -410.365431) (xy 389.082404 -410.388072) (xy 389.030117 -410.403428) (xy 388.976178 -410.411188)
			(xy 388.94893 -410.411676) (xy 388.08533 -410.411676) (xy 388.058073 -410.411279) (xy 388.004115 -410.403525)
			(xy 387.951809 -410.38817) (xy 387.902221 -410.365528) (xy 387.85636 -410.336058) (xy 387.81516 -410.300361)
			(xy 387.77946 -410.259164) (xy 387.749987 -410.213306) (xy 387.72734 -410.163719) (xy 387.711981 -410.111415)
			(xy 387.704223 -410.057457) (xy 386.266712 -410.057457) (xy 386.258956 -410.111398) (xy 386.243601 -410.163693)
			(xy 386.22096 -410.213269) (xy 386.191493 -410.259119) (xy 386.155801 -410.300308) (xy 386.114611 -410.335999)
			(xy 386.06876 -410.365464) (xy 386.019183 -410.388104) (xy 385.966889 -410.403458) (xy 385.912941 -410.411213)
			(xy 385.88569 -410.411676) (xy 385.02209 -410.411676) (xy 384.994837 -410.411253) (xy 384.940886 -410.403495)
			(xy 384.888588 -410.388138) (xy 384.839008 -410.365494) (xy 384.793155 -410.336025) (xy 384.751962 -410.300331)
			(xy 384.716269 -410.259137) (xy 384.686801 -410.213283) (xy 384.664159 -410.163703) (xy 384.648803 -410.111404)
			(xy 384.641046 -410.057453) (xy 383.203513 -410.057453) (xy 383.195755 -410.111404) (xy 383.180398 -410.163701)
			(xy 383.157753 -410.21328) (xy 383.128283 -410.259132) (xy 383.092587 -410.300323) (xy 383.051392 -410.336013)
			(xy 383.005536 -410.365477) (xy 382.955954 -410.388115) (xy 382.903655 -410.403466) (xy 382.849703 -410.411216)
			(xy 382.82245 -410.411676) (xy 381.95885 -410.411676) (xy 381.931599 -410.411251) (xy 381.877652 -410.403488)
			(xy 381.825359 -410.388127) (xy 381.775784 -410.365481) (xy 381.729936 -410.336011) (xy 381.688748 -410.300317)
			(xy 381.653059 -410.259124) (xy 381.623595 -410.213272) (xy 381.600955 -410.163694) (xy 381.585602 -410.111399)
			(xy 381.577846 -410.057451) (xy 380.14019 -410.057451) (xy 380.132434 -410.111391) (xy 380.117081 -410.16368)
			(xy 380.094442 -410.213253) (xy 380.06498 -410.259099) (xy 380.029292 -410.300285) (xy 379.988107 -410.335974)
			(xy 379.942261 -410.365438) (xy 379.89269 -410.388077) (xy 379.840401 -410.403432) (xy 379.786458 -410.411189)
			(xy 379.75921 -410.411676) (xy 378.89561 -410.411676) (xy 378.868354 -410.411278) (xy 378.814398 -410.403521)
			(xy 378.762094 -410.388165) (xy 378.712509 -410.365521) (xy 378.66665 -410.336051) (xy 378.625453 -410.300354)
			(xy 378.589755 -410.259158) (xy 378.560284 -410.2133) (xy 378.537639 -410.163715) (xy 378.522281 -410.111412)
			(xy 378.514523 -410.057456) (xy 377.077012 -410.057456) (xy 377.069256 -410.111401) (xy 377.053899 -410.163697)
			(xy 377.031257 -410.213275) (xy 377.001788 -410.259126) (xy 376.966094 -410.300316) (xy 376.924901 -410.336006)
			(xy 376.879048 -410.365471) (xy 376.829469 -410.38811) (xy 376.777172 -410.403462) (xy 376.723222 -410.411215)
			(xy 376.69597 -410.411676) (xy 375.83237 -410.411676) (xy 375.805118 -410.411252) (xy 375.751169 -410.403491)
			(xy 375.698873 -410.388132) (xy 375.649296 -410.365488) (xy 375.603445 -410.336018) (xy 375.562255 -410.300324)
			(xy 375.526564 -410.259131) (xy 375.497098 -410.213278) (xy 375.474457 -410.163699) (xy 375.459102 -410.111402)
			(xy 375.451346 -410.057452) (xy 374.013689 -410.057452) (xy 374.005935 -410.111388) (xy 373.990583 -410.163676)
			(xy 373.967945 -410.213247) (xy 373.938484 -410.259092) (xy 373.902799 -410.300278) (xy 373.861616 -410.335966)
			(xy 373.815773 -410.365431) (xy 373.766204 -410.388072) (xy 373.713917 -410.403428) (xy 373.659978 -410.411188)
			(xy 373.63273 -410.411676) (xy 372.76913 -410.411676) (xy 372.741873 -410.411279) (xy 372.687915 -410.403525)
			(xy 372.635609 -410.38817) (xy 372.586021 -410.365528) (xy 372.54016 -410.336058) (xy 372.49896 -410.300361)
			(xy 372.46326 -410.259164) (xy 372.433787 -410.213306) (xy 372.41114 -410.163719) (xy 372.395781 -410.111415)
			(xy 372.388023 -410.057457) (xy 352.519512 -410.057457) (xy 352.511756 -410.111399) (xy 352.496401 -410.163693)
			(xy 352.473759 -410.21327) (xy 352.444293 -410.25912) (xy 352.408601 -410.300309) (xy 352.36741 -410.336)
			(xy 352.321559 -410.365465) (xy 352.271982 -410.388105) (xy 352.219687 -410.403459) (xy 352.165739 -410.411214)
			(xy 352.138488 -410.411676) (xy 351.274888 -410.411676) (xy 351.247635 -410.411253) (xy 351.193684 -410.403495)
			(xy 351.141386 -410.388137) (xy 351.091807 -410.365494) (xy 351.045954 -410.336025) (xy 351.004762 -410.30033)
			(xy 350.969068 -410.259137) (xy 350.939601 -410.213283) (xy 350.916958 -410.163702) (xy 350.901603 -410.111404)
			(xy 350.893846 -410.057453) (xy 349.456189 -410.057453) (xy 349.448435 -410.111386) (xy 349.433084 -410.163672)
			(xy 349.410448 -410.213242) (xy 349.380989 -410.259086) (xy 349.345306 -410.300272) (xy 349.304125 -410.33596)
			(xy 349.258284 -410.365425) (xy 349.208717 -410.388067) (xy 349.156433 -410.403425) (xy 349.102495 -410.411187)
			(xy 349.075248 -410.411676) (xy 348.211648 -410.411676) (xy 348.184391 -410.41128) (xy 348.13043 -410.403528)
			(xy 348.078122 -410.388175) (xy 348.028531 -410.365533) (xy 347.982668 -410.336064) (xy 347.941466 -410.300367)
			(xy 347.905765 -410.25917) (xy 347.87629 -410.213311) (xy 347.853642 -410.163723) (xy 347.838282 -410.111417)
			(xy 347.830523 -410.057457) (xy 346.392989 -410.057457) (xy 346.385234 -410.111391) (xy 346.369881 -410.163681)
			(xy 346.347242 -410.213253) (xy 346.317779 -410.259099) (xy 346.282091 -410.300286) (xy 346.240906 -410.335974)
			(xy 346.19506 -410.365438) (xy 346.145488 -410.388078) (xy 346.093199 -410.403432) (xy 346.039257 -410.411189)
			(xy 346.012008 -410.411676) (xy 345.148408 -410.411676) (xy 345.121152 -410.411278) (xy 345.067196 -410.403521)
			(xy 345.014893 -410.388164) (xy 344.965307 -410.36552) (xy 344.919449 -410.33605) (xy 344.878252 -410.300353)
			(xy 344.842555 -410.259157) (xy 344.813084 -410.2133) (xy 344.790439 -410.163715) (xy 344.775081 -410.111412)
			(xy 344.767323 -410.057456) (xy 343.329812 -410.057456) (xy 343.322055 -410.111401) (xy 343.306699 -410.163697)
			(xy 343.284056 -410.213275) (xy 343.254588 -410.259126) (xy 343.218894 -410.300316) (xy 343.177701 -410.336007)
			(xy 343.131847 -410.365472) (xy 343.082267 -410.38811) (xy 343.02997 -410.403462) (xy 342.97602 -410.411215)
			(xy 342.948768 -410.411676) (xy 342.085168 -410.411676) (xy 342.057916 -410.411252) (xy 342.003967 -410.403491)
			(xy 341.951672 -410.388132) (xy 341.902095 -410.365487) (xy 341.856244 -410.336017) (xy 341.815054 -410.300323)
			(xy 341.779363 -410.25913) (xy 341.749898 -410.213277) (xy 341.727257 -410.163698) (xy 341.711902 -410.111402)
			(xy 341.704146 -410.057452) (xy 340.266489 -410.057452) (xy 340.258735 -410.111388) (xy 340.243382 -410.163676)
			(xy 340.220745 -410.213248) (xy 340.191284 -410.259093) (xy 340.155599 -410.300279) (xy 340.114415 -410.335967)
			(xy 340.068572 -410.365432) (xy 340.019003 -410.388073) (xy 339.966716 -410.403429) (xy 339.912776 -410.411188)
			(xy 339.885528 -410.411676) (xy 339.021928 -410.411676) (xy 338.994672 -410.411279) (xy 338.940713 -410.403525)
			(xy 338.888407 -410.38817) (xy 338.838819 -410.365527) (xy 338.792959 -410.336057) (xy 338.751759 -410.30036)
			(xy 338.71606 -410.259164) (xy 338.686587 -410.213305) (xy 338.66394 -410.163719) (xy 338.648581 -410.111414)
			(xy 338.640823 -410.057456) (xy 337.203312 -410.057456) (xy 337.195556 -410.111399) (xy 337.180201 -410.163693)
			(xy 337.157559 -410.21327) (xy 337.128093 -410.25912) (xy 337.092401 -410.300309) (xy 337.05121 -410.336)
			(xy 337.005359 -410.365465) (xy 336.955782 -410.388105) (xy 336.903487 -410.403459) (xy 336.849539 -410.411214)
			(xy 336.822288 -410.411676) (xy 335.958688 -410.411676) (xy 335.931435 -410.411253) (xy 335.877484 -410.403495)
			(xy 335.825186 -410.388137) (xy 335.775607 -410.365494) (xy 335.729754 -410.336025) (xy 335.688562 -410.30033)
			(xy 335.652868 -410.259137) (xy 335.623401 -410.213283) (xy 335.600758 -410.163702) (xy 335.585403 -410.111404)
			(xy 335.577646 -410.057453) (xy 334.139989 -410.057453) (xy 334.132235 -410.111386) (xy 334.116884 -410.163672)
			(xy 334.094248 -410.213242) (xy 334.064789 -410.259086) (xy 334.029106 -410.300272) (xy 333.987925 -410.33596)
			(xy 333.942084 -410.365425) (xy 333.892517 -410.388067) (xy 333.840233 -410.403425) (xy 333.786295 -410.411187)
			(xy 333.759048 -410.411676) (xy 332.895448 -410.411676) (xy 332.868191 -410.41128) (xy 332.81423 -410.403528)
			(xy 332.761922 -410.388175) (xy 332.712331 -410.365533) (xy 332.666468 -410.336064) (xy 332.625266 -410.300367)
			(xy 332.589565 -410.25917) (xy 332.56009 -410.213311) (xy 332.537442 -410.163723) (xy 332.522082 -410.111417)
			(xy 332.514323 -410.057457) (xy 331.076789 -410.057457) (xy 331.069034 -410.111391) (xy 331.053681 -410.163681)
			(xy 331.031042 -410.213253) (xy 331.001579 -410.259099) (xy 330.965891 -410.300286) (xy 330.924706 -410.335974)
			(xy 330.87886 -410.365438) (xy 330.829288 -410.388078) (xy 330.776999 -410.403432) (xy 330.723057 -410.411189)
			(xy 330.695808 -410.411676) (xy 329.832208 -410.411676) (xy 329.804952 -410.411278) (xy 329.750996 -410.403521)
			(xy 329.698693 -410.388164) (xy 329.649107 -410.36552) (xy 329.603249 -410.33605) (xy 329.562052 -410.300353)
			(xy 329.526355 -410.259157) (xy 329.496884 -410.2133) (xy 329.474239 -410.163715) (xy 329.458881 -410.111412)
			(xy 329.451123 -410.057456) (xy 328.013612 -410.057456) (xy 328.005855 -410.111401) (xy 327.990499 -410.163697)
			(xy 327.967856 -410.213275) (xy 327.938388 -410.259126) (xy 327.902694 -410.300316) (xy 327.861501 -410.336007)
			(xy 327.815647 -410.365472) (xy 327.766067 -410.38811) (xy 327.71377 -410.403462) (xy 327.65982 -410.411215)
			(xy 327.632568 -410.411676) (xy 326.768968 -410.411676) (xy 326.741716 -410.411252) (xy 326.687767 -410.403491)
			(xy 326.635472 -410.388132) (xy 326.585895 -410.365487) (xy 326.540044 -410.336017) (xy 326.498854 -410.300323)
			(xy 326.463163 -410.25913) (xy 326.433698 -410.213277) (xy 326.411057 -410.163698) (xy 326.395702 -410.111402)
			(xy 326.387946 -410.057452) (xy 324.950289 -410.057452) (xy 324.942535 -410.111388) (xy 324.927182 -410.163676)
			(xy 324.904545 -410.213248) (xy 324.875084 -410.259093) (xy 324.839399 -410.300279) (xy 324.798215 -410.335967)
			(xy 324.752372 -410.365432) (xy 324.702803 -410.388073) (xy 324.650516 -410.403429) (xy 324.596576 -410.411188)
			(xy 324.569328 -410.411676) (xy 323.705728 -410.411676) (xy 323.678472 -410.411279) (xy 323.624513 -410.403525)
			(xy 323.572207 -410.38817) (xy 323.522619 -410.365527) (xy 323.476759 -410.336057) (xy 323.435559 -410.30036)
			(xy 323.39986 -410.259164) (xy 323.370387 -410.213305) (xy 323.34774 -410.163719) (xy 323.332381 -410.111414)
			(xy 323.324623 -410.057456) (xy 321.887112 -410.057456) (xy 321.879356 -410.111399) (xy 321.864001 -410.163693)
			(xy 321.841359 -410.21327) (xy 321.811893 -410.25912) (xy 321.776201 -410.300309) (xy 321.73501 -410.336)
			(xy 321.689159 -410.365465) (xy 321.639582 -410.388105) (xy 321.587287 -410.403459) (xy 321.533339 -410.411214)
			(xy 321.506088 -410.411676) (xy 320.642488 -410.411676) (xy 320.615235 -410.411253) (xy 320.561284 -410.403495)
			(xy 320.508986 -410.388137) (xy 320.459407 -410.365494) (xy 320.413554 -410.336025) (xy 320.372362 -410.30033)
			(xy 320.336668 -410.259137) (xy 320.307201 -410.213283) (xy 320.284558 -410.163702) (xy 320.269203 -410.111404)
			(xy 320.261446 -410.057453) (xy 318.823789 -410.057453) (xy 318.816035 -410.111386) (xy 318.800684 -410.163672)
			(xy 318.778048 -410.213242) (xy 318.748589 -410.259086) (xy 318.712906 -410.300272) (xy 318.671725 -410.33596)
			(xy 318.625884 -410.365425) (xy 318.576317 -410.388067) (xy 318.524033 -410.403425) (xy 318.470095 -410.411187)
			(xy 318.442848 -410.411676) (xy 317.579248 -410.411676) (xy 317.551991 -410.41128) (xy 317.49803 -410.403528)
			(xy 317.445722 -410.388175) (xy 317.396131 -410.365533) (xy 317.350268 -410.336064) (xy 317.309066 -410.300367)
			(xy 317.273365 -410.25917) (xy 317.24389 -410.213311) (xy 317.221242 -410.163723) (xy 317.205882 -410.111417)
			(xy 317.198123 -410.057457) (xy 315.760589 -410.057457) (xy 315.752834 -410.111391) (xy 315.737481 -410.163681)
			(xy 315.714842 -410.213253) (xy 315.685379 -410.259099) (xy 315.649691 -410.300286) (xy 315.608506 -410.335974)
			(xy 315.56266 -410.365438) (xy 315.513088 -410.388078) (xy 315.460799 -410.403432) (xy 315.406857 -410.411189)
			(xy 315.379608 -410.411676) (xy 314.516008 -410.411676) (xy 314.488752 -410.411278) (xy 314.434796 -410.403521)
			(xy 314.382493 -410.388164) (xy 314.332907 -410.36552) (xy 314.287049 -410.33605) (xy 314.245852 -410.300353)
			(xy 314.210155 -410.259157) (xy 314.180684 -410.2133) (xy 314.158039 -410.163715) (xy 314.142681 -410.111412)
			(xy 314.134923 -410.057456) (xy 312.697412 -410.057456) (xy 312.689655 -410.111401) (xy 312.674299 -410.163697)
			(xy 312.651656 -410.213275) (xy 312.622188 -410.259126) (xy 312.586494 -410.300316) (xy 312.545301 -410.336007)
			(xy 312.499447 -410.365472) (xy 312.449867 -410.38811) (xy 312.39757 -410.403462) (xy 312.34362 -410.411215)
			(xy 312.316368 -410.411676) (xy 311.452768 -410.411676) (xy 311.425516 -410.411252) (xy 311.371567 -410.403491)
			(xy 311.319272 -410.388132) (xy 311.269695 -410.365487) (xy 311.223844 -410.336017) (xy 311.182654 -410.300323)
			(xy 311.146963 -410.25913) (xy 311.117498 -410.213277) (xy 311.094857 -410.163698) (xy 311.079502 -410.111402)
			(xy 311.071746 -410.057452) (xy 309.634089 -410.057452) (xy 309.626335 -410.111388) (xy 309.610982 -410.163676)
			(xy 309.588345 -410.213248) (xy 309.558884 -410.259093) (xy 309.523199 -410.300279) (xy 309.482015 -410.335967)
			(xy 309.436172 -410.365432) (xy 309.386603 -410.388073) (xy 309.334316 -410.403429) (xy 309.280376 -410.411188)
			(xy 309.253128 -410.411676) (xy 308.389528 -410.411676) (xy 308.362272 -410.411279) (xy 308.308313 -410.403525)
			(xy 308.256007 -410.38817) (xy 308.206419 -410.365527) (xy 308.160559 -410.336057) (xy 308.119359 -410.30036)
			(xy 308.08366 -410.259164) (xy 308.054187 -410.213305) (xy 308.03154 -410.163719) (xy 308.016181 -410.111414)
			(xy 308.008423 -410.057456) (xy 306.570912 -410.057456) (xy 306.563156 -410.111399) (xy 306.547801 -410.163693)
			(xy 306.525159 -410.21327) (xy 306.495693 -410.25912) (xy 306.460001 -410.300309) (xy 306.41881 -410.336)
			(xy 306.372959 -410.365465) (xy 306.323382 -410.388105) (xy 306.271087 -410.403459) (xy 306.217139 -410.411214)
			(xy 306.189888 -410.411676) (xy 305.326288 -410.411676) (xy 305.299035 -410.411253) (xy 305.245084 -410.403495)
			(xy 305.192786 -410.388137) (xy 305.143207 -410.365494) (xy 305.097354 -410.336025) (xy 305.056162 -410.30033)
			(xy 305.020468 -410.259137) (xy 304.991001 -410.213283) (xy 304.968358 -410.163702) (xy 304.953003 -410.111404)
			(xy 304.945246 -410.057453) (xy 280.83256 -410.057453) (xy 280.83256 -415.172652) (xy 280.832075 -415.197601)
			(xy 280.824257 -415.246884) (xy 280.808837 -415.294341) (xy 280.786193 -415.338807) (xy 280.756881 -415.37919)
			(xy 280.739596 -415.397188) (xy 280.152348 -415.984436) (xy 280.134386 -416.001764) (xy 280.094003 -416.03109)
			(xy 280.04953 -416.053738) (xy 280.002061 -416.069148) (xy 279.952766 -416.076943) (xy 279.927812 -416.0774)
			(xy 275.812504 -416.0774) (xy 270.688308 -421.201596) (xy 270.670313 -421.218886) (xy 270.629937 -421.24821)
			(xy 270.585471 -421.270858) (xy 270.53801 -421.286272) (xy 270.488723 -421.294073) (xy 270.463772 -421.29456)
			(xy 233.303572 -421.29456) (xy 231.01554 -423.582592) (xy 231.01554 -424.804386) (xy 357.679233 -424.804386)
			(xy 357.679233 -424.675246) (xy 357.687183 -424.546351) (xy 357.703053 -424.418191) (xy 357.726782 -424.29125)
			(xy 357.758281 -424.166011) (xy 357.79743 -424.042948) (xy 357.844081 -423.922529) (xy 357.898056 -423.80521)
			(xy 357.959151 -423.691436) (xy 358.027134 -423.581639) (xy 358.101748 -423.476236) (xy 358.182709 -423.375626)
			(xy 358.269709 -423.280191) (xy 358.36242 -423.190292) (xy 358.46049 -423.106271) (xy 358.563545 -423.028447)
			(xy 358.671196 -422.957115) (xy 358.783035 -422.892545) (xy 358.898636 -422.834983) (xy 359.017561 -422.784646)
			(xy 359.13936 -422.741726) (xy 359.26357 -422.706385) (xy 359.389719 -422.678758) (xy 359.517331 -422.658949)
			(xy 359.64592 -422.647033) (xy 359.774998 -422.643057) (xy 359.904076 -422.647033) (xy 360.032665 -422.658949)
			(xy 360.160277 -422.678758) (xy 360.286426 -422.706385) (xy 360.410636 -422.741726) (xy 360.532435 -422.784646)
			(xy 360.65136 -422.834983) (xy 360.766961 -422.892545) (xy 360.8788 -422.957115) (xy 360.986451 -423.028447)
			(xy 361.089506 -423.106271) (xy 361.187576 -423.190292) (xy 361.280287 -423.280191) (xy 361.367287 -423.375626)
			(xy 361.448248 -423.476236) (xy 361.522862 -423.581639) (xy 361.590845 -423.691436) (xy 361.65194 -423.80521)
			(xy 361.705915 -423.922529) (xy 361.752566 -424.042948) (xy 361.791715 -424.166011) (xy 361.823214 -424.29125)
			(xy 361.846943 -424.418191) (xy 361.853367 -424.470068) (xy 421.270176 -424.470068) (xy 421.270176 -417.770056)
			(xy 421.270681 -417.664527) (xy 421.278765 -417.453623) (xy 421.294922 -417.243184) (xy 421.319127 -417.033518)
			(xy 421.351345 -416.824934) (xy 421.391528 -416.617736) (xy 421.439619 -416.412229) (xy 421.495545 -416.208716)
			(xy 421.559226 -416.007493) (xy 421.630567 -415.808858) (xy 421.709464 -415.613101) (xy 421.795802 -415.420509)
			(xy 421.889452 -415.231366) (xy 421.990279 -415.045949) (xy 422.098134 -414.864529) (xy 422.212858 -414.687374)
			(xy 422.334284 -414.514743) (xy 422.462233 -414.34689) (xy 422.596517 -414.184061) (xy 422.73694 -414.026495)
			(xy 422.883295 -413.874423) (xy 423.035367 -413.728068) (xy 423.192933 -413.587645) (xy 423.355762 -413.453361)
			(xy 423.523615 -413.325412) (xy 423.696246 -413.203986) (xy 423.873401 -413.089262) (xy 424.054821 -412.981407)
			(xy 424.240238 -412.88058) (xy 424.429381 -412.78693) (xy 424.621973 -412.700592) (xy 424.81773 -412.621695)
			(xy 425.016365 -412.550354) (xy 425.217588 -412.486673) (xy 425.421101 -412.430747) (xy 425.626608 -412.382656)
			(xy 425.833806 -412.342473) (xy 426.04239 -412.310255) (xy 426.252056 -412.28605) (xy 426.462495 -412.269893)
			(xy 426.673399 -412.261809) (xy 426.884457 -412.261809) (xy 427.095361 -412.269893) (xy 427.3058 -412.28605)
			(xy 427.515466 -412.310255) (xy 427.72405 -412.342473) (xy 427.931248 -412.382656) (xy 428.136755 -412.430747)
			(xy 428.340268 -412.486673) (xy 428.541491 -412.550354) (xy 428.740126 -412.621695) (xy 428.935883 -412.700592)
			(xy 429.128475 -412.78693) (xy 429.317618 -412.88058) (xy 429.503035 -412.981407) (xy 429.684455 -413.089262)
			(xy 429.86161 -413.203986) (xy 430.034241 -413.325412) (xy 430.202094 -413.453361) (xy 430.364923 -413.587645)
			(xy 430.522489 -413.728068) (xy 430.674561 -413.874423) (xy 430.820916 -414.026495) (xy 430.961339 -414.184061)
			(xy 431.095623 -414.34689) (xy 431.223572 -414.514743) (xy 431.344998 -414.687374) (xy 431.459722 -414.864529)
			(xy 431.567577 -415.045949) (xy 431.668404 -415.231366) (xy 431.762054 -415.420509) (xy 431.848392 -415.613101)
			(xy 431.927289 -415.808858) (xy 431.99863 -416.007493) (xy 432.062311 -416.208716) (xy 432.118237 -416.412229)
			(xy 432.166328 -416.617736) (xy 432.206511 -416.824934) (xy 432.238729 -417.033518) (xy 432.262934 -417.243184)
			(xy 432.279091 -417.453623) (xy 432.287175 -417.664527) (xy 432.28768 -417.770056) (xy 432.28768 -424.470068)
			(xy 432.287175 -424.575597) (xy 432.279091 -424.786501) (xy 432.262934 -424.99694) (xy 432.238729 -425.206606)
			(xy 432.206511 -425.41519) (xy 432.166328 -425.622388) (xy 432.118237 -425.827895) (xy 432.062311 -426.031408)
			(xy 431.99863 -426.232631) (xy 431.927289 -426.431266) (xy 431.848392 -426.627023) (xy 431.762054 -426.819615)
			(xy 431.668404 -427.008758) (xy 431.567577 -427.194175) (xy 431.459722 -427.375595) (xy 431.344998 -427.55275)
			(xy 431.223572 -427.725381) (xy 431.095623 -427.893234) (xy 430.961339 -428.056063) (xy 430.820916 -428.213629)
			(xy 430.674561 -428.365701) (xy 430.522489 -428.512056) (xy 430.364923 -428.652479) (xy 430.202094 -428.786763)
			(xy 430.034241 -428.914712) (xy 429.86161 -429.036138) (xy 429.684455 -429.150862) (xy 429.503035 -429.258717)
			(xy 429.317618 -429.359544) (xy 429.128475 -429.453194) (xy 428.935883 -429.539532) (xy 428.740126 -429.618429)
			(xy 428.541491 -429.68977) (xy 428.340268 -429.753451) (xy 428.136755 -429.809377) (xy 427.931248 -429.857468)
			(xy 427.72405 -429.897651) (xy 427.515466 -429.929869) (xy 427.3058 -429.954074) (xy 427.095361 -429.970231)
			(xy 426.884457 -429.978315) (xy 426.673399 -429.978315) (xy 426.462495 -429.970231) (xy 426.252056 -429.954074)
			(xy 426.04239 -429.929869) (xy 425.833806 -429.897651) (xy 425.626608 -429.857468) (xy 425.421101 -429.809377)
			(xy 425.217588 -429.753451) (xy 425.016365 -429.68977) (xy 424.81773 -429.618429) (xy 424.621973 -429.539532)
			(xy 424.429381 -429.453194) (xy 424.240238 -429.359544) (xy 424.054821 -429.258717) (xy 423.873401 -429.150862)
			(xy 423.696246 -429.036138) (xy 423.523615 -428.914712) (xy 423.355762 -428.786763) (xy 423.192933 -428.652479)
			(xy 423.035367 -428.512056) (xy 422.883295 -428.365701) (xy 422.73694 -428.213629) (xy 422.596517 -428.056063)
			(xy 422.462233 -427.893234) (xy 422.334284 -427.725381) (xy 422.212858 -427.55275) (xy 422.098134 -427.375595)
			(xy 421.990279 -427.194175) (xy 421.889452 -427.008758) (xy 421.795802 -426.819615) (xy 421.709464 -426.627023)
			(xy 421.630567 -426.431266) (xy 421.559226 -426.232631) (xy 421.495545 -426.031408) (xy 421.439619 -425.827895)
			(xy 421.391528 -425.622388) (xy 421.351345 -425.41519) (xy 421.319127 -425.206606) (xy 421.294922 -424.99694)
			(xy 421.278765 -424.786501) (xy 421.270681 -424.575597) (xy 421.270176 -424.470068) (xy 361.853367 -424.470068)
			(xy 361.862813 -424.546351) (xy 361.870763 -424.675246) (xy 361.87126 -424.739816) (xy 361.870763 -424.804386)
			(xy 361.862813 -424.933281) (xy 361.846943 -425.061441) (xy 361.823214 -425.188382) (xy 361.791715 -425.313621)
			(xy 361.752566 -425.436684) (xy 361.705915 -425.557103) (xy 361.65194 -425.674422) (xy 361.590845 -425.788196)
			(xy 361.522862 -425.897993) (xy 361.448248 -426.003396) (xy 361.367287 -426.104006) (xy 361.280287 -426.199441)
			(xy 361.187576 -426.28934) (xy 361.089506 -426.373361) (xy 360.986451 -426.451185) (xy 360.8788 -426.522517)
			(xy 360.766961 -426.587087) (xy 360.65136 -426.644649) (xy 360.532435 -426.694986) (xy 360.410636 -426.737906)
			(xy 360.286426 -426.773247) (xy 360.160277 -426.800874) (xy 360.032665 -426.820683) (xy 359.904076 -426.832599)
			(xy 359.774998 -426.836576) (xy 359.64592 -426.832599) (xy 359.517331 -426.820683) (xy 359.389719 -426.800874)
			(xy 359.26357 -426.773247) (xy 359.13936 -426.737906) (xy 359.017561 -426.694986) (xy 358.898636 -426.644649)
			(xy 358.783035 -426.587087) (xy 358.671196 -426.522517) (xy 358.563545 -426.451185) (xy 358.46049 -426.373361)
			(xy 358.36242 -426.28934) (xy 358.269709 -426.199441) (xy 358.182709 -426.104006) (xy 358.101748 -426.003396)
			(xy 358.027134 -425.897993) (xy 357.959151 -425.788196) (xy 357.898056 -425.674422) (xy 357.844081 -425.557103)
			(xy 357.79743 -425.436684) (xy 357.758281 -425.313621) (xy 357.726782 -425.188382) (xy 357.703053 -425.061441)
			(xy 357.687183 -424.933281) (xy 357.679233 -424.804386) (xy 231.01554 -424.804386) (xy 231.01554 -427.289976)
			(xy 314.138056 -427.289976) (xy 314.13817 -427.274891) (xy 314.139948 -427.244772) (xy 314.141612 -427.229778)
			(xy 314.141612 -426.150024) (xy 314.139943 -426.135031) (xy 314.138165 -426.104912) (xy 314.138056 -426.089826)
			(xy 314.138166 -426.07474) (xy 314.139947 -426.044622) (xy 314.141612 -426.029628) (xy 314.141612 -425.419012)
			(xy 314.142023 -425.406928) (xy 314.14949 -425.383942) (xy 314.163696 -425.36439) (xy 314.183249 -425.350186)
			(xy 314.206236 -425.342722) (xy 314.21832 -425.342304) (xy 315.15812 -425.342304) (xy 315.170197 -425.342748)
			(xy 315.193167 -425.350217) (xy 315.212704 -425.364419) (xy 315.226898 -425.383962) (xy 315.234357 -425.406935)
			(xy 315.234828 -425.419012) (xy 315.234828 -427.960536) (xy 315.234367 -427.97261) (xy 315.226897 -427.995576)
			(xy 315.212699 -428.01511) (xy 315.193161 -428.029304) (xy 315.170195 -428.036769) (xy 315.15812 -428.037244)
			(xy 314.21832 -428.037244) (xy 314.20625 -428.036719) (xy 314.18329 -428.029267) (xy 314.163755 -428.015085)
			(xy 314.149559 -427.995561) (xy 314.142089 -427.972606) (xy 314.141612 -427.960536) (xy 314.141612 -427.350174)
			(xy 314.139948 -427.33518) (xy 314.138166 -427.305062) (xy 314.138056 -427.289976) (xy 231.01554 -427.289976)
			(xy 231.01554 -428.28972) (xy 316.138052 -428.28972) (xy 316.138162 -428.274634) (xy 316.139943 -428.244516)
			(xy 316.141608 -428.229522) (xy 316.141608 -427.150022) (xy 316.139939 -427.135029) (xy 316.138161 -427.10491)
			(xy 316.138052 -427.089824) (xy 316.138162 -427.074738) (xy 316.139943 -427.04462) (xy 316.141608 -427.029626)
			(xy 316.141608 -426.41901) (xy 316.142115 -426.406924) (xy 316.149565 -426.383929) (xy 316.163743 -426.364352)
			(xy 316.183266 -426.3501) (xy 316.206232 -426.342562) (xy 316.218316 -426.342048) (xy 317.158116 -426.342048)
			(xy 317.170221 -426.342502) (xy 317.193239 -426.349999) (xy 317.212808 -426.364253) (xy 317.227004 -426.383863)
			(xy 317.234433 -426.406904) (xy 317.234824 -426.41901) (xy 317.234824 -427.289976) (xy 318.138048 -427.289976)
			(xy 318.138162 -427.274891) (xy 318.13994 -427.244772) (xy 318.141604 -427.229778) (xy 318.141604 -426.150024)
			(xy 318.139935 -426.135031) (xy 318.138157 -426.104912) (xy 318.138048 -426.089826) (xy 318.138158 -426.07474)
			(xy 318.139939 -426.044622) (xy 318.141604 -426.029628) (xy 318.141604 -425.419012) (xy 318.142023 -425.406929)
			(xy 318.149489 -425.383944) (xy 318.163693 -425.364393) (xy 318.183244 -425.350189) (xy 318.206229 -425.342723)
			(xy 318.218312 -425.342304) (xy 319.158112 -425.342304) (xy 319.170188 -425.342754) (xy 319.193158 -425.350222)
			(xy 319.212696 -425.364421) (xy 319.226889 -425.383964) (xy 319.234349 -425.406935) (xy 319.23482 -425.419012)
			(xy 319.23482 -427.960536) (xy 319.234367 -427.972611) (xy 319.226896 -427.995578) (xy 319.212696 -428.015113)
			(xy 319.193156 -428.029307) (xy 319.170187 -428.036771) (xy 319.158112 -428.037244) (xy 318.218312 -428.037244)
			(xy 318.206242 -428.036726) (xy 318.183281 -428.029271) (xy 318.163747 -428.015087) (xy 318.149551 -427.995562)
			(xy 318.142081 -427.972606) (xy 318.141604 -427.960536) (xy 318.141604 -427.350174) (xy 318.13994 -427.33518)
			(xy 318.138158 -427.305062) (xy 318.138048 -427.289976) (xy 317.234824 -427.289976) (xy 317.234824 -428.28972)
			(xy 320.138044 -428.28972) (xy 320.138154 -428.274634) (xy 320.139935 -428.244516) (xy 320.1416 -428.229522)
			(xy 320.1416 -427.150022) (xy 320.139931 -427.135029) (xy 320.138153 -427.10491) (xy 320.138044 -427.089824)
			(xy 320.138154 -427.074738) (xy 320.139935 -427.04462) (xy 320.1416 -427.029626) (xy 320.1416 -426.41901)
			(xy 320.142115 -426.406925) (xy 320.149564 -426.383931) (xy 320.16374 -426.364355) (xy 320.183261 -426.350103)
			(xy 320.206225 -426.342563) (xy 320.218308 -426.342048) (xy 321.158108 -426.342048) (xy 321.170212 -426.342509)
			(xy 321.193231 -426.350004) (xy 321.212799 -426.364256) (xy 321.226996 -426.383865) (xy 321.234425 -426.406905)
			(xy 321.234816 -426.41901) (xy 321.234816 -427.289976) (xy 322.13804 -427.289976) (xy 322.138155 -427.274891)
			(xy 322.139932 -427.244772) (xy 322.141596 -427.229778) (xy 322.141596 -426.150024) (xy 322.139927 -426.135031)
			(xy 322.138149 -426.104912) (xy 322.13804 -426.089826) (xy 322.13815 -426.07474) (xy 322.139931 -426.044622)
			(xy 322.141596 -426.029628) (xy 322.141596 -425.419012) (xy 322.142023 -425.40693) (xy 322.149488 -425.383947)
			(xy 322.16369 -425.364396) (xy 322.183239 -425.350191) (xy 322.206222 -425.342724) (xy 322.218304 -425.342304)
			(xy 323.158104 -425.342304) (xy 323.170188 -425.342709) (xy 323.193173 -425.350179) (xy 323.212724 -425.364387)
			(xy 323.226928 -425.383941) (xy 323.234393 -425.406928) (xy 323.234812 -425.419012) (xy 323.234812 -427.960536)
			(xy 323.234367 -427.972612) (xy 323.226895 -427.99558) (xy 323.212693 -428.015116) (xy 323.193151 -428.029309)
			(xy 323.17018 -428.036772) (xy 323.158104 -428.037244) (xy 322.218304 -428.037244) (xy 322.206233 -428.036733)
			(xy 322.183272 -428.029276) (xy 322.163738 -428.01509) (xy 322.149542 -427.995564) (xy 322.142073 -427.972607)
			(xy 322.141596 -427.960536) (xy 322.141596 -427.350174) (xy 322.139932 -427.33518) (xy 322.13815 -427.305062)
			(xy 322.13804 -427.289976) (xy 321.234816 -427.289976) (xy 321.234816 -428.28972) (xy 324.138036 -428.28972)
			(xy 324.138148 -428.274634) (xy 324.139929 -428.244516) (xy 324.141592 -428.229522) (xy 324.141592 -427.150022)
			(xy 324.139923 -427.135029) (xy 324.138145 -427.10491) (xy 324.138036 -427.089824) (xy 324.138148 -427.074738)
			(xy 324.139929 -427.04462) (xy 324.141592 -427.029626) (xy 324.141592 -426.41901) (xy 324.142115 -426.406926)
			(xy 324.149563 -426.383934) (xy 324.163737 -426.364358) (xy 324.183256 -426.350105) (xy 324.206218 -426.342564)
			(xy 324.2183 -426.342048) (xy 325.1581 -426.342048) (xy 325.170204 -426.342515) (xy 325.193222 -426.350009)
			(xy 325.212791 -426.364259) (xy 325.226987 -426.383866) (xy 325.234417 -426.406905) (xy 325.234808 -426.41901)
			(xy 325.234808 -427.289976) (xy 326.138032 -427.289976) (xy 326.138149 -427.274891) (xy 326.139927 -427.244772)
			(xy 326.141588 -427.229778) (xy 326.141588 -426.150024) (xy 326.139919 -426.135031) (xy 326.138141 -426.104912)
			(xy 326.138032 -426.089826) (xy 326.138144 -426.07474) (xy 326.139925 -426.044622) (xy 326.141588 -426.029628)
			(xy 326.141588 -425.419012) (xy 326.142023 -425.40693) (xy 326.149487 -425.383949) (xy 326.163687 -425.364399)
			(xy 326.183234 -425.350194) (xy 326.206214 -425.342726) (xy 326.218296 -425.342304) (xy 327.158096 -425.342304)
			(xy 327.17018 -425.342716) (xy 327.193164 -425.350184) (xy 327.212716 -425.36439) (xy 327.22692 -425.383943)
			(xy 327.234385 -425.406928) (xy 327.234804 -425.419012) (xy 327.234804 -427.960536) (xy 327.234367 -427.972613)
			(xy 327.226894 -427.995582) (xy 327.21269 -428.015119) (xy 327.193146 -428.029312) (xy 327.170173 -428.036773)
			(xy 327.158096 -428.037244) (xy 326.218296 -428.037244) (xy 326.206225 -428.03674) (xy 326.183264 -428.02928)
			(xy 326.16373 -428.015093) (xy 326.149534 -427.995565) (xy 326.142065 -427.972607) (xy 326.141588 -427.960536)
			(xy 326.141588 -427.350174) (xy 326.139924 -427.33518) (xy 326.138142 -427.305062) (xy 326.138032 -427.289976)
			(xy 325.234808 -427.289976) (xy 325.234808 -428.28972) (xy 328.138028 -428.28972) (xy 328.13814 -428.274634)
			(xy 328.139921 -428.244516) (xy 328.141584 -428.229522) (xy 328.141584 -427.150022) (xy 328.139915 -427.135029)
			(xy 328.138137 -427.10491) (xy 328.138028 -427.089824) (xy 328.13814 -427.074738) (xy 328.139921 -427.04462)
			(xy 328.141584 -427.029626) (xy 328.141584 -426.41901) (xy 328.142017 -426.406917) (xy 328.149476 -426.383909)
			(xy 328.16367 -426.364325) (xy 328.183214 -426.350076) (xy 328.2062 -426.342551) (xy 328.218292 -426.342048)
			(xy 329.158092 -426.342048) (xy 329.170195 -426.342522) (xy 329.193214 -426.350013) (xy 329.212782 -426.364262)
			(xy 329.226979 -426.383868) (xy 329.234409 -426.406906) (xy 329.2348 -426.41901) (xy 329.2348 -427.289976)
			(xy 331.138022 -427.289976) (xy 331.138113 -427.275402) (xy 331.139767 -427.246301) (xy 331.141324 -427.23181)
			(xy 331.141324 -426.147992) (xy 331.139781 -426.1335) (xy 331.138128 -426.1044) (xy 331.138022 -426.089826)
			(xy 331.138117 -426.075252) (xy 331.139769 -426.046151) (xy 331.141324 -426.03166) (xy 331.141324 -425.419012)
			(xy 331.141727 -425.406901) (xy 331.149226 -425.38387) (xy 331.16349 -425.364295) (xy 331.183116 -425.350101)
			(xy 331.206174 -425.342684) (xy 331.218286 -425.342304) (xy 332.158086 -425.342304) (xy 332.170171 -425.342819)
			(xy 332.193165 -425.350267) (xy 332.212742 -425.364443) (xy 332.226995 -425.383964) (xy 332.234533 -425.406929)
			(xy 332.235048 -425.419012) (xy 332.235048 -427.960536) (xy 332.234615 -427.972642) (xy 332.227111 -427.995662)
			(xy 332.212852 -428.01523) (xy 332.193238 -428.029426) (xy 332.170193 -428.036854) (xy 332.158086 -428.037244)
			(xy 331.218286 -428.037244) (xy 331.206194 -428.036804) (xy 331.18319 -428.029342) (xy 331.163609 -428.015149)
			(xy 331.14936 -427.995609) (xy 331.141831 -427.972627) (xy 331.141324 -427.960536) (xy 331.141324 -427.348142)
			(xy 331.139777 -427.33365) (xy 331.138127 -427.30455) (xy 331.138022 -427.289976) (xy 329.2348 -427.289976)
			(xy 329.2348 -428.28972) (xy 333.138018 -428.28972) (xy 333.138113 -428.275146) (xy 333.139764 -428.246045)
			(xy 333.14132 -428.231554) (xy 333.14132 -427.14799) (xy 333.139777 -427.133498) (xy 333.138124 -427.104398)
			(xy 333.138018 -427.089824) (xy 333.138113 -427.07525) (xy 333.139765 -427.046149) (xy 333.14132 -427.031658)
			(xy 333.14132 -426.41901) (xy 333.14182 -426.406898) (xy 333.149302 -426.383858) (xy 333.163538 -426.364258)
			(xy 333.183133 -426.350015) (xy 333.20617 -426.342525) (xy 333.218282 -426.342048) (xy 334.158082 -426.342048)
			(xy 334.170205 -426.342475) (xy 334.193265 -426.349964) (xy 334.212881 -426.364213) (xy 334.227132 -426.383828)
			(xy 334.234623 -426.406887) (xy 334.235044 -426.41901) (xy 334.235044 -427.289976) (xy 335.138014 -427.289976)
			(xy 335.138104 -427.275402) (xy 335.139759 -427.246301) (xy 335.141316 -427.23181) (xy 335.141316 -426.147992)
			(xy 335.139773 -426.1335) (xy 335.13812 -426.1044) (xy 335.138014 -426.089826) (xy 335.138109 -426.075252)
			(xy 335.13976 -426.046151) (xy 335.141316 -426.03166) (xy 335.141316 -425.419012) (xy 335.141727 -425.406902)
			(xy 335.149225 -425.383873) (xy 335.163487 -425.364298) (xy 335.183111 -425.350104) (xy 335.206167 -425.342685)
			(xy 335.218278 -425.342304) (xy 336.158078 -425.342304) (xy 336.170163 -425.342825) (xy 336.193157 -425.350272)
			(xy 336.212734 -425.364446) (xy 336.226986 -425.383966) (xy 336.234525 -425.406929) (xy 336.23504 -425.419012)
			(xy 336.23504 -427.960536) (xy 336.234615 -427.972643) (xy 336.22711 -427.995664) (xy 336.21285 -428.015233)
			(xy 336.193233 -428.029428) (xy 336.170186 -428.036855) (xy 336.158078 -428.037244) (xy 335.218278 -428.037244)
			(xy 335.206186 -428.036811) (xy 335.183182 -428.029347) (xy 335.163601 -428.015152) (xy 335.149351 -427.99561)
			(xy 335.141823 -427.972627) (xy 335.141316 -427.960536) (xy 335.141316 -427.348142) (xy 335.139769 -427.33365)
			(xy 335.138119 -427.30455) (xy 335.138014 -427.289976) (xy 334.235044 -427.289976) (xy 334.235044 -428.28972)
			(xy 337.13801 -428.28972) (xy 337.138104 -428.275146) (xy 337.139756 -428.246045) (xy 337.141312 -428.231554)
			(xy 337.141312 -427.14799) (xy 337.139769 -427.133498) (xy 337.138116 -427.104398) (xy 337.13801 -427.089824)
			(xy 337.138104 -427.07525) (xy 337.139756 -427.046149) (xy 337.141312 -427.031658) (xy 337.141312 -426.41901)
			(xy 337.14182 -426.406899) (xy 337.149301 -426.38386) (xy 337.163535 -426.36426) (xy 337.183128 -426.350018)
			(xy 337.206163 -426.342526) (xy 337.218274 -426.342048) (xy 338.158074 -426.342048) (xy 338.170196 -426.342482)
			(xy 338.193256 -426.349969) (xy 338.212872 -426.364216) (xy 338.227124 -426.38383) (xy 338.234615 -426.406888)
			(xy 338.235036 -426.41901) (xy 338.235036 -427.289976) (xy 339.138006 -427.289976) (xy 339.138096 -427.275402)
			(xy 339.139751 -427.246301) (xy 339.141308 -427.23181) (xy 339.141308 -426.147992) (xy 339.139765 -426.1335)
			(xy 339.138112 -426.1044) (xy 339.138006 -426.089826) (xy 339.138101 -426.075252) (xy 339.139752 -426.046151)
			(xy 339.141308 -426.03166) (xy 339.141308 -425.419012) (xy 339.141727 -425.406903) (xy 339.149224 -425.383875)
			(xy 339.163485 -425.364301) (xy 339.183106 -425.350106) (xy 339.20616 -425.342687) (xy 339.21827 -425.342304)
			(xy 340.15807 -425.342304) (xy 340.170154 -425.342832) (xy 340.193148 -425.350276) (xy 340.212725 -425.364448)
			(xy 340.226978 -425.383967) (xy 340.234517 -425.40693) (xy 340.235032 -425.419012) (xy 340.235032 -427.960536)
			(xy 340.234615 -427.972644) (xy 340.227109 -427.995667) (xy 340.212847 -428.015236) (xy 340.193228 -428.029431)
			(xy 340.170179 -428.036856) (xy 340.15807 -428.037244) (xy 339.21827 -428.037244) (xy 339.206177 -428.036818)
			(xy 339.183173 -428.029351) (xy 339.163592 -428.015154) (xy 339.149343 -427.995612) (xy 339.141815 -427.972627)
			(xy 339.141308 -427.960536) (xy 339.141308 -427.348142) (xy 339.139761 -427.33365) (xy 339.138111 -427.30455)
			(xy 339.138006 -427.289976) (xy 338.235036 -427.289976) (xy 338.235036 -428.28972) (xy 341.138002 -428.28972)
			(xy 341.138096 -428.275146) (xy 341.139748 -428.246045) (xy 341.141304 -428.231554) (xy 341.141304 -427.14799)
			(xy 341.139761 -427.133498) (xy 341.138108 -427.104398) (xy 341.138002 -427.089824) (xy 341.138096 -427.07525)
			(xy 341.139748 -427.046149) (xy 341.141304 -427.031658) (xy 341.141304 -426.41901) (xy 341.14182 -426.406899)
			(xy 341.1493 -426.383862) (xy 341.163532 -426.364263) (xy 341.183123 -426.35002) (xy 341.206156 -426.342527)
			(xy 341.218266 -426.342048) (xy 342.158066 -426.342048) (xy 342.170188 -426.342489) (xy 342.193247 -426.349973)
			(xy 342.212864 -426.364219) (xy 342.227116 -426.383831) (xy 342.234607 -426.406888) (xy 342.235028 -426.41901)
			(xy 342.235028 -427.289976) (xy 343.137998 -427.289976) (xy 343.138088 -427.275402) (xy 343.139743 -427.246301)
			(xy 343.1413 -427.23181) (xy 343.1413 -426.147992) (xy 343.139757 -426.1335) (xy 343.138104 -426.1044)
			(xy 343.137998 -426.089826) (xy 343.138093 -426.075252) (xy 343.139744 -426.046151) (xy 343.1413 -426.03166)
			(xy 343.1413 -425.419012) (xy 343.141727 -425.406904) (xy 343.149223 -425.383877) (xy 343.163482 -425.364304)
			(xy 343.183101 -425.350109) (xy 343.206152 -425.342688) (xy 343.218262 -425.342304) (xy 344.158062 -425.342304)
			(xy 344.170146 -425.342839) (xy 344.193139 -425.350281) (xy 344.212717 -425.364451) (xy 344.22697 -425.383968)
			(xy 344.234509 -425.40693) (xy 344.235024 -425.419012) (xy 344.235024 -427.960536) (xy 344.234615 -427.972644)
			(xy 344.227108 -427.995669) (xy 344.212844 -428.015239) (xy 344.193223 -428.029433) (xy 344.170172 -428.036857)
			(xy 344.158062 -428.037244) (xy 343.218262 -428.037244) (xy 343.206169 -428.036825) (xy 343.183164 -428.029356)
			(xy 343.163584 -428.015157) (xy 343.149335 -427.995613) (xy 343.141807 -427.972628) (xy 343.1413 -427.960536)
			(xy 343.1413 -427.348142) (xy 343.139753 -427.33365) (xy 343.138103 -427.30455) (xy 343.137998 -427.289976)
			(xy 342.235028 -427.289976) (xy 342.235028 -428.28972) (xy 345.137994 -428.28972) (xy 345.138088 -428.275146)
			(xy 345.13974 -428.246045) (xy 345.141296 -428.231554) (xy 345.141296 -427.14799) (xy 345.139753 -427.133498)
			(xy 345.1381 -427.104398) (xy 345.137994 -427.089824) (xy 345.138088 -427.07525) (xy 345.13974 -427.046149)
			(xy 345.141296 -427.031658) (xy 345.141296 -426.41901) (xy 345.14182 -426.4069) (xy 345.149299 -426.383864)
			(xy 345.163529 -426.364266) (xy 345.183118 -426.350023) (xy 345.206148 -426.342528) (xy 345.218258 -426.342048)
			(xy 346.158058 -426.342048) (xy 346.17018 -426.342496) (xy 346.193239 -426.349978) (xy 346.212855 -426.364222)
			(xy 346.227108 -426.383833) (xy 346.234599 -426.406889) (xy 346.23502 -426.41901) (xy 346.23502 -427.289976)
			(xy 381.21844 -427.289976) (xy 381.218922 -427.257419) (xy 381.226871 -427.192794) (xy 381.242658 -427.129623)
			(xy 381.266048 -427.068856) (xy 381.296688 -427.011404) (xy 381.334121 -426.958126) (xy 381.377785 -426.909823)
			(xy 381.402082 -426.888148) (xy 381.482854 -426.723302) (xy 381.487539 -426.71278) (xy 381.491032 -426.690025)
			(xy 381.487554 -426.667269) (xy 381.482854 -426.656754) (xy 381.401828 -426.491654) (xy 381.377569 -426.469953)
			(xy 381.333971 -426.421622) (xy 381.296595 -426.368333) (xy 381.266001 -426.310881) (xy 381.242645 -426.250126)
			(xy 381.226877 -426.186974) (xy 381.218932 -426.122371) (xy 381.21844 -426.089826) (xy 381.219145 -426.0507)
			(xy 381.230616 -425.973293) (xy 381.2413 -425.935648) (xy 381.2413 -425.419012) (xy 381.241727 -425.406904)
			(xy 381.249223 -425.383877) (xy 381.263482 -425.364304) (xy 381.283101 -425.350109) (xy 381.306152 -425.342688)
			(xy 381.318262 -425.342304) (xy 382.258062 -425.342304) (xy 382.270146 -425.342839) (xy 382.293139 -425.350281)
			(xy 382.312717 -425.364451) (xy 382.32697 -425.383968) (xy 382.334509 -425.40693) (xy 382.335024 -425.419012)
			(xy 382.335024 -427.960536) (xy 382.334615 -427.972644) (xy 382.327108 -427.995669) (xy 382.312844 -428.015239)
			(xy 382.293223 -428.029433) (xy 382.270172 -428.036857) (xy 382.258062 -428.037244) (xy 381.318262 -428.037244)
			(xy 381.306169 -428.036825) (xy 381.283164 -428.029356) (xy 381.263584 -428.015157) (xy 381.249335 -427.995613)
			(xy 381.241807 -427.972628) (xy 381.2413 -427.960536) (xy 381.2413 -427.444154) (xy 381.230607 -427.40651)
			(xy 381.219134 -427.329103) (xy 381.21844 -427.289976) (xy 346.23502 -427.289976) (xy 346.23502 -428.960534)
			(xy 346.234669 -428.972663) (xy 346.227162 -428.99573) (xy 346.212894 -429.015348) (xy 346.193262 -429.029597)
			(xy 346.170187 -429.03708) (xy 346.158058 -429.037496) (xy 345.218258 -429.037496) (xy 345.206145 -429.037025)
			(xy 345.183106 -429.02953) (xy 345.163508 -429.015287) (xy 345.149266 -428.995687) (xy 345.141774 -428.972647)
			(xy 345.141296 -428.960534) (xy 345.141296 -428.347886) (xy 345.139753 -428.333394) (xy 345.1381 -428.304294)
			(xy 345.137994 -428.28972) (xy 342.235028 -428.28972) (xy 342.235028 -428.960534) (xy 342.234617 -428.972654)
			(xy 342.227116 -428.995704) (xy 342.21286 -429.015308) (xy 342.193243 -429.029547) (xy 342.170186 -429.037027)
			(xy 342.158066 -429.037496) (xy 341.218266 -429.037496) (xy 341.206153 -429.037018) (xy 341.183114 -429.029525)
			(xy 341.163516 -429.015284) (xy 341.149275 -428.995686) (xy 341.141782 -428.972647) (xy 341.141304 -428.960534)
			(xy 341.141304 -428.347886) (xy 341.139761 -428.333394) (xy 341.138108 -428.304294) (xy 341.138002 -428.28972)
			(xy 338.235036 -428.28972) (xy 338.235036 -428.960534) (xy 338.234617 -428.972653) (xy 338.227117 -428.995702)
			(xy 338.212862 -429.015305) (xy 338.193248 -429.029545) (xy 338.170193 -429.037026) (xy 338.158074 -429.037496)
			(xy 337.218274 -429.037496) (xy 337.206161 -429.037011) (xy 337.183123 -429.029521) (xy 337.163525 -429.015281)
			(xy 337.149283 -428.995684) (xy 337.14179 -428.972646) (xy 337.141312 -428.960534) (xy 337.141312 -428.347886)
			(xy 337.139769 -428.333394) (xy 337.138116 -428.304294) (xy 337.13801 -428.28972) (xy 334.235044 -428.28972)
			(xy 334.235044 -428.960534) (xy 334.234617 -428.972652) (xy 334.227118 -428.9957) (xy 334.212865 -429.015302)
			(xy 334.193253 -429.029542) (xy 334.1702 -429.037025) (xy 334.158082 -429.037496) (xy 333.218282 -429.037496)
			(xy 333.20617 -429.037004) (xy 333.183132 -429.029516) (xy 333.163533 -429.015278) (xy 333.149291 -428.995683)
			(xy 333.141798 -428.972646) (xy 333.14132 -428.960534) (xy 333.14132 -428.347886) (xy 333.139777 -428.333394)
			(xy 333.138124 -428.304294) (xy 333.138018 -428.28972) (xy 329.2348 -428.28972) (xy 329.2348 -428.960534)
			(xy 329.234322 -428.972621) (xy 329.226861 -428.995616) (xy 329.212676 -429.015192) (xy 329.193148 -429.029443)
			(xy 329.170178 -429.036981) (xy 329.158092 -429.037496) (xy 328.218292 -429.037496) (xy 328.206182 -429.037091)
			(xy 328.183154 -429.029588) (xy 328.163581 -429.015324) (xy 328.149386 -428.9957) (xy 328.141967 -428.972645)
			(xy 328.141584 -428.960534) (xy 328.141584 -428.349918) (xy 328.139915 -428.334925) (xy 328.138137 -428.304806)
			(xy 328.138028 -428.28972) (xy 325.234808 -428.28972) (xy 325.234808 -428.960534) (xy 325.234323 -428.972621)
			(xy 325.226862 -428.995614) (xy 325.212679 -429.01519) (xy 325.193153 -429.029441) (xy 325.170185 -429.03698)
			(xy 325.1581 -429.037496) (xy 324.2183 -429.037496) (xy 324.206191 -429.037084) (xy 324.183163 -429.029584)
			(xy 324.163589 -429.015321) (xy 324.149395 -428.995699) (xy 324.141975 -428.972645) (xy 324.141592 -428.960534)
			(xy 324.141592 -428.349918) (xy 324.139923 -428.334925) (xy 324.138145 -428.304806) (xy 324.138036 -428.28972)
			(xy 321.234816 -428.28972) (xy 321.234816 -428.960534) (xy 321.234421 -428.97263) (xy 321.226949 -428.995639)
			(xy 321.212746 -429.015222) (xy 321.193195 -429.02947) (xy 321.170203 -429.036993) (xy 321.158108 -429.037496)
			(xy 320.218308 -429.037496) (xy 320.206199 -429.037077) (xy 320.183171 -429.029579) (xy 320.163598 -429.015319)
			(xy 320.149403 -428.995697) (xy 320.141983 -428.972644) (xy 320.1416 -428.960534) (xy 320.1416 -428.349918)
			(xy 320.139931 -428.334925) (xy 320.138153 -428.304806) (xy 320.138044 -428.28972) (xy 317.234824 -428.28972)
			(xy 317.234824 -428.960534) (xy 317.234421 -428.972629) (xy 317.226951 -428.995637) (xy 317.212749 -429.015219)
			(xy 317.1932 -429.029467) (xy 317.17021 -429.036992) (xy 317.158116 -429.037496) (xy 316.218316 -429.037496)
			(xy 316.206208 -429.03707) (xy 316.18318 -429.029574) (xy 316.163607 -429.015315) (xy 316.149412 -428.995695)
			(xy 316.141991 -428.972644) (xy 316.141608 -428.960534) (xy 316.141608 -428.349918) (xy 316.139939 -428.334925)
			(xy 316.138161 -428.304806) (xy 316.138052 -428.28972) (xy 231.01554 -428.28972) (xy 231.01554 -433.130695)
			(xy 266.885917 -433.130695) (xy 266.885917 -432.953425) (xy 266.89387 -432.776334) (xy 266.909761 -432.599778)
			(xy 266.933556 -432.424113) (xy 266.965209 -432.249692) (xy 267.004655 -432.076867) (xy 267.051815 -431.905986)
			(xy 267.106594 -431.737392) (xy 267.168882 -431.571427) (xy 267.238554 -431.408422) (xy 267.315468 -431.248708)
			(xy 267.399471 -431.092605) (xy 267.490392 -430.940428) (xy 267.588049 -430.792484) (xy 267.692246 -430.64907)
			(xy 267.802772 -430.510475) (xy 267.919404 -430.376978) (xy 268.041909 -430.248849) (xy 268.170038 -430.126344)
			(xy 268.303535 -430.009712) (xy 268.44213 -429.899186) (xy 268.585544 -429.794989) (xy 268.733488 -429.697332)
			(xy 268.885665 -429.606411) (xy 269.041768 -429.522408) (xy 269.201482 -429.445494) (xy 269.364487 -429.375822)
			(xy 269.530452 -429.313534) (xy 269.699046 -429.258755) (xy 269.869927 -429.211595) (xy 270.042752 -429.172149)
			(xy 270.217173 -429.140496) (xy 270.392838 -429.116701) (xy 270.569394 -429.10081) (xy 270.746485 -429.092857)
			(xy 270.923755 -429.092857) (xy 271.100846 -429.10081) (xy 271.277402 -429.116701) (xy 271.453067 -429.140496)
			(xy 271.627488 -429.172149) (xy 271.800313 -429.211595) (xy 271.971194 -429.258755) (xy 272.139788 -429.313534)
			(xy 272.305753 -429.375822) (xy 272.468758 -429.445494) (xy 272.628472 -429.522408) (xy 272.784575 -429.606411)
			(xy 272.936752 -429.697332) (xy 273.084696 -429.794989) (xy 273.22811 -429.899186) (xy 273.366705 -430.009712)
			(xy 273.500202 -430.126344) (xy 273.628331 -430.248849) (xy 273.750836 -430.376978) (xy 273.867468 -430.510475)
			(xy 273.977994 -430.64907) (xy 274.082191 -430.792484) (xy 274.146507 -430.889918) (xy 314.118498 -430.889918)
			(xy 314.119024 -430.857363) (xy 314.126967 -430.792739) (xy 314.142748 -430.729571) (xy 314.166131 -430.668804)
			(xy 314.196764 -430.611351) (xy 314.23419 -430.558072) (xy 314.277846 -430.509767) (xy 314.30214 -430.48809)
			(xy 314.382912 -430.323244) (xy 314.38764 -430.312738) (xy 314.39112 -430.289973) (xy 314.387623 -430.267211)
			(xy 314.382912 -430.256696) (xy 314.301886 -430.091596) (xy 314.277639 -430.069883) (xy 314.234041 -430.021553)
			(xy 314.196666 -429.968265) (xy 314.16607 -429.910816) (xy 314.142713 -429.850062) (xy 314.126941 -429.786914)
			(xy 314.118992 -429.722312) (xy 314.118498 -429.689768) (xy 314.119226 -429.650443) (xy 314.13083 -429.572653)
			(xy 314.141612 -429.534828) (xy 314.141612 -429.018954) (xy 314.142068 -429.006865) (xy 314.149534 -428.983867)
			(xy 314.163724 -428.964291) (xy 314.183258 -428.950041) (xy 314.206232 -428.942505) (xy 314.21832 -428.941992)
			(xy 315.15812 -428.941992) (xy 315.170229 -428.942399) (xy 315.193256 -428.949903) (xy 315.212828 -428.964167)
			(xy 315.227022 -428.98379) (xy 315.234444 -429.006843) (xy 315.234828 -429.018954) (xy 315.234828 -431.560478)
			(xy 315.234373 -431.57257) (xy 315.226919 -431.595575) (xy 315.21273 -431.615158) (xy 315.193192 -431.629408)
			(xy 315.17021 -431.636935) (xy 315.15812 -431.63744) (xy 314.21832 -431.63744) (xy 314.206216 -431.636967)
			(xy 314.183196 -431.629478) (xy 314.163627 -431.61523) (xy 314.14943 -431.595622) (xy 314.142001 -431.572583)
			(xy 314.141612 -431.560478) (xy 314.141612 -431.044858) (xy 314.130817 -431.007035) (xy 314.119208 -430.929244)
			(xy 314.118498 -430.889918) (xy 274.146507 -430.889918) (xy 274.179848 -430.940428) (xy 274.270769 -431.092605)
			(xy 274.354772 -431.248708) (xy 274.431686 -431.408422) (xy 274.501358 -431.571427) (xy 274.563646 -431.737392)
			(xy 274.613204 -431.889916) (xy 316.118494 -431.889916) (xy 316.118986 -431.85736) (xy 316.126931 -431.792733)
			(xy 316.142715 -431.729563) (xy 316.166103 -431.668795) (xy 316.196742 -431.611342) (xy 316.234175 -431.558065)
			(xy 316.277838 -431.509763) (xy 316.302136 -431.488088) (xy 316.382908 -431.323242) (xy 316.387637 -431.312736)
			(xy 316.391117 -431.289971) (xy 316.38762 -431.267208) (xy 316.382908 -431.256694) (xy 316.301882 -431.091594)
			(xy 316.277633 -431.069883) (xy 316.234036 -431.021552) (xy 316.19666 -430.968264) (xy 316.166065 -430.910814)
			(xy 316.142708 -430.850061) (xy 316.126937 -430.786912) (xy 316.118988 -430.72231) (xy 316.118494 -430.689766)
			(xy 316.119222 -430.650441) (xy 316.130826 -430.572651) (xy 316.141608 -430.534826) (xy 316.141608 -430.018952)
			(xy 316.142023 -430.006873) (xy 316.149501 -429.983902) (xy 316.16371 -429.964364) (xy 316.183259 -429.950172)
			(xy 316.206237 -429.942713) (xy 316.218316 -429.942244) (xy 317.158116 -429.942244) (xy 317.170187 -429.94275)
			(xy 317.193146 -429.950211) (xy 317.212679 -429.964399) (xy 317.226874 -429.983925) (xy 317.234345 -430.006882)
			(xy 317.234824 -430.018952) (xy 317.234824 -430.889918) (xy 318.11849 -430.889918) (xy 318.118985 -430.857362)
			(xy 318.126929 -430.792736) (xy 318.142713 -430.729565) (xy 318.1661 -430.668798) (xy 318.196739 -430.611345)
			(xy 318.234171 -430.558067) (xy 318.277835 -430.509765) (xy 318.302132 -430.48809) (xy 318.382904 -430.323244)
			(xy 318.387632 -430.312738) (xy 318.391113 -430.289973) (xy 318.387616 -430.26721) (xy 318.382904 -430.256696)
			(xy 318.301878 -430.091596) (xy 318.277629 -430.069884) (xy 318.234032 -430.021554) (xy 318.196657 -429.968266)
			(xy 318.166062 -429.910816) (xy 318.142704 -429.850063) (xy 318.126933 -429.786914) (xy 318.118984 -429.722312)
			(xy 318.11849 -429.689768) (xy 318.119218 -429.650443) (xy 318.130823 -429.572653) (xy 318.141604 -429.534828)
			(xy 318.141604 -429.018954) (xy 318.142067 -429.006866) (xy 318.149532 -428.98387) (xy 318.163721 -428.964293)
			(xy 318.183253 -428.950043) (xy 318.206225 -428.942506) (xy 318.218312 -428.941992) (xy 319.158112 -428.941992)
			(xy 319.170221 -428.942406) (xy 319.193247 -428.949908) (xy 319.212819 -428.96417) (xy 319.227014 -428.983792)
			(xy 319.234436 -429.006844) (xy 319.23482 -429.018954) (xy 319.23482 -431.560478) (xy 319.234373 -431.57257)
			(xy 319.226918 -431.595577) (xy 319.212727 -431.615161) (xy 319.193187 -431.629411) (xy 319.170203 -431.636936)
			(xy 319.158112 -431.63744) (xy 318.218312 -431.63744) (xy 318.206208 -431.636974) (xy 318.183188 -431.629483)
			(xy 318.163618 -431.615232) (xy 318.149422 -431.595624) (xy 318.141993 -431.572583) (xy 318.141604 -431.560478)
			(xy 318.141604 -431.044858) (xy 318.130809 -431.007035) (xy 318.1192 -430.929244) (xy 318.11849 -430.889918)
			(xy 317.234824 -430.889918) (xy 317.234824 -431.889916) (xy 320.118486 -431.889916) (xy 320.118981 -431.85736)
			(xy 320.126925 -431.792734) (xy 320.14271 -431.729563) (xy 320.166097 -431.668796) (xy 320.196736 -431.611343)
			(xy 320.234168 -431.558065) (xy 320.277831 -431.509763) (xy 320.302128 -431.488088) (xy 320.3829 -431.323242)
			(xy 320.38763 -431.312736) (xy 320.39111 -431.289971) (xy 320.387612 -431.267208) (xy 320.3829 -431.256694)
			(xy 320.301874 -431.091594) (xy 320.277623 -431.069884) (xy 320.234026 -431.021554) (xy 320.196651 -430.968265)
			(xy 320.166057 -430.910815) (xy 320.1427 -430.850061) (xy 320.126929 -430.786912) (xy 320.11898 -430.72231)
			(xy 320.118486 -430.689766) (xy 320.119214 -430.650441) (xy 320.130819 -430.572651) (xy 320.1416 -430.534826)
			(xy 320.1416 -430.018952) (xy 320.142023 -430.006874) (xy 320.1495 -429.983904) (xy 320.163707 -429.964367)
			(xy 320.183254 -429.950174) (xy 320.20623 -429.942714) (xy 320.218308 -429.942244) (xy 321.158108 -429.942244)
			(xy 321.170178 -429.942757) (xy 321.193137 -429.950216) (xy 321.21267 -429.964401) (xy 321.226866 -429.983927)
			(xy 321.234337 -430.006882) (xy 321.234816 -430.018952) (xy 321.234816 -430.889918) (xy 322.118482 -430.889918)
			(xy 322.11898 -430.857362) (xy 322.126924 -430.792736) (xy 322.142708 -430.729566) (xy 322.166094 -430.668798)
			(xy 322.196733 -430.611345) (xy 322.234164 -430.558068) (xy 322.277827 -430.509765) (xy 322.302124 -430.48809)
			(xy 322.382896 -430.323244) (xy 322.387625 -430.312738) (xy 322.391105 -430.289973) (xy 322.387608 -430.26721)
			(xy 322.382896 -430.256696) (xy 322.30187 -430.091596) (xy 322.27764 -430.069864) (xy 322.234038 -430.02154)
			(xy 322.196658 -429.968256) (xy 322.16606 -429.91081) (xy 322.142699 -429.850059) (xy 322.126926 -429.786912)
			(xy 322.118976 -429.722312) (xy 322.118482 -429.689768) (xy 322.119211 -429.650443) (xy 322.130815 -429.572653)
			(xy 322.141596 -429.534828) (xy 322.141596 -429.018954) (xy 322.142067 -429.006866) (xy 322.149531 -428.983872)
			(xy 322.163718 -428.964296) (xy 322.183248 -428.950046) (xy 322.206218 -428.942507) (xy 322.218304 -428.941992)
			(xy 323.158104 -428.941992) (xy 323.170212 -428.942413) (xy 323.193238 -428.949912) (xy 323.212811 -428.964173)
			(xy 323.227006 -428.983793) (xy 323.234428 -429.006844) (xy 323.234812 -429.018954) (xy 323.234812 -431.560478)
			(xy 323.234373 -431.572571) (xy 323.226916 -431.595579) (xy 323.212724 -431.615164) (xy 323.193182 -431.629413)
			(xy 323.170196 -431.636937) (xy 323.158104 -431.63744) (xy 322.218304 -431.63744) (xy 322.206199 -431.636981)
			(xy 322.183179 -431.629488) (xy 322.163609 -431.615236) (xy 322.149413 -431.595625) (xy 322.141985 -431.572584)
			(xy 322.141596 -431.560478) (xy 322.141596 -431.044858) (xy 322.130801 -431.007035) (xy 322.119192 -430.929244)
			(xy 322.118482 -430.889918) (xy 321.234816 -430.889918) (xy 321.234816 -431.889916) (xy 324.118478 -431.889916)
			(xy 324.118976 -431.85736) (xy 324.12692 -431.792734) (xy 324.142704 -431.729564) (xy 324.166091 -431.668797)
			(xy 324.196729 -431.611343) (xy 324.23416 -431.558066) (xy 324.277823 -431.509763) (xy 324.30212 -431.488088)
			(xy 324.382892 -431.323242) (xy 324.387622 -431.312737) (xy 324.391103 -431.289971) (xy 324.387605 -431.267208)
			(xy 324.382892 -431.256694) (xy 324.301866 -431.091594) (xy 324.277634 -431.069864) (xy 324.234032 -431.021539)
			(xy 324.196653 -430.968255) (xy 324.166055 -430.910808) (xy 324.142695 -430.850057) (xy 324.126922 -430.78691)
			(xy 324.118972 -430.72231) (xy 324.118478 -430.689766) (xy 324.119206 -430.650441) (xy 324.130811 -430.572651)
			(xy 324.141592 -430.534826) (xy 324.141592 -430.018952) (xy 324.142023 -430.006875) (xy 324.149499 -429.983906)
			(xy 324.163704 -429.96437) (xy 324.183249 -429.950177) (xy 324.206223 -429.942716) (xy 324.2183 -429.942244)
			(xy 325.1581 -429.942244) (xy 325.17017 -429.942764) (xy 325.193129 -429.95022) (xy 325.212662 -429.964404)
			(xy 325.226858 -429.983928) (xy 325.234329 -430.006883) (xy 325.234808 -430.018952) (xy 325.234808 -430.889918)
			(xy 326.118474 -430.889918) (xy 326.118974 -430.857362) (xy 326.126919 -430.792736) (xy 326.142702 -430.729566)
			(xy 326.166088 -430.668799) (xy 326.196726 -430.611346) (xy 326.234157 -430.558068) (xy 326.277819 -430.509765)
			(xy 326.302116 -430.48809) (xy 326.382888 -430.323244) (xy 326.387617 -430.312738) (xy 326.391098 -430.289973)
			(xy 326.3876 -430.26721) (xy 326.382888 -430.256696) (xy 326.301862 -430.091596) (xy 326.27763 -430.069866)
			(xy 326.234029 -430.021541) (xy 326.19665 -429.968257) (xy 326.166051 -429.91081) (xy 326.142691 -429.850059)
			(xy 326.126918 -429.786912) (xy 326.118968 -429.722312) (xy 326.118474 -429.689768) (xy 326.119203 -429.650443)
			(xy 326.130807 -429.572653) (xy 326.141588 -429.534828) (xy 326.141588 -429.018954) (xy 326.141969 -429.006857)
			(xy 326.149444 -428.983847) (xy 326.163651 -428.964264) (xy 326.183205 -428.950016) (xy 326.2062 -428.942494)
			(xy 326.218296 -428.941992) (xy 327.158096 -428.941992) (xy 327.170204 -428.942419) (xy 327.19323 -428.949917)
			(xy 327.212802 -428.964176) (xy 327.226997 -428.983795) (xy 327.23442 -429.006845) (xy 327.234804 -429.018954)
			(xy 327.234804 -431.560478) (xy 327.234275 -431.572562) (xy 327.226829 -431.595555) (xy 327.212657 -431.615131)
			(xy 327.19314 -431.629384) (xy 327.170178 -431.636924) (xy 327.158096 -431.63744) (xy 326.218296 -431.63744)
			(xy 326.206191 -431.636988) (xy 326.18317 -431.629492) (xy 326.163601 -431.615238) (xy 326.149405 -431.595627)
			(xy 326.141977 -431.572584) (xy 326.141588 -431.560478) (xy 326.141588 -431.044858) (xy 326.130793 -431.007036)
			(xy 326.119184 -430.929244) (xy 326.118474 -430.889918) (xy 325.234808 -430.889918) (xy 325.234808 -431.889916)
			(xy 328.11847 -431.889916) (xy 328.11897 -431.85736) (xy 328.126915 -431.792734) (xy 328.142698 -431.729564)
			(xy 328.166084 -431.668797) (xy 328.196723 -431.611344) (xy 328.234153 -431.558066) (xy 328.277815 -431.509763)
			(xy 328.302112 -431.488088) (xy 328.382884 -431.323242) (xy 328.387614 -431.312737) (xy 328.391095 -431.289971)
			(xy 328.387597 -431.267208) (xy 328.382884 -431.256694) (xy 328.301858 -431.091594) (xy 328.277624 -431.069866)
			(xy 328.234023 -431.02154) (xy 328.196644 -430.968256) (xy 328.166046 -430.910809) (xy 328.142687 -430.850058)
			(xy 328.126914 -430.78691) (xy 328.118964 -430.72231) (xy 328.11847 -430.689766) (xy 328.119199 -430.650441)
			(xy 328.130803 -430.572651) (xy 328.141584 -430.534826) (xy 328.141584 -430.018952) (xy 328.142023 -430.006876)
			(xy 328.149498 -429.983908) (xy 328.163701 -429.964373) (xy 328.183244 -429.95018) (xy 328.206215 -429.942717)
			(xy 328.218292 -429.942244) (xy 329.158092 -429.942244) (xy 329.170161 -429.94277) (xy 329.19312 -429.950225)
			(xy 329.212653 -429.964407) (xy 329.22685 -429.98393) (xy 329.234321 -430.006883) (xy 329.2348 -430.018952)
			(xy 329.2348 -430.889918) (xy 331.118464 -430.889918) (xy 331.118968 -430.857362) (xy 331.126912 -430.792737)
			(xy 331.142695 -430.729567) (xy 331.166081 -430.6688) (xy 331.196718 -430.611347) (xy 331.234148 -430.558069)
			(xy 331.27781 -430.509765) (xy 331.302106 -430.48809) (xy 331.382878 -430.323244) (xy 331.387607 -430.312738)
			(xy 331.391089 -430.289973) (xy 331.387591 -430.26721) (xy 331.382878 -430.256696) (xy 331.301852 -430.091596)
			(xy 331.277618 -430.069868) (xy 331.234017 -430.021542) (xy 331.196639 -429.968258) (xy 331.166041 -429.910811)
			(xy 331.142681 -429.85006) (xy 331.126908 -429.786912) (xy 331.118958 -429.722312) (xy 331.118464 -429.689768)
			(xy 331.119156 -429.650641) (xy 331.130636 -429.573235) (xy 331.141324 -429.53559) (xy 331.141324 -429.018954)
			(xy 331.141772 -429.006838) (xy 331.14927 -428.983796) (xy 331.163519 -428.964196) (xy 331.183125 -428.949956)
			(xy 331.20617 -428.942467) (xy 331.218286 -428.941992) (xy 332.158086 -428.941992) (xy 332.170195 -428.942523)
			(xy 332.19323 -428.950001) (xy 332.212828 -428.964229) (xy 332.227072 -428.983816) (xy 332.234568 -429.006845)
			(xy 332.235048 -429.018954) (xy 332.235048 -431.560478) (xy 332.234621 -431.572601) (xy 332.227133 -431.595662)
			(xy 332.212884 -431.615278) (xy 332.193269 -431.62953) (xy 332.170209 -431.63702) (xy 332.158086 -431.63744)
			(xy 331.218286 -431.63744) (xy 331.20616 -431.637051) (xy 331.183097 -431.629553) (xy 331.163481 -431.615294)
			(xy 331.149231 -431.59567) (xy 331.141743 -431.572604) (xy 331.141324 -431.560478) (xy 331.141324 -431.044096)
			(xy 331.130641 -431.00645) (xy 331.119161 -430.929044) (xy 331.118464 -430.889918) (xy 329.2348 -430.889918)
			(xy 329.2348 -431.889916) (xy 333.11846 -431.889916) (xy 333.118964 -431.85736) (xy 333.126908 -431.792735)
			(xy 333.142691 -431.729565) (xy 333.166077 -431.668798) (xy 333.196715 -431.611345) (xy 333.234145 -431.558067)
			(xy 333.277806 -431.509763) (xy 333.302102 -431.488088) (xy 333.382874 -431.323242) (xy 333.387605 -431.312737)
			(xy 333.391086 -431.289971) (xy 333.387587 -431.267208) (xy 333.382874 -431.256694) (xy 333.301848 -431.091594)
			(xy 333.277612 -431.069868) (xy 333.234012 -431.021542) (xy 333.196633 -430.968257) (xy 333.166036 -430.91081)
			(xy 333.142676 -430.850058) (xy 333.126904 -430.78691) (xy 333.118954 -430.72231) (xy 333.11846 -430.689766)
			(xy 333.119152 -430.650639) (xy 333.130632 -430.573233) (xy 333.14132 -430.535588) (xy 333.14132 -430.018952)
			(xy 333.141676 -430.006839) (xy 333.149191 -429.983806) (xy 333.163467 -429.964232) (xy 333.183103 -429.95004)
			(xy 333.206167 -429.942624) (xy 333.218282 -429.942244) (xy 334.158082 -429.942244) (xy 334.170171 -429.942723)
			(xy 334.193172 -429.950175) (xy 334.212752 -429.964358) (xy 334.227003 -429.98389) (xy 334.234535 -430.006865)
			(xy 334.235044 -430.018952) (xy 334.235044 -430.889918) (xy 335.118456 -430.889918) (xy 335.118963 -430.857362)
			(xy 335.126906 -430.792737) (xy 335.142689 -430.729567) (xy 335.166075 -430.6688) (xy 335.196712 -430.611347)
			(xy 335.234141 -430.558069) (xy 335.277802 -430.509765) (xy 335.302098 -430.48809) (xy 335.38287 -430.323244)
			(xy 335.3876 -430.312738) (xy 335.391082 -430.289973) (xy 335.387583 -430.26721) (xy 335.38287 -430.256696)
			(xy 335.301844 -430.091596) (xy 335.277609 -430.06987) (xy 335.234008 -430.021544) (xy 335.19663 -429.968259)
			(xy 335.166032 -429.910811) (xy 335.142673 -429.85006) (xy 335.1269 -429.786912) (xy 335.11895 -429.722312)
			(xy 335.118456 -429.689768) (xy 335.119148 -429.650641) (xy 335.130628 -429.573235) (xy 335.141316 -429.53559)
			(xy 335.141316 -429.018954) (xy 335.141772 -429.006839) (xy 335.149269 -428.983798) (xy 335.163516 -428.964199)
			(xy 335.18312 -428.949958) (xy 335.206163 -428.942468) (xy 335.218278 -428.941992) (xy 336.158078 -428.941992)
			(xy 336.170187 -428.94253) (xy 336.193222 -428.950005) (xy 336.21282 -428.964232) (xy 336.227064 -428.983817)
			(xy 336.234559 -429.006846) (xy 336.23504 -429.018954) (xy 336.23504 -431.560478) (xy 336.234621 -431.572602)
			(xy 336.227132 -431.595664) (xy 336.212881 -431.615281) (xy 336.193264 -431.629532) (xy 336.170202 -431.637021)
			(xy 336.158078 -431.63744) (xy 335.218278 -431.63744) (xy 335.20616 -431.637007) (xy 335.183112 -431.629511)
			(xy 335.163509 -431.61526) (xy 335.149269 -431.595648) (xy 335.141786 -431.572596) (xy 335.141316 -431.560478)
			(xy 335.141316 -431.044096) (xy 335.130633 -431.00645) (xy 335.119153 -430.929044) (xy 335.118456 -430.889918)
			(xy 334.235044 -430.889918) (xy 334.235044 -431.889916) (xy 337.118452 -431.889916) (xy 337.118959 -431.85736)
			(xy 337.126903 -431.792735) (xy 337.142686 -431.729565) (xy 337.166071 -431.668798) (xy 337.196708 -431.611345)
			(xy 337.234138 -431.558067) (xy 337.277798 -431.509764) (xy 337.302094 -431.488088) (xy 337.382866 -431.323242)
			(xy 337.387592 -431.312736) (xy 337.391069 -431.289971) (xy 337.387575 -431.267209) (xy 337.382866 -431.256694)
			(xy 337.30184 -431.091594) (xy 337.277603 -431.06987) (xy 337.234003 -431.021543) (xy 337.196624 -430.968258)
			(xy 337.166027 -430.91081) (xy 337.142668 -430.850058) (xy 337.126896 -430.78691) (xy 337.118946 -430.72231)
			(xy 337.118452 -430.689766) (xy 337.119144 -430.650639) (xy 337.130624 -430.573233) (xy 337.141312 -430.535588)
			(xy 337.141312 -430.018952) (xy 337.141676 -430.006839) (xy 337.14919 -429.983809) (xy 337.163465 -429.964235)
			(xy 337.183098 -429.950043) (xy 337.20616 -429.942625) (xy 337.218274 -429.942244) (xy 338.158074 -429.942244)
			(xy 338.170163 -429.94273) (xy 338.193163 -429.95018) (xy 338.212744 -429.964361) (xy 338.226995 -429.983891)
			(xy 338.234527 -430.006865) (xy 338.235036 -430.018952) (xy 338.235036 -430.889918) (xy 339.118448 -430.889918)
			(xy 339.118957 -430.857362) (xy 339.126901 -430.792737) (xy 339.142684 -430.729568) (xy 339.166069 -430.668801)
			(xy 339.196705 -430.611348) (xy 339.234134 -430.55807) (xy 339.277794 -430.509766) (xy 339.30209 -430.48809)
			(xy 339.382862 -430.323244) (xy 339.387587 -430.312737) (xy 339.391065 -430.289973) (xy 339.387571 -430.267211)
			(xy 339.382862 -430.256696) (xy 339.301836 -430.091596) (xy 339.277599 -430.069871) (xy 339.233999 -430.021545)
			(xy 339.196621 -429.96826) (xy 339.166024 -429.910812) (xy 339.142664 -429.85006) (xy 339.126892 -429.786912)
			(xy 339.118942 -429.722312) (xy 339.118448 -429.689768) (xy 339.119141 -429.650641) (xy 339.13062 -429.573235)
			(xy 339.141308 -429.53559) (xy 339.141308 -429.018954) (xy 339.141772 -429.00684) (xy 339.149268 -428.9838)
			(xy 339.163513 -428.964202) (xy 339.183115 -428.949961) (xy 339.206156 -428.94247) (xy 339.21827 -428.941992)
			(xy 340.15807 -428.941992) (xy 340.170178 -428.942537) (xy 340.193213 -428.95001) (xy 340.212811 -428.964235)
			(xy 340.227055 -428.983819) (xy 340.234551 -429.006846) (xy 340.235032 -429.018954) (xy 340.235032 -431.560478)
			(xy 340.234621 -431.572603) (xy 340.227131 -431.595666) (xy 340.212878 -431.615284) (xy 340.193259 -431.629535)
			(xy 340.170195 -431.637022) (xy 340.15807 -431.63744) (xy 339.21827 -431.63744) (xy 339.206152 -431.637014)
			(xy 339.183104 -431.629515) (xy 339.163501 -431.615262) (xy 339.149261 -431.59565) (xy 339.141778 -431.572597)
			(xy 339.141308 -431.560478) (xy 339.141308 -431.044096) (xy 339.130624 -431.00645) (xy 339.119145 -430.929044)
			(xy 339.118448 -430.889918) (xy 338.235036 -430.889918) (xy 338.235036 -431.889916) (xy 341.118444 -431.889916)
			(xy 341.118953 -431.85736) (xy 341.126897 -431.792735) (xy 341.14268 -431.729566) (xy 341.166065 -431.668799)
			(xy 341.196702 -431.611346) (xy 341.23413 -431.558068) (xy 341.27779 -431.509764) (xy 341.302086 -431.488088)
			(xy 341.382858 -431.323242) (xy 341.387585 -431.312736) (xy 341.391062 -431.289971) (xy 341.387567 -431.267209)
			(xy 341.382858 -431.256694) (xy 341.301832 -431.091594) (xy 341.277593 -431.069871) (xy 341.233993 -431.021544)
			(xy 341.196616 -430.968259) (xy 341.166019 -430.910811) (xy 341.14266 -430.850059) (xy 341.126887 -430.786911)
			(xy 341.118938 -430.72231) (xy 341.118444 -430.689766) (xy 341.119136 -430.650639) (xy 341.130616 -430.573233)
			(xy 341.141304 -430.535588) (xy 341.141304 -430.018952) (xy 341.141676 -430.00684) (xy 341.149189 -429.983811)
			(xy 341.163462 -429.964238) (xy 341.183093 -429.950045) (xy 341.206153 -429.942626) (xy 341.218266 -429.942244)
			(xy 342.158066 -429.942244) (xy 342.170154 -429.942736) (xy 342.193154 -429.950184) (xy 342.212735 -429.964364)
			(xy 342.226987 -429.983893) (xy 342.234519 -430.006866) (xy 342.235028 -430.018952) (xy 342.235028 -430.889918)
			(xy 343.11844 -430.889918) (xy 343.118952 -430.857362) (xy 343.126896 -430.792738) (xy 343.142678 -430.729568)
			(xy 343.166063 -430.668801) (xy 343.196699 -430.611348) (xy 343.234127 -430.55807) (xy 343.277787 -430.509766)
			(xy 343.302082 -430.48809) (xy 343.382854 -430.323244) (xy 343.387579 -430.312737) (xy 343.391058 -430.289973)
			(xy 343.387563 -430.267211) (xy 343.382854 -430.256696) (xy 343.301828 -430.091596) (xy 343.277589 -430.069873)
			(xy 343.23399 -430.021546) (xy 343.196612 -429.968261) (xy 343.166015 -429.910813) (xy 343.142656 -429.850061)
			(xy 343.126884 -429.786913) (xy 343.118934 -429.722312) (xy 343.11844 -429.689768) (xy 343.119133 -429.650641)
			(xy 343.130612 -429.573235) (xy 343.1413 -429.53559) (xy 343.1413 -429.018954) (xy 343.141772 -429.006841)
			(xy 343.149267 -428.983803) (xy 343.163511 -428.964205) (xy 343.18311 -428.949964) (xy 343.206149 -428.942471)
			(xy 343.218262 -428.941992) (xy 344.158062 -428.941992) (xy 344.17017 -428.942543) (xy 344.193204 -428.950015)
			(xy 344.212803 -428.964238) (xy 344.227047 -428.98382) (xy 344.234543 -429.006847) (xy 344.235024 -429.018954)
			(xy 344.235024 -431.560478) (xy 344.234621 -431.572603) (xy 344.22713 -431.595668) (xy 344.212875 -431.615287)
			(xy 344.193254 -431.629537) (xy 344.170187 -431.637023) (xy 344.158062 -431.63744) (xy 343.218262 -431.63744)
			(xy 343.206143 -431.63702) (xy 343.183095 -431.62952) (xy 343.163492 -431.615265) (xy 343.149253 -431.595651)
			(xy 343.14177 -431.572597) (xy 343.1413 -431.560478) (xy 343.1413 -431.044096) (xy 343.130616 -431.00645)
			(xy 343.119137 -430.929044) (xy 343.11844 -430.889918) (xy 342.235028 -430.889918) (xy 342.235028 -431.889916)
			(xy 345.118436 -431.889916) (xy 345.118948 -431.85736) (xy 345.126892 -431.792736) (xy 345.142674 -431.729566)
			(xy 345.166059 -431.6688) (xy 345.196695 -431.611346) (xy 345.234123 -431.558068) (xy 345.277783 -431.509764)
			(xy 345.302078 -431.488088) (xy 345.38285 -431.323242) (xy 345.387577 -431.312736) (xy 345.391055 -431.289971)
			(xy 345.38756 -431.267209) (xy 345.38285 -431.256694) (xy 345.301824 -431.091594) (xy 345.277584 -431.069873)
			(xy 345.233984 -431.021546) (xy 345.196607 -430.96826) (xy 345.16601 -430.910811) (xy 345.142651 -430.850059)
			(xy 345.126879 -430.786911) (xy 345.11893 -430.72231) (xy 345.118436 -430.689766) (xy 345.119129 -430.650639)
			(xy 345.130608 -430.573233) (xy 345.141296 -430.535588) (xy 345.141296 -430.018952) (xy 345.141676 -430.006841)
			(xy 345.149188 -429.983813) (xy 345.163459 -429.964241) (xy 345.183088 -429.950048) (xy 345.206145 -429.942628)
			(xy 345.218258 -429.942244) (xy 346.158058 -429.942244) (xy 346.170146 -429.942743) (xy 346.193146 -429.950189)
			(xy 346.212727 -429.964367) (xy 346.226979 -429.983894) (xy 346.234511 -430.006866) (xy 346.23502 -430.018952)
			(xy 346.23502 -431.359818) (xy 356.154736 -431.359818) (xy 356.155234 -431.274938) (xy 356.163191 -431.105365)
			(xy 356.179087 -430.936351) (xy 356.202888 -430.768268) (xy 356.234542 -430.601485) (xy 356.273978 -430.436369)
			(xy 356.32111 -430.273284) (xy 356.375834 -430.112586) (xy 356.438031 -429.954631) (xy 356.507563 -429.799764)
			(xy 356.584278 -429.648327) (xy 356.668006 -429.500651) (xy 356.758564 -429.357063) (xy 356.855753 -429.217877)
			(xy 356.95936 -429.0834) (xy 357.069155 -428.953927) (xy 357.184899 -428.829742) (xy 357.306336 -428.711119)
			(xy 357.4332 -428.598318) (xy 357.565211 -428.491588) (xy 357.702081 -428.391163) (xy 357.843506 -428.297264)
			(xy 357.989178 -428.210096) (xy 358.138776 -428.129853) (xy 358.29197 -428.056709) (xy 358.448424 -427.990827)
			(xy 358.607794 -427.93235) (xy 358.76973 -427.881408) (xy 358.933876 -427.838112) (xy 359.099871 -427.802557)
			(xy 359.26735 -427.774822) (xy 359.435945 -427.754968) (xy 359.605285 -427.743038) (xy 359.774998 -427.739059)
			(xy 359.944711 -427.743038) (xy 360.114051 -427.754968) (xy 360.282646 -427.774822) (xy 360.450125 -427.802557)
			(xy 360.61612 -427.838112) (xy 360.780266 -427.881408) (xy 360.942202 -427.93235) (xy 361.101572 -427.990827)
			(xy 361.258026 -428.056709) (xy 361.41122 -428.129853) (xy 361.560818 -428.210096) (xy 361.693883 -428.28972)
			(xy 383.218436 -428.28972) (xy 383.218959 -428.25714) (xy 383.226931 -428.19247) (xy 383.242746 -428.129258)
			(xy 383.266166 -428.068452) (xy 383.296841 -428.010965) (xy 383.334311 -427.957656) (xy 383.378014 -427.909325)
			(xy 383.402332 -427.887638) (xy 383.48285 -427.7233) (xy 383.487537 -427.712778) (xy 383.491029 -427.690023)
			(xy 383.487551 -427.667267) (xy 383.48285 -427.656752) (xy 383.401824 -427.491652) (xy 383.377563 -427.469953)
			(xy 383.333965 -427.421622) (xy 383.29659 -427.368332) (xy 383.265996 -427.31088) (xy 383.24264 -427.250124)
			(xy 383.226872 -427.186973) (xy 383.218927 -427.122369) (xy 383.218436 -427.089824) (xy 383.219141 -427.050698)
			(xy 383.230612 -426.973291) (xy 383.241296 -426.935646) (xy 383.241296 -426.41901) (xy 383.24182 -426.4069)
			(xy 383.249299 -426.383864) (xy 383.263529 -426.364266) (xy 383.283118 -426.350023) (xy 383.306148 -426.342528)
			(xy 383.318258 -426.342048) (xy 384.258058 -426.342048) (xy 384.27018 -426.342496) (xy 384.293239 -426.349978)
			(xy 384.312855 -426.364222) (xy 384.327108 -426.383833) (xy 384.334599 -426.406889) (xy 384.33502 -426.41901)
			(xy 384.33502 -427.289976) (xy 385.218432 -427.289976) (xy 385.218917 -427.25742) (xy 385.226866 -427.192794)
			(xy 385.242653 -427.129624) (xy 385.266042 -427.068857) (xy 385.296682 -427.011404) (xy 385.334114 -426.958126)
			(xy 385.377777 -426.909823) (xy 385.402074 -426.888148) (xy 385.482846 -426.723302) (xy 385.487532 -426.71278)
			(xy 385.491025 -426.690025) (xy 385.487547 -426.667269) (xy 385.482846 -426.656754) (xy 385.40182 -426.491654)
			(xy 385.377559 -426.469955) (xy 385.333961 -426.421623) (xy 385.296586 -426.368334) (xy 385.265992 -426.310881)
			(xy 385.242637 -426.250126) (xy 385.226869 -426.186974) (xy 385.218924 -426.122371) (xy 385.218432 -426.089826)
			(xy 385.219138 -426.0507) (xy 385.230609 -425.973294) (xy 385.241292 -425.935648) (xy 385.241292 -425.419012)
			(xy 385.241727 -425.406905) (xy 385.249222 -425.383879) (xy 385.263479 -425.364307) (xy 385.283096 -425.350111)
			(xy 385.306145 -425.342689) (xy 385.318254 -425.342304) (xy 386.258054 -425.342304) (xy 386.270138 -425.342846)
			(xy 386.293131 -425.350286) (xy 386.312708 -425.364454) (xy 386.326962 -425.38397) (xy 386.334501 -425.40693)
			(xy 386.335016 -425.419012) (xy 386.335016 -427.960536) (xy 386.334615 -427.972645) (xy 386.327107 -427.995671)
			(xy 386.312841 -428.015242) (xy 386.293218 -428.029436) (xy 386.270165 -428.036859) (xy 386.258054 -428.037244)
			(xy 385.318254 -428.037244) (xy 385.30616 -428.036832) (xy 385.283156 -428.02936) (xy 385.263575 -428.01516)
			(xy 385.249327 -427.995615) (xy 385.241799 -427.972628) (xy 385.241292 -427.960536) (xy 385.241292 -427.444154)
			(xy 385.230599 -427.40651) (xy 385.219126 -427.329103) (xy 385.218432 -427.289976) (xy 384.33502 -427.289976)
			(xy 384.33502 -428.28972) (xy 387.218428 -428.28972) (xy 387.218954 -428.25714) (xy 387.226926 -428.19247)
			(xy 387.24274 -428.129258) (xy 387.26616 -428.068453) (xy 387.296834 -428.010965) (xy 387.334304 -427.957656)
			(xy 387.378006 -427.909325) (xy 387.402324 -427.887638) (xy 387.482842 -427.7233) (xy 387.487529 -427.712778)
			(xy 387.491022 -427.690023) (xy 387.487543 -427.667267) (xy 387.482842 -427.656752) (xy 387.401816 -427.491652)
			(xy 387.377554 -427.469955) (xy 387.333956 -427.421623) (xy 387.296581 -427.368333) (xy 387.265987 -427.31088)
			(xy 387.242632 -427.250124) (xy 387.226864 -427.186973) (xy 387.218919 -427.122369) (xy 387.218428 -427.089824)
			(xy 387.219133 -427.050698) (xy 387.230604 -426.973292) (xy 387.241288 -426.935646) (xy 387.241288 -426.41901)
			(xy 387.24182 -426.406901) (xy 387.249298 -426.383867) (xy 387.263526 -426.364269) (xy 387.283113 -426.350025)
			(xy 387.306141 -426.342529) (xy 387.31825 -426.342048) (xy 388.25805 -426.342048) (xy 388.270168 -426.342469)
			(xy 388.293215 -426.349972) (xy 388.312816 -426.364226) (xy 388.327056 -426.383839) (xy 388.33454 -426.406891)
			(xy 388.335012 -426.41901) (xy 388.335012 -427.289976) (xy 389.218424 -427.289976) (xy 389.218912 -427.25742)
			(xy 389.22686 -427.192794) (xy 389.242647 -427.129624) (xy 389.266036 -427.068858) (xy 389.296675 -427.011405)
			(xy 389.334107 -426.958127) (xy 389.377769 -426.909823) (xy 389.402066 -426.888148) (xy 389.482838 -426.723302)
			(xy 389.487524 -426.71278) (xy 389.491018 -426.690025) (xy 389.487539 -426.667268) (xy 389.482838 -426.656754)
			(xy 389.401812 -426.491654) (xy 389.37755 -426.469957) (xy 389.333952 -426.421625) (xy 389.296577 -426.368334)
			(xy 389.265984 -426.310882) (xy 389.242628 -426.250126) (xy 389.22686 -426.186975) (xy 389.218916 -426.122371)
			(xy 389.218424 -426.089826) (xy 389.21913 -426.0507) (xy 389.230601 -425.973294) (xy 389.241284 -425.935648)
			(xy 389.241284 -425.419012) (xy 389.241727 -425.406905) (xy 389.249221 -425.383881) (xy 389.263476 -425.364309)
			(xy 389.283091 -425.350114) (xy 389.306138 -425.34269) (xy 389.318246 -425.342304) (xy 390.258046 -425.342304)
			(xy 390.270134 -425.342767) (xy 390.29313 -425.350232) (xy 390.312707 -425.364421) (xy 390.326957 -425.383953)
			(xy 390.334494 -425.406925) (xy 390.335008 -425.419012) (xy 390.335008 -427.960536) (xy 390.334614 -427.972646)
			(xy 390.327106 -427.995673) (xy 390.312838 -428.015245) (xy 390.293213 -428.029438) (xy 390.270157 -428.03686)
			(xy 390.258046 -428.037244) (xy 389.318246 -428.037244) (xy 389.306157 -428.036753) (xy 389.283155 -428.029307)
			(xy 389.263573 -428.015127) (xy 389.249322 -427.995597) (xy 389.241791 -427.972623) (xy 389.241284 -427.960536)
			(xy 389.241284 -427.444154) (xy 389.230591 -427.406511) (xy 389.219118 -427.329103) (xy 389.218424 -427.289976)
			(xy 388.335012 -427.289976) (xy 388.335012 -428.28972) (xy 391.21842 -428.28972) (xy 391.218948 -428.25714)
			(xy 391.22692 -428.19247) (xy 391.242734 -428.129259) (xy 391.266154 -428.068454) (xy 391.296828 -428.010966)
			(xy 391.334297 -427.957657) (xy 391.377999 -427.909325) (xy 391.402316 -427.887638) (xy 391.482834 -427.7233)
			(xy 391.487522 -427.712778) (xy 391.491015 -427.690023) (xy 391.487536 -427.667266) (xy 391.482834 -427.656752)
			(xy 391.401808 -427.491652) (xy 391.377544 -427.469957) (xy 391.333947 -427.421624) (xy 391.296572 -427.368334)
			(xy 391.265979 -427.310881) (xy 391.242624 -427.250125) (xy 391.226856 -427.186973) (xy 391.218911 -427.122369)
			(xy 391.21842 -427.089824) (xy 391.219126 -427.050698) (xy 391.230597 -426.973292) (xy 391.24128 -426.935646)
			(xy 391.24128 -426.41901) (xy 391.241669 -426.406884) (xy 391.249164 -426.383818) (xy 391.263422 -426.364199)
			(xy 391.283047 -426.349949) (xy 391.306115 -426.342464) (xy 391.318242 -426.342048) (xy 392.258042 -426.342048)
			(xy 392.27016 -426.342476) (xy 392.293206 -426.349976) (xy 392.312808 -426.364229) (xy 392.327048 -426.383841)
			(xy 392.334532 -426.406892) (xy 392.335004 -426.41901) (xy 392.335004 -427.289976) (xy 393.218416 -427.289976)
			(xy 393.218907 -427.25742) (xy 393.226855 -427.192794) (xy 393.242641 -427.129625) (xy 393.26603 -427.068858)
			(xy 393.296669 -427.011405) (xy 393.3341 -426.958127) (xy 393.377761 -426.909823) (xy 393.402058 -426.888148)
			(xy 393.48283 -426.723302) (xy 393.487517 -426.71278) (xy 393.49101 -426.690025) (xy 393.487532 -426.667268)
			(xy 393.48283 -426.656754) (xy 393.401804 -426.491654) (xy 393.37754 -426.469959) (xy 393.333943 -426.421626)
			(xy 393.296568 -426.368335) (xy 393.265975 -426.310883) (xy 393.24262 -426.250127) (xy 393.226852 -426.186975)
			(xy 393.218908 -426.122371) (xy 393.218416 -426.089826) (xy 393.219118 -426.0507) (xy 393.230591 -425.973293)
			(xy 393.241276 -425.935648) (xy 393.241276 -425.419012) (xy 393.241726 -425.406906) (xy 393.24922 -425.383883)
			(xy 393.263473 -425.364312) (xy 393.283086 -425.350116) (xy 393.306131 -425.342691) (xy 393.318238 -425.342304)
			(xy 394.258038 -425.342304) (xy 394.270126 -425.342774) (xy 394.293122 -425.350237) (xy 394.312698 -425.364424)
			(xy 394.326949 -425.383954) (xy 394.334486 -425.406926) (xy 394.335 -425.419012) (xy 394.335 -427.960536)
			(xy 394.334614 -427.972647) (xy 394.327105 -427.995675) (xy 394.312835 -428.015248) (xy 394.293208 -428.029441)
			(xy 394.27015 -428.036861) (xy 394.258038 -428.037244) (xy 393.318238 -428.037244) (xy 393.306149 -428.03676)
			(xy 393.283147 -428.029312) (xy 393.263565 -428.01513) (xy 393.249314 -427.995599) (xy 393.241783 -427.972623)
			(xy 393.241276 -427.960536) (xy 393.241276 -427.444154) (xy 393.230583 -427.406511) (xy 393.21911 -427.329103)
			(xy 393.218416 -427.289976) (xy 392.335004 -427.289976) (xy 392.335004 -428.28972) (xy 395.218412 -428.28972)
			(xy 395.218943 -428.25714) (xy 395.226915 -428.192471) (xy 395.242729 -428.129259) (xy 395.266148 -428.068454)
			(xy 395.296821 -428.010966) (xy 395.33429 -427.957657) (xy 395.377991 -427.909326) (xy 395.402308 -427.887638)
			(xy 395.482826 -427.7233) (xy 395.487514 -427.712778) (xy 395.491008 -427.690023) (xy 395.487528 -427.667266)
			(xy 395.482826 -427.656752) (xy 395.4018 -427.491652) (xy 395.377534 -427.469959) (xy 395.333937 -427.421626)
			(xy 395.296563 -427.368334) (xy 395.26597 -427.310881) (xy 395.242615 -427.250125) (xy 395.226848 -427.186973)
			(xy 395.218903 -427.122369) (xy 395.218412 -427.089824) (xy 395.219114 -427.050698) (xy 395.230587 -426.973291)
			(xy 395.241272 -426.935646) (xy 395.241272 -426.41901) (xy 395.241669 -426.406884) (xy 395.249163 -426.38382)
			(xy 395.263419 -426.364202) (xy 395.283042 -426.349952) (xy 395.306108 -426.342465) (xy 395.318234 -426.342048)
			(xy 396.258034 -426.342048) (xy 396.270151 -426.342483) (xy 396.293197 -426.349981) (xy 396.312799 -426.364232)
			(xy 396.327039 -426.383842) (xy 396.334524 -426.406892) (xy 396.334996 -426.41901) (xy 396.334996 -427.289976)
			(xy 398.218406 -427.289976) (xy 398.2189 -427.25742) (xy 398.226848 -427.192795) (xy 398.242634 -427.129626)
			(xy 398.266022 -427.068859) (xy 398.296661 -427.011406) (xy 398.334091 -426.958128) (xy 398.377752 -426.909824)
			(xy 398.402048 -426.888148) (xy 398.48282 -426.723302) (xy 398.487507 -426.71278) (xy 398.491001 -426.690025)
			(xy 398.487522 -426.667268) (xy 398.48282 -426.656754) (xy 398.401794 -426.491654) (xy 398.377528 -426.469961)
			(xy 398.333931 -426.421628) (xy 398.296557 -426.368336) (xy 398.265964 -426.310883) (xy 398.24261 -426.250127)
			(xy 398.226842 -426.186975) (xy 398.218898 -426.122371) (xy 398.218406 -426.089826) (xy 398.219125 -426.050501)
			(xy 398.230735 -425.972711) (xy 398.24152 -425.934886) (xy 398.24152 -425.419012) (xy 398.241924 -425.406927)
			(xy 398.249391 -425.38394) (xy 398.263599 -425.364387) (xy 398.283154 -425.350184) (xy 398.306143 -425.342721)
			(xy 398.318228 -425.342304) (xy 399.258028 -425.342304) (xy 399.270105 -425.34274) (xy 399.293075 -425.350212)
			(xy 399.312613 -425.364415) (xy 399.326806 -425.38396) (xy 399.334266 -425.406935) (xy 399.334736 -425.419012)
			(xy 399.334736 -427.960536) (xy 399.334267 -427.97261) (xy 399.326798 -427.995573) (xy 399.312602 -428.015107)
			(xy 399.293066 -428.029302) (xy 399.270102 -428.036768) (xy 399.258028 -428.037244) (xy 398.318228 -428.037244)
			(xy 398.306158 -428.036713) (xy 398.283198 -428.029262) (xy 398.263664 -428.015082) (xy 398.249467 -427.995559)
			(xy 398.241997 -427.972605) (xy 398.24152 -427.960536) (xy 398.24152 -427.444916) (xy 398.230716 -427.407096)
			(xy 398.219113 -427.329303) (xy 398.218406 -427.289976) (xy 396.334996 -427.289976) (xy 396.334996 -428.28972)
			(xy 400.218402 -428.28972) (xy 400.218937 -428.257141) (xy 400.226908 -428.192471) (xy 400.242722 -428.12926)
			(xy 400.26614 -428.068455) (xy 400.296813 -428.010967) (xy 400.334281 -427.957658) (xy 400.377981 -427.909326)
			(xy 400.402298 -427.887638) (xy 400.482816 -427.7233) (xy 400.487504 -427.712778) (xy 400.490998 -427.690023)
			(xy 400.487518 -427.667266) (xy 400.482816 -427.656752) (xy 400.40179 -427.491652) (xy 400.377522 -427.469961)
			(xy 400.333926 -427.421627) (xy 400.296552 -427.368335) (xy 400.265959 -427.310882) (xy 400.242605 -427.250125)
			(xy 400.226838 -427.186973) (xy 400.218893 -427.122369) (xy 400.218402 -427.089824) (xy 400.21912 -427.050499)
			(xy 400.230731 -426.972709) (xy 400.241516 -426.934884) (xy 400.241516 -426.41901) (xy 400.242016 -426.406923)
			(xy 400.249467 -426.383927) (xy 400.263646 -426.364349) (xy 400.283171 -426.350097) (xy 400.306139 -426.342561)
			(xy 400.318224 -426.342048) (xy 401.258024 -426.342048) (xy 401.270129 -426.342495) (xy 401.293148 -426.349995)
			(xy 401.312716 -426.36425) (xy 401.326912 -426.383862) (xy 401.334341 -426.406904) (xy 401.334732 -426.41901)
			(xy 401.334732 -427.289976) (xy 402.218398 -427.289976) (xy 402.218895 -427.25742) (xy 402.226843 -427.192795)
			(xy 402.242629 -427.129626) (xy 402.266016 -427.068859) (xy 402.296654 -427.011407) (xy 402.334084 -426.958128)
			(xy 402.377744 -426.909824) (xy 402.40204 -426.888148) (xy 402.482812 -426.723302) (xy 402.487499 -426.71278)
			(xy 402.490994 -426.690025) (xy 402.487514 -426.667268) (xy 402.482812 -426.656754) (xy 402.401786 -426.491654)
			(xy 402.377518 -426.469963) (xy 402.333922 -426.421629) (xy 402.296548 -426.368337) (xy 402.265956 -426.310884)
			(xy 402.242601 -426.250127) (xy 402.226834 -426.186975) (xy 402.21889 -426.122371) (xy 402.218398 -426.089826)
			(xy 402.219117 -426.050501) (xy 402.230727 -425.972711) (xy 402.241512 -425.934886) (xy 402.241512 -425.419012)
			(xy 402.241923 -425.406928) (xy 402.24939 -425.383942) (xy 402.263596 -425.36439) (xy 402.283149 -425.350186)
			(xy 402.306136 -425.342722) (xy 402.31822 -425.342304) (xy 403.25802 -425.342304) (xy 403.270097 -425.342748)
			(xy 403.293067 -425.350217) (xy 403.312604 -425.364419) (xy 403.326798 -425.383962) (xy 403.334257 -425.406935)
			(xy 403.334728 -425.419012) (xy 403.334728 -427.960536) (xy 403.334267 -427.97261) (xy 403.326797 -427.995576)
			(xy 403.312599 -428.01511) (xy 403.293061 -428.029304) (xy 403.270095 -428.036769) (xy 403.25802 -428.037244)
			(xy 402.31822 -428.037244) (xy 402.30615 -428.036719) (xy 402.28319 -428.029267) (xy 402.263655 -428.015085)
			(xy 402.249459 -427.995561) (xy 402.241989 -427.972606) (xy 402.241512 -427.960536) (xy 402.241512 -427.444916)
			(xy 402.230708 -427.407096) (xy 402.219105 -427.329303) (xy 402.218398 -427.289976) (xy 401.334732 -427.289976)
			(xy 401.334732 -428.28972) (xy 404.218394 -428.28972) (xy 404.218931 -428.257141) (xy 404.226902 -428.192471)
			(xy 404.242715 -428.12926) (xy 404.266134 -428.068455) (xy 404.296806 -428.010967) (xy 404.334273 -427.957658)
			(xy 404.377973 -427.909326) (xy 404.40229 -427.887638) (xy 404.482808 -427.7233) (xy 404.487497 -427.712779)
			(xy 404.490991 -427.690023) (xy 404.487511 -427.667266) (xy 404.482808 -427.656752) (xy 404.401782 -427.491652)
			(xy 404.377513 -427.469963) (xy 404.333917 -427.421628) (xy 404.296543 -427.368336) (xy 404.265951 -427.310883)
			(xy 404.242597 -427.250126) (xy 404.22683 -427.186974) (xy 404.218885 -427.122369) (xy 404.218394 -427.089824)
			(xy 404.219113 -427.050499) (xy 404.230723 -426.972709) (xy 404.241508 -426.934884) (xy 404.241508 -426.41901)
			(xy 404.242015 -426.406924) (xy 404.249465 -426.383929) (xy 404.263643 -426.364352) (xy 404.283166 -426.3501)
			(xy 404.306132 -426.342562) (xy 404.318216 -426.342048) (xy 405.258016 -426.342048) (xy 405.270121 -426.342502)
			(xy 405.293139 -426.349999) (xy 405.312708 -426.364253) (xy 405.326904 -426.383863) (xy 405.334333 -426.406904)
			(xy 405.334724 -426.41901) (xy 405.334724 -427.289976) (xy 406.21839 -427.289976) (xy 406.218856 -427.257419)
			(xy 406.226805 -427.192792) (xy 406.242594 -427.129621) (xy 406.265986 -427.068853) (xy 406.296629 -427.0114)
			(xy 406.334066 -426.958124) (xy 406.377733 -426.909822) (xy 406.402032 -426.888148) (xy 406.482804 -426.723302)
			(xy 406.487492 -426.71278) (xy 406.490987 -426.690025) (xy 406.487507 -426.667268) (xy 406.482804 -426.656754)
			(xy 406.401778 -426.491654) (xy 406.377509 -426.469964) (xy 406.333913 -426.42163) (xy 406.29654 -426.368338)
			(xy 406.265947 -426.310884) (xy 406.242593 -426.250128) (xy 406.226826 -426.186975) (xy 406.218882 -426.122371)
			(xy 406.21839 -426.089826) (xy 406.219109 -426.050501) (xy 406.23072 -425.972711) (xy 406.241504 -425.934886)
			(xy 406.241504 -425.419012) (xy 406.241923 -425.406929) (xy 406.249389 -425.383944) (xy 406.263593 -425.364393)
			(xy 406.283144 -425.350189) (xy 406.306129 -425.342723) (xy 406.318212 -425.342304) (xy 407.258012 -425.342304)
			(xy 407.270088 -425.342754) (xy 407.293058 -425.350222) (xy 407.312596 -425.364421) (xy 407.326789 -425.383964)
			(xy 407.334249 -425.406935) (xy 407.33472 -425.419012) (xy 407.33472 -427.960536) (xy 407.334267 -427.972611)
			(xy 407.326796 -427.995578) (xy 407.312596 -428.015113) (xy 407.293056 -428.029307) (xy 407.270087 -428.036771)
			(xy 407.258012 -428.037244) (xy 406.318212 -428.037244) (xy 406.306142 -428.036726) (xy 406.283181 -428.029271)
			(xy 406.263647 -428.015087) (xy 406.249451 -427.995562) (xy 406.241981 -427.972606) (xy 406.241504 -427.960536)
			(xy 406.241504 -427.444916) (xy 406.2307 -427.407096) (xy 406.219097 -427.329303) (xy 406.21839 -427.289976)
			(xy 405.334724 -427.289976) (xy 405.334724 -428.28972) (xy 408.218386 -428.28972) (xy 408.218926 -428.257141)
			(xy 408.226897 -428.192472) (xy 408.24271 -428.129261) (xy 408.266128 -428.068456) (xy 408.2968 -428.010968)
			(xy 408.334266 -427.957658) (xy 408.377966 -427.909326) (xy 408.402282 -427.887638) (xy 408.4828 -427.7233)
			(xy 408.487489 -427.712779) (xy 408.490984 -427.690023) (xy 408.487503 -427.667266) (xy 408.4828 -427.656752)
			(xy 408.401774 -427.491652) (xy 408.377503 -427.469964) (xy 408.333907 -427.42163) (xy 408.296534 -427.368337)
			(xy 408.265942 -427.310883) (xy 408.242588 -427.250126) (xy 408.226822 -427.186974) (xy 408.218877 -427.122369)
			(xy 408.218386 -427.089824) (xy 408.219105 -427.050499) (xy 408.230716 -426.972709) (xy 408.2415 -426.934884)
			(xy 408.2415 -426.41901) (xy 408.242015 -426.406925) (xy 408.249464 -426.383931) (xy 408.26364 -426.364355)
			(xy 408.283161 -426.350103) (xy 408.306125 -426.342563) (xy 408.318208 -426.342048) (xy 409.258008 -426.342048)
			(xy 409.270112 -426.342509) (xy 409.293131 -426.350004) (xy 409.312699 -426.364256) (xy 409.326896 -426.383865)
			(xy 409.334325 -426.406905) (xy 409.334716 -426.41901) (xy 409.334716 -427.289976) (xy 410.218382 -427.289976)
			(xy 410.218851 -427.257419) (xy 410.2268 -427.192792) (xy 410.242588 -427.129621) (xy 410.26598 -427.068854)
			(xy 410.296623 -427.011401) (xy 410.334059 -426.958124) (xy 410.377725 -426.909822) (xy 410.402024 -426.888148)
			(xy 410.482796 -426.723302) (xy 410.487484 -426.71278) (xy 410.490979 -426.690025) (xy 410.487499 -426.667268)
			(xy 410.482796 -426.656754) (xy 410.40177 -426.491654) (xy 410.377519 -426.469944) (xy 410.333919 -426.421616)
			(xy 410.296541 -426.368328) (xy 410.265945 -426.310878) (xy 410.242588 -426.250124) (xy 410.226819 -426.186973)
			(xy 410.218874 -426.122371) (xy 410.218382 -426.089826) (xy 410.219102 -426.050501) (xy 410.230712 -425.972711)
			(xy 410.241496 -425.934886) (xy 410.241496 -425.419012) (xy 410.241923 -425.40693) (xy 410.249388 -425.383947)
			(xy 410.26359 -425.364396) (xy 410.283139 -425.350191) (xy 410.306122 -425.342724) (xy 410.318204 -425.342304)
			(xy 411.258004 -425.342304) (xy 411.270088 -425.342709) (xy 411.293073 -425.350179) (xy 411.312624 -425.364387)
			(xy 411.326828 -425.383941) (xy 411.334293 -425.406928) (xy 411.334712 -425.419012) (xy 411.334712 -427.960536)
			(xy 411.334267 -427.972612) (xy 411.326795 -427.99558) (xy 411.312593 -428.015116) (xy 411.293051 -428.029309)
			(xy 411.27008 -428.036772) (xy 411.258004 -428.037244) (xy 410.318204 -428.037244) (xy 410.306133 -428.036733)
			(xy 410.283172 -428.029276) (xy 410.263638 -428.01509) (xy 410.249442 -427.995564) (xy 410.241973 -427.972607)
			(xy 410.241496 -427.960536) (xy 410.241496 -427.444916) (xy 410.230692 -427.407096) (xy 410.219088 -427.329303)
			(xy 410.218382 -427.289976) (xy 409.334716 -427.289976) (xy 409.334716 -428.28972) (xy 412.218378 -428.28972)
			(xy 412.21892 -428.257141) (xy 412.226891 -428.192472) (xy 412.242704 -428.129261) (xy 412.266122 -428.068456)
			(xy 412.296793 -428.010968) (xy 412.334259 -427.957659) (xy 412.377958 -427.909326) (xy 412.402274 -427.887638)
			(xy 412.482792 -427.7233) (xy 412.487482 -427.712779) (xy 412.490977 -427.690023) (xy 412.487496 -427.667266)
			(xy 412.482792 -427.656752) (xy 412.401766 -427.491652) (xy 412.377514 -427.469944) (xy 412.333913 -427.421615)
			(xy 412.296536 -427.368327) (xy 412.26594 -427.310877) (xy 412.242584 -427.250122) (xy 412.226815 -427.186972)
			(xy 412.21887 -427.122369) (xy 412.218378 -427.089824) (xy 412.219097 -427.050499) (xy 412.230708 -426.972709)
			(xy 412.241492 -426.934884) (xy 412.241492 -426.41901) (xy 412.242015 -426.406926) (xy 412.249463 -426.383934)
			(xy 412.263637 -426.364358) (xy 412.283156 -426.350105) (xy 412.306118 -426.342564) (xy 412.3182 -426.342048)
			(xy 413.258 -426.342048) (xy 413.270104 -426.342515) (xy 413.293122 -426.350009) (xy 413.312691 -426.364259)
			(xy 413.326887 -426.383866) (xy 413.334317 -426.406905) (xy 413.334708 -426.41901) (xy 413.334708 -428.960534)
			(xy 413.334223 -428.972621) (xy 413.326762 -428.995614) (xy 413.312579 -429.01519) (xy 413.293053 -429.029441)
			(xy 413.270085 -429.03698) (xy 413.258 -429.037496) (xy 412.3182 -429.037496) (xy 412.306091 -429.037084)
			(xy 412.283063 -429.029584) (xy 412.263489 -429.015321) (xy 412.249295 -428.995699) (xy 412.241875 -428.972645)
			(xy 412.241492 -428.960534) (xy 412.241492 -428.44466) (xy 412.230697 -428.406837) (xy 412.219088 -428.329046)
			(xy 412.218378 -428.28972) (xy 409.334716 -428.28972) (xy 409.334716 -428.960534) (xy 409.334321 -428.97263)
			(xy 409.326849 -428.995639) (xy 409.312646 -429.015222) (xy 409.293095 -429.02947) (xy 409.270103 -429.036993)
			(xy 409.258008 -429.037496) (xy 408.318208 -429.037496) (xy 408.306099 -429.037077) (xy 408.283071 -429.029579)
			(xy 408.263498 -429.015319) (xy 408.249303 -428.995697) (xy 408.241883 -428.972644) (xy 408.2415 -428.960534)
			(xy 408.2415 -428.44466) (xy 408.230705 -428.406837) (xy 408.219096 -428.329046) (xy 408.218386 -428.28972)
			(xy 405.334724 -428.28972) (xy 405.334724 -428.960534) (xy 405.334321 -428.972629) (xy 405.326851 -428.995637)
			(xy 405.312649 -429.015219) (xy 405.2931 -429.029467) (xy 405.27011 -429.036992) (xy 405.258016 -429.037496)
			(xy 404.318216 -429.037496) (xy 404.306108 -429.03707) (xy 404.28308 -429.029574) (xy 404.263507 -429.015315)
			(xy 404.249312 -428.995695) (xy 404.241891 -428.972644) (xy 404.241508 -428.960534) (xy 404.241508 -428.44466)
			(xy 404.230713 -428.406837) (xy 404.219104 -428.329046) (xy 404.218394 -428.28972) (xy 401.334732 -428.28972)
			(xy 401.334732 -428.960534) (xy 401.334321 -428.972628) (xy 401.326852 -428.995635) (xy 401.312652 -429.015216)
			(xy 401.293105 -429.029465) (xy 401.270117 -429.036991) (xy 401.258024 -429.037496) (xy 400.318224 -429.037496)
			(xy 400.306116 -429.037063) (xy 400.283089 -429.02957) (xy 400.263515 -429.015313) (xy 400.24932 -428.995694)
			(xy 400.241899 -428.972643) (xy 400.241516 -428.960534) (xy 400.241516 -428.44466) (xy 400.230722 -428.406837)
			(xy 400.219112 -428.329046) (xy 400.218402 -428.28972) (xy 396.334996 -428.28972) (xy 396.334996 -428.960534)
			(xy 396.334518 -428.972647) (xy 396.327025 -428.995686) (xy 396.312784 -429.015284) (xy 396.293186 -429.029525)
			(xy 396.270147 -429.037018) (xy 396.258034 -429.037496) (xy 395.318234 -429.037496) (xy 395.306125 -429.03696)
			(xy 395.283088 -429.029486) (xy 395.263489 -429.01526) (xy 395.249245 -428.995673) (xy 395.241751 -428.972643)
			(xy 395.241272 -428.960534) (xy 395.241272 -428.443898) (xy 395.230588 -428.406252) (xy 395.219109 -428.328846)
			(xy 395.218412 -428.28972) (xy 392.335004 -428.28972) (xy 392.335004 -428.960534) (xy 392.334518 -428.972646)
			(xy 392.327027 -428.995683) (xy 392.312787 -429.015281) (xy 392.293191 -429.029523) (xy 392.270154 -429.037017)
			(xy 392.258042 -429.037496) (xy 391.318242 -429.037496) (xy 391.306125 -429.037005) (xy 391.283073 -429.029528)
			(xy 391.26346 -429.015294) (xy 391.249206 -428.995695) (xy 391.241707 -428.972651) (xy 391.24128 -428.960534)
			(xy 391.24128 -428.443898) (xy 391.230596 -428.406252) (xy 391.219117 -428.328846) (xy 391.21842 -428.28972)
			(xy 388.335012 -428.28972) (xy 388.335012 -428.960534) (xy 388.334518 -428.972645) (xy 388.327028 -428.995681)
			(xy 388.31279 -429.015278) (xy 388.293196 -429.02952) (xy 388.270161 -429.037016) (xy 388.25805 -429.037496)
			(xy 387.31825 -429.037496) (xy 387.306136 -429.037031) (xy 387.283097 -429.029535) (xy 387.263499 -429.015289)
			(xy 387.249258 -428.995689) (xy 387.241766 -428.972648) (xy 387.241288 -428.960534) (xy 387.241288 -428.443898)
			(xy 387.230604 -428.406252) (xy 387.219125 -428.328846) (xy 387.218428 -428.28972) (xy 384.33502 -428.28972)
			(xy 384.33502 -428.960534) (xy 384.334669 -428.972663) (xy 384.327162 -428.99573) (xy 384.312894 -429.015348)
			(xy 384.293262 -429.029597) (xy 384.270187 -429.03708) (xy 384.258058 -429.037496) (xy 383.318258 -429.037496)
			(xy 383.306145 -429.037025) (xy 383.283106 -429.02953) (xy 383.263508 -429.015287) (xy 383.249266 -428.995687)
			(xy 383.241774 -428.972647) (xy 383.241296 -428.960534) (xy 383.241296 -428.443898) (xy 383.230613 -428.406252)
			(xy 383.219133 -428.328846) (xy 383.218436 -428.28972) (xy 361.693883 -428.28972) (xy 361.70649 -428.297264)
			(xy 361.847915 -428.391163) (xy 361.984785 -428.491588) (xy 362.116796 -428.598318) (xy 362.24366 -428.711119)
			(xy 362.365097 -428.829742) (xy 362.480841 -428.953927) (xy 362.590636 -429.0834) (xy 362.694243 -429.217877)
			(xy 362.791432 -429.357063) (xy 362.88199 -429.500651) (xy 362.965718 -429.648327) (xy 363.042433 -429.799764)
			(xy 363.111965 -429.954631) (xy 363.174162 -430.112586) (xy 363.228886 -430.273284) (xy 363.276018 -430.436369)
			(xy 363.315454 -430.601485) (xy 363.347108 -430.768268) (xy 363.364334 -430.889918) (xy 381.237998 -430.889918)
			(xy 381.238092 -430.875344) (xy 381.239744 -430.846243) (xy 381.2413 -430.831752) (xy 381.2413 -429.747934)
			(xy 381.239752 -429.733442) (xy 381.238102 -429.704342) (xy 381.237998 -429.689768) (xy 381.238096 -429.675194)
			(xy 381.239746 -429.646093) (xy 381.2413 -429.631602) (xy 381.2413 -429.018954) (xy 381.241772 -429.006841)
			(xy 381.249267 -428.983803) (xy 381.263511 -428.964205) (xy 381.28311 -428.949964) (xy 381.306149 -428.942471)
			(xy 381.318262 -428.941992) (xy 382.258062 -428.941992) (xy 382.27017 -428.942543) (xy 382.293204 -428.950015)
			(xy 382.312803 -428.964238) (xy 382.327047 -428.98382) (xy 382.334543 -429.006847) (xy 382.335024 -429.018954)
			(xy 382.335024 -431.560478) (xy 382.334621 -431.572603) (xy 382.32713 -431.595668) (xy 382.312875 -431.615287)
			(xy 382.293254 -431.629537) (xy 382.270187 -431.637023) (xy 382.258062 -431.63744) (xy 381.318262 -431.63744)
			(xy 381.306143 -431.63702) (xy 381.283095 -431.62952) (xy 381.263492 -431.615265) (xy 381.249253 -431.595651)
			(xy 381.24177 -431.572597) (xy 381.2413 -431.560478) (xy 381.2413 -430.948084) (xy 381.239756 -430.933592)
			(xy 381.238104 -430.904492) (xy 381.237998 -430.889918) (xy 363.364334 -430.889918) (xy 363.370909 -430.936351)
			(xy 363.386805 -431.105365) (xy 363.394762 -431.274938) (xy 363.39526 -431.359818) (xy 363.39483 -431.445421)
			(xy 363.38674 -431.616436) (xy 363.370574 -431.786877) (xy 363.355859 -431.889916) (xy 383.237994 -431.889916)
			(xy 383.238088 -431.875342) (xy 383.23974 -431.846241) (xy 383.241296 -431.83175) (xy 383.241296 -430.747932)
			(xy 383.239748 -430.73344) (xy 383.238098 -430.70434) (xy 383.237994 -430.689766) (xy 383.238092 -430.675192)
			(xy 383.239742 -430.646091) (xy 383.241296 -430.6316) (xy 383.241296 -430.018952) (xy 383.241676 -430.006841)
			(xy 383.249188 -429.983813) (xy 383.263459 -429.964241) (xy 383.283088 -429.950048) (xy 383.306145 -429.942628)
			(xy 383.318258 -429.942244) (xy 384.258058 -429.942244) (xy 384.270146 -429.942743) (xy 384.293146 -429.950189)
			(xy 384.312727 -429.964367) (xy 384.326979 -429.983894) (xy 384.334511 -430.006866) (xy 384.33502 -430.018952)
			(xy 384.33502 -430.889918) (xy 385.23799 -430.889918) (xy 385.238084 -430.875344) (xy 385.239736 -430.846243)
			(xy 385.241292 -430.831752) (xy 385.241292 -429.747934) (xy 385.239745 -429.733442) (xy 385.238094 -429.704342)
			(xy 385.23799 -429.689768) (xy 385.238088 -429.675194) (xy 385.239738 -429.646093) (xy 385.241292 -429.631602)
			(xy 385.241292 -429.018954) (xy 385.241772 -429.006842) (xy 385.249266 -428.983805) (xy 385.263508 -428.964208)
			(xy 385.283105 -428.949966) (xy 385.306142 -428.942472) (xy 385.318254 -428.941992) (xy 386.258054 -428.941992)
			(xy 386.270162 -428.94255) (xy 386.293196 -428.950019) (xy 386.312794 -428.96424) (xy 386.327039 -428.983822)
			(xy 386.334535 -429.006847) (xy 386.335016 -429.018954) (xy 386.335016 -431.560478) (xy 386.334621 -431.572604)
			(xy 386.327129 -431.59567) (xy 386.312872 -431.61529) (xy 386.293249 -431.62954) (xy 386.27018 -431.637024)
			(xy 386.258054 -431.63744) (xy 385.318254 -431.63744) (xy 385.306135 -431.637027) (xy 385.283086 -431.629525)
			(xy 385.263484 -431.615268) (xy 385.249244 -431.595653) (xy 385.241762 -431.572598) (xy 385.241292 -431.560478)
			(xy 385.241292 -430.948084) (xy 385.239749 -430.933592) (xy 385.238096 -430.904492) (xy 385.23799 -430.889918)
			(xy 384.33502 -430.889918) (xy 384.33502 -431.889916) (xy 387.237986 -431.889916) (xy 387.23808 -431.875342)
			(xy 387.239732 -431.846241) (xy 387.241288 -431.83175) (xy 387.241288 -430.747932) (xy 387.23974 -430.73344)
			(xy 387.23809 -430.70434) (xy 387.237986 -430.689766) (xy 387.238084 -430.675192) (xy 387.239734 -430.646091)
			(xy 387.241288 -430.6316) (xy 387.241288 -430.018952) (xy 387.241675 -430.006842) (xy 387.249187 -429.983815)
			(xy 387.263456 -429.964244) (xy 387.283083 -429.95005) (xy 387.306138 -429.942629) (xy 387.31825 -429.942244)
			(xy 388.25805 -429.942244) (xy 388.270137 -429.94275) (xy 388.293137 -429.950193) (xy 388.312718 -429.96437)
			(xy 388.32697 -429.983896) (xy 388.334503 -430.006866) (xy 388.335012 -430.018952) (xy 388.335012 -430.889918)
			(xy 389.237982 -430.889918) (xy 389.238076 -430.875344) (xy 389.239728 -430.846243) (xy 389.241284 -430.831752)
			(xy 389.241284 -429.747934) (xy 389.239737 -429.733442) (xy 389.238086 -429.704342) (xy 389.237982 -429.689768)
			(xy 389.23808 -429.675194) (xy 389.23973 -429.646093) (xy 389.241284 -429.631602) (xy 389.241284 -429.018954)
			(xy 389.241673 -429.006832) (xy 389.249179 -428.98378) (xy 389.26344 -428.964175) (xy 389.283062 -428.949937)
			(xy 389.306124 -428.942459) (xy 389.318246 -428.941992) (xy 390.258046 -428.941992) (xy 390.270158 -428.942472)
			(xy 390.293195 -428.949966) (xy 390.312792 -428.964208) (xy 390.327034 -428.983805) (xy 390.334528 -429.006842)
			(xy 390.335008 -429.018954) (xy 390.335008 -431.560478) (xy 390.33447 -431.572587) (xy 390.326995 -431.595622)
			(xy 390.312768 -431.61522) (xy 390.293183 -431.629464) (xy 390.270154 -431.636959) (xy 390.258046 -431.63744)
			(xy 389.318246 -431.63744) (xy 389.306123 -431.637001) (xy 389.283062 -431.629518) (xy 389.263445 -431.615273)
			(xy 389.249193 -431.595659) (xy 389.241703 -431.5726) (xy 389.241284 -431.560478) (xy 389.241284 -430.948084)
			(xy 389.239741 -430.933592) (xy 389.238088 -430.904492) (xy 389.237982 -430.889918) (xy 388.335012 -430.889918)
			(xy 388.335012 -431.889916) (xy 391.237978 -431.889916) (xy 391.238072 -431.875342) (xy 391.239724 -431.846241)
			(xy 391.24128 -431.83175) (xy 391.24128 -430.747932) (xy 391.239732 -430.73344) (xy 391.238082 -430.70434)
			(xy 391.237978 -430.689766) (xy 391.238076 -430.675192) (xy 391.239726 -430.646091) (xy 391.24128 -430.6316)
			(xy 391.24128 -430.018952) (xy 391.241675 -430.006843) (xy 391.249186 -429.983817) (xy 391.263453 -429.964247)
			(xy 391.283077 -429.950053) (xy 391.306131 -429.94263) (xy 391.318242 -429.942244) (xy 392.258042 -429.942244)
			(xy 392.270134 -429.942672) (xy 392.293137 -429.95014) (xy 392.312716 -429.964337) (xy 392.326965 -429.983879)
			(xy 392.334496 -430.006861) (xy 392.335004 -430.018952) (xy 392.335004 -430.889918) (xy 393.237974 -430.889918)
			(xy 393.238068 -430.875344) (xy 393.23972 -430.846243) (xy 393.241276 -430.831752) (xy 393.241276 -429.747934)
			(xy 393.239729 -429.733442) (xy 393.238078 -429.704342) (xy 393.237974 -429.689768) (xy 393.238072 -429.675194)
			(xy 393.239722 -429.646093) (xy 393.241276 -429.631602) (xy 393.241276 -429.018954) (xy 393.241673 -429.006833)
			(xy 393.249178 -428.983782) (xy 393.263438 -428.964178) (xy 393.283057 -428.949939) (xy 393.306117 -428.94246)
			(xy 393.318238 -428.941992) (xy 394.258038 -428.941992) (xy 394.27015 -428.942479) (xy 394.293187 -428.949971)
			(xy 394.312784 -428.964211) (xy 394.327026 -428.983806) (xy 394.33452 -429.006842) (xy 394.335 -429.018954)
			(xy 394.335 -431.560478) (xy 394.33447 -431.572588) (xy 394.326994 -431.595624) (xy 394.312765 -431.615223)
			(xy 394.293177 -431.629466) (xy 394.270147 -431.636961) (xy 394.258038 -431.63744) (xy 393.318238 -431.63744)
			(xy 393.306115 -431.637007) (xy 393.283054 -431.629523) (xy 393.263436 -431.615275) (xy 393.249184 -431.595661)
			(xy 393.241695 -431.572601) (xy 393.241276 -431.560478) (xy 393.241276 -430.948084) (xy 393.239733 -430.933592)
			(xy 393.23808 -430.904492) (xy 393.237974 -430.889918) (xy 392.335004 -430.889918) (xy 392.335004 -431.889916)
			(xy 395.23797 -431.889916) (xy 395.238064 -431.875342) (xy 395.239716 -431.846241) (xy 395.241272 -431.83175)
			(xy 395.241272 -430.747932) (xy 395.239724 -430.73344) (xy 395.238074 -430.70434) (xy 395.23797 -430.689766)
			(xy 395.238068 -430.675192) (xy 395.239718 -430.646091) (xy 395.241272 -430.6316) (xy 395.241272 -430.018952)
			(xy 395.241675 -430.006843) (xy 395.249184 -429.983819) (xy 395.26345 -429.96425) (xy 395.283072 -429.950056)
			(xy 395.306124 -429.942631) (xy 395.318234 -429.942244) (xy 396.258034 -429.942244) (xy 396.270126 -429.942678)
			(xy 396.293128 -429.950145) (xy 396.312708 -429.96434) (xy 396.326957 -429.98388) (xy 396.334488 -430.006862)
			(xy 396.334996 -430.018952) (xy 396.334996 -430.889918) (xy 398.237964 -430.889918) (xy 398.238073 -430.874832)
			(xy 398.239855 -430.844714) (xy 398.24152 -430.82972) (xy 398.24152 -429.749966) (xy 398.239855 -429.734972)
			(xy 398.238074 -429.704854) (xy 398.237964 -429.689768) (xy 398.238078 -429.674682) (xy 398.239856 -429.644564)
			(xy 398.24152 -429.62957) (xy 398.24152 -429.018954) (xy 398.241968 -429.006864) (xy 398.249435 -428.983865)
			(xy 398.263627 -428.964288) (xy 398.283163 -428.950038) (xy 398.306139 -428.942504) (xy 398.318228 -428.941992)
			(xy 399.258028 -428.941992) (xy 399.270138 -428.942392) (xy 399.293164 -428.949899) (xy 399.312736 -428.964165)
			(xy 399.32693 -428.983789) (xy 399.334352 -429.006843) (xy 399.334736 -429.018954) (xy 399.334736 -431.560478)
			(xy 399.334273 -431.572569) (xy 399.32682 -431.595573) (xy 399.312633 -431.615155) (xy 399.293097 -431.629405)
			(xy 399.270117 -431.636934) (xy 399.258028 -431.63744) (xy 398.318228 -431.63744) (xy 398.306125 -431.63696)
			(xy 398.283105 -431.629473) (xy 398.263535 -431.615227) (xy 398.249338 -431.595621) (xy 398.241909 -431.572582)
			(xy 398.24152 -431.560478) (xy 398.24152 -430.950116) (xy 398.239851 -430.935123) (xy 398.238073 -430.905004)
			(xy 398.237964 -430.889918) (xy 396.334996 -430.889918) (xy 396.334996 -431.889916) (xy 400.23796 -431.889916)
			(xy 400.238069 -431.87483) (xy 400.239851 -431.844712) (xy 400.241516 -431.829718) (xy 400.241516 -430.749964)
			(xy 400.239851 -430.73497) (xy 400.23807 -430.704852) (xy 400.23796 -430.689766) (xy 400.238074 -430.67468)
			(xy 400.239852 -430.644562) (xy 400.241516 -430.629568) (xy 400.241516 -430.018952) (xy 400.241924 -430.006873)
			(xy 400.249402 -429.9839) (xy 400.263613 -429.964361) (xy 400.283164 -429.950169) (xy 400.306144 -429.942712)
			(xy 400.318224 -429.942244) (xy 401.258024 -429.942244) (xy 401.270095 -429.942743) (xy 401.293055 -429.950206)
			(xy 401.312587 -429.964396) (xy 401.326783 -429.983924) (xy 401.334253 -430.006881) (xy 401.334732 -430.018952)
			(xy 401.334732 -430.889918) (xy 402.237956 -430.889918) (xy 402.238065 -430.874832) (xy 402.239847 -430.844714)
			(xy 402.241512 -430.82972) (xy 402.241512 -429.749966) (xy 402.239847 -429.734972) (xy 402.238066 -429.704854)
			(xy 402.237956 -429.689768) (xy 402.23807 -429.674682) (xy 402.239848 -429.644564) (xy 402.241512 -429.62957)
			(xy 402.241512 -429.018954) (xy 402.241968 -429.006865) (xy 402.249434 -428.983867) (xy 402.263624 -428.964291)
			(xy 402.283158 -428.950041) (xy 402.306132 -428.942505) (xy 402.31822 -428.941992) (xy 403.25802 -428.941992)
			(xy 403.270129 -428.942399) (xy 403.293156 -428.949903) (xy 403.312728 -428.964167) (xy 403.326922 -428.98379)
			(xy 403.334344 -429.006843) (xy 403.334728 -429.018954) (xy 403.334728 -431.560478) (xy 403.334273 -431.57257)
			(xy 403.326819 -431.595575) (xy 403.31263 -431.615158) (xy 403.293092 -431.629408) (xy 403.27011 -431.636935)
			(xy 403.25802 -431.63744) (xy 402.31822 -431.63744) (xy 402.306116 -431.636967) (xy 402.283096 -431.629478)
			(xy 402.263527 -431.61523) (xy 402.24933 -431.595622) (xy 402.241901 -431.572583) (xy 402.241512 -431.560478)
			(xy 402.241512 -430.950116) (xy 402.239843 -430.935123) (xy 402.238065 -430.905004) (xy 402.237956 -430.889918)
			(xy 401.334732 -430.889918) (xy 401.334732 -431.889916) (xy 404.237952 -431.889916) (xy 404.238061 -431.87483)
			(xy 404.239843 -431.844712) (xy 404.241508 -431.829718) (xy 404.241508 -430.749964) (xy 404.239843 -430.73497)
			(xy 404.238062 -430.704852) (xy 404.237952 -430.689766) (xy 404.238066 -430.67468) (xy 404.239844 -430.644562)
			(xy 404.241508 -430.629568) (xy 404.241508 -430.018952) (xy 404.241923 -430.006873) (xy 404.249401 -429.983902)
			(xy 404.26361 -429.964364) (xy 404.283159 -429.950172) (xy 404.306137 -429.942713) (xy 404.318216 -429.942244)
			(xy 405.258016 -429.942244) (xy 405.270087 -429.94275) (xy 405.293046 -429.950211) (xy 405.312579 -429.964399)
			(xy 405.326774 -429.983925) (xy 405.334245 -430.006882) (xy 405.334724 -430.018952) (xy 405.334724 -430.889918)
			(xy 406.237948 -430.889918) (xy 406.238057 -430.874832) (xy 406.239839 -430.844714) (xy 406.241504 -430.82972)
			(xy 406.241504 -429.749966) (xy 406.239839 -429.734972) (xy 406.238058 -429.704854) (xy 406.237948 -429.689768)
			(xy 406.238062 -429.674682) (xy 406.23984 -429.644564) (xy 406.241504 -429.62957) (xy 406.241504 -429.018954)
			(xy 406.241967 -429.006866) (xy 406.249432 -428.98387) (xy 406.263621 -428.964293) (xy 406.283153 -428.950043)
			(xy 406.306125 -428.942506) (xy 406.318212 -428.941992) (xy 407.258012 -428.941992) (xy 407.270121 -428.942406)
			(xy 407.293147 -428.949908) (xy 407.312719 -428.96417) (xy 407.326914 -428.983792) (xy 407.334336 -429.006844)
			(xy 407.33472 -429.018954) (xy 407.33472 -431.560478) (xy 407.334273 -431.57257) (xy 407.326818 -431.595577)
			(xy 407.312627 -431.615161) (xy 407.293087 -431.629411) (xy 407.270103 -431.636936) (xy 407.258012 -431.63744)
			(xy 406.318212 -431.63744) (xy 406.306108 -431.636974) (xy 406.283088 -431.629483) (xy 406.263518 -431.615232)
			(xy 406.249322 -431.595624) (xy 406.241893 -431.572583) (xy 406.241504 -431.560478) (xy 406.241504 -430.950116)
			(xy 406.239835 -430.935123) (xy 406.238057 -430.905004) (xy 406.237948 -430.889918) (xy 405.334724 -430.889918)
			(xy 405.334724 -431.889916) (xy 408.237944 -431.889916) (xy 408.238053 -431.87483) (xy 408.239835 -431.844712)
			(xy 408.2415 -431.829718) (xy 408.2415 -430.749964) (xy 408.239835 -430.73497) (xy 408.238054 -430.704852)
			(xy 408.237944 -430.689766) (xy 408.238058 -430.67468) (xy 408.239836 -430.644562) (xy 408.2415 -430.629568)
			(xy 408.2415 -430.018952) (xy 408.241923 -430.006874) (xy 408.2494 -429.983904) (xy 408.263607 -429.964367)
			(xy 408.283154 -429.950174) (xy 408.30613 -429.942714) (xy 408.318208 -429.942244) (xy 409.258008 -429.942244)
			(xy 409.270078 -429.942757) (xy 409.293037 -429.950216) (xy 409.31257 -429.964401) (xy 409.326766 -429.983927)
			(xy 409.334237 -430.006882) (xy 409.334716 -430.018952) (xy 409.334716 -430.889918) (xy 410.23794 -430.889918)
			(xy 410.238051 -430.874832) (xy 410.239833 -430.844714) (xy 410.241496 -430.82972) (xy 410.241496 -429.749966)
			(xy 410.239831 -429.734972) (xy 410.23805 -429.704854) (xy 410.23794 -429.689768) (xy 410.238054 -429.674682)
			(xy 410.239832 -429.644564) (xy 410.241496 -429.62957) (xy 410.241496 -429.018954) (xy 410.241967 -429.006866)
			(xy 410.249431 -428.983872) (xy 410.263618 -428.964296) (xy 410.283148 -428.950046) (xy 410.306118 -428.942507)
			(xy 410.318204 -428.941992) (xy 411.258004 -428.941992) (xy 411.270112 -428.942413) (xy 411.293138 -428.949912)
			(xy 411.312711 -428.964173) (xy 411.326906 -428.983793) (xy 411.334328 -429.006844) (xy 411.334712 -429.018954)
			(xy 411.334712 -431.560478) (xy 411.334273 -431.572571) (xy 411.326816 -431.595579) (xy 411.312624 -431.615164)
			(xy 411.293082 -431.629413) (xy 411.270096 -431.636937) (xy 411.258004 -431.63744) (xy 410.318204 -431.63744)
			(xy 410.306099 -431.636981) (xy 410.283079 -431.629488) (xy 410.263509 -431.615236) (xy 410.249313 -431.595625)
			(xy 410.241885 -431.572584) (xy 410.241496 -431.560478) (xy 410.241496 -430.950116) (xy 410.239827 -430.935123)
			(xy 410.238049 -430.905004) (xy 410.23794 -430.889918) (xy 409.334716 -430.889918) (xy 409.334716 -431.889916)
			(xy 412.237936 -431.889916) (xy 412.238047 -431.87483) (xy 412.239829 -431.844712) (xy 412.241492 -431.829718)
			(xy 412.241492 -430.749964) (xy 412.239827 -430.73497) (xy 412.238046 -430.704852) (xy 412.237936 -430.689766)
			(xy 412.238052 -430.674681) (xy 412.23983 -430.644562) (xy 412.241492 -430.629568) (xy 412.241492 -430.018952)
			(xy 412.241923 -430.006875) (xy 412.249399 -429.983906) (xy 412.263604 -429.96437) (xy 412.283149 -429.950177)
			(xy 412.306123 -429.942716) (xy 412.3182 -429.942244) (xy 413.258 -429.942244) (xy 413.27007 -429.942764)
			(xy 413.293029 -429.95022) (xy 413.312562 -429.964404) (xy 413.326758 -429.983928) (xy 413.334229 -430.006883)
			(xy 413.334708 -430.018952) (xy 413.334708 -432.560476) (xy 413.334267 -432.572557) (xy 413.326806 -432.595539)
			(xy 413.312607 -432.61509) (xy 413.293061 -432.629295) (xy 413.270081 -432.636763) (xy 413.258 -432.637184)
			(xy 412.3182 -432.637184) (xy 412.306115 -432.636787) (xy 412.283128 -432.629317) (xy 412.263576 -432.615107)
			(xy 412.249372 -432.59555) (xy 412.241909 -432.572561) (xy 412.241492 -432.560476) (xy 412.241492 -431.950114)
			(xy 412.239822 -431.935121) (xy 412.238045 -431.905002) (xy 412.237936 -431.889916) (xy 409.334716 -431.889916)
			(xy 409.334716 -432.560476) (xy 409.334267 -432.572557) (xy 409.326807 -432.595537) (xy 409.31261 -432.615087)
			(xy 409.293066 -432.629292) (xy 409.270088 -432.636762) (xy 409.258008 -432.637184) (xy 408.318208 -432.637184)
			(xy 408.306123 -432.63678) (xy 408.283137 -432.629312) (xy 408.263584 -432.615105) (xy 408.249381 -432.595549)
			(xy 408.241917 -432.572561) (xy 408.2415 -432.560476) (xy 408.2415 -431.950114) (xy 408.23983 -431.935121)
			(xy 408.238053 -431.905002) (xy 408.237944 -431.889916) (xy 405.334724 -431.889916) (xy 405.334724 -432.560476)
			(xy 405.334267 -432.572556) (xy 405.326808 -432.595535) (xy 405.312613 -432.615084) (xy 405.293071 -432.62929)
			(xy 405.270096 -432.636761) (xy 405.258016 -432.637184) (xy 404.318216 -432.637184) (xy 404.306132 -432.636773)
			(xy 404.283146 -432.629307) (xy 404.263593 -432.615101) (xy 404.249389 -432.595547) (xy 404.241926 -432.57256)
			(xy 404.241508 -432.560476) (xy 404.241508 -431.950114) (xy 404.239838 -431.935121) (xy 404.238061 -431.905002)
			(xy 404.237952 -431.889916) (xy 401.334732 -431.889916) (xy 401.334732 -432.560476) (xy 401.334216 -432.572547)
			(xy 401.326763 -432.595509) (xy 401.312579 -432.615045) (xy 401.293052 -432.629241) (xy 401.270095 -432.636708)
			(xy 401.258024 -432.637184) (xy 400.318224 -432.637184) (xy 400.30614 -432.636766) (xy 400.283154 -432.629303)
			(xy 400.263601 -432.615099) (xy 400.249397 -432.595546) (xy 400.241934 -432.57256) (xy 400.241516 -432.560476)
			(xy 400.241516 -431.950114) (xy 400.239846 -431.935121) (xy 400.238069 -431.905002) (xy 400.23796 -431.889916)
			(xy 396.334996 -431.889916) (xy 396.334996 -432.560476) (xy 396.334563 -432.572584) (xy 396.32707 -432.595611)
			(xy 396.312813 -432.615185) (xy 396.293194 -432.62938) (xy 396.270143 -432.636801) (xy 396.258034 -432.637184)
			(xy 395.318234 -432.637184) (xy 395.306149 -432.636664) (xy 395.283153 -432.62922) (xy 395.263575 -432.615046)
			(xy 395.249322 -432.595525) (xy 395.241785 -432.572559) (xy 395.241272 -432.560476) (xy 395.241272 -431.948082)
			(xy 395.239729 -431.93359) (xy 395.238076 -431.90449) (xy 395.23797 -431.889916) (xy 392.335004 -431.889916)
			(xy 392.335004 -432.560476) (xy 392.334563 -432.572583) (xy 392.327071 -432.595609) (xy 392.312815 -432.615182)
			(xy 392.293199 -432.629378) (xy 392.27015 -432.6368) (xy 392.258042 -432.637184) (xy 391.318242 -432.637184)
			(xy 391.306157 -432.636657) (xy 391.283162 -432.629215) (xy 391.263583 -432.615043) (xy 391.24933 -432.595523)
			(xy 391.241793 -432.572559) (xy 391.24128 -432.560476) (xy 391.24128 -431.948082) (xy 391.239737 -431.93359)
			(xy 391.238084 -431.90449) (xy 391.237978 -431.889916) (xy 388.335012 -431.889916) (xy 388.335012 -432.560476)
			(xy 388.334563 -432.572582) (xy 388.327072 -432.595607) (xy 388.312818 -432.615179) (xy 388.293204 -432.629375)
			(xy 388.270158 -432.636799) (xy 388.25805 -432.637184) (xy 387.31825 -432.637184) (xy 387.306165 -432.636651)
			(xy 387.28317 -432.62921) (xy 387.263592 -432.61504) (xy 387.249339 -432.595522) (xy 387.241801 -432.572559)
			(xy 387.241288 -432.560476) (xy 387.241288 -431.948082) (xy 387.239745 -431.93359) (xy 387.238092 -431.90449)
			(xy 387.237986 -431.889916) (xy 384.33502 -431.889916) (xy 384.33502 -432.560476) (xy 384.334563 -432.572582)
			(xy 384.327073 -432.595605) (xy 384.312821 -432.615176) (xy 384.293209 -432.629373) (xy 384.270165 -432.636797)
			(xy 384.258058 -432.637184) (xy 383.318258 -432.637184) (xy 383.306169 -432.636729) (xy 383.283171 -432.629264)
			(xy 383.263593 -432.615073) (xy 383.249343 -432.595539) (xy 383.241808 -432.572564) (xy 383.241296 -432.560476)
			(xy 383.241296 -431.948082) (xy 383.239753 -431.93359) (xy 383.2381 -431.90449) (xy 383.237994 -431.889916)
			(xy 363.355859 -431.889916) (xy 363.346369 -431.956363) (xy 363.314178 -432.124516) (xy 363.274074 -432.290959)
			(xy 363.226145 -432.455319) (xy 363.170501 -432.61723) (xy 363.107264 -432.776329) (xy 363.036576 -432.932261)
			(xy 362.958595 -433.084677) (xy 362.873496 -433.233236) (xy 362.781469 -433.377605) (xy 362.68272 -433.517463)
			(xy 362.577469 -433.652495) (xy 362.465953 -433.782401) (xy 362.348419 -433.90689) (xy 362.225132 -434.025683)
			(xy 362.096367 -434.138515) (xy 361.962411 -434.245133) (xy 361.823565 -434.345299) (xy 361.680139 -434.438789)
			(xy 361.593049 -434.48986) (xy 381.237998 -434.48986) (xy 381.238096 -434.475286) (xy 381.239745 -434.446185)
			(xy 381.2413 -434.431694) (xy 381.2413 -433.34813) (xy 381.239752 -433.333638) (xy 381.238102 -433.304538)
			(xy 381.237998 -433.289964) (xy 381.238096 -433.27539) (xy 381.239745 -433.246289) (xy 381.2413 -433.231798)
			(xy 381.2413 -432.618896) (xy 381.241713 -432.606787) (xy 381.249213 -432.583759) (xy 381.263476 -432.564186)
			(xy 381.283098 -432.549992) (xy 381.306152 -432.542571) (xy 381.318262 -432.542188) (xy 382.258062 -432.542188)
			(xy 382.270154 -432.542641) (xy 382.293162 -432.550093) (xy 382.312747 -432.564281) (xy 382.326997 -432.583821)
			(xy 382.334521 -432.606805) (xy 382.335024 -432.618896) (xy 382.335024 -435.16042) (xy 382.334601 -435.172528)
			(xy 382.327099 -435.195551) (xy 382.312838 -435.215122) (xy 382.29322 -435.229317) (xy 382.270171 -435.236741)
			(xy 382.258062 -435.237128) (xy 381.318262 -435.237128) (xy 381.306167 -435.236724) (xy 381.28316 -435.229253)
			(xy 381.263578 -435.215052) (xy 381.24933 -435.195503) (xy 381.241804 -435.172514) (xy 381.2413 -435.16042)
			(xy 381.2413 -434.548026) (xy 381.239752 -434.533534) (xy 381.238102 -434.504434) (xy 381.237998 -434.48986)
			(xy 361.593049 -434.48986) (xy 361.532453 -434.525394) (xy 361.380838 -434.60492) (xy 361.225633 -434.67719)
			(xy 361.146598 -434.710078) (xy 361.132966 -434.716266) (xy 361.109724 -434.735103) (xy 361.092944 -434.759873)
			(xy 361.084069 -434.788444) (xy 361.083862 -434.818361) (xy 361.092341 -434.847052) (xy 361.108777 -434.872051)
			(xy 361.119928 -434.882036) (xy 361.169374 -434.924045) (xy 361.263563 -435.013299) (xy 361.352051 -435.108208)
			(xy 361.434498 -435.208409) (xy 361.510589 -435.313518) (xy 361.580032 -435.423133) (xy 361.616728 -435.489858)
			(xy 383.237994 -435.489858) (xy 383.238091 -435.475284) (xy 383.239741 -435.446183) (xy 383.241296 -435.431692)
			(xy 383.241296 -434.348128) (xy 383.239748 -434.333636) (xy 383.238098 -434.304536) (xy 383.237994 -434.289962)
			(xy 383.238092 -434.275388) (xy 383.239741 -434.246287) (xy 383.241296 -434.231796) (xy 383.241296 -433.618894)
			(xy 383.241806 -433.606783) (xy 383.24929 -433.583747) (xy 383.263524 -433.564149) (xy 383.283115 -433.549906)
			(xy 383.306148 -433.542412) (xy 383.318258 -433.541932) (xy 384.258058 -433.541932) (xy 384.270178 -433.542396)
			(xy 384.293234 -433.549876) (xy 384.31285 -433.564116) (xy 384.327103 -433.583722) (xy 384.334597 -433.606774)
			(xy 384.33502 -433.618894) (xy 384.33502 -434.48986) (xy 385.23799 -434.48986) (xy 385.238088 -434.475286)
			(xy 385.239737 -434.446185) (xy 385.241292 -434.431694) (xy 385.241292 -433.34813) (xy 385.239744 -433.333638)
			(xy 385.238094 -433.304538) (xy 385.23799 -433.289964) (xy 385.238088 -433.27539) (xy 385.239737 -433.246289)
			(xy 385.241292 -433.231798) (xy 385.241292 -432.618896) (xy 385.241713 -432.606788) (xy 385.249212 -432.583762)
			(xy 385.263473 -432.564189) (xy 385.283093 -432.549994) (xy 385.306144 -432.542572) (xy 385.318254 -432.542188)
			(xy 386.258054 -432.542188) (xy 386.270146 -432.542647) (xy 386.293153 -432.550097) (xy 386.312738 -432.564284)
			(xy 386.326988 -432.583823) (xy 386.334513 -432.606806) (xy 386.335016 -432.618896) (xy 386.335016 -435.16042)
			(xy 386.334601 -435.172528) (xy 386.327098 -435.195554) (xy 386.312836 -435.215125) (xy 386.293215 -435.229319)
			(xy 386.270164 -435.236743) (xy 386.258054 -435.237128) (xy 385.318254 -435.237128) (xy 385.306159 -435.236731)
			(xy 385.283151 -435.229258) (xy 385.263569 -435.215054) (xy 385.249322 -435.195505) (xy 385.241796 -435.172514)
			(xy 385.241292 -435.16042) (xy 385.241292 -434.548026) (xy 385.239744 -434.533534) (xy 385.238094 -434.504434)
			(xy 385.23799 -434.48986) (xy 384.33502 -434.48986) (xy 384.33502 -435.489858) (xy 387.237986 -435.489858)
			(xy 387.238083 -435.475284) (xy 387.239733 -435.446183) (xy 387.241288 -435.431692) (xy 387.241288 -434.348128)
			(xy 387.23974 -434.333636) (xy 387.23809 -434.304536) (xy 387.237986 -434.289962) (xy 387.238084 -434.275388)
			(xy 387.239733 -434.246287) (xy 387.241288 -434.231796) (xy 387.241288 -433.618894) (xy 387.241806 -433.606784)
			(xy 387.249289 -433.583749) (xy 387.263521 -433.564152) (xy 387.28311 -433.549909) (xy 387.30614 -433.542413)
			(xy 387.31825 -433.541932) (xy 388.25805 -433.541932) (xy 388.270167 -433.542369) (xy 388.29321 -433.549869)
			(xy 388.312811 -433.564121) (xy 388.327051 -433.583729) (xy 388.334538 -433.606777) (xy 388.335012 -433.618894)
			(xy 388.335012 -434.48986) (xy 389.237982 -434.48986) (xy 389.23808 -434.475286) (xy 389.239729 -434.446185)
			(xy 389.241284 -434.431694) (xy 389.241284 -433.34813) (xy 389.239736 -433.333638) (xy 389.238086 -433.304538)
			(xy 389.237982 -433.289964) (xy 389.23808 -433.27539) (xy 389.23973 -433.246289) (xy 389.241284 -433.231798)
			(xy 389.241284 -432.618896) (xy 389.241713 -432.606789) (xy 389.249211 -432.583764) (xy 389.26347 -432.564192)
			(xy 389.283088 -432.549997) (xy 389.306137 -432.542573) (xy 389.318246 -432.542188) (xy 390.258046 -432.542188)
			(xy 390.270143 -432.542569) (xy 390.293153 -432.550044) (xy 390.312736 -432.564251) (xy 390.326984 -432.583805)
			(xy 390.334506 -432.6068) (xy 390.335008 -432.618896) (xy 390.335008 -435.16042) (xy 390.334601 -435.172529)
			(xy 390.327097 -435.195556) (xy 390.312833 -435.215128) (xy 390.29321 -435.229322) (xy 390.270157 -435.236744)
			(xy 390.258046 -435.237128) (xy 389.318246 -435.237128) (xy 389.306156 -435.236653) (xy 389.283151 -435.229205)
			(xy 389.263568 -435.215022) (xy 389.249317 -435.195487) (xy 389.241789 -435.172509) (xy 389.241284 -435.16042)
			(xy 389.241284 -434.548026) (xy 389.239736 -434.533534) (xy 389.238086 -434.504434) (xy 389.237982 -434.48986)
			(xy 388.335012 -434.48986) (xy 388.335012 -435.489858) (xy 391.237978 -435.489858) (xy 391.238076 -435.475284)
			(xy 391.239725 -435.446183) (xy 391.24128 -435.431692) (xy 391.24128 -434.348128) (xy 391.239732 -434.333636)
			(xy 391.238082 -434.304536) (xy 391.237978 -434.289962) (xy 391.238076 -434.275388) (xy 391.239725 -434.246287)
			(xy 391.24128 -434.231796) (xy 391.24128 -433.618894) (xy 391.241656 -433.606767) (xy 391.249155 -433.583701)
			(xy 391.263416 -433.564082) (xy 391.283044 -433.549833) (xy 391.306115 -433.542348) (xy 391.318242 -433.541932)
			(xy 392.258042 -433.541932) (xy 392.270158 -433.542376) (xy 392.293202 -433.549874) (xy 392.312802 -433.564123)
			(xy 392.327043 -433.583731) (xy 392.33453 -433.606778) (xy 392.335004 -433.618894) (xy 392.335004 -434.48986)
			(xy 393.237974 -434.48986) (xy 393.238072 -434.475286) (xy 393.239721 -434.446185) (xy 393.241276 -434.431694)
			(xy 393.241276 -433.34813) (xy 393.239728 -433.333638) (xy 393.238078 -433.304538) (xy 393.237974 -433.289964)
			(xy 393.238072 -433.27539) (xy 393.239722 -433.246289) (xy 393.241276 -433.231798) (xy 393.241276 -432.618896)
			(xy 393.241712 -432.606789) (xy 393.24921 -432.583766) (xy 393.263467 -432.564195) (xy 393.283083 -432.55)
			(xy 393.30613 -432.542575) (xy 393.318238 -432.542188) (xy 394.258038 -432.542188) (xy 394.270134 -432.542576)
			(xy 394.293144 -432.550049) (xy 394.312728 -432.564254) (xy 394.326975 -432.583807) (xy 394.334498 -432.606801)
			(xy 394.335 -432.618896) (xy 394.335 -435.16042) (xy 394.334601 -435.17253) (xy 394.327096 -435.195558)
			(xy 394.31283 -435.215131) (xy 394.293205 -435.229325) (xy 394.270149 -435.236745) (xy 394.258038 -435.237128)
			(xy 393.318238 -435.237128) (xy 393.306147 -435.23666) (xy 393.283142 -435.22921) (xy 393.263559 -435.215024)
			(xy 393.249308 -435.195489) (xy 393.241781 -435.172509) (xy 393.241276 -435.16042) (xy 393.241276 -434.548026)
			(xy 393.239728 -434.533534) (xy 393.238078 -434.504434) (xy 393.237974 -434.48986) (xy 392.335004 -434.48986)
			(xy 392.335004 -435.489858) (xy 395.23797 -435.489858) (xy 395.238068 -435.475284) (xy 395.239717 -435.446183)
			(xy 395.241272 -435.431692) (xy 395.241272 -434.348128) (xy 395.239724 -434.333636) (xy 395.238074 -434.304536)
			(xy 395.23797 -434.289962) (xy 395.238068 -434.275388) (xy 395.239717 -434.246287) (xy 395.241272 -434.231796)
			(xy 395.241272 -433.618894) (xy 395.241656 -433.606768) (xy 395.249154 -433.583703) (xy 395.263413 -433.564085)
			(xy 395.283039 -433.549835) (xy 395.306107 -433.542349) (xy 395.318234 -433.541932) (xy 396.258034 -433.541932)
			(xy 396.27015 -433.542383) (xy 396.293193 -433.549878) (xy 396.312794 -433.564126) (xy 396.327034 -433.583732)
			(xy 396.334522 -433.606778) (xy 396.334996 -433.618894) (xy 396.334996 -434.48986) (xy 398.237964 -434.48986)
			(xy 398.238077 -434.474774) (xy 398.239856 -434.444656) (xy 398.24152 -434.429662) (xy 398.24152 -433.350162)
			(xy 398.239855 -433.335168) (xy 398.238074 -433.30505) (xy 398.237964 -433.289964) (xy 398.238077 -433.274878)
			(xy 398.239856 -433.24476) (xy 398.24152 -433.229766) (xy 398.24152 -432.618896) (xy 398.241909 -432.60681)
			(xy 398.249382 -432.583823) (xy 398.263593 -432.56427) (xy 398.283151 -432.550067) (xy 398.306142 -432.542604)
			(xy 398.318228 -432.542188) (xy 399.258028 -432.542188) (xy 399.270104 -432.54264) (xy 399.293071 -432.55011)
			(xy 399.312607 -432.56431) (xy 399.326801 -432.58385) (xy 399.334264 -432.60682) (xy 399.334736 -432.618896)
			(xy 399.334736 -435.16042) (xy 399.334253 -435.172493) (xy 399.326788 -435.195456) (xy 399.312596 -435.21499)
			(xy 399.293063 -435.229185) (xy 399.270101 -435.236652) (xy 399.258028 -435.237128) (xy 398.318228 -435.237128)
			(xy 398.306149 -435.236664) (xy 398.28317 -435.229206) (xy 398.263621 -435.215013) (xy 398.249416 -435.195473)
			(xy 398.241944 -435.172499) (xy 398.24152 -435.16042) (xy 398.24152 -434.550058) (xy 398.239854 -434.535064)
			(xy 398.238074 -434.504946) (xy 398.237964 -434.48986) (xy 396.334996 -434.48986) (xy 396.334996 -435.489858)
			(xy 400.23796 -435.489858) (xy 400.238073 -435.474772) (xy 400.239852 -435.444654) (xy 400.241516 -435.42966)
			(xy 400.241516 -434.35016) (xy 400.239851 -434.335166) (xy 400.23807 -434.305048) (xy 400.23796 -434.289962)
			(xy 400.238073 -434.274876) (xy 400.239852 -434.244758) (xy 400.241516 -434.229764) (xy 400.241516 -433.618894)
			(xy 400.242002 -433.606807) (xy 400.249457 -433.58381) (xy 400.26364 -433.564232) (xy 400.283168 -433.549981)
			(xy 400.306138 -433.542445) (xy 400.318224 -433.541932) (xy 401.258024 -433.541932) (xy 401.270137 -433.542296)
			(xy 401.293171 -433.549806) (xy 401.312746 -433.56408) (xy 401.326939 -433.583715) (xy 401.334353 -433.606779)
			(xy 401.334732 -433.618894) (xy 401.334732 -434.48986) (xy 402.237956 -434.48986) (xy 402.238069 -434.474774)
			(xy 402.239848 -434.444656) (xy 402.241512 -434.429662) (xy 402.241512 -433.350162) (xy 402.239847 -433.335168)
			(xy 402.238066 -433.30505) (xy 402.237956 -433.289964) (xy 402.238069 -433.274878) (xy 402.239848 -433.24476)
			(xy 402.241512 -433.229766) (xy 402.241512 -432.618896) (xy 402.241909 -432.606811) (xy 402.24938 -432.583825)
			(xy 402.26359 -432.564273) (xy 402.283146 -432.550069) (xy 402.306135 -432.542606) (xy 402.31822 -432.542188)
			(xy 403.25802 -432.542188) (xy 403.270095 -432.542647) (xy 403.293062 -432.550115) (xy 403.312599 -432.564313)
			(xy 403.326793 -432.583852) (xy 403.334255 -432.606821) (xy 403.334728 -432.618896) (xy 403.334728 -435.16042)
			(xy 403.334253 -435.172494) (xy 403.326787 -435.195458) (xy 403.312593 -435.214993) (xy 403.293058 -435.229187)
			(xy 403.270094 -435.236653) (xy 403.25802 -435.237128) (xy 402.31822 -435.237128) (xy 402.306148 -435.236619)
			(xy 402.283185 -435.229165) (xy 402.26365 -435.214979) (xy 402.249454 -435.195451) (xy 402.241987 -435.172491)
			(xy 402.241512 -435.16042) (xy 402.241512 -434.550058) (xy 402.239846 -434.535064) (xy 402.238066 -434.504946)
			(xy 402.237956 -434.48986) (xy 401.334732 -434.48986) (xy 401.334732 -435.489858) (xy 404.237952 -435.489858)
			(xy 404.238065 -435.474772) (xy 404.239844 -435.444654) (xy 404.241508 -435.42966) (xy 404.241508 -434.35016)
			(xy 404.239843 -434.335166) (xy 404.238062 -434.305048) (xy 404.237952 -434.289962) (xy 404.238065 -434.274876)
			(xy 404.239844 -434.244758) (xy 404.241508 -434.229764) (xy 404.241508 -433.618894) (xy 404.242002 -433.606807)
			(xy 404.249456 -433.583812) (xy 404.263637 -433.564235) (xy 404.283163 -433.549984) (xy 404.306131 -433.542446)
			(xy 404.318216 -433.541932) (xy 405.258016 -433.541932) (xy 405.270129 -433.542303) (xy 405.293162 -433.549811)
			(xy 405.312738 -433.564083) (xy 405.326931 -433.583716) (xy 405.334345 -433.606779) (xy 405.334724 -433.618894)
			(xy 405.334724 -434.48986) (xy 406.237948 -434.48986) (xy 406.238061 -434.474774) (xy 406.23984 -434.444656)
			(xy 406.241504 -434.429662) (xy 406.241504 -433.350162) (xy 406.239839 -433.335168) (xy 406.238058 -433.30505)
			(xy 406.237948 -433.289964) (xy 406.238061 -433.274878) (xy 406.23984 -433.24476) (xy 406.241504 -433.229766)
			(xy 406.241504 -432.618896) (xy 406.241909 -432.606812) (xy 406.249379 -432.583827) (xy 406.263587 -432.564276)
			(xy 406.283141 -432.550072) (xy 406.306128 -432.542607) (xy 406.318212 -432.542188) (xy 407.258012 -432.542188)
			(xy 407.270087 -432.542654) (xy 407.293054 -432.550119) (xy 407.31259 -432.564316) (xy 407.326784 -432.583854)
			(xy 407.334247 -432.606821) (xy 407.33472 -432.618896) (xy 407.33472 -435.16042) (xy 407.334253 -435.172494)
			(xy 407.326786 -435.19546) (xy 407.31259 -435.214996) (xy 407.293053 -435.22919) (xy 407.270086 -435.236654)
			(xy 407.258012 -435.237128) (xy 406.318212 -435.237128) (xy 406.30614 -435.236626) (xy 406.283177 -435.229169)
			(xy 406.263641 -435.214982) (xy 406.249446 -435.195452) (xy 406.241979 -435.172492) (xy 406.241504 -435.16042)
			(xy 406.241504 -434.550058) (xy 406.239838 -434.535064) (xy 406.238058 -434.504946) (xy 406.237948 -434.48986)
			(xy 405.334724 -434.48986) (xy 405.334724 -435.489858) (xy 408.237944 -435.489858) (xy 408.238057 -435.474772)
			(xy 408.239836 -435.444654) (xy 408.2415 -435.42966) (xy 408.2415 -434.35016) (xy 408.239834 -434.335166)
			(xy 408.238054 -434.305048) (xy 408.237944 -434.289962) (xy 408.238057 -434.274876) (xy 408.239836 -434.244758)
			(xy 408.2415 -434.229764) (xy 408.2415 -433.618894) (xy 408.242002 -433.606808) (xy 408.249455 -433.583814)
			(xy 408.263634 -433.564238) (xy 408.283158 -433.549986) (xy 408.306124 -433.542447) (xy 408.318208 -433.541932)
			(xy 409.258008 -433.541932) (xy 409.270121 -433.54231) (xy 409.293154 -433.549815) (xy 409.312729 -433.564086)
			(xy 409.326923 -433.583717) (xy 409.334337 -433.60678) (xy 409.334716 -433.618894) (xy 409.334716 -434.48986)
			(xy 410.23794 -434.48986) (xy 410.238053 -434.474774) (xy 410.239832 -434.444656) (xy 410.241496 -434.429662)
			(xy 410.241496 -433.350162) (xy 410.239831 -433.335168) (xy 410.23805 -433.30505) (xy 410.23794 -433.289964)
			(xy 410.238053 -433.274878) (xy 410.239832 -433.24476) (xy 410.241496 -433.229766) (xy 410.241496 -432.618896)
			(xy 410.241961 -432.606821) (xy 410.249425 -432.583853) (xy 410.263621 -432.564316) (xy 410.28316 -432.550121)
			(xy 410.306129 -432.54266) (xy 410.318204 -432.542188) (xy 411.258004 -432.542188) (xy 411.270078 -432.542661)
			(xy 411.293045 -432.550124) (xy 411.312582 -432.564318) (xy 411.326776 -432.583855) (xy 411.334239 -432.606822)
			(xy 411.334712 -432.618896) (xy 411.334712 -435.16042) (xy 411.334253 -435.172495) (xy 411.326785 -435.195462)
			(xy 411.312587 -435.214999) (xy 411.293048 -435.229193) (xy 411.270079 -435.236655) (xy 411.258004 -435.237128)
			(xy 410.318204 -435.237128) (xy 410.306132 -435.236633) (xy 410.283168 -435.229174) (xy 410.263633 -435.214984)
			(xy 410.249437 -435.195454) (xy 410.241971 -435.172492) (xy 410.241496 -435.16042) (xy 410.241496 -434.550058)
			(xy 410.23983 -434.535064) (xy 410.23805 -434.504946) (xy 410.23794 -434.48986) (xy 409.334716 -434.48986)
			(xy 409.334716 -435.489858) (xy 412.237936 -435.489858) (xy 412.238051 -435.474773) (xy 412.23983 -435.444654)
			(xy 412.241492 -435.42966) (xy 412.241492 -434.35016) (xy 412.239826 -434.335166) (xy 412.238046 -434.305048)
			(xy 412.237936 -434.289962) (xy 412.238051 -434.274877) (xy 412.23983 -434.244758) (xy 412.241492 -434.229764)
			(xy 412.241492 -433.618894) (xy 412.242002 -433.606809) (xy 412.249454 -433.583816) (xy 412.263631 -433.564241)
			(xy 412.283153 -433.549989) (xy 412.306117 -433.542448) (xy 412.3182 -433.541932) (xy 413.258 -433.541932)
			(xy 413.270112 -433.542317) (xy 413.293145 -433.54982) (xy 413.312721 -433.564088) (xy 413.326914 -433.583719)
			(xy 413.334329 -433.60678) (xy 413.334708 -433.618894) (xy 413.334708 -436.160418) (xy 413.334209 -436.172504)
			(xy 413.326753 -436.195497) (xy 413.312573 -436.215072) (xy 413.29305 -436.229324) (xy 413.270084 -436.236864)
			(xy 413.258 -436.23738) (xy 412.3182 -436.23738) (xy 412.306089 -436.236984) (xy 412.283058 -436.229482)
			(xy 412.263483 -436.215216) (xy 412.24929 -436.195589) (xy 412.241872 -436.17253) (xy 412.241492 -436.160418)
			(xy 412.241492 -435.550056) (xy 412.239826 -435.535062) (xy 412.238046 -435.504944) (xy 412.237936 -435.489858)
			(xy 409.334716 -435.489858) (xy 409.334716 -436.160418) (xy 409.334307 -436.172513) (xy 409.32684 -436.195522)
			(xy 409.31264 -436.215105) (xy 409.293092 -436.229353) (xy 409.270102 -436.236877) (xy 409.258008 -436.23738)
			(xy 408.318208 -436.23738) (xy 408.306098 -436.236977) (xy 408.283067 -436.229477) (xy 408.263492 -436.215213)
			(xy 408.249298 -436.195587) (xy 408.24188 -436.17253) (xy 408.2415 -436.160418) (xy 408.2415 -435.550056)
			(xy 408.239834 -435.535062) (xy 408.238054 -435.504944) (xy 408.237944 -435.489858) (xy 405.334724 -435.489858)
			(xy 405.334724 -436.160418) (xy 405.334307 -436.172512) (xy 405.326841 -436.195519) (xy 405.312643 -436.215102)
			(xy 405.293097 -436.229351) (xy 405.270109 -436.236876) (xy 405.258016 -436.23738) (xy 404.318216 -436.23738)
			(xy 404.306106 -436.23697) (xy 404.283076 -436.229472) (xy 404.263501 -436.21521) (xy 404.249306 -436.195585)
			(xy 404.241889 -436.172529) (xy 404.241508 -436.160418) (xy 404.241508 -435.550056) (xy 404.239842 -435.535062)
			(xy 404.238062 -435.504944) (xy 404.237952 -435.489858) (xy 401.334732 -435.489858) (xy 401.334732 -436.160418)
			(xy 401.334308 -436.172511) (xy 401.326843 -436.195517) (xy 401.312646 -436.215099) (xy 401.293102 -436.229348)
			(xy 401.270116 -436.236875) (xy 401.258024 -436.23738) (xy 400.318224 -436.23738) (xy 400.306114 -436.236963)
			(xy 400.283085 -436.229468) (xy 400.263509 -436.215207) (xy 400.249315 -436.195584) (xy 400.241897 -436.172529)
			(xy 400.241516 -436.160418) (xy 400.241516 -435.550056) (xy 400.23985 -435.535062) (xy 400.23807 -435.504944)
			(xy 400.23796 -435.489858) (xy 396.334996 -435.489858) (xy 396.334996 -436.160418) (xy 396.334504 -436.17253)
			(xy 396.327016 -436.195568) (xy 396.312778 -436.215167) (xy 396.293183 -436.229409) (xy 396.270146 -436.236902)
			(xy 396.258034 -436.23738) (xy 395.318234 -436.23738) (xy 395.306115 -436.236911) (xy 395.28306 -436.229431)
			(xy 395.263446 -436.215191) (xy 395.249193 -436.195587) (xy 395.241697 -436.172537) (xy 395.241272 -436.160418)
			(xy 395.241272 -435.548024) (xy 395.239724 -435.533532) (xy 395.238074 -435.504432) (xy 395.23797 -435.489858)
			(xy 392.335004 -435.489858) (xy 392.335004 -436.160418) (xy 392.334504 -436.172529) (xy 392.327017 -436.195566)
			(xy 392.312781 -436.215164) (xy 392.293188 -436.229406) (xy 392.270153 -436.236901) (xy 392.258042 -436.23738)
			(xy 391.318242 -436.23738) (xy 391.306123 -436.236905) (xy 391.283069 -436.229426) (xy 391.263455 -436.215188)
			(xy 391.249201 -436.195585) (xy 391.241705 -436.172536) (xy 391.24128 -436.160418) (xy 391.24128 -435.548024)
			(xy 391.239732 -435.533532) (xy 391.238082 -435.504432) (xy 391.237978 -435.489858) (xy 388.335012 -435.489858)
			(xy 388.335012 -436.160418) (xy 388.334505 -436.172529) (xy 388.327018 -436.195564) (xy 388.312784 -436.215161)
			(xy 388.293193 -436.229404) (xy 388.27016 -436.2369) (xy 388.25805 -436.23738) (xy 387.31825 -436.23738)
			(xy 387.306135 -436.236931) (xy 387.283093 -436.229432) (xy 387.263493 -436.215184) (xy 387.249253 -436.195578)
			(xy 387.241764 -436.172534) (xy 387.241288 -436.160418) (xy 387.241288 -435.548024) (xy 387.23974 -435.533532)
			(xy 387.23809 -435.504432) (xy 387.237986 -435.489858) (xy 384.33502 -435.489858) (xy 384.33502 -436.160418)
			(xy 384.334654 -436.172546) (xy 384.327152 -436.195612) (xy 384.312888 -436.215231) (xy 384.293258 -436.22948)
			(xy 384.270186 -436.236964) (xy 384.258058 -436.23738) (xy 383.318258 -436.23738) (xy 383.306143 -436.236924)
			(xy 383.283101 -436.229428) (xy 383.263502 -436.215181) (xy 383.249261 -436.195577) (xy 383.241772 -436.172533)
			(xy 383.241296 -436.160418) (xy 383.241296 -435.548024) (xy 383.239748 -435.533532) (xy 383.238098 -435.504432)
			(xy 383.237994 -435.489858) (xy 361.616728 -435.489858) (xy 361.642562 -435.536833) (xy 361.697938 -435.654184)
			(xy 361.74595 -435.774736) (xy 361.786412 -435.898026) (xy 361.81917 -436.023584) (xy 361.844098 -436.150927)
			(xy 361.861101 -436.279569) (xy 361.870114 -436.409016) (xy 361.871103 -436.538773) (xy 361.864062 -436.668342)
			(xy 361.849021 -436.797228) (xy 361.826035 -436.924936) (xy 361.795194 -437.050978) (xy 361.756614 -437.174871)
			(xy 361.710445 -437.29614) (xy 361.656862 -437.41432) (xy 361.596072 -437.52896) (xy 361.528306 -437.63962)
			(xy 361.453825 -437.745876) (xy 361.372914 -437.847321) (xy 361.285882 -437.943567) (xy 361.193064 -438.034245)
			(xy 361.128666 -438.089802) (xy 381.237998 -438.089802) (xy 381.238091 -438.075228) (xy 381.239744 -438.046127)
			(xy 381.2413 -438.031636) (xy 381.2413 -436.948072) (xy 381.239755 -436.93358) (xy 381.238103 -436.90448)
			(xy 381.237998 -436.889906) (xy 381.238091 -436.875332) (xy 381.239744 -436.846231) (xy 381.2413 -436.83174)
			(xy 381.2413 -436.219092) (xy 381.241709 -436.206983) (xy 381.249211 -436.183955) (xy 381.263474 -436.164382)
			(xy 381.283097 -436.150188) (xy 381.306151 -436.142767) (xy 381.318262 -436.142384) (xy 382.258062 -436.142384)
			(xy 382.270154 -436.142841) (xy 382.293161 -436.150292) (xy 382.312745 -436.16448) (xy 382.326995 -436.184019)
			(xy 382.334521 -436.207002) (xy 382.335024 -436.219092) (xy 382.335024 -438.760616) (xy 382.334598 -438.772723)
			(xy 382.327097 -438.795747) (xy 382.312837 -438.815318) (xy 382.293219 -438.829513) (xy 382.270171 -438.836937)
			(xy 382.258062 -438.837324) (xy 381.318262 -438.837324) (xy 381.306167 -438.836924) (xy 381.283159 -438.829453)
			(xy 381.263577 -438.81525) (xy 381.249329 -438.795701) (xy 381.241804 -438.77271) (xy 381.2413 -438.760616)
			(xy 381.2413 -438.147968) (xy 381.239755 -438.133476) (xy 381.238103 -438.104376) (xy 381.237998 -438.089802)
			(xy 361.128666 -438.089802) (xy 361.094814 -438.119007) (xy 360.991508 -438.19753) (xy 360.883543 -438.269512)
			(xy 360.771333 -438.334677) (xy 360.655306 -438.392776) (xy 360.535907 -438.443587) (xy 360.413594 -438.486915)
			(xy 360.288835 -438.522593) (xy 360.162108 -438.550485) (xy 360.033898 -438.570485) (xy 359.904696 -438.582516)
			(xy 359.774998 -438.586531) (xy 359.6453 -438.582516) (xy 359.516098 -438.570485) (xy 359.387888 -438.550485)
			(xy 359.261161 -438.522593) (xy 359.136402 -438.486915) (xy 359.014089 -438.443587) (xy 358.89469 -438.392776)
			(xy 358.778663 -438.334677) (xy 358.666453 -438.269512) (xy 358.558488 -438.19753) (xy 358.455182 -438.119007)
			(xy 358.356932 -438.034245) (xy 358.264114 -437.943567) (xy 358.177082 -437.847321) (xy 358.096171 -437.745876)
			(xy 358.02169 -437.63962) (xy 357.953924 -437.52896) (xy 357.893134 -437.41432) (xy 357.839551 -437.29614)
			(xy 357.793382 -437.174871) (xy 357.754802 -437.050978) (xy 357.723961 -436.924936) (xy 357.700975 -436.797228)
			(xy 357.685934 -436.668342) (xy 357.678893 -436.538773) (xy 357.679882 -436.409016) (xy 357.688895 -436.279569)
			(xy 357.705898 -436.150927) (xy 357.730826 -436.023584) (xy 357.763584 -435.898026) (xy 357.804046 -435.774736)
			(xy 357.852058 -435.654184) (xy 357.907434 -435.536833) (xy 357.969964 -435.423133) (xy 358.039407 -435.313518)
			(xy 358.115498 -435.208409) (xy 358.197945 -435.108208) (xy 358.286433 -435.013299) (xy 358.380622 -434.924045)
			(xy 358.430068 -434.882036) (xy 358.441235 -434.872067) (xy 358.457661 -434.847056) (xy 358.466134 -434.818358)
			(xy 358.465926 -434.788437) (xy 358.457055 -434.759859) (xy 358.440283 -434.735079) (xy 358.417049 -434.716224)
			(xy 358.403398 -434.710078) (xy 358.324356 -434.677212) (xy 358.169157 -434.604934) (xy 358.017549 -434.5254)
			(xy 357.869871 -434.438788) (xy 357.726451 -434.345291) (xy 357.587612 -434.24512) (xy 357.453663 -434.138498)
			(xy 357.324904 -434.025662) (xy 357.201623 -433.906867) (xy 357.084096 -433.782376) (xy 356.972584 -433.652469)
			(xy 356.867339 -433.517435) (xy 356.768594 -433.377578) (xy 356.676571 -433.233209) (xy 356.591476 -433.084651)
			(xy 356.513498 -432.932237) (xy 356.442812 -432.776307) (xy 356.379576 -432.61721) (xy 356.323932 -432.455301)
			(xy 356.276004 -432.290943) (xy 356.235899 -432.124503) (xy 356.203706 -431.956354) (xy 356.179498 -431.78687)
			(xy 356.163329 -431.616432) (xy 356.155235 -431.44542) (xy 356.154736 -431.359818) (xy 346.23502 -431.359818)
			(xy 346.23502 -432.560476) (xy 346.234563 -432.572582) (xy 346.227073 -432.595605) (xy 346.212821 -432.615176)
			(xy 346.193209 -432.629373) (xy 346.170165 -432.636797) (xy 346.158058 -432.637184) (xy 345.218258 -432.637184)
			(xy 345.206169 -432.636729) (xy 345.183171 -432.629264) (xy 345.163593 -432.615073) (xy 345.149343 -432.595539)
			(xy 345.141808 -432.572564) (xy 345.141296 -432.560476) (xy 345.141296 -432.044094) (xy 345.130612 -432.006448)
			(xy 345.119133 -431.929042) (xy 345.118436 -431.889916) (xy 342.235028 -431.889916) (xy 342.235028 -432.560476)
			(xy 342.234563 -432.572581) (xy 342.227074 -432.595602) (xy 342.212824 -432.615174) (xy 342.193214 -432.62937)
			(xy 342.170172 -432.636796) (xy 342.158066 -432.637184) (xy 341.218266 -432.637184) (xy 341.206177 -432.636722)
			(xy 341.183179 -432.629259) (xy 341.163602 -432.61507) (xy 341.149352 -432.595538) (xy 341.141816 -432.572563)
			(xy 341.141304 -432.560476) (xy 341.141304 -432.044094) (xy 341.13062 -432.006448) (xy 341.119141 -431.929042)
			(xy 341.118444 -431.889916) (xy 338.235036 -431.889916) (xy 338.235036 -432.560476) (xy 338.234564 -432.57258)
			(xy 338.227075 -432.5956) (xy 338.212827 -432.615171) (xy 338.193219 -432.629367) (xy 338.170179 -432.636795)
			(xy 338.158074 -432.637184) (xy 337.218274 -432.637184) (xy 337.206185 -432.636715) (xy 337.183188 -432.629254)
			(xy 337.163611 -432.615067) (xy 337.14936 -432.595536) (xy 337.141824 -432.572563) (xy 337.141312 -432.560476)
			(xy 337.141312 -432.044094) (xy 337.130628 -432.006448) (xy 337.119149 -431.929042) (xy 337.118452 -431.889916)
			(xy 334.235044 -431.889916) (xy 334.235044 -432.560476) (xy 334.234564 -432.572579) (xy 334.227076 -432.595598)
			(xy 334.21283 -432.615168) (xy 334.193224 -432.629365) (xy 334.170186 -432.636794) (xy 334.158082 -432.637184)
			(xy 333.218282 -432.637184) (xy 333.206194 -432.636709) (xy 333.183197 -432.62925) (xy 333.163619 -432.615065)
			(xy 333.149368 -432.595535) (xy 333.141832 -432.572563) (xy 333.14132 -432.560476) (xy 333.14132 -432.044094)
			(xy 333.130636 -432.006448) (xy 333.119157 -431.929042) (xy 333.11846 -431.889916) (xy 329.2348 -431.889916)
			(xy 329.2348 -432.560476) (xy 329.234367 -432.572558) (xy 329.226905 -432.595542) (xy 329.212704 -432.615093)
			(xy 329.193156 -432.629297) (xy 329.170174 -432.636764) (xy 329.158092 -432.637184) (xy 328.218292 -432.637184)
			(xy 328.206206 -432.636794) (xy 328.183219 -432.629321) (xy 328.163667 -432.61511) (xy 328.149464 -432.595552)
			(xy 328.142001 -432.572562) (xy 328.141584 -432.560476) (xy 328.141584 -432.044856) (xy 328.130788 -432.007034)
			(xy 328.119179 -431.929242) (xy 328.11847 -431.889916) (xy 325.234808 -431.889916) (xy 325.234808 -432.560476)
			(xy 325.234367 -432.572557) (xy 325.226906 -432.595539) (xy 325.212707 -432.61509) (xy 325.193161 -432.629295)
			(xy 325.170181 -432.636763) (xy 325.1581 -432.637184) (xy 324.2183 -432.637184) (xy 324.206215 -432.636787)
			(xy 324.183228 -432.629317) (xy 324.163676 -432.615107) (xy 324.149472 -432.59555) (xy 324.142009 -432.572561)
			(xy 324.141592 -432.560476) (xy 324.141592 -432.044856) (xy 324.130796 -432.007034) (xy 324.119187 -431.929242)
			(xy 324.118478 -431.889916) (xy 321.234816 -431.889916) (xy 321.234816 -432.560476) (xy 321.234367 -432.572557)
			(xy 321.226907 -432.595537) (xy 321.21271 -432.615087) (xy 321.193166 -432.629292) (xy 321.170188 -432.636762)
			(xy 321.158108 -432.637184) (xy 320.218308 -432.637184) (xy 320.206223 -432.63678) (xy 320.183237 -432.629312)
			(xy 320.163684 -432.615105) (xy 320.149481 -432.595549) (xy 320.142017 -432.572561) (xy 320.1416 -432.560476)
			(xy 320.1416 -432.044856) (xy 320.130804 -432.007034) (xy 320.119195 -431.929242) (xy 320.118486 -431.889916)
			(xy 317.234824 -431.889916) (xy 317.234824 -432.560476) (xy 317.234367 -432.572556) (xy 317.226908 -432.595535)
			(xy 317.212713 -432.615084) (xy 317.193171 -432.62929) (xy 317.170196 -432.636761) (xy 317.158116 -432.637184)
			(xy 316.218316 -432.637184) (xy 316.206232 -432.636773) (xy 316.183246 -432.629307) (xy 316.163693 -432.615101)
			(xy 316.149489 -432.595547) (xy 316.142026 -432.57256) (xy 316.141608 -432.560476) (xy 316.141608 -432.044856)
			(xy 316.130813 -432.007034) (xy 316.119203 -431.929242) (xy 316.118494 -431.889916) (xy 274.613204 -431.889916)
			(xy 274.618425 -431.905986) (xy 274.665585 -432.076867) (xy 274.705031 -432.249692) (xy 274.736684 -432.424113)
			(xy 274.760479 -432.599778) (xy 274.77637 -432.776334) (xy 274.784323 -432.953425) (xy 274.78482 -433.04206)
			(xy 274.784323 -433.130695) (xy 274.77637 -433.307786) (xy 274.760479 -433.484342) (xy 274.736684 -433.660007)
			(xy 274.705031 -433.834428) (xy 274.665585 -434.007253) (xy 274.618425 -434.178134) (xy 274.563646 -434.346728)
			(xy 274.509927 -434.48986) (xy 314.138056 -434.48986) (xy 314.138169 -434.474774) (xy 314.139948 -434.444656)
			(xy 314.141612 -434.429662) (xy 314.141612 -433.350162) (xy 314.139947 -433.335168) (xy 314.138166 -433.30505)
			(xy 314.138056 -433.289964) (xy 314.138169 -433.274878) (xy 314.139948 -433.24476) (xy 314.141612 -433.229766)
			(xy 314.141612 -432.618896) (xy 314.142009 -432.606811) (xy 314.14948 -432.583825) (xy 314.16369 -432.564273)
			(xy 314.183246 -432.550069) (xy 314.206235 -432.542606) (xy 314.21832 -432.542188) (xy 315.15812 -432.542188)
			(xy 315.170195 -432.542647) (xy 315.193162 -432.550115) (xy 315.212699 -432.564313) (xy 315.226893 -432.583852)
			(xy 315.234355 -432.606821) (xy 315.234828 -432.618896) (xy 315.234828 -435.16042) (xy 315.234353 -435.172494)
			(xy 315.226887 -435.195458) (xy 315.212693 -435.214993) (xy 315.193158 -435.229187) (xy 315.170194 -435.236653)
			(xy 315.15812 -435.237128) (xy 314.21832 -435.237128) (xy 314.206248 -435.236619) (xy 314.183285 -435.229165)
			(xy 314.16375 -435.214979) (xy 314.149554 -435.195451) (xy 314.142087 -435.172491) (xy 314.141612 -435.16042)
			(xy 314.141612 -434.550058) (xy 314.139946 -434.535064) (xy 314.138166 -434.504946) (xy 314.138056 -434.48986)
			(xy 274.509927 -434.48986) (xy 274.501358 -434.512693) (xy 274.431686 -434.675698) (xy 274.354772 -434.835412)
			(xy 274.270769 -434.991515) (xy 274.179848 -435.143692) (xy 274.082191 -435.291636) (xy 273.977994 -435.43505)
			(xy 273.934286 -435.489858) (xy 316.138052 -435.489858) (xy 316.138165 -435.474772) (xy 316.139944 -435.444654)
			(xy 316.141608 -435.42966) (xy 316.141608 -434.35016) (xy 316.139943 -434.335166) (xy 316.138162 -434.305048)
			(xy 316.138052 -434.289962) (xy 316.138165 -434.274876) (xy 316.139944 -434.244758) (xy 316.141608 -434.229764)
			(xy 316.141608 -433.618894) (xy 316.142102 -433.606807) (xy 316.149556 -433.583812) (xy 316.163737 -433.564235)
			(xy 316.183263 -433.549984) (xy 316.206231 -433.542446) (xy 316.218316 -433.541932) (xy 317.158116 -433.541932)
			(xy 317.170229 -433.542303) (xy 317.193262 -433.549811) (xy 317.212838 -433.564083) (xy 317.227031 -433.583716)
			(xy 317.234445 -433.606779) (xy 317.234824 -433.618894) (xy 317.234824 -434.48986) (xy 318.138048 -434.48986)
			(xy 318.138161 -434.474774) (xy 318.13994 -434.444656) (xy 318.141604 -434.429662) (xy 318.141604 -433.350162)
			(xy 318.139939 -433.335168) (xy 318.138158 -433.30505) (xy 318.138048 -433.289964) (xy 318.138161 -433.274878)
			(xy 318.13994 -433.24476) (xy 318.141604 -433.229766) (xy 318.141604 -432.618896) (xy 318.142009 -432.606812)
			(xy 318.149479 -432.583827) (xy 318.163687 -432.564276) (xy 318.183241 -432.550072) (xy 318.206228 -432.542607)
			(xy 318.218312 -432.542188) (xy 319.158112 -432.542188) (xy 319.170187 -432.542654) (xy 319.193154 -432.550119)
			(xy 319.21269 -432.564316) (xy 319.226884 -432.583854) (xy 319.234347 -432.606821) (xy 319.23482 -432.618896)
			(xy 319.23482 -435.16042) (xy 319.234353 -435.172494) (xy 319.226886 -435.19546) (xy 319.21269 -435.214996)
			(xy 319.193153 -435.22919) (xy 319.170186 -435.236654) (xy 319.158112 -435.237128) (xy 318.218312 -435.237128)
			(xy 318.20624 -435.236626) (xy 318.183277 -435.229169) (xy 318.163741 -435.214982) (xy 318.149546 -435.195452)
			(xy 318.142079 -435.172492) (xy 318.141604 -435.16042) (xy 318.141604 -434.550058) (xy 318.139938 -434.535064)
			(xy 318.138158 -434.504946) (xy 318.138048 -434.48986) (xy 317.234824 -434.48986) (xy 317.234824 -435.489858)
			(xy 320.138044 -435.489858) (xy 320.138157 -435.474772) (xy 320.139936 -435.444654) (xy 320.1416 -435.42966)
			(xy 320.1416 -434.35016) (xy 320.139934 -434.335166) (xy 320.138154 -434.305048) (xy 320.138044 -434.289962)
			(xy 320.138157 -434.274876) (xy 320.139936 -434.244758) (xy 320.1416 -434.229764) (xy 320.1416 -433.618894)
			(xy 320.142102 -433.606808) (xy 320.149555 -433.583814) (xy 320.163734 -433.564238) (xy 320.183258 -433.549986)
			(xy 320.206224 -433.542447) (xy 320.218308 -433.541932) (xy 321.158108 -433.541932) (xy 321.170221 -433.54231)
			(xy 321.193254 -433.549815) (xy 321.212829 -433.564086) (xy 321.227023 -433.583717) (xy 321.234437 -433.60678)
			(xy 321.234816 -433.618894) (xy 321.234816 -434.48986) (xy 322.13804 -434.48986) (xy 322.138153 -434.474774)
			(xy 322.139932 -434.444656) (xy 322.141596 -434.429662) (xy 322.141596 -433.350162) (xy 322.139931 -433.335168)
			(xy 322.13815 -433.30505) (xy 322.13804 -433.289964) (xy 322.138153 -433.274878) (xy 322.139932 -433.24476)
			(xy 322.141596 -433.229766) (xy 322.141596 -432.618896) (xy 322.142061 -432.606821) (xy 322.149525 -432.583853)
			(xy 322.163721 -432.564316) (xy 322.18326 -432.550121) (xy 322.206229 -432.54266) (xy 322.218304 -432.542188)
			(xy 323.158104 -432.542188) (xy 323.170178 -432.542661) (xy 323.193145 -432.550124) (xy 323.212682 -432.564318)
			(xy 323.226876 -432.583855) (xy 323.234339 -432.606822) (xy 323.234812 -432.618896) (xy 323.234812 -435.16042)
			(xy 323.234353 -435.172495) (xy 323.226885 -435.195462) (xy 323.212687 -435.214999) (xy 323.193148 -435.229193)
			(xy 323.170179 -435.236655) (xy 323.158104 -435.237128) (xy 322.218304 -435.237128) (xy 322.206232 -435.236633)
			(xy 322.183268 -435.229174) (xy 322.163733 -435.214984) (xy 322.149537 -435.195454) (xy 322.142071 -435.172492)
			(xy 322.141596 -435.16042) (xy 322.141596 -434.550058) (xy 322.13993 -434.535064) (xy 322.13815 -434.504946)
			(xy 322.13804 -434.48986) (xy 321.234816 -434.48986) (xy 321.234816 -435.489858) (xy 324.138036 -435.489858)
			(xy 324.138151 -435.474773) (xy 324.13993 -435.444654) (xy 324.141592 -435.42966) (xy 324.141592 -434.35016)
			(xy 324.139926 -434.335166) (xy 324.138146 -434.305048) (xy 324.138036 -434.289962) (xy 324.138151 -434.274877)
			(xy 324.13993 -434.244758) (xy 324.141592 -434.229764) (xy 324.141592 -433.618894) (xy 324.142102 -433.606809)
			(xy 324.149554 -433.583816) (xy 324.163731 -433.564241) (xy 324.183253 -433.549989) (xy 324.206217 -433.542448)
			(xy 324.2183 -433.541932) (xy 325.1581 -433.541932) (xy 325.170212 -433.542317) (xy 325.193245 -433.54982)
			(xy 325.212821 -433.564088) (xy 325.227014 -433.583719) (xy 325.234429 -433.60678) (xy 325.234808 -433.618894)
			(xy 325.234808 -434.48986) (xy 326.138032 -434.48986) (xy 326.138147 -434.474775) (xy 326.139926 -434.444656)
			(xy 326.141588 -434.429662) (xy 326.141588 -433.350162) (xy 326.139923 -433.335168) (xy 326.138142 -433.30505)
			(xy 326.138032 -433.289964) (xy 326.138148 -433.274879) (xy 326.139926 -433.24476) (xy 326.141588 -433.229766)
			(xy 326.141588 -432.618896) (xy 326.142061 -432.606822) (xy 326.149524 -432.583855) (xy 326.163718 -432.564318)
			(xy 326.183255 -432.550124) (xy 326.206222 -432.542661) (xy 326.218296 -432.542188) (xy 327.158096 -432.542188)
			(xy 327.17017 -432.542668) (xy 327.193136 -432.550129) (xy 327.212673 -432.564321) (xy 327.226868 -432.583857)
			(xy 327.234331 -432.606822) (xy 327.234804 -432.618896) (xy 327.234804 -435.16042) (xy 327.234353 -435.172496)
			(xy 327.226884 -435.195464) (xy 327.212684 -435.215001) (xy 327.193143 -435.229195) (xy 327.170172 -435.236656)
			(xy 327.158096 -435.237128) (xy 326.218296 -435.237128) (xy 326.206223 -435.236639) (xy 326.183259 -435.229178)
			(xy 326.163724 -435.214987) (xy 326.149529 -435.195455) (xy 326.142063 -435.172493) (xy 326.141588 -435.16042)
			(xy 326.141588 -434.550058) (xy 326.139922 -434.535064) (xy 326.138142 -434.504946) (xy 326.138032 -434.48986)
			(xy 325.234808 -434.48986) (xy 325.234808 -435.489858) (xy 328.138028 -435.489858) (xy 328.138143 -435.474773)
			(xy 328.139922 -435.444654) (xy 328.141584 -435.42966) (xy 328.141584 -434.35016) (xy 328.139918 -434.335166)
			(xy 328.138138 -434.305048) (xy 328.138028 -434.289962) (xy 328.138143 -434.274877) (xy 328.139922 -434.244758)
			(xy 328.141584 -434.229764) (xy 328.141584 -433.618894) (xy 328.142003 -433.6068) (xy 328.149467 -433.583792)
			(xy 328.163664 -433.564208) (xy 328.183211 -433.549959) (xy 328.206199 -433.542435) (xy 328.218292 -433.541932)
			(xy 329.158092 -433.541932) (xy 329.170204 -433.542323) (xy 329.193236 -433.549824) (xy 329.212812 -433.564091)
			(xy 329.227006 -433.58372) (xy 329.234421 -433.606781) (xy 329.2348 -433.618894) (xy 329.2348 -434.48986)
			(xy 331.138022 -434.48986) (xy 331.13812 -434.475286) (xy 331.13977 -434.446185) (xy 331.141324 -434.431694)
			(xy 331.141324 -433.34813) (xy 331.139776 -433.333638) (xy 331.138126 -433.304538) (xy 331.138022 -433.289964)
			(xy 331.13812 -433.27539) (xy 331.13977 -433.246289) (xy 331.141324 -433.231798) (xy 331.141324 -432.618896)
			(xy 331.141713 -432.606785) (xy 331.149217 -432.583753) (xy 331.163484 -432.564178) (xy 331.183113 -432.549984)
			(xy 331.206173 -432.542568) (xy 331.218286 -432.542188) (xy 332.158086 -432.542188) (xy 332.17018 -432.54262)
			(xy 332.193188 -432.550079) (xy 332.212772 -432.564273) (xy 332.227021 -432.583817) (xy 332.234545 -432.606804)
			(xy 332.235048 -432.618896) (xy 332.235048 -435.16042) (xy 332.234601 -435.172525) (xy 332.227102 -435.195545)
			(xy 332.212847 -435.215113) (xy 332.193235 -435.229309) (xy 332.170192 -435.236738) (xy 332.158086 -435.237128)
			(xy 331.218286 -435.237128) (xy 331.206192 -435.236704) (xy 331.183186 -435.22924) (xy 331.163603 -435.215043)
			(xy 331.149354 -435.195499) (xy 331.141828 -435.172512) (xy 331.141324 -435.16042) (xy 331.141324 -434.548026)
			(xy 331.139776 -434.533534) (xy 331.138126 -434.504434) (xy 331.138022 -434.48986) (xy 329.2348 -434.48986)
			(xy 329.2348 -435.489858) (xy 333.138018 -435.489858) (xy 333.138116 -435.475284) (xy 333.139766 -435.446183)
			(xy 333.14132 -435.431692) (xy 333.14132 -434.348128) (xy 333.139772 -434.333636) (xy 333.138122 -434.304536)
			(xy 333.138018 -434.289962) (xy 333.138116 -434.275388) (xy 333.139766 -434.246287) (xy 333.14132 -434.231796)
			(xy 333.14132 -433.618894) (xy 333.141807 -433.606781) (xy 333.149293 -433.583741) (xy 333.163532 -433.564141)
			(xy 333.18313 -433.549899) (xy 333.206169 -433.542408) (xy 333.218282 -433.541932) (xy 334.158082 -433.541932)
			(xy 334.170203 -433.542375) (xy 334.19326 -433.549862) (xy 334.212875 -433.564108) (xy 334.227127 -433.583718)
			(xy 334.234621 -433.606773) (xy 334.235044 -433.618894) (xy 334.235044 -434.48986) (xy 335.138014 -434.48986)
			(xy 335.138111 -434.475286) (xy 335.139761 -434.446185) (xy 335.141316 -434.431694) (xy 335.141316 -433.34813)
			(xy 335.139768 -433.333638) (xy 335.138118 -433.304538) (xy 335.138014 -433.289964) (xy 335.138112 -433.27539)
			(xy 335.139761 -433.246289) (xy 335.141316 -433.231798) (xy 335.141316 -432.618896) (xy 335.141713 -432.606785)
			(xy 335.149215 -432.583755) (xy 335.163481 -432.564181) (xy 335.183108 -432.549987) (xy 335.206166 -432.542569)
			(xy 335.218278 -432.542188) (xy 336.158078 -432.542188) (xy 336.170171 -432.542627) (xy 336.193179 -432.550084)
			(xy 336.212764 -432.564276) (xy 336.227013 -432.583818) (xy 336.234537 -432.606804) (xy 336.23504 -432.618896)
			(xy 336.23504 -435.16042) (xy 336.234601 -435.172526) (xy 336.227101 -435.195547) (xy 336.212844 -435.215116)
			(xy 336.19323 -435.229312) (xy 336.170185 -435.236739) (xy 336.158078 -435.237128) (xy 335.218278 -435.237128)
			(xy 335.206184 -435.236711) (xy 335.183177 -435.229244) (xy 335.163595 -435.215046) (xy 335.149346 -435.1955)
			(xy 335.14182 -435.172513) (xy 335.141316 -435.16042) (xy 335.141316 -434.548026) (xy 335.139768 -434.533534)
			(xy 335.138118 -434.504434) (xy 335.138014 -434.48986) (xy 334.235044 -434.48986) (xy 334.235044 -435.489858)
			(xy 337.13801 -435.489858) (xy 337.138107 -435.475284) (xy 337.139757 -435.446183) (xy 337.141312 -435.431692)
			(xy 337.141312 -434.348128) (xy 337.139764 -434.333636) (xy 337.138114 -434.304536) (xy 337.13801 -434.289962)
			(xy 337.138108 -434.275388) (xy 337.139757 -434.246287) (xy 337.141312 -434.231796) (xy 337.141312 -433.618894)
			(xy 337.141806 -433.606782) (xy 337.149292 -433.583743) (xy 337.163529 -433.564143) (xy 337.183125 -433.549901)
			(xy 337.206162 -433.54241) (xy 337.218274 -433.541932) (xy 338.158074 -433.541932) (xy 338.170195 -433.542382)
			(xy 338.193252 -433.549866) (xy 338.212867 -433.56411) (xy 338.227119 -433.58372) (xy 338.234613 -433.606773)
			(xy 338.235036 -433.618894) (xy 338.235036 -434.48986) (xy 339.138006 -434.48986) (xy 339.138104 -434.475286)
			(xy 339.139753 -434.446185) (xy 339.141308 -434.431694) (xy 339.141308 -433.34813) (xy 339.13976 -433.333638)
			(xy 339.13811 -433.304538) (xy 339.138006 -433.289964) (xy 339.138104 -433.27539) (xy 339.139753 -433.246289)
			(xy 339.141308 -433.231798) (xy 339.141308 -432.618896) (xy 339.141713 -432.606786) (xy 339.149214 -432.583757)
			(xy 339.163479 -432.564184) (xy 339.183103 -432.549989) (xy 339.206159 -432.54257) (xy 339.21827 -432.542188)
			(xy 340.15807 -432.542188) (xy 340.170163 -432.542634) (xy 340.19317 -432.550088) (xy 340.212755 -432.564278)
			(xy 340.227005 -432.58382) (xy 340.234529 -432.606805) (xy 340.235032 -432.618896) (xy 340.235032 -435.16042)
			(xy 340.234601 -435.172527) (xy 340.2271 -435.195549) (xy 340.212841 -435.215119) (xy 340.193225 -435.229314)
			(xy 340.170178 -435.23674) (xy 340.15807 -435.237128) (xy 339.21827 -435.237128) (xy 339.206176 -435.236718)
			(xy 339.183169 -435.229249) (xy 339.163586 -435.215049) (xy 339.149338 -435.195502) (xy 339.141812 -435.172513)
			(xy 339.141308 -435.16042) (xy 339.141308 -434.548026) (xy 339.13976 -434.533534) (xy 339.13811 -434.504434)
			(xy 339.138006 -434.48986) (xy 338.235036 -434.48986) (xy 338.235036 -435.489858) (xy 341.138002 -435.489858)
			(xy 341.138099 -435.475284) (xy 341.139749 -435.446183) (xy 341.141304 -435.431692) (xy 341.141304 -434.348128)
			(xy 341.139756 -434.333636) (xy 341.138106 -434.304536) (xy 341.138002 -434.289962) (xy 341.1381 -434.275388)
			(xy 341.139749 -434.246287) (xy 341.141304 -434.231796) (xy 341.141304 -433.618894) (xy 341.141806 -433.606783)
			(xy 341.149291 -433.583745) (xy 341.163526 -433.564146) (xy 341.18312 -433.549904) (xy 341.206155 -433.542411)
			(xy 341.218266 -433.541932) (xy 342.158066 -433.541932) (xy 342.170186 -433.542389) (xy 342.193243 -433.549871)
			(xy 342.212858 -433.564113) (xy 342.227111 -433.583721) (xy 342.234605 -433.606774) (xy 342.235028 -433.618894)
			(xy 342.235028 -434.48986) (xy 343.137998 -434.48986) (xy 343.138096 -434.475286) (xy 343.139745 -434.446185)
			(xy 343.1413 -434.431694) (xy 343.1413 -433.34813) (xy 343.139752 -433.333638) (xy 343.138102 -433.304538)
			(xy 343.137998 -433.289964) (xy 343.138096 -433.27539) (xy 343.139745 -433.246289) (xy 343.1413 -433.231798)
			(xy 343.1413 -432.618896) (xy 343.141713 -432.606787) (xy 343.149213 -432.583759) (xy 343.163476 -432.564186)
			(xy 343.183098 -432.549992) (xy 343.206152 -432.542571) (xy 343.218262 -432.542188) (xy 344.158062 -432.542188)
			(xy 344.170154 -432.542641) (xy 344.193162 -432.550093) (xy 344.212747 -432.564281) (xy 344.226997 -432.583821)
			(xy 344.234521 -432.606805) (xy 344.235024 -432.618896) (xy 344.235024 -435.16042) (xy 344.234601 -435.172528)
			(xy 344.227099 -435.195551) (xy 344.212838 -435.215122) (xy 344.19322 -435.229317) (xy 344.170171 -435.236741)
			(xy 344.158062 -435.237128) (xy 343.218262 -435.237128) (xy 343.206167 -435.236724) (xy 343.18316 -435.229253)
			(xy 343.163578 -435.215052) (xy 343.14933 -435.195503) (xy 343.141804 -435.172514) (xy 343.1413 -435.16042)
			(xy 343.1413 -434.548026) (xy 343.139752 -434.533534) (xy 343.138102 -434.504434) (xy 343.137998 -434.48986)
			(xy 342.235028 -434.48986) (xy 342.235028 -435.489858) (xy 345.137994 -435.489858) (xy 345.138091 -435.475284)
			(xy 345.139741 -435.446183) (xy 345.141296 -435.431692) (xy 345.141296 -434.348128) (xy 345.139748 -434.333636)
			(xy 345.138098 -434.304536) (xy 345.137994 -434.289962) (xy 345.138092 -434.275388) (xy 345.139741 -434.246287)
			(xy 345.141296 -434.231796) (xy 345.141296 -433.618894) (xy 345.141806 -433.606783) (xy 345.14929 -433.583747)
			(xy 345.163524 -433.564149) (xy 345.183115 -433.549906) (xy 345.206148 -433.542412) (xy 345.218258 -433.541932)
			(xy 346.158058 -433.541932) (xy 346.170178 -433.542396) (xy 346.193234 -433.549876) (xy 346.21285 -433.564116)
			(xy 346.227103 -433.583722) (xy 346.234597 -433.606774) (xy 346.23502 -433.618894) (xy 346.23502 -436.160418)
			(xy 346.234654 -436.172546) (xy 346.227152 -436.195612) (xy 346.212888 -436.215231) (xy 346.193258 -436.22948)
			(xy 346.170186 -436.236964) (xy 346.158058 -436.23738) (xy 345.218258 -436.23738) (xy 345.206143 -436.236924)
			(xy 345.183101 -436.229428) (xy 345.163502 -436.215181) (xy 345.149261 -436.195577) (xy 345.141772 -436.172533)
			(xy 345.141296 -436.160418) (xy 345.141296 -435.548024) (xy 345.139748 -435.533532) (xy 345.138098 -435.504432)
			(xy 345.137994 -435.489858) (xy 342.235028 -435.489858) (xy 342.235028 -436.160418) (xy 342.234655 -436.172545)
			(xy 342.227153 -436.19561) (xy 342.212891 -436.215228) (xy 342.193264 -436.229477) (xy 342.170193 -436.236963)
			(xy 342.158066 -436.23738) (xy 341.218266 -436.23738) (xy 341.206151 -436.236918) (xy 341.18311 -436.229423)
			(xy 341.16351 -436.215178) (xy 341.149269 -436.195576) (xy 341.14178 -436.172533) (xy 341.141304 -436.160418)
			(xy 341.141304 -435.548024) (xy 341.139755 -435.533532) (xy 341.138106 -435.504432) (xy 341.138002 -435.489858)
			(xy 338.235036 -435.489858) (xy 338.235036 -436.160418) (xy 338.234655 -436.172544) (xy 338.227154 -436.195608)
			(xy 338.212894 -436.215225) (xy 338.193269 -436.229474) (xy 338.1702 -436.236962) (xy 338.158074 -436.23738)
			(xy 337.218274 -436.23738) (xy 337.20616 -436.236911) (xy 337.183119 -436.229419) (xy 337.163519 -436.215175)
			(xy 337.149278 -436.195574) (xy 337.141788 -436.172532) (xy 337.141312 -436.160418) (xy 337.141312 -435.548024)
			(xy 337.139763 -435.533532) (xy 337.138114 -435.504432) (xy 337.13801 -435.489858) (xy 334.235044 -435.489858)
			(xy 334.235044 -436.160418) (xy 334.234604 -436.172535) (xy 334.227109 -436.195582) (xy 334.21286 -436.215185)
			(xy 334.19325 -436.229426) (xy 334.1702 -436.236909) (xy 334.158082 -436.23738) (xy 333.218282 -436.23738)
			(xy 333.206168 -436.236904) (xy 333.183127 -436.229414) (xy 333.163528 -436.215172) (xy 333.149286 -436.195573)
			(xy 333.141796 -436.172532) (xy 333.14132 -436.160418) (xy 333.14132 -435.548024) (xy 333.139771 -435.533532)
			(xy 333.138122 -435.504432) (xy 333.138018 -435.489858) (xy 329.2348 -435.489858) (xy 329.2348 -436.160418)
			(xy 329.234309 -436.172505) (xy 329.226852 -436.195499) (xy 329.21267 -436.215075) (xy 329.193145 -436.229327)
			(xy 329.170177 -436.236865) (xy 329.158092 -436.23738) (xy 328.218292 -436.23738) (xy 328.206181 -436.23699)
			(xy 328.18315 -436.229486) (xy 328.163575 -436.215219) (xy 328.149381 -436.19559) (xy 328.141964 -436.172531)
			(xy 328.141584 -436.160418) (xy 328.141584 -435.550056) (xy 328.139918 -435.535062) (xy 328.138138 -435.504944)
			(xy 328.138028 -435.489858) (xy 325.234808 -435.489858) (xy 325.234808 -436.160418) (xy 325.234309 -436.172504)
			(xy 325.226853 -436.195497) (xy 325.212673 -436.215072) (xy 325.19315 -436.229324) (xy 325.170184 -436.236864)
			(xy 325.1581 -436.23738) (xy 324.2183 -436.23738) (xy 324.206189 -436.236984) (xy 324.183158 -436.229482)
			(xy 324.163583 -436.215216) (xy 324.14939 -436.195589) (xy 324.141972 -436.17253) (xy 324.141592 -436.160418)
			(xy 324.141592 -435.550056) (xy 324.139926 -435.535062) (xy 324.138146 -435.504944) (xy 324.138036 -435.489858)
			(xy 321.234816 -435.489858) (xy 321.234816 -436.160418) (xy 321.234407 -436.172513) (xy 321.22694 -436.195522)
			(xy 321.21274 -436.215105) (xy 321.193192 -436.229353) (xy 321.170202 -436.236877) (xy 321.158108 -436.23738)
			(xy 320.218308 -436.23738) (xy 320.206198 -436.236977) (xy 320.183167 -436.229477) (xy 320.163592 -436.215213)
			(xy 320.149398 -436.195587) (xy 320.14198 -436.17253) (xy 320.1416 -436.160418) (xy 320.1416 -435.550056)
			(xy 320.139934 -435.535062) (xy 320.138154 -435.504944) (xy 320.138044 -435.489858) (xy 317.234824 -435.489858)
			(xy 317.234824 -436.160418) (xy 317.234407 -436.172512) (xy 317.226941 -436.195519) (xy 317.212743 -436.215102)
			(xy 317.193197 -436.229351) (xy 317.170209 -436.236876) (xy 317.158116 -436.23738) (xy 316.218316 -436.23738)
			(xy 316.206206 -436.23697) (xy 316.183176 -436.229472) (xy 316.163601 -436.21521) (xy 316.149406 -436.195585)
			(xy 316.141989 -436.172529) (xy 316.141608 -436.160418) (xy 316.141608 -435.550056) (xy 316.139942 -435.535062)
			(xy 316.138162 -435.504944) (xy 316.138052 -435.489858) (xy 273.934286 -435.489858) (xy 273.867468 -435.573645)
			(xy 273.750836 -435.707142) (xy 273.628331 -435.835271) (xy 273.500202 -435.957776) (xy 273.366705 -436.074408)
			(xy 273.22811 -436.184934) (xy 273.084696 -436.289131) (xy 272.936752 -436.386788) (xy 272.784575 -436.477709)
			(xy 272.628472 -436.561712) (xy 272.468758 -436.638626) (xy 272.305753 -436.708298) (xy 272.139788 -436.770586)
			(xy 271.971194 -436.825365) (xy 271.800313 -436.872525) (xy 271.627488 -436.911971) (xy 271.453067 -436.943624)
			(xy 271.277402 -436.967419) (xy 271.100846 -436.98331) (xy 270.923755 -436.991263) (xy 270.746485 -436.991263)
			(xy 270.569394 -436.98331) (xy 270.392838 -436.967419) (xy 270.217173 -436.943624) (xy 270.042752 -436.911971)
			(xy 269.869927 -436.872525) (xy 269.699046 -436.825365) (xy 269.530452 -436.770586) (xy 269.364487 -436.708298)
			(xy 269.201482 -436.638626) (xy 269.041768 -436.561712) (xy 268.885665 -436.477709) (xy 268.733488 -436.386788)
			(xy 268.585544 -436.289131) (xy 268.44213 -436.184934) (xy 268.303535 -436.074408) (xy 268.170038 -435.957776)
			(xy 268.041909 -435.835271) (xy 267.919404 -435.707142) (xy 267.802772 -435.573645) (xy 267.692246 -435.43505)
			(xy 267.588049 -435.291636) (xy 267.490392 -435.143692) (xy 267.399471 -434.991515) (xy 267.315468 -434.835412)
			(xy 267.238554 -434.675698) (xy 267.168882 -434.512693) (xy 267.106594 -434.346728) (xy 267.051815 -434.178134)
			(xy 267.004655 -434.007253) (xy 266.965209 -433.834428) (xy 266.933556 -433.660007) (xy 266.909761 -433.484342)
			(xy 266.89387 -433.307786) (xy 266.885917 -433.130695) (xy 231.01554 -433.130695) (xy 231.01554 -435.063392)
			(xy 231.015024 -435.08834) (xy 231.007214 -435.137622) (xy 230.991802 -435.185079) (xy 230.969165 -435.229545)
			(xy 230.939859 -435.269929) (xy 230.922576 -435.287928) (xy 229.133908 -437.076596) (xy 229.115913 -437.093886)
			(xy 229.075537 -437.12321) (xy 229.031071 -437.145858) (xy 228.98361 -437.161272) (xy 228.934323 -437.169073)
			(xy 228.909372 -437.16956) (xy 207.503268 -437.16956) (xy 207.478319 -437.169063) (xy 207.429037 -437.161248)
			(xy 207.38158 -437.14583) (xy 207.337114 -437.123189) (xy 207.296731 -437.09388) (xy 207.278732 -437.076596)
			(xy 205.949804 -435.747668) (xy 205.932495 -435.72969) (xy 205.903173 -435.68931) (xy 205.880529 -435.64484)
			(xy 205.865119 -435.597375) (xy 205.857324 -435.548084) (xy 205.85684 -435.523132) (xy 205.85684 -429.817784)
			(xy 197.285356 -421.2463) (xy 192.75044 -421.2463) (xy 192.725489 -421.245838) (xy 192.676205 -421.238017)
			(xy 192.628747 -421.222592) (xy 192.584282 -421.199943) (xy 192.543901 -421.170625) (xy 192.525904 -421.153336)
			(xy 184.781952 -413.409384) (xy 184.764639 -413.391408) (xy 184.735311 -413.351029) (xy 184.712661 -413.306559)
			(xy 184.697247 -413.259094) (xy 184.689448 -413.209801) (xy 184.688988 -413.184848) (xy 184.688988 -408.491182)
			(xy 184.68948 -408.466233) (xy 184.697294 -408.416949) (xy 184.712712 -408.369492) (xy 184.735355 -408.325026)
			(xy 184.764667 -408.284644) (xy 184.781952 -408.266646) (xy 184.892188 -408.15641) (xy 184.892188 -407.290778)
			(xy 184.874462 -407.269826) (xy 184.844586 -407.223792) (xy 184.821621 -407.173948) (xy 184.806044 -407.121325)
			(xy 184.798176 -407.067012) (xy 184.7977 -407.039572) (xy 184.798716 -407.01341) (xy 184.80024 -406.99055)
			(xy 184.654952 -406.845262) (xy 184.637629 -406.827296) (xy 184.608302 -406.786914) (xy 184.585654 -406.742442)
			(xy 184.570242 -406.694974) (xy 184.562446 -406.64568) (xy 184.561988 -406.620726) (xy 16.741648 -406.620726)
			(xy 16.741648 -407.031753) (xy 48.944975 -407.031753) (xy 48.944975 -406.977247) (xy 48.952733 -406.923295)
			(xy 48.96809 -406.870997) (xy 48.990734 -406.821417) (xy 49.020204 -406.775565) (xy 49.0559 -406.734373)
			(xy 49.097095 -406.698681) (xy 49.142951 -406.669216) (xy 49.192533 -406.646577) (xy 49.244833 -406.631225)
			(xy 49.298785 -406.623473) (xy 49.326038 -406.623012) (xy 50.189638 -406.623012) (xy 50.216889 -406.62346)
			(xy 50.270835 -406.631222) (xy 50.323128 -406.646581) (xy 50.372703 -406.669225) (xy 50.418551 -406.698694)
			(xy 50.459739 -406.734388) (xy 50.495428 -406.775579) (xy 50.524893 -406.82143) (xy 50.547532 -406.871007)
			(xy 50.562886 -406.923302) (xy 50.570642 -406.977249) (xy 50.570642 -407.031749) (xy 52.008298 -407.031749)
			(xy 52.008298 -406.977251) (xy 52.016054 -406.923308) (xy 52.031407 -406.871018) (xy 52.054045 -406.821445)
			(xy 52.083508 -406.775598) (xy 52.119195 -406.734411) (xy 52.16038 -406.698721) (xy 52.206226 -406.669256)
			(xy 52.255797 -406.646615) (xy 52.308087 -406.631258) (xy 52.362029 -406.6235) (xy 52.389278 -406.623012)
			(xy 53.252878 -406.623012) (xy 53.280133 -406.623433) (xy 53.33409 -406.631188) (xy 53.386393 -406.646543)
			(xy 53.435978 -406.669186) (xy 53.481837 -406.698655) (xy 53.523034 -406.73435) (xy 53.558732 -406.775546)
			(xy 53.588204 -406.821402) (xy 53.610849 -406.870987) (xy 53.626207 -406.923289) (xy 53.633965 -406.977245)
			(xy 53.633965 -407.031752) (xy 55.071475 -407.031752) (xy 55.071475 -406.977248) (xy 55.079232 -406.923298)
			(xy 55.094589 -406.871002) (xy 55.117231 -406.821423) (xy 55.146699 -406.775571) (xy 55.182393 -406.73438)
			(xy 55.223586 -406.698688) (xy 55.269439 -406.669222) (xy 55.319018 -406.646582) (xy 55.371316 -406.631229)
			(xy 55.425266 -406.623474) (xy 55.452518 -406.623012) (xy 56.316118 -406.623012) (xy 56.34337 -406.623459)
			(xy 56.397318 -406.631218) (xy 56.449614 -406.646576) (xy 56.499191 -406.669219) (xy 56.545042 -406.698687)
			(xy 56.586232 -406.734381) (xy 56.621924 -406.775573) (xy 56.65139 -406.821424) (xy 56.674031 -406.871003)
			(xy 56.689386 -406.923299) (xy 56.697142 -406.977248) (xy 56.697142 -407.031748) (xy 58.134798 -407.031748)
			(xy 58.134798 -406.977252) (xy 58.142553 -406.923311) (xy 58.157905 -406.871022) (xy 58.180542 -406.821451)
			(xy 58.210003 -406.775605) (xy 58.245688 -406.734418) (xy 58.286871 -406.698728) (xy 58.332714 -406.669262)
			(xy 58.382283 -406.64662) (xy 58.43457 -406.631262) (xy 58.48851 -406.623501) (xy 58.515758 -406.623012)
			(xy 59.379358 -406.623012) (xy 59.406614 -406.623432) (xy 59.460573 -406.631185) (xy 59.512878 -406.646538)
			(xy 59.562466 -406.669179) (xy 59.608327 -406.698648) (xy 59.649527 -406.734343) (xy 59.685227 -406.775539)
			(xy 59.714701 -406.821397) (xy 59.737348 -406.870982) (xy 59.752707 -406.923286) (xy 59.760465 -406.977244)
			(xy 59.760465 -407.03175) (xy 61.197998 -407.03175) (xy 61.197998 -406.97725) (xy 61.205754 -406.923306)
			(xy 61.221108 -406.871014) (xy 61.243748 -406.821439) (xy 61.273213 -406.775592) (xy 61.308902 -406.734404)
			(xy 61.35009 -406.698714) (xy 61.395938 -406.669249) (xy 61.445512 -406.646609) (xy 61.497804 -406.631255)
			(xy 61.551748 -406.623498) (xy 61.578998 -406.623012) (xy 62.442598 -406.623012) (xy 62.469852 -406.623435)
			(xy 62.523806 -406.631192) (xy 62.576107 -406.646549) (xy 62.62569 -406.669192) (xy 62.671546 -406.698662)
			(xy 62.712741 -406.734357) (xy 62.748437 -406.775552) (xy 62.777907 -406.821408) (xy 62.800551 -406.870991)
			(xy 62.815908 -406.923292) (xy 62.823665 -406.977246) (xy 62.823665 -407.031753) (xy 64.261175 -407.031753)
			(xy 64.261175 -406.977247) (xy 64.268933 -406.923295) (xy 64.28429 -406.870997) (xy 64.306934 -406.821417)
			(xy 64.336404 -406.775565) (xy 64.3721 -406.734373) (xy 64.413295 -406.698681) (xy 64.459151 -406.669216)
			(xy 64.508733 -406.646577) (xy 64.561033 -406.631225) (xy 64.614985 -406.623473) (xy 64.642238 -406.623012)
			(xy 65.505838 -406.623012) (xy 65.533089 -406.62346) (xy 65.587035 -406.631222) (xy 65.639328 -406.646581)
			(xy 65.688903 -406.669225) (xy 65.734751 -406.698694) (xy 65.775939 -406.734388) (xy 65.811628 -406.775579)
			(xy 65.841093 -406.82143) (xy 65.863732 -406.871007) (xy 65.879086 -406.923302) (xy 65.886842 -406.977249)
			(xy 65.886842 -407.031749) (xy 67.324498 -407.031749) (xy 67.324498 -406.977251) (xy 67.332254 -406.923308)
			(xy 67.347607 -406.871018) (xy 67.370245 -406.821445) (xy 67.399708 -406.775598) (xy 67.435395 -406.734411)
			(xy 67.47658 -406.698721) (xy 67.522426 -406.669256) (xy 67.571997 -406.646615) (xy 67.624287 -406.631258)
			(xy 67.678229 -406.6235) (xy 67.705478 -406.623012) (xy 68.569078 -406.623012) (xy 68.596333 -406.623433)
			(xy 68.65029 -406.631188) (xy 68.702593 -406.646543) (xy 68.752178 -406.669186) (xy 68.798037 -406.698655)
			(xy 68.839234 -406.73435) (xy 68.874932 -406.775546) (xy 68.904404 -406.821402) (xy 68.927049 -406.870987)
			(xy 68.942407 -406.923289) (xy 68.950165 -406.977245) (xy 68.950165 -407.031752) (xy 70.387675 -407.031752)
			(xy 70.387675 -406.977248) (xy 70.395432 -406.923298) (xy 70.410789 -406.871002) (xy 70.433431 -406.821423)
			(xy 70.462899 -406.775571) (xy 70.498593 -406.73438) (xy 70.539786 -406.698688) (xy 70.585639 -406.669222)
			(xy 70.635218 -406.646582) (xy 70.687516 -406.631229) (xy 70.741466 -406.623474) (xy 70.768718 -406.623012)
			(xy 71.632318 -406.623012) (xy 71.65957 -406.623459) (xy 71.713518 -406.631218) (xy 71.765814 -406.646576)
			(xy 71.815391 -406.669219) (xy 71.861242 -406.698687) (xy 71.902432 -406.734381) (xy 71.938124 -406.775573)
			(xy 71.96759 -406.821424) (xy 71.990231 -406.871003) (xy 72.005586 -406.923299) (xy 72.013342 -406.977248)
			(xy 72.013342 -407.031748) (xy 73.450998 -407.031748) (xy 73.450998 -406.977252) (xy 73.458753 -406.923311)
			(xy 73.474105 -406.871022) (xy 73.496742 -406.821451) (xy 73.526203 -406.775605) (xy 73.561888 -406.734418)
			(xy 73.603071 -406.698728) (xy 73.648914 -406.669262) (xy 73.698483 -406.64662) (xy 73.75077 -406.631262)
			(xy 73.80471 -406.623501) (xy 73.831958 -406.623012) (xy 74.695558 -406.623012) (xy 74.722814 -406.623432)
			(xy 74.776773 -406.631185) (xy 74.829078 -406.646538) (xy 74.878666 -406.669179) (xy 74.924527 -406.698648)
			(xy 74.965727 -406.734343) (xy 75.001427 -406.775539) (xy 75.030901 -406.821397) (xy 75.053548 -406.870982)
			(xy 75.068907 -406.923286) (xy 75.076665 -406.977244) (xy 75.076665 -407.03175) (xy 76.514198 -407.03175)
			(xy 76.514198 -406.97725) (xy 76.521954 -406.923306) (xy 76.537308 -406.871014) (xy 76.559948 -406.821439)
			(xy 76.589413 -406.775592) (xy 76.625102 -406.734404) (xy 76.66629 -406.698714) (xy 76.712138 -406.669249)
			(xy 76.761712 -406.646609) (xy 76.814004 -406.631255) (xy 76.867948 -406.623498) (xy 76.895198 -406.623012)
			(xy 77.758798 -406.623012) (xy 77.786052 -406.623435) (xy 77.840006 -406.631192) (xy 77.892307 -406.646549)
			(xy 77.94189 -406.669192) (xy 77.987746 -406.698662) (xy 78.028941 -406.734357) (xy 78.064637 -406.775552)
			(xy 78.094107 -406.821408) (xy 78.116751 -406.870991) (xy 78.132108 -406.923292) (xy 78.139865 -406.977246)
			(xy 78.139865 -407.031753) (xy 79.577375 -407.031753) (xy 79.577375 -406.977247) (xy 79.585133 -406.923295)
			(xy 79.60049 -406.870997) (xy 79.623134 -406.821417) (xy 79.652604 -406.775565) (xy 79.6883 -406.734373)
			(xy 79.729495 -406.698681) (xy 79.775351 -406.669216) (xy 79.824933 -406.646577) (xy 79.877233 -406.631225)
			(xy 79.931185 -406.623473) (xy 79.958438 -406.623012) (xy 80.822038 -406.623012) (xy 80.849289 -406.62346)
			(xy 80.903235 -406.631222) (xy 80.955528 -406.646581) (xy 81.005103 -406.669225) (xy 81.050951 -406.698694)
			(xy 81.092139 -406.734388) (xy 81.127828 -406.775579) (xy 81.157293 -406.82143) (xy 81.179932 -406.871007)
			(xy 81.195286 -406.923302) (xy 81.203042 -406.977249) (xy 81.203042 -407.031749) (xy 82.640698 -407.031749)
			(xy 82.640698 -406.977251) (xy 82.648454 -406.923308) (xy 82.663807 -406.871018) (xy 82.686445 -406.821445)
			(xy 82.715908 -406.775598) (xy 82.751595 -406.734411) (xy 82.79278 -406.698721) (xy 82.838626 -406.669256)
			(xy 82.888197 -406.646615) (xy 82.940487 -406.631258) (xy 82.994429 -406.6235) (xy 83.021678 -406.623012)
			(xy 83.885278 -406.623012) (xy 83.912533 -406.623433) (xy 83.96649 -406.631188) (xy 84.018793 -406.646543)
			(xy 84.068378 -406.669186) (xy 84.114237 -406.698655) (xy 84.155434 -406.73435) (xy 84.191132 -406.775546)
			(xy 84.220604 -406.821402) (xy 84.243249 -406.870987) (xy 84.258607 -406.923289) (xy 84.266365 -406.977245)
			(xy 84.266365 -407.031752) (xy 85.703875 -407.031752) (xy 85.703875 -406.977248) (xy 85.711632 -406.923298)
			(xy 85.726989 -406.871002) (xy 85.749631 -406.821423) (xy 85.779099 -406.775571) (xy 85.814793 -406.73438)
			(xy 85.855986 -406.698688) (xy 85.901839 -406.669222) (xy 85.951418 -406.646582) (xy 86.003716 -406.631229)
			(xy 86.057666 -406.623474) (xy 86.084918 -406.623012) (xy 86.948518 -406.623012) (xy 86.97577 -406.623459)
			(xy 87.029718 -406.631218) (xy 87.082014 -406.646576) (xy 87.131591 -406.669219) (xy 87.177442 -406.698687)
			(xy 87.218632 -406.734381) (xy 87.254324 -406.775573) (xy 87.28379 -406.821424) (xy 87.306431 -406.871003)
			(xy 87.321786 -406.923299) (xy 87.329542 -406.977248) (xy 87.329542 -407.031748) (xy 88.767198 -407.031748)
			(xy 88.767198 -406.977252) (xy 88.774953 -406.923311) (xy 88.790305 -406.871022) (xy 88.812942 -406.821451)
			(xy 88.842403 -406.775605) (xy 88.878088 -406.734418) (xy 88.919271 -406.698728) (xy 88.965114 -406.669262)
			(xy 89.014683 -406.64662) (xy 89.06697 -406.631262) (xy 89.12091 -406.623501) (xy 89.148158 -406.623012)
			(xy 90.011758 -406.623012) (xy 90.039014 -406.623432) (xy 90.092973 -406.631185) (xy 90.145278 -406.646538)
			(xy 90.194866 -406.669179) (xy 90.240727 -406.698648) (xy 90.281927 -406.734343) (xy 90.317627 -406.775539)
			(xy 90.347101 -406.821397) (xy 90.369748 -406.870982) (xy 90.385107 -406.923286) (xy 90.392865 -406.977244)
			(xy 90.392865 -407.03175) (xy 91.830398 -407.03175) (xy 91.830398 -406.97725) (xy 91.838154 -406.923306)
			(xy 91.853508 -406.871014) (xy 91.876148 -406.821439) (xy 91.905613 -406.775592) (xy 91.941302 -406.734404)
			(xy 91.98249 -406.698714) (xy 92.028338 -406.669249) (xy 92.077912 -406.646609) (xy 92.130204 -406.631255)
			(xy 92.184148 -406.623498) (xy 92.211398 -406.623012) (xy 93.074998 -406.623012) (xy 93.102252 -406.623435)
			(xy 93.156206 -406.631192) (xy 93.208507 -406.646549) (xy 93.25809 -406.669192) (xy 93.303946 -406.698662)
			(xy 93.345141 -406.734357) (xy 93.380837 -406.775552) (xy 93.410307 -406.821408) (xy 93.432951 -406.870991)
			(xy 93.448308 -406.923292) (xy 93.456065 -406.977246) (xy 93.456065 -407.031753) (xy 94.893575 -407.031753)
			(xy 94.893575 -406.977247) (xy 94.901333 -406.923295) (xy 94.91669 -406.870997) (xy 94.939334 -406.821417)
			(xy 94.968804 -406.775565) (xy 95.0045 -406.734373) (xy 95.045695 -406.698681) (xy 95.091551 -406.669216)
			(xy 95.141133 -406.646577) (xy 95.193433 -406.631225) (xy 95.247385 -406.623473) (xy 95.274638 -406.623012)
			(xy 96.138238 -406.623012) (xy 96.165489 -406.62346) (xy 96.219435 -406.631222) (xy 96.271728 -406.646581)
			(xy 96.321303 -406.669225) (xy 96.367151 -406.698694) (xy 96.408339 -406.734388) (xy 96.444028 -406.775579)
			(xy 96.473493 -406.82143) (xy 96.496132 -406.871007) (xy 96.511486 -406.923302) (xy 96.519242 -406.977249)
			(xy 96.519242 -407.031751) (xy 96.511486 -407.085698) (xy 96.496132 -407.137993) (xy 96.495694 -407.138953)
			(xy 106.243063 -407.138953) (xy 106.243063 -407.084447) (xy 106.250821 -407.030495) (xy 106.266177 -406.978197)
			(xy 106.288821 -406.928617) (xy 106.31829 -406.882763) (xy 106.353985 -406.841571) (xy 106.395179 -406.805878)
			(xy 106.441034 -406.776411) (xy 106.490616 -406.75377) (xy 106.542915 -406.738416) (xy 106.596867 -406.730662)
			(xy 106.62412 -406.7302) (xy 107.48772 -406.7302) (xy 107.514971 -406.730671) (xy 107.568918 -406.73843)
			(xy 107.621211 -406.753787) (xy 107.670787 -406.77643) (xy 107.716636 -406.805898) (xy 107.757824 -406.84159)
			(xy 107.793514 -406.88278) (xy 107.82298 -406.928631) (xy 107.84562 -406.978208) (xy 107.860974 -407.030502)
			(xy 107.861153 -407.031748) (xy 121.120198 -407.031748) (xy 121.120198 -406.977252) (xy 121.127953 -406.923312)
			(xy 121.143305 -406.871023) (xy 121.165942 -406.821452) (xy 121.195402 -406.775606) (xy 121.231087 -406.734419)
			(xy 121.272269 -406.69873) (xy 121.318111 -406.669264) (xy 121.36768 -406.646621) (xy 121.419967 -406.631263)
			(xy 121.473906 -406.623501) (xy 121.501154 -406.623012) (xy 122.364754 -406.623012) (xy 122.39201 -406.623432)
			(xy 122.445969 -406.631184) (xy 122.498275 -406.646537) (xy 122.547864 -406.669178) (xy 122.593725 -406.698646)
			(xy 122.634926 -406.734342) (xy 122.670626 -406.775538) (xy 122.7001 -406.821396) (xy 122.722747 -406.870981)
			(xy 122.738106 -406.923286) (xy 122.745865 -406.977244) (xy 122.745865 -407.03175) (xy 124.183398 -407.03175)
			(xy 124.183398 -406.97725) (xy 124.191154 -406.923306) (xy 124.206508 -406.871015) (xy 124.229148 -406.821441)
			(xy 124.258612 -406.775593) (xy 124.294301 -406.734405) (xy 124.335488 -406.698715) (xy 124.381335 -406.669251)
			(xy 124.430909 -406.64661) (xy 124.4832 -406.631255) (xy 124.537144 -406.623499) (xy 124.564394 -406.623012)
			(xy 125.427994 -406.623012) (xy 125.455249 -406.623434) (xy 125.509203 -406.631191) (xy 125.561504 -406.646548)
			(xy 125.611088 -406.669191) (xy 125.656944 -406.69866) (xy 125.69814 -406.734356) (xy 125.733836 -406.775551)
			(xy 125.763306 -406.821407) (xy 125.78595 -406.87099) (xy 125.801308 -406.923291) (xy 125.809065 -406.977245)
			(xy 125.809065 -407.031753) (xy 127.246575 -407.031753) (xy 127.246575 -406.977247) (xy 127.254333 -406.923296)
			(xy 127.26969 -406.870998) (xy 127.292334 -406.821418) (xy 127.321803 -406.775566) (xy 127.357499 -406.734375)
			(xy 127.398693 -406.698683) (xy 127.444548 -406.669217) (xy 127.49413 -406.646578) (xy 127.546429 -406.631226)
			(xy 127.600381 -406.623473) (xy 127.627634 -406.623012) (xy 128.491234 -406.623012) (xy 128.518485 -406.62346)
			(xy 128.572432 -406.631221) (xy 128.624725 -406.64658) (xy 128.674301 -406.669224) (xy 128.720149 -406.698693)
			(xy 128.761338 -406.734386) (xy 128.797028 -406.775578) (xy 128.826492 -406.821429) (xy 128.849132 -406.871007)
			(xy 128.864486 -406.923301) (xy 128.872242 -406.977249) (xy 128.872242 -407.031749) (xy 130.309898 -407.031749)
			(xy 130.309898 -406.977251) (xy 130.317654 -406.923309) (xy 130.333007 -406.871019) (xy 130.355645 -406.821446)
			(xy 130.385107 -406.775599) (xy 130.420794 -406.734412) (xy 130.461979 -406.698722) (xy 130.507823 -406.669257)
			(xy 130.557395 -406.646616) (xy 130.609683 -406.631259) (xy 130.663625 -406.6235) (xy 130.690874 -406.623012)
			(xy 131.554474 -406.623012) (xy 131.58173 -406.623433) (xy 131.635686 -406.631187) (xy 131.68799 -406.646542)
			(xy 131.737576 -406.669184) (xy 131.783435 -406.698653) (xy 131.824633 -406.734349) (xy 131.860331 -406.775544)
			(xy 131.889803 -406.821401) (xy 131.912449 -406.870986) (xy 131.927807 -406.923288) (xy 131.935565 -406.977245)
			(xy 131.935565 -407.031752) (xy 133.373075 -407.031752) (xy 133.373075 -406.977248) (xy 133.380832 -406.923299)
			(xy 133.396188 -406.871002) (xy 133.418831 -406.821424) (xy 133.448298 -406.775573) (xy 133.483992 -406.734382)
			(xy 133.525184 -406.69869) (xy 133.571036 -406.669224) (xy 133.620616 -406.646583) (xy 133.672912 -406.631229)
			(xy 133.726862 -406.623474) (xy 133.754114 -406.623012) (xy 134.617714 -406.623012) (xy 134.644966 -406.623459)
			(xy 134.698915 -406.631217) (xy 134.751211 -406.646574) (xy 134.800789 -406.669218) (xy 134.84664 -406.698686)
			(xy 134.887831 -406.734379) (xy 134.923523 -406.775571) (xy 134.952989 -406.821423) (xy 134.97563 -406.871002)
			(xy 134.990986 -406.923299) (xy 134.998742 -406.977248) (xy 134.998742 -407.031748) (xy 136.436398 -407.031748)
			(xy 136.436398 -406.977252) (xy 136.444153 -406.923312) (xy 136.459505 -406.871023) (xy 136.482142 -406.821452)
			(xy 136.511602 -406.775606) (xy 136.547287 -406.734419) (xy 136.588469 -406.69873) (xy 136.634311 -406.669264)
			(xy 136.68388 -406.646621) (xy 136.736167 -406.631263) (xy 136.790106 -406.623501) (xy 136.817354 -406.623012)
			(xy 137.680954 -406.623012) (xy 137.70821 -406.623432) (xy 137.762169 -406.631184) (xy 137.814475 -406.646537)
			(xy 137.864064 -406.669178) (xy 137.909925 -406.698646) (xy 137.951126 -406.734342) (xy 137.986826 -406.775538)
			(xy 138.0163 -406.821396) (xy 138.038947 -406.870981) (xy 138.054306 -406.923286) (xy 138.062065 -406.977244)
			(xy 138.062065 -407.03175) (xy 139.499598 -407.03175) (xy 139.499598 -406.97725) (xy 139.507354 -406.923306)
			(xy 139.522708 -406.871015) (xy 139.545348 -406.821441) (xy 139.574812 -406.775593) (xy 139.610501 -406.734405)
			(xy 139.651688 -406.698715) (xy 139.697535 -406.669251) (xy 139.747109 -406.64661) (xy 139.7994 -406.631255)
			(xy 139.853344 -406.623499) (xy 139.880594 -406.623012) (xy 140.744194 -406.623012) (xy 140.771449 -406.623434)
			(xy 140.825403 -406.631191) (xy 140.877704 -406.646548) (xy 140.927288 -406.669191) (xy 140.973144 -406.69866)
			(xy 141.01434 -406.734356) (xy 141.050036 -406.775551) (xy 141.079506 -406.821407) (xy 141.10215 -406.87099)
			(xy 141.117508 -406.923291) (xy 141.125265 -406.977245) (xy 141.125265 -407.031753) (xy 142.562775 -407.031753)
			(xy 142.562775 -406.977247) (xy 142.570533 -406.923296) (xy 142.58589 -406.870998) (xy 142.608534 -406.821418)
			(xy 142.638003 -406.775566) (xy 142.673699 -406.734375) (xy 142.714893 -406.698683) (xy 142.760748 -406.669217)
			(xy 142.81033 -406.646578) (xy 142.862629 -406.631226) (xy 142.916581 -406.623473) (xy 142.943834 -406.623012)
			(xy 143.807434 -406.623012) (xy 143.834685 -406.62346) (xy 143.888632 -406.631221) (xy 143.940925 -406.64658)
			(xy 143.990501 -406.669224) (xy 144.036349 -406.698693) (xy 144.077538 -406.734386) (xy 144.113228 -406.775578)
			(xy 144.142692 -406.821429) (xy 144.165332 -406.871007) (xy 144.180686 -406.923301) (xy 144.188442 -406.977249)
			(xy 144.188442 -407.031749) (xy 145.626098 -407.031749) (xy 145.626098 -406.977251) (xy 145.633854 -406.923309)
			(xy 145.649207 -406.871019) (xy 145.671845 -406.821446) (xy 145.701307 -406.775599) (xy 145.736994 -406.734412)
			(xy 145.778179 -406.698722) (xy 145.824023 -406.669257) (xy 145.873595 -406.646616) (xy 145.925883 -406.631259)
			(xy 145.979825 -406.6235) (xy 146.007074 -406.623012) (xy 146.870674 -406.623012) (xy 146.89793 -406.623433)
			(xy 146.951886 -406.631187) (xy 147.00419 -406.646542) (xy 147.053776 -406.669184) (xy 147.099635 -406.698653)
			(xy 147.140833 -406.734349) (xy 147.176531 -406.775544) (xy 147.206003 -406.821401) (xy 147.228649 -406.870986)
			(xy 147.244007 -406.923288) (xy 147.251765 -406.977245) (xy 147.251765 -407.031752) (xy 148.689275 -407.031752)
			(xy 148.689275 -406.977248) (xy 148.697032 -406.923299) (xy 148.712388 -406.871002) (xy 148.735031 -406.821424)
			(xy 148.764498 -406.775573) (xy 148.800192 -406.734382) (xy 148.841384 -406.69869) (xy 148.887236 -406.669224)
			(xy 148.936816 -406.646583) (xy 148.989112 -406.631229) (xy 149.043062 -406.623474) (xy 149.070314 -406.623012)
			(xy 149.933914 -406.623012) (xy 149.961166 -406.623459) (xy 150.015115 -406.631217) (xy 150.067411 -406.646574)
			(xy 150.116989 -406.669218) (xy 150.16284 -406.698686) (xy 150.204031 -406.734379) (xy 150.239723 -406.775571)
			(xy 150.269189 -406.821423) (xy 150.29183 -406.871002) (xy 150.307186 -406.923299) (xy 150.314942 -406.977248)
			(xy 150.314942 -407.031748) (xy 151.752598 -407.031748) (xy 151.752598 -406.977252) (xy 151.760353 -406.923312)
			(xy 151.775705 -406.871023) (xy 151.798342 -406.821452) (xy 151.827802 -406.775606) (xy 151.863487 -406.734419)
			(xy 151.904669 -406.69873) (xy 151.950511 -406.669264) (xy 152.00008 -406.646621) (xy 152.052367 -406.631263)
			(xy 152.106306 -406.623501) (xy 152.133554 -406.623012) (xy 152.997154 -406.623012) (xy 153.02441 -406.623432)
			(xy 153.078369 -406.631184) (xy 153.130675 -406.646537) (xy 153.180264 -406.669178) (xy 153.226125 -406.698646)
			(xy 153.267326 -406.734342) (xy 153.303026 -406.775538) (xy 153.3325 -406.821396) (xy 153.355147 -406.870981)
			(xy 153.370506 -406.923286) (xy 153.378265 -406.977244) (xy 153.378265 -407.03175) (xy 154.815798 -407.03175)
			(xy 154.815798 -406.97725) (xy 154.823554 -406.923306) (xy 154.838908 -406.871015) (xy 154.861548 -406.821441)
			(xy 154.891012 -406.775593) (xy 154.926701 -406.734405) (xy 154.967888 -406.698715) (xy 155.013735 -406.669251)
			(xy 155.063309 -406.64661) (xy 155.1156 -406.631255) (xy 155.169544 -406.623499) (xy 155.196794 -406.623012)
			(xy 156.060394 -406.623012) (xy 156.087649 -406.623434) (xy 156.141603 -406.631191) (xy 156.193904 -406.646548)
			(xy 156.243488 -406.669191) (xy 156.289344 -406.69866) (xy 156.33054 -406.734356) (xy 156.366236 -406.775551)
			(xy 156.395706 -406.821407) (xy 156.41835 -406.87099) (xy 156.433708 -406.923291) (xy 156.441465 -406.977245)
			(xy 156.441465 -407.031753) (xy 157.878975 -407.031753) (xy 157.878975 -406.977247) (xy 157.886733 -406.923296)
			(xy 157.90209 -406.870998) (xy 157.924734 -406.821418) (xy 157.954203 -406.775566) (xy 157.989899 -406.734375)
			(xy 158.031093 -406.698683) (xy 158.076948 -406.669217) (xy 158.12653 -406.646578) (xy 158.178829 -406.631226)
			(xy 158.232781 -406.623473) (xy 158.260034 -406.623012) (xy 159.123634 -406.623012) (xy 159.150885 -406.62346)
			(xy 159.204832 -406.631221) (xy 159.257125 -406.64658) (xy 159.306701 -406.669224) (xy 159.352549 -406.698693)
			(xy 159.393738 -406.734386) (xy 159.429428 -406.775578) (xy 159.458892 -406.821429) (xy 159.481532 -406.871007)
			(xy 159.496886 -406.923301) (xy 159.504642 -406.977249) (xy 159.504642 -407.031749) (xy 160.942298 -407.031749)
			(xy 160.942298 -406.977251) (xy 160.950054 -406.923309) (xy 160.965407 -406.871019) (xy 160.988045 -406.821446)
			(xy 161.017507 -406.775599) (xy 161.053194 -406.734412) (xy 161.094379 -406.698722) (xy 161.140223 -406.669257)
			(xy 161.189795 -406.646616) (xy 161.242083 -406.631259) (xy 161.296025 -406.6235) (xy 161.323274 -406.623012)
			(xy 162.186874 -406.623012) (xy 162.21413 -406.623433) (xy 162.268086 -406.631187) (xy 162.32039 -406.646542)
			(xy 162.369976 -406.669184) (xy 162.415835 -406.698653) (xy 162.457033 -406.734349) (xy 162.492731 -406.775544)
			(xy 162.522203 -406.821401) (xy 162.544849 -406.870986) (xy 162.560207 -406.923288) (xy 162.567965 -406.977245)
			(xy 162.567965 -407.031752) (xy 164.005475 -407.031752) (xy 164.005475 -406.977248) (xy 164.013232 -406.923299)
			(xy 164.028588 -406.871002) (xy 164.051231 -406.821424) (xy 164.080698 -406.775573) (xy 164.116392 -406.734382)
			(xy 164.157584 -406.69869) (xy 164.203436 -406.669224) (xy 164.253016 -406.646583) (xy 164.305312 -406.631229)
			(xy 164.359262 -406.623474) (xy 164.386514 -406.623012) (xy 165.250114 -406.623012) (xy 165.277366 -406.623459)
			(xy 165.331315 -406.631217) (xy 165.383611 -406.646574) (xy 165.433189 -406.669218) (xy 165.47904 -406.698686)
			(xy 165.520231 -406.734379) (xy 165.555923 -406.775571) (xy 165.585389 -406.821423) (xy 165.60803 -406.871002)
			(xy 165.623386 -406.923299) (xy 165.631142 -406.977248) (xy 165.631142 -407.031748) (xy 167.068798 -407.031748)
			(xy 167.068798 -406.977252) (xy 167.076553 -406.923312) (xy 167.091905 -406.871023) (xy 167.114542 -406.821452)
			(xy 167.144002 -406.775606) (xy 167.179687 -406.734419) (xy 167.220869 -406.69873) (xy 167.266711 -406.669264)
			(xy 167.31628 -406.646621) (xy 167.368567 -406.631263) (xy 167.422506 -406.623501) (xy 167.449754 -406.623012)
			(xy 168.313354 -406.623012) (xy 168.34061 -406.623432) (xy 168.394569 -406.631184) (xy 168.446875 -406.646537)
			(xy 168.496464 -406.669178) (xy 168.542325 -406.698646) (xy 168.583526 -406.734342) (xy 168.619226 -406.775538)
			(xy 168.6487 -406.821396) (xy 168.671347 -406.870981) (xy 168.686706 -406.923286) (xy 168.694465 -406.977244)
			(xy 168.694465 -407.031756) (xy 168.686706 -407.085714) (xy 168.671347 -407.138019) (xy 168.6487 -407.187604)
			(xy 168.619226 -407.233462) (xy 168.583526 -407.274658) (xy 168.542325 -407.310354) (xy 168.496464 -407.339822)
			(xy 168.446875 -407.362463) (xy 168.394569 -407.377816) (xy 168.34061 -407.385568) (xy 168.313354 -407.386028)
			(xy 167.449754 -407.386028) (xy 167.422506 -407.385499) (xy 167.368567 -407.377737) (xy 167.31628 -407.362379)
			(xy 167.266711 -407.339736) (xy 167.220869 -407.31027) (xy 167.179687 -407.274581) (xy 167.144002 -407.233394)
			(xy 167.114542 -407.187548) (xy 167.091905 -407.137977) (xy 167.076553 -407.085688) (xy 167.068798 -407.031748)
			(xy 165.631142 -407.031748) (xy 165.631142 -407.031752) (xy 165.623386 -407.085701) (xy 165.60803 -407.137998)
			(xy 165.585389 -407.187577) (xy 165.555923 -407.233429) (xy 165.520231 -407.274621) (xy 165.47904 -407.310314)
			(xy 165.433189 -407.339782) (xy 165.383611 -407.362426) (xy 165.331315 -407.377783) (xy 165.277366 -407.385541)
			(xy 165.250114 -407.386028) (xy 164.386514 -407.386028) (xy 164.359262 -407.385526) (xy 164.305312 -407.377771)
			(xy 164.253016 -407.362417) (xy 164.203436 -407.339776) (xy 164.157584 -407.31031) (xy 164.116392 -407.274618)
			(xy 164.080698 -407.233427) (xy 164.051231 -407.187576) (xy 164.028588 -407.137998) (xy 164.013232 -407.085701)
			(xy 164.005475 -407.031752) (xy 162.567965 -407.031752) (xy 162.567965 -407.031755) (xy 162.560207 -407.085712)
			(xy 162.544849 -407.138014) (xy 162.522203 -407.187599) (xy 162.492731 -407.233456) (xy 162.457033 -407.274651)
			(xy 162.415835 -407.310347) (xy 162.369976 -407.339816) (xy 162.32039 -407.362458) (xy 162.268086 -407.377813)
			(xy 162.21413 -407.385567) (xy 162.186874 -407.386028) (xy 161.323274 -407.386028) (xy 161.296025 -407.3855)
			(xy 161.242083 -407.377741) (xy 161.189795 -407.362384) (xy 161.140223 -407.339743) (xy 161.094379 -407.310278)
			(xy 161.053194 -407.274588) (xy 161.017507 -407.233401) (xy 160.988045 -407.187554) (xy 160.965407 -407.137981)
			(xy 160.950054 -407.085691) (xy 160.942298 -407.031749) (xy 159.504642 -407.031749) (xy 159.504642 -407.031751)
			(xy 159.496886 -407.085699) (xy 159.481532 -407.137993) (xy 159.458892 -407.187571) (xy 159.429428 -407.233422)
			(xy 159.393738 -407.274614) (xy 159.352549 -407.310307) (xy 159.306701 -407.339776) (xy 159.257125 -407.36242)
			(xy 159.204832 -407.377779) (xy 159.150885 -407.38554) (xy 159.123634 -407.386028) (xy 158.260034 -407.386028)
			(xy 158.232781 -407.385527) (xy 158.178829 -407.377774) (xy 158.12653 -407.362422) (xy 158.076948 -407.339783)
			(xy 158.031093 -407.310317) (xy 157.989899 -407.274625) (xy 157.954203 -407.233434) (xy 157.924734 -407.187582)
			(xy 157.90209 -407.138002) (xy 157.886733 -407.085704) (xy 157.878975 -407.031753) (xy 156.441465 -407.031753)
			(xy 156.441465 -407.031755) (xy 156.433708 -407.085709) (xy 156.41835 -407.13801) (xy 156.395706 -407.187593)
			(xy 156.366236 -407.233449) (xy 156.33054 -407.274644) (xy 156.289344 -407.31034) (xy 156.243488 -407.339809)
			(xy 156.193904 -407.362452) (xy 156.141603 -407.377809) (xy 156.087649 -407.385566) (xy 156.060394 -407.386028)
			(xy 155.196794 -407.386028) (xy 155.169544 -407.385501) (xy 155.1156 -407.377745) (xy 155.063309 -407.36239)
			(xy 155.013735 -407.339749) (xy 154.967888 -407.310285) (xy 154.926701 -407.274595) (xy 154.891012 -407.233407)
			(xy 154.861548 -407.187559) (xy 154.838908 -407.137985) (xy 154.823554 -407.085694) (xy 154.815798 -407.03175)
			(xy 153.378265 -407.03175) (xy 153.378265 -407.031756) (xy 153.370506 -407.085714) (xy 153.355147 -407.138019)
			(xy 153.3325 -407.187604) (xy 153.303026 -407.233462) (xy 153.267326 -407.274658) (xy 153.226125 -407.310354)
			(xy 153.180264 -407.339822) (xy 153.130675 -407.362463) (xy 153.078369 -407.377816) (xy 153.02441 -407.385568)
			(xy 152.997154 -407.386028) (xy 152.133554 -407.386028) (xy 152.106306 -407.385499) (xy 152.052367 -407.377737)
			(xy 152.00008 -407.362379) (xy 151.950511 -407.339736) (xy 151.904669 -407.31027) (xy 151.863487 -407.274581)
			(xy 151.827802 -407.233394) (xy 151.798342 -407.187548) (xy 151.775705 -407.137977) (xy 151.760353 -407.085688)
			(xy 151.752598 -407.031748) (xy 150.314942 -407.031748) (xy 150.314942 -407.031752) (xy 150.307186 -407.085701)
			(xy 150.29183 -407.137998) (xy 150.269189 -407.187577) (xy 150.239723 -407.233429) (xy 150.204031 -407.274621)
			(xy 150.16284 -407.310314) (xy 150.116989 -407.339782) (xy 150.067411 -407.362426) (xy 150.015115 -407.377783)
			(xy 149.961166 -407.385541) (xy 149.933914 -407.386028) (xy 149.070314 -407.386028) (xy 149.043062 -407.385526)
			(xy 148.989112 -407.377771) (xy 148.936816 -407.362417) (xy 148.887236 -407.339776) (xy 148.841384 -407.31031)
			(xy 148.800192 -407.274618) (xy 148.764498 -407.233427) (xy 148.735031 -407.187576) (xy 148.712388 -407.137998)
			(xy 148.697032 -407.085701) (xy 148.689275 -407.031752) (xy 147.251765 -407.031752) (xy 147.251765 -407.031755)
			(xy 147.244007 -407.085712) (xy 147.228649 -407.138014) (xy 147.206003 -407.187599) (xy 147.176531 -407.233456)
			(xy 147.140833 -407.274651) (xy 147.099635 -407.310347) (xy 147.053776 -407.339816) (xy 147.00419 -407.362458)
			(xy 146.951886 -407.377813) (xy 146.89793 -407.385567) (xy 146.870674 -407.386028) (xy 146.007074 -407.386028)
			(xy 145.979825 -407.3855) (xy 145.925883 -407.377741) (xy 145.873595 -407.362384) (xy 145.824023 -407.339743)
			(xy 145.778179 -407.310278) (xy 145.736994 -407.274588) (xy 145.701307 -407.233401) (xy 145.671845 -407.187554)
			(xy 145.649207 -407.137981) (xy 145.633854 -407.085691) (xy 145.626098 -407.031749) (xy 144.188442 -407.031749)
			(xy 144.188442 -407.031751) (xy 144.180686 -407.085699) (xy 144.165332 -407.137993) (xy 144.142692 -407.187571)
			(xy 144.113228 -407.233422) (xy 144.077538 -407.274614) (xy 144.036349 -407.310307) (xy 143.990501 -407.339776)
			(xy 143.940925 -407.36242) (xy 143.888632 -407.377779) (xy 143.834685 -407.38554) (xy 143.807434 -407.386028)
			(xy 142.943834 -407.386028) (xy 142.916581 -407.385527) (xy 142.862629 -407.377774) (xy 142.81033 -407.362422)
			(xy 142.760748 -407.339783) (xy 142.714893 -407.310317) (xy 142.673699 -407.274625) (xy 142.638003 -407.233434)
			(xy 142.608534 -407.187582) (xy 142.58589 -407.138002) (xy 142.570533 -407.085704) (xy 142.562775 -407.031753)
			(xy 141.125265 -407.031753) (xy 141.125265 -407.031755) (xy 141.117508 -407.085709) (xy 141.10215 -407.13801)
			(xy 141.079506 -407.187593) (xy 141.050036 -407.233449) (xy 141.01434 -407.274644) (xy 140.973144 -407.31034)
			(xy 140.927288 -407.339809) (xy 140.877704 -407.362452) (xy 140.825403 -407.377809) (xy 140.771449 -407.385566)
			(xy 140.744194 -407.386028) (xy 139.880594 -407.386028) (xy 139.853344 -407.385501) (xy 139.7994 -407.377745)
			(xy 139.747109 -407.36239) (xy 139.697535 -407.339749) (xy 139.651688 -407.310285) (xy 139.610501 -407.274595)
			(xy 139.574812 -407.233407) (xy 139.545348 -407.187559) (xy 139.522708 -407.137985) (xy 139.507354 -407.085694)
			(xy 139.499598 -407.03175) (xy 138.062065 -407.03175) (xy 138.062065 -407.031756) (xy 138.054306 -407.085714)
			(xy 138.038947 -407.138019) (xy 138.0163 -407.187604) (xy 137.986826 -407.233462) (xy 137.951126 -407.274658)
			(xy 137.909925 -407.310354) (xy 137.864064 -407.339822) (xy 137.814475 -407.362463) (xy 137.762169 -407.377816)
			(xy 137.70821 -407.385568) (xy 137.680954 -407.386028) (xy 136.817354 -407.386028) (xy 136.790106 -407.385499)
			(xy 136.736167 -407.377737) (xy 136.68388 -407.362379) (xy 136.634311 -407.339736) (xy 136.588469 -407.31027)
			(xy 136.547287 -407.274581) (xy 136.511602 -407.233394) (xy 136.482142 -407.187548) (xy 136.459505 -407.137977)
			(xy 136.444153 -407.085688) (xy 136.436398 -407.031748) (xy 134.998742 -407.031748) (xy 134.998742 -407.031752)
			(xy 134.990986 -407.085701) (xy 134.97563 -407.137998) (xy 134.952989 -407.187577) (xy 134.923523 -407.233429)
			(xy 134.887831 -407.274621) (xy 134.84664 -407.310314) (xy 134.800789 -407.339782) (xy 134.751211 -407.362426)
			(xy 134.698915 -407.377783) (xy 134.644966 -407.385541) (xy 134.617714 -407.386028) (xy 133.754114 -407.386028)
			(xy 133.726862 -407.385526) (xy 133.672912 -407.377771) (xy 133.620616 -407.362417) (xy 133.571036 -407.339776)
			(xy 133.525184 -407.31031) (xy 133.483992 -407.274618) (xy 133.448298 -407.233427) (xy 133.418831 -407.187576)
			(xy 133.396188 -407.137998) (xy 133.380832 -407.085701) (xy 133.373075 -407.031752) (xy 131.935565 -407.031752)
			(xy 131.935565 -407.031755) (xy 131.927807 -407.085712) (xy 131.912449 -407.138014) (xy 131.889803 -407.187599)
			(xy 131.860331 -407.233456) (xy 131.824633 -407.274651) (xy 131.783435 -407.310347) (xy 131.737576 -407.339816)
			(xy 131.68799 -407.362458) (xy 131.635686 -407.377813) (xy 131.58173 -407.385567) (xy 131.554474 -407.386028)
			(xy 130.690874 -407.386028) (xy 130.663625 -407.3855) (xy 130.609683 -407.377741) (xy 130.557395 -407.362384)
			(xy 130.507823 -407.339743) (xy 130.461979 -407.310278) (xy 130.420794 -407.274588) (xy 130.385107 -407.233401)
			(xy 130.355645 -407.187554) (xy 130.333007 -407.137981) (xy 130.317654 -407.085691) (xy 130.309898 -407.031749)
			(xy 128.872242 -407.031749) (xy 128.872242 -407.031751) (xy 128.864486 -407.085699) (xy 128.849132 -407.137993)
			(xy 128.826492 -407.187571) (xy 128.797028 -407.233422) (xy 128.761338 -407.274614) (xy 128.720149 -407.310307)
			(xy 128.674301 -407.339776) (xy 128.624725 -407.36242) (xy 128.572432 -407.377779) (xy 128.518485 -407.38554)
			(xy 128.491234 -407.386028) (xy 127.627634 -407.386028) (xy 127.600381 -407.385527) (xy 127.546429 -407.377774)
			(xy 127.49413 -407.362422) (xy 127.444548 -407.339783) (xy 127.398693 -407.310317) (xy 127.357499 -407.274625)
			(xy 127.321803 -407.233434) (xy 127.292334 -407.187582) (xy 127.26969 -407.138002) (xy 127.254333 -407.085704)
			(xy 127.246575 -407.031753) (xy 125.809065 -407.031753) (xy 125.809065 -407.031755) (xy 125.801308 -407.085709)
			(xy 125.78595 -407.13801) (xy 125.763306 -407.187593) (xy 125.733836 -407.233449) (xy 125.69814 -407.274644)
			(xy 125.656944 -407.31034) (xy 125.611088 -407.339809) (xy 125.561504 -407.362452) (xy 125.509203 -407.377809)
			(xy 125.455249 -407.385566) (xy 125.427994 -407.386028) (xy 124.564394 -407.386028) (xy 124.537144 -407.385501)
			(xy 124.4832 -407.377745) (xy 124.430909 -407.36239) (xy 124.381335 -407.339749) (xy 124.335488 -407.310285)
			(xy 124.294301 -407.274595) (xy 124.258612 -407.233407) (xy 124.229148 -407.187559) (xy 124.206508 -407.137985)
			(xy 124.191154 -407.085694) (xy 124.183398 -407.03175) (xy 122.745865 -407.03175) (xy 122.745865 -407.031756)
			(xy 122.738106 -407.085714) (xy 122.722747 -407.138019) (xy 122.7001 -407.187604) (xy 122.670626 -407.233462)
			(xy 122.634926 -407.274658) (xy 122.593725 -407.310354) (xy 122.547864 -407.339822) (xy 122.498275 -407.362463)
			(xy 122.445969 -407.377816) (xy 122.39201 -407.385568) (xy 122.364754 -407.386028) (xy 121.501154 -407.386028)
			(xy 121.473906 -407.385499) (xy 121.419967 -407.377737) (xy 121.36768 -407.362379) (xy 121.318111 -407.339736)
			(xy 121.272269 -407.31027) (xy 121.231087 -407.274581) (xy 121.195402 -407.233394) (xy 121.165942 -407.187548)
			(xy 121.143305 -407.137977) (xy 121.127953 -407.085688) (xy 121.120198 -407.031748) (xy 107.861153 -407.031748)
			(xy 107.86873 -407.084449) (xy 107.86873 -407.138951) (xy 107.860974 -407.192898) (xy 107.84562 -407.245192)
			(xy 107.822979 -407.294769) (xy 107.793514 -407.34062) (xy 107.757824 -407.38181) (xy 107.716636 -407.417502)
			(xy 107.670787 -407.44697) (xy 107.621211 -407.469613) (xy 107.568918 -407.48497) (xy 107.514971 -407.492729)
			(xy 107.48772 -407.493216) (xy 106.62412 -407.493216) (xy 106.596867 -407.492738) (xy 106.542915 -407.484984)
			(xy 106.490616 -407.46963) (xy 106.441034 -407.446989) (xy 106.395179 -407.417522) (xy 106.353985 -407.381829)
			(xy 106.31829 -407.340637) (xy 106.288821 -407.294783) (xy 106.266177 -407.245203) (xy 106.250821 -407.192905)
			(xy 106.243063 -407.138953) (xy 96.495694 -407.138953) (xy 96.473493 -407.18757) (xy 96.444028 -407.233421)
			(xy 96.408339 -407.274612) (xy 96.367151 -407.310306) (xy 96.321303 -407.339775) (xy 96.271728 -407.362419)
			(xy 96.219435 -407.377778) (xy 96.165489 -407.38554) (xy 96.138238 -407.386028) (xy 95.274638 -407.386028)
			(xy 95.247385 -407.385527) (xy 95.193433 -407.377775) (xy 95.141133 -407.362423) (xy 95.091551 -407.339784)
			(xy 95.045695 -407.310319) (xy 95.0045 -407.274627) (xy 94.968804 -407.233435) (xy 94.939334 -407.187583)
			(xy 94.91669 -407.138003) (xy 94.901333 -407.085705) (xy 94.893575 -407.031753) (xy 93.456065 -407.031753)
			(xy 93.456065 -407.031754) (xy 93.448308 -407.085708) (xy 93.432951 -407.138009) (xy 93.410307 -407.187592)
			(xy 93.380837 -407.233448) (xy 93.345141 -407.274643) (xy 93.303946 -407.310338) (xy 93.25809 -407.339808)
			(xy 93.208507 -407.362451) (xy 93.156206 -407.377808) (xy 93.102252 -407.385565) (xy 93.074998 -407.386028)
			(xy 92.211398 -407.386028) (xy 92.184148 -407.385502) (xy 92.130204 -407.377745) (xy 92.077912 -407.362391)
			(xy 92.028338 -407.339751) (xy 91.98249 -407.310286) (xy 91.941302 -407.274596) (xy 91.905613 -407.233408)
			(xy 91.876148 -407.187561) (xy 91.853508 -407.137986) (xy 91.838154 -407.085694) (xy 91.830398 -407.03175)
			(xy 90.392865 -407.03175) (xy 90.392865 -407.031756) (xy 90.385107 -407.085714) (xy 90.369748 -407.138018)
			(xy 90.347101 -407.187603) (xy 90.317627 -407.233461) (xy 90.281927 -407.274657) (xy 90.240727 -407.310352)
			(xy 90.194866 -407.339821) (xy 90.145278 -407.362462) (xy 90.092973 -407.377815) (xy 90.039014 -407.385568)
			(xy 90.011758 -407.386028) (xy 89.148158 -407.386028) (xy 89.12091 -407.385499) (xy 89.06697 -407.377738)
			(xy 89.014683 -407.36238) (xy 88.965114 -407.339738) (xy 88.919271 -407.310272) (xy 88.878088 -407.274582)
			(xy 88.842403 -407.233395) (xy 88.812942 -407.187549) (xy 88.790305 -407.137978) (xy 88.774953 -407.085689)
			(xy 88.767198 -407.031748) (xy 87.329542 -407.031748) (xy 87.329542 -407.031752) (xy 87.321786 -407.085701)
			(xy 87.306431 -407.137997) (xy 87.28379 -407.187576) (xy 87.254324 -407.233427) (xy 87.218632 -407.274619)
			(xy 87.177442 -407.310313) (xy 87.131591 -407.339781) (xy 87.082014 -407.362424) (xy 87.029718 -407.377782)
			(xy 86.97577 -407.385541) (xy 86.948518 -407.386028) (xy 86.084918 -407.386028) (xy 86.057666 -407.385526)
			(xy 86.003716 -407.377771) (xy 85.951418 -407.362418) (xy 85.901839 -407.339778) (xy 85.855986 -407.310312)
			(xy 85.814793 -407.27462) (xy 85.779099 -407.233429) (xy 85.749631 -407.187577) (xy 85.726989 -407.137998)
			(xy 85.711632 -407.085702) (xy 85.703875 -407.031752) (xy 84.266365 -407.031752) (xy 84.266365 -407.031755)
			(xy 84.258607 -407.085711) (xy 84.243249 -407.138013) (xy 84.220604 -407.187598) (xy 84.191132 -407.233454)
			(xy 84.155434 -407.27465) (xy 84.114237 -407.310345) (xy 84.068378 -407.339814) (xy 84.018793 -407.362457)
			(xy 83.96649 -407.377812) (xy 83.912533 -407.385567) (xy 83.885278 -407.386028) (xy 83.021678 -407.386028)
			(xy 82.994429 -407.3855) (xy 82.940487 -407.377742) (xy 82.888197 -407.362385) (xy 82.838626 -407.339744)
			(xy 82.79278 -407.310279) (xy 82.751595 -407.274589) (xy 82.715908 -407.233402) (xy 82.686445 -407.187555)
			(xy 82.663807 -407.137982) (xy 82.648454 -407.085692) (xy 82.640698 -407.031749) (xy 81.203042 -407.031749)
			(xy 81.203042 -407.031751) (xy 81.195286 -407.085698) (xy 81.179932 -407.137993) (xy 81.157293 -407.18757)
			(xy 81.127828 -407.233421) (xy 81.092139 -407.274612) (xy 81.050951 -407.310306) (xy 81.005103 -407.339775)
			(xy 80.955528 -407.362419) (xy 80.903235 -407.377778) (xy 80.849289 -407.38554) (xy 80.822038 -407.386028)
			(xy 79.958438 -407.386028) (xy 79.931185 -407.385527) (xy 79.877233 -407.377775) (xy 79.824933 -407.362423)
			(xy 79.775351 -407.339784) (xy 79.729495 -407.310319) (xy 79.6883 -407.274627) (xy 79.652604 -407.233435)
			(xy 79.623134 -407.187583) (xy 79.60049 -407.138003) (xy 79.585133 -407.085705) (xy 79.577375 -407.031753)
			(xy 78.139865 -407.031753) (xy 78.139865 -407.031754) (xy 78.132108 -407.085708) (xy 78.116751 -407.138009)
			(xy 78.094107 -407.187592) (xy 78.064637 -407.233448) (xy 78.028941 -407.274643) (xy 77.987746 -407.310338)
			(xy 77.94189 -407.339808) (xy 77.892307 -407.362451) (xy 77.840006 -407.377808) (xy 77.786052 -407.385565)
			(xy 77.758798 -407.386028) (xy 76.895198 -407.386028) (xy 76.867948 -407.385502) (xy 76.814004 -407.377745)
			(xy 76.761712 -407.362391) (xy 76.712138 -407.339751) (xy 76.66629 -407.310286) (xy 76.625102 -407.274596)
			(xy 76.589413 -407.233408) (xy 76.559948 -407.187561) (xy 76.537308 -407.137986) (xy 76.521954 -407.085694)
			(xy 76.514198 -407.03175) (xy 75.076665 -407.03175) (xy 75.076665 -407.031756) (xy 75.068907 -407.085714)
			(xy 75.053548 -407.138018) (xy 75.030901 -407.187603) (xy 75.001427 -407.233461) (xy 74.965727 -407.274657)
			(xy 74.924527 -407.310352) (xy 74.878666 -407.339821) (xy 74.829078 -407.362462) (xy 74.776773 -407.377815)
			(xy 74.722814 -407.385568) (xy 74.695558 -407.386028) (xy 73.831958 -407.386028) (xy 73.80471 -407.385499)
			(xy 73.75077 -407.377738) (xy 73.698483 -407.36238) (xy 73.648914 -407.339738) (xy 73.603071 -407.310272)
			(xy 73.561888 -407.274582) (xy 73.526203 -407.233395) (xy 73.496742 -407.187549) (xy 73.474105 -407.137978)
			(xy 73.458753 -407.085689) (xy 73.450998 -407.031748) (xy 72.013342 -407.031748) (xy 72.013342 -407.031752)
			(xy 72.005586 -407.085701) (xy 71.990231 -407.137997) (xy 71.96759 -407.187576) (xy 71.938124 -407.233427)
			(xy 71.902432 -407.274619) (xy 71.861242 -407.310313) (xy 71.815391 -407.339781) (xy 71.765814 -407.362424)
			(xy 71.713518 -407.377782) (xy 71.65957 -407.385541) (xy 71.632318 -407.386028) (xy 70.768718 -407.386028)
			(xy 70.741466 -407.385526) (xy 70.687516 -407.377771) (xy 70.635218 -407.362418) (xy 70.585639 -407.339778)
			(xy 70.539786 -407.310312) (xy 70.498593 -407.27462) (xy 70.462899 -407.233429) (xy 70.433431 -407.187577)
			(xy 70.410789 -407.137998) (xy 70.395432 -407.085702) (xy 70.387675 -407.031752) (xy 68.950165 -407.031752)
			(xy 68.950165 -407.031755) (xy 68.942407 -407.085711) (xy 68.927049 -407.138013) (xy 68.904404 -407.187598)
			(xy 68.874932 -407.233454) (xy 68.839234 -407.27465) (xy 68.798037 -407.310345) (xy 68.752178 -407.339814)
			(xy 68.702593 -407.362457) (xy 68.65029 -407.377812) (xy 68.596333 -407.385567) (xy 68.569078 -407.386028)
			(xy 67.705478 -407.386028) (xy 67.678229 -407.3855) (xy 67.624287 -407.377742) (xy 67.571997 -407.362385)
			(xy 67.522426 -407.339744) (xy 67.47658 -407.310279) (xy 67.435395 -407.274589) (xy 67.399708 -407.233402)
			(xy 67.370245 -407.187555) (xy 67.347607 -407.137982) (xy 67.332254 -407.085692) (xy 67.324498 -407.031749)
			(xy 65.886842 -407.031749) (xy 65.886842 -407.031751) (xy 65.879086 -407.085698) (xy 65.863732 -407.137993)
			(xy 65.841093 -407.18757) (xy 65.811628 -407.233421) (xy 65.775939 -407.274612) (xy 65.734751 -407.310306)
			(xy 65.688903 -407.339775) (xy 65.639328 -407.362419) (xy 65.587035 -407.377778) (xy 65.533089 -407.38554)
			(xy 65.505838 -407.386028) (xy 64.642238 -407.386028) (xy 64.614985 -407.385527) (xy 64.561033 -407.377775)
			(xy 64.508733 -407.362423) (xy 64.459151 -407.339784) (xy 64.413295 -407.310319) (xy 64.3721 -407.274627)
			(xy 64.336404 -407.233435) (xy 64.306934 -407.187583) (xy 64.28429 -407.138003) (xy 64.268933 -407.085705)
			(xy 64.261175 -407.031753) (xy 62.823665 -407.031753) (xy 62.823665 -407.031754) (xy 62.815908 -407.085708)
			(xy 62.800551 -407.138009) (xy 62.777907 -407.187592) (xy 62.748437 -407.233448) (xy 62.712741 -407.274643)
			(xy 62.671546 -407.310338) (xy 62.62569 -407.339808) (xy 62.576107 -407.362451) (xy 62.523806 -407.377808)
			(xy 62.469852 -407.385565) (xy 62.442598 -407.386028) (xy 61.578998 -407.386028) (xy 61.551748 -407.385502)
			(xy 61.497804 -407.377745) (xy 61.445512 -407.362391) (xy 61.395938 -407.339751) (xy 61.35009 -407.310286)
			(xy 61.308902 -407.274596) (xy 61.273213 -407.233408) (xy 61.243748 -407.187561) (xy 61.221108 -407.137986)
			(xy 61.205754 -407.085694) (xy 61.197998 -407.03175) (xy 59.760465 -407.03175) (xy 59.760465 -407.031756)
			(xy 59.752707 -407.085714) (xy 59.737348 -407.138018) (xy 59.714701 -407.187603) (xy 59.685227 -407.233461)
			(xy 59.649527 -407.274657) (xy 59.608327 -407.310352) (xy 59.562466 -407.339821) (xy 59.512878 -407.362462)
			(xy 59.460573 -407.377815) (xy 59.406614 -407.385568) (xy 59.379358 -407.386028) (xy 58.515758 -407.386028)
			(xy 58.48851 -407.385499) (xy 58.43457 -407.377738) (xy 58.382283 -407.36238) (xy 58.332714 -407.339738)
			(xy 58.286871 -407.310272) (xy 58.245688 -407.274582) (xy 58.210003 -407.233395) (xy 58.180542 -407.187549)
			(xy 58.157905 -407.137978) (xy 58.142553 -407.085689) (xy 58.134798 -407.031748) (xy 56.697142 -407.031748)
			(xy 56.697142 -407.031752) (xy 56.689386 -407.085701) (xy 56.674031 -407.137997) (xy 56.65139 -407.187576)
			(xy 56.621924 -407.233427) (xy 56.586232 -407.274619) (xy 56.545042 -407.310313) (xy 56.499191 -407.339781)
			(xy 56.449614 -407.362424) (xy 56.397318 -407.377782) (xy 56.34337 -407.385541) (xy 56.316118 -407.386028)
			(xy 55.452518 -407.386028) (xy 55.425266 -407.385526) (xy 55.371316 -407.377771) (xy 55.319018 -407.362418)
			(xy 55.269439 -407.339778) (xy 55.223586 -407.310312) (xy 55.182393 -407.27462) (xy 55.146699 -407.233429)
			(xy 55.117231 -407.187577) (xy 55.094589 -407.137998) (xy 55.079232 -407.085702) (xy 55.071475 -407.031752)
			(xy 53.633965 -407.031752) (xy 53.633965 -407.031755) (xy 53.626207 -407.085711) (xy 53.610849 -407.138013)
			(xy 53.588204 -407.187598) (xy 53.558732 -407.233454) (xy 53.523034 -407.27465) (xy 53.481837 -407.310345)
			(xy 53.435978 -407.339814) (xy 53.386393 -407.362457) (xy 53.33409 -407.377812) (xy 53.280133 -407.385567)
			(xy 53.252878 -407.386028) (xy 52.389278 -407.386028) (xy 52.362029 -407.3855) (xy 52.308087 -407.377742)
			(xy 52.255797 -407.362385) (xy 52.206226 -407.339744) (xy 52.16038 -407.310279) (xy 52.119195 -407.274589)
			(xy 52.083508 -407.233402) (xy 52.054045 -407.187555) (xy 52.031407 -407.137982) (xy 52.016054 -407.085692)
			(xy 52.008298 -407.031749) (xy 50.570642 -407.031749) (xy 50.570642 -407.031751) (xy 50.562886 -407.085698)
			(xy 50.547532 -407.137993) (xy 50.524893 -407.18757) (xy 50.495428 -407.233421) (xy 50.459739 -407.274612)
			(xy 50.418551 -407.310306) (xy 50.372703 -407.339775) (xy 50.323128 -407.362419) (xy 50.270835 -407.377778)
			(xy 50.216889 -407.38554) (xy 50.189638 -407.386028) (xy 49.326038 -407.386028) (xy 49.298785 -407.385527)
			(xy 49.244833 -407.377775) (xy 49.192533 -407.362423) (xy 49.142951 -407.339784) (xy 49.097095 -407.310319)
			(xy 49.0559 -407.274627) (xy 49.020204 -407.233435) (xy 48.990734 -407.187583) (xy 48.96809 -407.138003)
			(xy 48.952733 -407.085705) (xy 48.944975 -407.031753) (xy 16.741648 -407.031753) (xy 16.741648 -407.035508)
			(xy 16.741162 -407.062759) (xy 16.733406 -407.116707) (xy 16.718051 -407.169002) (xy 16.695409 -407.218579)
			(xy 16.665943 -407.264429) (xy 16.630252 -407.30562) (xy 16.589061 -407.341311) (xy 16.543211 -407.370777)
			(xy 16.493634 -407.393419) (xy 16.441339 -407.408774) (xy 16.387391 -407.41653) (xy 16.332889 -407.41653)
			(xy 16.278941 -407.408774) (xy 16.226646 -407.393419) (xy 16.177069 -407.370777) (xy 16.131219 -407.341311)
			(xy 16.090028 -407.30562) (xy 16.054337 -407.264429) (xy 16.024871 -407.218579) (xy 16.002229 -407.169002)
			(xy 15.986874 -407.116707) (xy 15.979118 -407.062759) (xy 15.978632 -407.035508) (xy 5.555234 -407.035508)
			(xy 6.274054 -407.754328) (xy 6.323476 -407.804436) (xy 6.417282 -407.909377) (xy 6.505056 -408.019414)
			(xy 6.586523 -408.134198) (xy 6.661426 -408.25337) (xy 6.729529 -408.376554) (xy 6.790618 -408.503362)
			(xy 6.844501 -408.633397) (xy 6.891008 -408.766247) (xy 6.929993 -408.901497) (xy 6.961334 -409.03872)
			(xy 6.984932 -409.177484) (xy 7.000712 -409.317352) (xy 7.008625 -409.457886) (xy 7.00913 -409.528264)
			(xy 7.00913 -410.057457) (xy 48.944923 -410.057457) (xy 48.944923 -410.002943) (xy 48.952682 -409.948984)
			(xy 48.968041 -409.896679) (xy 48.990688 -409.847092) (xy 49.020162 -409.801233) (xy 49.055863 -409.760036)
			(xy 49.097064 -409.724339) (xy 49.142925 -409.69487) (xy 49.192515 -409.672228) (xy 49.244821 -409.656874)
			(xy 49.298781 -409.64912) (xy 49.326038 -409.64866) (xy 50.189638 -409.64866) (xy 50.216885 -409.649213)
			(xy 50.270824 -409.656973) (xy 50.32311 -409.67233) (xy 50.372678 -409.694972) (xy 50.41852 -409.724436)
			(xy 50.459702 -409.760125) (xy 50.495386 -409.801311) (xy 50.524847 -409.847155) (xy 50.547483 -409.896726)
			(xy 50.562835 -409.949013) (xy 50.57059 -410.002953) (xy 50.57059 -410.057447) (xy 50.570589 -410.057453)
			(xy 52.008246 -410.057453) (xy 52.008246 -410.002947) (xy 52.016002 -409.948997) (xy 52.031358 -409.8967)
			(xy 52.053999 -409.84712) (xy 52.083466 -409.801267) (xy 52.119158 -409.760074) (xy 52.160349 -409.724379)
			(xy 52.206201 -409.69491) (xy 52.255779 -409.672265) (xy 52.308076 -409.656907) (xy 52.362025 -409.649147)
			(xy 52.389278 -409.64866) (xy 53.252878 -409.64866) (xy 53.28013 -409.649186) (xy 53.334078 -409.65694)
			(xy 53.386374 -409.672292) (xy 53.435953 -409.694932) (xy 53.481805 -409.724397) (xy 53.522997 -409.760087)
			(xy 53.55869 -409.801277) (xy 53.588158 -409.847127) (xy 53.6108 -409.896705) (xy 53.626156 -409.949)
			(xy 53.633913 -410.002948) (xy 53.633913 -410.057452) (xy 53.633912 -410.057456) (xy 55.071423 -410.057456)
			(xy 55.071423 -410.002944) (xy 55.079181 -409.948987) (xy 55.094539 -409.896683) (xy 55.117185 -409.847098)
			(xy 55.146657 -409.80124) (xy 55.182356 -409.760043) (xy 55.223554 -409.724346) (xy 55.269413 -409.694876)
			(xy 55.319 -409.672233) (xy 55.371305 -409.656877) (xy 55.425262 -409.649122) (xy 55.452518 -409.64866)
			(xy 56.316118 -409.64866) (xy 56.343366 -409.649211) (xy 56.397307 -409.656969) (xy 56.449595 -409.672325)
			(xy 56.499166 -409.694965) (xy 56.54501 -409.724429) (xy 56.586195 -409.760118) (xy 56.621882 -409.801304)
			(xy 56.651344 -409.84715) (xy 56.673982 -409.896721) (xy 56.689334 -409.94901) (xy 56.69709 -410.002952)
			(xy 56.69709 -410.057448) (xy 56.697089 -410.057452) (xy 58.134746 -410.057452) (xy 58.134746 -410.002948)
			(xy 58.142502 -409.949) (xy 58.157856 -409.896704) (xy 58.180496 -409.847125) (xy 58.209961 -409.801273)
			(xy 58.245651 -409.760081) (xy 58.28684 -409.724386) (xy 58.332689 -409.694916) (xy 58.382265 -409.672271)
			(xy 58.434559 -409.656911) (xy 58.488506 -409.649149) (xy 58.515758 -409.64866) (xy 59.379358 -409.64866)
			(xy 59.406611 -409.649184) (xy 59.460561 -409.656936) (xy 59.51286 -409.672287) (xy 59.562441 -409.694925)
			(xy 59.608296 -409.72439) (xy 59.64949 -409.76008) (xy 59.685185 -409.801271) (xy 59.714655 -409.847122)
			(xy 59.737298 -409.896701) (xy 59.752655 -409.948997) (xy 59.760413 -410.002948) (xy 59.760413 -410.057452)
			(xy 59.760413 -410.057453) (xy 61.197946 -410.057453) (xy 61.197946 -410.002947) (xy 61.205703 -409.948994)
			(xy 61.221059 -409.896695) (xy 61.243702 -409.847114) (xy 61.273171 -409.80126) (xy 61.308865 -409.760066)
			(xy 61.350059 -409.724372) (xy 61.395913 -409.694903) (xy 61.445494 -409.67226) (xy 61.497793 -409.656903)
			(xy 61.551745 -409.649146) (xy 61.578998 -409.64866) (xy 62.442598 -409.64866) (xy 62.469849 -409.649187)
			(xy 62.523795 -409.656943) (xy 62.576089 -409.672298) (xy 62.625665 -409.694938) (xy 62.671515 -409.724404)
			(xy 62.712704 -409.760094) (xy 62.748395 -409.801284) (xy 62.777861 -409.847133) (xy 62.800502 -409.896709)
			(xy 62.815856 -409.949003) (xy 62.823613 -410.002949) (xy 62.823613 -410.057451) (xy 62.823612 -410.057457)
			(xy 64.261123 -410.057457) (xy 64.261123 -410.002943) (xy 64.268882 -409.948984) (xy 64.284241 -409.896679)
			(xy 64.306888 -409.847092) (xy 64.336362 -409.801233) (xy 64.372063 -409.760036) (xy 64.413264 -409.724339)
			(xy 64.459125 -409.69487) (xy 64.508715 -409.672228) (xy 64.561021 -409.656874) (xy 64.614981 -409.64912)
			(xy 64.642238 -409.64866) (xy 65.505838 -409.64866) (xy 65.533085 -409.649213) (xy 65.587024 -409.656973)
			(xy 65.63931 -409.67233) (xy 65.688878 -409.694972) (xy 65.73472 -409.724436) (xy 65.775902 -409.760125)
			(xy 65.811586 -409.801311) (xy 65.841047 -409.847155) (xy 65.863683 -409.896726) (xy 65.879035 -409.949013)
			(xy 65.88679 -410.002953) (xy 65.88679 -410.057447) (xy 65.886789 -410.057453) (xy 67.324446 -410.057453)
			(xy 67.324446 -410.002947) (xy 67.332202 -409.948997) (xy 67.347558 -409.8967) (xy 67.370199 -409.84712)
			(xy 67.399666 -409.801267) (xy 67.435358 -409.760074) (xy 67.476549 -409.724379) (xy 67.522401 -409.69491)
			(xy 67.571979 -409.672265) (xy 67.624276 -409.656907) (xy 67.678225 -409.649147) (xy 67.705478 -409.64866)
			(xy 68.569078 -409.64866) (xy 68.59633 -409.649186) (xy 68.650278 -409.65694) (xy 68.702574 -409.672292)
			(xy 68.752153 -409.694932) (xy 68.798005 -409.724397) (xy 68.839197 -409.760087) (xy 68.87489 -409.801277)
			(xy 68.904358 -409.847127) (xy 68.927 -409.896705) (xy 68.942356 -409.949) (xy 68.950113 -410.002948)
			(xy 68.950113 -410.057452) (xy 68.950112 -410.057456) (xy 70.387623 -410.057456) (xy 70.387623 -410.002944)
			(xy 70.395381 -409.948987) (xy 70.410739 -409.896683) (xy 70.433385 -409.847098) (xy 70.462857 -409.80124)
			(xy 70.498556 -409.760043) (xy 70.539754 -409.724346) (xy 70.585613 -409.694876) (xy 70.6352 -409.672233)
			(xy 70.687505 -409.656877) (xy 70.741462 -409.649122) (xy 70.768718 -409.64866) (xy 71.632318 -409.64866)
			(xy 71.659566 -409.649211) (xy 71.713507 -409.656969) (xy 71.765795 -409.672325) (xy 71.815366 -409.694965)
			(xy 71.86121 -409.724429) (xy 71.902395 -409.760118) (xy 71.938082 -409.801304) (xy 71.967544 -409.84715)
			(xy 71.990182 -409.896721) (xy 72.005534 -409.94901) (xy 72.01329 -410.002952) (xy 72.01329 -410.057448)
			(xy 72.013289 -410.057452) (xy 73.450946 -410.057452) (xy 73.450946 -410.002948) (xy 73.458702 -409.949)
			(xy 73.474056 -409.896704) (xy 73.496696 -409.847125) (xy 73.526161 -409.801273) (xy 73.561851 -409.760081)
			(xy 73.60304 -409.724386) (xy 73.648889 -409.694916) (xy 73.698465 -409.672271) (xy 73.750759 -409.656911)
			(xy 73.804706 -409.649149) (xy 73.831958 -409.64866) (xy 74.695558 -409.64866) (xy 74.722811 -409.649184)
			(xy 74.776761 -409.656936) (xy 74.82906 -409.672287) (xy 74.878641 -409.694925) (xy 74.924496 -409.72439)
			(xy 74.96569 -409.76008) (xy 75.001385 -409.801271) (xy 75.030855 -409.847122) (xy 75.053498 -409.896701)
			(xy 75.068855 -409.948997) (xy 75.076613 -410.002948) (xy 75.076613 -410.057452) (xy 75.076613 -410.057453)
			(xy 76.514146 -410.057453) (xy 76.514146 -410.002947) (xy 76.521903 -409.948994) (xy 76.537259 -409.896695)
			(xy 76.559902 -409.847114) (xy 76.589371 -409.80126) (xy 76.625065 -409.760066) (xy 76.666259 -409.724372)
			(xy 76.712113 -409.694903) (xy 76.761694 -409.67226) (xy 76.813993 -409.656903) (xy 76.867945 -409.649146)
			(xy 76.895198 -409.64866) (xy 77.758798 -409.64866) (xy 77.786049 -409.649187) (xy 77.839995 -409.656943)
			(xy 77.892289 -409.672298) (xy 77.941865 -409.694938) (xy 77.987715 -409.724404) (xy 78.028904 -409.760094)
			(xy 78.064595 -409.801284) (xy 78.094061 -409.847133) (xy 78.116702 -409.896709) (xy 78.132056 -409.949003)
			(xy 78.139813 -410.002949) (xy 78.139813 -410.057451) (xy 78.139812 -410.057457) (xy 79.577323 -410.057457)
			(xy 79.577323 -410.002943) (xy 79.585082 -409.948984) (xy 79.600441 -409.896679) (xy 79.623088 -409.847092)
			(xy 79.652562 -409.801233) (xy 79.688263 -409.760036) (xy 79.729464 -409.724339) (xy 79.775325 -409.69487)
			(xy 79.824915 -409.672228) (xy 79.877221 -409.656874) (xy 79.931181 -409.64912) (xy 79.958438 -409.64866)
			(xy 80.822038 -409.64866) (xy 80.849285 -409.649213) (xy 80.903224 -409.656973) (xy 80.95551 -409.67233)
			(xy 81.005078 -409.694972) (xy 81.05092 -409.724436) (xy 81.092102 -409.760125) (xy 81.127786 -409.801311)
			(xy 81.157247 -409.847155) (xy 81.179883 -409.896726) (xy 81.195235 -409.949013) (xy 81.20299 -410.002953)
			(xy 81.20299 -410.057447) (xy 81.202989 -410.057453) (xy 82.640646 -410.057453) (xy 82.640646 -410.002947)
			(xy 82.648402 -409.948997) (xy 82.663758 -409.8967) (xy 82.686399 -409.84712) (xy 82.715866 -409.801267)
			(xy 82.751558 -409.760074) (xy 82.792749 -409.724379) (xy 82.838601 -409.69491) (xy 82.888179 -409.672265)
			(xy 82.940476 -409.656907) (xy 82.994425 -409.649147) (xy 83.021678 -409.64866) (xy 83.885278 -409.64866)
			(xy 83.91253 -409.649186) (xy 83.966478 -409.65694) (xy 84.018774 -409.672292) (xy 84.068353 -409.694932)
			(xy 84.114205 -409.724397) (xy 84.155397 -409.760087) (xy 84.19109 -409.801277) (xy 84.220558 -409.847127)
			(xy 84.2432 -409.896705) (xy 84.258556 -409.949) (xy 84.266313 -410.002948) (xy 84.266313 -410.057452)
			(xy 84.266312 -410.057456) (xy 85.703823 -410.057456) (xy 85.703823 -410.002944) (xy 85.711581 -409.948987)
			(xy 85.726939 -409.896683) (xy 85.749585 -409.847098) (xy 85.779057 -409.80124) (xy 85.814756 -409.760043)
			(xy 85.855954 -409.724346) (xy 85.901813 -409.694876) (xy 85.9514 -409.672233) (xy 86.003705 -409.656877)
			(xy 86.057662 -409.649122) (xy 86.084918 -409.64866) (xy 86.948518 -409.64866) (xy 86.975766 -409.649211)
			(xy 87.029707 -409.656969) (xy 87.081995 -409.672325) (xy 87.131566 -409.694965) (xy 87.17741 -409.724429)
			(xy 87.218595 -409.760118) (xy 87.254282 -409.801304) (xy 87.283744 -409.84715) (xy 87.306382 -409.896721)
			(xy 87.321734 -409.94901) (xy 87.32949 -410.002952) (xy 87.32949 -410.057448) (xy 87.329489 -410.057452)
			(xy 88.767146 -410.057452) (xy 88.767146 -410.002948) (xy 88.774902 -409.949) (xy 88.790256 -409.896704)
			(xy 88.812896 -409.847125) (xy 88.842361 -409.801273) (xy 88.878051 -409.760081) (xy 88.91924 -409.724386)
			(xy 88.965089 -409.694916) (xy 89.014665 -409.672271) (xy 89.066959 -409.656911) (xy 89.120906 -409.649149)
			(xy 89.148158 -409.64866) (xy 90.011758 -409.64866) (xy 90.039011 -409.649184) (xy 90.092961 -409.656936)
			(xy 90.14526 -409.672287) (xy 90.194841 -409.694925) (xy 90.240696 -409.72439) (xy 90.28189 -409.76008)
			(xy 90.317585 -409.801271) (xy 90.347055 -409.847122) (xy 90.369698 -409.896701) (xy 90.385055 -409.948997)
			(xy 90.392813 -410.002948) (xy 90.392813 -410.057452) (xy 90.392813 -410.057453) (xy 91.830346 -410.057453)
			(xy 91.830346 -410.002947) (xy 91.838103 -409.948994) (xy 91.853459 -409.896695) (xy 91.876102 -409.847114)
			(xy 91.905571 -409.80126) (xy 91.941265 -409.760066) (xy 91.982459 -409.724372) (xy 92.028313 -409.694903)
			(xy 92.077894 -409.67226) (xy 92.130193 -409.656903) (xy 92.184145 -409.649146) (xy 92.211398 -409.64866)
			(xy 93.074998 -409.64866) (xy 93.102249 -409.649187) (xy 93.156195 -409.656943) (xy 93.208489 -409.672298)
			(xy 93.258065 -409.694938) (xy 93.303915 -409.724404) (xy 93.345104 -409.760094) (xy 93.380795 -409.801284)
			(xy 93.410261 -409.847133) (xy 93.432902 -409.896709) (xy 93.448256 -409.949003) (xy 93.456013 -410.002949)
			(xy 93.456013 -410.057451) (xy 93.456012 -410.057457) (xy 94.893523 -410.057457) (xy 94.893523 -410.002943)
			(xy 94.901282 -409.948984) (xy 94.916641 -409.896679) (xy 94.939288 -409.847092) (xy 94.968762 -409.801233)
			(xy 95.004463 -409.760036) (xy 95.045664 -409.724339) (xy 95.091525 -409.69487) (xy 95.141115 -409.672228)
			(xy 95.193421 -409.656874) (xy 95.247381 -409.64912) (xy 95.274638 -409.64866) (xy 96.138238 -409.64866)
			(xy 96.165485 -409.649213) (xy 96.219424 -409.656973) (xy 96.27171 -409.67233) (xy 96.321278 -409.694972)
			(xy 96.36712 -409.724436) (xy 96.408302 -409.760125) (xy 96.443986 -409.801311) (xy 96.473447 -409.847155)
			(xy 96.496083 -409.896726) (xy 96.511435 -409.949013) (xy 96.51919 -410.002953) (xy 96.51919 -410.057447)
			(xy 96.519189 -410.057451) (xy 121.120146 -410.057451) (xy 121.120146 -410.002949) (xy 121.127902 -409.949)
			(xy 121.143256 -409.896705) (xy 121.165895 -409.847127) (xy 121.19536 -409.801275) (xy 121.231049 -409.760082)
			(xy 121.272238 -409.724388) (xy 121.318086 -409.694918) (xy 121.367662 -409.672272) (xy 121.419955 -409.656911)
			(xy 121.473903 -409.649149) (xy 121.501154 -409.64866) (xy 122.364754 -409.64866) (xy 122.392007 -409.649184)
			(xy 122.445958 -409.656935) (xy 122.498257 -409.672286) (xy 122.547839 -409.694924) (xy 122.593694 -409.724388)
			(xy 122.634889 -409.760079) (xy 122.670584 -409.801269) (xy 122.700054 -409.847121) (xy 122.722698 -409.8967)
			(xy 122.738055 -409.948997) (xy 122.745813 -410.002947) (xy 122.745813 -410.057453) (xy 124.183346 -410.057453)
			(xy 124.183346 -410.002947) (xy 124.191103 -409.948995) (xy 124.206459 -409.896696) (xy 124.229102 -409.847115)
			(xy 124.25857 -409.801261) (xy 124.294264 -409.760068) (xy 124.335457 -409.724373) (xy 124.38131 -409.694904)
			(xy 124.430891 -409.672261) (xy 124.483189 -409.656904) (xy 124.537141 -409.649146) (xy 124.564394 -409.64866)
			(xy 125.427994 -409.64866) (xy 125.455245 -409.649187) (xy 125.509192 -409.656942) (xy 125.561486 -409.672297)
			(xy 125.611063 -409.694937) (xy 125.656913 -409.724402) (xy 125.698103 -409.760093) (xy 125.733794 -409.801282)
			(xy 125.76326 -409.847132) (xy 125.785901 -409.896708) (xy 125.801256 -409.949002) (xy 125.809013 -410.002949)
			(xy 125.809013 -410.057451) (xy 125.809012 -410.057457) (xy 127.246523 -410.057457) (xy 127.246523 -410.002943)
			(xy 127.254282 -409.948985) (xy 127.269641 -409.89668) (xy 127.292287 -409.847093) (xy 127.321761 -409.801235)
			(xy 127.357462 -409.760037) (xy 127.398662 -409.724341) (xy 127.444523 -409.694871) (xy 127.494112 -409.672229)
			(xy 127.546418 -409.656874) (xy 127.600377 -409.649121) (xy 127.627634 -409.64866) (xy 128.491234 -409.64866)
			(xy 128.518481 -409.649213) (xy 128.572421 -409.656972) (xy 128.624707 -409.672329) (xy 128.674276 -409.69497)
			(xy 128.720118 -409.724435) (xy 128.761301 -409.760123) (xy 128.796985 -409.801309) (xy 128.826446 -409.847154)
			(xy 128.849083 -409.896725) (xy 128.864435 -409.949012) (xy 128.87219 -410.002953) (xy 128.87219 -410.057447)
			(xy 128.872189 -410.057452) (xy 130.309846 -410.057452) (xy 130.309846 -410.002948) (xy 130.317602 -409.948998)
			(xy 130.332957 -409.896701) (xy 130.355599 -409.847121) (xy 130.385065 -409.801268) (xy 130.420757 -409.760075)
			(xy 130.461947 -409.72438) (xy 130.507798 -409.694911) (xy 130.557376 -409.672266) (xy 130.609672 -409.656908)
			(xy 130.663622 -409.649148) (xy 130.690874 -409.64866) (xy 131.554474 -409.64866) (xy 131.581726 -409.649185)
			(xy 131.635675 -409.656939) (xy 131.687972 -409.672291) (xy 131.737551 -409.69493) (xy 131.783403 -409.724395)
			(xy 131.824596 -409.760086) (xy 131.860289 -409.801276) (xy 131.889757 -409.847126) (xy 131.9124 -409.896704)
			(xy 131.927756 -409.949) (xy 131.935513 -410.002948) (xy 131.935513 -410.057452) (xy 131.935512 -410.057456)
			(xy 133.373023 -410.057456) (xy 133.373023 -410.002944) (xy 133.380781 -409.948987) (xy 133.396139 -409.896684)
			(xy 133.418784 -409.847099) (xy 133.448256 -409.801241) (xy 133.483954 -409.760045) (xy 133.525152 -409.724348)
			(xy 133.571011 -409.694878) (xy 133.620597 -409.672234) (xy 133.672901 -409.656878) (xy 133.726858 -409.649122)
			(xy 133.754114 -409.64866) (xy 134.617714 -409.64866) (xy 134.644962 -409.649211) (xy 134.698904 -409.656969)
			(xy 134.751193 -409.672324) (xy 134.800764 -409.694964) (xy 134.846609 -409.724428) (xy 134.887794 -409.760116)
			(xy 134.923481 -409.801303) (xy 134.952943 -409.847149) (xy 134.975581 -409.896721) (xy 134.990934 -409.94901)
			(xy 134.99869 -410.002952) (xy 134.99869 -410.057448) (xy 134.99869 -410.057451) (xy 136.436346 -410.057451)
			(xy 136.436346 -410.002949) (xy 136.444102 -409.949) (xy 136.459456 -409.896705) (xy 136.482095 -409.847127)
			(xy 136.51156 -409.801275) (xy 136.547249 -409.760082) (xy 136.588438 -409.724388) (xy 136.634286 -409.694918)
			(xy 136.683862 -409.672272) (xy 136.736155 -409.656911) (xy 136.790103 -409.649149) (xy 136.817354 -409.64866)
			(xy 137.680954 -409.64866) (xy 137.708207 -409.649184) (xy 137.762158 -409.656935) (xy 137.814457 -409.672286)
			(xy 137.864039 -409.694924) (xy 137.909894 -409.724388) (xy 137.951089 -409.760079) (xy 137.986784 -409.801269)
			(xy 138.016254 -409.847121) (xy 138.038898 -409.8967) (xy 138.054255 -409.948997) (xy 138.062013 -410.002947)
			(xy 138.062013 -410.057453) (xy 139.499546 -410.057453) (xy 139.499546 -410.002947) (xy 139.507303 -409.948995)
			(xy 139.522659 -409.896696) (xy 139.545302 -409.847115) (xy 139.57477 -409.801261) (xy 139.610464 -409.760068)
			(xy 139.651657 -409.724373) (xy 139.69751 -409.694904) (xy 139.747091 -409.672261) (xy 139.799389 -409.656904)
			(xy 139.853341 -409.649146) (xy 139.880594 -409.64866) (xy 140.744194 -409.64866) (xy 140.771445 -409.649187)
			(xy 140.825392 -409.656942) (xy 140.877686 -409.672297) (xy 140.927263 -409.694937) (xy 140.973113 -409.724402)
			(xy 141.014303 -409.760093) (xy 141.049994 -409.801282) (xy 141.07946 -409.847132) (xy 141.102101 -409.896708)
			(xy 141.117456 -409.949002) (xy 141.125213 -410.002949) (xy 141.125213 -410.057451) (xy 141.125212 -410.057457)
			(xy 142.562723 -410.057457) (xy 142.562723 -410.002943) (xy 142.570482 -409.948985) (xy 142.585841 -409.89668)
			(xy 142.608487 -409.847093) (xy 142.637961 -409.801235) (xy 142.673662 -409.760037) (xy 142.714862 -409.724341)
			(xy 142.760723 -409.694871) (xy 142.810312 -409.672229) (xy 142.862618 -409.656874) (xy 142.916577 -409.649121)
			(xy 142.943834 -409.64866) (xy 143.807434 -409.64866) (xy 143.834681 -409.649213) (xy 143.888621 -409.656972)
			(xy 143.940907 -409.672329) (xy 143.990476 -409.69497) (xy 144.036318 -409.724435) (xy 144.077501 -409.760123)
			(xy 144.113185 -409.801309) (xy 144.142646 -409.847154) (xy 144.165283 -409.896725) (xy 144.180635 -409.949012)
			(xy 144.18839 -410.002953) (xy 144.18839 -410.057447) (xy 144.188389 -410.057452) (xy 145.626046 -410.057452)
			(xy 145.626046 -410.002948) (xy 145.633802 -409.948998) (xy 145.649157 -409.896701) (xy 145.671799 -409.847121)
			(xy 145.701265 -409.801268) (xy 145.736957 -409.760075) (xy 145.778147 -409.72438) (xy 145.823998 -409.694911)
			(xy 145.873576 -409.672266) (xy 145.925872 -409.656908) (xy 145.979822 -409.649148) (xy 146.007074 -409.64866)
			(xy 146.870674 -409.64866) (xy 146.897926 -409.649185) (xy 146.951875 -409.656939) (xy 147.004172 -409.672291)
			(xy 147.053751 -409.69493) (xy 147.099603 -409.724395) (xy 147.140796 -409.760086) (xy 147.176489 -409.801276)
			(xy 147.205957 -409.847126) (xy 147.2286 -409.896704) (xy 147.243956 -409.949) (xy 147.251713 -410.002948)
			(xy 147.251713 -410.057452) (xy 147.251712 -410.057456) (xy 148.689223 -410.057456) (xy 148.689223 -410.002944)
			(xy 148.696981 -409.948987) (xy 148.712339 -409.896684) (xy 148.734984 -409.847099) (xy 148.764456 -409.801241)
			(xy 148.800154 -409.760045) (xy 148.841352 -409.724348) (xy 148.887211 -409.694878) (xy 148.936797 -409.672234)
			(xy 148.989101 -409.656878) (xy 149.043058 -409.649122) (xy 149.070314 -409.64866) (xy 149.933914 -409.64866)
			(xy 149.961162 -409.649211) (xy 150.015104 -409.656969) (xy 150.067393 -409.672324) (xy 150.116964 -409.694964)
			(xy 150.162809 -409.724428) (xy 150.203994 -409.760116) (xy 150.239681 -409.801303) (xy 150.269143 -409.847149)
			(xy 150.291781 -409.896721) (xy 150.307134 -409.94901) (xy 150.31489 -410.002952) (xy 150.31489 -410.057448)
			(xy 150.31489 -410.057451) (xy 151.752546 -410.057451) (xy 151.752546 -410.002949) (xy 151.760302 -409.949)
			(xy 151.775656 -409.896705) (xy 151.798295 -409.847127) (xy 151.82776 -409.801275) (xy 151.863449 -409.760082)
			(xy 151.904638 -409.724388) (xy 151.950486 -409.694918) (xy 152.000062 -409.672272) (xy 152.052355 -409.656911)
			(xy 152.106303 -409.649149) (xy 152.133554 -409.64866) (xy 152.997154 -409.64866) (xy 153.024407 -409.649184)
			(xy 153.078358 -409.656935) (xy 153.130657 -409.672286) (xy 153.180239 -409.694924) (xy 153.226094 -409.724388)
			(xy 153.267289 -409.760079) (xy 153.302984 -409.801269) (xy 153.332454 -409.847121) (xy 153.355098 -409.8967)
			(xy 153.370455 -409.948997) (xy 153.378213 -410.002947) (xy 153.378213 -410.057453) (xy 154.815746 -410.057453)
			(xy 154.815746 -410.002947) (xy 154.823503 -409.948995) (xy 154.838859 -409.896696) (xy 154.861502 -409.847115)
			(xy 154.89097 -409.801261) (xy 154.926664 -409.760068) (xy 154.967857 -409.724373) (xy 155.01371 -409.694904)
			(xy 155.063291 -409.672261) (xy 155.115589 -409.656904) (xy 155.169541 -409.649146) (xy 155.196794 -409.64866)
			(xy 156.060394 -409.64866) (xy 156.087645 -409.649187) (xy 156.141592 -409.656942) (xy 156.193886 -409.672297)
			(xy 156.243463 -409.694937) (xy 156.289313 -409.724402) (xy 156.330503 -409.760093) (xy 156.366194 -409.801282)
			(xy 156.39566 -409.847132) (xy 156.418301 -409.896708) (xy 156.433656 -409.949002) (xy 156.441413 -410.002949)
			(xy 156.441413 -410.057451) (xy 156.441412 -410.057457) (xy 157.878923 -410.057457) (xy 157.878923 -410.002943)
			(xy 157.886682 -409.948985) (xy 157.902041 -409.89668) (xy 157.924687 -409.847093) (xy 157.954161 -409.801235)
			(xy 157.989862 -409.760037) (xy 158.031062 -409.724341) (xy 158.076923 -409.694871) (xy 158.126512 -409.672229)
			(xy 158.178818 -409.656874) (xy 158.232777 -409.649121) (xy 158.260034 -409.64866) (xy 159.123634 -409.64866)
			(xy 159.150881 -409.649213) (xy 159.204821 -409.656972) (xy 159.257107 -409.672329) (xy 159.306676 -409.69497)
			(xy 159.352518 -409.724435) (xy 159.393701 -409.760123) (xy 159.429385 -409.801309) (xy 159.458846 -409.847154)
			(xy 159.481483 -409.896725) (xy 159.496835 -409.949012) (xy 159.50459 -410.002953) (xy 159.50459 -410.057447)
			(xy 159.504589 -410.057452) (xy 160.942246 -410.057452) (xy 160.942246 -410.002948) (xy 160.950002 -409.948998)
			(xy 160.965357 -409.896701) (xy 160.987999 -409.847121) (xy 161.017465 -409.801268) (xy 161.053157 -409.760075)
			(xy 161.094347 -409.72438) (xy 161.140198 -409.694911) (xy 161.189776 -409.672266) (xy 161.242072 -409.656908)
			(xy 161.296022 -409.649148) (xy 161.323274 -409.64866) (xy 162.186874 -409.64866) (xy 162.214126 -409.649185)
			(xy 162.268075 -409.656939) (xy 162.320372 -409.672291) (xy 162.369951 -409.69493) (xy 162.415803 -409.724395)
			(xy 162.456996 -409.760086) (xy 162.492689 -409.801276) (xy 162.522157 -409.847126) (xy 162.5448 -409.896704)
			(xy 162.560156 -409.949) (xy 162.567913 -410.002948) (xy 162.567913 -410.057452) (xy 162.567912 -410.057456)
			(xy 164.005423 -410.057456) (xy 164.005423 -410.002944) (xy 164.013181 -409.948987) (xy 164.028539 -409.896684)
			(xy 164.051184 -409.847099) (xy 164.080656 -409.801241) (xy 164.116354 -409.760045) (xy 164.157552 -409.724348)
			(xy 164.203411 -409.694878) (xy 164.252997 -409.672234) (xy 164.305301 -409.656878) (xy 164.359258 -409.649122)
			(xy 164.386514 -409.64866) (xy 165.250114 -409.64866) (xy 165.277362 -409.649211) (xy 165.331304 -409.656969)
			(xy 165.383593 -409.672324) (xy 165.433164 -409.694964) (xy 165.479009 -409.724428) (xy 165.520194 -409.760116)
			(xy 165.555881 -409.801303) (xy 165.585343 -409.847149) (xy 165.607981 -409.896721) (xy 165.623334 -409.94901)
			(xy 165.63109 -410.002952) (xy 165.63109 -410.057448) (xy 165.63109 -410.057451) (xy 167.068746 -410.057451)
			(xy 167.068746 -410.002949) (xy 167.076502 -409.949) (xy 167.091856 -409.896705) (xy 167.114495 -409.847127)
			(xy 167.14396 -409.801275) (xy 167.179649 -409.760082) (xy 167.220838 -409.724388) (xy 167.266686 -409.694918)
			(xy 167.316262 -409.672272) (xy 167.368555 -409.656911) (xy 167.422503 -409.649149) (xy 167.449754 -409.64866)
			(xy 168.313354 -409.64866) (xy 168.340607 -409.649184) (xy 168.394558 -409.656935) (xy 168.446857 -409.672286)
			(xy 168.496439 -409.694924) (xy 168.542294 -409.724388) (xy 168.583489 -409.760079) (xy 168.619184 -409.801269)
			(xy 168.648654 -409.847121) (xy 168.671298 -409.8967) (xy 168.686655 -409.948997) (xy 168.694413 -410.002947)
			(xy 168.694413 -410.057453) (xy 168.686655 -410.111403) (xy 168.671298 -410.1637) (xy 168.648654 -410.213279)
			(xy 168.619184 -410.259131) (xy 168.583489 -410.300321) (xy 168.542294 -410.336012) (xy 168.496439 -410.365476)
			(xy 168.446857 -410.388114) (xy 168.394558 -410.403465) (xy 168.340607 -410.411216) (xy 168.313354 -410.411676)
			(xy 167.449754 -410.411676) (xy 167.422503 -410.411251) (xy 167.368555 -410.403489) (xy 167.316262 -410.388128)
			(xy 167.266686 -410.365482) (xy 167.220838 -410.336012) (xy 167.179649 -410.300318) (xy 167.14396 -410.259125)
			(xy 167.114495 -410.213273) (xy 167.091856 -410.163695) (xy 167.076502 -410.1114) (xy 167.068746 -410.057451)
			(xy 165.63109 -410.057451) (xy 165.623334 -410.11139) (xy 165.607981 -410.163679) (xy 165.585343 -410.213251)
			(xy 165.555881 -410.259097) (xy 165.520194 -410.300284) (xy 165.479009 -410.335972) (xy 165.433164 -410.365436)
			(xy 165.383593 -410.388076) (xy 165.331304 -410.403431) (xy 165.277362 -410.411189) (xy 165.250114 -410.411676)
			(xy 164.386514 -410.411676) (xy 164.359258 -410.411278) (xy 164.305301 -410.403522) (xy 164.252997 -410.388166)
			(xy 164.203411 -410.365522) (xy 164.157552 -410.336052) (xy 164.116354 -410.300355) (xy 164.080656 -410.259159)
			(xy 164.051184 -410.213301) (xy 164.028539 -410.163716) (xy 164.013181 -410.111413) (xy 164.005423 -410.057456)
			(xy 162.567912 -410.057456) (xy 162.560156 -410.1114) (xy 162.5448 -410.163696) (xy 162.522157 -410.213274)
			(xy 162.492689 -410.259124) (xy 162.456996 -410.300314) (xy 162.415803 -410.336005) (xy 162.369951 -410.36547)
			(xy 162.320372 -410.388109) (xy 162.268075 -410.403461) (xy 162.214126 -410.411215) (xy 162.186874 -410.411676)
			(xy 161.323274 -410.411676) (xy 161.296022 -410.411252) (xy 161.242072 -410.403492) (xy 161.189776 -410.388134)
			(xy 161.140198 -410.365489) (xy 161.094347 -410.33602) (xy 161.053157 -410.300325) (xy 161.017465 -410.259132)
			(xy 160.987999 -410.213279) (xy 160.965357 -410.163699) (xy 160.950002 -410.111402) (xy 160.942246 -410.057452)
			(xy 159.504589 -410.057452) (xy 159.496835 -410.111388) (xy 159.481483 -410.163675) (xy 159.458846 -410.213246)
			(xy 159.429385 -410.259091) (xy 159.393701 -410.300277) (xy 159.352518 -410.335965) (xy 159.306676 -410.36543)
			(xy 159.257107 -410.388071) (xy 159.204821 -410.403428) (xy 159.150881 -410.411187) (xy 159.123634 -410.411676)
			(xy 158.260034 -410.411676) (xy 158.232777 -410.411279) (xy 158.178818 -410.403526) (xy 158.126512 -410.388171)
			(xy 158.076923 -410.365529) (xy 158.031062 -410.336059) (xy 157.989862 -410.300363) (xy 157.954161 -410.259165)
			(xy 157.924687 -410.213307) (xy 157.902041 -410.16372) (xy 157.886682 -410.111415) (xy 157.878923 -410.057457)
			(xy 156.441412 -410.057457) (xy 156.433656 -410.111398) (xy 156.418301 -410.163692) (xy 156.39566 -410.213268)
			(xy 156.366194 -410.259118) (xy 156.330503 -410.300307) (xy 156.289313 -410.335998) (xy 156.243463 -410.365463)
			(xy 156.193886 -410.388103) (xy 156.141592 -410.403458) (xy 156.087645 -410.411213) (xy 156.060394 -410.411676)
			(xy 155.196794 -410.411676) (xy 155.169541 -410.411254) (xy 155.115589 -410.403496) (xy 155.063291 -410.388139)
			(xy 155.01371 -410.365496) (xy 154.967857 -410.336027) (xy 154.926664 -410.300332) (xy 154.89097 -410.259139)
			(xy 154.861502 -410.213285) (xy 154.838859 -410.163704) (xy 154.823503 -410.111405) (xy 154.815746 -410.057453)
			(xy 153.378213 -410.057453) (xy 153.370455 -410.111403) (xy 153.355098 -410.1637) (xy 153.332454 -410.213279)
			(xy 153.302984 -410.259131) (xy 153.267289 -410.300321) (xy 153.226094 -410.336012) (xy 153.180239 -410.365476)
			(xy 153.130657 -410.388114) (xy 153.078358 -410.403465) (xy 153.024407 -410.411216) (xy 152.997154 -410.411676)
			(xy 152.133554 -410.411676) (xy 152.106303 -410.411251) (xy 152.052355 -410.403489) (xy 152.000062 -410.388128)
			(xy 151.950486 -410.365482) (xy 151.904638 -410.336012) (xy 151.863449 -410.300318) (xy 151.82776 -410.259125)
			(xy 151.798295 -410.213273) (xy 151.775656 -410.163695) (xy 151.760302 -410.1114) (xy 151.752546 -410.057451)
			(xy 150.31489 -410.057451) (xy 150.307134 -410.11139) (xy 150.291781 -410.163679) (xy 150.269143 -410.213251)
			(xy 150.239681 -410.259097) (xy 150.203994 -410.300284) (xy 150.162809 -410.335972) (xy 150.116964 -410.365436)
			(xy 150.067393 -410.388076) (xy 150.015104 -410.403431) (xy 149.961162 -410.411189) (xy 149.933914 -410.411676)
			(xy 149.070314 -410.411676) (xy 149.043058 -410.411278) (xy 148.989101 -410.403522) (xy 148.936797 -410.388166)
			(xy 148.887211 -410.365522) (xy 148.841352 -410.336052) (xy 148.800154 -410.300355) (xy 148.764456 -410.259159)
			(xy 148.734984 -410.213301) (xy 148.712339 -410.163716) (xy 148.696981 -410.111413) (xy 148.689223 -410.057456)
			(xy 147.251712 -410.057456) (xy 147.243956 -410.1114) (xy 147.2286 -410.163696) (xy 147.205957 -410.213274)
			(xy 147.176489 -410.259124) (xy 147.140796 -410.300314) (xy 147.099603 -410.336005) (xy 147.053751 -410.36547)
			(xy 147.004172 -410.388109) (xy 146.951875 -410.403461) (xy 146.897926 -410.411215) (xy 146.870674 -410.411676)
			(xy 146.007074 -410.411676) (xy 145.979822 -410.411252) (xy 145.925872 -410.403492) (xy 145.873576 -410.388134)
			(xy 145.823998 -410.365489) (xy 145.778147 -410.33602) (xy 145.736957 -410.300325) (xy 145.701265 -410.259132)
			(xy 145.671799 -410.213279) (xy 145.649157 -410.163699) (xy 145.633802 -410.111402) (xy 145.626046 -410.057452)
			(xy 144.188389 -410.057452) (xy 144.180635 -410.111388) (xy 144.165283 -410.163675) (xy 144.142646 -410.213246)
			(xy 144.113185 -410.259091) (xy 144.077501 -410.300277) (xy 144.036318 -410.335965) (xy 143.990476 -410.36543)
			(xy 143.940907 -410.388071) (xy 143.888621 -410.403428) (xy 143.834681 -410.411187) (xy 143.807434 -410.411676)
			(xy 142.943834 -410.411676) (xy 142.916577 -410.411279) (xy 142.862618 -410.403526) (xy 142.810312 -410.388171)
			(xy 142.760723 -410.365529) (xy 142.714862 -410.336059) (xy 142.673662 -410.300363) (xy 142.637961 -410.259165)
			(xy 142.608487 -410.213307) (xy 142.585841 -410.16372) (xy 142.570482 -410.111415) (xy 142.562723 -410.057457)
			(xy 141.125212 -410.057457) (xy 141.117456 -410.111398) (xy 141.102101 -410.163692) (xy 141.07946 -410.213268)
			(xy 141.049994 -410.259118) (xy 141.014303 -410.300307) (xy 140.973113 -410.335998) (xy 140.927263 -410.365463)
			(xy 140.877686 -410.388103) (xy 140.825392 -410.403458) (xy 140.771445 -410.411213) (xy 140.744194 -410.411676)
			(xy 139.880594 -410.411676) (xy 139.853341 -410.411254) (xy 139.799389 -410.403496) (xy 139.747091 -410.388139)
			(xy 139.69751 -410.365496) (xy 139.651657 -410.336027) (xy 139.610464 -410.300332) (xy 139.57477 -410.259139)
			(xy 139.545302 -410.213285) (xy 139.522659 -410.163704) (xy 139.507303 -410.111405) (xy 139.499546 -410.057453)
			(xy 138.062013 -410.057453) (xy 138.054255 -410.111403) (xy 138.038898 -410.1637) (xy 138.016254 -410.213279)
			(xy 137.986784 -410.259131) (xy 137.951089 -410.300321) (xy 137.909894 -410.336012) (xy 137.864039 -410.365476)
			(xy 137.814457 -410.388114) (xy 137.762158 -410.403465) (xy 137.708207 -410.411216) (xy 137.680954 -410.411676)
			(xy 136.817354 -410.411676) (xy 136.790103 -410.411251) (xy 136.736155 -410.403489) (xy 136.683862 -410.388128)
			(xy 136.634286 -410.365482) (xy 136.588438 -410.336012) (xy 136.547249 -410.300318) (xy 136.51156 -410.259125)
			(xy 136.482095 -410.213273) (xy 136.459456 -410.163695) (xy 136.444102 -410.1114) (xy 136.436346 -410.057451)
			(xy 134.99869 -410.057451) (xy 134.990934 -410.11139) (xy 134.975581 -410.163679) (xy 134.952943 -410.213251)
			(xy 134.923481 -410.259097) (xy 134.887794 -410.300284) (xy 134.846609 -410.335972) (xy 134.800764 -410.365436)
			(xy 134.751193 -410.388076) (xy 134.698904 -410.403431) (xy 134.644962 -410.411189) (xy 134.617714 -410.411676)
			(xy 133.754114 -410.411676) (xy 133.726858 -410.411278) (xy 133.672901 -410.403522) (xy 133.620597 -410.388166)
			(xy 133.571011 -410.365522) (xy 133.525152 -410.336052) (xy 133.483954 -410.300355) (xy 133.448256 -410.259159)
			(xy 133.418784 -410.213301) (xy 133.396139 -410.163716) (xy 133.380781 -410.111413) (xy 133.373023 -410.057456)
			(xy 131.935512 -410.057456) (xy 131.927756 -410.1114) (xy 131.9124 -410.163696) (xy 131.889757 -410.213274)
			(xy 131.860289 -410.259124) (xy 131.824596 -410.300314) (xy 131.783403 -410.336005) (xy 131.737551 -410.36547)
			(xy 131.687972 -410.388109) (xy 131.635675 -410.403461) (xy 131.581726 -410.411215) (xy 131.554474 -410.411676)
			(xy 130.690874 -410.411676) (xy 130.663622 -410.411252) (xy 130.609672 -410.403492) (xy 130.557376 -410.388134)
			(xy 130.507798 -410.365489) (xy 130.461947 -410.33602) (xy 130.420757 -410.300325) (xy 130.385065 -410.259132)
			(xy 130.355599 -410.213279) (xy 130.332957 -410.163699) (xy 130.317602 -410.111402) (xy 130.309846 -410.057452)
			(xy 128.872189 -410.057452) (xy 128.864435 -410.111388) (xy 128.849083 -410.163675) (xy 128.826446 -410.213246)
			(xy 128.796985 -410.259091) (xy 128.761301 -410.300277) (xy 128.720118 -410.335965) (xy 128.674276 -410.36543)
			(xy 128.624707 -410.388071) (xy 128.572421 -410.403428) (xy 128.518481 -410.411187) (xy 128.491234 -410.411676)
			(xy 127.627634 -410.411676) (xy 127.600377 -410.411279) (xy 127.546418 -410.403526) (xy 127.494112 -410.388171)
			(xy 127.444523 -410.365529) (xy 127.398662 -410.336059) (xy 127.357462 -410.300363) (xy 127.321761 -410.259165)
			(xy 127.292287 -410.213307) (xy 127.269641 -410.16372) (xy 127.254282 -410.111415) (xy 127.246523 -410.057457)
			(xy 125.809012 -410.057457) (xy 125.801256 -410.111398) (xy 125.785901 -410.163692) (xy 125.76326 -410.213268)
			(xy 125.733794 -410.259118) (xy 125.698103 -410.300307) (xy 125.656913 -410.335998) (xy 125.611063 -410.365463)
			(xy 125.561486 -410.388103) (xy 125.509192 -410.403458) (xy 125.455245 -410.411213) (xy 125.427994 -410.411676)
			(xy 124.564394 -410.411676) (xy 124.537141 -410.411254) (xy 124.483189 -410.403496) (xy 124.430891 -410.388139)
			(xy 124.38131 -410.365496) (xy 124.335457 -410.336027) (xy 124.294264 -410.300332) (xy 124.25857 -410.259139)
			(xy 124.229102 -410.213285) (xy 124.206459 -410.163704) (xy 124.191103 -410.111405) (xy 124.183346 -410.057453)
			(xy 122.745813 -410.057453) (xy 122.738055 -410.111403) (xy 122.722698 -410.1637) (xy 122.700054 -410.213279)
			(xy 122.670584 -410.259131) (xy 122.634889 -410.300321) (xy 122.593694 -410.336012) (xy 122.547839 -410.365476)
			(xy 122.498257 -410.388114) (xy 122.445958 -410.403465) (xy 122.392007 -410.411216) (xy 122.364754 -410.411676)
			(xy 121.501154 -410.411676) (xy 121.473903 -410.411251) (xy 121.419955 -410.403489) (xy 121.367662 -410.388128)
			(xy 121.318086 -410.365482) (xy 121.272238 -410.336012) (xy 121.231049 -410.300318) (xy 121.19536 -410.259125)
			(xy 121.165895 -410.213273) (xy 121.143256 -410.163695) (xy 121.127902 -410.1114) (xy 121.120146 -410.057451)
			(xy 96.519189 -410.057451) (xy 96.511435 -410.111387) (xy 96.496083 -410.163674) (xy 96.473447 -410.213245)
			(xy 96.443986 -410.259089) (xy 96.408302 -410.300275) (xy 96.36712 -410.335964) (xy 96.321278 -410.365428)
			(xy 96.27171 -410.38807) (xy 96.219424 -410.403427) (xy 96.165485 -410.411187) (xy 96.138238 -410.411676)
			(xy 95.274638 -410.411676) (xy 95.247381 -410.41128) (xy 95.193421 -410.403526) (xy 95.141115 -410.388172)
			(xy 95.091525 -410.36553) (xy 95.045664 -410.336061) (xy 95.004463 -410.300364) (xy 94.968762 -410.259167)
			(xy 94.939288 -410.213308) (xy 94.916641 -410.163721) (xy 94.901282 -410.111416) (xy 94.893523 -410.057457)
			(xy 93.456012 -410.057457) (xy 93.448256 -410.111397) (xy 93.432902 -410.163691) (xy 93.410261 -410.213267)
			(xy 93.380795 -410.259116) (xy 93.345104 -410.300306) (xy 93.303915 -410.335996) (xy 93.258065 -410.365462)
			(xy 93.208489 -410.388102) (xy 93.156195 -410.403457) (xy 93.102249 -410.411213) (xy 93.074998 -410.411676)
			(xy 92.211398 -410.411676) (xy 92.184145 -410.411254) (xy 92.130193 -410.403497) (xy 92.077894 -410.38814)
			(xy 92.028313 -410.365497) (xy 91.982459 -410.336028) (xy 91.941265 -410.300334) (xy 91.905571 -410.25914)
			(xy 91.876102 -410.213286) (xy 91.853459 -410.163705) (xy 91.838103 -410.111406) (xy 91.830346 -410.057453)
			(xy 90.392813 -410.057453) (xy 90.385055 -410.111403) (xy 90.369698 -410.163699) (xy 90.347055 -410.213278)
			(xy 90.317585 -410.259129) (xy 90.28189 -410.30032) (xy 90.240696 -410.33601) (xy 90.194841 -410.365475)
			(xy 90.14526 -410.388113) (xy 90.092961 -410.403464) (xy 90.039011 -410.411216) (xy 90.011758 -410.411676)
			(xy 89.148158 -410.411676) (xy 89.120906 -410.411251) (xy 89.066959 -410.403489) (xy 89.014665 -410.388129)
			(xy 88.965089 -410.365484) (xy 88.91924 -410.336014) (xy 88.878051 -410.300319) (xy 88.842361 -410.259127)
			(xy 88.812896 -410.213275) (xy 88.790256 -410.163696) (xy 88.774902 -410.1114) (xy 88.767146 -410.057452)
			(xy 87.329489 -410.057452) (xy 87.321734 -410.11139) (xy 87.306382 -410.163679) (xy 87.283744 -410.21325)
			(xy 87.254282 -410.259096) (xy 87.218595 -410.300282) (xy 87.17741 -410.335971) (xy 87.131566 -410.365435)
			(xy 87.081995 -410.388075) (xy 87.029707 -410.403431) (xy 86.975766 -410.411189) (xy 86.948518 -410.411676)
			(xy 86.084918 -410.411676) (xy 86.057662 -410.411278) (xy 86.003705 -410.403523) (xy 85.9514 -410.388167)
			(xy 85.901813 -410.365524) (xy 85.855954 -410.336054) (xy 85.814756 -410.300357) (xy 85.779057 -410.25916)
			(xy 85.749585 -410.213302) (xy 85.726939 -410.163717) (xy 85.711581 -410.111413) (xy 85.703823 -410.057456)
			(xy 84.266312 -410.057456) (xy 84.258556 -410.1114) (xy 84.2432 -410.163695) (xy 84.220558 -410.213273)
			(xy 84.19109 -410.259123) (xy 84.155397 -410.300313) (xy 84.114205 -410.336003) (xy 84.068353 -410.365468)
			(xy 84.018774 -410.388108) (xy 83.966478 -410.40346) (xy 83.91253 -410.411214) (xy 83.885278 -410.411676)
			(xy 83.021678 -410.411676) (xy 82.994425 -410.411253) (xy 82.940476 -410.403493) (xy 82.888179 -410.388135)
			(xy 82.838601 -410.36549) (xy 82.792749 -410.336021) (xy 82.751558 -410.300326) (xy 82.715866 -410.259133)
			(xy 82.686399 -410.21328) (xy 82.663758 -410.1637) (xy 82.648402 -410.111403) (xy 82.640646 -410.057453)
			(xy 81.202989 -410.057453) (xy 81.195235 -410.111387) (xy 81.179883 -410.163674) (xy 81.157247 -410.213245)
			(xy 81.127786 -410.259089) (xy 81.092102 -410.300275) (xy 81.05092 -410.335964) (xy 81.005078 -410.365428)
			(xy 80.95551 -410.38807) (xy 80.903224 -410.403427) (xy 80.849285 -410.411187) (xy 80.822038 -410.411676)
			(xy 79.958438 -410.411676) (xy 79.931181 -410.41128) (xy 79.877221 -410.403526) (xy 79.824915 -410.388172)
			(xy 79.775325 -410.36553) (xy 79.729464 -410.336061) (xy 79.688263 -410.300364) (xy 79.652562 -410.259167)
			(xy 79.623088 -410.213308) (xy 79.600441 -410.163721) (xy 79.585082 -410.111416) (xy 79.577323 -410.057457)
			(xy 78.139812 -410.057457) (xy 78.132056 -410.111397) (xy 78.116702 -410.163691) (xy 78.094061 -410.213267)
			(xy 78.064595 -410.259116) (xy 78.028904 -410.300306) (xy 77.987715 -410.335996) (xy 77.941865 -410.365462)
			(xy 77.892289 -410.388102) (xy 77.839995 -410.403457) (xy 77.786049 -410.411213) (xy 77.758798 -410.411676)
			(xy 76.895198 -410.411676) (xy 76.867945 -410.411254) (xy 76.813993 -410.403497) (xy 76.761694 -410.38814)
			(xy 76.712113 -410.365497) (xy 76.666259 -410.336028) (xy 76.625065 -410.300334) (xy 76.589371 -410.25914)
			(xy 76.559902 -410.213286) (xy 76.537259 -410.163705) (xy 76.521903 -410.111406) (xy 76.514146 -410.057453)
			(xy 75.076613 -410.057453) (xy 75.068855 -410.111403) (xy 75.053498 -410.163699) (xy 75.030855 -410.213278)
			(xy 75.001385 -410.259129) (xy 74.96569 -410.30032) (xy 74.924496 -410.33601) (xy 74.878641 -410.365475)
			(xy 74.82906 -410.388113) (xy 74.776761 -410.403464) (xy 74.722811 -410.411216) (xy 74.695558 -410.411676)
			(xy 73.831958 -410.411676) (xy 73.804706 -410.411251) (xy 73.750759 -410.403489) (xy 73.698465 -410.388129)
			(xy 73.648889 -410.365484) (xy 73.60304 -410.336014) (xy 73.561851 -410.300319) (xy 73.526161 -410.259127)
			(xy 73.496696 -410.213275) (xy 73.474056 -410.163696) (xy 73.458702 -410.1114) (xy 73.450946 -410.057452)
			(xy 72.013289 -410.057452) (xy 72.005534 -410.11139) (xy 71.990182 -410.163679) (xy 71.967544 -410.21325)
			(xy 71.938082 -410.259096) (xy 71.902395 -410.300282) (xy 71.86121 -410.335971) (xy 71.815366 -410.365435)
			(xy 71.765795 -410.388075) (xy 71.713507 -410.403431) (xy 71.659566 -410.411189) (xy 71.632318 -410.411676)
			(xy 70.768718 -410.411676) (xy 70.741462 -410.411278) (xy 70.687505 -410.403523) (xy 70.6352 -410.388167)
			(xy 70.585613 -410.365524) (xy 70.539754 -410.336054) (xy 70.498556 -410.300357) (xy 70.462857 -410.25916)
			(xy 70.433385 -410.213302) (xy 70.410739 -410.163717) (xy 70.395381 -410.111413) (xy 70.387623 -410.057456)
			(xy 68.950112 -410.057456) (xy 68.942356 -410.1114) (xy 68.927 -410.163695) (xy 68.904358 -410.213273)
			(xy 68.87489 -410.259123) (xy 68.839197 -410.300313) (xy 68.798005 -410.336003) (xy 68.752153 -410.365468)
			(xy 68.702574 -410.388108) (xy 68.650278 -410.40346) (xy 68.59633 -410.411214) (xy 68.569078 -410.411676)
			(xy 67.705478 -410.411676) (xy 67.678225 -410.411253) (xy 67.624276 -410.403493) (xy 67.571979 -410.388135)
			(xy 67.522401 -410.36549) (xy 67.476549 -410.336021) (xy 67.435358 -410.300326) (xy 67.399666 -410.259133)
			(xy 67.370199 -410.21328) (xy 67.347558 -410.1637) (xy 67.332202 -410.111403) (xy 67.324446 -410.057453)
			(xy 65.886789 -410.057453) (xy 65.879035 -410.111387) (xy 65.863683 -410.163674) (xy 65.841047 -410.213245)
			(xy 65.811586 -410.259089) (xy 65.775902 -410.300275) (xy 65.73472 -410.335964) (xy 65.688878 -410.365428)
			(xy 65.63931 -410.38807) (xy 65.587024 -410.403427) (xy 65.533085 -410.411187) (xy 65.505838 -410.411676)
			(xy 64.642238 -410.411676) (xy 64.614981 -410.41128) (xy 64.561021 -410.403526) (xy 64.508715 -410.388172)
			(xy 64.459125 -410.36553) (xy 64.413264 -410.336061) (xy 64.372063 -410.300364) (xy 64.336362 -410.259167)
			(xy 64.306888 -410.213308) (xy 64.284241 -410.163721) (xy 64.268882 -410.111416) (xy 64.261123 -410.057457)
			(xy 62.823612 -410.057457) (xy 62.815856 -410.111397) (xy 62.800502 -410.163691) (xy 62.777861 -410.213267)
			(xy 62.748395 -410.259116) (xy 62.712704 -410.300306) (xy 62.671515 -410.335996) (xy 62.625665 -410.365462)
			(xy 62.576089 -410.388102) (xy 62.523795 -410.403457) (xy 62.469849 -410.411213) (xy 62.442598 -410.411676)
			(xy 61.578998 -410.411676) (xy 61.551745 -410.411254) (xy 61.497793 -410.403497) (xy 61.445494 -410.38814)
			(xy 61.395913 -410.365497) (xy 61.350059 -410.336028) (xy 61.308865 -410.300334) (xy 61.273171 -410.25914)
			(xy 61.243702 -410.213286) (xy 61.221059 -410.163705) (xy 61.205703 -410.111406) (xy 61.197946 -410.057453)
			(xy 59.760413 -410.057453) (xy 59.752655 -410.111403) (xy 59.737298 -410.163699) (xy 59.714655 -410.213278)
			(xy 59.685185 -410.259129) (xy 59.64949 -410.30032) (xy 59.608296 -410.33601) (xy 59.562441 -410.365475)
			(xy 59.51286 -410.388113) (xy 59.460561 -410.403464) (xy 59.406611 -410.411216) (xy 59.379358 -410.411676)
			(xy 58.515758 -410.411676) (xy 58.488506 -410.411251) (xy 58.434559 -410.403489) (xy 58.382265 -410.388129)
			(xy 58.332689 -410.365484) (xy 58.28684 -410.336014) (xy 58.245651 -410.300319) (xy 58.209961 -410.259127)
			(xy 58.180496 -410.213275) (xy 58.157856 -410.163696) (xy 58.142502 -410.1114) (xy 58.134746 -410.057452)
			(xy 56.697089 -410.057452) (xy 56.689334 -410.11139) (xy 56.673982 -410.163679) (xy 56.651344 -410.21325)
			(xy 56.621882 -410.259096) (xy 56.586195 -410.300282) (xy 56.54501 -410.335971) (xy 56.499166 -410.365435)
			(xy 56.449595 -410.388075) (xy 56.397307 -410.403431) (xy 56.343366 -410.411189) (xy 56.316118 -410.411676)
			(xy 55.452518 -410.411676) (xy 55.425262 -410.411278) (xy 55.371305 -410.403523) (xy 55.319 -410.388167)
			(xy 55.269413 -410.365524) (xy 55.223554 -410.336054) (xy 55.182356 -410.300357) (xy 55.146657 -410.25916)
			(xy 55.117185 -410.213302) (xy 55.094539 -410.163717) (xy 55.079181 -410.111413) (xy 55.071423 -410.057456)
			(xy 53.633912 -410.057456) (xy 53.626156 -410.1114) (xy 53.6108 -410.163695) (xy 53.588158 -410.213273)
			(xy 53.55869 -410.259123) (xy 53.522997 -410.300313) (xy 53.481805 -410.336003) (xy 53.435953 -410.365468)
			(xy 53.386374 -410.388108) (xy 53.334078 -410.40346) (xy 53.28013 -410.411214) (xy 53.252878 -410.411676)
			(xy 52.389278 -410.411676) (xy 52.362025 -410.411253) (xy 52.308076 -410.403493) (xy 52.255779 -410.388135)
			(xy 52.206201 -410.36549) (xy 52.160349 -410.336021) (xy 52.119158 -410.300326) (xy 52.083466 -410.259133)
			(xy 52.053999 -410.21328) (xy 52.031358 -410.1637) (xy 52.016002 -410.111403) (xy 52.008246 -410.057453)
			(xy 50.570589 -410.057453) (xy 50.562835 -410.111387) (xy 50.547483 -410.163674) (xy 50.524847 -410.213245)
			(xy 50.495386 -410.259089) (xy 50.459702 -410.300275) (xy 50.41852 -410.335964) (xy 50.372678 -410.365428)
			(xy 50.32311 -410.38807) (xy 50.270824 -410.403427) (xy 50.216885 -410.411187) (xy 50.189638 -410.411676)
			(xy 49.326038 -410.411676) (xy 49.298781 -410.41128) (xy 49.244821 -410.403526) (xy 49.192515 -410.388172)
			(xy 49.142925 -410.36553) (xy 49.097064 -410.336061) (xy 49.055863 -410.300364) (xy 49.020162 -410.259167)
			(xy 48.990688 -410.213308) (xy 48.968041 -410.163721) (xy 48.952682 -410.111416) (xy 48.944923 -410.057457)
			(xy 7.00913 -410.057457) (xy 7.00913 -411.241049) (xy 101.876886 -411.241049) (xy 101.876886 -411.186551)
			(xy 101.884641 -411.132608) (xy 101.899994 -411.080318) (xy 101.922631 -411.030744) (xy 101.952093 -410.984897)
			(xy 101.98778 -410.943708) (xy 102.028964 -410.908017) (xy 102.074809 -410.878551) (xy 102.12438 -410.855908)
			(xy 102.176669 -410.840549) (xy 102.230611 -410.832788) (xy 102.25786 -410.8323) (xy 103.12146 -410.8323)
			(xy 103.148715 -410.832745) (xy 103.202672 -410.840497) (xy 103.254975 -410.85585) (xy 103.304562 -410.878491)
			(xy 103.350421 -410.907958) (xy 103.391619 -410.943653) (xy 103.427318 -410.984847) (xy 103.45679 -411.030703)
			(xy 103.479436 -411.080287) (xy 103.494794 -411.132589) (xy 103.502553 -411.186545) (xy 103.502553 -411.241055)
			(xy 103.494794 -411.295011) (xy 103.479436 -411.347313) (xy 103.45679 -411.396897) (xy 103.427318 -411.442753)
			(xy 103.391619 -411.483947) (xy 103.350421 -411.519642) (xy 103.304562 -411.549109) (xy 103.254975 -411.57175)
			(xy 103.202672 -411.587103) (xy 103.148715 -411.594855) (xy 103.12146 -411.595316) (xy 102.25786 -411.595316)
			(xy 102.230611 -411.594812) (xy 102.176669 -411.587051) (xy 102.12438 -411.571692) (xy 102.074809 -411.549049)
			(xy 102.028964 -411.519583) (xy 101.98778 -411.483892) (xy 101.952093 -411.442703) (xy 101.922631 -411.396856)
			(xy 101.899994 -411.347282) (xy 101.884641 -411.294992) (xy 101.876886 -411.241049) (xy 7.00913 -411.241049)
			(xy 7.00913 -424.470068) (xy 39.528496 -424.470068) (xy 39.528496 -417.770056) (xy 39.529001 -417.664532)
			(xy 39.537085 -417.453638) (xy 39.553241 -417.243209) (xy 39.577444 -417.033552) (xy 39.609661 -416.824977)
			(xy 39.649843 -416.617789) (xy 39.697931 -416.412292) (xy 39.753855 -416.208788) (xy 39.817532 -416.007575)
			(xy 39.88887 -415.808948) (xy 39.967764 -415.6132) (xy 40.054097 -415.420618) (xy 40.147744 -415.231483)
			(xy 40.248566 -415.046074) (xy 40.356416 -414.864663) (xy 40.471135 -414.687516) (xy 40.592555 -414.514894)
			(xy 40.720498 -414.347048) (xy 40.854776 -414.184226) (xy 40.995192 -414.026667) (xy 41.14154 -413.874602)
			(xy 41.293605 -413.728254) (xy 41.451164 -413.587838) (xy 41.613986 -413.45356) (xy 41.781832 -413.325617)
			(xy 41.954454 -413.204197) (xy 42.131601 -413.089478) (xy 42.313012 -412.981628) (xy 42.498421 -412.880806)
			(xy 42.687556 -412.787159) (xy 42.880138 -412.700826) (xy 43.075886 -412.621932) (xy 43.274513 -412.550594)
			(xy 43.475726 -412.486917) (xy 43.67923 -412.430993) (xy 43.884727 -412.382905) (xy 44.091915 -412.342723)
			(xy 44.30049 -412.310506) (xy 44.510147 -412.286303) (xy 44.720576 -412.270147) (xy 44.93147 -412.262063)
			(xy 45.142518 -412.262063) (xy 45.353412 -412.270147) (xy 45.563841 -412.286303) (xy 45.773498 -412.310506)
			(xy 45.982073 -412.342723) (xy 46.189261 -412.382905) (xy 46.394758 -412.430993) (xy 46.598262 -412.486917)
			(xy 46.799475 -412.550594) (xy 46.998102 -412.621932) (xy 47.19385 -412.700826) (xy 47.386432 -412.787159)
			(xy 47.575567 -412.880806) (xy 47.760976 -412.981628) (xy 47.942387 -413.089478) (xy 48.119534 -413.204197)
			(xy 48.292156 -413.325617) (xy 48.460002 -413.45356) (xy 48.622824 -413.587838) (xy 48.649451 -413.611568)
			(xy 104.877616 -413.611568) (xy 104.877616 -412.747968) (xy 104.878102 -412.720717) (xy 104.885858 -412.666769)
			(xy 104.901213 -412.614474) (xy 104.923855 -412.564897) (xy 104.953321 -412.519047) (xy 104.989012 -412.477856)
			(xy 105.030203 -412.442165) (xy 105.076053 -412.412699) (xy 105.12563 -412.390057) (xy 105.177925 -412.374702)
			(xy 105.231873 -412.366946) (xy 105.286375 -412.366946) (xy 105.340323 -412.374702) (xy 105.392618 -412.390057)
			(xy 105.442195 -412.412699) (xy 105.488045 -412.442165) (xy 105.529236 -412.477856) (xy 105.564927 -412.519047)
			(xy 105.594393 -412.564897) (xy 105.617035 -412.614474) (xy 105.63239 -412.666769) (xy 105.640146 -412.720717)
			(xy 105.640632 -412.747968) (xy 105.640632 -413.611568) (xy 105.640146 -413.638819) (xy 105.63239 -413.692767)
			(xy 105.617035 -413.745062) (xy 105.594393 -413.794639) (xy 105.584722 -413.809688) (xy 116.689632 -413.809688)
			(xy 116.689632 -412.946088) (xy 116.690118 -412.918837) (xy 116.697874 -412.864889) (xy 116.713229 -412.812594)
			(xy 116.735871 -412.763017) (xy 116.765337 -412.717167) (xy 116.801028 -412.675976) (xy 116.842219 -412.640285)
			(xy 116.888069 -412.610819) (xy 116.937646 -412.588177) (xy 116.989941 -412.572822) (xy 117.043889 -412.565066)
			(xy 117.098391 -412.565066) (xy 117.152339 -412.572822) (xy 117.204634 -412.588177) (xy 117.254211 -412.610819)
			(xy 117.300061 -412.640285) (xy 117.341252 -412.675976) (xy 117.376943 -412.717167) (xy 117.406409 -412.763017)
			(xy 117.429051 -412.812594) (xy 117.444406 -412.864889) (xy 117.452162 -412.918837) (xy 117.452648 -412.946088)
			(xy 117.452648 -413.809688) (xy 117.452162 -413.836939) (xy 117.444406 -413.890887) (xy 117.429051 -413.943182)
			(xy 117.406409 -413.992759) (xy 117.376943 -414.038609) (xy 117.341252 -414.0798) (xy 117.300061 -414.115491)
			(xy 117.254211 -414.144957) (xy 117.204634 -414.167599) (xy 117.152339 -414.182954) (xy 117.098391 -414.19071)
			(xy 117.043889 -414.19071) (xy 116.989941 -414.182954) (xy 116.937646 -414.167599) (xy 116.888069 -414.144957)
			(xy 116.842219 -414.115491) (xy 116.801028 -414.0798) (xy 116.765337 -414.038609) (xy 116.735871 -413.992759)
			(xy 116.713229 -413.943182) (xy 116.697874 -413.890887) (xy 116.690118 -413.836939) (xy 116.689632 -413.809688)
			(xy 105.584722 -413.809688) (xy 105.564927 -413.840489) (xy 105.529236 -413.88168) (xy 105.488045 -413.917371)
			(xy 105.442195 -413.946837) (xy 105.392618 -413.969479) (xy 105.340323 -413.984834) (xy 105.286375 -413.99259)
			(xy 105.231873 -413.99259) (xy 105.177925 -413.984834) (xy 105.12563 -413.969479) (xy 105.076053 -413.946837)
			(xy 105.030203 -413.917371) (xy 104.989012 -413.88168) (xy 104.953321 -413.840489) (xy 104.923855 -413.794639)
			(xy 104.901213 -413.745062) (xy 104.885858 -413.692767) (xy 104.878102 -413.638819) (xy 104.877616 -413.611568)
			(xy 48.649451 -413.611568) (xy 48.780383 -413.728254) (xy 48.932448 -413.874602) (xy 49.078796 -414.026667)
			(xy 49.219212 -414.184226) (xy 49.35349 -414.347048) (xy 49.481433 -414.514894) (xy 49.602853 -414.687516)
			(xy 49.717572 -414.864663) (xy 49.825422 -415.046074) (xy 49.926244 -415.231483) (xy 50.019891 -415.420618)
			(xy 50.106224 -415.6132) (xy 50.133819 -415.681668) (xy 100.559616 -415.681668) (xy 100.559616 -414.818068)
			(xy 100.560102 -414.790817) (xy 100.567858 -414.736869) (xy 100.583213 -414.684574) (xy 100.605855 -414.634997)
			(xy 100.635321 -414.589147) (xy 100.671012 -414.547956) (xy 100.712203 -414.512265) (xy 100.758053 -414.482799)
			(xy 100.80763 -414.460157) (xy 100.859925 -414.444802) (xy 100.913873 -414.437046) (xy 100.968375 -414.437046)
			(xy 101.022323 -414.444802) (xy 101.074618 -414.460157) (xy 101.124195 -414.482799) (xy 101.170045 -414.512265)
			(xy 101.211236 -414.547956) (xy 101.246927 -414.589147) (xy 101.276393 -414.634997) (xy 101.299035 -414.684574)
			(xy 101.31439 -414.736869) (xy 101.322146 -414.790817) (xy 101.322632 -414.818068) (xy 101.322632 -415.681668)
			(xy 101.322146 -415.708919) (xy 101.31439 -415.762867) (xy 101.299035 -415.815162) (xy 101.276393 -415.864739)
			(xy 101.246927 -415.910589) (xy 101.211236 -415.95178) (xy 101.170045 -415.987471) (xy 101.124195 -416.016937)
			(xy 101.074618 -416.039579) (xy 101.022323 -416.054934) (xy 100.968375 -416.06269) (xy 100.913873 -416.06269)
			(xy 100.859925 -416.054934) (xy 100.80763 -416.039579) (xy 100.758053 -416.016937) (xy 100.712203 -415.987471)
			(xy 100.671012 -415.95178) (xy 100.635321 -415.910589) (xy 100.605855 -415.864739) (xy 100.583213 -415.815162)
			(xy 100.567858 -415.762867) (xy 100.560102 -415.708919) (xy 100.559616 -415.681668) (xy 50.133819 -415.681668)
			(xy 50.185118 -415.808948) (xy 50.256456 -416.007575) (xy 50.320133 -416.208788) (xy 50.376057 -416.412292)
			(xy 50.424145 -416.617789) (xy 50.464327 -416.824977) (xy 50.496544 -417.033552) (xy 50.520747 -417.243209)
			(xy 50.536903 -417.453638) (xy 50.544987 -417.664532) (xy 50.545492 -417.770056) (xy 50.545492 -420.089838)
			(xy 58.13806 -420.089838) (xy 58.138171 -420.074752) (xy 58.139951 -420.044634) (xy 58.141616 -420.02964)
			(xy 58.141616 -418.95014) (xy 58.139949 -418.935146) (xy 58.138169 -418.905028) (xy 58.13806 -418.889942)
			(xy 58.138171 -418.874856) (xy 58.139951 -418.844738) (xy 58.141616 -418.829744) (xy 58.141616 -418.218874)
			(xy 58.142085 -418.206785) (xy 58.149546 -418.183788) (xy 58.163733 -418.164211) (xy 58.183264 -418.14996)
			(xy 58.206237 -418.142424) (xy 58.218324 -418.141912) (xy 59.158124 -418.141912) (xy 59.170235 -418.142296)
			(xy 59.193265 -418.149803) (xy 59.212839 -418.164073) (xy 59.227033 -418.183702) (xy 59.234451 -418.206761)
			(xy 59.234832 -418.218874) (xy 59.234832 -420.760398) (xy 59.23439 -420.77249) (xy 59.226931 -420.795495)
			(xy 59.212739 -420.815078) (xy 59.193198 -420.829327) (xy 59.170215 -420.836854) (xy 59.158124 -420.83736)
			(xy 58.218324 -420.83736) (xy 58.206212 -420.836963) (xy 58.183179 -420.829465) (xy 58.163602 -420.8152)
			(xy 58.149408 -420.795571) (xy 58.141994 -420.772511) (xy 58.141616 -420.760398) (xy 58.141616 -420.150036)
			(xy 58.139948 -420.135042) (xy 58.138169 -420.104924) (xy 58.13806 -420.089838) (xy 50.545492 -420.089838)
			(xy 50.545492 -421.089836) (xy 60.138056 -421.089836) (xy 60.138167 -421.07475) (xy 60.139947 -421.044632)
			(xy 60.141612 -421.029638) (xy 60.141612 -419.950138) (xy 60.139945 -419.935144) (xy 60.138165 -419.905026)
			(xy 60.138056 -419.88994) (xy 60.138167 -419.874854) (xy 60.139947 -419.844736) (xy 60.141612 -419.829742)
			(xy 60.141612 -419.218872) (xy 60.14204 -419.206794) (xy 60.149513 -419.183822) (xy 60.163718 -419.164284)
			(xy 60.183265 -419.150091) (xy 60.206242 -419.142633) (xy 60.21832 -419.142164) (xy 61.15812 -419.142164)
			(xy 61.170193 -419.142647) (xy 61.193156 -419.150112) (xy 61.21269 -419.164304) (xy 61.226885 -419.183837)
			(xy 61.234352 -419.206799) (xy 61.234828 -419.218872) (xy 61.234828 -421.089836) (xy 68.13804 -421.089836)
			(xy 68.138151 -421.07475) (xy 68.139931 -421.044632) (xy 68.141596 -421.029638) (xy 68.141596 -419.950138)
			(xy 68.139929 -419.935144) (xy 68.138149 -419.905026) (xy 68.13804 -419.88994) (xy 68.138151 -419.874854)
			(xy 68.139931 -419.844736) (xy 68.141596 -419.829742) (xy 68.141596 -419.218872) (xy 68.14204 -419.206796)
			(xy 68.149511 -419.183827) (xy 68.163712 -419.16429) (xy 68.183255 -419.150096) (xy 68.206227 -419.142635)
			(xy 68.218304 -419.142164) (xy 69.158104 -419.142164) (xy 69.170176 -419.14266) (xy 69.193139 -419.150121)
			(xy 69.212673 -419.16431) (xy 69.226868 -419.18384) (xy 69.234336 -419.2068) (xy 69.234812 -419.218872)
			(xy 69.234812 -420.089838) (xy 70.138036 -420.089838) (xy 70.138149 -420.074753) (xy 70.139929 -420.044634)
			(xy 70.141592 -420.02964) (xy 70.141592 -418.95014) (xy 70.139925 -418.935146) (xy 70.138145 -418.905028)
			(xy 70.138036 -418.889942) (xy 70.13815 -418.874857) (xy 70.139929 -418.844738) (xy 70.141592 -418.829744)
			(xy 70.141592 -418.218874) (xy 70.142084 -418.206788) (xy 70.149542 -418.183794) (xy 70.163724 -418.164219)
			(xy 70.183249 -418.149968) (xy 70.206216 -418.142428) (xy 70.2183 -418.141912) (xy 71.1581 -418.141912)
			(xy 71.17021 -418.142316) (xy 71.193239 -418.149817) (xy 71.212814 -418.164081) (xy 71.227008 -418.183706)
			(xy 71.234426 -418.206762) (xy 71.234808 -418.218874) (xy 71.234808 -420.760398) (xy 71.234292 -420.772483)
			(xy 71.226841 -420.795475) (xy 71.212666 -420.815051) (xy 71.193146 -420.829303) (xy 71.170183 -420.836844)
			(xy 71.1581 -420.83736) (xy 70.2183 -420.83736) (xy 70.206187 -420.836983) (xy 70.183153 -420.829479)
			(xy 70.163576 -420.815209) (xy 70.149383 -420.795576) (xy 70.14197 -420.772512) (xy 70.141592 -420.760398)
			(xy 70.141592 -420.150036) (xy 70.139924 -420.135042) (xy 70.138145 -420.104924) (xy 70.138036 -420.089838)
			(xy 69.234812 -420.089838) (xy 69.234812 -421.089836) (xy 72.138032 -421.089836) (xy 72.138145 -421.074751)
			(xy 72.139925 -421.044632) (xy 72.141588 -421.029638) (xy 72.141588 -419.950138) (xy 72.13992 -419.935144)
			(xy 72.138141 -419.905026) (xy 72.138032 -419.88994) (xy 72.138145 -419.874855) (xy 72.139925 -419.844736)
			(xy 72.141588 -419.829742) (xy 72.141588 -419.218872) (xy 72.14204 -419.206796) (xy 72.14951 -419.183829)
			(xy 72.16371 -419.164293) (xy 72.18325 -419.150099) (xy 72.20622 -419.142636) (xy 72.218296 -419.142164)
			(xy 73.158096 -419.142164) (xy 73.170168 -419.142667) (xy 73.19313 -419.150125) (xy 73.212665 -419.164313)
			(xy 73.22686 -419.183841) (xy 73.234328 -419.206801) (xy 73.234804 -419.218872) (xy 73.234804 -419.702852)
			(xy 110.957342 -419.702852) (xy 110.957342 -419.648348) (xy 110.965098 -419.594399) (xy 110.980453 -419.542102)
			(xy 111.003093 -419.492523) (xy 111.032558 -419.44667) (xy 111.068249 -419.405477) (xy 111.109438 -419.369782)
			(xy 111.155288 -419.340312) (xy 111.204865 -419.317667) (xy 111.25716 -419.302306) (xy 111.311108 -419.294545)
			(xy 111.33836 -419.294056) (xy 112.20196 -419.294056) (xy 112.229212 -419.294589) (xy 112.283162 -419.30234)
			(xy 112.33546 -419.317691) (xy 112.385041 -419.340329) (xy 112.430894 -419.369793) (xy 112.472088 -419.405484)
			(xy 112.507783 -419.446674) (xy 112.537251 -419.492524) (xy 112.559895 -419.542102) (xy 112.575251 -419.594399)
			(xy 112.583009 -419.648348) (xy 112.583009 -419.702852) (xy 112.575251 -419.756801) (xy 112.559895 -419.809098)
			(xy 112.537251 -419.858676) (xy 112.507783 -419.904526) (xy 112.472088 -419.945716) (xy 112.430894 -419.981407)
			(xy 112.385041 -420.010871) (xy 112.33546 -420.033509) (xy 112.283162 -420.04886) (xy 112.229212 -420.056611)
			(xy 112.20196 -420.057072) (xy 111.33836 -420.057072) (xy 111.311108 -420.056655) (xy 111.25716 -420.048894)
			(xy 111.204865 -420.033533) (xy 111.155288 -420.010888) (xy 111.109438 -419.981418) (xy 111.068249 -419.945723)
			(xy 111.032558 -419.90453) (xy 111.003093 -419.858677) (xy 110.980453 -419.809098) (xy 110.965098 -419.756801)
			(xy 110.957342 -419.702852) (xy 73.234804 -419.702852) (xy 73.234804 -421.760396) (xy 73.234384 -421.772479)
			(xy 73.226917 -421.795462) (xy 73.212713 -421.815013) (xy 73.193162 -421.829217) (xy 73.170179 -421.836684)
			(xy 73.158096 -421.837104) (xy 72.218296 -421.837104) (xy 72.206221 -421.836639) (xy 72.183253 -421.829175)
			(xy 72.163716 -421.814979) (xy 72.149521 -421.79544) (xy 72.14206 -421.772471) (xy 72.141588 -421.760396)
			(xy 72.141588 -421.150034) (xy 72.13992 -421.13504) (xy 72.138141 -421.104922) (xy 72.138032 -421.089836)
			(xy 69.234812 -421.089836) (xy 69.234812 -421.760396) (xy 69.234332 -421.77247) (xy 69.226871 -421.795436)
			(xy 69.212679 -421.814973) (xy 69.193143 -421.829168) (xy 69.170178 -421.836631) (xy 69.158104 -421.837104)
			(xy 68.218304 -421.837104) (xy 68.206221 -421.836684) (xy 68.183238 -421.829217) (xy 68.163687 -421.815013)
			(xy 68.149483 -421.795462) (xy 68.142016 -421.772479) (xy 68.141596 -421.760396) (xy 68.141596 -421.150034)
			(xy 68.139928 -421.13504) (xy 68.138149 -421.104922) (xy 68.13804 -421.089836) (xy 61.234828 -421.089836)
			(xy 61.234828 -421.760396) (xy 61.234333 -421.772468) (xy 61.226874 -421.795432) (xy 61.212684 -421.814967)
			(xy 61.193154 -421.829163) (xy 61.170192 -421.836629) (xy 61.15812 -421.837104) (xy 60.21832 -421.837104)
			(xy 60.206238 -421.83667) (xy 60.183255 -421.829208) (xy 60.163704 -421.815007) (xy 60.1495 -421.795459)
			(xy 60.142032 -421.772478) (xy 60.141612 -421.760396) (xy 60.141612 -421.150034) (xy 60.139944 -421.13504)
			(xy 60.138165 -421.104922) (xy 60.138056 -421.089836) (xy 50.545492 -421.089836) (xy 50.545492 -423.68978)
			(xy 58.13806 -423.68978) (xy 58.138175 -423.674695) (xy 58.139953 -423.644576) (xy 58.141616 -423.629582)
			(xy 58.141616 -422.550082) (xy 58.139952 -422.535088) (xy 58.138171 -422.50497) (xy 58.13806 -422.489884)
			(xy 58.138175 -422.474799) (xy 58.139953 -422.44468) (xy 58.141616 -422.429686) (xy 58.141616 -421.81907)
			(xy 58.142081 -421.806981) (xy 58.149543 -421.783984) (xy 58.163731 -421.764406) (xy 58.183263 -421.750156)
			(xy 58.206237 -421.74262) (xy 58.218324 -421.742108) (xy 59.158124 -421.742108) (xy 59.170235 -421.742496)
			(xy 59.193264 -421.750003) (xy 59.212838 -421.764272) (xy 59.227031 -421.783899) (xy 59.23445 -421.806958)
			(xy 59.234832 -421.81907) (xy 59.234832 -423.68978) (xy 62.138052 -423.68978) (xy 62.138167 -423.674695)
			(xy 62.139945 -423.644576) (xy 62.141608 -423.629582) (xy 62.141608 -422.550082) (xy 62.139944 -422.535088)
			(xy 62.138163 -422.50497) (xy 62.138052 -422.489884) (xy 62.138167 -422.474799) (xy 62.139945 -422.44468)
			(xy 62.141608 -422.429686) (xy 62.141608 -421.81907) (xy 62.142081 -421.806982) (xy 62.149542 -421.783986)
			(xy 62.163728 -421.764409) (xy 62.183258 -421.750158) (xy 62.20623 -421.742621) (xy 62.218316 -421.742108)
			(xy 63.158116 -421.742108) (xy 63.170227 -421.742503) (xy 63.193256 -421.750008) (xy 63.212829 -421.764274)
			(xy 63.227023 -421.783901) (xy 63.234442 -421.806958) (xy 63.234824 -421.81907) (xy 63.234824 -424.360594)
			(xy 63.234387 -424.372687) (xy 63.226927 -424.395693) (xy 63.212734 -424.415276) (xy 63.193192 -424.429526)
			(xy 63.170207 -424.437051) (xy 63.158116 -424.437556) (xy 62.218316 -424.437556) (xy 62.206214 -424.437071)
			(xy 62.183196 -424.429582) (xy 62.163628 -424.415337) (xy 62.149431 -424.395733) (xy 62.142 -424.372697)
			(xy 62.141608 -424.360594) (xy 62.141608 -423.749978) (xy 62.139944 -423.734984) (xy 62.138162 -423.704866)
			(xy 62.138052 -423.68978) (xy 59.234832 -423.68978) (xy 59.234832 -424.360594) (xy 59.234387 -424.372686)
			(xy 59.226928 -424.395691) (xy 59.212737 -424.415274) (xy 59.193197 -424.429523) (xy 59.170215 -424.43705)
			(xy 59.158124 -424.437556) (xy 58.218324 -424.437556) (xy 58.206222 -424.437064) (xy 58.183205 -424.429578)
			(xy 58.163637 -424.415334) (xy 58.149439 -424.395732) (xy 58.142008 -424.372697) (xy 58.141616 -424.360594)
			(xy 58.141616 -423.749978) (xy 58.139952 -423.734984) (xy 58.13817 -423.704866) (xy 58.13806 -423.68978)
			(xy 50.545492 -423.68978) (xy 50.545492 -424.470068) (xy 50.544987 -424.575592) (xy 50.54061 -424.689778)
			(xy 64.138048 -424.689778) (xy 64.138163 -424.674693) (xy 64.139941 -424.644574) (xy 64.141604 -424.62958)
			(xy 64.141604 -423.55008) (xy 64.13994 -423.535086) (xy 64.138158 -423.504968) (xy 64.138048 -423.489882)
			(xy 64.138163 -423.474797) (xy 64.139941 -423.444678) (xy 64.141604 -423.429684) (xy 64.141604 -422.819068)
			(xy 64.142037 -422.806991) (xy 64.14951 -422.78402) (xy 64.163714 -422.764483) (xy 64.18326 -422.75029)
			(xy 64.206234 -422.74283) (xy 64.218312 -422.74236) (xy 65.158112 -422.74236) (xy 65.170184 -422.742854)
			(xy 65.193146 -422.750316) (xy 65.21268 -422.764506) (xy 65.226875 -422.784036) (xy 65.234343 -422.806996)
			(xy 65.23482 -422.819068) (xy 65.23482 -424.689778) (xy 68.13804 -424.689778) (xy 68.138155 -424.674693)
			(xy 68.139933 -424.644574) (xy 68.141596 -424.62958) (xy 68.141596 -423.55008) (xy 68.139932 -423.535086)
			(xy 68.13815 -423.504968) (xy 68.13804 -423.489882) (xy 68.138155 -423.474797) (xy 68.139933 -423.444678)
			(xy 68.141596 -423.429684) (xy 68.141596 -422.819068) (xy 68.142037 -422.806991) (xy 68.149509 -422.784022)
			(xy 68.163711 -422.764485) (xy 68.183255 -422.750292) (xy 68.206227 -422.742831) (xy 68.218304 -422.74236)
			(xy 69.158104 -422.74236) (xy 69.170176 -422.74286) (xy 69.193137 -422.75032) (xy 69.212672 -422.764508)
			(xy 69.226867 -422.784037) (xy 69.234335 -422.806997) (xy 69.234812 -422.819068) (xy 69.234812 -423.68978)
			(xy 70.138036 -423.68978) (xy 70.138153 -423.674695) (xy 70.139931 -423.644576) (xy 70.141592 -423.629582)
			(xy 70.141592 -422.550082) (xy 70.139928 -422.535088) (xy 70.138147 -422.50497) (xy 70.138036 -422.489884)
			(xy 70.138153 -422.474799) (xy 70.139931 -422.44468) (xy 70.141592 -422.429686) (xy 70.141592 -421.81907)
			(xy 70.142081 -421.806984) (xy 70.14954 -421.78399) (xy 70.163723 -421.764415) (xy 70.183248 -421.750163)
			(xy 70.206215 -421.742624) (xy 70.2183 -421.742108) (xy 71.1581 -421.742108) (xy 71.17021 -421.742516)
			(xy 71.193238 -421.750017) (xy 71.212812 -421.76428) (xy 71.227007 -421.783904) (xy 71.234426 -421.806959)
			(xy 71.234808 -421.81907) (xy 71.234808 -424.360594) (xy 71.234288 -424.372678) (xy 71.226839 -424.395671)
			(xy 71.212664 -424.415247) (xy 71.193145 -424.429499) (xy 71.170183 -424.43704) (xy 71.1581 -424.437556)
			(xy 70.2183 -424.437556) (xy 70.206197 -424.437085) (xy 70.183179 -424.429592) (xy 70.163611 -424.415343)
			(xy 70.149414 -424.395736) (xy 70.141983 -424.372698) (xy 70.141592 -424.360594) (xy 70.141592 -423.749978)
			(xy 70.139928 -423.734984) (xy 70.138146 -423.704866) (xy 70.138036 -423.68978) (xy 69.234812 -423.68978)
			(xy 69.234812 -424.689778) (xy 72.138032 -424.689778) (xy 72.138149 -424.674693) (xy 72.139927 -424.644574)
			(xy 72.141588 -424.62958) (xy 72.141588 -423.55008) (xy 72.139924 -423.535086) (xy 72.138142 -423.504968)
			(xy 72.138032 -423.489882) (xy 72.138149 -423.474797) (xy 72.139927 -423.444678) (xy 72.141588 -423.429684)
			(xy 72.141588 -422.819068) (xy 72.142037 -422.806992) (xy 72.149508 -422.784025) (xy 72.163708 -422.764488)
			(xy 72.18325 -422.750295) (xy 72.20622 -422.742832) (xy 72.218296 -422.74236) (xy 73.158096 -422.74236)
			(xy 73.170167 -422.742867) (xy 73.193129 -422.750325) (xy 73.212663 -422.764511) (xy 73.226859 -422.784039)
			(xy 73.234327 -422.806997) (xy 73.234804 -422.819068) (xy 73.234804 -424.80464) (xy 109.929157 -424.80464)
			(xy 109.929157 -424.6755) (xy 109.937107 -424.546605) (xy 109.952977 -424.418445) (xy 109.976706 -424.291504)
			(xy 110.008205 -424.166265) (xy 110.047354 -424.043202) (xy 110.094005 -423.922783) (xy 110.14798 -423.805464)
			(xy 110.209075 -423.69169) (xy 110.277058 -423.581893) (xy 110.351672 -423.47649) (xy 110.432633 -423.37588)
			(xy 110.519633 -423.280445) (xy 110.612344 -423.190546) (xy 110.710414 -423.106525) (xy 110.813469 -423.028701)
			(xy 110.92112 -422.957369) (xy 111.032959 -422.892799) (xy 111.14856 -422.835237) (xy 111.267485 -422.7849)
			(xy 111.389284 -422.74198) (xy 111.513494 -422.706639) (xy 111.639643 -422.679012) (xy 111.767255 -422.659203)
			(xy 111.895844 -422.647287) (xy 112.024922 -422.643311) (xy 112.154 -422.647287) (xy 112.282589 -422.659203)
			(xy 112.410201 -422.679012) (xy 112.53635 -422.706639) (xy 112.66056 -422.74198) (xy 112.782359 -422.7849)
			(xy 112.901284 -422.835237) (xy 113.016885 -422.892799) (xy 113.128724 -422.957369) (xy 113.236375 -423.028701)
			(xy 113.33943 -423.106525) (xy 113.4375 -423.190546) (xy 113.530211 -423.280445) (xy 113.617211 -423.37588)
			(xy 113.698172 -423.47649) (xy 113.772786 -423.581893) (xy 113.840769 -423.69169) (xy 113.901864 -423.805464)
			(xy 113.955839 -423.922783) (xy 114.00249 -424.043202) (xy 114.041639 -424.166265) (xy 114.073138 -424.291504)
			(xy 114.096867 -424.418445) (xy 114.112737 -424.546605) (xy 114.120687 -424.6755) (xy 114.121184 -424.74007)
			(xy 114.120687 -424.80464) (xy 114.112737 -424.933535) (xy 114.096867 -425.061695) (xy 114.073138 -425.188636)
			(xy 114.041639 -425.313875) (xy 114.00249 -425.436938) (xy 113.955839 -425.557357) (xy 113.901864 -425.674676)
			(xy 113.840769 -425.78845) (xy 113.772786 -425.898247) (xy 113.698172 -426.00365) (xy 113.617211 -426.10426)
			(xy 113.530211 -426.199695) (xy 113.4375 -426.289594) (xy 113.33943 -426.373615) (xy 113.236375 -426.451439)
			(xy 113.128724 -426.522771) (xy 113.016885 -426.587341) (xy 112.901284 -426.644903) (xy 112.782359 -426.69524)
			(xy 112.66056 -426.73816) (xy 112.53635 -426.773501) (xy 112.410201 -426.801128) (xy 112.282589 -426.820937)
			(xy 112.154 -426.832853) (xy 112.024922 -426.83683) (xy 111.895844 -426.832853) (xy 111.767255 -426.820937)
			(xy 111.639643 -426.801128) (xy 111.513494 -426.773501) (xy 111.389284 -426.73816) (xy 111.267485 -426.69524)
			(xy 111.14856 -426.644903) (xy 111.032959 -426.587341) (xy 110.92112 -426.522771) (xy 110.813469 -426.451439)
			(xy 110.710414 -426.373615) (xy 110.612344 -426.289594) (xy 110.519633 -426.199695) (xy 110.432633 -426.10426)
			(xy 110.351672 -426.00365) (xy 110.277058 -425.898247) (xy 110.209075 -425.78845) (xy 110.14798 -425.674676)
			(xy 110.094005 -425.557357) (xy 110.047354 -425.436938) (xy 110.008205 -425.313875) (xy 109.976706 -425.188636)
			(xy 109.952977 -425.061695) (xy 109.937107 -424.933535) (xy 109.929157 -424.80464) (xy 73.234804 -424.80464)
			(xy 73.234804 -425.360592) (xy 73.234381 -425.372675) (xy 73.226915 -425.395658) (xy 73.212712 -425.415209)
			(xy 73.193162 -425.429413) (xy 73.170179 -425.43688) (xy 73.158096 -425.4373) (xy 72.218296 -425.4373)
			(xy 72.206212 -425.436891) (xy 72.183228 -425.429421) (xy 72.163677 -425.415214) (xy 72.149473 -425.395661)
			(xy 72.142007 -425.372676) (xy 72.141588 -425.360592) (xy 72.141588 -424.749976) (xy 72.139924 -424.734982)
			(xy 72.138142 -424.704864) (xy 72.138032 -424.689778) (xy 69.234812 -424.689778) (xy 69.234812 -425.360592)
			(xy 69.234381 -425.372674) (xy 69.226916 -425.395656) (xy 69.212714 -425.415206) (xy 69.193167 -425.429411)
			(xy 69.170186 -425.436879) (xy 69.158104 -425.4373) (xy 68.218304 -425.4373) (xy 68.206221 -425.436884)
			(xy 68.183237 -425.429417) (xy 68.163686 -425.415212) (xy 68.149482 -425.39566) (xy 68.142015 -425.372675)
			(xy 68.141596 -425.360592) (xy 68.141596 -424.749976) (xy 68.139932 -424.734982) (xy 68.13815 -424.704864)
			(xy 68.13804 -424.689778) (xy 65.23482 -424.689778) (xy 65.23482 -425.360592) (xy 65.234329 -425.372665)
			(xy 65.22687 -425.39563) (xy 65.21268 -425.415166) (xy 65.193148 -425.429361) (xy 65.170185 -425.436826)
			(xy 65.158112 -425.4373) (xy 64.218312 -425.4373) (xy 64.206229 -425.436877) (xy 64.183246 -425.429412)
			(xy 64.163694 -425.415208) (xy 64.14949 -425.395658) (xy 64.142024 -425.372675) (xy 64.141604 -425.360592)
			(xy 64.141604 -424.749976) (xy 64.13994 -424.734982) (xy 64.138158 -424.704864) (xy 64.138048 -424.689778)
			(xy 50.54061 -424.689778) (xy 50.536903 -424.786486) (xy 50.520747 -424.996915) (xy 50.496544 -425.206572)
			(xy 50.464327 -425.415147) (xy 50.424145 -425.622335) (xy 50.376057 -425.827832) (xy 50.320133 -426.031336)
			(xy 50.256456 -426.232549) (xy 50.185118 -426.431176) (xy 50.106224 -426.626924) (xy 50.019891 -426.819506)
			(xy 49.926244 -427.008641) (xy 49.825422 -427.19405) (xy 49.768393 -427.289976) (xy 58.13806 -427.289976)
			(xy 58.138174 -427.274891) (xy 58.139952 -427.244772) (xy 58.141616 -427.229778) (xy 58.141616 -426.150024)
			(xy 58.139947 -426.135031) (xy 58.138169 -426.104912) (xy 58.13806 -426.089826) (xy 58.13817 -426.07474)
			(xy 58.139951 -426.044622) (xy 58.141616 -426.029628) (xy 58.141616 -425.419012) (xy 58.142023 -425.406928)
			(xy 58.149491 -425.383941) (xy 58.163697 -425.364389) (xy 58.183252 -425.350185) (xy 58.206239 -425.342722)
			(xy 58.218324 -425.342304) (xy 59.158124 -425.342304) (xy 59.170201 -425.342744) (xy 59.193171 -425.350215)
			(xy 59.212709 -425.364417) (xy 59.226902 -425.383961) (xy 59.234361 -425.406935) (xy 59.234832 -425.419012)
			(xy 59.234832 -427.960536) (xy 59.234367 -427.97261) (xy 59.226898 -427.995574) (xy 59.2127 -428.015109)
			(xy 59.193164 -428.029303) (xy 59.170198 -428.036769) (xy 59.158124 -428.037244) (xy 58.218324 -428.037244)
			(xy 58.206254 -428.036716) (xy 58.183294 -428.029264) (xy 58.16376 -428.015083) (xy 58.149563 -427.99556)
			(xy 58.142093 -427.972605) (xy 58.141616 -427.960536) (xy 58.141616 -427.350174) (xy 58.139952 -427.33518)
			(xy 58.13817 -427.305062) (xy 58.13806 -427.289976) (xy 49.768393 -427.289976) (xy 49.717572 -427.375461)
			(xy 49.602853 -427.552608) (xy 49.481433 -427.72523) (xy 49.35349 -427.893076) (xy 49.219212 -428.055898)
			(xy 49.078796 -428.213457) (xy 49.0054 -428.28972) (xy 60.138056 -428.28972) (xy 60.138166 -428.274634)
			(xy 60.139947 -428.244516) (xy 60.141612 -428.229522) (xy 60.141612 -427.150022) (xy 60.139943 -427.135029)
			(xy 60.138165 -427.10491) (xy 60.138056 -427.089824) (xy 60.138166 -427.074738) (xy 60.139947 -427.04462)
			(xy 60.141612 -427.029626) (xy 60.141612 -426.41901) (xy 60.142115 -426.406924) (xy 60.149566 -426.383928)
			(xy 60.163744 -426.364351) (xy 60.183268 -426.350099) (xy 60.206236 -426.342562) (xy 60.21832 -426.342048)
			(xy 61.15812 -426.342048) (xy 61.170225 -426.342499) (xy 61.193244 -426.349997) (xy 61.212812 -426.364252)
			(xy 61.227008 -426.383863) (xy 61.234437 -426.406904) (xy 61.234828 -426.41901) (xy 61.234828 -427.289976)
			(xy 62.138052 -427.289976) (xy 62.138166 -427.274891) (xy 62.139944 -427.244772) (xy 62.141608 -427.229778)
			(xy 62.141608 -426.150024) (xy 62.139939 -426.135031) (xy 62.138161 -426.104912) (xy 62.138052 -426.089826)
			(xy 62.138162 -426.07474) (xy 62.139943 -426.044622) (xy 62.141608 -426.029628) (xy 62.141608 -425.419012)
			(xy 62.142023 -425.406928) (xy 62.149489 -425.383943) (xy 62.163694 -425.364392) (xy 62.183247 -425.350188)
			(xy 62.206232 -425.342723) (xy 62.218316 -425.342304) (xy 63.158116 -425.342304) (xy 63.170193 -425.342751)
			(xy 63.193162 -425.350219) (xy 63.2127 -425.36442) (xy 63.226894 -425.383963) (xy 63.234353 -425.406935)
			(xy 63.234824 -425.419012) (xy 63.234824 -427.960536) (xy 63.234367 -427.972611) (xy 63.226896 -427.995577)
			(xy 63.212697 -428.015112) (xy 63.193159 -428.029306) (xy 63.170191 -428.03677) (xy 63.158116 -428.037244)
			(xy 62.218316 -428.037244) (xy 62.206246 -428.036723) (xy 62.183285 -428.029269) (xy 62.163751 -428.015086)
			(xy 62.149555 -427.995561) (xy 62.142085 -427.972606) (xy 62.141608 -427.960536) (xy 62.141608 -427.350174)
			(xy 62.139944 -427.33518) (xy 62.138162 -427.305062) (xy 62.138052 -427.289976) (xy 61.234828 -427.289976)
			(xy 61.234828 -428.28972) (xy 64.138048 -428.28972) (xy 64.138158 -428.274634) (xy 64.139939 -428.244516)
			(xy 64.141604 -428.229522) (xy 64.141604 -427.150022) (xy 64.139935 -427.135029) (xy 64.138157 -427.10491)
			(xy 64.138048 -427.089824) (xy 64.138158 -427.074738) (xy 64.139939 -427.04462) (xy 64.141604 -427.029626)
			(xy 64.141604 -426.41901) (xy 64.142115 -426.406925) (xy 64.149565 -426.38393) (xy 64.163741 -426.364353)
			(xy 64.183263 -426.350101) (xy 64.206228 -426.342563) (xy 64.218312 -426.342048) (xy 65.158112 -426.342048)
			(xy 65.170216 -426.342505) (xy 65.193235 -426.350002) (xy 65.212804 -426.364255) (xy 65.227 -426.383864)
			(xy 65.234429 -426.406905) (xy 65.23482 -426.41901) (xy 65.23482 -427.289976) (xy 66.138044 -427.289976)
			(xy 66.138159 -427.274891) (xy 66.139936 -427.244772) (xy 66.1416 -427.229778) (xy 66.1416 -426.150024)
			(xy 66.139931 -426.135031) (xy 66.138153 -426.104912) (xy 66.138044 -426.089826) (xy 66.138154 -426.07474)
			(xy 66.139935 -426.044622) (xy 66.1416 -426.029628) (xy 66.1416 -425.419012) (xy 66.142023 -425.406929)
			(xy 66.149488 -425.383946) (xy 66.163692 -425.364394) (xy 66.183242 -425.35019) (xy 66.206225 -425.342724)
			(xy 66.218308 -425.342304) (xy 67.158108 -425.342304) (xy 67.170192 -425.342706) (xy 67.193177 -425.350177)
			(xy 67.212729 -425.364386) (xy 67.226932 -425.383941) (xy 67.234397 -425.406928) (xy 67.234816 -425.419012)
			(xy 67.234816 -427.960536) (xy 67.234367 -427.972612) (xy 67.226895 -427.995579) (xy 67.212695 -428.015115)
			(xy 67.193154 -428.029308) (xy 67.170184 -428.036771) (xy 67.158108 -428.037244) (xy 66.218308 -428.037244)
			(xy 66.206237 -428.03673) (xy 66.183277 -428.029274) (xy 66.163743 -428.015089) (xy 66.149547 -427.995563)
			(xy 66.142077 -427.972606) (xy 66.1416 -427.960536) (xy 66.1416 -427.350174) (xy 66.139936 -427.33518)
			(xy 66.138154 -427.305062) (xy 66.138044 -427.289976) (xy 65.23482 -427.289976) (xy 65.23482 -428.28972)
			(xy 68.13804 -428.28972) (xy 68.138152 -428.274634) (xy 68.139933 -428.244516) (xy 68.141596 -428.229522)
			(xy 68.141596 -427.150022) (xy 68.139927 -427.135029) (xy 68.138149 -427.10491) (xy 68.13804 -427.089824)
			(xy 68.13815 -427.074738) (xy 68.139931 -427.04462) (xy 68.141596 -427.029626) (xy 68.141596 -426.41901)
			(xy 68.142115 -426.406925) (xy 68.149564 -426.383932) (xy 68.163739 -426.364356) (xy 68.183258 -426.350104)
			(xy 68.206221 -426.342564) (xy 68.218304 -426.342048) (xy 69.158104 -426.342048) (xy 69.170208 -426.342512)
			(xy 69.193227 -426.350006) (xy 69.212795 -426.364257) (xy 69.226991 -426.383866) (xy 69.234421 -426.406905)
			(xy 69.234812 -426.41901) (xy 69.234812 -427.289976) (xy 70.138036 -427.289976) (xy 70.138153 -427.274891)
			(xy 70.13993 -427.244772) (xy 70.141592 -427.229778) (xy 70.141592 -426.150024) (xy 70.139923 -426.135031)
			(xy 70.138145 -426.104912) (xy 70.138036 -426.089826) (xy 70.138148 -426.07474) (xy 70.139929 -426.044622)
			(xy 70.141592 -426.029628) (xy 70.141592 -425.419012) (xy 70.142023 -425.40693) (xy 70.149487 -425.383948)
			(xy 70.163689 -425.364397) (xy 70.183237 -425.350193) (xy 70.206218 -425.342725) (xy 70.2183 -425.342304)
			(xy 71.1581 -425.342304) (xy 71.170184 -425.342713) (xy 71.193169 -425.350182) (xy 71.21272 -425.364388)
			(xy 71.226924 -425.383942) (xy 71.234389 -425.406928) (xy 71.234808 -425.419012) (xy 71.234808 -427.960536)
			(xy 71.234367 -427.972612) (xy 71.226894 -427.995581) (xy 71.212692 -428.015117) (xy 71.193149 -428.029311)
			(xy 71.170177 -428.036772) (xy 71.1581 -428.037244) (xy 70.2183 -428.037244) (xy 70.206229 -428.036736)
			(xy 70.183268 -428.029278) (xy 70.163734 -428.015092) (xy 70.149538 -427.995564) (xy 70.142069 -427.972607)
			(xy 70.141592 -427.960536) (xy 70.141592 -427.350174) (xy 70.139928 -427.33518) (xy 70.138146 -427.305062)
			(xy 70.138036 -427.289976) (xy 69.234812 -427.289976) (xy 69.234812 -428.28972) (xy 72.138032 -428.28972)
			(xy 72.138144 -428.274634) (xy 72.139925 -428.244516) (xy 72.141588 -428.229522) (xy 72.141588 -427.150022)
			(xy 72.139919 -427.135029) (xy 72.138141 -427.10491) (xy 72.138032 -427.089824) (xy 72.138144 -427.074738)
			(xy 72.139925 -427.04462) (xy 72.141588 -427.029626) (xy 72.141588 -426.41901) (xy 72.142017 -426.406916)
			(xy 72.149477 -426.383908) (xy 72.163671 -426.364324) (xy 72.183216 -426.350075) (xy 72.206204 -426.342551)
			(xy 72.218296 -426.342048) (xy 73.158096 -426.342048) (xy 73.170199 -426.342519) (xy 73.193218 -426.350011)
			(xy 73.212787 -426.36426) (xy 73.226983 -426.383867) (xy 73.234413 -426.406905) (xy 73.234804 -426.41901)
			(xy 73.234804 -427.289976) (xy 75.138026 -427.289976) (xy 75.138117 -427.275402) (xy 75.139771 -427.246301)
			(xy 75.141328 -427.23181) (xy 75.141328 -426.147992) (xy 75.139785 -426.1335) (xy 75.138132 -426.1044)
			(xy 75.138026 -426.089826) (xy 75.138121 -426.075252) (xy 75.139773 -426.046151) (xy 75.141328 -426.03166)
			(xy 75.141328 -425.419012) (xy 75.141727 -425.406901) (xy 75.149227 -425.383869) (xy 75.163492 -425.364294)
			(xy 75.183119 -425.3501) (xy 75.206178 -425.342684) (xy 75.21829 -425.342304) (xy 76.15809 -425.342304)
			(xy 76.170175 -425.342815) (xy 76.19317 -425.350265) (xy 76.212747 -425.364441) (xy 76.226999 -425.383963)
			(xy 76.234537 -425.406928) (xy 76.235052 -425.419012) (xy 76.235052 -427.960536) (xy 76.234615 -427.972642)
			(xy 76.227112 -427.995661) (xy 76.212854 -428.015229) (xy 76.19324 -428.029424) (xy 76.170197 -428.036854)
			(xy 76.15809 -428.037244) (xy 75.21829 -428.037244) (xy 75.206198 -428.036801) (xy 75.183195 -428.029339)
			(xy 75.163614 -428.015147) (xy 75.149364 -427.995608) (xy 75.141835 -427.972626) (xy 75.141328 -427.960536)
			(xy 75.141328 -427.348142) (xy 75.139781 -427.33365) (xy 75.138131 -427.30455) (xy 75.138026 -427.289976)
			(xy 73.234804 -427.289976) (xy 73.234804 -428.28972) (xy 77.138022 -428.28972) (xy 77.138117 -428.275146)
			(xy 77.139768 -428.246045) (xy 77.141324 -428.231554) (xy 77.141324 -427.14799) (xy 77.139781 -427.133498)
			(xy 77.138128 -427.104398) (xy 77.138022 -427.089824) (xy 77.138117 -427.07525) (xy 77.139769 -427.046149)
			(xy 77.141324 -427.031658) (xy 77.141324 -426.41901) (xy 77.14182 -426.406897) (xy 77.149303 -426.383857)
			(xy 77.163539 -426.364256) (xy 77.183135 -426.350014) (xy 77.206174 -426.342524) (xy 77.218286 -426.342048)
			(xy 78.158086 -426.342048) (xy 78.170209 -426.342472) (xy 78.193269 -426.349962) (xy 78.212885 -426.364212)
			(xy 78.227136 -426.383827) (xy 78.234627 -426.406887) (xy 78.235048 -426.41901) (xy 78.235048 -427.289976)
			(xy 79.138018 -427.289976) (xy 79.138109 -427.275402) (xy 79.139763 -427.246301) (xy 79.14132 -427.23181)
			(xy 79.14132 -426.147992) (xy 79.139777 -426.1335) (xy 79.138124 -426.1044) (xy 79.138018 -426.089826)
			(xy 79.138113 -426.075252) (xy 79.139765 -426.046151) (xy 79.14132 -426.03166) (xy 79.14132 -425.419012)
			(xy 79.141727 -425.406902) (xy 79.149226 -425.383872) (xy 79.163489 -425.364297) (xy 79.183114 -425.350102)
			(xy 79.20617 -425.342685) (xy 79.218282 -425.342304) (xy 80.158082 -425.342304) (xy 80.170167 -425.342822)
			(xy 80.193161 -425.35027) (xy 80.212738 -425.364444) (xy 80.226991 -425.383965) (xy 80.234529 -425.406929)
			(xy 80.235044 -425.419012) (xy 80.235044 -427.960536) (xy 80.234615 -427.972642) (xy 80.227111 -427.995663)
			(xy 80.212851 -428.015232) (xy 80.193235 -428.029427) (xy 80.17019 -428.036855) (xy 80.158082 -428.037244)
			(xy 79.218282 -428.037244) (xy 79.20619 -428.036808) (xy 79.183186 -428.029344) (xy 79.163605 -428.01515)
			(xy 79.149355 -427.995609) (xy 79.141827 -427.972627) (xy 79.14132 -427.960536) (xy 79.14132 -427.348142)
			(xy 79.139773 -427.33365) (xy 79.138123 -427.30455) (xy 79.138018 -427.289976) (xy 78.235048 -427.289976)
			(xy 78.235048 -428.28972) (xy 81.138014 -428.28972) (xy 81.138108 -428.275146) (xy 81.13976 -428.246045)
			(xy 81.141316 -428.231554) (xy 81.141316 -427.14799) (xy 81.139773 -427.133498) (xy 81.13812 -427.104398)
			(xy 81.138014 -427.089824) (xy 81.138108 -427.07525) (xy 81.13976 -427.046149) (xy 81.141316 -427.031658)
			(xy 81.141316 -426.41901) (xy 81.14182 -426.406898) (xy 81.149302 -426.383859) (xy 81.163536 -426.364259)
			(xy 81.18313 -426.350016) (xy 81.206166 -426.342525) (xy 81.218278 -426.342048) (xy 82.158078 -426.342048)
			(xy 82.170201 -426.342479) (xy 82.19326 -426.349966) (xy 82.212877 -426.364215) (xy 82.227128 -426.383829)
			(xy 82.234619 -426.406887) (xy 82.23504 -426.41901) (xy 82.23504 -427.289976) (xy 83.13801 -427.289976)
			(xy 83.1381 -427.275402) (xy 83.139755 -427.246301) (xy 83.141312 -427.23181) (xy 83.141312 -426.147992)
			(xy 83.139769 -426.1335) (xy 83.138116 -426.1044) (xy 83.13801 -426.089826) (xy 83.138105 -426.075252)
			(xy 83.139756 -426.046151) (xy 83.141312 -426.03166) (xy 83.141312 -425.419012) (xy 83.141727 -425.406903)
			(xy 83.149224 -425.383874) (xy 83.163486 -425.364299) (xy 83.183109 -425.350105) (xy 83.206163 -425.342686)
			(xy 83.218274 -425.342304) (xy 84.158074 -425.342304) (xy 84.170159 -425.342829) (xy 84.193152 -425.350274)
			(xy 84.21273 -425.364447) (xy 84.226982 -425.383966) (xy 84.234521 -425.406929) (xy 84.235036 -425.419012)
			(xy 84.235036 -427.960536) (xy 84.234615 -427.972643) (xy 84.22711 -427.995665) (xy 84.212848 -428.015235)
			(xy 84.19323 -428.029429) (xy 84.170183 -428.036856) (xy 84.158074 -428.037244) (xy 83.218274 -428.037244)
			(xy 83.206181 -428.036815) (xy 83.183177 -428.029349) (xy 83.163596 -428.015153) (xy 83.149347 -427.995611)
			(xy 83.141819 -427.972627) (xy 83.141312 -427.960536) (xy 83.141312 -427.348142) (xy 83.139765 -427.33365)
			(xy 83.138115 -427.30455) (xy 83.13801 -427.289976) (xy 82.23504 -427.289976) (xy 82.23504 -428.28972)
			(xy 85.138006 -428.28972) (xy 85.1381 -428.275146) (xy 85.139752 -428.246045) (xy 85.141308 -428.231554)
			(xy 85.141308 -427.14799) (xy 85.139765 -427.133498) (xy 85.138112 -427.104398) (xy 85.138006 -427.089824)
			(xy 85.1381 -427.07525) (xy 85.139752 -427.046149) (xy 85.141308 -427.031658) (xy 85.141308 -426.41901)
			(xy 85.14182 -426.406899) (xy 85.149301 -426.383861) (xy 85.163533 -426.364262) (xy 85.183125 -426.350019)
			(xy 85.206159 -426.342526) (xy 85.21827 -426.342048) (xy 86.15807 -426.342048) (xy 86.170192 -426.342486)
			(xy 86.193252 -426.349971) (xy 86.212868 -426.364218) (xy 86.22712 -426.38383) (xy 86.234611 -426.406888)
			(xy 86.235032 -426.41901) (xy 86.235032 -427.289976) (xy 87.138002 -427.289976) (xy 87.138092 -427.275402)
			(xy 87.139747 -427.246301) (xy 87.141304 -427.23181) (xy 87.141304 -426.147992) (xy 87.139761 -426.1335)
			(xy 87.138108 -426.1044) (xy 87.138002 -426.089826) (xy 87.138097 -426.075252) (xy 87.139748 -426.046151)
			(xy 87.141304 -426.03166) (xy 87.141304 -425.419012) (xy 87.141727 -425.406903) (xy 87.149223 -425.383876)
			(xy 87.163483 -425.364302) (xy 87.183104 -425.350107) (xy 87.206156 -425.342687) (xy 87.218266 -425.342304)
			(xy 88.158066 -425.342304) (xy 88.17015 -425.342836) (xy 88.193144 -425.350279) (xy 88.212721 -425.36445)
			(xy 88.226974 -425.383968) (xy 88.234513 -425.40693) (xy 88.235028 -425.419012) (xy 88.235028 -427.960536)
			(xy 88.234615 -427.972644) (xy 88.227109 -427.995668) (xy 88.212845 -428.015238) (xy 88.193225 -428.029432)
			(xy 88.170175 -428.036857) (xy 88.158066 -428.037244) (xy 87.218266 -428.037244) (xy 87.206173 -428.036821)
			(xy 87.183169 -428.029353) (xy 87.163588 -428.015156) (xy 87.149339 -427.995612) (xy 87.141811 -427.972628)
			(xy 87.141304 -427.960536) (xy 87.141304 -427.348142) (xy 87.139757 -427.33365) (xy 87.138107 -427.30455)
			(xy 87.138002 -427.289976) (xy 86.235032 -427.289976) (xy 86.235032 -428.28972) (xy 89.137998 -428.28972)
			(xy 89.138092 -428.275146) (xy 89.139744 -428.246045) (xy 89.1413 -428.231554) (xy 89.1413 -427.14799)
			(xy 89.139757 -427.133498) (xy 89.138104 -427.104398) (xy 89.137998 -427.089824) (xy 89.138092 -427.07525)
			(xy 89.139744 -427.046149) (xy 89.1413 -427.031658) (xy 89.1413 -426.41901) (xy 89.14182 -426.4069)
			(xy 89.1493 -426.383863) (xy 89.163531 -426.364265) (xy 89.18312 -426.350022) (xy 89.206152 -426.342527)
			(xy 89.218262 -426.342048) (xy 90.158062 -426.342048) (xy 90.170184 -426.342492) (xy 90.193243 -426.349975)
			(xy 90.21286 -426.36422) (xy 90.227112 -426.383832) (xy 90.234603 -426.406888) (xy 90.235024 -426.41901)
			(xy 90.235024 -427.289976) (xy 125.218444 -427.289976) (xy 125.218925 -427.257419) (xy 125.226874 -427.192793)
			(xy 125.242661 -427.129623) (xy 125.266051 -427.068856) (xy 125.296692 -427.011403) (xy 125.334125 -426.958126)
			(xy 125.377788 -426.909823) (xy 125.402086 -426.888148) (xy 125.482858 -426.723302) (xy 125.487543 -426.71278)
			(xy 125.491036 -426.690025) (xy 125.487558 -426.667269) (xy 125.482858 -426.656754) (xy 125.401832 -426.491654)
			(xy 125.377574 -426.469952) (xy 125.333975 -426.421622) (xy 125.296599 -426.368332) (xy 125.266005 -426.310881)
			(xy 125.242649 -426.250125) (xy 125.226881 -426.186974) (xy 125.218936 -426.122371) (xy 125.218444 -426.089826)
			(xy 125.219149 -426.0507) (xy 125.23062 -425.973293) (xy 125.241304 -425.935648) (xy 125.241304 -425.419012)
			(xy 125.241727 -425.406903) (xy 125.249223 -425.383876) (xy 125.263483 -425.364302) (xy 125.283104 -425.350107)
			(xy 125.306156 -425.342687) (xy 125.318266 -425.342304) (xy 126.258066 -425.342304) (xy 126.27015 -425.342836)
			(xy 126.293144 -425.350279) (xy 126.312721 -425.36445) (xy 126.326974 -425.383968) (xy 126.334513 -425.40693)
			(xy 126.335028 -425.419012) (xy 126.335028 -427.960536) (xy 126.334615 -427.972644) (xy 126.327109 -427.995668)
			(xy 126.312845 -428.015238) (xy 126.293225 -428.029432) (xy 126.270175 -428.036857) (xy 126.258066 -428.037244)
			(xy 125.318266 -428.037244) (xy 125.306173 -428.036821) (xy 125.283169 -428.029353) (xy 125.263588 -428.015156)
			(xy 125.249339 -427.995612) (xy 125.241811 -427.972628) (xy 125.241304 -427.960536) (xy 125.241304 -427.444154)
			(xy 125.230611 -427.40651) (xy 125.219138 -427.329103) (xy 125.218444 -427.289976) (xy 90.235024 -427.289976)
			(xy 90.235024 -428.960534) (xy 90.234669 -428.972662) (xy 90.227162 -428.995729) (xy 90.212895 -429.015347)
			(xy 90.193264 -429.029595) (xy 90.170191 -429.03708) (xy 90.158062 -429.037496) (xy 89.218262 -429.037496)
			(xy 89.206149 -429.037021) (xy 89.18311 -429.029528) (xy 89.163512 -429.015285) (xy 89.14927 -428.995686)
			(xy 89.141778 -428.972647) (xy 89.1413 -428.960534) (xy 89.1413 -428.347886) (xy 89.139757 -428.333394)
			(xy 89.138104 -428.304294) (xy 89.137998 -428.28972) (xy 86.235032 -428.28972) (xy 86.235032 -428.960534)
			(xy 86.234617 -428.972653) (xy 86.227117 -428.995703) (xy 86.212861 -429.015307) (xy 86.193245 -429.029546)
			(xy 86.17019 -429.037027) (xy 86.15807 -429.037496) (xy 85.21827 -429.037496) (xy 85.206157 -429.037014)
			(xy 85.183119 -429.029523) (xy 85.16352 -429.015282) (xy 85.149279 -428.995685) (xy 85.141786 -428.972647)
			(xy 85.141308 -428.960534) (xy 85.141308 -428.347886) (xy 85.139765 -428.333394) (xy 85.138112 -428.304294)
			(xy 85.138006 -428.28972) (xy 82.23504 -428.28972) (xy 82.23504 -428.960534) (xy 82.234617 -428.972653)
			(xy 82.227118 -428.995701) (xy 82.212864 -429.015304) (xy 82.19325 -429.029543) (xy 82.170197 -429.037026)
			(xy 82.158078 -429.037496) (xy 81.218278 -429.037496) (xy 81.206166 -429.037008) (xy 81.183127 -429.029519)
			(xy 81.163529 -429.01528) (xy 81.149287 -428.995683) (xy 81.141794 -428.972646) (xy 81.141316 -428.960534)
			(xy 81.141316 -428.347886) (xy 81.139773 -428.333394) (xy 81.13812 -428.304294) (xy 81.138014 -428.28972)
			(xy 78.235048 -428.28972) (xy 78.235048 -428.960534) (xy 78.234617 -428.972652) (xy 78.227119 -428.995698)
			(xy 78.212867 -429.015301) (xy 78.193255 -429.029541) (xy 78.170204 -429.037025) (xy 78.158086 -429.037496)
			(xy 77.218286 -429.037496) (xy 77.206174 -429.037001) (xy 77.183136 -429.029514) (xy 77.163537 -429.015277)
			(xy 77.149295 -428.995682) (xy 77.141802 -428.972646) (xy 77.141324 -428.960534) (xy 77.141324 -428.347886)
			(xy 77.139781 -428.333394) (xy 77.138128 -428.304294) (xy 77.138022 -428.28972) (xy 73.234804 -428.28972)
			(xy 73.234804 -428.960534) (xy 73.234323 -428.972621) (xy 73.226862 -428.995615) (xy 73.212677 -429.015191)
			(xy 73.19315 -429.029442) (xy 73.170181 -429.036981) (xy 73.158096 -429.037496) (xy 72.218296 -429.037496)
			(xy 72.206187 -429.037087) (xy 72.183158 -429.029586) (xy 72.163585 -429.015323) (xy 72.149391 -428.995699)
			(xy 72.141971 -428.972645) (xy 72.141588 -428.960534) (xy 72.141588 -428.349918) (xy 72.139919 -428.334925)
			(xy 72.138141 -428.304806) (xy 72.138032 -428.28972) (xy 69.234812 -428.28972) (xy 69.234812 -428.960534)
			(xy 69.234421 -428.97263) (xy 69.226949 -428.99564) (xy 69.212744 -429.015223) (xy 69.193192 -429.029471)
			(xy 69.170199 -429.036994) (xy 69.158104 -429.037496) (xy 68.218304 -429.037496) (xy 68.206195 -429.03708)
			(xy 68.183167 -429.029582) (xy 68.163593 -429.01532) (xy 68.149399 -428.995698) (xy 68.141979 -428.972644)
			(xy 68.141596 -428.960534) (xy 68.141596 -428.349918) (xy 68.139927 -428.334925) (xy 68.138149 -428.304806)
			(xy 68.13804 -428.28972) (xy 65.23482 -428.28972) (xy 65.23482 -428.960534) (xy 65.234421 -428.972629)
			(xy 65.22695 -428.995638) (xy 65.212747 -429.015221) (xy 65.193197 -429.029469) (xy 65.170206 -429.036993)
			(xy 65.158112 -429.037496) (xy 64.218312 -429.037496) (xy 64.206203 -429.037073) (xy 64.183176 -429.029577)
			(xy 64.163602 -429.015317) (xy 64.149407 -428.995696) (xy 64.141987 -428.972644) (xy 64.141604 -428.960534)
			(xy 64.141604 -428.349918) (xy 64.139935 -428.334925) (xy 64.138157 -428.304806) (xy 64.138048 -428.28972)
			(xy 61.234828 -428.28972) (xy 61.234828 -428.960534) (xy 61.234421 -428.972629) (xy 61.226951 -428.995636)
			(xy 61.21275 -429.015218) (xy 61.193202 -429.029466) (xy 61.170213 -429.036992) (xy 61.15812 -429.037496)
			(xy 60.21832 -429.037496) (xy 60.206212 -429.037066) (xy 60.183185 -429.029572) (xy 60.163611 -429.015314)
			(xy 60.149416 -428.995695) (xy 60.141995 -428.972643) (xy 60.141612 -428.960534) (xy 60.141612 -428.349918)
			(xy 60.139943 -428.334925) (xy 60.138165 -428.304806) (xy 60.138056 -428.28972) (xy 49.0054 -428.28972)
			(xy 48.932448 -428.365522) (xy 48.780383 -428.51187) (xy 48.622824 -428.652286) (xy 48.460002 -428.786564)
			(xy 48.292156 -428.914507) (xy 48.119534 -429.035927) (xy 47.942387 -429.150646) (xy 47.760976 -429.258496)
			(xy 47.575567 -429.359318) (xy 47.386432 -429.452965) (xy 47.19385 -429.539298) (xy 46.998102 -429.618192)
			(xy 46.799475 -429.68953) (xy 46.598262 -429.753207) (xy 46.394758 -429.809131) (xy 46.189261 -429.857219)
			(xy 45.982073 -429.897401) (xy 45.773498 -429.929618) (xy 45.563841 -429.953821) (xy 45.353412 -429.969977)
			(xy 45.142518 -429.978061) (xy 44.93147 -429.978061) (xy 44.720576 -429.969977) (xy 44.510147 -429.953821)
			(xy 44.30049 -429.929618) (xy 44.091915 -429.897401) (xy 43.884727 -429.857219) (xy 43.67923 -429.809131)
			(xy 43.475726 -429.753207) (xy 43.274513 -429.68953) (xy 43.075886 -429.618192) (xy 42.880138 -429.539298)
			(xy 42.687556 -429.452965) (xy 42.498421 -429.359318) (xy 42.313012 -429.258496) (xy 42.131601 -429.150646)
			(xy 41.954454 -429.035927) (xy 41.781832 -428.914507) (xy 41.613986 -428.786564) (xy 41.451164 -428.652286)
			(xy 41.293605 -428.51187) (xy 41.14154 -428.365522) (xy 40.995192 -428.213457) (xy 40.854776 -428.055898)
			(xy 40.720498 -427.893076) (xy 40.592555 -427.72523) (xy 40.471135 -427.552608) (xy 40.356416 -427.375461)
			(xy 40.248566 -427.19405) (xy 40.147744 -427.008641) (xy 40.054097 -426.819506) (xy 39.967764 -426.626924)
			(xy 39.88887 -426.431176) (xy 39.817532 -426.232549) (xy 39.753855 -426.031336) (xy 39.697931 -425.827832)
			(xy 39.649843 -425.622335) (xy 39.609661 -425.415147) (xy 39.577444 -425.206572) (xy 39.553241 -424.996915)
			(xy 39.537085 -424.786486) (xy 39.529001 -424.575592) (xy 39.528496 -424.470068) (xy 7.00913 -424.470068)
			(xy 7.00913 -430.889918) (xy 58.118502 -430.889918) (xy 58.119027 -430.857363) (xy 58.12697 -430.792739)
			(xy 58.142751 -430.72957) (xy 58.166134 -430.668804) (xy 58.196768 -430.611351) (xy 58.234193 -430.558072)
			(xy 58.27785 -430.509766) (xy 58.302144 -430.48809) (xy 58.382916 -430.323244) (xy 58.387643 -430.312738)
			(xy 58.391123 -430.289973) (xy 58.387627 -430.267211) (xy 58.382916 -430.256696) (xy 58.30189 -430.091596)
			(xy 58.277644 -430.069882) (xy 58.234046 -430.021552) (xy 58.19667 -429.968265) (xy 58.166075 -429.910815)
			(xy 58.142717 -429.850062) (xy 58.126945 -429.786913) (xy 58.118996 -429.722312) (xy 58.118502 -429.689768)
			(xy 58.11923 -429.650443) (xy 58.130834 -429.572653) (xy 58.141616 -429.534828) (xy 58.141616 -429.018954)
			(xy 58.142068 -429.006864) (xy 58.149534 -428.983866) (xy 58.163726 -428.964289) (xy 58.18326 -428.950039)
			(xy 58.206236 -428.942504) (xy 58.218324 -428.941992) (xy 59.158124 -428.941992) (xy 59.170233 -428.942396)
			(xy 59.19326 -428.949901) (xy 59.212832 -428.964166) (xy 59.227026 -428.983789) (xy 59.234448 -429.006843)
			(xy 59.234832 -429.018954) (xy 59.234832 -431.560478) (xy 59.234373 -431.572569) (xy 59.226919 -431.595574)
			(xy 59.212732 -431.615156) (xy 59.193194 -431.629407) (xy 59.170214 -431.636934) (xy 59.158124 -431.63744)
			(xy 58.218324 -431.63744) (xy 58.20622 -431.636964) (xy 58.183201 -431.629476) (xy 58.163631 -431.615228)
			(xy 58.149434 -431.595622) (xy 58.142005 -431.572583) (xy 58.141616 -431.560478) (xy 58.141616 -431.044858)
			(xy 58.130821 -431.007035) (xy 58.119212 -430.929244) (xy 58.118502 -430.889918) (xy 7.00913 -430.889918)
			(xy 7.00913 -431.889916) (xy 60.118498 -431.889916) (xy 60.119023 -431.857361) (xy 60.126966 -431.792737)
			(xy 60.142747 -431.729569) (xy 60.16613 -431.668802) (xy 60.196764 -431.611349) (xy 60.234189 -431.55807)
			(xy 60.277846 -431.509764) (xy 60.30214 -431.488088) (xy 60.382912 -431.323242) (xy 60.387641 -431.312736)
			(xy 60.391121 -431.289971) (xy 60.387624 -431.267209) (xy 60.382912 -431.256694) (xy 60.301886 -431.091594)
			(xy 60.277638 -431.069882) (xy 60.23404 -431.021552) (xy 60.196665 -430.968264) (xy 60.16607 -430.910814)
			(xy 60.142712 -430.850061) (xy 60.126941 -430.786912) (xy 60.118992 -430.72231) (xy 60.118498 -430.689766)
			(xy 60.119226 -430.650441) (xy 60.13083 -430.572651) (xy 60.141612 -430.534826) (xy 60.141612 -430.018952)
			(xy 60.142024 -430.006873) (xy 60.149502 -429.983901) (xy 60.163711 -429.964363) (xy 60.183262 -429.950171)
			(xy 60.206241 -429.942713) (xy 60.21832 -429.942244) (xy 61.15812 -429.942244) (xy 61.170191 -429.942747)
			(xy 61.19315 -429.950209) (xy 61.212683 -429.964397) (xy 61.226878 -429.983924) (xy 61.234349 -430.006881)
			(xy 61.234828 -430.018952) (xy 61.234828 -430.889918) (xy 62.118494 -430.889918) (xy 62.118988 -430.857362)
			(xy 62.126932 -430.792736) (xy 62.142716 -430.729565) (xy 62.166103 -430.668798) (xy 62.196743 -430.611344)
			(xy 62.234175 -430.558067) (xy 62.277839 -430.509765) (xy 62.302136 -430.48809) (xy 62.382908 -430.323244)
			(xy 62.387636 -430.312738) (xy 62.391116 -430.289973) (xy 62.38762 -430.26721) (xy 62.382908 -430.256696)
			(xy 62.301882 -430.091596) (xy 62.277634 -430.069883) (xy 62.234037 -430.021553) (xy 62.196661 -429.968266)
			(xy 62.166066 -429.910816) (xy 62.142708 -429.850063) (xy 62.126937 -429.786914) (xy 62.118988 -429.722312)
			(xy 62.118494 -429.689768) (xy 62.119222 -429.650443) (xy 62.130827 -429.572653) (xy 62.141608 -429.534828)
			(xy 62.141608 -429.018954) (xy 62.142068 -429.006865) (xy 62.149533 -428.983868) (xy 62.163723 -428.964292)
			(xy 62.183255 -428.950042) (xy 62.206229 -428.942505) (xy 62.218316 -428.941992) (xy 63.158116 -428.941992)
			(xy 63.170225 -428.942402) (xy 63.193251 -428.949905) (xy 63.212824 -428.964169) (xy 63.227018 -428.983791)
			(xy 63.23444 -429.006844) (xy 63.234824 -429.018954) (xy 63.234824 -431.560478) (xy 63.234373 -431.57257)
			(xy 63.226918 -431.595576) (xy 63.212729 -431.615159) (xy 63.193189 -431.629409) (xy 63.170206 -431.636935)
			(xy 63.158116 -431.63744) (xy 62.218316 -431.63744) (xy 62.206212 -431.63697) (xy 62.183192 -431.62948)
			(xy 62.163622 -431.615231) (xy 62.149426 -431.595623) (xy 62.141997 -431.572583) (xy 62.141608 -431.560478)
			(xy 62.141608 -431.044858) (xy 62.130813 -431.007035) (xy 62.119204 -430.929244) (xy 62.118494 -430.889918)
			(xy 61.234828 -430.889918) (xy 61.234828 -431.889916) (xy 64.11849 -431.889916) (xy 64.118984 -431.85736)
			(xy 64.126928 -431.792734) (xy 64.142712 -431.729563) (xy 64.1661 -431.668796) (xy 64.196739 -431.611343)
			(xy 64.234171 -431.558065) (xy 64.277835 -431.509763) (xy 64.302132 -431.488088) (xy 64.382904 -431.323242)
			(xy 64.387634 -431.312736) (xy 64.391114 -431.289971) (xy 64.387616 -431.267208) (xy 64.382904 -431.256694)
			(xy 64.301878 -431.091594) (xy 64.277628 -431.069883) (xy 64.234031 -431.021553) (xy 64.196656 -430.968265)
			(xy 64.166061 -430.910815) (xy 64.142704 -430.850061) (xy 64.126933 -430.786912) (xy 64.118984 -430.72231)
			(xy 64.11849 -430.689766) (xy 64.119218 -430.650441) (xy 64.130822 -430.572651) (xy 64.141604 -430.534826)
			(xy 64.141604 -430.018952) (xy 64.142023 -430.006874) (xy 64.149501 -429.983903) (xy 64.163708 -429.964366)
			(xy 64.183257 -429.950173) (xy 64.206233 -429.942714) (xy 64.218312 -429.942244) (xy 65.158112 -429.942244)
			(xy 65.170182 -429.942753) (xy 65.193142 -429.950213) (xy 65.212674 -429.9644) (xy 65.22687 -429.983926)
			(xy 65.234341 -430.006882) (xy 65.23482 -430.018952) (xy 65.23482 -430.889918) (xy 66.118486 -430.889918)
			(xy 66.118982 -430.857362) (xy 66.126927 -430.792736) (xy 66.14271 -430.729566) (xy 66.166097 -430.668798)
			(xy 66.196736 -430.611345) (xy 66.234168 -430.558067) (xy 66.277831 -430.509765) (xy 66.302128 -430.48809)
			(xy 66.3829 -430.323244) (xy 66.387628 -430.312738) (xy 66.391109 -430.289973) (xy 66.387612 -430.26721)
			(xy 66.3829 -430.256696) (xy 66.301874 -430.091596) (xy 66.277624 -430.069885) (xy 66.234027 -430.021555)
			(xy 66.196652 -429.968266) (xy 66.166057 -429.910816) (xy 66.1427 -429.850063) (xy 66.126929 -429.786914)
			(xy 66.11898 -429.722312) (xy 66.118486 -429.689768) (xy 66.119215 -429.650443) (xy 66.130819 -429.572653)
			(xy 66.1416 -429.534828) (xy 66.1416 -429.018954) (xy 66.142067 -429.006866) (xy 66.149532 -428.983871)
			(xy 66.16372 -428.964295) (xy 66.18325 -428.950044) (xy 66.206222 -428.942507) (xy 66.218308 -428.941992)
			(xy 67.158108 -428.941992) (xy 67.170217 -428.942409) (xy 67.193243 -428.94991) (xy 67.212815 -428.964172)
			(xy 67.22701 -428.983792) (xy 67.234432 -429.006844) (xy 67.234816 -429.018954) (xy 67.234816 -431.560478)
			(xy 67.234373 -431.572571) (xy 67.226917 -431.595578) (xy 67.212726 -431.615162) (xy 67.193184 -431.629412)
			(xy 67.170199 -431.636937) (xy 67.158108 -431.63744) (xy 66.218308 -431.63744) (xy 66.206204 -431.636978)
			(xy 66.183183 -431.629485) (xy 66.163613 -431.615234) (xy 66.149417 -431.595625) (xy 66.141989 -431.572584)
			(xy 66.1416 -431.560478) (xy 66.1416 -431.044858) (xy 66.130805 -431.007035) (xy 66.119196 -430.929244)
			(xy 66.118486 -430.889918) (xy 65.23482 -430.889918) (xy 65.23482 -431.889916) (xy 68.118482 -431.889916)
			(xy 68.118978 -431.85736) (xy 68.126923 -431.792734) (xy 68.142707 -431.729564) (xy 68.166094 -431.668796)
			(xy 68.196732 -431.611343) (xy 68.234164 -431.558066) (xy 68.277827 -431.509763) (xy 68.302124 -431.488088)
			(xy 68.382896 -431.323242) (xy 68.387626 -431.312737) (xy 68.391106 -431.289971) (xy 68.387609 -431.267208)
			(xy 68.382896 -431.256694) (xy 68.30187 -431.091594) (xy 68.277639 -431.069863) (xy 68.234037 -431.021538)
			(xy 68.196658 -430.968255) (xy 68.166059 -430.910808) (xy 68.142699 -430.850057) (xy 68.126926 -430.78691)
			(xy 68.118976 -430.72231) (xy 68.118482 -430.689766) (xy 68.11921 -430.650441) (xy 68.130815 -430.572651)
			(xy 68.141596 -430.534826) (xy 68.141596 -430.018952) (xy 68.142023 -430.006875) (xy 68.149499 -429.983905)
			(xy 68.163705 -429.964368) (xy 68.183252 -429.950176) (xy 68.206226 -429.942715) (xy 68.218304 -429.942244)
			(xy 69.158104 -429.942244) (xy 69.170174 -429.94276) (xy 69.193133 -429.950218) (xy 69.212666 -429.964403)
			(xy 69.226862 -429.983927) (xy 69.234333 -430.006882) (xy 69.234812 -430.018952) (xy 69.234812 -430.889918)
			(xy 70.118478 -430.889918) (xy 70.118977 -430.857362) (xy 70.126921 -430.792736) (xy 70.142705 -430.729566)
			(xy 70.166091 -430.668799) (xy 70.19673 -430.611346) (xy 70.234161 -430.558068) (xy 70.277823 -430.509765)
			(xy 70.30212 -430.48809) (xy 70.382892 -430.323244) (xy 70.38762 -430.312738) (xy 70.391101 -430.289973)
			(xy 70.387604 -430.26721) (xy 70.382892 -430.256696) (xy 70.301866 -430.091596) (xy 70.277635 -430.069865)
			(xy 70.234033 -430.02154) (xy 70.196654 -429.968256) (xy 70.166056 -429.91081) (xy 70.142695 -429.850059)
			(xy 70.126922 -429.786912) (xy 70.118972 -429.722312) (xy 70.118478 -429.689768) (xy 70.119207 -429.650443)
			(xy 70.130811 -429.572653) (xy 70.141592 -429.534828) (xy 70.141592 -429.018954) (xy 70.142067 -429.006867)
			(xy 70.149531 -428.983873) (xy 70.163717 -428.964298) (xy 70.183245 -428.950047) (xy 70.206214 -428.942508)
			(xy 70.2183 -428.941992) (xy 71.1581 -428.941992) (xy 71.170208 -428.942416) (xy 71.193234 -428.949914)
			(xy 71.212807 -428.964174) (xy 71.227001 -428.983794) (xy 71.234424 -429.006845) (xy 71.234808 -429.018954)
			(xy 71.234808 -431.560478) (xy 71.234275 -431.572562) (xy 71.22683 -431.595553) (xy 71.212659 -431.61513)
			(xy 71.193142 -431.629383) (xy 71.170182 -431.636924) (xy 71.1581 -431.63744) (xy 70.2183 -431.63744)
			(xy 70.206195 -431.636984) (xy 70.183175 -431.62949) (xy 70.163605 -431.615237) (xy 70.149409 -431.595626)
			(xy 70.141981 -431.572584) (xy 70.141592 -431.560478) (xy 70.141592 -431.044858) (xy 70.130797 -431.007036)
			(xy 70.119188 -430.929244) (xy 70.118478 -430.889918) (xy 69.234812 -430.889918) (xy 69.234812 -431.889916)
			(xy 72.118474 -431.889916) (xy 72.118973 -431.85736) (xy 72.126917 -431.792734) (xy 72.142701 -431.729564)
			(xy 72.166088 -431.668797) (xy 72.196726 -431.611344) (xy 72.234157 -431.558066) (xy 72.277819 -431.509763)
			(xy 72.302116 -431.488088) (xy 72.382888 -431.323242) (xy 72.387618 -431.312736) (xy 72.391099 -431.289971)
			(xy 72.387601 -431.267208) (xy 72.382888 -431.256694) (xy 72.301862 -431.091594) (xy 72.277629 -431.069865)
			(xy 72.234028 -431.02154) (xy 72.196649 -430.968256) (xy 72.166051 -430.910809) (xy 72.142691 -430.850058)
			(xy 72.126918 -430.78691) (xy 72.118968 -430.72231) (xy 72.118474 -430.689766) (xy 72.119203 -430.650441)
			(xy 72.130807 -430.572651) (xy 72.141588 -430.534826) (xy 72.141588 -430.018952) (xy 72.142023 -430.006875)
			(xy 72.149498 -429.983907) (xy 72.163703 -429.964371) (xy 72.183247 -429.950178) (xy 72.206219 -429.942716)
			(xy 72.218296 -429.942244) (xy 73.158096 -429.942244) (xy 73.170166 -429.942767) (xy 73.193124 -429.950222)
			(xy 73.212657 -429.964406) (xy 73.226854 -429.983929) (xy 73.234325 -430.006883) (xy 73.234804 -430.018952)
			(xy 73.234804 -430.889918) (xy 75.118468 -430.889918) (xy 75.118971 -430.857362) (xy 75.126915 -430.792737)
			(xy 75.142698 -430.729567) (xy 75.166084 -430.668799) (xy 75.196722 -430.611346) (xy 75.234152 -430.558069)
			(xy 75.277814 -430.509765) (xy 75.30211 -430.48809) (xy 75.382882 -430.323244) (xy 75.387611 -430.312738)
			(xy 75.391092 -430.289973) (xy 75.387595 -430.26721) (xy 75.382882 -430.256696) (xy 75.301856 -430.091596)
			(xy 75.277623 -430.069867) (xy 75.234022 -430.021542) (xy 75.196643 -429.968258) (xy 75.166045 -429.910811)
			(xy 75.142685 -429.850059) (xy 75.126912 -429.786912) (xy 75.118962 -429.722312) (xy 75.118468 -429.689768)
			(xy 75.11916 -429.650641) (xy 75.13064 -429.573235) (xy 75.141328 -429.53559) (xy 75.141328 -429.018954)
			(xy 75.141772 -429.006838) (xy 75.149271 -428.983795) (xy 75.163521 -428.964195) (xy 75.183127 -428.949955)
			(xy 75.206174 -428.942467) (xy 75.21829 -428.941992) (xy 76.15809 -428.941992) (xy 76.170199 -428.94252)
			(xy 76.193235 -428.949999) (xy 76.212832 -428.964228) (xy 76.227076 -428.983815) (xy 76.234572 -429.006845)
			(xy 76.235052 -429.018954) (xy 76.235052 -431.560478) (xy 76.234621 -431.572601) (xy 76.227134 -431.59566)
			(xy 76.212885 -431.615277) (xy 76.193271 -431.629528) (xy 76.170213 -431.637019) (xy 76.15809 -431.63744)
			(xy 75.21829 -431.63744) (xy 75.206165 -431.637048) (xy 75.183102 -431.62955) (xy 75.163485 -431.615292)
			(xy 75.149235 -431.59567) (xy 75.141747 -431.572604) (xy 75.141328 -431.560478) (xy 75.141328 -431.044096)
			(xy 75.130645 -431.00645) (xy 75.119165 -430.929044) (xy 75.118468 -430.889918) (xy 73.234804 -430.889918)
			(xy 73.234804 -431.889916) (xy 77.118464 -431.889916) (xy 77.118967 -431.85736) (xy 77.126911 -431.792735)
			(xy 77.142694 -431.729565) (xy 77.16608 -431.668798) (xy 77.196718 -431.611344) (xy 77.234148 -431.558067)
			(xy 77.27781 -431.509763) (xy 77.302106 -431.488088) (xy 77.382878 -431.323242) (xy 77.387608 -431.312737)
			(xy 77.39109 -431.289971) (xy 77.387591 -431.267208) (xy 77.382878 -431.256694) (xy 77.301852 -431.091594)
			(xy 77.277617 -431.069867) (xy 77.234016 -431.021541) (xy 77.196638 -430.968257) (xy 77.16604 -430.910809)
			(xy 77.14268 -430.850058) (xy 77.126908 -430.78691) (xy 77.118958 -430.72231) (xy 77.118464 -430.689766)
			(xy 77.119155 -430.650639) (xy 77.130636 -430.573233) (xy 77.141324 -430.535588) (xy 77.141324 -430.018952)
			(xy 77.141676 -430.006838) (xy 77.149191 -429.983805) (xy 77.163469 -429.964231) (xy 77.183105 -429.950039)
			(xy 77.20617 -429.942624) (xy 77.218286 -429.942244) (xy 78.158086 -429.942244) (xy 78.170175 -429.942719)
			(xy 78.193176 -429.950173) (xy 78.212757 -429.964357) (xy 78.227007 -429.983889) (xy 78.234539 -430.006864)
			(xy 78.235048 -430.018952) (xy 78.235048 -430.889918) (xy 79.11846 -430.889918) (xy 79.118965 -430.857362)
			(xy 79.126909 -430.792737) (xy 79.142692 -430.729567) (xy 79.166078 -430.6688) (xy 79.196715 -430.611347)
			(xy 79.234145 -430.558069) (xy 79.277806 -430.509765) (xy 79.302102 -430.48809) (xy 79.382874 -430.323244)
			(xy 79.387603 -430.312738) (xy 79.391085 -430.289973) (xy 79.387587 -430.26721) (xy 79.382874 -430.256696)
			(xy 79.301848 -430.091596) (xy 79.277613 -430.069869) (xy 79.234013 -430.021543) (xy 79.196634 -429.968258)
			(xy 79.166036 -429.910811) (xy 79.142677 -429.85006) (xy 79.126904 -429.786912) (xy 79.118954 -429.722312)
			(xy 79.11846 -429.689768) (xy 79.119152 -429.650641) (xy 79.130632 -429.573235) (xy 79.14132 -429.53559)
			(xy 79.14132 -429.018954) (xy 79.141772 -429.006839) (xy 79.14927 -428.983797) (xy 79.163518 -428.964198)
			(xy 79.183122 -428.949957) (xy 79.206167 -428.942468) (xy 79.218282 -428.941992) (xy 80.158082 -428.941992)
			(xy 80.170191 -428.942526) (xy 80.193226 -428.950003) (xy 80.212824 -428.964231) (xy 80.227068 -428.983817)
			(xy 80.234563 -429.006845) (xy 80.235044 -429.018954) (xy 80.235044 -431.560478) (xy 80.234621 -431.572601)
			(xy 80.227133 -431.595663) (xy 80.212882 -431.61528) (xy 80.193266 -431.629531) (xy 80.170205 -431.63702)
			(xy 80.158082 -431.63744) (xy 79.218282 -431.63744) (xy 79.206156 -431.637055) (xy 79.183093 -431.629555)
			(xy 79.163476 -431.615295) (xy 79.149227 -431.595671) (xy 79.141739 -431.572604) (xy 79.14132 -431.560478)
			(xy 79.14132 -431.044096) (xy 79.130637 -431.00645) (xy 79.119157 -430.929044) (xy 79.11846 -430.889918)
			(xy 78.235048 -430.889918) (xy 78.235048 -431.889916) (xy 81.118456 -431.889916) (xy 81.118961 -431.85736)
			(xy 81.126905 -431.792735) (xy 81.142688 -431.729565) (xy 81.166074 -431.668798) (xy 81.196711 -431.611345)
			(xy 81.234141 -431.558067) (xy 81.277802 -431.509763) (xy 81.302098 -431.488088) (xy 81.38287 -431.323242)
			(xy 81.387601 -431.312737) (xy 81.391082 -431.289971) (xy 81.387584 -431.267208) (xy 81.38287 -431.256694)
			(xy 81.301844 -431.091594) (xy 81.277608 -431.069869) (xy 81.234007 -431.021543) (xy 81.196629 -430.968257)
			(xy 81.166031 -430.91081) (xy 81.142672 -430.850058) (xy 81.1269 -430.78691) (xy 81.11895 -430.72231)
			(xy 81.118456 -430.689766) (xy 81.119148 -430.650639) (xy 81.130628 -430.573233) (xy 81.141316 -430.535588)
			(xy 81.141316 -430.018952) (xy 81.141676 -430.006839) (xy 81.14919 -429.983807) (xy 81.163466 -429.964234)
			(xy 81.1831 -429.950041) (xy 81.206163 -429.942625) (xy 81.218278 -429.942244) (xy 82.158078 -429.942244)
			(xy 82.170167 -429.942726) (xy 82.193167 -429.950177) (xy 82.212748 -429.96436) (xy 82.226999 -429.983891)
			(xy 82.234531 -430.006865) (xy 82.23504 -430.018952) (xy 82.23504 -430.889918) (xy 83.118452 -430.889918)
			(xy 83.11896 -430.857362) (xy 83.126904 -430.792737) (xy 83.142686 -430.729568) (xy 83.166072 -430.668801)
			(xy 83.196709 -430.611347) (xy 83.234138 -430.558069) (xy 83.277798 -430.509766) (xy 83.302094 -430.48809)
			(xy 83.382866 -430.323244) (xy 83.387591 -430.312737) (xy 83.391068 -430.289973) (xy 83.387574 -430.267211)
			(xy 83.382866 -430.256696) (xy 83.30184 -430.091596) (xy 83.277604 -430.069871) (xy 83.234003 -430.021544)
			(xy 83.196625 -429.968259) (xy 83.166028 -429.910812) (xy 83.142668 -429.85006) (xy 83.126896 -429.786912)
			(xy 83.118946 -429.722312) (xy 83.118452 -429.689768) (xy 83.119144 -429.650641) (xy 83.130624 -429.573235)
			(xy 83.141312 -429.53559) (xy 83.141312 -429.018954) (xy 83.141772 -429.00684) (xy 83.149269 -428.983799)
			(xy 83.163515 -428.964201) (xy 83.183117 -428.94996) (xy 83.20616 -428.942469) (xy 83.218274 -428.941992)
			(xy 84.158074 -428.941992) (xy 84.170183 -428.942533) (xy 84.193217 -428.950008) (xy 84.212815 -428.964233)
			(xy 84.227059 -428.983818) (xy 84.234555 -429.006846) (xy 84.235036 -429.018954) (xy 84.235036 -431.560478)
			(xy 84.234621 -431.572602) (xy 84.227132 -431.595665) (xy 84.21288 -431.615282) (xy 84.193261 -431.629533)
			(xy 84.170198 -431.637022) (xy 84.158074 -431.63744) (xy 83.218274 -431.63744) (xy 83.206156 -431.63701)
			(xy 83.183108 -431.629513) (xy 83.163505 -431.615261) (xy 83.149265 -431.595649) (xy 83.141782 -431.572596)
			(xy 83.141312 -431.560478) (xy 83.141312 -431.044096) (xy 83.130629 -431.00645) (xy 83.119149 -430.929044)
			(xy 83.118452 -430.889918) (xy 82.23504 -430.889918) (xy 82.23504 -431.889916) (xy 85.118448 -431.889916)
			(xy 85.118956 -431.85736) (xy 85.1269 -431.792735) (xy 85.142683 -431.729566) (xy 85.166068 -431.668799)
			(xy 85.196705 -431.611346) (xy 85.234134 -431.558068) (xy 85.277794 -431.509764) (xy 85.30209 -431.488088)
			(xy 85.382862 -431.323242) (xy 85.387588 -431.312736) (xy 85.391066 -431.289971) (xy 85.387571 -431.267209)
			(xy 85.382862 -431.256694) (xy 85.301836 -431.091594) (xy 85.277598 -431.069871) (xy 85.233998 -431.021544)
			(xy 85.19662 -430.968258) (xy 85.166023 -430.91081) (xy 85.142664 -430.850059) (xy 85.126892 -430.786911)
			(xy 85.118942 -430.72231) (xy 85.118448 -430.689766) (xy 85.11914 -430.650639) (xy 85.13062 -430.573233)
			(xy 85.141308 -430.535588) (xy 85.141308 -430.018952) (xy 85.141676 -430.00684) (xy 85.149189 -429.98381)
			(xy 85.163463 -429.964237) (xy 85.183095 -429.950044) (xy 85.206156 -429.942626) (xy 85.21827 -429.942244)
			(xy 86.15807 -429.942244) (xy 86.170158 -429.942733) (xy 86.193159 -429.950182) (xy 86.212739 -429.964363)
			(xy 86.226991 -429.983892) (xy 86.234523 -430.006865) (xy 86.235032 -430.018952) (xy 86.235032 -430.889918)
			(xy 87.118444 -430.889918) (xy 87.118955 -430.857362) (xy 87.126898 -430.792738) (xy 87.142681 -430.729568)
			(xy 87.166066 -430.668801) (xy 87.196702 -430.611348) (xy 87.234131 -430.55807) (xy 87.277791 -430.509766)
			(xy 87.302086 -430.48809) (xy 87.382858 -430.323244) (xy 87.387583 -430.312737) (xy 87.391061 -430.289973)
			(xy 87.387567 -430.267211) (xy 87.382858 -430.256696) (xy 87.301832 -430.091596) (xy 87.277594 -430.069872)
			(xy 87.233994 -430.021546) (xy 87.196616 -429.96826) (xy 87.166019 -429.910812) (xy 87.14266 -429.85006)
			(xy 87.126888 -429.786912) (xy 87.118938 -429.722312) (xy 87.118444 -429.689768) (xy 87.119137 -429.650641)
			(xy 87.130616 -429.573235) (xy 87.141304 -429.53559) (xy 87.141304 -429.018954) (xy 87.141772 -429.00684)
			(xy 87.149268 -428.983801) (xy 87.163512 -428.964203) (xy 87.183112 -428.949962) (xy 87.206152 -428.94247)
			(xy 87.218266 -428.941992) (xy 88.158066 -428.941992) (xy 88.170174 -428.94254) (xy 88.193209 -428.950012)
			(xy 88.212807 -428.964236) (xy 88.227051 -428.98382) (xy 88.234547 -429.006846) (xy 88.235028 -429.018954)
			(xy 88.235028 -431.560478) (xy 88.234621 -431.572603) (xy 88.22713 -431.595667) (xy 88.212877 -431.615285)
			(xy 88.193256 -431.629536) (xy 88.170191 -431.637023) (xy 88.158066 -431.63744) (xy 87.218266 -431.63744)
			(xy 87.206147 -431.637017) (xy 87.183099 -431.629518) (xy 87.163496 -431.615264) (xy 87.149257 -431.59565)
			(xy 87.141774 -431.572597) (xy 87.141304 -431.560478) (xy 87.141304 -431.044096) (xy 87.13062 -431.00645)
			(xy 87.119141 -430.929044) (xy 87.118444 -430.889918) (xy 86.235032 -430.889918) (xy 86.235032 -431.889916)
			(xy 89.11844 -431.889916) (xy 89.118951 -431.85736) (xy 89.126895 -431.792736) (xy 89.142677 -431.729566)
			(xy 89.166062 -431.668799) (xy 89.196698 -431.611346) (xy 89.234127 -431.558068) (xy 89.277787 -431.509764)
			(xy 89.302082 -431.488088) (xy 89.382854 -431.323242) (xy 89.387581 -431.312736) (xy 89.391058 -431.289971)
			(xy 89.387563 -431.267209) (xy 89.382854 -431.256694) (xy 89.301828 -431.091594) (xy 89.277588 -431.069872)
			(xy 89.233989 -431.021545) (xy 89.196611 -430.968259) (xy 89.166014 -430.910811) (xy 89.142655 -430.850059)
			(xy 89.126883 -430.786911) (xy 89.118934 -430.72231) (xy 89.11844 -430.689766) (xy 89.119132 -430.650639)
			(xy 89.130612 -430.573233) (xy 89.1413 -430.535588) (xy 89.1413 -430.018952) (xy 89.141676 -430.006841)
			(xy 89.149188 -429.983812) (xy 89.16346 -429.96424) (xy 89.18309 -429.950047) (xy 89.206149 -429.942627)
			(xy 89.218262 -429.942244) (xy 90.158062 -429.942244) (xy 90.17015 -429.94274) (xy 90.19315 -429.950187)
			(xy 90.212731 -429.964366) (xy 90.226983 -429.983894) (xy 90.234515 -430.006866) (xy 90.235024 -430.018952)
			(xy 90.235024 -431.360072) (xy 108.40466 -431.360072) (xy 108.405158 -431.275192) (xy 108.413115 -431.105619)
			(xy 108.429011 -430.936605) (xy 108.452812 -430.768522) (xy 108.484466 -430.601739) (xy 108.523902 -430.436623)
			(xy 108.571034 -430.273538) (xy 108.625758 -430.11284) (xy 108.687955 -429.954885) (xy 108.757487 -429.800018)
			(xy 108.834202 -429.648581) (xy 108.91793 -429.500905) (xy 109.008488 -429.357317) (xy 109.105677 -429.218131)
			(xy 109.209284 -429.083654) (xy 109.319079 -428.954181) (xy 109.434823 -428.829996) (xy 109.55626 -428.711373)
			(xy 109.683124 -428.598572) (xy 109.815135 -428.491842) (xy 109.952005 -428.391417) (xy 110.09343 -428.297518)
			(xy 110.239102 -428.21035) (xy 110.3887 -428.130107) (xy 110.541894 -428.056963) (xy 110.698348 -427.991081)
			(xy 110.857718 -427.932604) (xy 111.019654 -427.881662) (xy 111.1838 -427.838366) (xy 111.349795 -427.802811)
			(xy 111.517274 -427.775076) (xy 111.685869 -427.755222) (xy 111.855209 -427.743292) (xy 112.024922 -427.739313)
			(xy 112.194635 -427.743292) (xy 112.363975 -427.755222) (xy 112.53257 -427.775076) (xy 112.700049 -427.802811)
			(xy 112.866044 -427.838366) (xy 113.03019 -427.881662) (xy 113.192126 -427.932604) (xy 113.351496 -427.991081)
			(xy 113.50795 -428.056963) (xy 113.661144 -428.130107) (xy 113.810742 -428.21035) (xy 113.943382 -428.28972)
			(xy 127.21844 -428.28972) (xy 127.218962 -428.25714) (xy 127.226934 -428.192469) (xy 127.242748 -428.129258)
			(xy 127.266169 -428.068452) (xy 127.296844 -428.010964) (xy 127.334314 -427.957655) (xy 127.378018 -427.909325)
			(xy 127.402336 -427.887638) (xy 127.482854 -427.7233) (xy 127.487541 -427.712778) (xy 127.491033 -427.690023)
			(xy 127.487555 -427.667267) (xy 127.482854 -427.656752) (xy 127.401828 -427.491652) (xy 127.377568 -427.469952)
			(xy 127.33397 -427.421621) (xy 127.296594 -427.368331) (xy 127.266 -427.310879) (xy 127.242644 -427.250124)
			(xy 127.226876 -427.186972) (xy 127.218931 -427.122369) (xy 127.21844 -427.089824) (xy 127.219145 -427.050698)
			(xy 127.230616 -426.973291) (xy 127.2413 -426.935646) (xy 127.2413 -426.41901) (xy 127.24182 -426.4069)
			(xy 127.2493 -426.383863) (xy 127.263531 -426.364265) (xy 127.28312 -426.350022) (xy 127.306152 -426.342527)
			(xy 127.318262 -426.342048) (xy 128.258062 -426.342048) (xy 128.270184 -426.342492) (xy 128.293243 -426.349975)
			(xy 128.31286 -426.36422) (xy 128.327112 -426.383832) (xy 128.334603 -426.406888) (xy 128.335024 -426.41901)
			(xy 128.335024 -427.289976) (xy 129.218436 -427.289976) (xy 129.21892 -427.25742) (xy 129.226868 -427.192794)
			(xy 129.242656 -427.129624) (xy 129.266045 -427.068857) (xy 129.296685 -427.011404) (xy 129.334118 -426.958126)
			(xy 129.377781 -426.909823) (xy 129.402078 -426.888148) (xy 129.48285 -426.723302) (xy 129.487536 -426.71278)
			(xy 129.491028 -426.690025) (xy 129.487551 -426.667269) (xy 129.48285 -426.656754) (xy 129.401824 -426.491654)
			(xy 129.377564 -426.469954) (xy 129.333966 -426.421623) (xy 129.29659 -426.368333) (xy 129.265996 -426.310881)
			(xy 129.242641 -426.250126) (xy 129.226873 -426.186974) (xy 129.218928 -426.122371) (xy 129.218436 -426.089826)
			(xy 129.219142 -426.0507) (xy 129.230612 -425.973294) (xy 129.241296 -425.935648) (xy 129.241296 -425.419012)
			(xy 129.241727 -425.406904) (xy 129.249222 -425.383878) (xy 129.26348 -425.364305) (xy 129.283099 -425.35011)
			(xy 129.306149 -425.342688) (xy 129.318258 -425.342304) (xy 130.258058 -425.342304) (xy 130.270142 -425.342842)
			(xy 130.293135 -425.350283) (xy 130.312713 -425.364453) (xy 130.326966 -425.383969) (xy 130.334505 -425.40693)
			(xy 130.33502 -425.419012) (xy 130.33502 -427.960536) (xy 130.334615 -427.972645) (xy 130.327108 -427.99567)
			(xy 130.312843 -428.01524) (xy 130.29322 -428.029435) (xy 130.270168 -428.036858) (xy 130.258058 -428.037244)
			(xy 129.318258 -428.037244) (xy 129.306165 -428.036828) (xy 129.28316 -428.029358) (xy 129.263579 -428.015159)
			(xy 129.249331 -427.995614) (xy 129.241803 -427.972628) (xy 129.241296 -427.960536) (xy 129.241296 -427.444154)
			(xy 129.230603 -427.40651) (xy 129.21913 -427.329103) (xy 129.218436 -427.289976) (xy 128.335024 -427.289976)
			(xy 128.335024 -428.28972) (xy 131.218432 -428.28972) (xy 131.218956 -428.25714) (xy 131.226928 -428.19247)
			(xy 131.242743 -428.129258) (xy 131.266163 -428.068453) (xy 131.296838 -428.010965) (xy 131.334307 -427.957656)
			(xy 131.37801 -427.909325) (xy 131.402328 -427.887638) (xy 131.482846 -427.7233) (xy 131.487533 -427.712778)
			(xy 131.491026 -427.690023) (xy 131.487547 -427.667267) (xy 131.482846 -427.656752) (xy 131.40182 -427.491652)
			(xy 131.377558 -427.469954) (xy 131.33396 -427.421622) (xy 131.296585 -427.368332) (xy 131.265991 -427.31088)
			(xy 131.242636 -427.250124) (xy 131.226868 -427.186973) (xy 131.218923 -427.122369) (xy 131.218432 -427.089824)
			(xy 131.219137 -427.050698) (xy 131.230608 -426.973291) (xy 131.241292 -426.935646) (xy 131.241292 -426.41901)
			(xy 131.24182 -426.406901) (xy 131.249299 -426.383865) (xy 131.263528 -426.364268) (xy 131.283115 -426.350024)
			(xy 131.306145 -426.342528) (xy 131.318254 -426.342048) (xy 132.258054 -426.342048) (xy 132.270175 -426.342499)
			(xy 132.293234 -426.34998) (xy 132.312851 -426.364223) (xy 132.327104 -426.383833) (xy 132.334595 -426.406889)
			(xy 132.335016 -426.41901) (xy 132.335016 -427.289976) (xy 133.218428 -427.289976) (xy 133.218915 -427.25742)
			(xy 133.226863 -427.192794) (xy 133.24265 -427.129624) (xy 133.266039 -427.068857) (xy 133.296679 -427.011404)
			(xy 133.334111 -426.958127) (xy 133.377773 -426.909823) (xy 133.40207 -426.888148) (xy 133.482842 -426.723302)
			(xy 133.487528 -426.71278) (xy 133.491021 -426.690025) (xy 133.487543 -426.667269) (xy 133.482842 -426.656754)
			(xy 133.401816 -426.491654) (xy 133.377555 -426.469956) (xy 133.333957 -426.421624) (xy 133.296582 -426.368334)
			(xy 133.265988 -426.310882) (xy 133.242632 -426.250126) (xy 133.226865 -426.186975) (xy 133.21892 -426.122371)
			(xy 133.218428 -426.089826) (xy 133.219134 -426.0507) (xy 133.230605 -425.973294) (xy 133.241288 -425.935648)
			(xy 133.241288 -425.419012) (xy 133.241727 -425.406905) (xy 133.249221 -425.38388) (xy 133.263477 -425.364308)
			(xy 133.283094 -425.350113) (xy 133.306142 -425.342689) (xy 133.31825 -425.342304) (xy 134.25805 -425.342304)
			(xy 134.270133 -425.342849) (xy 134.293126 -425.350288) (xy 134.312704 -425.364455) (xy 134.326958 -425.383971)
			(xy 134.334497 -425.406931) (xy 134.335012 -425.419012) (xy 134.335012 -427.960536) (xy 134.334614 -427.972646)
			(xy 134.327107 -427.995672) (xy 134.31284 -428.015243) (xy 134.293215 -428.029437) (xy 134.270161 -428.036859)
			(xy 134.25805 -428.037244) (xy 133.31825 -428.037244) (xy 133.306161 -428.03675) (xy 133.28316 -428.029305)
			(xy 133.263578 -428.015126) (xy 133.249326 -427.995597) (xy 133.241795 -427.972623) (xy 133.241288 -427.960536)
			(xy 133.241288 -427.444154) (xy 133.230595 -427.406511) (xy 133.219122 -427.329103) (xy 133.218428 -427.289976)
			(xy 132.335016 -427.289976) (xy 132.335016 -428.28972) (xy 135.218424 -428.28972) (xy 135.218951 -428.25714)
			(xy 135.226923 -428.19247) (xy 135.242737 -428.129259) (xy 135.266157 -428.068453) (xy 135.296831 -428.010965)
			(xy 135.3343 -427.957656) (xy 135.378002 -427.909325) (xy 135.40232 -427.887638) (xy 135.482838 -427.7233)
			(xy 135.487526 -427.712778) (xy 135.491018 -427.690023) (xy 135.48754 -427.667267) (xy 135.482838 -427.656752)
			(xy 135.401812 -427.491652) (xy 135.377549 -427.469956) (xy 135.333951 -427.421624) (xy 135.296576 -427.368333)
			(xy 135.265983 -427.310881) (xy 135.242628 -427.250125) (xy 135.22686 -427.186973) (xy 135.218915 -427.122369)
			(xy 135.218424 -427.089824) (xy 135.21913 -427.050698) (xy 135.230601 -426.973292) (xy 135.241284 -426.935646)
			(xy 135.241284 -426.41901) (xy 135.241669 -426.406883) (xy 135.249164 -426.383817) (xy 135.263423 -426.364198)
			(xy 135.283049 -426.349948) (xy 135.306119 -426.342464) (xy 135.318246 -426.342048) (xy 136.258046 -426.342048)
			(xy 136.270164 -426.342473) (xy 136.29321 -426.349974) (xy 136.312812 -426.364228) (xy 136.327052 -426.38384)
			(xy 136.334536 -426.406892) (xy 136.335008 -426.41901) (xy 136.335008 -427.289976) (xy 137.21842 -427.289976)
			(xy 137.218909 -427.25742) (xy 137.226858 -427.192794) (xy 137.242644 -427.129625) (xy 137.266033 -427.068858)
			(xy 137.296672 -427.011405) (xy 137.334103 -426.958127) (xy 137.377765 -426.909823) (xy 137.402062 -426.888148)
			(xy 137.482834 -426.723302) (xy 137.48752 -426.71278) (xy 137.491014 -426.690025) (xy 137.487536 -426.667268)
			(xy 137.482834 -426.656754) (xy 137.401808 -426.491654) (xy 137.377545 -426.469958) (xy 137.333947 -426.421625)
			(xy 137.296573 -426.368335) (xy 137.265979 -426.310882) (xy 137.242624 -426.250126) (xy 137.226856 -426.186975)
			(xy 137.218912 -426.122371) (xy 137.21842 -426.089826) (xy 137.219126 -426.0507) (xy 137.230597 -425.973294)
			(xy 137.24128 -425.935648) (xy 137.24128 -425.419012) (xy 137.241727 -425.406906) (xy 137.24922 -425.383882)
			(xy 137.263475 -425.364311) (xy 137.283089 -425.350115) (xy 137.306135 -425.342691) (xy 137.318242 -425.342304)
			(xy 138.258042 -425.342304) (xy 138.27013 -425.342771) (xy 138.293126 -425.350235) (xy 138.312702 -425.364423)
			(xy 138.326953 -425.383953) (xy 138.33449 -425.406925) (xy 138.335004 -425.419012) (xy 138.335004 -427.960536)
			(xy 138.334614 -427.972646) (xy 138.327106 -427.995674) (xy 138.312837 -428.015246) (xy 138.29321 -428.02944)
			(xy 138.270154 -428.03686) (xy 138.258042 -428.037244) (xy 137.318242 -428.037244) (xy 137.306153 -428.036757)
			(xy 137.283151 -428.029309) (xy 137.263569 -428.015129) (xy 137.249318 -427.995598) (xy 137.241787 -427.972623)
			(xy 137.24128 -427.960536) (xy 137.24128 -427.444154) (xy 137.230587 -427.406511) (xy 137.219114 -427.329103)
			(xy 137.21842 -427.289976) (xy 136.335008 -427.289976) (xy 136.335008 -428.28972) (xy 139.218416 -428.28972)
			(xy 139.218946 -428.25714) (xy 139.226917 -428.19247) (xy 139.242731 -428.129259) (xy 139.266151 -428.068454)
			(xy 139.296825 -428.010966) (xy 139.334293 -427.957657) (xy 139.377995 -427.909325) (xy 139.402312 -427.887638)
			(xy 139.48283 -427.7233) (xy 139.487518 -427.712778) (xy 139.491011 -427.690023) (xy 139.487532 -427.667266)
			(xy 139.48283 -427.656752) (xy 139.401804 -427.491652) (xy 139.377539 -427.469958) (xy 139.333942 -427.421625)
			(xy 139.296568 -427.368334) (xy 139.265974 -427.310881) (xy 139.24262 -427.250125) (xy 139.226852 -427.186973)
			(xy 139.218907 -427.122369) (xy 139.218416 -427.089824) (xy 139.219118 -427.050698) (xy 139.230591 -426.973291)
			(xy 139.241276 -426.935646) (xy 139.241276 -426.41901) (xy 139.241669 -426.406884) (xy 139.249163 -426.383819)
			(xy 139.26342 -426.364201) (xy 139.283044 -426.34995) (xy 139.306112 -426.342465) (xy 139.318238 -426.342048)
			(xy 140.258038 -426.342048) (xy 140.270156 -426.342479) (xy 140.293202 -426.349978) (xy 140.312804 -426.36423)
			(xy 140.327044 -426.383841) (xy 140.334528 -426.406892) (xy 140.335 -426.41901) (xy 140.335 -427.289976)
			(xy 142.21841 -427.289976) (xy 142.218903 -427.25742) (xy 142.226851 -427.192795) (xy 142.242637 -427.129625)
			(xy 142.266025 -427.068859) (xy 142.296664 -427.011406) (xy 142.334095 -426.958128) (xy 142.377756 -426.909824)
			(xy 142.402052 -426.888148) (xy 142.482824 -426.723302) (xy 142.487511 -426.71278) (xy 142.491005 -426.690025)
			(xy 142.487526 -426.667268) (xy 142.482824 -426.656754) (xy 142.401798 -426.491654) (xy 142.377533 -426.46996)
			(xy 142.333936 -426.421627) (xy 142.296562 -426.368336) (xy 142.265969 -426.310883) (xy 142.242614 -426.250127)
			(xy 142.226846 -426.186975) (xy 142.218902 -426.122371) (xy 142.21841 -426.089826) (xy 142.219128 -426.050501)
			(xy 142.230739 -425.972711) (xy 142.241524 -425.934886) (xy 142.241524 -425.419012) (xy 142.241924 -425.406927)
			(xy 142.249392 -425.383939) (xy 142.2636 -425.364386) (xy 142.283157 -425.350183) (xy 142.306147 -425.34272)
			(xy 142.318232 -425.342304) (xy 143.258032 -425.342304) (xy 143.270109 -425.342737) (xy 143.29308 -425.35021)
			(xy 143.312617 -425.364414) (xy 143.32681 -425.38396) (xy 143.33427 -425.406934) (xy 143.33474 -425.419012)
			(xy 143.33474 -427.960536) (xy 143.334267 -427.972609) (xy 143.326799 -427.995572) (xy 143.312603 -428.015106)
			(xy 143.293069 -428.0293) (xy 143.270105 -428.036768) (xy 143.258032 -428.037244) (xy 142.318232 -428.037244)
			(xy 142.306163 -428.036709) (xy 142.283203 -428.02926) (xy 142.263668 -428.01508) (xy 142.249471 -427.995558)
			(xy 142.242001 -427.972605) (xy 142.241524 -427.960536) (xy 142.241524 -427.444916) (xy 142.23072 -427.407096)
			(xy 142.219117 -427.329303) (xy 142.21841 -427.289976) (xy 140.335 -427.289976) (xy 140.335 -428.28972)
			(xy 144.218406 -428.28972) (xy 144.218939 -428.257141) (xy 144.226911 -428.192471) (xy 144.242724 -428.12926)
			(xy 144.266143 -428.068455) (xy 144.296817 -428.010967) (xy 144.334284 -427.957657) (xy 144.377985 -427.909326)
			(xy 144.402302 -427.887638) (xy 144.48282 -427.7233) (xy 144.487509 -427.712779) (xy 144.491002 -427.690023)
			(xy 144.487523 -427.667266) (xy 144.48282 -427.656752) (xy 144.401794 -427.491652) (xy 144.377527 -427.46996)
			(xy 144.33393 -427.421626) (xy 144.296556 -427.368335) (xy 144.265964 -427.310882) (xy 144.242609 -427.250125)
			(xy 144.226842 -427.186973) (xy 144.218897 -427.122369) (xy 144.218406 -427.089824) (xy 144.219124 -427.050499)
			(xy 144.230735 -426.972709) (xy 144.24152 -426.934884) (xy 144.24152 -426.41901) (xy 144.242016 -426.406923)
			(xy 144.249467 -426.383926) (xy 144.263647 -426.364348) (xy 144.283173 -426.350096) (xy 144.306143 -426.34256)
			(xy 144.318228 -426.342048) (xy 145.258028 -426.342048) (xy 145.270133 -426.342492) (xy 145.293152 -426.349993)
			(xy 145.312721 -426.364249) (xy 145.326916 -426.383861) (xy 145.334345 -426.406904) (xy 145.334736 -426.41901)
			(xy 145.334736 -427.289976) (xy 146.218402 -427.289976) (xy 146.218898 -427.25742) (xy 146.226845 -427.192795)
			(xy 146.242632 -427.129626) (xy 146.266019 -427.068859) (xy 146.296658 -427.011406) (xy 146.334088 -426.958128)
			(xy 146.377748 -426.909824) (xy 146.402044 -426.888148) (xy 146.482816 -426.723302) (xy 146.487503 -426.71278)
			(xy 146.490997 -426.690025) (xy 146.487518 -426.667268) (xy 146.482816 -426.656754) (xy 146.40179 -426.491654)
			(xy 146.377523 -426.469962) (xy 146.333927 -426.421628) (xy 146.296553 -426.368337) (xy 146.26596 -426.310884)
			(xy 146.242606 -426.250127) (xy 146.226838 -426.186975) (xy 146.218894 -426.122371) (xy 146.218402 -426.089826)
			(xy 146.219121 -426.050501) (xy 146.230731 -425.972711) (xy 146.241516 -425.934886) (xy 146.241516 -425.419012)
			(xy 146.241923 -425.406928) (xy 146.249391 -425.383941) (xy 146.263597 -425.364389) (xy 146.283152 -425.350185)
			(xy 146.306139 -425.342722) (xy 146.318224 -425.342304) (xy 147.258024 -425.342304) (xy 147.270101 -425.342744)
			(xy 147.293071 -425.350215) (xy 147.312609 -425.364417) (xy 147.326802 -425.383961) (xy 147.334261 -425.406935)
			(xy 147.334732 -425.419012) (xy 147.334732 -427.960536) (xy 147.334267 -427.97261) (xy 147.326798 -427.995574)
			(xy 147.3126 -428.015109) (xy 147.293064 -428.029303) (xy 147.270098 -428.036769) (xy 147.258024 -428.037244)
			(xy 146.318224 -428.037244) (xy 146.306154 -428.036716) (xy 146.283194 -428.029264) (xy 146.26366 -428.015083)
			(xy 146.249463 -427.99556) (xy 146.241993 -427.972605) (xy 146.241516 -427.960536) (xy 146.241516 -427.444916)
			(xy 146.230712 -427.407096) (xy 146.219109 -427.329303) (xy 146.218402 -427.289976) (xy 145.334736 -427.289976)
			(xy 145.334736 -428.28972) (xy 148.218398 -428.28972) (xy 148.218934 -428.257141) (xy 148.226905 -428.192471)
			(xy 148.242719 -428.12926) (xy 148.266137 -428.068455) (xy 148.29681 -428.010967) (xy 148.334277 -427.957658)
			(xy 148.377977 -427.909326) (xy 148.402294 -427.887638) (xy 148.482812 -427.7233) (xy 148.487501 -427.712779)
			(xy 148.490995 -427.690023) (xy 148.487515 -427.667266) (xy 148.482812 -427.656752) (xy 148.401786 -427.491652)
			(xy 148.377517 -427.469962) (xy 148.333921 -427.421628) (xy 148.296548 -427.368336) (xy 148.265955 -427.310882)
			(xy 148.242601 -427.250126) (xy 148.226834 -427.186973) (xy 148.218889 -427.122369) (xy 148.218398 -427.089824)
			(xy 148.219117 -427.050499) (xy 148.230727 -426.972709) (xy 148.241512 -426.934884) (xy 148.241512 -426.41901)
			(xy 148.242015 -426.406924) (xy 148.249466 -426.383928) (xy 148.263644 -426.364351) (xy 148.283168 -426.350099)
			(xy 148.306136 -426.342562) (xy 148.31822 -426.342048) (xy 149.25802 -426.342048) (xy 149.270125 -426.342499)
			(xy 149.293144 -426.349997) (xy 149.312712 -426.364252) (xy 149.326908 -426.383863) (xy 149.334337 -426.406904)
			(xy 149.334728 -426.41901) (xy 149.334728 -427.289976) (xy 150.218394 -427.289976) (xy 150.218858 -427.257419)
			(xy 150.226808 -427.192791) (xy 150.242597 -427.12962) (xy 150.265989 -427.068853) (xy 150.296633 -427.0114)
			(xy 150.334069 -426.958123) (xy 150.377737 -426.909822) (xy 150.402036 -426.888148) (xy 150.482808 -426.723302)
			(xy 150.487495 -426.71278) (xy 150.49099 -426.690025) (xy 150.487511 -426.667268) (xy 150.482808 -426.656754)
			(xy 150.401782 -426.491654) (xy 150.377514 -426.469963) (xy 150.333917 -426.42163) (xy 150.296544 -426.368338)
			(xy 150.265952 -426.310884) (xy 150.242597 -426.250128) (xy 150.22683 -426.186975) (xy 150.218886 -426.122371)
			(xy 150.218394 -426.089826) (xy 150.219113 -426.050501) (xy 150.230724 -425.972711) (xy 150.241508 -425.934886)
			(xy 150.241508 -425.419012) (xy 150.241923 -425.406928) (xy 150.249389 -425.383943) (xy 150.263594 -425.364392)
			(xy 150.283147 -425.350188) (xy 150.306132 -425.342723) (xy 150.318216 -425.342304) (xy 151.258016 -425.342304)
			(xy 151.270093 -425.342751) (xy 151.293062 -425.350219) (xy 151.3126 -425.36442) (xy 151.326794 -425.383963)
			(xy 151.334253 -425.406935) (xy 151.334724 -425.419012) (xy 151.334724 -427.960536) (xy 151.334267 -427.972611)
			(xy 151.326796 -427.995577) (xy 151.312597 -428.015112) (xy 151.293059 -428.029306) (xy 151.270091 -428.03677)
			(xy 151.258016 -428.037244) (xy 150.318216 -428.037244) (xy 150.306146 -428.036723) (xy 150.283185 -428.029269)
			(xy 150.263651 -428.015086) (xy 150.249455 -427.995561) (xy 150.241985 -427.972606) (xy 150.241508 -427.960536)
			(xy 150.241508 -427.444916) (xy 150.230704 -427.407096) (xy 150.219101 -427.329303) (xy 150.218394 -427.289976)
			(xy 149.334728 -427.289976) (xy 149.334728 -428.28972) (xy 152.21839 -428.28972) (xy 152.218928 -428.257141)
			(xy 152.226899 -428.192471) (xy 152.242713 -428.129261) (xy 152.266131 -428.068456) (xy 152.296803 -428.010968)
			(xy 152.33427 -427.957658) (xy 152.377969 -427.909326) (xy 152.402286 -427.887638) (xy 152.482804 -427.7233)
			(xy 152.487493 -427.712779) (xy 152.490987 -427.690023) (xy 152.487507 -427.667266) (xy 152.482804 -427.656752)
			(xy 152.401778 -427.491652) (xy 152.377508 -427.469963) (xy 152.333912 -427.421629) (xy 152.296539 -427.368337)
			(xy 152.265947 -427.310883) (xy 152.242593 -427.250126) (xy 152.226826 -427.186974) (xy 152.218881 -427.122369)
			(xy 152.21839 -427.089824) (xy 152.219109 -427.050499) (xy 152.230719 -426.972709) (xy 152.241504 -426.934884)
			(xy 152.241504 -426.41901) (xy 152.242015 -426.406925) (xy 152.249465 -426.38393) (xy 152.263641 -426.364353)
			(xy 152.283163 -426.350101) (xy 152.306128 -426.342563) (xy 152.318212 -426.342048) (xy 153.258012 -426.342048)
			(xy 153.270116 -426.342505) (xy 153.293135 -426.350002) (xy 153.312704 -426.364255) (xy 153.3269 -426.383864)
			(xy 153.334329 -426.406905) (xy 153.33472 -426.41901) (xy 153.33472 -427.289976) (xy 154.218386 -427.289976)
			(xy 154.218853 -427.257419) (xy 154.226802 -427.192792) (xy 154.242591 -427.129621) (xy 154.265983 -427.068853)
			(xy 154.296626 -427.0114) (xy 154.334062 -426.958124) (xy 154.377729 -426.909822) (xy 154.402028 -426.888148)
			(xy 154.4828 -426.723302) (xy 154.487488 -426.71278) (xy 154.490983 -426.690025) (xy 154.487503 -426.667268)
			(xy 154.4828 -426.656754) (xy 154.401774 -426.491654) (xy 154.377504 -426.469965) (xy 154.333908 -426.421631)
			(xy 154.296535 -426.368339) (xy 154.265943 -426.310885) (xy 154.242589 -426.250128) (xy 154.226822 -426.186976)
			(xy 154.218878 -426.122371) (xy 154.218386 -426.089826) (xy 154.219105 -426.050501) (xy 154.230716 -425.972711)
			(xy 154.2415 -425.934886) (xy 154.2415 -425.419012) (xy 154.241923 -425.406929) (xy 154.249388 -425.383946)
			(xy 154.263592 -425.364394) (xy 154.283142 -425.35019) (xy 154.306125 -425.342724) (xy 154.318208 -425.342304)
			(xy 155.258008 -425.342304) (xy 155.270092 -425.342706) (xy 155.293077 -425.350177) (xy 155.312629 -425.364386)
			(xy 155.326832 -425.383941) (xy 155.334297 -425.406928) (xy 155.334716 -425.419012) (xy 155.334716 -427.960536)
			(xy 155.334267 -427.972612) (xy 155.326795 -427.995579) (xy 155.312595 -428.015115) (xy 155.293054 -428.029308)
			(xy 155.270084 -428.036771) (xy 155.258008 -428.037244) (xy 154.318208 -428.037244) (xy 154.306137 -428.03673)
			(xy 154.283177 -428.029274) (xy 154.263643 -428.015089) (xy 154.249447 -427.995563) (xy 154.241977 -427.972606)
			(xy 154.2415 -427.960536) (xy 154.2415 -427.444916) (xy 154.230696 -427.407096) (xy 154.219092 -427.329303)
			(xy 154.218386 -427.289976) (xy 153.33472 -427.289976) (xy 153.33472 -428.28972) (xy 156.218382 -428.28972)
			(xy 156.218923 -428.257141) (xy 156.226894 -428.192472) (xy 156.242707 -428.129261) (xy 156.266125 -428.068456)
			(xy 156.296797 -428.010968) (xy 156.334263 -427.957658) (xy 156.377962 -427.909326) (xy 156.402278 -427.887638)
			(xy 156.482796 -427.7233) (xy 156.487485 -427.712779) (xy 156.49098 -427.690023) (xy 156.487499 -427.667266)
			(xy 156.482796 -427.656752) (xy 156.40177 -427.491652) (xy 156.377518 -427.469943) (xy 156.333918 -427.421614)
			(xy 156.296541 -427.368327) (xy 156.265945 -427.310876) (xy 156.242588 -427.250122) (xy 156.226819 -427.186972)
			(xy 156.218874 -427.122369) (xy 156.218382 -427.089824) (xy 156.219101 -427.050499) (xy 156.230712 -426.972709)
			(xy 156.241496 -426.934884) (xy 156.241496 -426.41901) (xy 156.242015 -426.406925) (xy 156.249464 -426.383932)
			(xy 156.263639 -426.364356) (xy 156.283158 -426.350104) (xy 156.306121 -426.342564) (xy 156.318204 -426.342048)
			(xy 157.258004 -426.342048) (xy 157.270108 -426.342512) (xy 157.293127 -426.350006) (xy 157.312695 -426.364257)
			(xy 157.326891 -426.383866) (xy 157.334321 -426.406905) (xy 157.334712 -426.41901) (xy 157.334712 -428.960534)
			(xy 157.334321 -428.97263) (xy 157.326849 -428.99564) (xy 157.312644 -429.015223) (xy 157.293092 -429.029471)
			(xy 157.270099 -429.036994) (xy 157.258004 -429.037496) (xy 156.318204 -429.037496) (xy 156.306095 -429.03708)
			(xy 156.283067 -429.029582) (xy 156.263493 -429.01532) (xy 156.249299 -428.995698) (xy 156.241879 -428.972644)
			(xy 156.241496 -428.960534) (xy 156.241496 -428.44466) (xy 156.230701 -428.406837) (xy 156.219092 -428.329046)
			(xy 156.218382 -428.28972) (xy 153.33472 -428.28972) (xy 153.33472 -428.960534) (xy 153.334321 -428.972629)
			(xy 153.32685 -428.995638) (xy 153.312647 -429.015221) (xy 153.293097 -429.029469) (xy 153.270106 -429.036993)
			(xy 153.258012 -429.037496) (xy 152.318212 -429.037496) (xy 152.306103 -429.037073) (xy 152.283076 -429.029577)
			(xy 152.263502 -429.015317) (xy 152.249307 -428.995696) (xy 152.241887 -428.972644) (xy 152.241504 -428.960534)
			(xy 152.241504 -428.44466) (xy 152.230709 -428.406837) (xy 152.2191 -428.329046) (xy 152.21839 -428.28972)
			(xy 149.334728 -428.28972) (xy 149.334728 -428.960534) (xy 149.334321 -428.972629) (xy 149.326851 -428.995636)
			(xy 149.31265 -429.015218) (xy 149.293102 -429.029466) (xy 149.270113 -429.036992) (xy 149.25802 -429.037496)
			(xy 148.31822 -429.037496) (xy 148.306112 -429.037066) (xy 148.283085 -429.029572) (xy 148.263511 -429.015314)
			(xy 148.249316 -428.995695) (xy 148.241895 -428.972643) (xy 148.241512 -428.960534) (xy 148.241512 -428.44466)
			(xy 148.230718 -428.406837) (xy 148.219108 -428.329046) (xy 148.218398 -428.28972) (xy 145.334736 -428.28972)
			(xy 145.334736 -428.960534) (xy 145.334321 -428.972628) (xy 145.326852 -428.995634) (xy 145.312653 -429.015215)
			(xy 145.293107 -429.029464) (xy 145.27012 -429.03699) (xy 145.258028 -429.037496) (xy 144.318228 -429.037496)
			(xy 144.30612 -429.03706) (xy 144.283093 -429.029567) (xy 144.263519 -429.015311) (xy 144.249324 -428.995693)
			(xy 144.241903 -428.972643) (xy 144.24152 -428.960534) (xy 144.24152 -428.44466) (xy 144.230726 -428.406837)
			(xy 144.219116 -428.329046) (xy 144.218406 -428.28972) (xy 140.335 -428.28972) (xy 140.335 -428.960534)
			(xy 140.334518 -428.972647) (xy 140.327026 -428.995684) (xy 140.312785 -429.015282) (xy 140.293188 -429.029524)
			(xy 140.270151 -429.037017) (xy 140.258038 -429.037496) (xy 139.318238 -429.037496) (xy 139.306121 -429.037008)
			(xy 139.283069 -429.029531) (xy 139.263456 -429.015295) (xy 139.249202 -428.995696) (xy 139.241703 -428.972651)
			(xy 139.241276 -428.960534) (xy 139.241276 -428.443898) (xy 139.230592 -428.406252) (xy 139.219113 -428.328846)
			(xy 139.218416 -428.28972) (xy 136.335008 -428.28972) (xy 136.335008 -428.960534) (xy 136.334518 -428.972646)
			(xy 136.327027 -428.995682) (xy 136.312788 -429.01528) (xy 136.293193 -429.029522) (xy 136.270158 -429.037016)
			(xy 136.258046 -429.037496) (xy 135.318246 -429.037496) (xy 135.306129 -429.037002) (xy 135.283077 -429.029526)
			(xy 135.263464 -429.015292) (xy 135.249211 -428.995694) (xy 135.241711 -428.972651) (xy 135.241284 -428.960534)
			(xy 135.241284 -428.443898) (xy 135.2306 -428.406252) (xy 135.219121 -428.328846) (xy 135.218424 -428.28972)
			(xy 132.335016 -428.28972) (xy 132.335016 -428.960534) (xy 132.334668 -428.972663) (xy 132.327161 -428.995731)
			(xy 132.312892 -429.015349) (xy 132.293259 -429.029598) (xy 132.270184 -429.037081) (xy 132.258054 -429.037496)
			(xy 131.318254 -429.037496) (xy 131.30614 -429.037028) (xy 131.283101 -429.029532) (xy 131.263503 -429.015288)
			(xy 131.249262 -428.995688) (xy 131.24177 -428.972648) (xy 131.241292 -428.960534) (xy 131.241292 -428.443898)
			(xy 131.230608 -428.406252) (xy 131.219129 -428.328846) (xy 131.218432 -428.28972) (xy 128.335024 -428.28972)
			(xy 128.335024 -428.960534) (xy 128.334669 -428.972662) (xy 128.327162 -428.995729) (xy 128.312895 -429.015347)
			(xy 128.293264 -429.029595) (xy 128.270191 -429.03708) (xy 128.258062 -429.037496) (xy 127.318262 -429.037496)
			(xy 127.306149 -429.037021) (xy 127.28311 -429.029528) (xy 127.263512 -429.015285) (xy 127.24927 -428.995686)
			(xy 127.241778 -428.972647) (xy 127.2413 -428.960534) (xy 127.2413 -428.443898) (xy 127.230617 -428.406252)
			(xy 127.219137 -428.328846) (xy 127.21844 -428.28972) (xy 113.943382 -428.28972) (xy 113.956414 -428.297518)
			(xy 114.097839 -428.391417) (xy 114.234709 -428.491842) (xy 114.36672 -428.598572) (xy 114.493584 -428.711373)
			(xy 114.615021 -428.829996) (xy 114.730765 -428.954181) (xy 114.84056 -429.083654) (xy 114.944167 -429.218131)
			(xy 115.041356 -429.357317) (xy 115.131914 -429.500905) (xy 115.215642 -429.648581) (xy 115.292357 -429.800018)
			(xy 115.361889 -429.954885) (xy 115.424086 -430.11284) (xy 115.47881 -430.273538) (xy 115.525942 -430.436623)
			(xy 115.565378 -430.601739) (xy 115.597032 -430.768522) (xy 115.614222 -430.889918) (xy 125.238002 -430.889918)
			(xy 125.238096 -430.875344) (xy 125.239748 -430.846243) (xy 125.241304 -430.831752) (xy 125.241304 -429.747934)
			(xy 125.239756 -429.733442) (xy 125.238106 -429.704342) (xy 125.238002 -429.689768) (xy 125.2381 -429.675194)
			(xy 125.23975 -429.646093) (xy 125.241304 -429.631602) (xy 125.241304 -429.018954) (xy 125.241772 -429.00684)
			(xy 125.249268 -428.983801) (xy 125.263512 -428.964203) (xy 125.283112 -428.949962) (xy 125.306152 -428.94247)
			(xy 125.318266 -428.941992) (xy 126.258066 -428.941992) (xy 126.270174 -428.94254) (xy 126.293209 -428.950012)
			(xy 126.312807 -428.964236) (xy 126.327051 -428.98382) (xy 126.334547 -429.006846) (xy 126.335028 -429.018954)
			(xy 126.335028 -431.560478) (xy 126.334621 -431.572603) (xy 126.32713 -431.595667) (xy 126.312877 -431.615285)
			(xy 126.293256 -431.629536) (xy 126.270191 -431.637023) (xy 126.258066 -431.63744) (xy 125.318266 -431.63744)
			(xy 125.306147 -431.637017) (xy 125.283099 -431.629518) (xy 125.263496 -431.615264) (xy 125.249257 -431.59565)
			(xy 125.241774 -431.572597) (xy 125.241304 -431.560478) (xy 125.241304 -430.948084) (xy 125.23976 -430.933592)
			(xy 125.238108 -430.904492) (xy 125.238002 -430.889918) (xy 115.614222 -430.889918) (xy 115.620833 -430.936605)
			(xy 115.636729 -431.105619) (xy 115.644686 -431.275192) (xy 115.645184 -431.360072) (xy 115.644698 -431.445674)
			(xy 115.63661 -431.616688) (xy 115.620446 -431.787128) (xy 115.605768 -431.889916) (xy 127.237998 -431.889916)
			(xy 127.238092 -431.875342) (xy 127.239744 -431.846241) (xy 127.2413 -431.83175) (xy 127.2413 -430.747932)
			(xy 127.239752 -430.73344) (xy 127.238102 -430.70434) (xy 127.237998 -430.689766) (xy 127.238096 -430.675192)
			(xy 127.239746 -430.646091) (xy 127.2413 -430.6316) (xy 127.2413 -430.018952) (xy 127.241676 -430.006841)
			(xy 127.249188 -429.983812) (xy 127.26346 -429.96424) (xy 127.28309 -429.950047) (xy 127.306149 -429.942627)
			(xy 127.318262 -429.942244) (xy 128.258062 -429.942244) (xy 128.27015 -429.94274) (xy 128.29315 -429.950187)
			(xy 128.312731 -429.964366) (xy 128.326983 -429.983894) (xy 128.334515 -430.006866) (xy 128.335024 -430.018952)
			(xy 128.335024 -430.889918) (xy 129.237994 -430.889918) (xy 129.238088 -430.875344) (xy 129.23974 -430.846243)
			(xy 129.241296 -430.831752) (xy 129.241296 -429.747934) (xy 129.239749 -429.733442) (xy 129.238098 -429.704342)
			(xy 129.237994 -429.689768) (xy 129.238092 -429.675194) (xy 129.239742 -429.646093) (xy 129.241296 -429.631602)
			(xy 129.241296 -429.018954) (xy 129.241772 -429.006841) (xy 129.249267 -428.983804) (xy 129.263509 -428.964206)
			(xy 129.283107 -428.949965) (xy 129.306145 -428.942471) (xy 129.318258 -428.941992) (xy 130.258058 -428.941992)
			(xy 130.270166 -428.942547) (xy 130.2932 -428.950017) (xy 130.312798 -428.964239) (xy 130.327043 -428.983821)
			(xy 130.334539 -429.006847) (xy 130.33502 -429.018954) (xy 130.33502 -431.560478) (xy 130.334621 -431.572604)
			(xy 130.327129 -431.595669) (xy 130.312874 -431.615288) (xy 130.293251 -431.629538) (xy 130.270184 -431.637024)
			(xy 130.258058 -431.63744) (xy 129.318258 -431.63744) (xy 129.306139 -431.637024) (xy 129.283091 -431.629522)
			(xy 129.263488 -431.615267) (xy 129.249248 -431.595652) (xy 129.241766 -431.572597) (xy 129.241296 -431.560478)
			(xy 129.241296 -430.948084) (xy 129.239753 -430.933592) (xy 129.2381 -430.904492) (xy 129.237994 -430.889918)
			(xy 128.335024 -430.889918) (xy 128.335024 -431.889916) (xy 131.23799 -431.889916) (xy 131.238084 -431.875342)
			(xy 131.239736 -431.846241) (xy 131.241292 -431.83175) (xy 131.241292 -430.747932) (xy 131.239744 -430.73344)
			(xy 131.238094 -430.70434) (xy 131.23799 -430.689766) (xy 131.238088 -430.675192) (xy 131.239738 -430.646091)
			(xy 131.241292 -430.6316) (xy 131.241292 -430.018952) (xy 131.241675 -430.006841) (xy 131.249187 -429.983814)
			(xy 131.263458 -429.964242) (xy 131.283085 -429.950049) (xy 131.306142 -429.942628) (xy 131.318254 -429.942244)
			(xy 132.258054 -429.942244) (xy 132.270142 -429.942747) (xy 132.293141 -429.950191) (xy 132.312722 -429.964368)
			(xy 132.326974 -429.983895) (xy 132.334507 -430.006866) (xy 132.335016 -430.018952) (xy 132.335016 -430.889918)
			(xy 133.237986 -430.889918) (xy 133.23808 -430.875344) (xy 133.239732 -430.846243) (xy 133.241288 -430.831752)
			(xy 133.241288 -429.747934) (xy 133.239741 -429.733442) (xy 133.23809 -429.704342) (xy 133.237986 -429.689768)
			(xy 133.238084 -429.675194) (xy 133.239734 -429.646093) (xy 133.241288 -429.631602) (xy 133.241288 -429.018954)
			(xy 133.241772 -429.006842) (xy 133.249266 -428.983806) (xy 133.263506 -428.964209) (xy 133.283102 -428.949967)
			(xy 133.306138 -428.942472) (xy 133.31825 -428.941992) (xy 134.25805 -428.941992) (xy 134.270163 -428.942468)
			(xy 134.2932 -428.949964) (xy 134.312797 -428.964206) (xy 134.327038 -428.983804) (xy 134.334532 -429.006841)
			(xy 134.335012 -429.018954) (xy 134.335012 -431.560478) (xy 134.33447 -431.572586) (xy 134.326995 -431.59562)
			(xy 134.312769 -431.615218) (xy 134.293185 -431.629462) (xy 134.270158 -431.636959) (xy 134.25805 -431.63744)
			(xy 133.31825 -431.63744) (xy 133.306131 -431.63703) (xy 133.283082 -431.629527) (xy 133.263479 -431.615269)
			(xy 133.24924 -431.595653) (xy 133.241758 -431.572598) (xy 133.241288 -431.560478) (xy 133.241288 -430.948084)
			(xy 133.239745 -430.933592) (xy 133.238092 -430.904492) (xy 133.237986 -430.889918) (xy 132.335016 -430.889918)
			(xy 132.335016 -431.889916) (xy 135.237982 -431.889916) (xy 135.238076 -431.875342) (xy 135.239728 -431.846241)
			(xy 135.241284 -431.83175) (xy 135.241284 -430.747932) (xy 135.239736 -430.73344) (xy 135.238086 -430.70434)
			(xy 135.237982 -430.689766) (xy 135.23808 -430.675192) (xy 135.23973 -430.646091) (xy 135.241284 -430.6316)
			(xy 135.241284 -430.018952) (xy 135.241675 -430.006842) (xy 135.249186 -429.983816) (xy 135.263455 -429.964245)
			(xy 135.28308 -429.950052) (xy 135.306135 -429.942629) (xy 135.318246 -429.942244) (xy 136.258046 -429.942244)
			(xy 136.270138 -429.942668) (xy 136.293141 -429.950138) (xy 136.312721 -429.964336) (xy 136.32697 -429.983878)
			(xy 136.3345 -430.006861) (xy 136.335008 -430.018952) (xy 136.335008 -430.889918) (xy 137.237978 -430.889918)
			(xy 137.238072 -430.875344) (xy 137.239724 -430.846243) (xy 137.24128 -430.831752) (xy 137.24128 -429.747934)
			(xy 137.239733 -429.733442) (xy 137.238082 -429.704342) (xy 137.237978 -429.689768) (xy 137.238076 -429.675194)
			(xy 137.239726 -429.646093) (xy 137.24128 -429.631602) (xy 137.24128 -429.018954) (xy 137.241673 -429.006833)
			(xy 137.249178 -428.983781) (xy 137.263439 -428.964176) (xy 137.28306 -428.949938) (xy 137.30612 -428.942459)
			(xy 137.318242 -428.941992) (xy 138.258042 -428.941992) (xy 138.270154 -428.942475) (xy 138.293191 -428.949968)
			(xy 138.312788 -428.964209) (xy 138.32703 -428.983805) (xy 138.334524 -429.006842) (xy 138.335004 -429.018954)
			(xy 138.335004 -431.560478) (xy 138.33447 -431.572587) (xy 138.326994 -431.595623) (xy 138.312767 -431.615221)
			(xy 138.29318 -431.629465) (xy 138.270151 -431.63696) (xy 138.258042 -431.63744) (xy 137.318242 -431.63744)
			(xy 137.306119 -431.637004) (xy 137.283058 -431.629521) (xy 137.26344 -431.615274) (xy 137.249188 -431.59566)
			(xy 137.241699 -431.572601) (xy 137.24128 -431.560478) (xy 137.24128 -430.948084) (xy 137.239737 -430.933592)
			(xy 137.238084 -430.904492) (xy 137.237978 -430.889918) (xy 136.335008 -430.889918) (xy 136.335008 -431.889916)
			(xy 139.237974 -431.889916) (xy 139.238068 -431.875342) (xy 139.23972 -431.846241) (xy 139.241276 -431.83175)
			(xy 139.241276 -430.747932) (xy 139.239728 -430.73344) (xy 139.238078 -430.70434) (xy 139.237974 -430.689766)
			(xy 139.238072 -430.675192) (xy 139.239722 -430.646091) (xy 139.241276 -430.6316) (xy 139.241276 -430.018952)
			(xy 139.241675 -430.006843) (xy 139.249185 -429.983818) (xy 139.263452 -429.964248) (xy 139.283075 -429.950054)
			(xy 139.306128 -429.94263) (xy 139.318238 -429.942244) (xy 140.258038 -429.942244) (xy 140.27013 -429.942675)
			(xy 140.293133 -429.950143) (xy 140.312712 -429.964338) (xy 140.326961 -429.983879) (xy 140.334492 -430.006861)
			(xy 140.335 -430.018952) (xy 140.335 -430.889918) (xy 142.237968 -430.889918) (xy 142.238077 -430.874832)
			(xy 142.239859 -430.844714) (xy 142.241524 -430.82972) (xy 142.241524 -429.749966) (xy 142.239859 -429.734972)
			(xy 142.238078 -429.704854) (xy 142.237968 -429.689768) (xy 142.238082 -429.674682) (xy 142.23986 -429.644564)
			(xy 142.241524 -429.62957) (xy 142.241524 -429.018954) (xy 142.241968 -429.006864) (xy 142.249435 -428.983864)
			(xy 142.263628 -428.964286) (xy 142.283165 -428.950037) (xy 142.306143 -428.942503) (xy 142.318232 -428.941992)
			(xy 143.258032 -428.941992) (xy 143.270142 -428.942389) (xy 143.293169 -428.949896) (xy 143.312741 -428.964163)
			(xy 143.326934 -428.983788) (xy 143.334356 -429.006843) (xy 143.33474 -429.018954) (xy 143.33474 -431.560478)
			(xy 143.334273 -431.572568) (xy 143.32682 -431.595572) (xy 143.312634 -431.615154) (xy 143.293099 -431.629404)
			(xy 143.270121 -431.636933) (xy 143.258032 -431.63744) (xy 142.318232 -431.63744) (xy 142.306129 -431.636957)
			(xy 142.283109 -431.629471) (xy 142.263539 -431.615225) (xy 142.249342 -431.59562) (xy 142.241913 -431.572582)
			(xy 142.241524 -431.560478) (xy 142.241524 -430.950116) (xy 142.239855 -430.935123) (xy 142.238077 -430.905004)
			(xy 142.237968 -430.889918) (xy 140.335 -430.889918) (xy 140.335 -431.889916) (xy 144.237964 -431.889916)
			(xy 144.238073 -431.87483) (xy 144.239855 -431.844712) (xy 144.24152 -431.829718) (xy 144.24152 -430.749964)
			(xy 144.239855 -430.73497) (xy 144.238074 -430.704852) (xy 144.237964 -430.689766) (xy 144.238078 -430.67468)
			(xy 144.239856 -430.644562) (xy 144.24152 -430.629568) (xy 144.24152 -430.018952) (xy 144.241924 -430.006872)
			(xy 144.249403 -429.983899) (xy 144.263614 -429.96436) (xy 144.283167 -429.950168) (xy 144.306148 -429.942712)
			(xy 144.318228 -429.942244) (xy 145.258028 -429.942244) (xy 145.270099 -429.942739) (xy 145.293059 -429.950204)
			(xy 145.312592 -429.964394) (xy 145.326787 -429.983923) (xy 145.334258 -430.006881) (xy 145.334736 -430.018952)
			(xy 145.334736 -430.889918) (xy 146.23796 -430.889918) (xy 146.238069 -430.874832) (xy 146.239851 -430.844714)
			(xy 146.241516 -430.82972) (xy 146.241516 -429.749966) (xy 146.239851 -429.734972) (xy 146.23807 -429.704854)
			(xy 146.23796 -429.689768) (xy 146.238074 -429.674682) (xy 146.239852 -429.644564) (xy 146.241516 -429.62957)
			(xy 146.241516 -429.018954) (xy 146.241968 -429.006864) (xy 146.249434 -428.983866) (xy 146.263626 -428.964289)
			(xy 146.28316 -428.950039) (xy 146.306136 -428.942504) (xy 146.318224 -428.941992) (xy 147.258024 -428.941992)
			(xy 147.270133 -428.942396) (xy 147.29316 -428.949901) (xy 147.312732 -428.964166) (xy 147.326926 -428.983789)
			(xy 147.334348 -429.006843) (xy 147.334732 -429.018954) (xy 147.334732 -431.560478) (xy 147.334273 -431.572569)
			(xy 147.326819 -431.595574) (xy 147.312632 -431.615156) (xy 147.293094 -431.629407) (xy 147.270114 -431.636934)
			(xy 147.258024 -431.63744) (xy 146.318224 -431.63744) (xy 146.30612 -431.636964) (xy 146.283101 -431.629476)
			(xy 146.263531 -431.615228) (xy 146.249334 -431.595622) (xy 146.241905 -431.572583) (xy 146.241516 -431.560478)
			(xy 146.241516 -430.950116) (xy 146.239847 -430.935123) (xy 146.238069 -430.905004) (xy 146.23796 -430.889918)
			(xy 145.334736 -430.889918) (xy 145.334736 -431.889916) (xy 148.237956 -431.889916) (xy 148.238065 -431.87483)
			(xy 148.239847 -431.844712) (xy 148.241512 -431.829718) (xy 148.241512 -430.749964) (xy 148.239847 -430.73497)
			(xy 148.238066 -430.704852) (xy 148.237956 -430.689766) (xy 148.23807 -430.67468) (xy 148.239848 -430.644562)
			(xy 148.241512 -430.629568) (xy 148.241512 -430.018952) (xy 148.241924 -430.006873) (xy 148.249402 -429.983901)
			(xy 148.263611 -429.964363) (xy 148.283162 -429.950171) (xy 148.306141 -429.942713) (xy 148.31822 -429.942244)
			(xy 149.25802 -429.942244) (xy 149.270091 -429.942747) (xy 149.29305 -429.950209) (xy 149.312583 -429.964397)
			(xy 149.326778 -429.983924) (xy 149.334249 -430.006881) (xy 149.334728 -430.018952) (xy 149.334728 -430.889918)
			(xy 150.237952 -430.889918) (xy 150.238061 -430.874832) (xy 150.239843 -430.844714) (xy 150.241508 -430.82972)
			(xy 150.241508 -429.749966) (xy 150.239843 -429.734972) (xy 150.238062 -429.704854) (xy 150.237952 -429.689768)
			(xy 150.238066 -429.674682) (xy 150.239844 -429.644564) (xy 150.241508 -429.62957) (xy 150.241508 -429.018954)
			(xy 150.241968 -429.006865) (xy 150.249433 -428.983868) (xy 150.263623 -428.964292) (xy 150.283155 -428.950042)
			(xy 150.306129 -428.942505) (xy 150.318216 -428.941992) (xy 151.258016 -428.941992) (xy 151.270125 -428.942402)
			(xy 151.293151 -428.949905) (xy 151.312724 -428.964169) (xy 151.326918 -428.983791) (xy 151.33434 -429.006844)
			(xy 151.334724 -429.018954) (xy 151.334724 -431.560478) (xy 151.334273 -431.57257) (xy 151.326818 -431.595576)
			(xy 151.312629 -431.615159) (xy 151.293089 -431.629409) (xy 151.270106 -431.636935) (xy 151.258016 -431.63744)
			(xy 150.318216 -431.63744) (xy 150.306112 -431.63697) (xy 150.283092 -431.62948) (xy 150.263522 -431.615231)
			(xy 150.249326 -431.595623) (xy 150.241897 -431.572583) (xy 150.241508 -431.560478) (xy 150.241508 -430.950116)
			(xy 150.239839 -430.935123) (xy 150.238061 -430.905004) (xy 150.237952 -430.889918) (xy 149.334728 -430.889918)
			(xy 149.334728 -431.889916) (xy 152.237948 -431.889916) (xy 152.238057 -431.87483) (xy 152.239839 -431.844712)
			(xy 152.241504 -431.829718) (xy 152.241504 -430.749964) (xy 152.239839 -430.73497) (xy 152.238058 -430.704852)
			(xy 152.237948 -430.689766) (xy 152.238062 -430.67468) (xy 152.23984 -430.644562) (xy 152.241504 -430.629568)
			(xy 152.241504 -430.018952) (xy 152.241923 -430.006874) (xy 152.249401 -429.983903) (xy 152.263608 -429.964366)
			(xy 152.283157 -429.950173) (xy 152.306133 -429.942714) (xy 152.318212 -429.942244) (xy 153.258012 -429.942244)
			(xy 153.270082 -429.942753) (xy 153.293042 -429.950213) (xy 153.312574 -429.9644) (xy 153.32677 -429.983926)
			(xy 153.334241 -430.006882) (xy 153.33472 -430.018952) (xy 153.33472 -430.889918) (xy 154.237944 -430.889918)
			(xy 154.238053 -430.874832) (xy 154.239835 -430.844714) (xy 154.2415 -430.82972) (xy 154.2415 -429.749966)
			(xy 154.239835 -429.734972) (xy 154.238054 -429.704854) (xy 154.237944 -429.689768) (xy 154.238058 -429.674682)
			(xy 154.239836 -429.644564) (xy 154.2415 -429.62957) (xy 154.2415 -429.018954) (xy 154.241967 -429.006866)
			(xy 154.249432 -428.983871) (xy 154.26362 -428.964295) (xy 154.28315 -428.950044) (xy 154.306122 -428.942507)
			(xy 154.318208 -428.941992) (xy 155.258008 -428.941992) (xy 155.270117 -428.942409) (xy 155.293143 -428.94991)
			(xy 155.312715 -428.964172) (xy 155.32691 -428.983792) (xy 155.334332 -429.006844) (xy 155.334716 -429.018954)
			(xy 155.334716 -431.560478) (xy 155.334273 -431.572571) (xy 155.326817 -431.595578) (xy 155.312626 -431.615162)
			(xy 155.293084 -431.629412) (xy 155.270099 -431.636937) (xy 155.258008 -431.63744) (xy 154.318208 -431.63744)
			(xy 154.306104 -431.636978) (xy 154.283083 -431.629485) (xy 154.263513 -431.615234) (xy 154.249317 -431.595625)
			(xy 154.241889 -431.572584) (xy 154.2415 -431.560478) (xy 154.2415 -430.950116) (xy 154.239831 -430.935123)
			(xy 154.238053 -430.905004) (xy 154.237944 -430.889918) (xy 153.33472 -430.889918) (xy 153.33472 -431.889916)
			(xy 156.23794 -431.889916) (xy 156.238051 -431.87483) (xy 156.239833 -431.844712) (xy 156.241496 -431.829718)
			(xy 156.241496 -430.749964) (xy 156.239831 -430.73497) (xy 156.23805 -430.704852) (xy 156.23794 -430.689766)
			(xy 156.238054 -430.67468) (xy 156.239832 -430.644562) (xy 156.241496 -430.629568) (xy 156.241496 -430.018952)
			(xy 156.241923 -430.006875) (xy 156.249399 -429.983905) (xy 156.263605 -429.964368) (xy 156.283152 -429.950176)
			(xy 156.306126 -429.942715) (xy 156.318204 -429.942244) (xy 157.258004 -429.942244) (xy 157.270074 -429.94276)
			(xy 157.293033 -429.950218) (xy 157.312566 -429.964403) (xy 157.326762 -429.983927) (xy 157.334233 -430.006882)
			(xy 157.334712 -430.018952) (xy 157.334712 -432.560476) (xy 157.334267 -432.572557) (xy 157.326806 -432.595538)
			(xy 157.312609 -432.615089) (xy 157.293063 -432.629294) (xy 157.270085 -432.636762) (xy 157.258004 -432.637184)
			(xy 156.318204 -432.637184) (xy 156.306119 -432.636784) (xy 156.283132 -432.629314) (xy 156.26358 -432.615106)
			(xy 156.249376 -432.59555) (xy 156.241913 -432.572561) (xy 156.241496 -432.560476) (xy 156.241496 -431.950114)
			(xy 156.239826 -431.935121) (xy 156.238049 -431.905002) (xy 156.23794 -431.889916) (xy 153.33472 -431.889916)
			(xy 153.33472 -432.560476) (xy 153.334267 -432.572556) (xy 153.326807 -432.595536) (xy 153.312611 -432.615086)
			(xy 153.293068 -432.629291) (xy 153.270092 -432.636761) (xy 153.258012 -432.637184) (xy 152.318212 -432.637184)
			(xy 152.306128 -432.636777) (xy 152.283141 -432.629309) (xy 152.263589 -432.615103) (xy 152.249385 -432.595548)
			(xy 152.241922 -432.572561) (xy 152.241504 -432.560476) (xy 152.241504 -431.950114) (xy 152.239834 -431.935121)
			(xy 152.238057 -431.905002) (xy 152.237948 -431.889916) (xy 149.334728 -431.889916) (xy 149.334728 -432.560476)
			(xy 149.334267 -432.572555) (xy 149.326809 -432.595534) (xy 149.312614 -432.615083) (xy 149.293073 -432.629288)
			(xy 149.270099 -432.63676) (xy 149.25802 -432.637184) (xy 148.31822 -432.637184) (xy 148.306136 -432.63677)
			(xy 148.28315 -432.629305) (xy 148.263597 -432.6151) (xy 148.249393 -432.595547) (xy 148.24193 -432.57256)
			(xy 148.241512 -432.560476) (xy 148.241512 -431.950114) (xy 148.239842 -431.935121) (xy 148.238065 -431.905002)
			(xy 148.237956 -431.889916) (xy 145.334736 -431.889916) (xy 145.334736 -432.560476) (xy 145.334216 -432.572547)
			(xy 145.326763 -432.595508) (xy 145.31258 -432.615043) (xy 145.293055 -432.62924) (xy 145.270098 -432.636708)
			(xy 145.258028 -432.637184) (xy 144.318228 -432.637184) (xy 144.306144 -432.636763) (xy 144.283159 -432.6293)
			(xy 144.263606 -432.615097) (xy 144.249402 -432.595545) (xy 144.241938 -432.57256) (xy 144.24152 -432.560476)
			(xy 144.24152 -431.950114) (xy 144.23985 -431.935121) (xy 144.238073 -431.905002) (xy 144.237964 -431.889916)
			(xy 140.335 -431.889916) (xy 140.335 -432.560476) (xy 140.334563 -432.572584) (xy 140.32707 -432.59561)
			(xy 140.312814 -432.615184) (xy 140.293196 -432.629379) (xy 140.270147 -432.6368) (xy 140.258038 -432.637184)
			(xy 139.318238 -432.637184) (xy 139.306153 -432.636661) (xy 139.283157 -432.629217) (xy 139.263579 -432.615044)
			(xy 139.249326 -432.595524) (xy 139.241789 -432.572559) (xy 139.241276 -432.560476) (xy 139.241276 -431.948082)
			(xy 139.239733 -431.93359) (xy 139.23808 -431.90449) (xy 139.237974 -431.889916) (xy 136.335008 -431.889916)
			(xy 136.335008 -432.560476) (xy 136.334563 -432.572583) (xy 136.327071 -432.595608) (xy 136.312817 -432.615181)
			(xy 136.293201 -432.629376) (xy 136.270154 -432.636799) (xy 136.258046 -432.637184) (xy 135.318246 -432.637184)
			(xy 135.306161 -432.636654) (xy 135.283166 -432.629213) (xy 135.263587 -432.615042) (xy 135.249334 -432.595522)
			(xy 135.241797 -432.572559) (xy 135.241284 -432.560476) (xy 135.241284 -431.948082) (xy 135.239741 -431.93359)
			(xy 135.238088 -431.90449) (xy 135.237982 -431.889916) (xy 132.335016 -431.889916) (xy 132.335016 -432.560476)
			(xy 132.334563 -432.572582) (xy 132.327072 -432.595606) (xy 132.31282 -432.615178) (xy 132.293206 -432.629374)
			(xy 132.270161 -432.636798) (xy 132.258054 -432.637184) (xy 131.318254 -432.637184) (xy 131.306164 -432.636732)
			(xy 131.283166 -432.629266) (xy 131.263589 -432.615074) (xy 131.249339 -432.59554) (xy 131.241804 -432.572564)
			(xy 131.241292 -432.560476) (xy 131.241292 -431.948082) (xy 131.239749 -431.93359) (xy 131.238096 -431.90449)
			(xy 131.23799 -431.889916) (xy 128.335024 -431.889916) (xy 128.335024 -432.560476) (xy 128.334563 -432.572581)
			(xy 128.327074 -432.595604) (xy 128.312823 -432.615175) (xy 128.293212 -432.629371) (xy 128.270168 -432.636797)
			(xy 128.258062 -432.637184) (xy 127.318262 -432.637184) (xy 127.306173 -432.636726) (xy 127.283175 -432.629261)
			(xy 127.263598 -432.615072) (xy 127.249348 -432.595538) (xy 127.241812 -432.572564) (xy 127.2413 -432.560476)
			(xy 127.2413 -431.948082) (xy 127.239756 -431.93359) (xy 127.238104 -431.90449) (xy 127.237998 -431.889916)
			(xy 115.605768 -431.889916) (xy 115.596243 -431.956613) (xy 115.564055 -432.124765) (xy 115.523953 -432.291207)
			(xy 115.476027 -432.455567) (xy 115.420385 -432.617477) (xy 115.35715 -432.776576) (xy 115.286464 -432.932508)
			(xy 115.208486 -433.084923) (xy 115.12339 -433.233482) (xy 115.031365 -433.377851) (xy 114.932619 -433.517709)
			(xy 114.82737 -433.652742) (xy 114.715856 -433.782648) (xy 114.598325 -433.907137) (xy 114.47504 -434.02593)
			(xy 114.346277 -434.138763) (xy 114.212324 -434.245381) (xy 114.07348 -434.345548) (xy 113.930056 -434.439039)
			(xy 113.843394 -434.48986) (xy 125.238002 -434.48986) (xy 125.2381 -434.475286) (xy 125.239749 -434.446185)
			(xy 125.241304 -434.431694) (xy 125.241304 -433.34813) (xy 125.239756 -433.333638) (xy 125.238106 -433.304538)
			(xy 125.238002 -433.289964) (xy 125.2381 -433.27539) (xy 125.239749 -433.246289) (xy 125.241304 -433.231798)
			(xy 125.241304 -432.618896) (xy 125.241713 -432.606787) (xy 125.249214 -432.583758) (xy 125.263477 -432.564185)
			(xy 125.283101 -432.549991) (xy 125.306155 -432.542571) (xy 125.318266 -432.542188) (xy 126.258066 -432.542188)
			(xy 126.270159 -432.542637) (xy 126.293166 -432.55009) (xy 126.312751 -432.56428) (xy 126.327001 -432.583821)
			(xy 126.334525 -432.606805) (xy 126.335028 -432.618896) (xy 126.335028 -435.16042) (xy 126.334601 -435.172527)
			(xy 126.3271 -435.19555) (xy 126.31284 -435.215121) (xy 126.293222 -435.229316) (xy 126.270174 -435.236741)
			(xy 126.258066 -435.237128) (xy 125.318266 -435.237128) (xy 125.306171 -435.236721) (xy 125.283164 -435.229251)
			(xy 125.263582 -435.21505) (xy 125.249334 -435.195502) (xy 125.241808 -435.172513) (xy 125.241304 -435.16042)
			(xy 125.241304 -434.548026) (xy 125.239756 -434.533534) (xy 125.238106 -434.504434) (xy 125.238002 -434.48986)
			(xy 113.843394 -434.48986) (xy 113.782372 -434.525645) (xy 113.630759 -434.605172) (xy 113.475556 -434.677443)
			(xy 113.396522 -434.710332) (xy 113.382851 -434.716444) (xy 113.359598 -434.735293) (xy 113.342813 -434.760077)
			(xy 113.333939 -434.788665) (xy 113.333741 -434.818598) (xy 113.342235 -434.847301) (xy 113.358691 -434.872305)
			(xy 113.369852 -434.88229) (xy 113.419298 -434.924299) (xy 113.513487 -435.013553) (xy 113.601975 -435.108462)
			(xy 113.684422 -435.208663) (xy 113.760513 -435.313772) (xy 113.829956 -435.423387) (xy 113.866512 -435.489858)
			(xy 127.237998 -435.489858) (xy 127.238095 -435.475284) (xy 127.239745 -435.446183) (xy 127.2413 -435.431692)
			(xy 127.2413 -434.348128) (xy 127.239752 -434.333636) (xy 127.238102 -434.304536) (xy 127.237998 -434.289962)
			(xy 127.238096 -434.275388) (xy 127.239745 -434.246287) (xy 127.2413 -434.231796) (xy 127.2413 -433.618894)
			(xy 127.241806 -433.606783) (xy 127.24929 -433.583746) (xy 127.263525 -433.564148) (xy 127.283117 -433.549905)
			(xy 127.306151 -433.542411) (xy 127.318262 -433.541932) (xy 128.258062 -433.541932) (xy 128.270182 -433.542392)
			(xy 128.293239 -433.549873) (xy 128.312854 -433.564115) (xy 128.327107 -433.583722) (xy 128.334601 -433.606774)
			(xy 128.335024 -433.618894) (xy 128.335024 -434.48986) (xy 129.237994 -434.48986) (xy 129.238092 -434.475286)
			(xy 129.239741 -434.446185) (xy 129.241296 -434.431694) (xy 129.241296 -433.34813) (xy 129.239748 -433.333638)
			(xy 129.238098 -433.304538) (xy 129.237994 -433.289964) (xy 129.238092 -433.27539) (xy 129.239741 -433.246289)
			(xy 129.241296 -433.231798) (xy 129.241296 -432.618896) (xy 129.241713 -432.606787) (xy 129.249213 -432.583761)
			(xy 129.263474 -432.564188) (xy 129.283096 -432.549993) (xy 129.306148 -432.542572) (xy 129.318258 -432.542188)
			(xy 130.258058 -432.542188) (xy 130.27015 -432.542644) (xy 130.293158 -432.550095) (xy 130.312742 -432.564283)
			(xy 130.326993 -432.583822) (xy 130.334517 -432.606805) (xy 130.33502 -432.618896) (xy 130.33502 -435.16042)
			(xy 130.334601 -435.172528) (xy 130.327099 -435.195552) (xy 130.312837 -435.215123) (xy 130.293217 -435.229318)
			(xy 130.270167 -435.236742) (xy 130.258058 -435.237128) (xy 129.318258 -435.237128) (xy 129.306163 -435.236728)
			(xy 129.283156 -435.229256) (xy 129.263574 -435.215053) (xy 129.249326 -435.195504) (xy 129.2418 -435.172514)
			(xy 129.241296 -435.16042) (xy 129.241296 -434.548026) (xy 129.239748 -434.533534) (xy 129.238098 -434.504434)
			(xy 129.237994 -434.48986) (xy 128.335024 -434.48986) (xy 128.335024 -435.489858) (xy 131.23799 -435.489858)
			(xy 131.238087 -435.475284) (xy 131.239737 -435.446183) (xy 131.241292 -435.431692) (xy 131.241292 -434.348128)
			(xy 131.239744 -434.333636) (xy 131.238094 -434.304536) (xy 131.23799 -434.289962) (xy 131.238088 -434.275388)
			(xy 131.239737 -434.246287) (xy 131.241292 -434.231796) (xy 131.241292 -433.618894) (xy 131.241806 -433.606784)
			(xy 131.249289 -433.583748) (xy 131.263522 -433.564151) (xy 131.283112 -433.549908) (xy 131.306144 -433.542412)
			(xy 131.318254 -433.541932) (xy 132.258054 -433.541932) (xy 132.270174 -433.542399) (xy 132.29323 -433.549878)
			(xy 132.312846 -433.564117) (xy 132.327098 -433.583723) (xy 132.334593 -433.606775) (xy 132.335016 -433.618894)
			(xy 132.335016 -434.48986) (xy 133.237986 -434.48986) (xy 133.238084 -434.475286) (xy 133.239733 -434.446185)
			(xy 133.241288 -434.431694) (xy 133.241288 -433.34813) (xy 133.23974 -433.333638) (xy 133.23809 -433.304538)
			(xy 133.237986 -433.289964) (xy 133.238084 -433.27539) (xy 133.239733 -433.246289) (xy 133.241288 -433.231798)
			(xy 133.241288 -432.618896) (xy 133.241713 -432.606788) (xy 133.249212 -432.583763) (xy 133.263472 -432.564191)
			(xy 133.283091 -432.549996) (xy 133.306141 -432.542573) (xy 133.31825 -432.542188) (xy 134.25805 -432.542188)
			(xy 134.270142 -432.542651) (xy 134.293149 -432.5501) (xy 134.312734 -432.564285) (xy 134.326984 -432.583823)
			(xy 134.334509 -432.606806) (xy 134.335012 -432.618896) (xy 134.335012 -435.16042) (xy 134.334601 -435.172529)
			(xy 134.327097 -435.195555) (xy 134.312834 -435.215126) (xy 134.293212 -435.229321) (xy 134.27016 -435.236743)
			(xy 134.25805 -435.237128) (xy 133.31825 -435.237128) (xy 133.30616 -435.23665) (xy 133.283155 -435.229203)
			(xy 133.263572 -435.21502) (xy 133.249321 -435.195487) (xy 133.241793 -435.172508) (xy 133.241288 -435.16042)
			(xy 133.241288 -434.548026) (xy 133.23974 -434.533534) (xy 133.23809 -434.504434) (xy 133.237986 -434.48986)
			(xy 132.335016 -434.48986) (xy 132.335016 -435.489858) (xy 135.237982 -435.489858) (xy 135.238079 -435.475284)
			(xy 135.239729 -435.446183) (xy 135.241284 -435.431692) (xy 135.241284 -434.348128) (xy 135.239736 -434.333636)
			(xy 135.238086 -434.304536) (xy 135.237982 -434.289962) (xy 135.23808 -434.275388) (xy 135.239729 -434.246287)
			(xy 135.241284 -434.231796) (xy 135.241284 -433.618894) (xy 135.241656 -433.606766) (xy 135.249155 -433.5837)
			(xy 135.263418 -433.564081) (xy 135.283046 -433.549831) (xy 135.306118 -433.542348) (xy 135.318246 -433.541932)
			(xy 136.258046 -433.541932) (xy 136.270162 -433.542372) (xy 136.293206 -433.549872) (xy 136.312807 -433.564122)
			(xy 136.327047 -433.58373) (xy 136.334534 -433.606777) (xy 136.335008 -433.618894) (xy 136.335008 -434.48986)
			(xy 137.237978 -434.48986) (xy 137.238076 -434.475286) (xy 137.239725 -434.446185) (xy 137.24128 -434.431694)
			(xy 137.24128 -433.34813) (xy 137.239732 -433.333638) (xy 137.238082 -433.304538) (xy 137.237978 -433.289964)
			(xy 137.238076 -433.27539) (xy 137.239726 -433.246289) (xy 137.24128 -433.231798) (xy 137.24128 -432.618896)
			(xy 137.241712 -432.606789) (xy 137.249211 -432.583765) (xy 137.263469 -432.564194) (xy 137.283086 -432.549998)
			(xy 137.306134 -432.542574) (xy 137.318242 -432.542188) (xy 138.258042 -432.542188) (xy 138.270139 -432.542572)
			(xy 138.293149 -432.550047) (xy 138.312732 -432.564253) (xy 138.326979 -432.583806) (xy 138.334502 -432.606801)
			(xy 138.335004 -432.618896) (xy 138.335004 -435.16042) (xy 138.334601 -435.17253) (xy 138.327096 -435.195557)
			(xy 138.312831 -435.215129) (xy 138.293207 -435.229323) (xy 138.270153 -435.236744) (xy 138.258042 -435.237128)
			(xy 137.318242 -435.237128) (xy 137.306151 -435.236656) (xy 137.283147 -435.229207) (xy 137.263563 -435.215023)
			(xy 137.249313 -435.195488) (xy 137.241785 -435.172509) (xy 137.24128 -435.16042) (xy 137.24128 -434.548026)
			(xy 137.239732 -434.533534) (xy 137.238082 -434.504434) (xy 137.237978 -434.48986) (xy 136.335008 -434.48986)
			(xy 136.335008 -435.489858) (xy 139.237974 -435.489858) (xy 139.238072 -435.475284) (xy 139.239721 -435.446183)
			(xy 139.241276 -435.431692) (xy 139.241276 -434.348128) (xy 139.239728 -434.333636) (xy 139.238078 -434.304536)
			(xy 139.237974 -434.289962) (xy 139.238072 -434.275388) (xy 139.239721 -434.246287) (xy 139.241276 -434.231796)
			(xy 139.241276 -433.618894) (xy 139.241656 -433.606767) (xy 139.249154 -433.583702) (xy 139.263415 -433.564084)
			(xy 139.283041 -433.549834) (xy 139.306111 -433.542349) (xy 139.318238 -433.541932) (xy 140.258038 -433.541932)
			(xy 140.270154 -433.542379) (xy 140.293197 -433.549876) (xy 140.312798 -433.564125) (xy 140.327038 -433.583731)
			(xy 140.334526 -433.606778) (xy 140.335 -433.618894) (xy 140.335 -434.48986) (xy 142.237968 -434.48986)
			(xy 142.238081 -434.474774) (xy 142.23986 -434.444656) (xy 142.241524 -434.429662) (xy 142.241524 -433.350162)
			(xy 142.239859 -433.335168) (xy 142.238078 -433.30505) (xy 142.237968 -433.289964) (xy 142.238081 -433.274878)
			(xy 142.23986 -433.24476) (xy 142.241524 -433.229766) (xy 142.241524 -432.618896) (xy 142.24191 -432.60681)
			(xy 142.249382 -432.583822) (xy 142.263594 -432.564268) (xy 142.283154 -432.550066) (xy 142.306146 -432.542604)
			(xy 142.318232 -432.542188) (xy 143.258032 -432.542188) (xy 143.270108 -432.542637) (xy 143.293075 -432.550108)
			(xy 143.312612 -432.564308) (xy 143.326805 -432.58385) (xy 143.334268 -432.60682) (xy 143.33474 -432.618896)
			(xy 143.33474 -435.16042) (xy 143.334253 -435.172492) (xy 143.326789 -435.195455) (xy 143.312597 -435.214989)
			(xy 143.293065 -435.229184) (xy 143.270104 -435.236651) (xy 143.258032 -435.237128) (xy 142.318232 -435.237128)
			(xy 142.306153 -435.23666) (xy 142.283175 -435.229204) (xy 142.263626 -435.215011) (xy 142.24942 -435.195472)
			(xy 142.241948 -435.172499) (xy 142.241524 -435.16042) (xy 142.241524 -434.550058) (xy 142.239858 -434.535064)
			(xy 142.238078 -434.504946) (xy 142.237968 -434.48986) (xy 140.335 -434.48986) (xy 140.335 -435.489858)
			(xy 144.237964 -435.489858) (xy 144.238077 -435.474772) (xy 144.239856 -435.444654) (xy 144.24152 -435.42966)
			(xy 144.24152 -434.35016) (xy 144.239855 -434.335166) (xy 144.238074 -434.305048) (xy 144.237964 -434.289962)
			(xy 144.238077 -434.274876) (xy 144.239856 -434.244758) (xy 144.24152 -434.229764) (xy 144.24152 -433.618894)
			(xy 144.242002 -433.606806) (xy 144.249458 -433.583809) (xy 144.263641 -433.564231) (xy 144.28317 -433.54998)
			(xy 144.306142 -433.542444) (xy 144.318228 -433.541932) (xy 145.258028 -433.541932) (xy 145.270142 -433.542293)
			(xy 145.293175 -433.549804) (xy 145.312751 -433.564079) (xy 145.326943 -433.583714) (xy 145.334357 -433.606779)
			(xy 145.334736 -433.618894) (xy 145.334736 -434.48986) (xy 146.23796 -434.48986) (xy 146.238073 -434.474774)
			(xy 146.239852 -434.444656) (xy 146.241516 -434.429662) (xy 146.241516 -433.350162) (xy 146.239851 -433.335168)
			(xy 146.23807 -433.30505) (xy 146.23796 -433.289964) (xy 146.238073 -433.274878) (xy 146.239852 -433.24476)
			(xy 146.241516 -433.229766) (xy 146.241516 -432.618896) (xy 146.241909 -432.606811) (xy 146.249381 -432.583824)
			(xy 146.263591 -432.564271) (xy 146.283149 -432.550068) (xy 146.306138 -432.542605) (xy 146.318224 -432.542188)
			(xy 147.258024 -432.542188) (xy 147.270099 -432.542644) (xy 147.293067 -432.550113) (xy 147.312603 -432.564311)
			(xy 147.326797 -432.583851) (xy 147.334259 -432.606821) (xy 147.334732 -432.618896) (xy 147.334732 -435.16042)
			(xy 147.334253 -435.172493) (xy 147.326788 -435.195457) (xy 147.312594 -435.214991) (xy 147.29306 -435.229186)
			(xy 147.270097 -435.236652) (xy 147.258024 -435.237128) (xy 146.318224 -435.237128) (xy 146.306145 -435.236667)
			(xy 146.283166 -435.229209) (xy 146.263617 -435.215014) (xy 146.249412 -435.195473) (xy 146.24194 -435.172499)
			(xy 146.241516 -435.16042) (xy 146.241516 -434.550058) (xy 146.23985 -434.535064) (xy 146.23807 -434.504946)
			(xy 146.23796 -434.48986) (xy 145.334736 -434.48986) (xy 145.334736 -435.489858) (xy 148.237956 -435.489858)
			(xy 148.238069 -435.474772) (xy 148.239848 -435.444654) (xy 148.241512 -435.42966) (xy 148.241512 -434.35016)
			(xy 148.239847 -434.335166) (xy 148.238066 -434.305048) (xy 148.237956 -434.289962) (xy 148.238069 -434.274876)
			(xy 148.239848 -434.244758) (xy 148.241512 -434.229764) (xy 148.241512 -433.618894) (xy 148.242002 -433.606807)
			(xy 148.249457 -433.583811) (xy 148.263639 -433.564234) (xy 148.283165 -433.549982) (xy 148.306135 -433.542445)
			(xy 148.31822 -433.541932) (xy 149.25802 -433.541932) (xy 149.270133 -433.5423) (xy 149.293167 -433.549808)
			(xy 149.312742 -433.564081) (xy 149.326935 -433.583715) (xy 149.334349 -433.606779) (xy 149.334728 -433.618894)
			(xy 149.334728 -434.48986) (xy 150.237952 -434.48986) (xy 150.238065 -434.474774) (xy 150.239844 -434.444656)
			(xy 150.241508 -434.429662) (xy 150.241508 -433.350162) (xy 150.239843 -433.335168) (xy 150.238062 -433.30505)
			(xy 150.237952 -433.289964) (xy 150.238065 -433.274878) (xy 150.239844 -433.24476) (xy 150.241508 -433.229766)
			(xy 150.241508 -432.618896) (xy 150.241909 -432.606811) (xy 150.24938 -432.583826) (xy 150.263588 -432.564274)
			(xy 150.283144 -432.550071) (xy 150.306131 -432.542606) (xy 150.318216 -432.542188) (xy 151.258016 -432.542188)
			(xy 151.270091 -432.542651) (xy 151.293058 -432.550117) (xy 151.312594 -432.564314) (xy 151.326788 -432.583853)
			(xy 151.334251 -432.606821) (xy 151.334724 -432.618896) (xy 151.334724 -435.16042) (xy 151.334253 -435.172494)
			(xy 151.326787 -435.195459) (xy 151.312591 -435.214994) (xy 151.293055 -435.229189) (xy 151.27009 -435.236654)
			(xy 151.258016 -435.237128) (xy 150.318216 -435.237128) (xy 150.306144 -435.236622) (xy 150.283181 -435.229167)
			(xy 150.263645 -435.21498) (xy 150.24945 -435.195451) (xy 150.241983 -435.172492) (xy 150.241508 -435.16042)
			(xy 150.241508 -434.550058) (xy 150.239842 -434.535064) (xy 150.238062 -434.504946) (xy 150.237952 -434.48986)
			(xy 149.334728 -434.48986) (xy 149.334728 -435.489858) (xy 152.237948 -435.489858) (xy 152.238061 -435.474772)
			(xy 152.23984 -435.444654) (xy 152.241504 -435.42966) (xy 152.241504 -434.35016) (xy 152.239838 -434.335166)
			(xy 152.238058 -434.305048) (xy 152.237948 -434.289962) (xy 152.238061 -434.274876) (xy 152.23984 -434.244758)
			(xy 152.241504 -434.229764) (xy 152.241504 -433.618894) (xy 152.242002 -433.606808) (xy 152.249456 -433.583813)
			(xy 152.263636 -433.564236) (xy 152.28316 -433.549985) (xy 152.306128 -433.542447) (xy 152.318212 -433.541932)
			(xy 153.258012 -433.541932) (xy 153.270125 -433.542306) (xy 153.293158 -433.549813) (xy 153.312734 -433.564084)
			(xy 153.326927 -433.583717) (xy 153.334341 -433.60678) (xy 153.33472 -433.618894) (xy 153.33472 -434.48986)
			(xy 154.237944 -434.48986) (xy 154.238057 -434.474774) (xy 154.239836 -434.444656) (xy 154.2415 -434.429662)
			(xy 154.2415 -433.350162) (xy 154.239835 -433.335168) (xy 154.238054 -433.30505) (xy 154.237944 -433.289964)
			(xy 154.238057 -433.274878) (xy 154.239836 -433.24476) (xy 154.2415 -433.229766) (xy 154.2415 -432.618896)
			(xy 154.241909 -432.606812) (xy 154.249379 -432.583828) (xy 154.263586 -432.564277) (xy 154.283139 -432.550073)
			(xy 154.306124 -432.542607) (xy 154.318208 -432.542188) (xy 155.258008 -432.542188) (xy 155.270083 -432.542657)
			(xy 155.293049 -432.550122) (xy 155.312586 -432.564317) (xy 155.32678 -432.583854) (xy 155.334243 -432.606821)
			(xy 155.334716 -432.618896) (xy 155.334716 -433.130695) (xy 197.035917 -433.130695) (xy 197.035917 -432.953425)
			(xy 197.04387 -432.776334) (xy 197.059761 -432.599778) (xy 197.083556 -432.424113) (xy 197.115209 -432.249692)
			(xy 197.154655 -432.076867) (xy 197.201815 -431.905986) (xy 197.256594 -431.737392) (xy 197.318882 -431.571427)
			(xy 197.388554 -431.408422) (xy 197.465468 -431.248708) (xy 197.549471 -431.092605) (xy 197.640392 -430.940428)
			(xy 197.738049 -430.792484) (xy 197.842246 -430.64907) (xy 197.952772 -430.510475) (xy 198.069404 -430.376978)
			(xy 198.191909 -430.248849) (xy 198.320038 -430.126344) (xy 198.453535 -430.009712) (xy 198.59213 -429.899186)
			(xy 198.735544 -429.794989) (xy 198.883488 -429.697332) (xy 199.035665 -429.606411) (xy 199.191768 -429.522408)
			(xy 199.351482 -429.445494) (xy 199.514487 -429.375822) (xy 199.680452 -429.313534) (xy 199.849046 -429.258755)
			(xy 200.019927 -429.211595) (xy 200.192752 -429.172149) (xy 200.367173 -429.140496) (xy 200.542838 -429.116701)
			(xy 200.719394 -429.10081) (xy 200.896485 -429.092857) (xy 201.073755 -429.092857) (xy 201.250846 -429.10081)
			(xy 201.427402 -429.116701) (xy 201.603067 -429.140496) (xy 201.777488 -429.172149) (xy 201.950313 -429.211595)
			(xy 202.121194 -429.258755) (xy 202.289788 -429.313534) (xy 202.455753 -429.375822) (xy 202.618758 -429.445494)
			(xy 202.778472 -429.522408) (xy 202.934575 -429.606411) (xy 203.086752 -429.697332) (xy 203.234696 -429.794989)
			(xy 203.37811 -429.899186) (xy 203.516705 -430.009712) (xy 203.650202 -430.126344) (xy 203.778331 -430.248849)
			(xy 203.900836 -430.376978) (xy 204.017468 -430.510475) (xy 204.127994 -430.64907) (xy 204.232191 -430.792484)
			(xy 204.329848 -430.940428) (xy 204.420769 -431.092605) (xy 204.504772 -431.248708) (xy 204.581686 -431.408422)
			(xy 204.651358 -431.571427) (xy 204.713646 -431.737392) (xy 204.768425 -431.905986) (xy 204.815585 -432.076867)
			(xy 204.855031 -432.249692) (xy 204.886684 -432.424113) (xy 204.910479 -432.599778) (xy 204.92637 -432.776334)
			(xy 204.934323 -432.953425) (xy 204.93482 -433.04206) (xy 204.934323 -433.130695) (xy 204.92637 -433.307786)
			(xy 204.910479 -433.484342) (xy 204.886684 -433.660007) (xy 204.855031 -433.834428) (xy 204.815585 -434.007253)
			(xy 204.768425 -434.178134) (xy 204.713646 -434.346728) (xy 204.651358 -434.512693) (xy 204.581686 -434.675698)
			(xy 204.504772 -434.835412) (xy 204.420769 -434.991515) (xy 204.329848 -435.143692) (xy 204.232191 -435.291636)
			(xy 204.127994 -435.43505) (xy 204.017468 -435.573645) (xy 203.900836 -435.707142) (xy 203.778331 -435.835271)
			(xy 203.650202 -435.957776) (xy 203.516705 -436.074408) (xy 203.37811 -436.184934) (xy 203.234696 -436.289131)
			(xy 203.086752 -436.386788) (xy 202.934575 -436.477709) (xy 202.778472 -436.561712) (xy 202.618758 -436.638626)
			(xy 202.455753 -436.708298) (xy 202.289788 -436.770586) (xy 202.121194 -436.825365) (xy 201.950313 -436.872525)
			(xy 201.777488 -436.911971) (xy 201.603067 -436.943624) (xy 201.427402 -436.967419) (xy 201.250846 -436.98331)
			(xy 201.073755 -436.991263) (xy 200.896485 -436.991263) (xy 200.719394 -436.98331) (xy 200.542838 -436.967419)
			(xy 200.367173 -436.943624) (xy 200.192752 -436.911971) (xy 200.019927 -436.872525) (xy 199.849046 -436.825365)
			(xy 199.680452 -436.770586) (xy 199.514487 -436.708298) (xy 199.351482 -436.638626) (xy 199.191768 -436.561712)
			(xy 199.035665 -436.477709) (xy 198.883488 -436.386788) (xy 198.735544 -436.289131) (xy 198.59213 -436.184934)
			(xy 198.453535 -436.074408) (xy 198.320038 -435.957776) (xy 198.191909 -435.835271) (xy 198.069404 -435.707142)
			(xy 197.952772 -435.573645) (xy 197.842246 -435.43505) (xy 197.738049 -435.291636) (xy 197.640392 -435.143692)
			(xy 197.549471 -434.991515) (xy 197.465468 -434.835412) (xy 197.388554 -434.675698) (xy 197.318882 -434.512693)
			(xy 197.256594 -434.346728) (xy 197.201815 -434.178134) (xy 197.154655 -434.007253) (xy 197.115209 -433.834428)
			(xy 197.083556 -433.660007) (xy 197.059761 -433.484342) (xy 197.04387 -433.307786) (xy 197.035917 -433.130695)
			(xy 155.334716 -433.130695) (xy 155.334716 -435.16042) (xy 155.334253 -435.172495) (xy 155.326786 -435.195461)
			(xy 155.312589 -435.214997) (xy 155.29305 -435.229191) (xy 155.270083 -435.236655) (xy 155.258008 -435.237128)
			(xy 154.318208 -435.237128) (xy 154.306136 -435.236629) (xy 154.283172 -435.229171) (xy 154.263637 -435.214983)
			(xy 154.249441 -435.195453) (xy 154.241975 -435.172492) (xy 154.2415 -435.16042) (xy 154.2415 -434.550058)
			(xy 154.239834 -434.535064) (xy 154.238054 -434.504946) (xy 154.237944 -434.48986) (xy 153.33472 -434.48986)
			(xy 153.33472 -435.489858) (xy 156.23794 -435.489858) (xy 156.238053 -435.474772) (xy 156.239832 -435.444654)
			(xy 156.241496 -435.42966) (xy 156.241496 -434.35016) (xy 156.23983 -434.335166) (xy 156.23805 -434.305048)
			(xy 156.23794 -434.289962) (xy 156.238053 -434.274876) (xy 156.239832 -434.244758) (xy 156.241496 -434.229764)
			(xy 156.241496 -433.618894) (xy 156.242002 -433.606809) (xy 156.249455 -433.583815) (xy 156.263633 -433.564239)
			(xy 156.283155 -433.549987) (xy 156.30612 -433.542448) (xy 156.318204 -433.541932) (xy 157.258004 -433.541932)
			(xy 157.270116 -433.542313) (xy 157.293149 -433.549818) (xy 157.312725 -433.564087) (xy 157.326918 -433.583718)
			(xy 157.334333 -433.60678) (xy 157.334712 -433.618894) (xy 157.334712 -436.160418) (xy 157.334307 -436.172513)
			(xy 157.32684 -436.195523) (xy 157.312639 -436.215106) (xy 157.293089 -436.229355) (xy 157.270098 -436.236878)
			(xy 157.258004 -436.23738) (xy 156.318204 -436.23738) (xy 156.306093 -436.23698) (xy 156.283063 -436.229479)
			(xy 156.263488 -436.215214) (xy 156.249294 -436.195588) (xy 156.241876 -436.17253) (xy 156.241496 -436.160418)
			(xy 156.241496 -435.550056) (xy 156.23983 -435.535062) (xy 156.23805 -435.504944) (xy 156.23794 -435.489858)
			(xy 153.33472 -435.489858) (xy 153.33472 -436.160418) (xy 153.334307 -436.172513) (xy 153.326841 -436.195521)
			(xy 153.312642 -436.215104) (xy 153.293094 -436.229352) (xy 153.270105 -436.236877) (xy 153.258012 -436.23738)
			(xy 152.318212 -436.23738) (xy 152.306102 -436.236973) (xy 152.283072 -436.229474) (xy 152.263497 -436.215211)
			(xy 152.249302 -436.195586) (xy 152.241885 -436.17253) (xy 152.241504 -436.160418) (xy 152.241504 -435.550056)
			(xy 152.239838 -435.535062) (xy 152.238058 -435.504944) (xy 152.237948 -435.489858) (xy 149.334728 -435.489858)
			(xy 149.334728 -436.160418) (xy 149.334308 -436.172512) (xy 149.326842 -436.195518) (xy 149.312645 -436.215101)
			(xy 149.293099 -436.22935) (xy 149.270112 -436.236876) (xy 149.25802 -436.23738) (xy 148.31822 -436.23738)
			(xy 148.30611 -436.236966) (xy 148.28308 -436.22947) (xy 148.263505 -436.215208) (xy 148.249311 -436.195585)
			(xy 148.241893 -436.172529) (xy 148.241512 -436.160418) (xy 148.241512 -435.550056) (xy 148.239846 -435.535062)
			(xy 148.238066 -435.504944) (xy 148.237956 -435.489858) (xy 145.334736 -435.489858) (xy 145.334736 -436.160418)
			(xy 145.334308 -436.172511) (xy 145.326843 -436.195516) (xy 145.312647 -436.215098) (xy 145.293104 -436.229347)
			(xy 145.27012 -436.236874) (xy 145.258028 -436.23738) (xy 144.318228 -436.23738) (xy 144.306119 -436.236959)
			(xy 144.283089 -436.229465) (xy 144.263514 -436.215206) (xy 144.249319 -436.195583) (xy 144.241901 -436.172529)
			(xy 144.24152 -436.160418) (xy 144.24152 -435.550056) (xy 144.239854 -435.535062) (xy 144.238074 -435.504944)
			(xy 144.237964 -435.489858) (xy 140.335 -435.489858) (xy 140.335 -436.160418) (xy 140.334504 -436.17253)
			(xy 140.327017 -436.195567) (xy 140.31278 -436.215165) (xy 140.293185 -436.229408) (xy 140.27015 -436.236901)
			(xy 140.258038 -436.23738) (xy 139.318238 -436.23738) (xy 139.306119 -436.236908) (xy 139.283064 -436.229428)
			(xy 139.26345 -436.21519) (xy 139.249197 -436.195586) (xy 139.241701 -436.172537) (xy 139.241276 -436.160418)
			(xy 139.241276 -435.548024) (xy 139.239728 -435.533532) (xy 139.238078 -435.504432) (xy 139.237974 -435.489858)
			(xy 136.335008 -435.489858) (xy 136.335008 -436.160418) (xy 136.334505 -436.172529) (xy 136.327018 -436.195565)
			(xy 136.312782 -436.215163) (xy 136.29319 -436.229405) (xy 136.270157 -436.2369) (xy 136.258046 -436.23738)
			(xy 135.318246 -436.23738) (xy 135.306127 -436.236901) (xy 135.283073 -436.229424) (xy 135.263459 -436.215187)
			(xy 135.249205 -436.195584) (xy 135.241709 -436.172536) (xy 135.241284 -436.160418) (xy 135.241284 -435.548024)
			(xy 135.239736 -435.533532) (xy 135.238086 -435.504432) (xy 135.237982 -435.489858) (xy 132.335016 -435.489858)
			(xy 132.335016 -436.160418) (xy 132.334654 -436.172546) (xy 132.327152 -436.195613) (xy 132.312886 -436.215232)
			(xy 132.293256 -436.229481) (xy 132.270183 -436.236965) (xy 132.258054 -436.23738) (xy 131.318254 -436.23738)
			(xy 131.306139 -436.236928) (xy 131.283097 -436.22943) (xy 131.263498 -436.215182) (xy 131.249257 -436.195578)
			(xy 131.241768 -436.172533) (xy 131.241292 -436.160418) (xy 131.241292 -435.548024) (xy 131.239744 -435.533532)
			(xy 131.238094 -435.504432) (xy 131.23799 -435.489858) (xy 128.335024 -435.489858) (xy 128.335024 -436.160418)
			(xy 128.334655 -436.172545) (xy 128.327153 -436.195611) (xy 128.312889 -436.215229) (xy 128.293261 -436.229478)
			(xy 128.27019 -436.236963) (xy 128.258062 -436.23738) (xy 127.318262 -436.23738) (xy 127.306147 -436.236921)
			(xy 127.283106 -436.229425) (xy 127.263506 -436.21518) (xy 127.249265 -436.195576) (xy 127.241776 -436.172533)
			(xy 127.2413 -436.160418) (xy 127.2413 -435.548024) (xy 127.239751 -435.533532) (xy 127.238102 -435.504432)
			(xy 127.237998 -435.489858) (xy 113.866512 -435.489858) (xy 113.892486 -435.537087) (xy 113.947862 -435.654438)
			(xy 113.995874 -435.77499) (xy 114.036336 -435.89828) (xy 114.069094 -436.023838) (xy 114.094022 -436.151181)
			(xy 114.111025 -436.279823) (xy 114.120038 -436.40927) (xy 114.121027 -436.539027) (xy 114.113986 -436.668596)
			(xy 114.098945 -436.797482) (xy 114.075959 -436.92519) (xy 114.045118 -437.051232) (xy 114.006538 -437.175125)
			(xy 113.960369 -437.296394) (xy 113.906786 -437.414574) (xy 113.845996 -437.529214) (xy 113.77823 -437.639874)
			(xy 113.703749 -437.74613) (xy 113.622838 -437.847575) (xy 113.535806 -437.943821) (xy 113.442988 -438.034499)
			(xy 113.378885 -438.089802) (xy 125.238002 -438.089802) (xy 125.238095 -438.075228) (xy 125.239748 -438.046127)
			(xy 125.241304 -438.031636) (xy 125.241304 -436.948072) (xy 125.239759 -436.93358) (xy 125.238107 -436.90448)
			(xy 125.238002 -436.889906) (xy 125.238095 -436.875332) (xy 125.239748 -436.846231) (xy 125.241304 -436.83174)
			(xy 125.241304 -436.219092) (xy 125.241709 -436.206982) (xy 125.249212 -436.183954) (xy 125.263476 -436.164381)
			(xy 125.2831 -436.150186) (xy 125.306155 -436.142767) (xy 125.318266 -436.142384) (xy 126.258066 -436.142384)
			(xy 126.270158 -436.142837) (xy 126.293165 -436.15029) (xy 126.312749 -436.164478) (xy 126.327 -436.184018)
			(xy 126.334525 -436.207001) (xy 126.335028 -436.219092) (xy 126.335028 -438.760616) (xy 126.334598 -438.772723)
			(xy 126.327097 -438.795746) (xy 126.312838 -438.815316) (xy 126.293222 -438.829511) (xy 126.270174 -438.836937)
			(xy 126.258066 -438.837324) (xy 125.318266 -438.837324) (xy 125.306171 -438.836921) (xy 125.283163 -438.829451)
			(xy 125.263581 -438.815249) (xy 125.249333 -438.7957) (xy 125.241808 -438.77271) (xy 125.241304 -438.760616)
			(xy 125.241304 -438.147968) (xy 125.239759 -438.133476) (xy 125.238107 -438.104376) (xy 125.238002 -438.089802)
			(xy 113.378885 -438.089802) (xy 113.344738 -438.119261) (xy 113.241432 -438.197784) (xy 113.133467 -438.269766)
			(xy 113.021257 -438.334931) (xy 112.90523 -438.39303) (xy 112.785831 -438.443841) (xy 112.663518 -438.487169)
			(xy 112.538759 -438.522847) (xy 112.412032 -438.550739) (xy 112.283822 -438.570739) (xy 112.15462 -438.58277)
			(xy 112.024922 -438.586785) (xy 111.895224 -438.58277) (xy 111.766022 -438.570739) (xy 111.637812 -438.550739)
			(xy 111.511085 -438.522847) (xy 111.386326 -438.487169) (xy 111.264013 -438.443841) (xy 111.144614 -438.39303)
			(xy 111.028587 -438.334931) (xy 110.916377 -438.269766) (xy 110.808412 -438.197784) (xy 110.705106 -438.119261)
			(xy 110.606856 -438.034499) (xy 110.514038 -437.943821) (xy 110.427006 -437.847575) (xy 110.346095 -437.74613)
			(xy 110.271614 -437.639874) (xy 110.203848 -437.529214) (xy 110.143058 -437.414574) (xy 110.089475 -437.296394)
			(xy 110.043306 -437.175125) (xy 110.004726 -437.051232) (xy 109.973885 -436.92519) (xy 109.950899 -436.797482)
			(xy 109.935858 -436.668596) (xy 109.928817 -436.539027) (xy 109.929806 -436.40927) (xy 109.938819 -436.279823)
			(xy 109.955822 -436.151181) (xy 109.98075 -436.023838) (xy 110.013508 -435.89828) (xy 110.05397 -435.77499)
			(xy 110.101982 -435.654438) (xy 110.157358 -435.537087) (xy 110.219888 -435.423387) (xy 110.289331 -435.313772)
			(xy 110.365422 -435.208663) (xy 110.447869 -435.108462) (xy 110.536357 -435.013553) (xy 110.630546 -434.924299)
			(xy 110.679992 -434.88229) (xy 110.691093 -434.872254) (xy 110.707515 -434.847259) (xy 110.71599 -434.818578)
			(xy 110.71579 -434.788672) (xy 110.706933 -434.760107) (xy 110.690178 -434.735334) (xy 110.666963 -434.71648)
			(xy 110.653322 -434.710332) (xy 110.574304 -434.677407) (xy 110.419107 -434.605131) (xy 110.267499 -434.5256)
			(xy 110.119821 -434.438991) (xy 109.976402 -434.345497) (xy 109.837562 -434.245328) (xy 109.703613 -434.138709)
			(xy 109.574854 -434.025876) (xy 109.451573 -433.907083) (xy 109.334045 -433.782595) (xy 109.222533 -433.65269)
			(xy 109.117287 -433.517659) (xy 109.018541 -433.377804) (xy 108.926517 -433.233438) (xy 108.84142 -433.084883)
			(xy 108.763441 -432.932471) (xy 108.692754 -432.776543) (xy 108.629516 -432.617449) (xy 108.57387 -432.455542)
			(xy 108.52594 -432.291187) (xy 108.485833 -432.124749) (xy 108.453638 -431.956601) (xy 108.429428 -431.78712)
			(xy 108.413257 -431.616683) (xy 108.405161 -431.445673) (xy 108.40466 -431.360072) (xy 90.235024 -431.360072)
			(xy 90.235024 -432.560476) (xy 90.234563 -432.572581) (xy 90.227074 -432.595604) (xy 90.212823 -432.615175)
			(xy 90.193212 -432.629371) (xy 90.170168 -432.636797) (xy 90.158062 -432.637184) (xy 89.218262 -432.637184)
			(xy 89.206173 -432.636726) (xy 89.183175 -432.629261) (xy 89.163598 -432.615072) (xy 89.149348 -432.595538)
			(xy 89.141812 -432.572564) (xy 89.1413 -432.560476) (xy 89.1413 -432.044094) (xy 89.130616 -432.006448)
			(xy 89.119137 -431.929042) (xy 89.11844 -431.889916) (xy 86.235032 -431.889916) (xy 86.235032 -432.560476)
			(xy 86.234563 -432.57258) (xy 86.227075 -432.595601) (xy 86.212825 -432.615172) (xy 86.193217 -432.629369)
			(xy 86.170175 -432.636796) (xy 86.15807 -432.637184) (xy 85.21827 -432.637184) (xy 85.206181 -432.636719)
			(xy 85.183184 -432.629257) (xy 85.163606 -432.615069) (xy 85.149356 -432.595537) (xy 85.14182 -432.572563)
			(xy 85.141308 -432.560476) (xy 85.141308 -432.044094) (xy 85.130624 -432.006448) (xy 85.119145 -431.929042)
			(xy 85.118448 -431.889916) (xy 82.23504 -431.889916) (xy 82.23504 -432.560476) (xy 82.234564 -432.57258)
			(xy 82.227076 -432.595599) (xy 82.212828 -432.615169) (xy 82.193222 -432.629366) (xy 82.170183 -432.636795)
			(xy 82.158078 -432.637184) (xy 81.218278 -432.637184) (xy 81.20619 -432.636712) (xy 81.183192 -432.629252)
			(xy 81.163615 -432.615066) (xy 81.149364 -432.595535) (xy 81.141828 -432.572563) (xy 81.141316 -432.560476)
			(xy 81.141316 -432.044094) (xy 81.130632 -432.006448) (xy 81.119153 -431.929042) (xy 81.118456 -431.889916)
			(xy 78.235048 -431.889916) (xy 78.235048 -432.560476) (xy 78.234564 -432.572579) (xy 78.227077 -432.595597)
			(xy 78.212831 -432.615166) (xy 78.193227 -432.629364) (xy 78.17019 -432.636793) (xy 78.158086 -432.637184)
			(xy 77.218286 -432.637184) (xy 77.206198 -432.636705) (xy 77.183201 -432.629248) (xy 77.163623 -432.615063)
			(xy 77.149372 -432.595534) (xy 77.141836 -432.572562) (xy 77.141324 -432.560476) (xy 77.141324 -432.044094)
			(xy 77.13064 -432.006448) (xy 77.119161 -431.929042) (xy 77.118464 -431.889916) (xy 73.234804 -431.889916)
			(xy 73.234804 -432.560476) (xy 73.234367 -432.572558) (xy 73.226905 -432.59554) (xy 73.212706 -432.615091)
			(xy 73.193158 -432.629296) (xy 73.170178 -432.636764) (xy 73.158096 -432.637184) (xy 72.218296 -432.637184)
			(xy 72.206211 -432.636791) (xy 72.183224 -432.629319) (xy 72.163671 -432.615109) (xy 72.149468 -432.595551)
			(xy 72.142005 -432.572562) (xy 72.141588 -432.560476) (xy 72.141588 -432.044856) (xy 72.130792 -432.007034)
			(xy 72.119183 -431.929242) (xy 72.118474 -431.889916) (xy 69.234812 -431.889916) (xy 69.234812 -432.560476)
			(xy 69.234367 -432.572557) (xy 69.226906 -432.595538) (xy 69.212709 -432.615089) (xy 69.193163 -432.629294)
			(xy 69.170185 -432.636762) (xy 69.158104 -432.637184) (xy 68.218304 -432.637184) (xy 68.206219 -432.636784)
			(xy 68.183232 -432.629314) (xy 68.16368 -432.615106) (xy 68.149476 -432.59555) (xy 68.142013 -432.572561)
			(xy 68.141596 -432.560476) (xy 68.141596 -432.044856) (xy 68.1308 -432.007034) (xy 68.119191 -431.929242)
			(xy 68.118482 -431.889916) (xy 65.23482 -431.889916) (xy 65.23482 -432.560476) (xy 65.234367 -432.572556)
			(xy 65.226907 -432.595536) (xy 65.212711 -432.615086) (xy 65.193168 -432.629291) (xy 65.170192 -432.636761)
			(xy 65.158112 -432.637184) (xy 64.218312 -432.637184) (xy 64.206228 -432.636777) (xy 64.183241 -432.629309)
			(xy 64.163689 -432.615103) (xy 64.149485 -432.595548) (xy 64.142022 -432.572561) (xy 64.141604 -432.560476)
			(xy 64.141604 -432.044856) (xy 64.130808 -432.007034) (xy 64.119199 -431.929242) (xy 64.11849 -431.889916)
			(xy 61.234828 -431.889916) (xy 61.234828 -432.560476) (xy 61.234367 -432.572555) (xy 61.226909 -432.595534)
			(xy 61.212714 -432.615083) (xy 61.193173 -432.629288) (xy 61.170199 -432.63676) (xy 61.15812 -432.637184)
			(xy 60.21832 -432.637184) (xy 60.206236 -432.63677) (xy 60.18325 -432.629305) (xy 60.163697 -432.6151)
			(xy 60.149493 -432.595547) (xy 60.14203 -432.57256) (xy 60.141612 -432.560476) (xy 60.141612 -432.044856)
			(xy 60.130817 -432.007033) (xy 60.119207 -431.929242) (xy 60.118498 -431.889916) (xy 7.00913 -431.889916)
			(xy 7.00913 -434.48986) (xy 58.13806 -434.48986) (xy 58.138173 -434.474774) (xy 58.139952 -434.444656)
			(xy 58.141616 -434.429662) (xy 58.141616 -433.350162) (xy 58.139951 -433.335168) (xy 58.13817 -433.30505)
			(xy 58.13806 -433.289964) (xy 58.138173 -433.274878) (xy 58.139952 -433.24476) (xy 58.141616 -433.229766)
			(xy 58.141616 -432.618896) (xy 58.142009 -432.606811) (xy 58.149481 -432.583824) (xy 58.163691 -432.564271)
			(xy 58.183249 -432.550068) (xy 58.206238 -432.542605) (xy 58.218324 -432.542188) (xy 59.158124 -432.542188)
			(xy 59.170199 -432.542644) (xy 59.193167 -432.550113) (xy 59.212703 -432.564311) (xy 59.226897 -432.583851)
			(xy 59.234359 -432.606821) (xy 59.234832 -432.618896) (xy 59.234832 -435.16042) (xy 59.234353 -435.172493)
			(xy 59.226888 -435.195457) (xy 59.212694 -435.214991) (xy 59.19316 -435.229186) (xy 59.170197 -435.236652)
			(xy 59.158124 -435.237128) (xy 58.218324 -435.237128) (xy 58.206245 -435.236667) (xy 58.183266 -435.229209)
			(xy 58.163717 -435.215014) (xy 58.149512 -435.195473) (xy 58.14204 -435.172499) (xy 58.141616 -435.16042)
			(xy 58.141616 -434.550058) (xy 58.13995 -434.535064) (xy 58.13817 -434.504946) (xy 58.13806 -434.48986)
			(xy 7.00913 -434.48986) (xy 7.00913 -435.489858) (xy 60.138056 -435.489858) (xy 60.138169 -435.474772)
			(xy 60.139948 -435.444654) (xy 60.141612 -435.42966) (xy 60.141612 -434.35016) (xy 60.139947 -434.335166)
			(xy 60.138166 -434.305048) (xy 60.138056 -434.289962) (xy 60.138169 -434.274876) (xy 60.139948 -434.244758)
			(xy 60.141612 -434.229764) (xy 60.141612 -433.618894) (xy 60.142102 -433.606807) (xy 60.149557 -433.583811)
			(xy 60.163739 -433.564234) (xy 60.183265 -433.549982) (xy 60.206235 -433.542445) (xy 60.21832 -433.541932)
			(xy 61.15812 -433.541932) (xy 61.170233 -433.5423) (xy 61.193267 -433.549808) (xy 61.212842 -433.564081)
			(xy 61.227035 -433.583715) (xy 61.234449 -433.606779) (xy 61.234828 -433.618894) (xy 61.234828 -434.48986)
			(xy 62.138052 -434.48986) (xy 62.138165 -434.474774) (xy 62.139944 -434.444656) (xy 62.141608 -434.429662)
			(xy 62.141608 -433.350162) (xy 62.139943 -433.335168) (xy 62.138162 -433.30505) (xy 62.138052 -433.289964)
			(xy 62.138165 -433.274878) (xy 62.139944 -433.24476) (xy 62.141608 -433.229766) (xy 62.141608 -432.618896)
			(xy 62.142009 -432.606811) (xy 62.14948 -432.583826) (xy 62.163688 -432.564274) (xy 62.183244 -432.550071)
			(xy 62.206231 -432.542606) (xy 62.218316 -432.542188) (xy 63.158116 -432.542188) (xy 63.170191 -432.542651)
			(xy 63.193158 -432.550117) (xy 63.212694 -432.564314) (xy 63.226888 -432.583853) (xy 63.234351 -432.606821)
			(xy 63.234824 -432.618896) (xy 63.234824 -435.16042) (xy 63.234353 -435.172494) (xy 63.226887 -435.195459)
			(xy 63.212691 -435.214994) (xy 63.193155 -435.229189) (xy 63.17019 -435.236654) (xy 63.158116 -435.237128)
			(xy 62.218316 -435.237128) (xy 62.206244 -435.236622) (xy 62.183281 -435.229167) (xy 62.163745 -435.21498)
			(xy 62.14955 -435.195451) (xy 62.142083 -435.172492) (xy 62.141608 -435.16042) (xy 62.141608 -434.550058)
			(xy 62.139942 -434.535064) (xy 62.138162 -434.504946) (xy 62.138052 -434.48986) (xy 61.234828 -434.48986)
			(xy 61.234828 -435.489858) (xy 64.138048 -435.489858) (xy 64.138161 -435.474772) (xy 64.13994 -435.444654)
			(xy 64.141604 -435.42966) (xy 64.141604 -434.35016) (xy 64.139938 -434.335166) (xy 64.138158 -434.305048)
			(xy 64.138048 -434.289962) (xy 64.138161 -434.274876) (xy 64.13994 -434.244758) (xy 64.141604 -434.229764)
			(xy 64.141604 -433.618894) (xy 64.142102 -433.606808) (xy 64.149556 -433.583813) (xy 64.163736 -433.564236)
			(xy 64.18326 -433.549985) (xy 64.206228 -433.542447) (xy 64.218312 -433.541932) (xy 65.158112 -433.541932)
			(xy 65.170225 -433.542306) (xy 65.193258 -433.549813) (xy 65.212834 -433.564084) (xy 65.227027 -433.583717)
			(xy 65.234441 -433.60678) (xy 65.23482 -433.618894) (xy 65.23482 -434.48986) (xy 66.138044 -434.48986)
			(xy 66.138157 -434.474774) (xy 66.139936 -434.444656) (xy 66.1416 -434.429662) (xy 66.1416 -433.350162)
			(xy 66.139935 -433.335168) (xy 66.138154 -433.30505) (xy 66.138044 -433.289964) (xy 66.138157 -433.274878)
			(xy 66.139936 -433.24476) (xy 66.1416 -433.229766) (xy 66.1416 -432.618896) (xy 66.142009 -432.606812)
			(xy 66.149479 -432.583828) (xy 66.163686 -432.564277) (xy 66.183239 -432.550073) (xy 66.206224 -432.542607)
			(xy 66.218308 -432.542188) (xy 67.158108 -432.542188) (xy 67.170183 -432.542657) (xy 67.193149 -432.550122)
			(xy 67.212686 -432.564317) (xy 67.22688 -432.583854) (xy 67.234343 -432.606821) (xy 67.234816 -432.618896)
			(xy 67.234816 -435.16042) (xy 67.234353 -435.172495) (xy 67.226886 -435.195461) (xy 67.212689 -435.214997)
			(xy 67.19315 -435.229191) (xy 67.170183 -435.236655) (xy 67.158108 -435.237128) (xy 66.218308 -435.237128)
			(xy 66.206236 -435.236629) (xy 66.183272 -435.229171) (xy 66.163737 -435.214983) (xy 66.149541 -435.195453)
			(xy 66.142075 -435.172492) (xy 66.1416 -435.16042) (xy 66.1416 -434.550058) (xy 66.139934 -434.535064)
			(xy 66.138154 -434.504946) (xy 66.138044 -434.48986) (xy 65.23482 -434.48986) (xy 65.23482 -435.489858)
			(xy 68.13804 -435.489858) (xy 68.138153 -435.474772) (xy 68.139932 -435.444654) (xy 68.141596 -435.42966)
			(xy 68.141596 -434.35016) (xy 68.13993 -434.335166) (xy 68.13815 -434.305048) (xy 68.13804 -434.289962)
			(xy 68.138153 -434.274876) (xy 68.139932 -434.244758) (xy 68.141596 -434.229764) (xy 68.141596 -433.618894)
			(xy 68.142102 -433.606809) (xy 68.149555 -433.583815) (xy 68.163733 -433.564239) (xy 68.183255 -433.549987)
			(xy 68.20622 -433.542448) (xy 68.218304 -433.541932) (xy 69.158104 -433.541932) (xy 69.170216 -433.542313)
			(xy 69.193249 -433.549818) (xy 69.212825 -433.564087) (xy 69.227018 -433.583718) (xy 69.234433 -433.60678)
			(xy 69.234812 -433.618894) (xy 69.234812 -434.48986) (xy 70.138036 -434.48986) (xy 70.138151 -434.474775)
			(xy 70.13993 -434.444656) (xy 70.141592 -434.429662) (xy 70.141592 -433.350162) (xy 70.139927 -433.335168)
			(xy 70.138146 -433.30505) (xy 70.138036 -433.289964) (xy 70.138152 -433.274879) (xy 70.13993 -433.24476)
			(xy 70.141592 -433.229766) (xy 70.141592 -432.618896) (xy 70.142061 -432.606821) (xy 70.149524 -432.583854)
			(xy 70.16372 -432.564317) (xy 70.183258 -432.550123) (xy 70.206225 -432.54266) (xy 70.2183 -432.542188)
			(xy 71.1581 -432.542188) (xy 71.170174 -432.542664) (xy 71.193141 -432.550126) (xy 71.212677 -432.56432)
			(xy 71.226872 -432.583856) (xy 71.234335 -432.606822) (xy 71.234808 -432.618896) (xy 71.234808 -435.16042)
			(xy 71.234353 -435.172496) (xy 71.226885 -435.195463) (xy 71.212686 -435.215) (xy 71.193145 -435.229194)
			(xy 71.170176 -435.236656) (xy 71.1581 -435.237128) (xy 70.2183 -435.237128) (xy 70.206227 -435.236636)
			(xy 70.183264 -435.229176) (xy 70.163728 -435.214986) (xy 70.149533 -435.195454) (xy 70.142067 -435.172492)
			(xy 70.141592 -435.16042) (xy 70.141592 -434.550058) (xy 70.139926 -434.535064) (xy 70.138146 -434.504946)
			(xy 70.138036 -434.48986) (xy 69.234812 -434.48986) (xy 69.234812 -435.489858) (xy 72.138032 -435.489858)
			(xy 72.138147 -435.474773) (xy 72.139926 -435.444654) (xy 72.141588 -435.42966) (xy 72.141588 -434.35016)
			(xy 72.139922 -434.335166) (xy 72.138142 -434.305048) (xy 72.138032 -434.289962) (xy 72.138147 -434.274877)
			(xy 72.139926 -434.244758) (xy 72.141588 -434.229764) (xy 72.141588 -433.618894) (xy 72.142003 -433.606799)
			(xy 72.149468 -433.583791) (xy 72.163666 -433.564207) (xy 72.183213 -433.549958) (xy 72.206203 -433.542435)
			(xy 72.218296 -433.541932) (xy 73.158096 -433.541932) (xy 73.170208 -433.54232) (xy 73.193241 -433.549822)
			(xy 73.212817 -433.56409) (xy 73.22701 -433.58372) (xy 73.234425 -433.606781) (xy 73.234804 -433.618894)
			(xy 73.234804 -434.48986) (xy 75.138026 -434.48986) (xy 75.138124 -434.475286) (xy 75.139774 -434.446185)
			(xy 75.141328 -434.431694) (xy 75.141328 -433.34813) (xy 75.13978 -433.333638) (xy 75.13813 -433.304538)
			(xy 75.138026 -433.289964) (xy 75.138124 -433.27539) (xy 75.139774 -433.246289) (xy 75.141328 -433.231798)
			(xy 75.141328 -432.618896) (xy 75.141713 -432.606784) (xy 75.149217 -432.583752) (xy 75.163486 -432.564176)
			(xy 75.183116 -432.549983) (xy 75.206177 -432.542567) (xy 75.21829 -432.542188) (xy 76.15809 -432.542188)
			(xy 76.170184 -432.542617) (xy 76.193192 -432.550077) (xy 76.212776 -432.564271) (xy 76.227025 -432.583816)
			(xy 76.234549 -432.606804) (xy 76.235052 -432.618896) (xy 76.235052 -435.16042) (xy 76.234601 -435.172525)
			(xy 76.227103 -435.195544) (xy 76.212848 -435.215112) (xy 76.193237 -435.229308) (xy 76.170196 -435.236737)
			(xy 76.15809 -435.237128) (xy 75.21829 -435.237128) (xy 75.206197 -435.2367) (xy 75.183191 -435.229237)
			(xy 75.163608 -435.215041) (xy 75.149359 -435.195498) (xy 75.141833 -435.172512) (xy 75.141328 -435.16042)
			(xy 75.141328 -434.548026) (xy 75.13978 -434.533534) (xy 75.13813 -434.504434) (xy 75.138026 -434.48986)
			(xy 73.234804 -434.48986) (xy 73.234804 -435.489858) (xy 77.138022 -435.489858) (xy 77.13812 -435.475284)
			(xy 77.13977 -435.446183) (xy 77.141324 -435.431692) (xy 77.141324 -434.348128) (xy 77.139776 -434.333636)
			(xy 77.138126 -434.304536) (xy 77.138022 -434.289962) (xy 77.13812 -434.275388) (xy 77.13977 -434.246287)
			(xy 77.141324 -434.231796) (xy 77.141324 -433.618894) (xy 77.141807 -433.606781) (xy 77.149294 -433.58374)
			(xy 77.163534 -433.564139) (xy 77.183132 -433.549897) (xy 77.206173 -433.542408) (xy 77.218286 -433.541932)
			(xy 78.158086 -433.541932) (xy 78.170207 -433.542372) (xy 78.193265 -433.54986) (xy 78.21288 -433.564106)
			(xy 78.227131 -433.583717) (xy 78.234625 -433.606773) (xy 78.235048 -433.618894) (xy 78.235048 -434.48986)
			(xy 79.138018 -434.48986) (xy 79.138116 -434.475286) (xy 79.139766 -434.446185) (xy 79.14132 -434.431694)
			(xy 79.14132 -433.34813) (xy 79.139772 -433.333638) (xy 79.138122 -433.304538) (xy 79.138018 -433.289964)
			(xy 79.138116 -433.27539) (xy 79.139766 -433.246289) (xy 79.14132 -433.231798) (xy 79.14132 -432.618896)
			(xy 79.141713 -432.606785) (xy 79.149216 -432.583754) (xy 79.163483 -432.564179) (xy 79.183111 -432.549985)
			(xy 79.206169 -432.542568) (xy 79.218282 -432.542188) (xy 80.158082 -432.542188) (xy 80.170175 -432.542624)
			(xy 80.193183 -432.550081) (xy 80.212768 -432.564274) (xy 80.227017 -432.583818) (xy 80.234541 -432.606804)
			(xy 80.235044 -432.618896) (xy 80.235044 -435.16042) (xy 80.234601 -435.172526) (xy 80.227102 -435.195546)
			(xy 80.212845 -435.215115) (xy 80.193232 -435.22931) (xy 80.170189 -435.236739) (xy 80.158082 -435.237128)
			(xy 79.218282 -435.237128) (xy 79.206188 -435.236708) (xy 79.183182 -435.229242) (xy 79.163599 -435.215045)
			(xy 79.14935 -435.195499) (xy 79.141824 -435.172512) (xy 79.14132 -435.16042) (xy 79.14132 -434.548026)
			(xy 79.139772 -434.533534) (xy 79.138122 -434.504434) (xy 79.138018 -434.48986) (xy 78.235048 -434.48986)
			(xy 78.235048 -435.489858) (xy 81.138014 -435.489858) (xy 81.138111 -435.475284) (xy 81.139761 -435.446183)
			(xy 81.141316 -435.431692) (xy 81.141316 -434.348128) (xy 81.139768 -434.333636) (xy 81.138118 -434.304536)
			(xy 81.138014 -434.289962) (xy 81.138112 -434.275388) (xy 81.139761 -434.246287) (xy 81.141316 -434.231796)
			(xy 81.141316 -433.618894) (xy 81.141807 -433.606781) (xy 81.149293 -433.583742) (xy 81.163531 -433.564142)
			(xy 81.183127 -433.5499) (xy 81.206165 -433.542409) (xy 81.218278 -433.541932) (xy 82.158078 -433.541932)
			(xy 82.170199 -433.542379) (xy 82.193256 -433.549864) (xy 82.212871 -433.564109) (xy 82.227123 -433.583719)
			(xy 82.234617 -433.606773) (xy 82.23504 -433.618894) (xy 82.23504 -434.48986) (xy 83.13801 -434.48986)
			(xy 83.138107 -434.475286) (xy 83.139757 -434.446185) (xy 83.141312 -434.431694) (xy 83.141312 -433.34813)
			(xy 83.139764 -433.333638) (xy 83.138114 -433.304538) (xy 83.13801 -433.289964) (xy 83.138108 -433.27539)
			(xy 83.139757 -433.246289) (xy 83.141312 -433.231798) (xy 83.141312 -432.618896) (xy 83.141713 -432.606786)
			(xy 83.149215 -432.583756) (xy 83.16348 -432.564182) (xy 83.183106 -432.549988) (xy 83.206162 -432.542569)
			(xy 83.218274 -432.542188) (xy 84.158074 -432.542188) (xy 84.170167 -432.54263) (xy 84.193175 -432.550086)
			(xy 84.212759 -432.564277) (xy 84.227009 -432.583819) (xy 84.234533 -432.606804) (xy 84.235036 -432.618896)
			(xy 84.235036 -435.16042) (xy 84.234601 -435.172526) (xy 84.227101 -435.195548) (xy 84.212843 -435.215118)
			(xy 84.193227 -435.229313) (xy 84.170182 -435.23674) (xy 84.158074 -435.237128) (xy 83.218274 -435.237128)
			(xy 83.20618 -435.236714) (xy 83.183173 -435.229247) (xy 83.163591 -435.215047) (xy 83.149342 -435.195501)
			(xy 83.141816 -435.172513) (xy 83.141312 -435.16042) (xy 83.141312 -434.548026) (xy 83.139764 -434.533534)
			(xy 83.138114 -434.504434) (xy 83.13801 -434.48986) (xy 82.23504 -434.48986) (xy 82.23504 -435.489858)
			(xy 85.138006 -435.489858) (xy 85.138103 -435.475284) (xy 85.139753 -435.446183) (xy 85.141308 -435.431692)
			(xy 85.141308 -434.348128) (xy 85.13976 -434.333636) (xy 85.13811 -434.304536) (xy 85.138006 -434.289962)
			(xy 85.138104 -434.275388) (xy 85.139753 -434.246287) (xy 85.141308 -434.231796) (xy 85.141308 -433.618894)
			(xy 85.141806 -433.606782) (xy 85.149292 -433.583744) (xy 85.163528 -433.564145) (xy 85.183122 -433.549903)
			(xy 85.206158 -433.54241) (xy 85.21827 -433.541932) (xy 86.15807 -433.541932) (xy 86.170191 -433.542385)
			(xy 86.193247 -433.549869) (xy 86.212863 -433.564112) (xy 86.227115 -433.58372) (xy 86.234609 -433.606774)
			(xy 86.235032 -433.618894) (xy 86.235032 -434.48986) (xy 87.138002 -434.48986) (xy 87.1381 -434.475286)
			(xy 87.139749 -434.446185) (xy 87.141304 -434.431694) (xy 87.141304 -433.34813) (xy 87.139756 -433.333638)
			(xy 87.138106 -433.304538) (xy 87.138002 -433.289964) (xy 87.1381 -433.27539) (xy 87.139749 -433.246289)
			(xy 87.141304 -433.231798) (xy 87.141304 -432.618896) (xy 87.141713 -432.606787) (xy 87.149214 -432.583758)
			(xy 87.163477 -432.564185) (xy 87.183101 -432.549991) (xy 87.206155 -432.542571) (xy 87.218266 -432.542188)
			(xy 88.158066 -432.542188) (xy 88.170159 -432.542637) (xy 88.193166 -432.55009) (xy 88.212751 -432.56428)
			(xy 88.227001 -432.583821) (xy 88.234525 -432.606805) (xy 88.235028 -432.618896) (xy 88.235028 -435.16042)
			(xy 88.234601 -435.172527) (xy 88.2271 -435.19555) (xy 88.21284 -435.215121) (xy 88.193222 -435.229316)
			(xy 88.170174 -435.236741) (xy 88.158066 -435.237128) (xy 87.218266 -435.237128) (xy 87.206171 -435.236721)
			(xy 87.183164 -435.229251) (xy 87.163582 -435.21505) (xy 87.149334 -435.195502) (xy 87.141808 -435.172513)
			(xy 87.141304 -435.16042) (xy 87.141304 -434.548026) (xy 87.139756 -434.533534) (xy 87.138106 -434.504434)
			(xy 87.138002 -434.48986) (xy 86.235032 -434.48986) (xy 86.235032 -435.489858) (xy 89.137998 -435.489858)
			(xy 89.138095 -435.475284) (xy 89.139745 -435.446183) (xy 89.1413 -435.431692) (xy 89.1413 -434.348128)
			(xy 89.139752 -434.333636) (xy 89.138102 -434.304536) (xy 89.137998 -434.289962) (xy 89.138096 -434.275388)
			(xy 89.139745 -434.246287) (xy 89.1413 -434.231796) (xy 89.1413 -433.618894) (xy 89.141806 -433.606783)
			(xy 89.14929 -433.583746) (xy 89.163525 -433.564148) (xy 89.183117 -433.549905) (xy 89.206151 -433.542411)
			(xy 89.218262 -433.541932) (xy 90.158062 -433.541932) (xy 90.170182 -433.542392) (xy 90.193239 -433.549873)
			(xy 90.212854 -433.564115) (xy 90.227107 -433.583722) (xy 90.234601 -433.606774) (xy 90.235024 -433.618894)
			(xy 90.235024 -436.160418) (xy 90.234655 -436.172545) (xy 90.227153 -436.195611) (xy 90.212889 -436.215229)
			(xy 90.193261 -436.229478) (xy 90.17019 -436.236963) (xy 90.158062 -436.23738) (xy 89.218262 -436.23738)
			(xy 89.206147 -436.236921) (xy 89.183106 -436.229425) (xy 89.163506 -436.21518) (xy 89.149265 -436.195576)
			(xy 89.141776 -436.172533) (xy 89.1413 -436.160418) (xy 89.1413 -435.548024) (xy 89.139751 -435.533532)
			(xy 89.138102 -435.504432) (xy 89.137998 -435.489858) (xy 86.235032 -435.489858) (xy 86.235032 -436.160418)
			(xy 86.234655 -436.172545) (xy 86.227154 -436.195609) (xy 86.212892 -436.215226) (xy 86.193266 -436.229476)
			(xy 86.170197 -436.236962) (xy 86.15807 -436.23738) (xy 85.21827 -436.23738) (xy 85.206156 -436.236914)
			(xy 85.183114 -436.229421) (xy 85.163515 -436.215177) (xy 85.149274 -436.195575) (xy 85.141784 -436.172532)
			(xy 85.141308 -436.160418) (xy 85.141308 -435.548024) (xy 85.139759 -435.533532) (xy 85.13811 -435.504432)
			(xy 85.138006 -435.489858) (xy 82.23504 -435.489858) (xy 82.23504 -436.160418) (xy 82.234655 -436.172544)
			(xy 82.227155 -436.195607) (xy 82.212895 -436.215224) (xy 82.193271 -436.229473) (xy 82.170204 -436.236961)
			(xy 82.158078 -436.23738) (xy 81.218278 -436.23738) (xy 81.206164 -436.236907) (xy 81.183123 -436.229416)
			(xy 81.163523 -436.215174) (xy 81.149282 -436.195573) (xy 81.141792 -436.172532) (xy 81.141316 -436.160418)
			(xy 81.141316 -435.548024) (xy 81.139767 -435.533532) (xy 81.138118 -435.504432) (xy 81.138014 -435.489858)
			(xy 78.235048 -435.489858) (xy 78.235048 -436.160418) (xy 78.234604 -436.172535) (xy 78.22711 -436.195581)
			(xy 78.212861 -436.215184) (xy 78.193252 -436.229424) (xy 78.170203 -436.236909) (xy 78.158086 -436.23738)
			(xy 77.218286 -436.23738) (xy 77.206172 -436.236901) (xy 77.183132 -436.229412) (xy 77.163532 -436.215171)
			(xy 77.14929 -436.195572) (xy 77.1418 -436.172531) (xy 77.141324 -436.160418) (xy 77.141324 -435.548024)
			(xy 77.139775 -435.533532) (xy 77.138126 -435.504432) (xy 77.138022 -435.489858) (xy 73.234804 -435.489858)
			(xy 73.234804 -436.160418) (xy 73.234309 -436.172504) (xy 73.226853 -436.195498) (xy 73.212672 -436.215074)
			(xy 73.193147 -436.229325) (xy 73.17018 -436.236865) (xy 73.158096 -436.23738) (xy 72.218296 -436.23738)
			(xy 72.206185 -436.236987) (xy 72.183154 -436.229484) (xy 72.163579 -436.215217) (xy 72.149385 -436.195589)
			(xy 72.141968 -436.172531) (xy 72.141588 -436.160418) (xy 72.141588 -435.550056) (xy 72.139922 -435.535062)
			(xy 72.138142 -435.504944) (xy 72.138032 -435.489858) (xy 69.234812 -435.489858) (xy 69.234812 -436.160418)
			(xy 69.234407 -436.172513) (xy 69.22694 -436.195523) (xy 69.212739 -436.215106) (xy 69.193189 -436.229355)
			(xy 69.170198 -436.236878) (xy 69.158104 -436.23738) (xy 68.218304 -436.23738) (xy 68.206193 -436.23698)
			(xy 68.183163 -436.229479) (xy 68.163588 -436.215214) (xy 68.149394 -436.195588) (xy 68.141976 -436.17253)
			(xy 68.141596 -436.160418) (xy 68.141596 -435.550056) (xy 68.13993 -435.535062) (xy 68.13815 -435.504944)
			(xy 68.13804 -435.489858) (xy 65.23482 -435.489858) (xy 65.23482 -436.160418) (xy 65.234407 -436.172513)
			(xy 65.226941 -436.195521) (xy 65.212742 -436.215104) (xy 65.193194 -436.229352) (xy 65.170205 -436.236877)
			(xy 65.158112 -436.23738) (xy 64.218312 -436.23738) (xy 64.206202 -436.236973) (xy 64.183172 -436.229474)
			(xy 64.163597 -436.215211) (xy 64.149402 -436.195586) (xy 64.141985 -436.17253) (xy 64.141604 -436.160418)
			(xy 64.141604 -435.550056) (xy 64.139938 -435.535062) (xy 64.138158 -435.504944) (xy 64.138048 -435.489858)
			(xy 61.234828 -435.489858) (xy 61.234828 -436.160418) (xy 61.234408 -436.172512) (xy 61.226942 -436.195518)
			(xy 61.212745 -436.215101) (xy 61.193199 -436.22935) (xy 61.170212 -436.236876) (xy 61.15812 -436.23738)
			(xy 60.21832 -436.23738) (xy 60.20621 -436.236966) (xy 60.18318 -436.22947) (xy 60.163605 -436.215208)
			(xy 60.149411 -436.195585) (xy 60.141993 -436.172529) (xy 60.141612 -436.160418) (xy 60.141612 -435.550056)
			(xy 60.139946 -435.535062) (xy 60.138166 -435.504944) (xy 60.138056 -435.489858) (xy 7.00913 -435.489858)
			(xy 7.00913 -438.089802) (xy 58.13806 -438.089802) (xy 58.138177 -438.074717) (xy 58.139953 -438.044598)
			(xy 58.141616 -438.029604) (xy 58.141616 -436.950104) (xy 58.139946 -436.935111) (xy 58.138168 -436.904992)
			(xy 58.13806 -436.889906) (xy 58.138168 -436.87482) (xy 58.13995 -436.844702) (xy 58.141616 -436.829708)
			(xy 58.141616 -436.219092) (xy 58.142006 -436.207006) (xy 58.149479 -436.184019) (xy 58.16369 -436.164467)
			(xy 58.183248 -436.150264) (xy 58.206238 -436.142801) (xy 58.218324 -436.142384) (xy 59.158124 -436.142384)
			(xy 59.170199 -436.142844) (xy 59.193166 -436.150312) (xy 59.212701 -436.16451) (xy 59.226895 -436.184049)
			(xy 59.234359 -436.207017) (xy 59.234832 -436.219092) (xy 59.234832 -438.760616) (xy 59.23435 -438.772689)
			(xy 59.226886 -438.795653) (xy 59.212693 -438.815187) (xy 59.19316 -438.829382) (xy 59.170197 -438.836848)
			(xy 59.158124 -438.837324) (xy 58.218324 -438.837324) (xy 58.206244 -438.836867) (xy 58.183265 -438.829408)
			(xy 58.163716 -438.815213) (xy 58.14951 -438.795671) (xy 58.142039 -438.772696) (xy 58.141616 -438.760616)
			(xy 58.141616 -438.15) (xy 58.139945 -438.135007) (xy 58.138168 -438.104888) (xy 58.13806 -438.089802)
			(xy 7.00913 -438.089802) (xy 7.00913 -439.0898) (xy 60.138056 -439.0898) (xy 60.138173 -439.074715)
			(xy 60.139949 -439.044596) (xy 60.141612 -439.029602) (xy 60.141612 -437.950102) (xy 60.139941 -437.935109)
			(xy 60.138164 -437.90499) (xy 60.138056 -437.889904) (xy 60.138173 -437.874819) (xy 60.139949 -437.8447)
			(xy 60.141612 -437.829706) (xy 60.141612 -437.21909) (xy 60.142099 -437.207003) (xy 60.149555 -437.184007)
			(xy 60.163737 -437.164429) (xy 60.183265 -437.150178) (xy 60.206234 -437.142641) (xy 60.21832 -437.142128)
			(xy 61.15812 -437.142128) (xy 61.170233 -437.1425) (xy 61.193265 -437.150008) (xy 61.212841 -437.16428)
			(xy 61.227034 -437.183913) (xy 61.234449 -437.206976) (xy 61.234828 -437.21909) (xy 61.234828 -438.089802)
			(xy 62.138052 -438.089802) (xy 62.138169 -438.074717) (xy 62.139945 -438.044598) (xy 62.141608 -438.029604)
			(xy 62.141608 -436.950104) (xy 62.139938 -436.935111) (xy 62.13816 -436.904992) (xy 62.138052 -436.889906)
			(xy 62.13816 -436.87482) (xy 62.139942 -436.844702) (xy 62.141608 -436.829708) (xy 62.141608 -436.219092)
			(xy 62.142006 -436.207007) (xy 62.149478 -436.184021) (xy 62.163687 -436.16447) (xy 62.183243 -436.150267)
			(xy 62.206231 -436.142802) (xy 62.218316 -436.142384) (xy 63.158116 -436.142384) (xy 63.170191 -436.142851)
			(xy 63.193157 -436.150317) (xy 63.212693 -436.164513) (xy 63.226887 -436.18405) (xy 63.234351 -436.207017)
			(xy 63.234824 -436.219092) (xy 63.234824 -438.760616) (xy 63.23435 -438.77269) (xy 63.226885 -438.795655)
			(xy 63.21269 -438.81519) (xy 63.193155 -438.829385) (xy 63.17019 -438.83685) (xy 63.158116 -438.837324)
			(xy 62.218316 -438.837324) (xy 62.206244 -438.836822) (xy 62.18328 -438.829366) (xy 62.163744 -438.815179)
			(xy 62.149548 -438.795649) (xy 62.142083 -438.772688) (xy 62.141608 -438.760616) (xy 62.141608 -438.15)
			(xy 62.139937 -438.135007) (xy 62.13816 -438.104888) (xy 62.138052 -438.089802) (xy 61.234828 -438.089802)
			(xy 61.234828 -439.0898) (xy 64.138048 -439.0898) (xy 64.138165 -439.074715) (xy 64.139941 -439.044596)
			(xy 64.141604 -439.029602) (xy 64.141604 -437.950102) (xy 64.139933 -437.935109) (xy 64.138156 -437.90499)
			(xy 64.138048 -437.889904) (xy 64.138165 -437.874819) (xy 64.139941 -437.8447) (xy 64.141604 -437.829706)
			(xy 64.141604 -437.21909) (xy 64.142098 -437.207004) (xy 64.149553 -437.184009) (xy 64.163734 -437.164432)
			(xy 64.18326 -437.150181) (xy 64.206227 -437.142643) (xy 64.218312 -437.142128) (xy 65.158112 -437.142128)
			(xy 65.170224 -437.142506) (xy 65.193257 -437.150012) (xy 65.212832 -437.164283) (xy 65.227025 -437.183914)
			(xy 65.234441 -437.206976) (xy 65.23482 -437.21909) (xy 65.23482 -438.089802) (xy 66.138044 -438.089802)
			(xy 66.138161 -438.074717) (xy 66.139937 -438.044598) (xy 66.1416 -438.029604) (xy 66.1416 -436.950104)
			(xy 66.13993 -436.935111) (xy 66.138152 -436.904992) (xy 66.138044 -436.889906) (xy 66.138152 -436.87482)
			(xy 66.139934 -436.844702) (xy 66.1416 -436.829708) (xy 66.1416 -436.219092) (xy 66.142058 -436.207016)
			(xy 66.149523 -436.184047) (xy 66.163721 -436.16451) (xy 66.183262 -436.150316) (xy 66.206232 -436.142855)
			(xy 66.218308 -436.142384) (xy 67.158108 -436.142384) (xy 67.170182 -436.142857) (xy 67.193148 -436.150321)
			(xy 67.212684 -436.164516) (xy 67.226879 -436.184052) (xy 67.234343 -436.207018) (xy 67.234816 -436.219092)
			(xy 67.234816 -438.760616) (xy 67.234349 -438.772691) (xy 67.226883 -438.795657) (xy 67.212687 -438.815193)
			(xy 67.19315 -438.829387) (xy 67.170183 -438.836851) (xy 67.158108 -438.837324) (xy 66.218308 -438.837324)
			(xy 66.206235 -438.836829) (xy 66.183271 -438.829371) (xy 66.163735 -438.815182) (xy 66.14954 -438.79565)
			(xy 66.142075 -438.772688) (xy 66.1416 -438.760616) (xy 66.1416 -438.15) (xy 66.139929 -438.135007)
			(xy 66.138152 -438.104888) (xy 66.138044 -438.089802) (xy 65.23482 -438.089802) (xy 65.23482 -439.0898)
			(xy 68.13804 -439.0898) (xy 68.138157 -439.074715) (xy 68.139933 -439.044596) (xy 68.141596 -439.029602)
			(xy 68.141596 -437.950102) (xy 68.139925 -437.935109) (xy 68.138148 -437.90499) (xy 68.13804 -437.889904)
			(xy 68.138157 -437.874819) (xy 68.139933 -437.8447) (xy 68.141596 -437.829706) (xy 68.141596 -437.21909)
			(xy 68.142098 -437.207004) (xy 68.149552 -437.184011) (xy 68.163731 -437.164435) (xy 68.183255 -437.150183)
			(xy 68.20622 -437.142644) (xy 68.218304 -437.142128) (xy 69.158104 -437.142128) (xy 69.170216 -437.142513)
			(xy 69.193248 -437.150017) (xy 69.212824 -437.164286) (xy 69.227017 -437.183916) (xy 69.234433 -437.206977)
			(xy 69.234812 -437.21909) (xy 69.234812 -438.089802) (xy 70.138036 -438.089802) (xy 70.138153 -438.074717)
			(xy 70.139929 -438.044598) (xy 70.141592 -438.029604) (xy 70.141592 -436.950104) (xy 70.139922 -436.935111)
			(xy 70.138144 -436.904992) (xy 70.138036 -436.889906) (xy 70.138146 -436.87482) (xy 70.139928 -436.844702)
			(xy 70.141592 -436.829708) (xy 70.141592 -436.219092) (xy 70.142058 -436.207017) (xy 70.149522 -436.18405)
			(xy 70.163718 -436.164513) (xy 70.183257 -436.150319) (xy 70.206225 -436.142856) (xy 70.2183 -436.142384)
			(xy 71.1581 -436.142384) (xy 71.170174 -436.142864) (xy 71.19314 -436.150326) (xy 71.212676 -436.164518)
			(xy 71.226871 -436.184053) (xy 71.234335 -436.207018) (xy 71.234808 -436.219092) (xy 71.234808 -438.760616)
			(xy 71.234349 -438.772691) (xy 71.226882 -438.795659) (xy 71.212684 -438.815196) (xy 71.193145 -438.82939)
			(xy 71.170175 -438.836852) (xy 71.1581 -438.837324) (xy 70.2183 -438.837324) (xy 70.206227 -438.836836)
			(xy 70.183263 -438.829375) (xy 70.163727 -438.815184) (xy 70.149532 -438.795652) (xy 70.142067 -438.772689)
			(xy 70.141592 -438.760616) (xy 70.141592 -438.15) (xy 70.139921 -438.135007) (xy 70.138144 -438.104888)
			(xy 70.138036 -438.089802) (xy 69.234812 -438.089802) (xy 69.234812 -439.0898) (xy 72.138032 -439.0898)
			(xy 72.138151 -439.074715) (xy 72.139927 -439.044596) (xy 72.141588 -439.029602) (xy 72.141588 -437.950102)
			(xy 72.139917 -437.935109) (xy 72.13814 -437.90499) (xy 72.138032 -437.889904) (xy 72.138151 -437.874819)
			(xy 72.139927 -437.8447) (xy 72.141588 -437.829706) (xy 72.141588 -437.21909) (xy 72.142 -437.206995)
			(xy 72.149465 -437.183986) (xy 72.163664 -437.164402) (xy 72.183212 -437.150154) (xy 72.206202 -437.142631)
			(xy 72.218296 -437.142128) (xy 73.158096 -437.142128) (xy 73.170207 -437.14252) (xy 73.193239 -437.150022)
			(xy 73.212815 -437.164288) (xy 73.227009 -437.183917) (xy 73.234425 -437.206977) (xy 73.234804 -437.21909)
			(xy 73.234804 -438.089802) (xy 75.138026 -438.089802) (xy 75.138119 -438.075228) (xy 75.139772 -438.046127)
			(xy 75.141328 -438.031636) (xy 75.141328 -436.948072) (xy 75.139784 -436.93358) (xy 75.138131 -436.90448)
			(xy 75.138026 -436.889906) (xy 75.138119 -436.875332) (xy 75.139772 -436.846231) (xy 75.141328 -436.83174)
			(xy 75.141328 -436.219092) (xy 75.14171 -436.20698) (xy 75.149215 -436.183948) (xy 75.163484 -436.164372)
			(xy 75.183115 -436.150179) (xy 75.206176 -436.142763) (xy 75.21829 -436.142384) (xy 76.15809 -436.142384)
			(xy 76.170183 -436.142817) (xy 76.193191 -436.150276) (xy 76.212775 -436.16447) (xy 76.227024 -436.184014)
			(xy 76.234549 -436.207) (xy 76.235052 -436.219092) (xy 76.235052 -438.760616) (xy 76.234598 -438.772721)
			(xy 76.227101 -438.795739) (xy 76.212847 -438.815308) (xy 76.193237 -438.829504) (xy 76.170196 -438.836933)
			(xy 76.15809 -438.837324) (xy 75.21829 -438.837324) (xy 75.206196 -438.8369) (xy 75.183189 -438.829436)
			(xy 75.163607 -438.81524) (xy 75.149358 -438.795695) (xy 75.141832 -438.772708) (xy 75.141328 -438.760616)
			(xy 75.141328 -438.147968) (xy 75.139783 -438.133476) (xy 75.138131 -438.104376) (xy 75.138026 -438.089802)
			(xy 73.234804 -438.089802) (xy 73.234804 -439.0898) (xy 77.138022 -439.0898) (xy 77.138115 -439.075226)
			(xy 77.139768 -439.046125) (xy 77.141324 -439.031634) (xy 77.141324 -437.94807) (xy 77.139779 -437.933578)
			(xy 77.138127 -437.904478) (xy 77.138022 -437.889904) (xy 77.138115 -437.87533) (xy 77.139768 -437.846229)
			(xy 77.141324 -437.831738) (xy 77.141324 -437.21909) (xy 77.141803 -437.206976) (xy 77.149291 -437.183935)
			(xy 77.163532 -437.164335) (xy 77.183132 -437.150093) (xy 77.206172 -437.142604) (xy 77.218286 -437.142128)
			(xy 78.158086 -437.142128) (xy 78.170207 -437.142572) (xy 78.193264 -437.150059) (xy 78.212878 -437.164305)
			(xy 78.22713 -437.183915) (xy 78.234624 -437.206969) (xy 78.235048 -437.21909) (xy 78.235048 -438.089802)
			(xy 79.138018 -438.089802) (xy 79.138111 -438.075228) (xy 79.139764 -438.046127) (xy 79.14132 -438.031636)
			(xy 79.14132 -436.948072) (xy 79.139776 -436.93358) (xy 79.138123 -436.90448) (xy 79.138018 -436.889906)
			(xy 79.138111 -436.875332) (xy 79.139764 -436.846231) (xy 79.14132 -436.83174) (xy 79.14132 -436.219092)
			(xy 79.14171 -436.206981) (xy 79.149214 -436.18395) (xy 79.163481 -436.164375) (xy 79.18311 -436.150181)
			(xy 79.206169 -436.142764) (xy 79.218282 -436.142384) (xy 80.158082 -436.142384) (xy 80.170175 -436.142824)
			(xy 80.193182 -436.150281) (xy 80.212766 -436.164473) (xy 80.227016 -436.184015) (xy 80.234541 -436.207)
			(xy 80.235044 -436.219092) (xy 80.235044 -438.760616) (xy 80.234598 -438.772721) (xy 80.227099 -438.795742)
			(xy 80.212844 -438.815311) (xy 80.193232 -438.829506) (xy 80.170189 -438.836935) (xy 80.158082 -438.837324)
			(xy 79.218282 -438.837324) (xy 79.206188 -438.836907) (xy 79.183181 -438.829441) (xy 79.163598 -438.815243)
			(xy 79.149349 -438.795697) (xy 79.141824 -438.772709) (xy 79.14132 -438.760616) (xy 79.14132 -438.147968)
			(xy 79.139775 -438.133476) (xy 79.138123 -438.104376) (xy 79.138018 -438.089802) (xy 78.235048 -438.089802)
			(xy 78.235048 -439.0898) (xy 81.138014 -439.0898) (xy 81.138106 -439.075226) (xy 81.13976 -439.046125)
			(xy 81.141316 -439.031634) (xy 81.141316 -437.94807) (xy 81.139771 -437.933578) (xy 81.138119 -437.904478)
			(xy 81.138014 -437.889904) (xy 81.138107 -437.87533) (xy 81.13976 -437.846229) (xy 81.141316 -437.831738)
			(xy 81.141316 -437.21909) (xy 81.141803 -437.206977) (xy 81.14929 -437.183937) (xy 81.163529 -437.164338)
			(xy 81.183127 -437.150096) (xy 81.206165 -437.142605) (xy 81.218278 -437.142128) (xy 82.158078 -437.142128)
			(xy 82.170199 -437.142579) (xy 82.193255 -437.150064) (xy 82.21287 -437.164308) (xy 82.227122 -437.183916)
			(xy 82.234616 -437.20697) (xy 82.23504 -437.21909) (xy 82.23504 -438.089802) (xy 83.13801 -438.089802)
			(xy 83.138103 -438.075228) (xy 83.139756 -438.046127) (xy 83.141312 -438.031636) (xy 83.141312 -436.948072)
			(xy 83.139767 -436.93358) (xy 83.138115 -436.90448) (xy 83.13801 -436.889906) (xy 83.138103 -436.875332)
			(xy 83.139756 -436.846231) (xy 83.141312 -436.83174) (xy 83.141312 -436.219092) (xy 83.14171 -436.206981)
			(xy 83.149213 -436.183952) (xy 83.163479 -436.164378) (xy 83.183105 -436.150184) (xy 83.206162 -436.142765)
			(xy 83.218274 -436.142384) (xy 84.158074 -436.142384) (xy 84.170167 -436.14283) (xy 84.193174 -436.150285)
			(xy 84.212758 -436.164476) (xy 84.227008 -436.184017) (xy 84.234533 -436.207001) (xy 84.235036 -436.219092)
			(xy 84.235036 -438.760616) (xy 84.234598 -438.772722) (xy 84.227098 -438.795744) (xy 84.212841 -438.815313)
			(xy 84.193227 -438.829509) (xy 84.170181 -438.836936) (xy 84.158074 -438.837324) (xy 83.218274 -438.837324)
			(xy 83.206179 -438.836914) (xy 83.183172 -438.829446) (xy 83.163589 -438.815246) (xy 83.149341 -438.795698)
			(xy 83.141816 -438.772709) (xy 83.141312 -438.760616) (xy 83.141312 -438.147968) (xy 83.139767 -438.133476)
			(xy 83.138115 -438.104376) (xy 83.13801 -438.089802) (xy 82.23504 -438.089802) (xy 82.23504 -439.0898)
			(xy 85.138006 -439.0898) (xy 85.138098 -439.075226) (xy 85.139752 -439.046125) (xy 85.141308 -439.031634)
			(xy 85.141308 -437.94807) (xy 85.139763 -437.933578) (xy 85.138111 -437.904478) (xy 85.138006 -437.889904)
			(xy 85.138099 -437.87533) (xy 85.139752 -437.846229) (xy 85.141308 -437.831738) (xy 85.141308 -437.21909)
			(xy 85.141803 -437.206978) (xy 85.149289 -437.18394) (xy 85.163526 -437.164341) (xy 85.183122 -437.150098)
			(xy 85.206158 -437.142606) (xy 85.21827 -437.142128) (xy 86.15807 -437.142128) (xy 86.17019 -437.142585)
			(xy 86.193246 -437.150068) (xy 86.212861 -437.16431) (xy 86.227114 -437.183918) (xy 86.234608 -437.20697)
			(xy 86.235032 -437.21909) (xy 86.235032 -438.089802) (xy 87.138002 -438.089802) (xy 87.138095 -438.075228)
			(xy 87.139748 -438.046127) (xy 87.141304 -438.031636) (xy 87.141304 -436.948072) (xy 87.139759 -436.93358)
			(xy 87.138107 -436.90448) (xy 87.138002 -436.889906) (xy 87.138095 -436.875332) (xy 87.139748 -436.846231)
			(xy 87.141304 -436.83174) (xy 87.141304 -436.219092) (xy 87.141709 -436.206982) (xy 87.149212 -436.183954)
			(xy 87.163476 -436.164381) (xy 87.1831 -436.150186) (xy 87.206155 -436.142767) (xy 87.218266 -436.142384)
			(xy 88.158066 -436.142384) (xy 88.170158 -436.142837) (xy 88.193165 -436.15029) (xy 88.212749 -436.164478)
			(xy 88.227 -436.184018) (xy 88.234525 -436.207001) (xy 88.235028 -436.219092) (xy 88.235028 -438.760616)
			(xy 88.234598 -438.772723) (xy 88.227097 -438.795746) (xy 88.212838 -438.815316) (xy 88.193222 -438.829511)
			(xy 88.170174 -438.836937) (xy 88.158066 -438.837324) (xy 87.218266 -438.837324) (xy 87.206171 -438.836921)
			(xy 87.183163 -438.829451) (xy 87.163581 -438.815249) (xy 87.149333 -438.7957) (xy 87.141808 -438.77271)
			(xy 87.141304 -438.760616) (xy 87.141304 -438.147968) (xy 87.139759 -438.133476) (xy 87.138107 -438.104376)
			(xy 87.138002 -438.089802) (xy 86.235032 -438.089802) (xy 86.235032 -439.0898) (xy 89.137998 -439.0898)
			(xy 89.13809 -439.075226) (xy 89.139744 -439.046125) (xy 89.1413 -439.031634) (xy 89.1413 -437.94807)
			(xy 89.139755 -437.933578) (xy 89.138103 -437.904478) (xy 89.137998 -437.889904) (xy 89.138091 -437.87533)
			(xy 89.139744 -437.846229) (xy 89.1413 -437.831738) (xy 89.1413 -437.21909) (xy 89.141803 -437.206979)
			(xy 89.149288 -437.183942) (xy 89.163524 -437.164343) (xy 89.183117 -437.150101) (xy 89.206151 -437.142607)
			(xy 89.218262 -437.142128) (xy 90.158062 -437.142128) (xy 90.170182 -437.142592) (xy 90.193238 -437.150073)
			(xy 90.212853 -437.164313) (xy 90.227105 -437.183919) (xy 90.2346 -437.20697) (xy 90.235024 -437.21909)
			(xy 90.235024 -439.0898) (xy 127.237998 -439.0898) (xy 127.23809 -439.075226) (xy 127.239744 -439.046125)
			(xy 127.2413 -439.031634) (xy 127.2413 -437.94807) (xy 127.239755 -437.933578) (xy 127.238103 -437.904478)
			(xy 127.237998 -437.889904) (xy 127.238091 -437.87533) (xy 127.239744 -437.846229) (xy 127.2413 -437.831738)
			(xy 127.2413 -437.21909) (xy 127.241803 -437.206979) (xy 127.249288 -437.183942) (xy 127.263524 -437.164343)
			(xy 127.283117 -437.150101) (xy 127.306151 -437.142607) (xy 127.318262 -437.142128) (xy 128.258062 -437.142128)
			(xy 128.270182 -437.142592) (xy 128.293238 -437.150073) (xy 128.312853 -437.164313) (xy 128.327105 -437.183919)
			(xy 128.3346 -437.20697) (xy 128.335024 -437.21909) (xy 128.335024 -438.089802) (xy 129.237994 -438.089802)
			(xy 129.238087 -438.075228) (xy 129.23974 -438.046127) (xy 129.241296 -438.031636) (xy 129.241296 -436.948072)
			(xy 129.239752 -436.93358) (xy 129.238099 -436.90448) (xy 129.237994 -436.889906) (xy 129.238087 -436.875332)
			(xy 129.23974 -436.846231) (xy 129.241296 -436.83174) (xy 129.241296 -436.219092) (xy 129.241709 -436.206983)
			(xy 129.24921 -436.183956) (xy 129.263473 -436.164384) (xy 129.283095 -436.150189) (xy 129.306148 -436.142768)
			(xy 129.318258 -436.142384) (xy 130.258058 -436.142384) (xy 130.27015 -436.142844) (xy 130.293156 -436.150294)
			(xy 130.312741 -436.164481) (xy 130.326991 -436.184019) (xy 130.334516 -436.207002) (xy 130.33502 -436.219092)
			(xy 130.33502 -438.760616) (xy 130.334598 -438.772724) (xy 130.327096 -438.795748) (xy 130.312836 -438.815319)
			(xy 130.293217 -438.829514) (xy 130.270167 -438.836938) (xy 130.258058 -438.837324) (xy 129.318258 -438.837324)
			(xy 129.306163 -438.836928) (xy 129.283155 -438.829455) (xy 129.263572 -438.815252) (xy 129.249324 -438.795701)
			(xy 129.2418 -438.77271) (xy 129.241296 -438.760616) (xy 129.241296 -438.147968) (xy 129.239751 -438.133476)
			(xy 129.238099 -438.104376) (xy 129.237994 -438.089802) (xy 128.335024 -438.089802) (xy 128.335024 -439.0898)
			(xy 131.23799 -439.0898) (xy 131.238082 -439.075226) (xy 131.239736 -439.046125) (xy 131.241292 -439.031634)
			(xy 131.241292 -437.94807) (xy 131.239748 -437.933578) (xy 131.238095 -437.904478) (xy 131.23799 -437.889904)
			(xy 131.238083 -437.87533) (xy 131.239736 -437.846229) (xy 131.241292 -437.831738) (xy 131.241292 -437.21909)
			(xy 131.241803 -437.20698) (xy 131.249287 -437.183944) (xy 131.263521 -437.164346) (xy 131.283112 -437.150104)
			(xy 131.306144 -437.142608) (xy 131.318254 -437.142128) (xy 132.258054 -437.142128) (xy 132.270173 -437.142599)
			(xy 132.293229 -437.150077) (xy 132.312844 -437.164316) (xy 132.327097 -437.183921) (xy 132.334592 -437.206971)
			(xy 132.335016 -437.21909) (xy 132.335016 -438.089802) (xy 133.237986 -438.089802) (xy 133.238079 -438.075228)
			(xy 133.239732 -438.046127) (xy 133.241288 -438.031636) (xy 133.241288 -436.948072) (xy 133.239744 -436.93358)
			(xy 133.238091 -436.90448) (xy 133.237986 -436.889906) (xy 133.238079 -436.875332) (xy 133.239732 -436.846231)
			(xy 133.241288 -436.83174) (xy 133.241288 -436.219092) (xy 133.241709 -436.206984) (xy 133.249209 -436.183958)
			(xy 133.26347 -436.164386) (xy 133.28309 -436.150192) (xy 133.306141 -436.142769) (xy 133.31825 -436.142384)
			(xy 134.25805 -436.142384) (xy 134.270141 -436.142851) (xy 134.293148 -436.150299) (xy 134.312732 -436.164484)
			(xy 134.326983 -436.184021) (xy 134.334508 -436.207002) (xy 134.335012 -436.219092) (xy 134.335012 -438.760616)
			(xy 134.334598 -438.772725) (xy 134.327095 -438.79575) (xy 134.312833 -438.815322) (xy 134.293212 -438.829517)
			(xy 134.27016 -438.836939) (xy 134.25805 -438.837324) (xy 133.31825 -438.837324) (xy 133.306159 -438.836849)
			(xy 133.283154 -438.829402) (xy 133.26357 -438.815219) (xy 133.249319 -438.795684) (xy 133.241793 -438.772705)
			(xy 133.241288 -438.760616) (xy 133.241288 -438.147968) (xy 133.239743 -438.133476) (xy 133.238091 -438.104376)
			(xy 133.237986 -438.089802) (xy 132.335016 -438.089802) (xy 132.335016 -439.0898) (xy 135.237982 -439.0898)
			(xy 135.238075 -439.075226) (xy 135.239728 -439.046125) (xy 135.241284 -439.031634) (xy 135.241284 -437.94807)
			(xy 135.23974 -437.933578) (xy 135.238087 -437.904478) (xy 135.237982 -437.889904) (xy 135.238075 -437.87533)
			(xy 135.239728 -437.846229) (xy 135.241284 -437.831738) (xy 135.241284 -437.21909) (xy 135.241652 -437.206962)
			(xy 135.249153 -437.183895) (xy 135.263416 -437.164276) (xy 135.283045 -437.150027) (xy 135.306118 -437.142544)
			(xy 135.318246 -437.142128) (xy 136.258046 -437.142128) (xy 136.270162 -437.142572) (xy 136.293205 -437.150071)
			(xy 136.312805 -437.164321) (xy 136.327045 -437.183927) (xy 136.334533 -437.206974) (xy 136.335008 -437.21909)
			(xy 136.335008 -438.089802) (xy 137.237978 -438.089802) (xy 137.238071 -438.075228) (xy 137.239724 -438.046127)
			(xy 137.24128 -438.031636) (xy 137.24128 -436.948072) (xy 137.239736 -436.93358) (xy 137.238083 -436.90448)
			(xy 137.237978 -436.889906) (xy 137.238071 -436.875332) (xy 137.239724 -436.846231) (xy 137.24128 -436.83174)
			(xy 137.24128 -436.219092) (xy 137.241709 -436.206985) (xy 137.249208 -436.183961) (xy 137.263467 -436.164389)
			(xy 137.283085 -436.150194) (xy 137.306133 -436.14277) (xy 137.318242 -436.142384) (xy 138.258042 -436.142384)
			(xy 138.270138 -436.142772) (xy 138.293148 -436.150246) (xy 138.312731 -436.164451) (xy 138.326978 -436.184004)
			(xy 138.334501 -436.206997) (xy 138.335004 -436.219092) (xy 138.335004 -438.760616) (xy 138.334597 -438.772725)
			(xy 138.327094 -438.795752) (xy 138.31283 -438.815325) (xy 138.293207 -438.829519) (xy 138.270153 -438.83694)
			(xy 138.258042 -438.837324) (xy 137.318242 -438.837324) (xy 137.306151 -438.836856) (xy 137.283146 -438.829407)
			(xy 137.263562 -438.815222) (xy 137.249311 -438.795686) (xy 137.241785 -438.772705) (xy 137.24128 -438.760616)
			(xy 137.24128 -438.147968) (xy 137.239735 -438.133476) (xy 137.238083 -438.104376) (xy 137.237978 -438.089802)
			(xy 136.335008 -438.089802) (xy 136.335008 -439.0898) (xy 139.237974 -439.0898) (xy 139.238067 -439.075226)
			(xy 139.23972 -439.046125) (xy 139.241276 -439.031634) (xy 139.241276 -437.94807) (xy 139.239732 -437.933578)
			(xy 139.238079 -437.904478) (xy 139.237974 -437.889904) (xy 139.238067 -437.87533) (xy 139.23972 -437.846229)
			(xy 139.241276 -437.831738) (xy 139.241276 -437.21909) (xy 139.241652 -437.206963) (xy 139.249152 -437.183897)
			(xy 139.263413 -437.164279) (xy 139.28304 -437.15003) (xy 139.306111 -437.142545) (xy 139.318238 -437.142128)
			(xy 140.258038 -437.142128) (xy 140.270154 -437.142579) (xy 140.293196 -437.150076) (xy 140.312797 -437.164323)
			(xy 140.327037 -437.183929) (xy 140.334525 -437.206974) (xy 140.335 -437.21909) (xy 140.335 -438.089802)
			(xy 142.237968 -438.089802) (xy 142.238085 -438.074717) (xy 142.239861 -438.044598) (xy 142.241524 -438.029604)
			(xy 142.241524 -436.950104) (xy 142.239854 -436.935111) (xy 142.238076 -436.904992) (xy 142.237968 -436.889906)
			(xy 142.238076 -436.87482) (xy 142.239858 -436.844702) (xy 142.241524 -436.829708) (xy 142.241524 -436.219092)
			(xy 142.241906 -436.207006) (xy 142.24938 -436.184017) (xy 142.263593 -436.164464) (xy 142.283153 -436.150262)
			(xy 142.306145 -436.1428) (xy 142.318232 -436.142384) (xy 143.258032 -436.142384) (xy 143.270107 -436.142837)
			(xy 143.293074 -436.150307) (xy 143.31261 -436.164507) (xy 143.326804 -436.184047) (xy 143.334267 -436.207016)
			(xy 143.33474 -436.219092) (xy 143.33474 -438.760616) (xy 143.33425 -438.772688) (xy 143.326787 -438.79565)
			(xy 143.312596 -438.815184) (xy 143.293065 -438.829379) (xy 143.270104 -438.836847) (xy 143.258032 -438.837324)
			(xy 142.318232 -438.837324) (xy 142.306153 -438.83686) (xy 142.283174 -438.829403) (xy 142.263624 -438.81521)
			(xy 142.249418 -438.795669) (xy 142.241947 -438.772695) (xy 142.241524 -438.760616) (xy 142.241524 -438.15)
			(xy 142.239853 -438.135007) (xy 142.238076 -438.104888) (xy 142.237968 -438.089802) (xy 140.335 -438.089802)
			(xy 140.335 -439.0898) (xy 144.237964 -439.0898) (xy 144.23808 -439.074715) (xy 144.239857 -439.044596)
			(xy 144.24152 -439.029602) (xy 144.24152 -437.950102) (xy 144.239849 -437.935109) (xy 144.238072 -437.90499)
			(xy 144.237964 -437.889904) (xy 144.238081 -437.874819) (xy 144.239857 -437.8447) (xy 144.24152 -437.829706)
			(xy 144.24152 -437.21909) (xy 144.241999 -437.207002) (xy 144.249456 -437.184004) (xy 144.26364 -437.164426)
			(xy 144.28317 -437.150176) (xy 144.306142 -437.14264) (xy 144.318228 -437.142128) (xy 145.258028 -437.142128)
			(xy 145.270141 -437.142493) (xy 145.293174 -437.150003) (xy 145.312749 -437.164277) (xy 145.326942 -437.183911)
			(xy 145.334357 -437.206975) (xy 145.334736 -437.21909) (xy 145.334736 -438.089802) (xy 146.23796 -438.089802)
			(xy 146.238077 -438.074717) (xy 146.239853 -438.044598) (xy 146.241516 -438.029604) (xy 146.241516 -436.950104)
			(xy 146.239846 -436.935111) (xy 146.238068 -436.904992) (xy 146.23796 -436.889906) (xy 146.238068 -436.87482)
			(xy 146.23985 -436.844702) (xy 146.241516 -436.829708) (xy 146.241516 -436.219092) (xy 146.241906 -436.207006)
			(xy 146.249379 -436.184019) (xy 146.26359 -436.164467) (xy 146.283148 -436.150264) (xy 146.306138 -436.142801)
			(xy 146.318224 -436.142384) (xy 147.258024 -436.142384) (xy 147.270099 -436.142844) (xy 147.293066 -436.150312)
			(xy 147.312601 -436.16451) (xy 147.326795 -436.184049) (xy 147.334259 -436.207017) (xy 147.334732 -436.219092)
			(xy 147.334732 -438.760616) (xy 147.33425 -438.772689) (xy 147.326786 -438.795653) (xy 147.312593 -438.815187)
			(xy 147.29306 -438.829382) (xy 147.270097 -438.836848) (xy 147.258024 -438.837324) (xy 146.318224 -438.837324)
			(xy 146.306144 -438.836867) (xy 146.283165 -438.829408) (xy 146.263616 -438.815213) (xy 146.24941 -438.795671)
			(xy 146.241939 -438.772696) (xy 146.241516 -438.760616) (xy 146.241516 -438.15) (xy 146.239845 -438.135007)
			(xy 146.238068 -438.104888) (xy 146.23796 -438.089802) (xy 145.334736 -438.089802) (xy 145.334736 -439.0898)
			(xy 148.237956 -439.0898) (xy 148.238073 -439.074715) (xy 148.239849 -439.044596) (xy 148.241512 -439.029602)
			(xy 148.241512 -437.950102) (xy 148.239841 -437.935109) (xy 148.238064 -437.90499) (xy 148.237956 -437.889904)
			(xy 148.238073 -437.874819) (xy 148.239849 -437.8447) (xy 148.241512 -437.829706) (xy 148.241512 -437.21909)
			(xy 148.241999 -437.207003) (xy 148.249455 -437.184007) (xy 148.263637 -437.164429) (xy 148.283165 -437.150178)
			(xy 148.306134 -437.142641) (xy 148.31822 -437.142128) (xy 149.25802 -437.142128) (xy 149.270133 -437.1425)
			(xy 149.293165 -437.150008) (xy 149.312741 -437.16428) (xy 149.326934 -437.183913) (xy 149.334349 -437.206976)
			(xy 149.334728 -437.21909) (xy 149.334728 -438.089802) (xy 150.237952 -438.089802) (xy 150.238069 -438.074717)
			(xy 150.239845 -438.044598) (xy 150.241508 -438.029604) (xy 150.241508 -436.950104) (xy 150.239838 -436.935111)
			(xy 150.23806 -436.904992) (xy 150.237952 -436.889906) (xy 150.23806 -436.87482) (xy 150.239842 -436.844702)
			(xy 150.241508 -436.829708) (xy 150.241508 -436.219092) (xy 150.241906 -436.207007) (xy 150.249378 -436.184021)
			(xy 150.263587 -436.16447) (xy 150.283143 -436.150267) (xy 150.306131 -436.142802) (xy 150.318216 -436.142384)
			(xy 151.258016 -436.142384) (xy 151.270091 -436.142851) (xy 151.293057 -436.150317) (xy 151.312593 -436.164513)
			(xy 151.326787 -436.18405) (xy 151.334251 -436.207017) (xy 151.334724 -436.219092) (xy 151.334724 -438.760616)
			(xy 151.33425 -438.77269) (xy 151.326785 -438.795655) (xy 151.31259 -438.81519) (xy 151.293055 -438.829385)
			(xy 151.27009 -438.83685) (xy 151.258016 -438.837324) (xy 150.318216 -438.837324) (xy 150.306144 -438.836822)
			(xy 150.28318 -438.829366) (xy 150.263644 -438.815179) (xy 150.249448 -438.795649) (xy 150.241983 -438.772688)
			(xy 150.241508 -438.760616) (xy 150.241508 -438.15) (xy 150.239837 -438.135007) (xy 150.23806 -438.104888)
			(xy 150.237952 -438.089802) (xy 149.334728 -438.089802) (xy 149.334728 -439.0898) (xy 152.237948 -439.0898)
			(xy 152.238065 -439.074715) (xy 152.239841 -439.044596) (xy 152.241504 -439.029602) (xy 152.241504 -437.950102)
			(xy 152.239833 -437.935109) (xy 152.238056 -437.90499) (xy 152.237948 -437.889904) (xy 152.238065 -437.874819)
			(xy 152.239841 -437.8447) (xy 152.241504 -437.829706) (xy 152.241504 -437.21909) (xy 152.241998 -437.207004)
			(xy 152.249453 -437.184009) (xy 152.263634 -437.164432) (xy 152.28316 -437.150181) (xy 152.306127 -437.142643)
			(xy 152.318212 -437.142128) (xy 153.258012 -437.142128) (xy 153.270124 -437.142506) (xy 153.293157 -437.150012)
			(xy 153.312732 -437.164283) (xy 153.326925 -437.183914) (xy 153.334341 -437.206976) (xy 153.33472 -437.21909)
			(xy 153.33472 -438.089802) (xy 154.237944 -438.089802) (xy 154.238061 -438.074717) (xy 154.239837 -438.044598)
			(xy 154.2415 -438.029604) (xy 154.2415 -436.950104) (xy 154.23983 -436.935111) (xy 154.238052 -436.904992)
			(xy 154.237944 -436.889906) (xy 154.238052 -436.87482) (xy 154.239834 -436.844702) (xy 154.2415 -436.829708)
			(xy 154.2415 -436.219092) (xy 154.241958 -436.207016) (xy 154.249423 -436.184047) (xy 154.263621 -436.16451)
			(xy 154.283162 -436.150316) (xy 154.306132 -436.142855) (xy 154.318208 -436.142384) (xy 155.258008 -436.142384)
			(xy 155.270082 -436.142857) (xy 155.293048 -436.150321) (xy 155.312584 -436.164516) (xy 155.326779 -436.184052)
			(xy 155.334243 -436.207018) (xy 155.334716 -436.219092) (xy 155.334716 -438.760616) (xy 155.334249 -438.772691)
			(xy 155.326783 -438.795657) (xy 155.312587 -438.815193) (xy 155.29305 -438.829387) (xy 155.270083 -438.836851)
			(xy 155.258008 -438.837324) (xy 154.318208 -438.837324) (xy 154.306135 -438.836829) (xy 154.283171 -438.829371)
			(xy 154.263635 -438.815182) (xy 154.24944 -438.79565) (xy 154.241975 -438.772688) (xy 154.2415 -438.760616)
			(xy 154.2415 -438.15) (xy 154.239829 -438.135007) (xy 154.238052 -438.104888) (xy 154.237944 -438.089802)
			(xy 153.33472 -438.089802) (xy 153.33472 -439.0898) (xy 156.23794 -439.0898) (xy 156.238057 -439.074715)
			(xy 156.239833 -439.044596) (xy 156.241496 -439.029602) (xy 156.241496 -437.950102) (xy 156.239825 -437.935109)
			(xy 156.238048 -437.90499) (xy 156.23794 -437.889904) (xy 156.238057 -437.874819) (xy 156.239833 -437.8447)
			(xy 156.241496 -437.829706) (xy 156.241496 -437.21909) (xy 156.241998 -437.207004) (xy 156.249452 -437.184011)
			(xy 156.263631 -437.164435) (xy 156.283155 -437.150183) (xy 156.30612 -437.142644) (xy 156.318204 -437.142128)
			(xy 157.258004 -437.142128) (xy 157.270116 -437.142513) (xy 157.293148 -437.150017) (xy 157.312724 -437.164286)
			(xy 157.326917 -437.183916) (xy 157.334333 -437.206977) (xy 157.334712 -437.21909) (xy 157.334712 -438.089802)
			(xy 314.138056 -438.089802) (xy 314.138173 -438.074717) (xy 314.139949 -438.044598) (xy 314.141612 -438.029604)
			(xy 314.141612 -436.950104) (xy 314.139942 -436.935111) (xy 314.138164 -436.904992) (xy 314.138056 -436.889906)
			(xy 314.138164 -436.87482) (xy 314.139946 -436.844702) (xy 314.141612 -436.829708) (xy 314.141612 -436.219092)
			(xy 314.142006 -436.207007) (xy 314.149478 -436.18402) (xy 314.163688 -436.164469) (xy 314.183246 -436.150265)
			(xy 314.206235 -436.142802) (xy 314.21832 -436.142384) (xy 315.15812 -436.142384) (xy 315.170195 -436.142847)
			(xy 315.193161 -436.150314) (xy 315.212697 -436.164511) (xy 315.226891 -436.18405) (xy 315.234355 -436.207017)
			(xy 315.234828 -436.219092) (xy 315.234828 -438.760616) (xy 315.23435 -438.772689) (xy 315.226885 -438.795654)
			(xy 315.212691 -438.815189) (xy 315.193157 -438.829383) (xy 315.170193 -438.836849) (xy 315.15812 -438.837324)
			(xy 314.21832 -438.837324) (xy 314.20624 -438.83687) (xy 314.183261 -438.82941) (xy 314.163711 -438.815214)
			(xy 314.149506 -438.795672) (xy 314.142035 -438.772696) (xy 314.141612 -438.760616) (xy 314.141612 -438.15)
			(xy 314.139941 -438.135007) (xy 314.138164 -438.104888) (xy 314.138056 -438.089802) (xy 157.334712 -438.089802)
			(xy 157.334712 -439.0898) (xy 316.138052 -439.0898) (xy 316.138169 -439.074715) (xy 316.139945 -439.044596)
			(xy 316.141608 -439.029602) (xy 316.141608 -437.950102) (xy 316.139937 -437.935109) (xy 316.13816 -437.90499)
			(xy 316.138052 -437.889904) (xy 316.138169 -437.874819) (xy 316.139945 -437.8447) (xy 316.141608 -437.829706)
			(xy 316.141608 -437.21909) (xy 316.142098 -437.207003) (xy 316.149554 -437.184008) (xy 316.163736 -437.164431)
			(xy 316.183262 -437.150179) (xy 316.206231 -437.142642) (xy 316.218316 -437.142128) (xy 317.158116 -437.142128)
			(xy 317.170229 -437.142503) (xy 317.193261 -437.15001) (xy 317.212836 -437.164281) (xy 317.227029 -437.183914)
			(xy 317.234445 -437.206976) (xy 317.234824 -437.21909) (xy 317.234824 -438.089802) (xy 318.138048 -438.089802)
			(xy 318.138165 -438.074717) (xy 318.139941 -438.044598) (xy 318.141604 -438.029604) (xy 318.141604 -436.950104)
			(xy 318.139934 -436.935111) (xy 318.138156 -436.904992) (xy 318.138048 -436.889906) (xy 318.138156 -436.87482)
			(xy 318.139938 -436.844702) (xy 318.141604 -436.829708) (xy 318.141604 -436.219092) (xy 318.142006 -436.207008)
			(xy 318.149477 -436.184023) (xy 318.163686 -436.164471) (xy 318.183241 -436.150268) (xy 318.206228 -436.142803)
			(xy 318.218312 -436.142384) (xy 319.158112 -436.142384) (xy 319.170186 -436.142854) (xy 319.193153 -436.150319)
			(xy 319.212689 -436.164514) (xy 319.226883 -436.184051) (xy 319.234347 -436.207018) (xy 319.23482 -436.219092)
			(xy 319.23482 -438.760616) (xy 319.234349 -438.77269) (xy 319.226884 -438.795656) (xy 319.212689 -438.815191)
			(xy 319.193152 -438.829386) (xy 319.170186 -438.83685) (xy 319.158112 -438.837324) (xy 318.218312 -438.837324)
			(xy 318.20624 -438.836826) (xy 318.183276 -438.829369) (xy 318.16374 -438.81518) (xy 318.149544 -438.79565)
			(xy 318.142079 -438.772688) (xy 318.141604 -438.760616) (xy 318.141604 -438.15) (xy 318.139933 -438.135007)
			(xy 318.138156 -438.104888) (xy 318.138048 -438.089802) (xy 317.234824 -438.089802) (xy 317.234824 -439.0898)
			(xy 320.138044 -439.0898) (xy 320.138161 -439.074715) (xy 320.139937 -439.044596) (xy 320.1416 -439.029602)
			(xy 320.1416 -437.950102) (xy 320.139929 -437.935109) (xy 320.138152 -437.90499) (xy 320.138044 -437.889904)
			(xy 320.138161 -437.874819) (xy 320.139937 -437.8447) (xy 320.1416 -437.829706) (xy 320.1416 -437.21909)
			(xy 320.142098 -437.207004) (xy 320.149553 -437.18401) (xy 320.163733 -437.164434) (xy 320.183257 -437.150182)
			(xy 320.206224 -437.142643) (xy 320.218308 -437.142128) (xy 321.158108 -437.142128) (xy 321.17022 -437.14251)
			(xy 321.193252 -437.150015) (xy 321.212828 -437.164284) (xy 321.227021 -437.183915) (xy 321.234437 -437.206976)
			(xy 321.234816 -437.21909) (xy 321.234816 -438.089802) (xy 322.13804 -438.089802) (xy 322.138157 -438.074717)
			(xy 322.139933 -438.044598) (xy 322.141596 -438.029604) (xy 322.141596 -436.950104) (xy 322.139926 -436.935111)
			(xy 322.138148 -436.904992) (xy 322.13804 -436.889906) (xy 322.13815 -436.87482) (xy 322.139932 -436.844702)
			(xy 322.141596 -436.829708) (xy 322.141596 -436.219092) (xy 322.142058 -436.207017) (xy 322.149523 -436.184049)
			(xy 322.16372 -436.164511) (xy 322.183259 -436.150317) (xy 322.206229 -436.142856) (xy 322.218304 -436.142384)
			(xy 323.158104 -436.142384) (xy 323.170178 -436.142861) (xy 323.193144 -436.150323) (xy 323.21268 -436.164517)
			(xy 323.226875 -436.184053) (xy 323.234339 -436.207018) (xy 323.234812 -436.219092) (xy 323.234812 -438.760616)
			(xy 323.234349 -438.772691) (xy 323.226883 -438.795658) (xy 323.212686 -438.815194) (xy 323.193147 -438.829388)
			(xy 323.170179 -438.836851) (xy 323.158104 -438.837324) (xy 322.218304 -438.837324) (xy 322.206231 -438.836833)
			(xy 322.183267 -438.829373) (xy 322.163731 -438.815183) (xy 322.149536 -438.795651) (xy 322.142071 -438.772689)
			(xy 322.141596 -438.760616) (xy 322.141596 -438.15) (xy 322.139925 -438.135007) (xy 322.138148 -438.104888)
			(xy 322.13804 -438.089802) (xy 321.234816 -438.089802) (xy 321.234816 -439.0898) (xy 324.138036 -439.0898)
			(xy 324.138153 -439.074715) (xy 324.139929 -439.044596) (xy 324.141592 -439.029602) (xy 324.141592 -437.950102)
			(xy 324.139921 -437.935109) (xy 324.138144 -437.90499) (xy 324.138036 -437.889904) (xy 324.138153 -437.874819)
			(xy 324.139929 -437.8447) (xy 324.141592 -437.829706) (xy 324.141592 -437.21909) (xy 324.142098 -437.207005)
			(xy 324.149552 -437.184012) (xy 324.16373 -437.164436) (xy 324.183252 -437.150184) (xy 324.206217 -437.142644)
			(xy 324.2183 -437.142128) (xy 325.1581 -437.142128) (xy 325.170212 -437.142516) (xy 325.193244 -437.150019)
			(xy 325.212819 -437.164287) (xy 325.227013 -437.183916) (xy 325.234429 -437.206977) (xy 325.234808 -437.21909)
			(xy 325.234808 -438.089802) (xy 326.138032 -438.089802) (xy 326.138151 -438.074717) (xy 326.139927 -438.044598)
			(xy 326.141588 -438.029604) (xy 326.141588 -436.950104) (xy 326.139917 -436.935111) (xy 326.13814 -436.904992)
			(xy 326.138032 -436.889906) (xy 326.138142 -436.87482) (xy 326.139924 -436.844702) (xy 326.141588 -436.829708)
			(xy 326.141588 -436.219092) (xy 326.142057 -436.207017) (xy 326.149522 -436.184051) (xy 326.163717 -436.164514)
			(xy 326.183254 -436.15032) (xy 326.206221 -436.142857) (xy 326.218296 -436.142384) (xy 327.158096 -436.142384)
			(xy 327.17017 -436.142868) (xy 327.193135 -436.150328) (xy 327.212672 -436.16452) (xy 327.226867 -436.184054)
			(xy 327.234331 -436.207019) (xy 327.234804 -436.219092) (xy 327.234804 -438.760616) (xy 327.234349 -438.772692)
			(xy 327.226882 -438.79566) (xy 327.212683 -438.815197) (xy 327.193142 -438.829391) (xy 327.170172 -438.836852)
			(xy 327.158096 -438.837324) (xy 326.218296 -438.837324) (xy 326.206223 -438.836839) (xy 326.183258 -438.829378)
			(xy 326.163723 -438.815186) (xy 326.149528 -438.795652) (xy 326.142063 -438.772689) (xy 326.141588 -438.760616)
			(xy 326.141588 -438.15) (xy 326.139917 -438.135007) (xy 326.13814 -438.104888) (xy 326.138032 -438.089802)
			(xy 325.234808 -438.089802) (xy 325.234808 -439.0898) (xy 328.138028 -439.0898) (xy 328.138147 -439.074715)
			(xy 328.139923 -439.044596) (xy 328.141584 -439.029602) (xy 328.141584 -437.950102) (xy 328.139913 -437.935109)
			(xy 328.138136 -437.90499) (xy 328.138028 -437.889904) (xy 328.138147 -437.874819) (xy 328.139923 -437.8447)
			(xy 328.141584 -437.829706) (xy 328.141584 -437.21909) (xy 328.142 -437.206996) (xy 328.149465 -437.183987)
			(xy 328.163663 -437.164404) (xy 328.18321 -437.150155) (xy 328.206199 -437.142631) (xy 328.218292 -437.142128)
			(xy 329.158092 -437.142128) (xy 329.170203 -437.142523) (xy 329.193235 -437.150024) (xy 329.212811 -437.16429)
			(xy 329.227005 -437.183918) (xy 329.234421 -437.206977) (xy 329.2348 -437.21909) (xy 329.2348 -438.089802)
			(xy 331.138022 -438.089802) (xy 331.138115 -438.075228) (xy 331.139768 -438.046127) (xy 331.141324 -438.031636)
			(xy 331.141324 -436.948072) (xy 331.13978 -436.93358) (xy 331.138127 -436.90448) (xy 331.138022 -436.889906)
			(xy 331.138115 -436.875332) (xy 331.139768 -436.846231) (xy 331.141324 -436.83174) (xy 331.141324 -436.219092)
			(xy 331.14171 -436.20698) (xy 331.149214 -436.183949) (xy 331.163483 -436.164374) (xy 331.183112 -436.15018)
			(xy 331.206173 -436.142764) (xy 331.218286 -436.142384) (xy 332.158086 -436.142384) (xy 332.170179 -436.14282)
			(xy 332.193187 -436.150278) (xy 332.212771 -436.164471) (xy 332.22702 -436.184014) (xy 332.234545 -436.207)
			(xy 332.235048 -436.219092) (xy 332.235048 -438.760616) (xy 332.234598 -438.772721) (xy 332.2271 -438.795741)
			(xy 332.212845 -438.815309) (xy 332.193234 -438.829505) (xy 332.170192 -438.836934) (xy 332.158086 -438.837324)
			(xy 331.218286 -438.837324) (xy 331.206192 -438.836904) (xy 331.183185 -438.829439) (xy 331.163602 -438.815242)
			(xy 331.149353 -438.795696) (xy 331.141828 -438.772709) (xy 331.141324 -438.760616) (xy 331.141324 -438.147968)
			(xy 331.139779 -438.133476) (xy 331.138127 -438.104376) (xy 331.138022 -438.089802) (xy 329.2348 -438.089802)
			(xy 329.2348 -439.0898) (xy 333.138018 -439.0898) (xy 333.138111 -439.075226) (xy 333.139764 -439.046125)
			(xy 333.14132 -439.031634) (xy 333.14132 -437.94807) (xy 333.139775 -437.933578) (xy 333.138123 -437.904478)
			(xy 333.138018 -437.889904) (xy 333.138111 -437.87533) (xy 333.139764 -437.846229) (xy 333.14132 -437.831738)
			(xy 333.14132 -437.21909) (xy 333.141803 -437.206977) (xy 333.149291 -437.183936) (xy 333.163531 -437.164336)
			(xy 333.183129 -437.150095) (xy 333.206169 -437.142604) (xy 333.218282 -437.142128) (xy 334.158082 -437.142128)
			(xy 334.170203 -437.142575) (xy 334.193259 -437.150061) (xy 334.212874 -437.164306) (xy 334.227126 -437.183916)
			(xy 334.23462 -437.206969) (xy 334.235044 -437.21909) (xy 334.235044 -438.089802) (xy 335.138014 -438.089802)
			(xy 335.138106 -438.075228) (xy 335.13976 -438.046127) (xy 335.141316 -438.031636) (xy 335.141316 -436.948072)
			(xy 335.139772 -436.93358) (xy 335.138119 -436.90448) (xy 335.138014 -436.889906) (xy 335.138107 -436.875332)
			(xy 335.13976 -436.846231) (xy 335.141316 -436.83174) (xy 335.141316 -436.219092) (xy 335.14171 -436.206981)
			(xy 335.149213 -436.183951) (xy 335.16348 -436.164376) (xy 335.183107 -436.150183) (xy 335.206166 -436.142765)
			(xy 335.218278 -436.142384) (xy 336.158078 -436.142384) (xy 336.170171 -436.142827) (xy 336.193178 -436.150283)
			(xy 336.212762 -436.164474) (xy 336.227012 -436.184016) (xy 336.234537 -436.207001) (xy 336.23504 -436.219092)
			(xy 336.23504 -438.760616) (xy 336.234598 -438.772722) (xy 336.227099 -438.795743) (xy 336.212843 -438.815312)
			(xy 336.193229 -438.829508) (xy 336.170185 -438.836935) (xy 336.158078 -438.837324) (xy 335.218278 -438.837324)
			(xy 335.206184 -438.836911) (xy 335.183176 -438.829444) (xy 335.163594 -438.815245) (xy 335.149345 -438.795698)
			(xy 335.14182 -438.772709) (xy 335.141316 -438.760616) (xy 335.141316 -438.147968) (xy 335.139771 -438.133476)
			(xy 335.138119 -438.104376) (xy 335.138014 -438.089802) (xy 334.235044 -438.089802) (xy 334.235044 -439.0898)
			(xy 337.13801 -439.0898) (xy 337.138102 -439.075226) (xy 337.139756 -439.046125) (xy 337.141312 -439.031634)
			(xy 337.141312 -437.94807) (xy 337.139767 -437.933578) (xy 337.138115 -437.904478) (xy 337.13801 -437.889904)
			(xy 337.138103 -437.87533) (xy 337.139756 -437.846229) (xy 337.141312 -437.831738) (xy 337.141312 -437.21909)
			(xy 337.141803 -437.206978) (xy 337.14929 -437.183938) (xy 337.163528 -437.164339) (xy 337.183124 -437.150097)
			(xy 337.206162 -437.142606) (xy 337.218274 -437.142128) (xy 338.158074 -437.142128) (xy 338.170194 -437.142582)
			(xy 338.193251 -437.150066) (xy 338.212865 -437.164309) (xy 338.227118 -437.183917) (xy 338.234612 -437.20697)
			(xy 338.235036 -437.21909) (xy 338.235036 -438.089802) (xy 339.138006 -438.089802) (xy 339.138099 -438.075228)
			(xy 339.139752 -438.046127) (xy 339.141308 -438.031636) (xy 339.141308 -436.948072) (xy 339.139763 -436.93358)
			(xy 339.138111 -436.90448) (xy 339.138006 -436.889906) (xy 339.138099 -436.875332) (xy 339.139752 -436.846231)
			(xy 339.141308 -436.83174) (xy 339.141308 -436.219092) (xy 339.141709 -436.206982) (xy 339.149212 -436.183953)
			(xy 339.163477 -436.164379) (xy 339.183102 -436.150185) (xy 339.206158 -436.142766) (xy 339.21827 -436.142384)
			(xy 340.15807 -436.142384) (xy 340.170162 -436.142834) (xy 340.193169 -436.150288) (xy 340.212754 -436.164477)
			(xy 340.227004 -436.184017) (xy 340.234529 -436.207001) (xy 340.235032 -436.219092) (xy 340.235032 -438.760616)
			(xy 340.234598 -438.772723) (xy 340.227098 -438.795745) (xy 340.21284 -438.815315) (xy 340.193224 -438.82951)
			(xy 340.170178 -438.836936) (xy 340.15807 -438.837324) (xy 339.21827 -438.837324) (xy 339.206175 -438.836918)
			(xy 339.183168 -438.829448) (xy 339.163585 -438.815247) (xy 339.149337 -438.795699) (xy 339.141812 -438.77271)
			(xy 339.141308 -438.760616) (xy 339.141308 -438.147968) (xy 339.139763 -438.133476) (xy 339.138111 -438.104376)
			(xy 339.138006 -438.089802) (xy 338.235036 -438.089802) (xy 338.235036 -439.0898) (xy 341.138002 -439.0898)
			(xy 341.138094 -439.075226) (xy 341.139748 -439.046125) (xy 341.141304 -439.031634) (xy 341.141304 -437.94807)
			(xy 341.139759 -437.933578) (xy 341.138107 -437.904478) (xy 341.138002 -437.889904) (xy 341.138095 -437.87533)
			(xy 341.139748 -437.846229) (xy 341.141304 -437.831738) (xy 341.141304 -437.21909) (xy 341.141803 -437.206978)
			(xy 341.149289 -437.183941) (xy 341.163525 -437.164342) (xy 341.183119 -437.1501) (xy 341.206154 -437.142607)
			(xy 341.218266 -437.142128) (xy 342.158066 -437.142128) (xy 342.170186 -437.142589) (xy 342.193242 -437.15007)
			(xy 342.212857 -437.164312) (xy 342.22711 -437.183918) (xy 342.234604 -437.20697) (xy 342.235028 -437.21909)
			(xy 342.235028 -438.089802) (xy 343.137998 -438.089802) (xy 343.138091 -438.075228) (xy 343.139744 -438.046127)
			(xy 343.1413 -438.031636) (xy 343.1413 -436.948072) (xy 343.139755 -436.93358) (xy 343.138103 -436.90448)
			(xy 343.137998 -436.889906) (xy 343.138091 -436.875332) (xy 343.139744 -436.846231) (xy 343.1413 -436.83174)
			(xy 343.1413 -436.219092) (xy 343.141709 -436.206983) (xy 343.149211 -436.183955) (xy 343.163474 -436.164382)
			(xy 343.183097 -436.150188) (xy 343.206151 -436.142767) (xy 343.218262 -436.142384) (xy 344.158062 -436.142384)
			(xy 344.170154 -436.142841) (xy 344.193161 -436.150292) (xy 344.212745 -436.16448) (xy 344.226995 -436.184019)
			(xy 344.234521 -436.207002) (xy 344.235024 -436.219092) (xy 344.235024 -438.760616) (xy 344.234598 -438.772723)
			(xy 344.227097 -438.795747) (xy 344.212837 -438.815318) (xy 344.193219 -438.829513) (xy 344.170171 -438.836937)
			(xy 344.158062 -438.837324) (xy 343.218262 -438.837324) (xy 343.206167 -438.836924) (xy 343.183159 -438.829453)
			(xy 343.163577 -438.81525) (xy 343.149329 -438.795701) (xy 343.141804 -438.77271) (xy 343.1413 -438.760616)
			(xy 343.1413 -438.147968) (xy 343.139755 -438.133476) (xy 343.138103 -438.104376) (xy 343.137998 -438.089802)
			(xy 342.235028 -438.089802) (xy 342.235028 -439.0898) (xy 345.137994 -439.0898) (xy 345.138086 -439.075226)
			(xy 345.13974 -439.046125) (xy 345.141296 -439.031634) (xy 345.141296 -437.94807) (xy 345.139752 -437.933578)
			(xy 345.138099 -437.904478) (xy 345.137994 -437.889904) (xy 345.138087 -437.87533) (xy 345.13974 -437.846229)
			(xy 345.141296 -437.831738) (xy 345.141296 -437.21909) (xy 345.141803 -437.206979) (xy 345.149288 -437.183943)
			(xy 345.163522 -437.164345) (xy 345.183114 -437.150102) (xy 345.206147 -437.142608) (xy 345.218258 -437.142128)
			(xy 346.158058 -437.142128) (xy 346.170178 -437.142595) (xy 346.193233 -437.150075) (xy 346.212848 -437.164315)
			(xy 346.227101 -437.18392) (xy 346.234596 -437.206971) (xy 346.23502 -437.21909) (xy 346.23502 -439.0898)
			(xy 383.237994 -439.0898) (xy 383.238086 -439.075226) (xy 383.23974 -439.046125) (xy 383.241296 -439.031634)
			(xy 383.241296 -437.94807) (xy 383.239752 -437.933578) (xy 383.238099 -437.904478) (xy 383.237994 -437.889904)
			(xy 383.238087 -437.87533) (xy 383.23974 -437.846229) (xy 383.241296 -437.831738) (xy 383.241296 -437.21909)
			(xy 383.241803 -437.206979) (xy 383.249288 -437.183943) (xy 383.263522 -437.164345) (xy 383.283114 -437.150102)
			(xy 383.306147 -437.142608) (xy 383.318258 -437.142128) (xy 384.258058 -437.142128) (xy 384.270178 -437.142595)
			(xy 384.293233 -437.150075) (xy 384.312848 -437.164315) (xy 384.327101 -437.18392) (xy 384.334596 -437.206971)
			(xy 384.33502 -437.21909) (xy 384.33502 -438.089802) (xy 385.23799 -438.089802) (xy 385.238083 -438.075228)
			(xy 385.239736 -438.046127) (xy 385.241292 -438.031636) (xy 385.241292 -436.948072) (xy 385.239748 -436.93358)
			(xy 385.238095 -436.90448) (xy 385.23799 -436.889906) (xy 385.238083 -436.875332) (xy 385.239736 -436.846231)
			(xy 385.241292 -436.83174) (xy 385.241292 -436.219092) (xy 385.241709 -436.206983) (xy 385.24921 -436.183957)
			(xy 385.263472 -436.164385) (xy 385.283092 -436.15019) (xy 385.306144 -436.142768) (xy 385.318254 -436.142384)
			(xy 386.258054 -436.142384) (xy 386.270146 -436.142847) (xy 386.293152 -436.150297) (xy 386.312737 -436.164483)
			(xy 386.326987 -436.18402) (xy 386.334512 -436.207002) (xy 386.335016 -436.219092) (xy 386.335016 -438.760616)
			(xy 386.334598 -438.772724) (xy 386.327096 -438.795749) (xy 386.312834 -438.815321) (xy 386.293214 -438.829515)
			(xy 386.270163 -438.836939) (xy 386.258054 -438.837324) (xy 385.318254 -438.837324) (xy 385.306158 -438.836931)
			(xy 385.28315 -438.829457) (xy 385.263568 -438.815253) (xy 385.24932 -438.795702) (xy 385.241796 -438.77271)
			(xy 385.241292 -438.760616) (xy 385.241292 -438.147968) (xy 385.239747 -438.133476) (xy 385.238095 -438.104376)
			(xy 385.23799 -438.089802) (xy 384.33502 -438.089802) (xy 384.33502 -439.0898) (xy 387.237986 -439.0898)
			(xy 387.238078 -439.075226) (xy 387.239732 -439.046125) (xy 387.241288 -439.031634) (xy 387.241288 -437.94807)
			(xy 387.239744 -437.933578) (xy 387.238091 -437.904478) (xy 387.237986 -437.889904) (xy 387.238079 -437.87533)
			(xy 387.239732 -437.846229) (xy 387.241288 -437.831738) (xy 387.241288 -437.21909) (xy 387.241803 -437.20698)
			(xy 387.249287 -437.183945) (xy 387.263519 -437.164348) (xy 387.283109 -437.150105) (xy 387.30614 -437.142609)
			(xy 387.31825 -437.142128) (xy 388.25805 -437.142128) (xy 388.270166 -437.142569) (xy 388.293209 -437.150069)
			(xy 388.312809 -437.164319) (xy 388.32705 -437.183927) (xy 388.334537 -437.206974) (xy 388.335012 -437.21909)
			(xy 388.335012 -438.089802) (xy 389.237982 -438.089802) (xy 389.238075 -438.075228) (xy 389.239728 -438.046127)
			(xy 389.241284 -438.031636) (xy 389.241284 -436.948072) (xy 389.23974 -436.93358) (xy 389.238087 -436.90448)
			(xy 389.237982 -436.889906) (xy 389.238075 -436.875332) (xy 389.239728 -436.846231) (xy 389.241284 -436.83174)
			(xy 389.241284 -436.219092) (xy 389.241709 -436.206984) (xy 389.249209 -436.183959) (xy 389.263469 -436.164388)
			(xy 389.283087 -436.150193) (xy 389.306137 -436.142769) (xy 389.318246 -436.142384) (xy 390.258046 -436.142384)
			(xy 390.270142 -436.142769) (xy 390.293152 -436.150244) (xy 390.312735 -436.16445) (xy 390.326982 -436.184003)
			(xy 390.334505 -436.206997) (xy 390.335008 -436.219092) (xy 390.335008 -438.760616) (xy 390.334598 -438.772725)
			(xy 390.327095 -438.795751) (xy 390.312831 -438.815324) (xy 390.293209 -438.829518) (xy 390.270156 -438.83694)
			(xy 390.258046 -438.837324) (xy 389.318246 -438.837324) (xy 389.306155 -438.836853) (xy 389.28315 -438.829404)
			(xy 389.263566 -438.81522) (xy 389.249315 -438.795685) (xy 389.241789 -438.772705) (xy 389.241284 -438.760616)
			(xy 389.241284 -438.147968) (xy 389.239739 -438.133476) (xy 389.238087 -438.104376) (xy 389.237982 -438.089802)
			(xy 388.335012 -438.089802) (xy 388.335012 -439.0898) (xy 391.237978 -439.0898) (xy 391.238071 -439.075226)
			(xy 391.239724 -439.046125) (xy 391.24128 -439.031634) (xy 391.24128 -437.94807) (xy 391.239736 -437.933578)
			(xy 391.238083 -437.904478) (xy 391.237978 -437.889904) (xy 391.238071 -437.87533) (xy 391.239724 -437.846229)
			(xy 391.24128 -437.831738) (xy 391.24128 -437.21909) (xy 391.241652 -437.206963) (xy 391.249152 -437.183896)
			(xy 391.263415 -437.164278) (xy 391.283043 -437.150029) (xy 391.306114 -437.142544) (xy 391.318242 -437.142128)
			(xy 392.258042 -437.142128) (xy 392.270158 -437.142576) (xy 392.293201 -437.150073) (xy 392.312801 -437.164322)
			(xy 392.327041 -437.183928) (xy 392.334529 -437.206974) (xy 392.335004 -437.21909) (xy 392.335004 -438.089802)
			(xy 393.237974 -438.089802) (xy 393.238067 -438.075228) (xy 393.23972 -438.046127) (xy 393.241276 -438.031636)
			(xy 393.241276 -436.948072) (xy 393.239732 -436.93358) (xy 393.238079 -436.90448) (xy 393.237974 -436.889906)
			(xy 393.238067 -436.875332) (xy 393.23972 -436.846231) (xy 393.241276 -436.83174) (xy 393.241276 -436.219092)
			(xy 393.241709 -436.206985) (xy 393.249208 -436.183962) (xy 393.263466 -436.164391) (xy 393.283082 -436.150195)
			(xy 393.30613 -436.142771) (xy 393.318238 -436.142384) (xy 394.258038 -436.142384) (xy 394.270134 -436.142776)
			(xy 394.293143 -436.150248) (xy 394.312726 -436.164453) (xy 394.326974 -436.184004) (xy 394.334497 -436.206997)
			(xy 394.335 -436.219092) (xy 394.335 -438.760616) (xy 394.334597 -438.772726) (xy 394.327094 -438.795754)
			(xy 394.312828 -438.815326) (xy 394.293204 -438.82952) (xy 394.270149 -438.836941) (xy 394.258038 -438.837324)
			(xy 393.318238 -438.837324) (xy 393.306147 -438.83686) (xy 393.283141 -438.829409) (xy 393.263558 -438.815223)
			(xy 393.249307 -438.795686) (xy 393.241781 -438.772706) (xy 393.241276 -438.760616) (xy 393.241276 -438.147968)
			(xy 393.239731 -438.133476) (xy 393.238079 -438.104376) (xy 393.237974 -438.089802) (xy 392.335004 -438.089802)
			(xy 392.335004 -439.0898) (xy 395.23797 -439.0898) (xy 395.238063 -439.075226) (xy 395.239716 -439.046125)
			(xy 395.241272 -439.031634) (xy 395.241272 -437.94807) (xy 395.239728 -437.933578) (xy 395.238075 -437.904478)
			(xy 395.23797 -437.889904) (xy 395.238063 -437.87533) (xy 395.239716 -437.846229) (xy 395.241272 -437.831738)
			(xy 395.241272 -437.21909) (xy 395.241652 -437.206963) (xy 395.249151 -437.183898) (xy 395.263412 -437.164281)
			(xy 395.283038 -437.150031) (xy 395.306107 -437.142545) (xy 395.318234 -437.142128) (xy 396.258034 -437.142128)
			(xy 396.270149 -437.142583) (xy 396.293192 -437.150078) (xy 396.312792 -437.164325) (xy 396.327033 -437.18393)
			(xy 396.334521 -437.206975) (xy 396.334996 -437.21909) (xy 396.334996 -438.089802) (xy 398.237964 -438.089802)
			(xy 398.238081 -438.074717) (xy 398.239857 -438.044598) (xy 398.24152 -438.029604) (xy 398.24152 -436.950104)
			(xy 398.23985 -436.935111) (xy 398.238072 -436.904992) (xy 398.237964 -436.889906) (xy 398.238072 -436.87482)
			(xy 398.239854 -436.844702) (xy 398.24152 -436.829708) (xy 398.24152 -436.219092) (xy 398.241906 -436.207006)
			(xy 398.249379 -436.184018) (xy 398.263591 -436.164466) (xy 398.283151 -436.150263) (xy 398.306142 -436.1428)
			(xy 398.318228 -436.142384) (xy 399.258028 -436.142384) (xy 399.270103 -436.14284) (xy 399.29307 -436.150309)
			(xy 399.312606 -436.164508) (xy 399.3268 -436.184048) (xy 399.334263 -436.207017) (xy 399.334736 -436.219092)
			(xy 399.334736 -438.760616) (xy 399.33425 -438.772689) (xy 399.326786 -438.795651) (xy 399.312594 -438.815186)
			(xy 399.293062 -438.829381) (xy 399.270101 -438.836848) (xy 399.258028 -438.837324) (xy 398.318228 -438.837324)
			(xy 398.306148 -438.836864) (xy 398.283169 -438.829406) (xy 398.26362 -438.815211) (xy 398.249414 -438.79567)
			(xy 398.241943 -438.772695) (xy 398.24152 -438.760616) (xy 398.24152 -438.15) (xy 398.239849 -438.135007)
			(xy 398.238072 -438.104888) (xy 398.237964 -438.089802) (xy 396.334996 -438.089802) (xy 396.334996 -439.0898)
			(xy 400.23796 -439.0898) (xy 400.238077 -439.074715) (xy 400.239853 -439.044596) (xy 400.241516 -439.029602)
			(xy 400.241516 -437.950102) (xy 400.239845 -437.935109) (xy 400.238068 -437.90499) (xy 400.23796 -437.889904)
			(xy 400.238077 -437.874819) (xy 400.239853 -437.8447) (xy 400.241516 -437.829706) (xy 400.241516 -437.21909)
			(xy 400.241999 -437.207002) (xy 400.249455 -437.184006) (xy 400.263639 -437.164428) (xy 400.283167 -437.150177)
			(xy 400.306138 -437.142641) (xy 400.318224 -437.142128) (xy 401.258024 -437.142128) (xy 401.270137 -437.142496)
			(xy 401.29317 -437.150006) (xy 401.312745 -437.164279) (xy 401.326938 -437.183912) (xy 401.334353 -437.206975)
			(xy 401.334732 -437.21909) (xy 401.334732 -438.089802) (xy 402.237956 -438.089802) (xy 402.238073 -438.074717)
			(xy 402.239849 -438.044598) (xy 402.241512 -438.029604) (xy 402.241512 -436.950104) (xy 402.239842 -436.935111)
			(xy 402.238064 -436.904992) (xy 402.237956 -436.889906) (xy 402.238064 -436.87482) (xy 402.239846 -436.844702)
			(xy 402.241512 -436.829708) (xy 402.241512 -436.219092) (xy 402.241906 -436.207007) (xy 402.249378 -436.18402)
			(xy 402.263588 -436.164469) (xy 402.283146 -436.150265) (xy 402.306135 -436.142802) (xy 402.31822 -436.142384)
			(xy 403.25802 -436.142384) (xy 403.270095 -436.142847) (xy 403.293061 -436.150314) (xy 403.312597 -436.164511)
			(xy 403.326791 -436.18405) (xy 403.334255 -436.207017) (xy 403.334728 -436.219092) (xy 403.334728 -438.760616)
			(xy 403.33425 -438.772689) (xy 403.326785 -438.795654) (xy 403.312591 -438.815189) (xy 403.293057 -438.829383)
			(xy 403.270093 -438.836849) (xy 403.25802 -438.837324) (xy 402.31822 -438.837324) (xy 402.30614 -438.83687)
			(xy 402.283161 -438.82941) (xy 402.263611 -438.815214) (xy 402.249406 -438.795672) (xy 402.241935 -438.772696)
			(xy 402.241512 -438.760616) (xy 402.241512 -438.15) (xy 402.239841 -438.135007) (xy 402.238064 -438.104888)
			(xy 402.237956 -438.089802) (xy 401.334732 -438.089802) (xy 401.334732 -439.0898) (xy 404.237952 -439.0898)
			(xy 404.238069 -439.074715) (xy 404.239845 -439.044596) (xy 404.241508 -439.029602) (xy 404.241508 -437.950102)
			(xy 404.239837 -437.935109) (xy 404.23806 -437.90499) (xy 404.237952 -437.889904) (xy 404.238069 -437.874819)
			(xy 404.239845 -437.8447) (xy 404.241508 -437.829706) (xy 404.241508 -437.21909) (xy 404.241998 -437.207003)
			(xy 404.249454 -437.184008) (xy 404.263636 -437.164431) (xy 404.283162 -437.150179) (xy 404.306131 -437.142642)
			(xy 404.318216 -437.142128) (xy 405.258016 -437.142128) (xy 405.270129 -437.142503) (xy 405.293161 -437.15001)
			(xy 405.312736 -437.164281) (xy 405.326929 -437.183914) (xy 405.334345 -437.206976) (xy 405.334724 -437.21909)
			(xy 405.334724 -438.089802) (xy 406.237948 -438.089802) (xy 406.238065 -438.074717) (xy 406.239841 -438.044598)
			(xy 406.241504 -438.029604) (xy 406.241504 -436.950104) (xy 406.239834 -436.935111) (xy 406.238056 -436.904992)
			(xy 406.237948 -436.889906) (xy 406.238056 -436.87482) (xy 406.239838 -436.844702) (xy 406.241504 -436.829708)
			(xy 406.241504 -436.219092) (xy 406.241906 -436.207008) (xy 406.249377 -436.184023) (xy 406.263586 -436.164471)
			(xy 406.283141 -436.150268) (xy 406.306128 -436.142803) (xy 406.318212 -436.142384) (xy 407.258012 -436.142384)
			(xy 407.270086 -436.142854) (xy 407.293053 -436.150319) (xy 407.312589 -436.164514) (xy 407.326783 -436.184051)
			(xy 407.334247 -436.207018) (xy 407.33472 -436.219092) (xy 407.33472 -438.760616) (xy 407.334249 -438.77269)
			(xy 407.326784 -438.795656) (xy 407.312589 -438.815191) (xy 407.293052 -438.829386) (xy 407.270086 -438.83685)
			(xy 407.258012 -438.837324) (xy 406.318212 -438.837324) (xy 406.30614 -438.836826) (xy 406.283176 -438.829369)
			(xy 406.26364 -438.81518) (xy 406.249444 -438.79565) (xy 406.241979 -438.772688) (xy 406.241504 -438.760616)
			(xy 406.241504 -438.15) (xy 406.239833 -438.135007) (xy 406.238056 -438.104888) (xy 406.237948 -438.089802)
			(xy 405.334724 -438.089802) (xy 405.334724 -439.0898) (xy 408.237944 -439.0898) (xy 408.238061 -439.074715)
			(xy 408.239837 -439.044596) (xy 408.2415 -439.029602) (xy 408.2415 -437.950102) (xy 408.239829 -437.935109)
			(xy 408.238052 -437.90499) (xy 408.237944 -437.889904) (xy 408.238061 -437.874819) (xy 408.239837 -437.8447)
			(xy 408.2415 -437.829706) (xy 408.2415 -437.21909) (xy 408.241998 -437.207004) (xy 408.249453 -437.18401)
			(xy 408.263633 -437.164434) (xy 408.283157 -437.150182) (xy 408.306124 -437.142643) (xy 408.318208 -437.142128)
			(xy 409.258008 -437.142128) (xy 409.27012 -437.14251) (xy 409.293152 -437.150015) (xy 409.312728 -437.164284)
			(xy 409.326921 -437.183915) (xy 409.334337 -437.206976) (xy 409.334716 -437.21909) (xy 409.334716 -438.089802)
			(xy 410.23794 -438.089802) (xy 410.238057 -438.074717) (xy 410.239833 -438.044598) (xy 410.241496 -438.029604)
			(xy 410.241496 -436.950104) (xy 410.239826 -436.935111) (xy 410.238048 -436.904992) (xy 410.23794 -436.889906)
			(xy 410.23805 -436.87482) (xy 410.239832 -436.844702) (xy 410.241496 -436.829708) (xy 410.241496 -436.219092)
			(xy 410.241958 -436.207017) (xy 410.249423 -436.184049) (xy 410.26362 -436.164511) (xy 410.283159 -436.150317)
			(xy 410.306129 -436.142856) (xy 410.318204 -436.142384) (xy 411.258004 -436.142384) (xy 411.270078 -436.142861)
			(xy 411.293044 -436.150323) (xy 411.31258 -436.164517) (xy 411.326775 -436.184053) (xy 411.334239 -436.207018)
			(xy 411.334712 -436.219092) (xy 411.334712 -438.760616) (xy 411.334249 -438.772691) (xy 411.326783 -438.795658)
			(xy 411.312586 -438.815194) (xy 411.293047 -438.829388) (xy 411.270079 -438.836851) (xy 411.258004 -438.837324)
			(xy 410.318204 -438.837324) (xy 410.306131 -438.836833) (xy 410.283167 -438.829373) (xy 410.263631 -438.815183)
			(xy 410.249436 -438.795651) (xy 410.241971 -438.772689) (xy 410.241496 -438.760616) (xy 410.241496 -438.15)
			(xy 410.239825 -438.135007) (xy 410.238048 -438.104888) (xy 410.23794 -438.089802) (xy 409.334716 -438.089802)
			(xy 409.334716 -439.0898) (xy 412.237936 -439.0898) (xy 412.238053 -439.074715) (xy 412.239829 -439.044596)
			(xy 412.241492 -439.029602) (xy 412.241492 -437.950102) (xy 412.239821 -437.935109) (xy 412.238044 -437.90499)
			(xy 412.237936 -437.889904) (xy 412.238053 -437.874819) (xy 412.239829 -437.8447) (xy 412.241492 -437.829706)
			(xy 412.241492 -437.21909) (xy 412.241998 -437.207005) (xy 412.249452 -437.184012) (xy 412.26363 -437.164436)
			(xy 412.283152 -437.150184) (xy 412.306117 -437.142644) (xy 412.3182 -437.142128) (xy 413.258 -437.142128)
			(xy 413.270112 -437.142516) (xy 413.293144 -437.150019) (xy 413.312719 -437.164287) (xy 413.326913 -437.183916)
			(xy 413.334329 -437.206977) (xy 413.334708 -437.21909) (xy 413.334708 -439.760614) (xy 413.334206 -439.7727)
			(xy 413.326751 -439.795693) (xy 413.312572 -439.815268) (xy 413.293049 -439.82952) (xy 413.270084 -439.83706)
			(xy 413.258 -439.837576) (xy 412.3182 -439.837576) (xy 412.306089 -439.837184) (xy 412.283057 -439.829681)
			(xy 412.263482 -439.815414) (xy 412.249288 -439.795786) (xy 412.241872 -439.772727) (xy 412.241492 -439.760614)
			(xy 412.241492 -439.149998) (xy 412.239821 -439.135005) (xy 412.238044 -439.104886) (xy 412.237936 -439.0898)
			(xy 409.334716 -439.0898) (xy 409.334716 -439.760614) (xy 409.334304 -439.772709) (xy 409.326838 -439.795717)
			(xy 409.312639 -439.815301) (xy 409.293091 -439.829549) (xy 409.270101 -439.837073) (xy 409.258008 -439.837576)
			(xy 408.318208 -439.837576) (xy 408.306097 -439.837177) (xy 408.283066 -439.829677) (xy 408.263491 -439.815412)
			(xy 408.249296 -439.795785) (xy 408.24188 -439.772726) (xy 408.2415 -439.760614) (xy 408.2415 -439.149998)
			(xy 408.239829 -439.135005) (xy 408.238052 -439.104886) (xy 408.237944 -439.0898) (xy 405.334724 -439.0898)
			(xy 405.334724 -439.760614) (xy 405.334304 -439.772708) (xy 405.326839 -439.795715) (xy 405.312642 -439.815298)
			(xy 405.293096 -439.829547) (xy 405.270109 -439.837072) (xy 405.258016 -439.837576) (xy 404.318216 -439.837576)
			(xy 404.306106 -439.83717) (xy 404.283075 -439.829672) (xy 404.263499 -439.815408) (xy 404.249305 -439.795783)
			(xy 404.241888 -439.772726) (xy 404.241508 -439.760614) (xy 404.241508 -439.149998) (xy 404.239837 -439.135005)
			(xy 404.23806 -439.104886) (xy 404.237952 -439.0898) (xy 401.334732 -439.0898) (xy 401.334732 -439.760614)
			(xy 401.334304 -439.772707) (xy 401.32684 -439.795713) (xy 401.312645 -439.815295) (xy 401.293101 -439.829544)
			(xy 401.270116 -439.837071) (xy 401.258024 -439.837576) (xy 400.318224 -439.837576) (xy 400.306114 -439.837163)
			(xy 400.283083 -439.829667) (xy 400.263508 -439.815406) (xy 400.249313 -439.795781) (xy 400.241896 -439.772725)
			(xy 400.241516 -439.760614) (xy 400.241516 -439.149998) (xy 400.239845 -439.135005) (xy 400.238068 -439.104886)
			(xy 400.23796 -439.0898) (xy 396.334996 -439.0898) (xy 396.334996 -439.760614) (xy 396.334501 -439.772726)
			(xy 396.327014 -439.795764) (xy 396.312777 -439.815363) (xy 396.293182 -439.829605) (xy 396.270146 -439.837098)
			(xy 396.258034 -439.837576) (xy 395.318234 -439.837576) (xy 395.306114 -439.837111) (xy 395.283059 -439.82963)
			(xy 395.263445 -439.81539) (xy 395.249192 -439.795784) (xy 395.241696 -439.772733) (xy 395.241272 -439.760614)
			(xy 395.241272 -439.147966) (xy 395.239727 -439.133474) (xy 395.238075 -439.104374) (xy 395.23797 -439.0898)
			(xy 392.335004 -439.0898) (xy 392.335004 -439.760614) (xy 392.334501 -439.772725) (xy 392.327015 -439.795762)
			(xy 392.31278 -439.81536) (xy 392.293187 -439.829602) (xy 392.270153 -439.837097) (xy 392.258042 -439.837576)
			(xy 391.318242 -439.837576) (xy 391.306123 -439.837105) (xy 391.283068 -439.829626) (xy 391.263453 -439.815387)
			(xy 391.2492 -439.795783) (xy 391.241704 -439.772733) (xy 391.24128 -439.760614) (xy 391.24128 -439.147966)
			(xy 391.239735 -439.133474) (xy 391.238083 -439.104374) (xy 391.237978 -439.0898) (xy 388.335012 -439.0898)
			(xy 388.335012 -439.760614) (xy 388.334501 -439.772724) (xy 388.327016 -439.79576) (xy 388.312782 -439.815357)
			(xy 388.293192 -439.8296) (xy 388.27016 -439.837096) (xy 388.25805 -439.837576) (xy 387.31825 -439.837576)
			(xy 387.306134 -439.837131) (xy 387.283092 -439.829632) (xy 387.263492 -439.815382) (xy 387.249252 -439.795776)
			(xy 387.241763 -439.77273) (xy 387.241288 -439.760614) (xy 387.241288 -439.147966) (xy 387.239743 -439.133474)
			(xy 387.238091 -439.104374) (xy 387.237986 -439.0898) (xy 384.33502 -439.0898) (xy 384.33502 -439.760614)
			(xy 384.334651 -439.772742) (xy 384.32715 -439.795808) (xy 384.312886 -439.815426) (xy 384.293258 -439.829675)
			(xy 384.270186 -439.83716) (xy 384.258058 -439.837576) (xy 383.318258 -439.837576) (xy 383.306143 -439.837124)
			(xy 383.2831 -439.829627) (xy 383.263501 -439.815379) (xy 383.24926 -439.795774) (xy 383.241771 -439.77273)
			(xy 383.241296 -439.760614) (xy 383.241296 -439.147966) (xy 383.239751 -439.133474) (xy 383.238099 -439.104374)
			(xy 383.237994 -439.0898) (xy 346.23502 -439.0898) (xy 346.23502 -439.760614) (xy 346.234651 -439.772742)
			(xy 346.22715 -439.795808) (xy 346.212886 -439.815426) (xy 346.193258 -439.829675) (xy 346.170186 -439.83716)
			(xy 346.158058 -439.837576) (xy 345.218258 -439.837576) (xy 345.206143 -439.837124) (xy 345.1831 -439.829627)
			(xy 345.163501 -439.815379) (xy 345.14926 -439.795774) (xy 345.141771 -439.77273) (xy 345.141296 -439.760614)
			(xy 345.141296 -439.147966) (xy 345.139751 -439.133474) (xy 345.138099 -439.104374) (xy 345.137994 -439.0898)
			(xy 342.235028 -439.0898) (xy 342.235028 -439.760614) (xy 342.234651 -439.772741) (xy 342.227151 -439.795806)
			(xy 342.212889 -439.815424) (xy 342.193263 -439.829673) (xy 342.170193 -439.837159) (xy 342.158066 -439.837576)
			(xy 341.218266 -439.837576) (xy 341.206151 -439.837118) (xy 341.183109 -439.829623) (xy 341.163509 -439.815377)
			(xy 341.149268 -439.795773) (xy 341.141779 -439.772729) (xy 341.141304 -439.760614) (xy 341.141304 -439.147966)
			(xy 341.139759 -439.133474) (xy 341.138107 -439.104374) (xy 341.138002 -439.0898) (xy 338.235036 -439.0898)
			(xy 338.235036 -439.760614) (xy 338.234651 -439.77274) (xy 338.227152 -439.795804) (xy 338.212892 -439.815421)
			(xy 338.193268 -439.82967) (xy 338.1702 -439.837158) (xy 338.158074 -439.837576) (xy 337.218274 -439.837576)
			(xy 337.206159 -439.837111) (xy 337.183118 -439.829618) (xy 337.163518 -439.815374) (xy 337.149276 -439.795772)
			(xy 337.141787 -439.772729) (xy 337.141312 -439.760614) (xy 337.141312 -439.147966) (xy 337.139767 -439.133474)
			(xy 337.138115 -439.104374) (xy 337.13801 -439.0898) (xy 334.235044 -439.0898) (xy 334.235044 -439.760614)
			(xy 334.234651 -439.772739) (xy 334.227153 -439.795802) (xy 334.212895 -439.815418) (xy 334.193273 -439.829668)
			(xy 334.170207 -439.837157) (xy 334.158082 -439.837576) (xy 333.218282 -439.837576) (xy 333.206168 -439.837104)
			(xy 333.183126 -439.829614) (xy 333.163526 -439.815371) (xy 333.149285 -439.79577) (xy 333.141795 -439.772728)
			(xy 333.14132 -439.760614) (xy 333.14132 -439.147966) (xy 333.139775 -439.133474) (xy 333.138123 -439.104374)
			(xy 333.138018 -439.0898) (xy 329.2348 -439.0898) (xy 329.2348 -439.760614) (xy 329.234306 -439.7727)
			(xy 329.22685 -439.795695) (xy 329.212669 -439.815271) (xy 329.193144 -439.829523) (xy 329.170177 -439.837061)
			(xy 329.158092 -439.837576) (xy 328.218292 -439.837576) (xy 328.20618 -439.83719) (xy 328.183149 -439.829686)
			(xy 328.163574 -439.815417) (xy 328.14938 -439.795788) (xy 328.141964 -439.772727) (xy 328.141584 -439.760614)
			(xy 328.141584 -439.149998) (xy 328.139913 -439.135005) (xy 328.138136 -439.104886) (xy 328.138028 -439.0898)
			(xy 325.234808 -439.0898) (xy 325.234808 -439.760614) (xy 325.234306 -439.7727) (xy 325.226851 -439.795693)
			(xy 325.212672 -439.815268) (xy 325.193149 -439.82952) (xy 325.170184 -439.83706) (xy 325.1581 -439.837576)
			(xy 324.2183 -439.837576) (xy 324.206189 -439.837184) (xy 324.183157 -439.829681) (xy 324.163582 -439.815414)
			(xy 324.149388 -439.795786) (xy 324.141972 -439.772727) (xy 324.141592 -439.760614) (xy 324.141592 -439.149998)
			(xy 324.139921 -439.135005) (xy 324.138144 -439.104886) (xy 324.138036 -439.0898) (xy 321.234816 -439.0898)
			(xy 321.234816 -439.760614) (xy 321.234404 -439.772709) (xy 321.226938 -439.795717) (xy 321.212739 -439.815301)
			(xy 321.193191 -439.829549) (xy 321.170201 -439.837073) (xy 321.158108 -439.837576) (xy 320.218308 -439.837576)
			(xy 320.206197 -439.837177) (xy 320.183166 -439.829677) (xy 320.163591 -439.815412) (xy 320.149396 -439.795785)
			(xy 320.14198 -439.772726) (xy 320.1416 -439.760614) (xy 320.1416 -439.149998) (xy 320.139929 -439.135005)
			(xy 320.138152 -439.104886) (xy 320.138044 -439.0898) (xy 317.234824 -439.0898) (xy 317.234824 -439.760614)
			(xy 317.234404 -439.772708) (xy 317.226939 -439.795715) (xy 317.212742 -439.815298) (xy 317.193196 -439.829547)
			(xy 317.170209 -439.837072) (xy 317.158116 -439.837576) (xy 316.218316 -439.837576) (xy 316.206206 -439.83717)
			(xy 316.183175 -439.829672) (xy 316.163599 -439.815408) (xy 316.149405 -439.795783) (xy 316.141988 -439.772726)
			(xy 316.141608 -439.760614) (xy 316.141608 -439.149998) (xy 316.139937 -439.135005) (xy 316.13816 -439.104886)
			(xy 316.138052 -439.0898) (xy 157.334712 -439.0898) (xy 157.334712 -439.760614) (xy 157.334304 -439.772709)
			(xy 157.326838 -439.795718) (xy 157.312637 -439.815302) (xy 157.293089 -439.829551) (xy 157.270098 -439.837074)
			(xy 157.258004 -439.837576) (xy 156.318204 -439.837576) (xy 156.306093 -439.83718) (xy 156.283062 -439.829679)
			(xy 156.263486 -439.815413) (xy 156.249292 -439.795785) (xy 156.241876 -439.772727) (xy 156.241496 -439.760614)
			(xy 156.241496 -439.149998) (xy 156.239825 -439.135005) (xy 156.238048 -439.104886) (xy 156.23794 -439.0898)
			(xy 153.33472 -439.0898) (xy 153.33472 -439.760614) (xy 153.334304 -439.772708) (xy 153.326839 -439.795716)
			(xy 153.31264 -439.815299) (xy 153.293094 -439.829548) (xy 153.270105 -439.837073) (xy 153.258012 -439.837576)
			(xy 152.318212 -439.837576) (xy 152.306101 -439.837173) (xy 152.28307 -439.829674) (xy 152.263495 -439.81541)
			(xy 152.249301 -439.795784) (xy 152.241884 -439.772726) (xy 152.241504 -439.760614) (xy 152.241504 -439.149998)
			(xy 152.239833 -439.135005) (xy 152.238056 -439.104886) (xy 152.237948 -439.0898) (xy 149.334728 -439.0898)
			(xy 149.334728 -439.760614) (xy 149.334304 -439.772708) (xy 149.32684 -439.795714) (xy 149.312643 -439.815297)
			(xy 149.293099 -439.829546) (xy 149.270112 -439.837072) (xy 149.25802 -439.837576) (xy 148.31822 -439.837576)
			(xy 148.30611 -439.837166) (xy 148.283079 -439.829669) (xy 148.263504 -439.815407) (xy 148.249309 -439.795782)
			(xy 148.241892 -439.772726) (xy 148.241512 -439.760614) (xy 148.241512 -439.149998) (xy 148.239841 -439.135005)
			(xy 148.238064 -439.104886) (xy 148.237956 -439.0898) (xy 145.334736 -439.0898) (xy 145.334736 -439.760614)
			(xy 145.334304 -439.772707) (xy 145.326841 -439.795712) (xy 145.312646 -439.815294) (xy 145.293104 -439.829543)
			(xy 145.270119 -439.83707) (xy 145.258028 -439.837576) (xy 144.318228 -439.837576) (xy 144.306118 -439.837159)
			(xy 144.283088 -439.829665) (xy 144.263512 -439.815404) (xy 144.249317 -439.795781) (xy 144.2419 -439.772725)
			(xy 144.24152 -439.760614) (xy 144.24152 -439.149998) (xy 144.239849 -439.135005) (xy 144.238072 -439.104886)
			(xy 144.237964 -439.0898) (xy 140.335 -439.0898) (xy 140.335 -439.760614) (xy 140.334501 -439.772726)
			(xy 140.327015 -439.795763) (xy 140.312778 -439.815361) (xy 140.293184 -439.829604) (xy 140.270149 -439.837097)
			(xy 140.258038 -439.837576) (xy 139.318238 -439.837576) (xy 139.306119 -439.837108) (xy 139.283063 -439.829628)
			(xy 139.263449 -439.815388) (xy 139.249196 -439.795783) (xy 139.2417 -439.772733) (xy 139.241276 -439.760614)
			(xy 139.241276 -439.147966) (xy 139.239731 -439.133474) (xy 139.238079 -439.104374) (xy 139.237974 -439.0898)
			(xy 136.335008 -439.0898) (xy 136.335008 -439.760614) (xy 136.334501 -439.772725) (xy 136.327016 -439.795761)
			(xy 136.312781 -439.815358) (xy 136.293189 -439.829601) (xy 136.270157 -439.837096) (xy 136.258046 -439.837576)
			(xy 135.318246 -439.837576) (xy 135.306127 -439.837101) (xy 135.283072 -439.829623) (xy 135.263457 -439.815385)
			(xy 135.249204 -439.795782) (xy 135.241708 -439.772733) (xy 135.241284 -439.760614) (xy 135.241284 -439.147966)
			(xy 135.239739 -439.133474) (xy 135.238087 -439.104374) (xy 135.237982 -439.0898) (xy 132.335016 -439.0898)
			(xy 132.335016 -439.760614) (xy 132.334651 -439.772742) (xy 132.327149 -439.795809) (xy 132.312885 -439.815428)
			(xy 132.293255 -439.829677) (xy 132.270182 -439.83716) (xy 132.258054 -439.837576) (xy 131.318254 -439.837576)
			(xy 131.306138 -439.837128) (xy 131.283096 -439.82963) (xy 131.263496 -439.815381) (xy 131.249256 -439.795775)
			(xy 131.241767 -439.77273) (xy 131.241292 -439.760614) (xy 131.241292 -439.147966) (xy 131.239747 -439.133474)
			(xy 131.238095 -439.104374) (xy 131.23799 -439.0898) (xy 128.335024 -439.0898) (xy 128.335024 -439.760614)
			(xy 128.334651 -439.772741) (xy 128.32715 -439.795807) (xy 128.312888 -439.815425) (xy 128.29326 -439.829674)
			(xy 128.27019 -439.837159) (xy 128.258062 -439.837576) (xy 127.318262 -439.837576) (xy 127.306147 -439.837121)
			(xy 127.283105 -439.829625) (xy 127.263505 -439.815378) (xy 127.249264 -439.795774) (xy 127.241775 -439.772729)
			(xy 127.2413 -439.760614) (xy 127.2413 -439.147966) (xy 127.239755 -439.133474) (xy 127.238103 -439.104374)
			(xy 127.237998 -439.0898) (xy 90.235024 -439.0898) (xy 90.235024 -439.760614) (xy 90.234651 -439.772741)
			(xy 90.22715 -439.795807) (xy 90.212888 -439.815425) (xy 90.19326 -439.829674) (xy 90.17019 -439.837159)
			(xy 90.158062 -439.837576) (xy 89.218262 -439.837576) (xy 89.206147 -439.837121) (xy 89.183105 -439.829625)
			(xy 89.163505 -439.815378) (xy 89.149264 -439.795774) (xy 89.141775 -439.772729) (xy 89.1413 -439.760614)
			(xy 89.1413 -439.147966) (xy 89.139755 -439.133474) (xy 89.138103 -439.104374) (xy 89.137998 -439.0898)
			(xy 86.235032 -439.0898) (xy 86.235032 -439.760614) (xy 86.234651 -439.77274) (xy 86.227152 -439.795805)
			(xy 86.212891 -439.815422) (xy 86.193265 -439.829672) (xy 86.170197 -439.837158) (xy 86.15807 -439.837576)
			(xy 85.21827 -439.837576) (xy 85.206155 -439.837114) (xy 85.183113 -439.82962) (xy 85.163513 -439.815375)
			(xy 85.149272 -439.795772) (xy 85.141783 -439.772729) (xy 85.141308 -439.760614) (xy 85.141308 -439.147966)
			(xy 85.139763 -439.133474) (xy 85.138111 -439.104374) (xy 85.138006 -439.0898) (xy 82.23504 -439.0898)
			(xy 82.23504 -439.760614) (xy 82.234651 -439.77274) (xy 82.227153 -439.795803) (xy 82.212894 -439.815419)
			(xy 82.19327 -439.829669) (xy 82.170204 -439.837157) (xy 82.158078 -439.837576) (xy 81.218278 -439.837576)
			(xy 81.206164 -439.837107) (xy 81.183122 -439.829616) (xy 81.163522 -439.815372) (xy 81.149281 -439.795771)
			(xy 81.141791 -439.772728) (xy 81.141316 -439.760614) (xy 81.141316 -439.147966) (xy 81.139771 -439.133474)
			(xy 81.138119 -439.104374) (xy 81.138014 -439.0898) (xy 78.235048 -439.0898) (xy 78.235048 -439.760614)
			(xy 78.2346 -439.772731) (xy 78.227107 -439.795777) (xy 78.21286 -439.81538) (xy 78.193252 -439.82962)
			(xy 78.170203 -439.837105) (xy 78.158086 -439.837576) (xy 77.218286 -439.837576) (xy 77.206172 -439.837101)
			(xy 77.183131 -439.829611) (xy 77.16353 -439.81537) (xy 77.149289 -439.795769) (xy 77.141799 -439.772728)
			(xy 77.141324 -439.760614) (xy 77.141324 -439.147966) (xy 77.139779 -439.133474) (xy 77.138127 -439.104374)
			(xy 77.138022 -439.0898) (xy 73.234804 -439.0898) (xy 73.234804 -439.760614) (xy 73.234306 -439.7727)
			(xy 73.22685 -439.795694) (xy 73.21267 -439.81527) (xy 73.193146 -439.829521) (xy 73.17018 -439.837061)
			(xy 73.158096 -439.837576) (xy 72.218296 -439.837576) (xy 72.206185 -439.837187) (xy 72.183153 -439.829683)
			(xy 72.163578 -439.815416) (xy 72.149384 -439.795787) (xy 72.141968 -439.772727) (xy 72.141588 -439.760614)
			(xy 72.141588 -439.149998) (xy 72.139917 -439.135005) (xy 72.13814 -439.104886) (xy 72.138032 -439.0898)
			(xy 69.234812 -439.0898) (xy 69.234812 -439.760614) (xy 69.234404 -439.772709) (xy 69.226938 -439.795718)
			(xy 69.212737 -439.815302) (xy 69.193189 -439.829551) (xy 69.170198 -439.837074) (xy 69.158104 -439.837576)
			(xy 68.218304 -439.837576) (xy 68.206193 -439.83718) (xy 68.183162 -439.829679) (xy 68.163586 -439.815413)
			(xy 68.149392 -439.795785) (xy 68.141976 -439.772727) (xy 68.141596 -439.760614) (xy 68.141596 -439.149998)
			(xy 68.139925 -439.135005) (xy 68.138148 -439.104886) (xy 68.13804 -439.0898) (xy 65.23482 -439.0898)
			(xy 65.23482 -439.760614) (xy 65.234404 -439.772708) (xy 65.226939 -439.795716) (xy 65.21274 -439.815299)
			(xy 65.193194 -439.829548) (xy 65.170205 -439.837073) (xy 65.158112 -439.837576) (xy 64.218312 -439.837576)
			(xy 64.206201 -439.837173) (xy 64.18317 -439.829674) (xy 64.163595 -439.81541) (xy 64.149401 -439.795784)
			(xy 64.141984 -439.772726) (xy 64.141604 -439.760614) (xy 64.141604 -439.149998) (xy 64.139933 -439.135005)
			(xy 64.138156 -439.104886) (xy 64.138048 -439.0898) (xy 61.234828 -439.0898) (xy 61.234828 -439.760614)
			(xy 61.234404 -439.772708) (xy 61.22694 -439.795714) (xy 61.212743 -439.815297) (xy 61.193199 -439.829546)
			(xy 61.170212 -439.837072) (xy 61.15812 -439.837576) (xy 60.21832 -439.837576) (xy 60.20621 -439.837166)
			(xy 60.183179 -439.829669) (xy 60.163604 -439.815407) (xy 60.149409 -439.795782) (xy 60.141992 -439.772726)
			(xy 60.141612 -439.760614) (xy 60.141612 -439.149998) (xy 60.139941 -439.135005) (xy 60.138164 -439.104886)
			(xy 60.138056 -439.0898) (xy 7.00913 -439.0898) (xy 7.00913 -439.989976) (xy 7.009638 -440.045746)
			(xy 7.017973 -440.156973) (xy 7.034597 -440.267266) (xy 7.059417 -440.376009) (xy 7.092293 -440.482593)
			(xy 7.133043 -440.586422) (xy 7.181438 -440.686915) (xy 7.237207 -440.783511) (xy 7.300039 -440.87567)
			(xy 7.369583 -440.962874) (xy 7.445449 -441.044639) (xy 7.527212 -441.120505) (xy 7.614417 -441.190048)
			(xy 7.706575 -441.252881) (xy 7.803171 -441.30865) (xy 7.903664 -441.357045) (xy 8.007493 -441.397795)
			(xy 8.114077 -441.430672) (xy 8.22282 -441.455492) (xy 8.333113 -441.472116) (xy 8.44434 -441.480451)
			(xy 8.50011 -441.480956) (xy 194.495928 -441.480956)
		)
		(stroke
			(width 0)
			(type solid)
		)
		(fill yes)
		(layer "In10.Cu")
		(net "GND")
	)
	(gr_line
		(start 184.879488 -406.620726)
		(end 185.209688 -406.950926)
		(stroke
			(width 0.635)
			(type default)
		)
		(layer "In10.Cu")
	)
	(gr_line
		(start 184.879488 -400.685254)
		(end 184.879488 -406.620726)
		(stroke
			(width 0.635)
			(type default)
		)
		(layer "In10.Cu")
	)
	(gr_line
		(start 185.006488 -413.184848)
		(end 185.006488 -408.491182)
		(stroke
			(width 0.635)
			(type default)
		)
		(layer "In10.Cu")
	)
	(gr_line
		(start 185.209688 -408.287982)
		(end 185.006488 -408.491182)
		(stroke
			(width 0.635)
			(type default)
		)
		(layer "In10.Cu")
	)
	(gr_line
		(start 185.209688 -406.950926)
		(end 185.209688 -408.287982)
		(stroke
			(width 0.635)
			(type default)
		)
		(layer "In10.Cu")
	)
	(gr_line
		(start 188.73343 -400.685254)
		(end 184.879488 -400.685254)
		(stroke
			(width 0.635)
			(type default)
		)
		(layer "In10.Cu")
	)
	(gr_line
		(start 188.93536 -403.657054)
		(end 188.93536 -400.890232)
		(stroke
			(width 0.635)
			(type default)
		)
		(layer "In10.Cu")
	)
	(gr_line
		(start 188.93536 -400.890232)
		(end 188.73343 -400.685254)
		(stroke
			(width 0.635)
			(type default)
		)
		(layer "In10.Cu")
	)
	(gr_line
		(start 189.11316 -403.834854)
		(end 188.93536 -403.657054)
		(stroke
			(width 0.635)
			(type default)
		)
		(layer "In10.Cu")
	)
	(gr_line
		(start 189.46876 -403.834854)
		(end 189.11316 -403.834854)
		(stroke
			(width 0.635)
			(type default)
		)
		(layer "In10.Cu")
	)
	(gr_line
		(start 189.680088 -404.477982)
		(end 189.680088 -404.046182)
		(stroke
			(width 0.635)
			(type default)
		)
		(layer "In10.Cu")
	)
	(gr_line
		(start 189.680088 -404.046182)
		(end 189.46876 -403.834854)
		(stroke
			(width 0.635)
			(type default)
		)
		(layer "In10.Cu")
	)
	(gr_line
		(start 190.870332 -405.66848)
		(end 189.680088 -404.477982)
		(stroke
			(width 0.635)
			(type default)
		)
		(layer "In10.Cu")
	)
	(gr_line
		(start 192.75044 -420.9288)
		(end 185.006488 -413.184848)
		(stroke
			(width 0.635)
			(type default)
		)
		(layer "In10.Cu")
	)
	(gr_line
		(start 196.969888 -405.66848)
		(end 190.870332 -405.66848)
		(stroke
			(width 0.635)
			(type default)
		)
		(layer "In10.Cu")
	)
	(gr_line
		(start 197.416928 -420.9288)
		(end 192.75044 -420.9288)
		(stroke
			(width 0.635)
			(type default)
		)
		(layer "In10.Cu")
	)
	(gr_line
		(start 198.15048 -404.487888)
		(end 196.969888 -405.66848)
		(stroke
			(width 0.635)
			(type default)
		)
		(layer "In10.Cu")
	)
	(gr_line
		(start 198.15048 -400.893788)
		(end 198.15048 -404.487888)
		(stroke
			(width 0.635)
			(type default)
		)
		(layer "In10.Cu")
	)
	(gr_line
		(start 198.341488 -400.70278)
		(end 198.15048 -400.893788)
		(stroke
			(width 0.635)
			(type default)
		)
		(layer "In10.Cu")
	)
	(gr_line
		(start 201.995532 -400.70278)
		(end 198.341488 -400.70278)
		(stroke
			(width 0.635)
			(type default)
		)
		(layer "In10.Cu")
	)
	(gr_line
		(start 202.19416 -404.462488)
		(end 202.19416 -400.901408)
		(stroke
			(width 0.635)
			(type default)
		)
		(layer "In10.Cu")
	)
	(gr_line
		(start 202.19416 -400.901408)
		(end 201.995532 -400.70278)
		(stroke
			(width 0.635)
			(type default)
		)
		(layer "In10.Cu")
	)
	(gr_line
		(start 202.380088 -407.607008)
		(end 202.380088 -404.648416)
		(stroke
			(width 0.635)
			(type default)
		)
		(layer "In10.Cu")
	)
	(gr_line
		(start 202.380088 -404.648416)
		(end 202.19416 -404.462488)
		(stroke
			(width 0.635)
			(type default)
		)
		(layer "In10.Cu")
	)
	(gr_line
		(start 204.16012 -409.38704)
		(end 202.380088 -407.607008)
		(stroke
			(width 0.635)
			(type default)
		)
		(layer "In10.Cu")
	)
	(gr_line
		(start 206.17434 -435.523132)
		(end 207.503268 -436.85206)
		(stroke
			(width 0.635)
			(type default)
		)
		(layer "In10.Cu")
	)
	(gr_line
		(start 206.17434 -429.686212)
		(end 197.416928 -420.9288)
		(stroke
			(width 0.635)
			(type default)
		)
		(layer "In10.Cu")
	)
	(gr_line
		(start 206.17434 -429.686212)
		(end 206.17434 -435.523132)
		(stroke
			(width 0.635)
			(type default)
		)
		(layer "In10.Cu")
	)
	(gr_line
		(start 206.545688 -409.38704)
		(end 204.16012 -409.38704)
		(stroke
			(width 0.635)
			(type default)
		)
		(layer "In10.Cu")
	)
	(gr_line
		(start 207.503268 -436.85206)
		(end 228.909372 -436.85206)
		(stroke
			(width 0.635)
			(type default)
		)
		(layer "In10.Cu")
	)
	(gr_line
		(start 208.628488 -407.30424)
		(end 206.545688 -409.38704)
		(stroke
			(width 0.635)
			(type default)
		)
		(layer "In10.Cu")
	)
	(gr_line
		(start 208.628488 -404.642828)
		(end 208.628488 -407.30424)
		(stroke
			(width 0.635)
			(type default)
		)
		(layer "In10.Cu")
	)
	(gr_line
		(start 208.81848 -404.452836)
		(end 208.628488 -404.642828)
		(stroke
			(width 0.635)
			(type default)
		)
		(layer "In10.Cu")
	)
	(gr_line
		(start 208.81848 -400.893788)
		(end 208.81848 -404.452836)
		(stroke
			(width 0.635)
			(type default)
		)
		(layer "In10.Cu")
	)
	(gr_line
		(start 209.009488 -400.70278)
		(end 208.81848 -400.893788)
		(stroke
			(width 0.635)
			(type default)
		)
		(layer "In10.Cu")
	)
	(gr_line
		(start 212.668612 -400.70278)
		(end 209.009488 -400.70278)
		(stroke
			(width 0.635)
			(type default)
		)
		(layer "In10.Cu")
	)
	(gr_line
		(start 212.85962 -404.485348)
		(end 212.85962 -400.893788)
		(stroke
			(width 0.635)
			(type default)
		)
		(layer "In10.Cu")
	)
	(gr_line
		(start 212.85962 -400.893788)
		(end 212.668612 -400.70278)
		(stroke
			(width 0.635)
			(type default)
		)
		(layer "In10.Cu")
	)
	(gr_line
		(start 213.03742 -407.525728)
		(end 213.03742 -404.663148)
		(stroke
			(width 0.635)
			(type default)
		)
		(layer "In10.Cu")
	)
	(gr_line
		(start 213.03742 -404.663148)
		(end 212.85962 -404.485348)
		(stroke
			(width 0.635)
			(type default)
		)
		(layer "In10.Cu")
	)
	(gr_line
		(start 214.794592 -409.2829)
		(end 213.03742 -407.525728)
		(stroke
			(width 0.635)
			(type default)
		)
		(layer "In10.Cu")
	)
	(gr_line
		(start 217.272616 -409.2829)
		(end 214.794592 -409.2829)
		(stroke
			(width 0.635)
			(type default)
		)
		(layer "In10.Cu")
	)
	(gr_line
		(start 219.296488 -407.259028)
		(end 217.272616 -409.2829)
		(stroke
			(width 0.635)
			(type default)
		)
		(layer "In10.Cu")
	)
	(gr_line
		(start 219.296488 -404.673308)
		(end 219.296488 -407.259028)
		(stroke
			(width 0.635)
			(type default)
		)
		(layer "In10.Cu")
	)
	(gr_line
		(start 219.47886 -404.490936)
		(end 219.296488 -404.673308)
		(stroke
			(width 0.635)
			(type default)
		)
		(layer "In10.Cu")
	)
	(gr_line
		(start 219.47886 -400.906488)
		(end 219.47886 -404.490936)
		(stroke
			(width 0.635)
			(type default)
		)
		(layer "In10.Cu")
	)
	(gr_line
		(start 219.682568 -400.70278)
		(end 219.47886 -400.906488)
		(stroke
			(width 0.635)
			(type default)
		)
		(layer "In10.Cu")
	)
	(gr_line
		(start 223.323912 -400.70278)
		(end 219.682568 -400.70278)
		(stroke
			(width 0.635)
			(type default)
		)
		(layer "In10.Cu")
	)
	(gr_line
		(start 223.53524 -404.47976)
		(end 223.53524 -400.914108)
		(stroke
			(width 0.635)
			(type default)
		)
		(layer "In10.Cu")
	)
	(gr_line
		(start 223.53524 -400.914108)
		(end 223.323912 -400.70278)
		(stroke
			(width 0.635)
			(type default)
		)
		(layer "In10.Cu")
	)
	(gr_line
		(start 223.716088 -407.403808)
		(end 223.716088 -404.660608)
		(stroke
			(width 0.635)
			(type default)
		)
		(layer "In10.Cu")
	)
	(gr_line
		(start 223.716088 -404.660608)
		(end 223.53524 -404.47976)
		(stroke
			(width 0.635)
			(type default)
		)
		(layer "In10.Cu")
	)
	(gr_line
		(start 225.70694 -409.39466)
		(end 223.716088 -407.403808)
		(stroke
			(width 0.635)
			(type default)
		)
		(layer "In10.Cu")
	)
	(gr_line
		(start 227.935028 -409.39466)
		(end 225.70694 -409.39466)
		(stroke
			(width 0.635)
			(type default)
		)
		(layer "In10.Cu")
	)
	(gr_line
		(start 228.909372 -436.85206)
		(end 230.69804 -435.063392)
		(stroke
			(width 0.635)
			(type default)
		)
		(layer "In10.Cu")
	)
	(gr_line
		(start 229.939088 -407.3906)
		(end 227.935028 -409.39466)
		(stroke
			(width 0.635)
			(type default)
		)
		(layer "In10.Cu")
	)
	(gr_line
		(start 229.939088 -404.678388)
		(end 229.939088 -407.3906)
		(stroke
			(width 0.635)
			(type default)
		)
		(layer "In10.Cu")
	)
	(gr_line
		(start 230.14432 -404.473156)
		(end 229.939088 -404.678388)
		(stroke
			(width 0.635)
			(type default)
		)
		(layer "In10.Cu")
	)
	(gr_line
		(start 230.14432 -400.901408)
		(end 230.14432 -404.473156)
		(stroke
			(width 0.635)
			(type default)
		)
		(layer "In10.Cu")
	)
	(gr_line
		(start 230.345488 -400.70024)
		(end 230.14432 -400.901408)
		(stroke
			(width 0.635)
			(type default)
		)
		(layer "In10.Cu")
	)
	(gr_line
		(start 230.69804 -423.45102)
		(end 230.69804 -435.063392)
		(stroke
			(width 0.635)
			(type default)
		)
		(layer "In10.Cu")
	)
	(gr_line
		(start 233.172 -420.97706)
		(end 230.69804 -423.45102)
		(stroke
			(width 0.635)
			(type default)
		)
		(layer "In10.Cu")
	)
	(gr_line
		(start 233.996992 -400.70024)
		(end 230.345488 -400.70024)
		(stroke
			(width 0.635)
			(type default)
		)
		(layer "In10.Cu")
	)
	(gr_line
		(start 234.19816 -404.477728)
		(end 234.19816 -400.901408)
		(stroke
			(width 0.635)
			(type default)
		)
		(layer "In10.Cu")
	)
	(gr_line
		(start 234.19816 -400.901408)
		(end 233.996992 -400.70024)
		(stroke
			(width 0.635)
			(type default)
		)
		(layer "In10.Cu")
	)
	(gr_line
		(start 235.520992 -405.80056)
		(end 234.19816 -404.477728)
		(stroke
			(width 0.635)
			(type default)
		)
		(layer "In10.Cu")
	)
	(gr_line
		(start 237.746032 -405.80056)
		(end 235.520992 -405.80056)
		(stroke
			(width 0.635)
			(type default)
		)
		(layer "In10.Cu")
	)
	(gr_line
		(start 239.10036 -406.737312)
		(end 238.682784 -406.737312)
		(stroke
			(width 0.635)
			(type default)
		)
		(layer "In10.Cu")
	)
	(gr_line
		(start 239.3315 -406.506172)
		(end 239.10036 -406.737312)
		(stroke
			(width 0.635)
			(type default)
		)
		(layer "In10.Cu")
	)
	(gr_arc
		(start 239.3315 -406.506172)
		(mid 239.359619 -406.647264)
		(end 239.439704 -406.766776)
		(stroke
			(width 0.635)
			(type default)
		)
		(layer "In10.Cu")
	)
	(gr_line
		(start 239.3315 -397.839946)
		(end 239.3315 -406.506172)
		(stroke
			(width 0.635)
			(type default)
		)
		(layer "In10.Cu")
	)
	(gr_line
		(start 239.387634 -397.701516)
		(end 239.3315 -397.839946)
		(stroke
			(width 0.635)
			(type default)
		)
		(layer "In10.Cu")
	)
	(gr_line
		(start 239.439704 -406.766776)
		(end 239.663224 -406.990296)
		(stroke
			(width 0.635)
			(type default)
		)
		(layer "In10.Cu")
	)
	(gr_line
		(start 239.441482 -397.649446)
		(end 239.387634 -397.701516)
		(stroke
			(width 0.635)
			(type default)
		)
		(layer "In10.Cu")
	)
	(gr_arc
		(start 239.663224 -406.990296)
		(mid 239.782747 -407.070378)
		(end 239.923828 -407.0985)
		(stroke
			(width 0.635)
			(type default)
		)
		(layer "In10.Cu")
	)
	(gr_line
		(start 239.699292 -407.75382)
		(end 237.746032 -405.80056)
		(stroke
			(width 0.635)
			(type default)
		)
		(layer "In10.Cu")
	)
	(gr_line
		(start 239.699292 -407.75382)
		(end 240.057432 -407.39568)
		(stroke
			(width 0.635)
			(type default)
		)
		(layer "In10.Cu")
	)
	(gr_line
		(start 239.917224 -397.173704)
		(end 239.441482 -397.649446)
		(stroke
			(width 0.635)
			(type default)
		)
		(layer "In10.Cu")
	)
	(gr_line
		(start 239.923828 -407.0985)
		(end 273.791172 -407.0985)
		(stroke
			(width 0.635)
			(type default)
		)
		(layer "In10.Cu")
	)
	(gr_line
		(start 240.057432 -407.39568)
		(end 273.646392 -407.39568)
		(stroke
			(width 0.635)
			(type default)
		)
		(layer "In10.Cu")
	)
	(gr_arc
		(start 240.177828 -397.0655)
		(mid 240.036774 -397.093687)
		(end 239.917224 -397.173704)
		(stroke
			(width 0.635)
			(type default)
		)
		(layer "In10.Cu")
	)
	(gr_line
		(start 270.463772 -420.97706)
		(end 233.172 -420.97706)
		(stroke
			(width 0.635)
			(type default)
		)
		(layer "In10.Cu")
	)
	(gr_line
		(start 273.646392 -407.39568)
		(end 274.051776 -406.990296)
		(stroke
			(width 0.635)
			(type default)
		)
		(layer "In10.Cu")
	)
	(gr_arc
		(start 273.791172 -407.0985)
		(mid 273.932264 -407.070381)
		(end 274.051776 -406.990296)
		(stroke
			(width 0.635)
			(type default)
		)
		(layer "In10.Cu")
	)
	(gr_line
		(start 274.051776 -407.33472)
		(end 274.470876 -407.75382)
		(stroke
			(width 0.635)
			(type default)
		)
		(layer "In10.Cu")
	)
	(gr_line
		(start 274.051776 -406.990296)
		(end 274.051776 -407.33472)
		(stroke
			(width 0.635)
			(type default)
		)
		(layer "In10.Cu")
	)
	(gr_line
		(start 274.051776 -406.990296)
		(end 274.529296 -406.512776)
		(stroke
			(width 0.635)
			(type default)
		)
		(layer "In10.Cu")
	)
	(gr_line
		(start 274.117054 -397.0655)
		(end 240.177828 -397.0655)
		(stroke
			(width 0.635)
			(type default)
		)
		(layer "In10.Cu")
	)
	(gr_line
		(start 274.255484 -397.121634)
		(end 274.117054 -397.0655)
		(stroke
			(width 0.635)
			(type default)
		)
		(layer "In10.Cu")
	)
	(gr_line
		(start 274.307554 -397.175482)
		(end 274.255484 -397.121634)
		(stroke
			(width 0.635)
			(type default)
		)
		(layer "In10.Cu")
	)
	(gr_arc
		(start 274.529296 -406.512776)
		(mid 274.609378 -406.393253)
		(end 274.6375 -406.252172)
		(stroke
			(width 0.635)
			(type default)
		)
		(layer "In10.Cu")
	)
	(gr_line
		(start 274.529296 -397.397224)
		(end 274.307554 -397.175482)
		(stroke
			(width 0.635)
			(type default)
		)
		(layer "In10.Cu")
	)
	(gr_line
		(start 274.6375 -406.252172)
		(end 274.6375 -397.657828)
		(stroke
			(width 0.635)
			(type default)
		)
		(layer "In10.Cu")
	)
	(gr_arc
		(start 274.6375 -397.657828)
		(mid 274.609313 -397.516774)
		(end 274.529296 -397.397224)
		(stroke
			(width 0.635)
			(type default)
		)
		(layer "In10.Cu")
	)
	(gr_line
		(start 275.0693 -405.960072)
		(end 275.351748 -406.24252)
		(stroke
			(width 0.635)
			(type default)
		)
		(layer "In10.Cu")
	)
	(gr_line
		(start 275.0693 -397.505428)
		(end 275.0693 -405.960072)
		(stroke
			(width 0.635)
			(type default)
		)
		(layer "In10.Cu")
	)
	(gr_line
		(start 275.351748 -406.24252)
		(end 278.143208 -406.24252)
		(stroke
			(width 0.635)
			(type default)
		)
		(layer "In10.Cu")
	)
	(gr_line
		(start 275.509228 -397.0655)
		(end 275.0693 -397.505428)
		(stroke
			(width 0.635)
			(type default)
		)
		(layer "In10.Cu")
	)
	(gr_line
		(start 275.680932 -415.7599)
		(end 270.463772 -420.97706)
		(stroke
			(width 0.635)
			(type default)
		)
		(layer "In10.Cu")
	)
	(gr_line
		(start 278.143208 -406.24252)
		(end 278.145748 -406.23998)
		(stroke
			(width 0.635)
			(type default)
		)
		(layer "In10.Cu")
	)
	(gr_line
		(start 278.145748 -406.23998)
		(end 281.037792 -406.23998)
		(stroke
			(width 0.635)
			(type default)
		)
		(layer "In10.Cu")
	)
	(gr_line
		(start 279.927812 -415.7599)
		(end 275.680932 -415.7599)
		(stroke
			(width 0.635)
			(type default)
		)
		(layer "In10.Cu")
	)
	(gr_line
		(start 279.927812 -415.7599)
		(end 280.51506 -415.172652)
		(stroke
			(width 0.635)
			(type default)
		)
		(layer "In10.Cu")
	)
	(gr_line
		(start 280.100532 -407.75382)
		(end 239.699292 -407.75382)
		(stroke
			(width 0.635)
			(type default)
		)
		(layer "In10.Cu")
	)
	(gr_line
		(start 280.51506 -415.172652)
		(end 280.51506 -408.168348)
		(stroke
			(width 0.635)
			(type default)
		)
		(layer "In10.Cu")
	)
	(gr_line
		(start 280.51506 -408.168348)
		(end 280.100532 -407.75382)
		(stroke
			(width 0.635)
			(type default)
		)
		(layer "In10.Cu")
	)
	(gr_line
		(start 280.83764 -397.0655)
		(end 275.509228 -397.0655)
		(stroke
			(width 0.635)
			(type default)
		)
		(layer "In10.Cu")
	)
	(gr_line
		(start 281.037792 -406.23998)
		(end 281.369008 -405.908764)
		(stroke
			(width 0.635)
			(type default)
		)
		(layer "In10.Cu")
	)
	(gr_line
		(start 281.369008 -405.908764)
		(end 281.369008 -397.596868)
		(stroke
			(width 0.635)
			(type default)
		)
		(layer "In10.Cu")
	)
	(gr_line
		(start 281.369008 -397.596868)
		(end 280.83764 -397.0655)
		(stroke
			(width 0.635)
			(type default)
		)
		(layer "In10.Cu")
	)
	(gr_poly
		(pts
			(xy 84.673694 -264.70483) (xy 84.626704 -264.55243) (xy 84.365084 -264.55243) (xy 84.318094 -264.70483)
			(xy 84.318094 -264.749026) (xy 84.673694 -264.749026)
		)
		(stroke
			(width 0)
			(type solid)
		)
		(fill yes)
		(layer "In11.Cu")
		(net "M_D_CPU1_SA_CB<2>")
	)
	(gr_poly
		(pts
			(xy 84.673694 -264.29589) (xy 84.673694 -264.251694) (xy 84.318094 -264.251694) (xy 84.318094 -264.29589)
			(xy 84.365084 -264.44829) (xy 84.626704 -264.44829)
		)
		(stroke
			(width 0)
			(type solid)
		)
		(fill yes)
		(layer "In11.Cu")
		(net "M_D_CPU1_SA_CB<1>")
	)
	(gr_poly
		(pts
			(xy 84.673694 -263.07669) (xy 84.626704 -262.92429) (xy 84.365084 -262.92429) (xy 84.318094 -263.07669)
			(xy 84.318094 -263.12114) (xy 84.673694 -263.12114)
		)
		(stroke
			(width 0)
			(type solid)
		)
		(fill yes)
		(layer "In11.Cu")
		(net "M_D_CPU1_SA_DQS_DN<4>")
	)
	(gr_poly
		(pts
			(xy 84.673694 -262.665718) (xy 84.673694 -262.621268) (xy 84.318094 -262.621268) (xy 84.318094 -262.665718)
			(xy 84.365084 -262.818118) (xy 84.626704 -262.818118)
		)
		(stroke
			(width 0)
			(type solid)
		)
		(fill yes)
		(layer "In11.Cu")
		(net "M_D_CPU1_SA_DQS_DN<9>")
	)
	(gr_poly
		(pts
			(xy 84.673694 -261.449058) (xy 84.626704 -261.296658) (xy 84.365084 -261.296658) (xy 84.318094 -261.449058)
			(xy 84.318094 -261.493508) (xy 84.673694 -261.493508)
		)
		(stroke
			(width 0)
			(type solid)
		)
		(fill yes)
		(layer "In11.Cu")
		(net "M_D_CPU1_SA_CB<6>")
	)
	(gr_poly
		(pts
			(xy 84.673694 -261.040626) (xy 84.673694 -260.996176) (xy 84.318094 -260.996176) (xy 84.318094 -261.040626)
			(xy 84.365084 -261.193026) (xy 84.626704 -261.193026)
		)
		(stroke
			(width 0)
			(type solid)
		)
		(fill yes)
		(layer "In11.Cu")
		(net "M_D_CPU1_SA_CB<5>")
	)
	(gr_poly
		(pts
			(xy 84.673694 -259.412486) (xy 84.673694 -259.36829) (xy 84.318094 -259.36829) (xy 84.318094 -259.412486)
			(xy 84.365084 -259.564886) (xy 84.626704 -259.564886)
		)
		(stroke
			(width 0)
			(type solid)
		)
		(fill yes)
		(layer "In11.Cu")
		(net "M_D_CPU1_SA_CS_N<2>")
	)
	(gr_poly
		(pts
			(xy 84.673694 -256.565654) (xy 84.626704 -256.413254) (xy 84.365084 -256.413254) (xy 84.318094 -256.565654)
			(xy 84.318094 -256.610104) (xy 84.673694 -256.610104)
		)
		(stroke
			(width 0)
			(type solid)
		)
		(fill yes)
		(layer "In11.Cu")
		(net "M_D_CPU1_SA_CA<3>")
	)
	(gr_poly
		(pts
			(xy 84.673694 -256.157222) (xy 84.673694 -256.112772) (xy 84.318094 -256.112772) (xy 84.318094 -256.157222)
			(xy 84.365084 -256.309622) (xy 84.626704 -256.309622)
		)
		(stroke
			(width 0)
			(type solid)
		)
		(fill yes)
		(layer "In11.Cu")
		(net "M_D_CPU1_SA_CA<4>")
	)
	(gr_poly
		(pts
			(xy 84.999322 -245.393718) (xy 85.10778 -245.276878) (xy 84.97697 -245.05031) (xy 84.821522 -245.08587)
			(xy 84.783168 -245.107968) (xy 84.960968 -245.415816)
		)
		(stroke
			(width 0)
			(type solid)
		)
		(fill yes)
		(layer "In11.Cu")
		(net "M_D_CPU1_SB_CB<7>")
	)
	(gr_poly
		(pts
			(xy 85.02523 -237.61573) (xy 84.97824 -237.46333) (xy 84.71662 -237.46333) (xy 84.66963 -237.61573)
			(xy 84.66963 -237.66018) (xy 85.02523 -237.66018)
		)
		(stroke
			(width 0)
			(type solid)
		)
		(fill yes)
		(layer "In11.Cu")
		(net "M_D_CPU1_SB_DQS_DP<5>")
	)
	(gr_poly
		(pts
			(xy 85.02523 -237.207806) (xy 85.02523 -237.163356) (xy 84.66963 -237.163356) (xy 84.66963 -237.207806)
			(xy 84.71662 -237.360206) (xy 84.97824 -237.360206)
		)
		(stroke
			(width 0)
			(type solid)
		)
		(fill yes)
		(layer "In11.Cu")
		(net "M_D_CPU1_SB_DQ<4>")
	)
	(gr_poly
		(pts
			(xy 85.02523 -232.732326) (xy 84.97824 -232.579926) (xy 84.71662 -232.579926) (xy 84.66963 -232.732326)
			(xy 84.66963 -232.776776) (xy 85.02523 -232.776776)
		)
		(stroke
			(width 0)
			(type solid)
		)
		(fill yes)
		(layer "In11.Cu")
		(net "M_D_CPU1_SB_DQS_DN<1>")
	)
	(gr_poly
		(pts
			(xy 85.02523 -232.324402) (xy 85.02523 -232.279952) (xy 84.66963 -232.279952) (xy 84.66963 -232.324402)
			(xy 84.71662 -232.476802) (xy 84.97824 -232.476802)
		)
		(stroke
			(width 0)
			(type solid)
		)
		(fill yes)
		(layer "In11.Cu")
		(net "M_D_CPU1_SB_DQS_DN<6>")
	)
	(gr_poly
		(pts
			(xy 85.02523 -227.848922) (xy 84.97824 -227.696522) (xy 84.71662 -227.696522) (xy 84.66963 -227.848922)
			(xy 84.66963 -227.893372) (xy 85.02523 -227.893372)
		)
		(stroke
			(width 0)
			(type solid)
		)
		(fill yes)
		(layer "In11.Cu")
		(net "M_D_CPU1_SB_DQ<26>")
	)
	(gr_poly
		(pts
			(xy 85.033612 -227.44049) (xy 85.033612 -227.396294) (xy 84.678012 -227.396294) (xy 84.678012 -227.44049)
			(xy 84.725002 -227.59289) (xy 84.986622 -227.59289)
		)
		(stroke
			(width 0)
			(type solid)
		)
		(fill yes)
		(layer "In11.Cu")
		(net "M_D_CPU1_SB_DQ<25>")
	)
	(gr_poly
		(pts
			(xy 85.033866 -247.382538) (xy 84.986876 -247.230138) (xy 84.725256 -247.230138) (xy 84.678266 -247.382538)
			(xy 84.678266 -247.426988) (xy 85.033866 -247.426988)
		)
		(stroke
			(width 0)
			(type solid)
		)
		(fill yes)
		(layer "In11.Cu")
		(net "M_D_CPU1_SB_CA<6>")
	)
	(gr_poly
		(pts
			(xy 85.033866 -235.988098) (xy 84.986876 -235.835698) (xy 84.725256 -235.835698) (xy 84.678266 -235.988098)
			(xy 84.678266 -236.032548) (xy 85.033866 -236.032548)
		)
		(stroke
			(width 0)
			(type solid)
		)
		(fill yes)
		(layer "In11.Cu")
		(net "M_D_CPU1_SB_DQ<7>")
	)
	(gr_poly
		(pts
			(xy 85.033866 -233.952034) (xy 85.033866 -233.907584) (xy 84.678266 -233.907584) (xy 84.678266 -233.952034)
			(xy 84.725256 -234.104434) (xy 84.986876 -234.104434)
		)
		(stroke
			(width 0)
			(type solid)
		)
		(fill yes)
		(layer "In11.Cu")
		(net "M_D_CPU1_SB_DQ<9>")
	)
	(gr_poly
		(pts
			(xy 85.033866 -231.104694) (xy 84.986876 -230.952294) (xy 84.725256 -230.952294) (xy 84.678266 -231.104694)
			(xy 84.678266 -231.149144) (xy 85.033866 -231.149144)
		)
		(stroke
			(width 0)
			(type solid)
		)
		(fill yes)
		(layer "In11.Cu")
		(net "M_D_CPU1_SB_DQ<14>")
	)
	(gr_poly
		(pts
			(xy 85.03412 -238.835438) (xy 85.03412 -238.790988) (xy 84.67852 -238.790988) (xy 84.67852 -238.835438)
			(xy 84.72551 -238.987838) (xy 84.98713 -238.987838)
		)
		(stroke
			(width 0)
			(type solid)
		)
		(fill yes)
		(layer "In11.Cu")
		(net "M_D_CPU1_SB_DQS_DP<0>")
	)
	(gr_poly
		(pts
			(xy 85.042248 -240.46307) (xy 85.042248 -240.418874) (xy 84.686648 -240.418874) (xy 84.686648 -240.46307)
			(xy 84.733638 -240.61547) (xy 84.995258 -240.61547)
		)
		(stroke
			(width 0)
			(type solid)
		)
		(fill yes)
		(layer "In11.Cu")
		(net "M_D_CPU1_SB_DQ<0>")
	)
	(gr_poly
		(pts
			(xy 85.042248 -239.243362) (xy 84.995258 -239.090962) (xy 84.733638 -239.090962) (xy 84.686648 -239.243362)
			(xy 84.686648 -239.287812) (xy 85.042248 -239.287812)
		)
		(stroke
			(width 0)
			(type solid)
		)
		(fill yes)
		(layer "In11.Cu")
		(net "M_D_CPU1_SB_DQ<3>")
	)
	(gr_poly
		(pts
			(xy 85.042248 -234.360466) (xy 84.995258 -234.208066) (xy 84.733638 -234.208066) (xy 84.686648 -234.360466)
			(xy 84.686648 -234.404662) (xy 85.042248 -234.404662)
		)
		(stroke
			(width 0)
			(type solid)
		)
		(fill yes)
		(layer "In11.Cu")
		(net "M_D_CPU1_SB_DQ<10>")
	)
	(gr_poly
		(pts
			(xy 85.042248 -230.696262) (xy 85.042248 -230.652066) (xy 84.686648 -230.652066) (xy 84.686648 -230.696262)
			(xy 84.733638 -230.848662) (xy 84.995258 -230.848662)
		)
		(stroke
			(width 0)
			(type solid)
		)
		(fill yes)
		(layer "In11.Cu")
		(net "M_D_CPU1_SB_DQ<13>")
	)
	(gr_poly
		(pts
			(xy 85.143594 -268.77391) (xy 85.096604 -268.62151) (xy 84.834984 -268.62151) (xy 84.787994 -268.77391)
			(xy 84.787994 -268.81836) (xy 85.143594 -268.81836)
		)
		(stroke
			(width 0)
			(type solid)
		)
		(fill yes)
		(layer "In11.Cu")
		(net "M_D_CPU1_SA_DQ<27>")
	)
	(gr_poly
		(pts
			(xy 85.143594 -266.737846) (xy 85.143594 -266.693396) (xy 84.787994 -266.693396) (xy 84.787994 -266.737846)
			(xy 84.834984 -266.890246) (xy 85.096604 -266.890246)
		)
		(stroke
			(width 0)
			(type solid)
		)
		(fill yes)
		(layer "In11.Cu")
		(net "M_D_CPU1_SA_DQ<28>")
	)
	(gr_poly
		(pts
			(xy 85.143594 -265.518646) (xy 85.096604 -265.366246) (xy 84.834984 -265.366246) (xy 84.787994 -265.518646)
			(xy 84.787994 -265.562842) (xy 85.143594 -265.562842)
		)
		(stroke
			(width 0)
			(type solid)
		)
		(fill yes)
		(layer "In11.Cu")
		(net "M_D_CPU1_SA_DQ<31>")
	)
	(gr_poly
		(pts
			(xy 85.143594 -265.109706) (xy 85.143594 -265.06551) (xy 84.787994 -265.06551) (xy 84.787994 -265.109706)
			(xy 84.834984 -265.262106) (xy 85.096604 -265.262106)
		)
		(stroke
			(width 0)
			(type solid)
		)
		(fill yes)
		(layer "In11.Cu")
		(net "M_D_CPU1_SA_CB<0>")
	)
	(gr_poly
		(pts
			(xy 85.143594 -263.891014) (xy 85.096604 -263.738614) (xy 84.834984 -263.738614) (xy 84.787994 -263.891014)
			(xy 84.787994 -263.93521) (xy 85.143594 -263.93521)
		)
		(stroke
			(width 0)
			(type solid)
		)
		(fill yes)
		(layer "In11.Cu")
		(net "M_D_CPU1_SA_CB<3>")
	)
	(gr_poly
		(pts
			(xy 85.143594 -263.482074) (xy 85.143594 -263.437878) (xy 84.787994 -263.437878) (xy 84.787994 -263.482074)
			(xy 84.834984 -263.634474) (xy 85.096604 -263.634474)
		)
		(stroke
			(width 0)
			(type solid)
		)
		(fill yes)
		(layer "In11.Cu")
		(net "M_D_CPU1_SA_DQS_DP<4>")
	)
	(gr_poly
		(pts
			(xy 85.143594 -262.262874) (xy 85.096604 -262.110474) (xy 84.834984 -262.110474) (xy 84.787994 -262.262874)
			(xy 84.787994 -262.307324) (xy 85.143594 -262.307324)
		)
		(stroke
			(width 0)
			(type solid)
		)
		(fill yes)
		(layer "In11.Cu")
		(net "M_D_CPU1_SA_DQS_DP<9>")
	)
	(gr_poly
		(pts
			(xy 85.143594 -261.854442) (xy 85.143594 -261.809992) (xy 84.787994 -261.809992) (xy 84.787994 -261.854442)
			(xy 84.834984 -262.006842) (xy 85.096604 -262.006842)
		)
		(stroke
			(width 0)
			(type solid)
		)
		(fill yes)
		(layer "In11.Cu")
		(net "M_D_CPU1_SA_CB<4>")
	)
	(gr_poly
		(pts
			(xy 85.143594 -260.635242) (xy 85.096604 -260.482842) (xy 84.834984 -260.482842) (xy 84.787994 -260.635242)
			(xy 84.787994 -260.679438) (xy 85.143594 -260.679438)
		)
		(stroke
			(width 0)
			(type solid)
		)
		(fill yes)
		(layer "In11.Cu")
		(net "M_D_CPU1_SA_CB<7>")
	)
	(gr_poly
		(pts
			(xy 85.143594 -259.00761) (xy 85.096604 -258.85521) (xy 84.834984 -258.85521) (xy 84.787994 -259.00761)
			(xy 84.787994 -259.051806) (xy 85.143594 -259.051806)
		)
		(stroke
			(width 0)
			(type solid)
		)
		(fill yes)
		(layer "In11.Cu")
		(net "M_D_CPU1_SA_CS_N<0>")
	)
	(gr_poly
		(pts
			(xy 85.143594 -258.59867) (xy 85.143594 -258.554474) (xy 84.787994 -258.554474) (xy 84.787994 -258.59867)
			(xy 84.834984 -258.75107) (xy 85.096604 -258.75107)
		)
		(stroke
			(width 0)
			(type solid)
		)
		(fill yes)
		(layer "In11.Cu")
		(net "M_D_CPU1_SA_CS_N<3>")
	)
	(gr_poly
		(pts
			(xy 85.143594 -257.37947) (xy 85.096604 -257.22707) (xy 84.834984 -257.22707) (xy 84.787994 -257.37947)
			(xy 84.787994 -257.42392) (xy 85.143594 -257.42392)
		)
		(stroke
			(width 0)
			(type solid)
		)
		(fill yes)
		(layer "In11.Cu")
		(net "M_D_CPU1_SA_CA<1>")
	)
	(gr_poly
		(pts
			(xy 85.143594 -256.971038) (xy 85.143594 -256.926588) (xy 84.787994 -256.926588) (xy 84.787994 -256.971038)
			(xy 84.834984 -257.123438) (xy 85.096604 -257.123438)
		)
		(stroke
			(width 0)
			(type solid)
		)
		(fill yes)
		(layer "In11.Cu")
		(net "M_D_CPU1_SA_CA<2>")
	)
	(gr_poly
		(pts
			(xy 85.143594 -255.751838) (xy 85.096604 -255.599438) (xy 84.834984 -255.599438) (xy 84.787994 -255.751838)
			(xy 84.787994 -255.796288) (xy 85.143594 -255.796288)
		)
		(stroke
			(width 0)
			(type solid)
		)
		(fill yes)
		(layer "In11.Cu")
		(net "M_D_CPU1_SA_CA<5>")
	)
	(gr_poly
		(pts
			(xy 85.143848 -267.146278) (xy 85.096858 -266.993878) (xy 84.835238 -266.993878) (xy 84.788248 -267.146278)
			(xy 84.788248 -267.190474) (xy 85.143848 -267.190474)
		)
		(stroke
			(width 0)
			(type solid)
		)
		(fill yes)
		(layer "In11.Cu")
		(net "M_D_CPU1_SA_DQS_DP<8>")
	)
	(gr_poly
		(pts
			(xy 85.360256 -245.20144) (xy 85.39861 -245.179342) (xy 85.22081 -244.871494) (xy 85.182456 -244.893592)
			(xy 85.073998 -245.010432) (xy 85.204808 -245.237)
		)
		(stroke
			(width 0)
			(type solid)
		)
		(fill yes)
		(layer "In11.Cu")
		(net "M_D_CPU1_SB_DQS_DP<9>")
	)
	(gr_poly
		(pts
			(xy 85.49513 -240.057178) (xy 85.44814 -239.904778) (xy 85.18652 -239.904778) (xy 85.13953 -240.057178)
			(xy 85.13953 -240.101628) (xy 85.49513 -240.101628)
		)
		(stroke
			(width 0)
			(type solid)
		)
		(fill yes)
		(layer "In11.Cu")
		(net "M_D_CPU1_SB_DQ<2>")
	)
	(gr_poly
		(pts
			(xy 85.49513 -239.649254) (xy 85.49513 -239.604804) (xy 85.13953 -239.604804) (xy 85.13953 -239.649254)
			(xy 85.18652 -239.801654) (xy 85.44814 -239.801654)
		)
		(stroke
			(width 0)
			(type solid)
		)
		(fill yes)
		(layer "In11.Cu")
		(net "M_D_CPU1_SB_DQ<1>")
	)
	(gr_poly
		(pts
			(xy 85.49513 -234.76585) (xy 85.49513 -234.721654) (xy 85.13953 -234.721654) (xy 85.13953 -234.76585)
			(xy 85.18652 -234.91825) (xy 85.44814 -234.91825)
		)
		(stroke
			(width 0)
			(type solid)
		)
		(fill yes)
		(layer "In11.Cu")
		(net "M_D_CPU1_SB_DQ<8>")
	)
	(gr_poly
		(pts
			(xy 85.49513 -230.290878) (xy 85.44814 -230.138478) (xy 85.18652 -230.138478) (xy 85.13953 -230.290878)
			(xy 85.13953 -230.335074) (xy 85.49513 -230.335074)
		)
		(stroke
			(width 0)
			(type solid)
		)
		(fill yes)
		(layer "In11.Cu")
		(net "M_D_CPU1_SB_DQ<15>")
	)
	(gr_poly
		(pts
			(xy 85.503766 -248.196354) (xy 85.456776 -248.043954) (xy 85.195156 -248.043954) (xy 85.148166 -248.196354)
			(xy 85.148166 -248.240804) (xy 85.503766 -248.240804)
		)
		(stroke
			(width 0)
			(type solid)
		)
		(fill yes)
		(layer "In11.Cu")
		(net "M_D_CPU1_SB_CA<5>")
	)
	(gr_poly
		(pts
			(xy 85.503766 -247.787922) (xy 85.503766 -247.743472) (xy 85.148166 -247.743472) (xy 85.148166 -247.787922)
			(xy 85.195156 -247.940322) (xy 85.456776 -247.940322)
		)
		(stroke
			(width 0)
			(type solid)
		)
		(fill yes)
		(layer "In11.Cu")
		(net "M_D_CPU1_SB_PAR")
	)
	(gr_poly
		(pts
			(xy 85.503766 -246.16029) (xy 85.503766 -246.11584) (xy 85.148166 -246.11584) (xy 85.148166 -246.16029)
			(xy 85.195156 -246.31269) (xy 85.456776 -246.31269)
		)
		(stroke
			(width 0)
			(type solid)
		)
		(fill yes)
		(layer "In11.Cu")
		(net "M_D_CPU1_SB_CB<5>")
	)
	(gr_poly
		(pts
			(xy 85.503766 -238.430054) (xy 85.456776 -238.277654) (xy 85.195156 -238.277654) (xy 85.148166 -238.430054)
			(xy 85.148166 -238.47425) (xy 85.503766 -238.47425)
		)
		(stroke
			(width 0)
			(type solid)
		)
		(fill yes)
		(layer "In11.Cu")
		(net "M_D_CPU1_SB_DQS_DN<0>")
	)
	(gr_poly
		(pts
			(xy 85.503766 -236.393482) (xy 85.503766 -236.349286) (xy 85.148166 -236.349286) (xy 85.148166 -236.393482)
			(xy 85.195156 -236.545882) (xy 85.456776 -236.545882)
		)
		(stroke
			(width 0)
			(type solid)
		)
		(fill yes)
		(layer "In11.Cu")
		(net "M_D_CPU1_SB_DQ<5>")
	)
	(gr_poly
		(pts
			(xy 85.503766 -233.54665) (xy 85.456776 -233.39425) (xy 85.195156 -233.39425) (xy 85.148166 -233.54665)
			(xy 85.148166 -233.590846) (xy 85.503766 -233.590846)
		)
		(stroke
			(width 0)
			(type solid)
		)
		(fill yes)
		(layer "In11.Cu")
		(net "M_D_CPU1_SB_DQ<11>")
	)
	(gr_poly
		(pts
			(xy 85.503766 -231.510078) (xy 85.503766 -231.465882) (xy 85.148166 -231.465882) (xy 85.148166 -231.510078)
			(xy 85.195156 -231.662478) (xy 85.456776 -231.662478)
		)
		(stroke
			(width 0)
			(type solid)
		)
		(fill yes)
		(layer "In11.Cu")
		(net "M_D_CPU1_SB_DQ<12>")
	)
	(gr_poly
		(pts
			(xy 85.509608 -227.035106) (xy 85.462618 -226.882706) (xy 85.200998 -226.882706) (xy 85.154008 -227.035106)
			(xy 85.154008 -227.079556) (xy 85.509608 -227.079556)
		)
		(stroke
			(width 0)
			(type solid)
		)
		(fill yes)
		(layer "In11.Cu")
		(net "M_D_CPU1_SB_DQ<27>")
	)
	(gr_poly
		(pts
			(xy 85.509608 -226.627182) (xy 85.509608 -226.582732) (xy 85.154008 -226.582732) (xy 85.154008 -226.627182)
			(xy 85.200998 -226.779582) (xy 85.462618 -226.779582)
		)
		(stroke
			(width 0)
			(type solid)
		)
		(fill yes)
		(layer "In11.Cu")
		(net "M_D_CPU1_SB_DQS_DP<3>")
	)
	(gr_poly
		(pts
			(xy 85.512148 -243.31295) (xy 85.465158 -243.16055) (xy 85.203538 -243.16055) (xy 85.156548 -243.31295)
			(xy 85.156548 -243.3574) (xy 85.512148 -243.3574)
		)
		(stroke
			(width 0)
			(type solid)
		)
		(fill yes)
		(layer "In11.Cu")
		(net "M_D_CPU1_SB_DQS_DP<4>")
	)
	(gr_poly
		(pts
			(xy 85.512148 -242.905026) (xy 85.512148 -242.860576) (xy 85.156548 -242.860576) (xy 85.156548 -242.905026)
			(xy 85.203538 -243.057426) (xy 85.465158 -243.057426)
		)
		(stroke
			(width 0)
			(type solid)
		)
		(fill yes)
		(layer "In11.Cu")
		(net "M_D_CPU1_SB_CB<0>")
	)
	(gr_poly
		(pts
			(xy 85.512148 -241.685318) (xy 85.465158 -241.532918) (xy 85.203538 -241.532918) (xy 85.156548 -241.685318)
			(xy 85.156548 -241.729514) (xy 85.512148 -241.729514)
		)
		(stroke
			(width 0)
			(type solid)
		)
		(fill yes)
		(layer "In11.Cu")
		(net "M_D_CPU1_SB_CB<3>")
	)
	(gr_poly
		(pts
			(xy 85.512148 -238.021622) (xy 85.512148 -237.977172) (xy 85.156548 -237.977172) (xy 85.156548 -238.021622)
			(xy 85.203538 -238.174022) (xy 85.465158 -238.174022)
		)
		(stroke
			(width 0)
			(type solid)
		)
		(fill yes)
		(layer "In11.Cu")
		(net "M_D_CPU1_SB_DQS_DN<5>")
	)
	(gr_poly
		(pts
			(xy 85.512148 -236.801914) (xy 85.465158 -236.649514) (xy 85.203538 -236.649514) (xy 85.156548 -236.801914)
			(xy 85.156548 -236.846364) (xy 85.512148 -236.846364)
		)
		(stroke
			(width 0)
			(type solid)
		)
		(fill yes)
		(layer "In11.Cu")
		(net "M_D_CPU1_SB_DQ<6>")
	)
	(gr_poly
		(pts
			(xy 85.512148 -233.138218) (xy 85.512148 -233.093768) (xy 85.156548 -233.093768) (xy 85.156548 -233.138218)
			(xy 85.203538 -233.290618) (xy 85.465158 -233.290618)
		)
		(stroke
			(width 0)
			(type solid)
		)
		(fill yes)
		(layer "In11.Cu")
		(net "M_D_CPU1_SB_DQS_DP<1>")
	)
	(gr_poly
		(pts
			(xy 85.512148 -231.91851) (xy 85.465158 -231.76611) (xy 85.203538 -231.76611) (xy 85.156548 -231.91851)
			(xy 85.156548 -231.96296) (xy 85.512148 -231.96296)
		)
		(stroke
			(width 0)
			(type solid)
		)
		(fill yes)
		(layer "In11.Cu")
		(net "M_D_CPU1_SB_DQS_DP<6>")
	)
	(gr_poly
		(pts
			(xy 85.512148 -228.254814) (xy 85.512148 -228.210618) (xy 85.156548 -228.210618) (xy 85.156548 -228.254814)
			(xy 85.203538 -228.407214) (xy 85.465158 -228.407214)
		)
		(stroke
			(width 0)
			(type solid)
		)
		(fill yes)
		(layer "In11.Cu")
		(net "M_D_CPU1_SB_DQ<24>")
	)
	(gr_poly
		(pts
			(xy 85.512148 -225.407474) (xy 85.465158 -225.255074) (xy 85.203538 -225.255074) (xy 85.156548 -225.407474)
			(xy 85.156548 -225.45167) (xy 85.512148 -225.45167)
		)
		(stroke
			(width 0)
			(type solid)
		)
		(fill yes)
		(layer "In11.Cu")
		(net "M_D_CPU1_SB_DQS_DP<8>")
	)
	(gr_poly
		(pts
			(xy 85.512148 -224.999042) (xy 85.512148 -224.954846) (xy 85.156548 -224.954846) (xy 85.156548 -224.999042)
			(xy 85.203538 -225.151442) (xy 85.465158 -225.151442)
		)
		(stroke
			(width 0)
			(type solid)
		)
		(fill yes)
		(layer "In11.Cu")
		(net "M_D_CPU1_SB_DQ<28>")
	)
	(gr_poly
		(pts
			(xy 85.512148 -223.779842) (xy 85.465158 -223.627442) (xy 85.203538 -223.627442) (xy 85.156548 -223.779842)
			(xy 85.156548 -223.824038) (xy 85.512148 -223.824038)
		)
		(stroke
			(width 0)
			(type solid)
		)
		(fill yes)
		(layer "In11.Cu")
		(net "M_D_CPU1_SB_DQ<31>")
	)
	(gr_poly
		(pts
			(xy 85.607652 -272.843498) (xy 85.560662 -272.691098) (xy 85.299042 -272.691098) (xy 85.252052 -272.843498)
			(xy 85.252052 -272.887948) (xy 85.607652 -272.887948)
		)
		(stroke
			(width 0)
			(type solid)
		)
		(fill yes)
		(layer "In11.Cu")
		(net "M_D_CPU1_SA_DQS_DN<2>")
	)
	(gr_poly
		(pts
			(xy 85.613494 -271.215866) (xy 85.566504 -271.063466) (xy 85.304884 -271.063466) (xy 85.257894 -271.215866)
			(xy 85.257894 -271.260062) (xy 85.613494 -271.260062)
		)
		(stroke
			(width 0)
			(type solid)
		)
		(fill yes)
		(layer "In11.Cu")
		(net "M_D_CPU1_SA_DQ<22>")
	)
	(gr_poly
		(pts
			(xy 85.613494 -269.179294) (xy 85.613494 -269.134844) (xy 85.257894 -269.134844) (xy 85.257894 -269.179294)
			(xy 85.304884 -269.331694) (xy 85.566504 -269.331694)
		)
		(stroke
			(width 0)
			(type solid)
		)
		(fill yes)
		(layer "In11.Cu")
		(net "M_D_CPU1_SA_DQ<25>")
	)
	(gr_poly
		(pts
			(xy 85.613494 -267.960094) (xy 85.566504 -267.807694) (xy 85.304884 -267.807694) (xy 85.257894 -267.960094)
			(xy 85.257894 -268.004544) (xy 85.613494 -268.004544)
		)
		(stroke
			(width 0)
			(type solid)
		)
		(fill yes)
		(layer "In11.Cu")
		(net "M_D_CPU1_SA_DQS_DN<3>")
	)
	(gr_poly
		(pts
			(xy 85.613494 -267.551662) (xy 85.613494 -267.507212) (xy 85.257894 -267.507212) (xy 85.257894 -267.551662)
			(xy 85.304884 -267.704062) (xy 85.566504 -267.704062)
		)
		(stroke
			(width 0)
			(type solid)
		)
		(fill yes)
		(layer "In11.Cu")
		(net "M_D_CPU1_SA_DQS_DN<8>")
	)
	(gr_poly
		(pts
			(xy 85.613494 -266.332462) (xy 85.566504 -266.180062) (xy 85.304884 -266.180062) (xy 85.257894 -266.332462)
			(xy 85.257894 -266.376658) (xy 85.613494 -266.376658)
		)
		(stroke
			(width 0)
			(type solid)
		)
		(fill yes)
		(layer "In11.Cu")
		(net "M_D_CPU1_SA_DQ<30>")
	)
	(gr_poly
		(pts
			(xy 85.613494 -265.92403) (xy 85.613494 -265.87958) (xy 85.257894 -265.87958) (xy 85.257894 -265.92403)
			(xy 85.304884 -266.07643) (xy 85.566504 -266.07643)
		)
		(stroke
			(width 0)
			(type solid)
		)
		(fill yes)
		(layer "In11.Cu")
		(net "M_D_CPU1_SA_DQ<29>")
	)
	(gr_poly
		(pts
			(xy 85.613494 -264.70483) (xy 85.566504 -264.55243) (xy 85.304884 -264.55243) (xy 85.257894 -264.70483)
			(xy 85.257894 -264.749026) (xy 85.613494 -264.749026)
		)
		(stroke
			(width 0)
			(type solid)
		)
		(fill yes)
		(layer "In11.Cu")
		(net "M_D_CPU1_SA_CB<2>")
	)
	(gr_poly
		(pts
			(xy 85.613494 -264.29589) (xy 85.613494 -264.251694) (xy 85.257894 -264.251694) (xy 85.257894 -264.29589)
			(xy 85.304884 -264.44829) (xy 85.566504 -264.44829)
		)
		(stroke
			(width 0)
			(type solid)
		)
		(fill yes)
		(layer "In11.Cu")
		(net "M_D_CPU1_SA_CB<1>")
	)
	(gr_poly
		(pts
			(xy 85.613494 -263.07669) (xy 85.566504 -262.92429) (xy 85.304884 -262.92429) (xy 85.257894 -263.07669)
			(xy 85.257894 -263.12114) (xy 85.613494 -263.12114)
		)
		(stroke
			(width 0)
			(type solid)
		)
		(fill yes)
		(layer "In11.Cu")
		(net "M_D_CPU1_SA_DQS_DN<4>")
	)
	(gr_poly
		(pts
			(xy 85.613494 -262.668258) (xy 85.613494 -262.623808) (xy 85.257894 -262.623808) (xy 85.257894 -262.668258)
			(xy 85.304884 -262.820658) (xy 85.566504 -262.820658)
		)
		(stroke
			(width 0)
			(type solid)
		)
		(fill yes)
		(layer "In11.Cu")
		(net "M_D_CPU1_SA_DQS_DN<9>")
	)
	(gr_poly
		(pts
			(xy 85.613494 -261.449058) (xy 85.566504 -261.296658) (xy 85.304884 -261.296658) (xy 85.257894 -261.449058)
			(xy 85.257894 -261.493508) (xy 85.613494 -261.493508)
		)
		(stroke
			(width 0)
			(type solid)
		)
		(fill yes)
		(layer "In11.Cu")
		(net "M_D_CPU1_SA_CB<6>")
	)
	(gr_poly
		(pts
			(xy 85.613494 -261.040626) (xy 85.613494 -260.996176) (xy 85.257894 -260.996176) (xy 85.257894 -261.040626)
			(xy 85.304884 -261.193026) (xy 85.566504 -261.193026)
		)
		(stroke
			(width 0)
			(type solid)
		)
		(fill yes)
		(layer "In11.Cu")
		(net "M_D_CPU1_SA_CB<5>")
	)
	(gr_poly
		(pts
			(xy 85.613494 -259.412486) (xy 85.613494 -259.36829) (xy 85.257894 -259.36829) (xy 85.257894 -259.412486)
			(xy 85.304884 -259.564886) (xy 85.566504 -259.564886)
		)
		(stroke
			(width 0)
			(type solid)
		)
		(fill yes)
		(layer "In11.Cu")
		(net "M_D_CPU1_SA_CS_N<2>")
	)
	(gr_poly
		(pts
			(xy 85.613494 -258.193286) (xy 85.566504 -258.040886) (xy 85.304884 -258.040886) (xy 85.257894 -258.193286)
			(xy 85.257894 -258.237736) (xy 85.613494 -258.237736)
		)
		(stroke
			(width 0)
			(type solid)
		)
		(fill yes)
		(layer "In11.Cu")
		(net "M_D_CPU1_SA_CS_N<1>")
	)
	(gr_poly
		(pts
			(xy 85.613494 -257.784854) (xy 85.613494 -257.740404) (xy 85.257894 -257.740404) (xy 85.257894 -257.784854)
			(xy 85.304884 -257.937254) (xy 85.566504 -257.937254)
		)
		(stroke
			(width 0)
			(type solid)
		)
		(fill yes)
		(layer "In11.Cu")
		(net "M_D_CPU1_SA_CA<0>")
	)
	(gr_poly
		(pts
			(xy 85.613494 -256.565654) (xy 85.566504 -256.413254) (xy 85.304884 -256.413254) (xy 85.257894 -256.565654)
			(xy 85.257894 -256.610104) (xy 85.613494 -256.610104)
		)
		(stroke
			(width 0)
			(type solid)
		)
		(fill yes)
		(layer "In11.Cu")
		(net "M_D_CPU1_SA_CA<3>")
	)
	(gr_poly
		(pts
			(xy 85.613494 -256.157222) (xy 85.613494 -256.112772) (xy 85.257894 -256.112772) (xy 85.257894 -256.157222)
			(xy 85.304884 -256.309622) (xy 85.566504 -256.309622)
		)
		(stroke
			(width 0)
			(type solid)
		)
		(fill yes)
		(layer "In11.Cu")
		(net "M_D_CPU1_SA_CA<4>")
	)
	(gr_poly
		(pts
			(xy 85.61959 -272.435066) (xy 85.61959 -272.390616) (xy 85.26399 -272.390616) (xy 85.26399 -272.435066)
			(xy 85.31098 -272.587466) (xy 85.5726 -272.587466)
		)
		(stroke
			(width 0)
			(type solid)
		)
		(fill yes)
		(layer "In11.Cu")
		(net "M_D_CPU1_SA_DQS_DN<7>")
	)
	(gr_poly
		(pts
			(xy 85.82914 -244.385592) (xy 85.867494 -244.363494) (xy 85.689694 -244.055646) (xy 85.65134 -244.077744)
			(xy 85.542882 -244.194584) (xy 85.673692 -244.421152)
		)
		(stroke
			(width 0)
			(type solid)
		)
		(fill yes)
		(layer "In11.Cu")
		(net "M_D_CPU1_SB_DQS_DN<4>")
	)
	(gr_poly
		(pts
			(xy 85.829394 -241.130074) (xy 85.867748 -241.107976) (xy 85.689948 -240.800128) (xy 85.651594 -240.822226)
			(xy 85.543136 -240.939066) (xy 85.673946 -241.165634)
		)
		(stroke
			(width 0)
			(type solid)
		)
		(fill yes)
		(layer "In11.Cu")
		(net "M_D_CPU1_SB_DQ<0>")
	)
	(gr_poly
		(pts
			(xy 85.938868 -243.765324) (xy 86.047326 -243.648484) (xy 85.916516 -243.421916) (xy 85.761068 -243.457476)
			(xy 85.722714 -243.479574) (xy 85.900514 -243.787422)
		)
		(stroke
			(width 0)
			(type solid)
		)
		(fill yes)
		(layer "In11.Cu")
		(net "M_D_CPU1_SB_DQS_DP<4>")
	)
	(gr_poly
		(pts
			(xy 85.939122 -240.510314) (xy 86.04758 -240.393474) (xy 85.91677 -240.166906) (xy 85.761322 -240.202466)
			(xy 85.722968 -240.224564) (xy 85.900768 -240.532412)
		)
		(stroke
			(width 0)
			(type solid)
		)
		(fill yes)
		(layer "In11.Cu")
		(net "M_D_CPU1_SB_DQ<2>")
	)
	(gr_poly
		(pts
			(xy 85.96757 -242.499134) (xy 85.92058 -242.346734) (xy 85.65896 -242.346734) (xy 85.61197 -242.499134)
			(xy 85.61197 -242.54333) (xy 85.96757 -242.54333)
		)
		(stroke
			(width 0)
			(type solid)
		)
		(fill yes)
		(layer "In11.Cu")
		(net "M_D_CPU1_SB_CB<2>")
	)
	(gr_poly
		(pts
			(xy 85.96757 -242.090702) (xy 85.96757 -242.046506) (xy 85.61197 -242.046506) (xy 85.61197 -242.090702)
			(xy 85.65896 -242.243102) (xy 85.92058 -242.243102)
		)
		(stroke
			(width 0)
			(type solid)
		)
		(fill yes)
		(layer "In11.Cu")
		(net "M_D_CPU1_SB_CB<1>")
	)
	(gr_poly
		(pts
			(xy 85.96757 -237.61573) (xy 85.92058 -237.46333) (xy 85.65896 -237.46333) (xy 85.61197 -237.61573)
			(xy 85.61197 -237.66018) (xy 85.96757 -237.66018)
		)
		(stroke
			(width 0)
			(type solid)
		)
		(fill yes)
		(layer "In11.Cu")
		(net "M_D_CPU1_SB_DQS_DP<5>")
	)
	(gr_poly
		(pts
			(xy 85.96757 -237.207806) (xy 85.96757 -237.163356) (xy 85.61197 -237.163356) (xy 85.61197 -237.207806)
			(xy 85.65896 -237.360206) (xy 85.92058 -237.360206)
		)
		(stroke
			(width 0)
			(type solid)
		)
		(fill yes)
		(layer "In11.Cu")
		(net "M_D_CPU1_SB_DQ<4>")
	)
	(gr_poly
		(pts
			(xy 85.96757 -232.732326) (xy 85.92058 -232.579926) (xy 85.65896 -232.579926) (xy 85.61197 -232.732326)
			(xy 85.61197 -232.776776) (xy 85.96757 -232.776776)
		)
		(stroke
			(width 0)
			(type solid)
		)
		(fill yes)
		(layer "In11.Cu")
		(net "M_D_CPU1_SB_DQS_DN<1>")
	)
	(gr_poly
		(pts
			(xy 85.96757 -232.324402) (xy 85.96757 -232.279952) (xy 85.61197 -232.279952) (xy 85.61197 -232.324402)
			(xy 85.65896 -232.476802) (xy 85.92058 -232.476802)
		)
		(stroke
			(width 0)
			(type solid)
		)
		(fill yes)
		(layer "In11.Cu")
		(net "M_D_CPU1_SB_DQS_DN<6>")
	)
	(gr_poly
		(pts
			(xy 85.96757 -227.848922) (xy 85.92058 -227.696522) (xy 85.65896 -227.696522) (xy 85.61197 -227.848922)
			(xy 85.61197 -227.893372) (xy 85.96757 -227.893372)
		)
		(stroke
			(width 0)
			(type solid)
		)
		(fill yes)
		(layer "In11.Cu")
		(net "M_D_CPU1_SB_DQ<26>")
	)
	(gr_poly
		(pts
			(xy 85.96757 -227.440998) (xy 85.96757 -227.396548) (xy 85.61197 -227.396548) (xy 85.61197 -227.440998)
			(xy 85.65896 -227.593398) (xy 85.92058 -227.593398)
		)
		(stroke
			(width 0)
			(type solid)
		)
		(fill yes)
		(layer "In11.Cu")
		(net "M_D_CPU1_SB_DQ<25>")
	)
	(gr_poly
		(pts
			(xy 85.96757 -226.22129) (xy 85.92058 -226.06889) (xy 85.65896 -226.06889) (xy 85.61197 -226.22129)
			(xy 85.61197 -226.26574) (xy 85.96757 -226.26574)
		)
		(stroke
			(width 0)
			(type solid)
		)
		(fill yes)
		(layer "In11.Cu")
		(net "M_D_CPU1_SB_DQS_DN<3>")
	)
	(gr_poly
		(pts
			(xy 85.96757 -225.813366) (xy 85.96757 -225.768916) (xy 85.61197 -225.768916) (xy 85.61197 -225.813366)
			(xy 85.65896 -225.965766) (xy 85.92058 -225.965766)
		)
		(stroke
			(width 0)
			(type solid)
		)
		(fill yes)
		(layer "In11.Cu")
		(net "M_D_CPU1_SB_DQS_DN<8>")
	)
	(gr_poly
		(pts
			(xy 85.96757 -224.593658) (xy 85.92058 -224.441258) (xy 85.65896 -224.441258) (xy 85.61197 -224.593658)
			(xy 85.61197 -224.637854) (xy 85.96757 -224.637854)
		)
		(stroke
			(width 0)
			(type solid)
		)
		(fill yes)
		(layer "In11.Cu")
		(net "M_D_CPU1_SB_DQ<30>")
	)
	(gr_poly
		(pts
			(xy 85.96757 -224.185226) (xy 85.96757 -224.14103) (xy 85.61197 -224.14103) (xy 85.61197 -224.185226)
			(xy 85.65896 -224.337626) (xy 85.92058 -224.337626)
		)
		(stroke
			(width 0)
			(type solid)
		)
		(fill yes)
		(layer "In11.Cu")
		(net "M_D_CPU1_SB_DQ<29>")
	)
	(gr_poly
		(pts
			(xy 85.973666 -248.601738) (xy 85.973666 -248.557542) (xy 85.618066 -248.557542) (xy 85.618066 -248.601738)
			(xy 85.665056 -248.754138) (xy 85.926676 -248.754138)
		)
		(stroke
			(width 0)
			(type solid)
		)
		(fill yes)
		(layer "In11.Cu")
		(net "M_D_CPU1_SB_CA<4>")
	)
	(gr_poly
		(pts
			(xy 85.973666 -247.382538) (xy 85.926676 -247.230138) (xy 85.665056 -247.230138) (xy 85.618066 -247.382538)
			(xy 85.618066 -247.426988) (xy 85.973666 -247.426988)
		)
		(stroke
			(width 0)
			(type solid)
		)
		(fill yes)
		(layer "In11.Cu")
		(net "M_D_CPU1_SB_CA<6>")
	)
	(gr_poly
		(pts
			(xy 85.973666 -246.974106) (xy 85.973666 -246.929656) (xy 85.618066 -246.929656) (xy 85.618066 -246.974106)
			(xy 85.665056 -247.126506) (xy 85.926676 -247.126506)
		)
		(stroke
			(width 0)
			(type solid)
		)
		(fill yes)
		(layer "In11.Cu")
		(net "M_D_CPU1_SB_CB<4>")
	)
	(gr_poly
		(pts
			(xy 85.973666 -245.754906) (xy 85.926676 -245.602506) (xy 85.665056 -245.602506) (xy 85.618066 -245.754906)
			(xy 85.618066 -245.799356) (xy 85.973666 -245.799356)
		)
		(stroke
			(width 0)
			(type solid)
		)
		(fill yes)
		(layer "In11.Cu")
		(net "M_D_CPU1_SB_CB<7>")
	)
	(gr_poly
		(pts
			(xy 85.973666 -238.83493) (xy 85.973666 -238.790734) (xy 85.618066 -238.790734) (xy 85.618066 -238.83493)
			(xy 85.665056 -238.98733) (xy 85.926676 -238.98733)
		)
		(stroke
			(width 0)
			(type solid)
		)
		(fill yes)
		(layer "In11.Cu")
		(net "M_D_CPU1_SB_DQS_DP<0>")
	)
	(gr_poly
		(pts
			(xy 85.973666 -235.988098) (xy 85.926676 -235.835698) (xy 85.665056 -235.835698) (xy 85.618066 -235.988098)
			(xy 85.618066 -236.032548) (xy 85.973666 -236.032548)
		)
		(stroke
			(width 0)
			(type solid)
		)
		(fill yes)
		(layer "In11.Cu")
		(net "M_D_CPU1_SB_DQ<7>")
	)
	(gr_poly
		(pts
			(xy 85.973666 -233.952034) (xy 85.973666 -233.907584) (xy 85.618066 -233.907584) (xy 85.618066 -233.952034)
			(xy 85.665056 -234.104434) (xy 85.926676 -234.104434)
		)
		(stroke
			(width 0)
			(type solid)
		)
		(fill yes)
		(layer "In11.Cu")
		(net "M_D_CPU1_SB_DQ<9>")
	)
	(gr_poly
		(pts
			(xy 85.973666 -231.104694) (xy 85.926676 -230.952294) (xy 85.665056 -230.952294) (xy 85.618066 -231.104694)
			(xy 85.618066 -231.149144) (xy 85.973666 -231.149144)
		)
		(stroke
			(width 0)
			(type solid)
		)
		(fill yes)
		(layer "In11.Cu")
		(net "M_D_CPU1_SB_DQ<14>")
	)
	(gr_poly
		(pts
			(xy 85.982048 -249.01017) (xy 85.935058 -248.85777) (xy 85.673438 -248.85777) (xy 85.626448 -249.01017)
			(xy 85.626448 -249.05462) (xy 85.982048 -249.05462)
		)
		(stroke
			(width 0)
			(type solid)
		)
		(fill yes)
		(layer "In11.Cu")
		(net "M_D_CPU1_SB_CA<3>")
	)
	(gr_poly
		(pts
			(xy 85.982048 -245.346474) (xy 85.982048 -245.302278) (xy 85.626448 -245.302278) (xy 85.626448 -245.346474)
			(xy 85.673438 -245.498874) (xy 85.935058 -245.498874)
		)
		(stroke
			(width 0)
			(type solid)
		)
		(fill yes)
		(layer "In11.Cu")
		(net "M_D_CPU1_SB_DQS_DP<9>")
	)
	(gr_poly
		(pts
			(xy 85.982048 -239.243362) (xy 85.935058 -239.090962) (xy 85.673438 -239.090962) (xy 85.626448 -239.243362)
			(xy 85.626448 -239.287812) (xy 85.982048 -239.287812)
		)
		(stroke
			(width 0)
			(type solid)
		)
		(fill yes)
		(layer "In11.Cu")
		(net "M_D_CPU1_SB_DQ<3>")
	)
	(gr_poly
		(pts
			(xy 85.982048 -234.360466) (xy 85.935058 -234.208066) (xy 85.673438 -234.208066) (xy 85.626448 -234.360466)
			(xy 85.626448 -234.404662) (xy 85.982048 -234.404662)
		)
		(stroke
			(width 0)
			(type solid)
		)
		(fill yes)
		(layer "In11.Cu")
		(net "M_D_CPU1_SB_DQ<10>")
	)
	(gr_poly
		(pts
			(xy 85.982048 -230.696262) (xy 85.982048 -230.652066) (xy 85.626448 -230.652066) (xy 85.626448 -230.696262)
			(xy 85.673438 -230.848662) (xy 85.935058 -230.848662)
		)
		(stroke
			(width 0)
			(type solid)
		)
		(fill yes)
		(layer "In11.Cu")
		(net "M_D_CPU1_SB_DQ<13>")
	)
	(gr_poly
		(pts
			(xy 86.074758 -274.876514) (xy 86.074758 -274.832318) (xy 85.719158 -274.832318) (xy 85.719158 -274.876514)
			(xy 85.766148 -275.028914) (xy 86.027768 -275.028914)
		)
		(stroke
			(width 0)
			(type solid)
		)
		(fill yes)
		(layer "In11.Cu")
		(net "M_D_CPU1_SA_DQ<16>")
	)
	(gr_poly
		(pts
			(xy 86.083394 -272.029682) (xy 86.036404 -271.877282) (xy 85.774784 -271.877282) (xy 85.727794 -272.029682)
			(xy 85.727794 -272.073878) (xy 86.083394 -272.073878)
		)
		(stroke
			(width 0)
			(type solid)
		)
		(fill yes)
		(layer "In11.Cu")
		(net "M_D_CPU1_SA_DQS_DP<7>")
	)
	(gr_poly
		(pts
			(xy 86.083394 -271.620742) (xy 86.083394 -271.576546) (xy 85.727794 -271.576546) (xy 85.727794 -271.620742)
			(xy 85.774784 -271.773142) (xy 86.036404 -271.773142)
		)
		(stroke
			(width 0)
			(type solid)
		)
		(fill yes)
		(layer "In11.Cu")
		(net "M_D_CPU1_SA_DQ<20>")
	)
	(gr_poly
		(pts
			(xy 86.083394 -270.40205) (xy 86.036404 -270.24965) (xy 85.774784 -270.24965) (xy 85.727794 -270.40205)
			(xy 85.727794 -270.446246) (xy 86.083394 -270.446246)
		)
		(stroke
			(width 0)
			(type solid)
		)
		(fill yes)
		(layer "In11.Cu")
		(net "M_D_CPU1_SA_DQ<23>")
	)
	(gr_poly
		(pts
			(xy 86.083394 -268.77391) (xy 86.036404 -268.62151) (xy 85.774784 -268.62151) (xy 85.727794 -268.77391)
			(xy 85.727794 -268.81836) (xy 86.083394 -268.81836)
		)
		(stroke
			(width 0)
			(type solid)
		)
		(fill yes)
		(layer "In11.Cu")
		(net "M_D_CPU1_SA_DQ<27>")
	)
	(gr_poly
		(pts
			(xy 86.083394 -268.365478) (xy 86.083394 -268.321028) (xy 85.727794 -268.321028) (xy 85.727794 -268.365478)
			(xy 85.774784 -268.517878) (xy 86.036404 -268.517878)
		)
		(stroke
			(width 0)
			(type solid)
		)
		(fill yes)
		(layer "In11.Cu")
		(net "M_D_CPU1_SA_DQS_DP<3>")
	)
	(gr_poly
		(pts
			(xy 86.083394 -267.146278) (xy 86.036404 -266.993878) (xy 85.774784 -266.993878) (xy 85.727794 -267.146278)
			(xy 85.727794 -267.190474) (xy 86.083394 -267.190474)
		)
		(stroke
			(width 0)
			(type solid)
		)
		(fill yes)
		(layer "In11.Cu")
		(net "M_D_CPU1_SA_DQS_DP<8>")
	)
	(gr_poly
		(pts
			(xy 86.083394 -266.737846) (xy 86.083394 -266.693396) (xy 85.727794 -266.693396) (xy 85.727794 -266.737846)
			(xy 85.774784 -266.890246) (xy 86.036404 -266.890246)
		)
		(stroke
			(width 0)
			(type solid)
		)
		(fill yes)
		(layer "In11.Cu")
		(net "M_D_CPU1_SA_DQ<28>")
	)
	(gr_poly
		(pts
			(xy 86.083394 -265.518646) (xy 86.036404 -265.366246) (xy 85.774784 -265.366246) (xy 85.727794 -265.518646)
			(xy 85.727794 -265.562842) (xy 86.083394 -265.562842)
		)
		(stroke
			(width 0)
			(type solid)
		)
		(fill yes)
		(layer "In11.Cu")
		(net "M_D_CPU1_SA_DQ<31>")
	)
	(gr_poly
		(pts
			(xy 86.083394 -265.109706) (xy 86.083394 -265.06551) (xy 85.727794 -265.06551) (xy 85.727794 -265.109706)
			(xy 85.774784 -265.262106) (xy 86.036404 -265.262106)
		)
		(stroke
			(width 0)
			(type solid)
		)
		(fill yes)
		(layer "In11.Cu")
		(net "M_D_CPU1_SA_CB<0>")
	)
	(gr_poly
		(pts
			(xy 86.083394 -263.891014) (xy 86.036404 -263.738614) (xy 85.774784 -263.738614) (xy 85.727794 -263.891014)
			(xy 85.727794 -263.93521) (xy 86.083394 -263.93521)
		)
		(stroke
			(width 0)
			(type solid)
		)
		(fill yes)
		(layer "In11.Cu")
		(net "M_D_CPU1_SA_CB<3>")
	)
	(gr_poly
		(pts
			(xy 86.083394 -263.482074) (xy 86.083394 -263.437878) (xy 85.727794 -263.437878) (xy 85.727794 -263.482074)
			(xy 85.774784 -263.634474) (xy 86.036404 -263.634474)
		)
		(stroke
			(width 0)
			(type solid)
		)
		(fill yes)
		(layer "In11.Cu")
		(net "M_D_CPU1_SA_DQS_DP<4>")
	)
	(gr_poly
		(pts
			(xy 86.083394 -262.262874) (xy 86.036404 -262.110474) (xy 85.774784 -262.110474) (xy 85.727794 -262.262874)
			(xy 85.727794 -262.307324) (xy 86.083394 -262.307324)
		)
		(stroke
			(width 0)
			(type solid)
		)
		(fill yes)
		(layer "In11.Cu")
		(net "M_D_CPU1_SA_DQS_DP<9>")
	)
	(gr_poly
		(pts
			(xy 86.083394 -261.854442) (xy 86.083394 -261.809992) (xy 85.727794 -261.809992) (xy 85.727794 -261.854442)
			(xy 85.774784 -262.006842) (xy 86.036404 -262.006842)
		)
		(stroke
			(width 0)
			(type solid)
		)
		(fill yes)
		(layer "In11.Cu")
		(net "M_D_CPU1_SA_CB<4>")
	)
	(gr_poly
		(pts
			(xy 86.083394 -260.635242) (xy 86.036404 -260.482842) (xy 85.774784 -260.482842) (xy 85.727794 -260.635242)
			(xy 85.727794 -260.679438) (xy 86.083394 -260.679438)
		)
		(stroke
			(width 0)
			(type solid)
		)
		(fill yes)
		(layer "In11.Cu")
		(net "M_D_CPU1_SA_CB<7>")
	)
	(gr_poly
		(pts
			(xy 86.083394 -259.00761) (xy 86.036404 -258.85521) (xy 85.774784 -258.85521) (xy 85.727794 -259.00761)
			(xy 85.727794 -259.051806) (xy 86.083394 -259.051806)
		)
		(stroke
			(width 0)
			(type solid)
		)
		(fill yes)
		(layer "In11.Cu")
		(net "M_D_CPU1_SA_CS_N<0>")
	)
	(gr_poly
		(pts
			(xy 86.083394 -258.59867) (xy 86.083394 -258.554474) (xy 85.727794 -258.554474) (xy 85.727794 -258.59867)
			(xy 85.774784 -258.75107) (xy 86.036404 -258.75107)
		)
		(stroke
			(width 0)
			(type solid)
		)
		(fill yes)
		(layer "In11.Cu")
		(net "M_D_CPU1_SA_CS_N<3>")
	)
	(gr_poly
		(pts
			(xy 86.083394 -257.37947) (xy 86.036404 -257.22707) (xy 85.774784 -257.22707) (xy 85.727794 -257.37947)
			(xy 85.727794 -257.42392) (xy 86.083394 -257.42392)
		)
		(stroke
			(width 0)
			(type solid)
		)
		(fill yes)
		(layer "In11.Cu")
		(net "M_D_CPU1_SA_CA<1>")
	)
	(gr_poly
		(pts
			(xy 86.083394 -256.971038) (xy 86.083394 -256.926588) (xy 85.727794 -256.926588) (xy 85.727794 -256.971038)
			(xy 85.774784 -257.123438) (xy 86.036404 -257.123438)
		)
		(stroke
			(width 0)
			(type solid)
		)
		(fill yes)
		(layer "In11.Cu")
		(net "M_D_CPU1_SA_CA<2>")
	)
	(gr_poly
		(pts
			(xy 86.083394 -255.751838) (xy 86.036404 -255.599438) (xy 85.774784 -255.599438) (xy 85.727794 -255.751838)
			(xy 85.727794 -255.796288) (xy 86.083394 -255.796288)
		)
		(stroke
			(width 0)
			(type solid)
		)
		(fill yes)
		(layer "In11.Cu")
		(net "M_D_CPU1_SA_CA<5>")
	)
	(gr_poly
		(pts
			(xy 86.09203 -273.657314) (xy 86.04504 -273.504914) (xy 85.78342 -273.504914) (xy 85.73643 -273.657314)
			(xy 85.73643 -273.70151) (xy 86.09203 -273.70151)
		)
		(stroke
			(width 0)
			(type solid)
		)
		(fill yes)
		(layer "In11.Cu")
		(net "M_D_CPU1_SA_DQ<19>")
	)
	(gr_poly
		(pts
			(xy 86.09203 -273.248882) (xy 86.09203 -273.204686) (xy 85.73643 -273.204686) (xy 85.73643 -273.248882)
			(xy 85.78342 -273.401282) (xy 86.04504 -273.401282)
		)
		(stroke
			(width 0)
			(type solid)
		)
		(fill yes)
		(layer "In11.Cu")
		(net "M_D_CPU1_SA_DQS_DP<2>")
	)
	(gr_poly
		(pts
			(xy 86.299294 -228.921818) (xy 86.337648 -228.89972) (xy 86.159848 -228.591872) (xy 86.121494 -228.61397)
			(xy 86.013036 -228.73081) (xy 86.143846 -228.957378)
		)
		(stroke
			(width 0)
			(type solid)
		)
		(fill yes)
		(layer "In11.Cu")
		(net "M_D_CPU1_SB_DQ<24>")
	)
	(gr_poly
		(pts
			(xy 86.300056 -240.318036) (xy 86.33841 -240.295938) (xy 86.16061 -239.98809) (xy 86.122256 -240.010188)
			(xy 86.013798 -240.127028) (xy 86.144608 -240.353596)
		)
		(stroke
			(width 0)
			(type solid)
		)
		(fill yes)
		(layer "In11.Cu")
		(net "M_D_CPU1_SB_DQ<1>")
	)
	(gr_poly
		(pts
			(xy 86.30031 -243.574316) (xy 86.338664 -243.552218) (xy 86.160864 -243.24437) (xy 86.12251 -243.266468)
			(xy 86.014052 -243.383308) (xy 86.144862 -243.609876)
		)
		(stroke
			(width 0)
			(type solid)
		)
		(fill yes)
		(layer "In11.Cu")
		(net "M_D_CPU1_SB_CB<0>")
	)
	(gr_poly
		(pts
			(xy 86.408006 -242.949984) (xy 86.516464 -242.833144) (xy 86.385654 -242.606576) (xy 86.230206 -242.642136)
			(xy 86.191852 -242.664234) (xy 86.369652 -242.972082)
		)
		(stroke
			(width 0)
			(type solid)
		)
		(fill yes)
		(layer "In11.Cu")
		(net "M_D_CPU1_SB_CB<2>")
	)
	(gr_poly
		(pts
			(xy 86.408006 -228.300026) (xy 86.516464 -228.183186) (xy 86.385654 -227.956618) (xy 86.230206 -227.992178)
			(xy 86.191852 -228.014276) (xy 86.369652 -228.322124)
		)
		(stroke
			(width 0)
			(type solid)
		)
		(fill yes)
		(layer "In11.Cu")
		(net "M_D_CPU1_SB_DQ<26>")
	)
	(gr_poly
		(pts
			(xy 86.408768 -239.695736) (xy 86.517226 -239.578896) (xy 86.386416 -239.352328) (xy 86.230968 -239.387888)
			(xy 86.192614 -239.409986) (xy 86.370414 -239.717834)
		)
		(stroke
			(width 0)
			(type solid)
		)
		(fill yes)
		(layer "In11.Cu")
		(net "M_D_CPU1_SB_DQ<3>")
	)
	(gr_poly
		(pts
			(xy 86.43493 -249.416062) (xy 86.43493 -249.371612) (xy 86.07933 -249.371612) (xy 86.07933 -249.416062)
			(xy 86.12632 -249.568462) (xy 86.38794 -249.568462)
		)
		(stroke
			(width 0)
			(type solid)
		)
		(fill yes)
		(layer "In11.Cu")
		(net "M_D_CPU1_SB_CA<2>")
	)
	(gr_poly
		(pts
			(xy 86.43493 -244.940582) (xy 86.38794 -244.788182) (xy 86.12632 -244.788182) (xy 86.07933 -244.940582)
			(xy 86.07933 -244.985032) (xy 86.43493 -244.985032)
		)
		(stroke
			(width 0)
			(type solid)
		)
		(fill yes)
		(layer "In11.Cu")
		(net "M_D_CPU1_SB_DQS_DN<9>")
	)
	(gr_poly
		(pts
			(xy 86.43493 -234.76585) (xy 86.43493 -234.721654) (xy 86.07933 -234.721654) (xy 86.07933 -234.76585)
			(xy 86.12632 -234.91825) (xy 86.38794 -234.91825)
		)
		(stroke
			(width 0)
			(type solid)
		)
		(fill yes)
		(layer "In11.Cu")
		(net "M_D_CPU1_SB_DQ<8>")
	)
	(gr_poly
		(pts
			(xy 86.43493 -230.290878) (xy 86.38794 -230.138478) (xy 86.12632 -230.138478) (xy 86.07933 -230.290878)
			(xy 86.07933 -230.335074) (xy 86.43493 -230.335074)
		)
		(stroke
			(width 0)
			(type solid)
		)
		(fill yes)
		(layer "In11.Cu")
		(net "M_D_CPU1_SB_DQ<15>")
	)
	(gr_poly
		(pts
			(xy 86.43747 -227.035614) (xy 86.39048 -226.883214) (xy 86.12886 -226.883214) (xy 86.08187 -227.035614)
			(xy 86.08187 -227.07981) (xy 86.43747 -227.07981)
		)
		(stroke
			(width 0)
			(type solid)
		)
		(fill yes)
		(layer "In11.Cu")
		(net "M_D_CPU1_SB_DQ<27>")
	)
	(gr_poly
		(pts
			(xy 86.43747 -226.626674) (xy 86.43747 -226.582478) (xy 86.08187 -226.582478) (xy 86.08187 -226.626674)
			(xy 86.12886 -226.779074) (xy 86.39048 -226.779074)
		)
		(stroke
			(width 0)
			(type solid)
		)
		(fill yes)
		(layer "In11.Cu")
		(net "M_D_CPU1_SB_DQS_DP<3>")
	)
	(gr_poly
		(pts
			(xy 86.443312 -244.53215) (xy 86.443312 -244.487954) (xy 86.087712 -244.487954) (xy 86.087712 -244.53215)
			(xy 86.134702 -244.68455) (xy 86.396322 -244.68455)
		)
		(stroke
			(width 0)
			(type solid)
		)
		(fill yes)
		(layer "In11.Cu")
		(net "M_D_CPU1_SB_DQS_DN<4>")
	)
	(gr_poly
		(pts
			(xy 86.443566 -248.196354) (xy 86.396576 -248.043954) (xy 86.134956 -248.043954) (xy 86.087966 -248.196354)
			(xy 86.087966 -248.240804) (xy 86.443566 -248.240804)
		)
		(stroke
			(width 0)
			(type solid)
		)
		(fill yes)
		(layer "In11.Cu")
		(net "M_D_CPU1_SB_CA<5>")
	)
	(gr_poly
		(pts
			(xy 86.443566 -247.787922) (xy 86.443566 -247.743472) (xy 86.087966 -247.743472) (xy 86.087966 -247.787922)
			(xy 86.134956 -247.940322) (xy 86.396576 -247.940322)
		)
		(stroke
			(width 0)
			(type solid)
		)
		(fill yes)
		(layer "In11.Cu")
		(net "M_D_CPU1_SB_PAR")
	)
	(gr_poly
		(pts
			(xy 86.443566 -246.568722) (xy 86.396576 -246.416322) (xy 86.134956 -246.416322) (xy 86.087966 -246.568722)
			(xy 86.087966 -246.613172) (xy 86.443566 -246.613172)
		)
		(stroke
			(width 0)
			(type solid)
		)
		(fill yes)
		(layer "In11.Cu")
		(net "M_D_CPU1_SB_CB<6>")
	)
	(gr_poly
		(pts
			(xy 86.443566 -246.16029) (xy 86.443566 -246.11584) (xy 86.087966 -246.11584) (xy 86.087966 -246.16029)
			(xy 86.134956 -246.31269) (xy 86.396576 -246.31269)
		)
		(stroke
			(width 0)
			(type solid)
		)
		(fill yes)
		(layer "In11.Cu")
		(net "M_D_CPU1_SB_CB<5>")
	)
	(gr_poly
		(pts
			(xy 86.443566 -241.685318) (xy 86.396576 -241.532918) (xy 86.134956 -241.532918) (xy 86.087966 -241.685318)
			(xy 86.087966 -241.729768) (xy 86.443566 -241.729768)
		)
		(stroke
			(width 0)
			(type solid)
		)
		(fill yes)
		(layer "In11.Cu")
		(net "M_D_CPU1_SB_CB<3>")
	)
	(gr_poly
		(pts
			(xy 86.443566 -241.276886) (xy 86.443566 -241.232436) (xy 86.087966 -241.232436) (xy 86.087966 -241.276886)
			(xy 86.134956 -241.429286) (xy 86.396576 -241.429286)
		)
		(stroke
			(width 0)
			(type solid)
		)
		(fill yes)
		(layer "In11.Cu")
		(net "M_D_CPU1_SB_DQ<0>")
	)
	(gr_poly
		(pts
			(xy 86.443566 -238.430054) (xy 86.396576 -238.277654) (xy 86.134956 -238.277654) (xy 86.087966 -238.430054)
			(xy 86.087966 -238.47425) (xy 86.443566 -238.47425)
		)
		(stroke
			(width 0)
			(type solid)
		)
		(fill yes)
		(layer "In11.Cu")
		(net "M_D_CPU1_SB_DQS_DN<0>")
	)
	(gr_poly
		(pts
			(xy 86.443566 -238.021114) (xy 86.443566 -237.976918) (xy 86.087966 -237.976918) (xy 86.087966 -238.021114)
			(xy 86.134956 -238.173514) (xy 86.396576 -238.173514)
		)
		(stroke
			(width 0)
			(type solid)
		)
		(fill yes)
		(layer "In11.Cu")
		(net "M_D_CPU1_SB_DQS_DN<5>")
	)
	(gr_poly
		(pts
			(xy 86.443566 -236.802422) (xy 86.396576 -236.650022) (xy 86.134956 -236.650022) (xy 86.087966 -236.802422)
			(xy 86.087966 -236.846618) (xy 86.443566 -236.846618)
		)
		(stroke
			(width 0)
			(type solid)
		)
		(fill yes)
		(layer "In11.Cu")
		(net "M_D_CPU1_SB_DQ<6>")
	)
	(gr_poly
		(pts
			(xy 86.443566 -236.393482) (xy 86.443566 -236.349286) (xy 86.087966 -236.349286) (xy 86.087966 -236.393482)
			(xy 86.134956 -236.545882) (xy 86.396576 -236.545882)
		)
		(stroke
			(width 0)
			(type solid)
		)
		(fill yes)
		(layer "In11.Cu")
		(net "M_D_CPU1_SB_DQ<5>")
	)
	(gr_poly
		(pts
			(xy 86.443566 -233.54665) (xy 86.396576 -233.39425) (xy 86.134956 -233.39425) (xy 86.087966 -233.54665)
			(xy 86.087966 -233.590846) (xy 86.443566 -233.590846)
		)
		(stroke
			(width 0)
			(type solid)
		)
		(fill yes)
		(layer "In11.Cu")
		(net "M_D_CPU1_SB_DQ<11>")
	)
	(gr_poly
		(pts
			(xy 86.443566 -233.13771) (xy 86.443566 -233.093514) (xy 86.087966 -233.093514) (xy 86.087966 -233.13771)
			(xy 86.134956 -233.29011) (xy 86.396576 -233.29011)
		)
		(stroke
			(width 0)
			(type solid)
		)
		(fill yes)
		(layer "In11.Cu")
		(net "M_D_CPU1_SB_DQS_DP<1>")
	)
	(gr_poly
		(pts
			(xy 86.443566 -231.919018) (xy 86.396576 -231.766618) (xy 86.134956 -231.766618) (xy 86.087966 -231.919018)
			(xy 86.087966 -231.963214) (xy 86.443566 -231.963214)
		)
		(stroke
			(width 0)
			(type solid)
		)
		(fill yes)
		(layer "In11.Cu")
		(net "M_D_CPU1_SB_DQS_DP<6>")
	)
	(gr_poly
		(pts
			(xy 86.443566 -231.510078) (xy 86.443566 -231.465882) (xy 86.087966 -231.465882) (xy 86.087966 -231.510078)
			(xy 86.134956 -231.662478) (xy 86.396576 -231.662478)
		)
		(stroke
			(width 0)
			(type solid)
		)
		(fill yes)
		(layer "In11.Cu")
		(net "M_D_CPU1_SB_DQ<12>")
	)
	(gr_poly
		(pts
			(xy 86.443566 -225.407474) (xy 86.396576 -225.255074) (xy 86.134956 -225.255074) (xy 86.087966 -225.407474)
			(xy 86.087966 -225.451924) (xy 86.443566 -225.451924)
		)
		(stroke
			(width 0)
			(type solid)
		)
		(fill yes)
		(layer "In11.Cu")
		(net "M_D_CPU1_SB_DQS_DP<8>")
	)
	(gr_poly
		(pts
			(xy 86.443566 -224.999042) (xy 86.443566 -224.954592) (xy 86.087966 -224.954592) (xy 86.087966 -224.999042)
			(xy 86.134956 -225.151442) (xy 86.396576 -225.151442)
		)
		(stroke
			(width 0)
			(type solid)
		)
		(fill yes)
		(layer "In11.Cu")
		(net "M_D_CPU1_SB_DQ<28>")
	)
	(gr_poly
		(pts
			(xy 86.443566 -223.779842) (xy 86.396576 -223.627442) (xy 86.134956 -223.627442) (xy 86.087966 -223.779842)
			(xy 86.087966 -223.824292) (xy 86.443566 -223.824292)
		)
		(stroke
			(width 0)
			(type solid)
		)
		(fill yes)
		(layer "In11.Cu")
		(net "M_D_CPU1_SB_DQ<31>")
	)
	(gr_poly
		(pts
			(xy 86.544912 -274.062698) (xy 86.544912 -274.018502) (xy 86.189312 -274.018502) (xy 86.189312 -274.062698)
			(xy 86.236302 -274.215098) (xy 86.497922 -274.215098)
		)
		(stroke
			(width 0)
			(type solid)
		)
		(fill yes)
		(layer "In11.Cu")
		(net "M_D_CPU1_SA_DQ<17>")
	)
	(gr_poly
		(pts
			(xy 86.547452 -272.843498) (xy 86.500462 -272.691098) (xy 86.238842 -272.691098) (xy 86.191852 -272.843498)
			(xy 86.191852 -272.887694) (xy 86.547452 -272.887694)
		)
		(stroke
			(width 0)
			(type solid)
		)
		(fill yes)
		(layer "In11.Cu")
		(net "M_D_CPU1_SA_DQS_DN<2>")
	)
	(gr_poly
		(pts
			(xy 86.553294 -271.215866) (xy 86.506304 -271.063466) (xy 86.244684 -271.063466) (xy 86.197694 -271.215866)
			(xy 86.197694 -271.260062) (xy 86.553294 -271.260062)
		)
		(stroke
			(width 0)
			(type solid)
		)
		(fill yes)
		(layer "In11.Cu")
		(net "M_D_CPU1_SA_DQ<22>")
	)
	(gr_poly
		(pts
			(xy 86.553294 -270.806926) (xy 86.553294 -270.76273) (xy 86.197694 -270.76273) (xy 86.197694 -270.806926)
			(xy 86.244684 -270.959326) (xy 86.506304 -270.959326)
		)
		(stroke
			(width 0)
			(type solid)
		)
		(fill yes)
		(layer "In11.Cu")
		(net "M_D_CPU1_SA_DQ<21>")
	)
	(gr_poly
		(pts
			(xy 86.553294 -269.587726) (xy 86.506304 -269.435326) (xy 86.244684 -269.435326) (xy 86.197694 -269.587726)
			(xy 86.197694 -269.632176) (xy 86.553294 -269.632176)
		)
		(stroke
			(width 0)
			(type solid)
		)
		(fill yes)
		(layer "In11.Cu")
		(net "M_D_CPU1_SA_DQ<26>")
	)
	(gr_poly
		(pts
			(xy 86.553294 -269.179294) (xy 86.553294 -269.134844) (xy 86.197694 -269.134844) (xy 86.197694 -269.179294)
			(xy 86.244684 -269.331694) (xy 86.506304 -269.331694)
		)
		(stroke
			(width 0)
			(type solid)
		)
		(fill yes)
		(layer "In11.Cu")
		(net "M_D_CPU1_SA_DQ<25>")
	)
	(gr_poly
		(pts
			(xy 86.553294 -267.960094) (xy 86.506304 -267.807694) (xy 86.244684 -267.807694) (xy 86.197694 -267.960094)
			(xy 86.197694 -268.004544) (xy 86.553294 -268.004544)
		)
		(stroke
			(width 0)
			(type solid)
		)
		(fill yes)
		(layer "In11.Cu")
		(net "M_D_CPU1_SA_DQS_DN<3>")
	)
	(gr_poly
		(pts
			(xy 86.553294 -267.551662) (xy 86.553294 -267.507212) (xy 86.197694 -267.507212) (xy 86.197694 -267.551662)
			(xy 86.244684 -267.704062) (xy 86.506304 -267.704062)
		)
		(stroke
			(width 0)
			(type solid)
		)
		(fill yes)
		(layer "In11.Cu")
		(net "M_D_CPU1_SA_DQS_DN<8>")
	)
	(gr_poly
		(pts
			(xy 86.553294 -266.332462) (xy 86.506304 -266.180062) (xy 86.244684 -266.180062) (xy 86.197694 -266.332462)
			(xy 86.197694 -266.376658) (xy 86.553294 -266.376658)
		)
		(stroke
			(width 0)
			(type solid)
		)
		(fill yes)
		(layer "In11.Cu")
		(net "M_D_CPU1_SA_DQ<30>")
	)
	(gr_poly
		(pts
			(xy 86.553294 -265.92403) (xy 86.553294 -265.87958) (xy 86.197694 -265.87958) (xy 86.197694 -265.92403)
			(xy 86.244684 -266.07643) (xy 86.506304 -266.07643)
		)
		(stroke
			(width 0)
			(type solid)
		)
		(fill yes)
		(layer "In11.Cu")
		(net "M_D_CPU1_SA_DQ<29>")
	)
	(gr_poly
		(pts
			(xy 86.553294 -264.70483) (xy 86.506304 -264.55243) (xy 86.244684 -264.55243) (xy 86.197694 -264.70483)
			(xy 86.197694 -264.749026) (xy 86.553294 -264.749026)
		)
		(stroke
			(width 0)
			(type solid)
		)
		(fill yes)
		(layer "In11.Cu")
		(net "M_D_CPU1_SA_CB<2>")
	)
	(gr_poly
		(pts
			(xy 86.553294 -264.29589) (xy 86.553294 -264.251694) (xy 86.197694 -264.251694) (xy 86.197694 -264.29589)
			(xy 86.244684 -264.44829) (xy 86.506304 -264.44829)
		)
		(stroke
			(width 0)
			(type solid)
		)
		(fill yes)
		(layer "In11.Cu")
		(net "M_D_CPU1_SA_CB<1>")
	)
	(gr_poly
		(pts
			(xy 86.553294 -263.07669) (xy 86.506304 -262.92429) (xy 86.244684 -262.92429) (xy 86.197694 -263.07669)
			(xy 86.197694 -263.12114) (xy 86.553294 -263.12114)
		)
		(stroke
			(width 0)
			(type solid)
		)
		(fill yes)
		(layer "In11.Cu")
		(net "M_D_CPU1_SA_DQS_DN<4>")
	)
	(gr_poly
		(pts
			(xy 86.553294 -262.668258) (xy 86.553294 -262.623808) (xy 86.197694 -262.623808) (xy 86.197694 -262.668258)
			(xy 86.244684 -262.820658) (xy 86.506304 -262.820658)
		)
		(stroke
			(width 0)
			(type solid)
		)
		(fill yes)
		(layer "In11.Cu")
		(net "M_D_CPU1_SA_DQS_DN<9>")
	)
	(gr_poly
		(pts
			(xy 86.553294 -261.449058) (xy 86.506304 -261.296658) (xy 86.244684 -261.296658) (xy 86.197694 -261.449058)
			(xy 86.197694 -261.493508) (xy 86.553294 -261.493508)
		)
		(stroke
			(width 0)
			(type solid)
		)
		(fill yes)
		(layer "In11.Cu")
		(net "M_D_CPU1_SA_CB<6>")
	)
	(gr_poly
		(pts
			(xy 86.553294 -261.040626) (xy 86.553294 -260.996176) (xy 86.197694 -260.996176) (xy 86.197694 -261.040626)
			(xy 86.244684 -261.193026) (xy 86.506304 -261.193026)
		)
		(stroke
			(width 0)
			(type solid)
		)
		(fill yes)
		(layer "In11.Cu")
		(net "M_D_CPU1_SA_CB<5>")
	)
	(gr_poly
		(pts
			(xy 86.553294 -259.412486) (xy 86.553294 -259.36829) (xy 86.197694 -259.36829) (xy 86.197694 -259.412486)
			(xy 86.244684 -259.564886) (xy 86.506304 -259.564886)
		)
		(stroke
			(width 0)
			(type solid)
		)
		(fill yes)
		(layer "In11.Cu")
		(net "M_D_CPU1_SA_CS_N<2>")
	)
	(gr_poly
		(pts
			(xy 86.553294 -258.193286) (xy 86.506304 -258.040886) (xy 86.244684 -258.040886) (xy 86.197694 -258.193286)
			(xy 86.197694 -258.237736) (xy 86.553294 -258.237736)
		)
		(stroke
			(width 0)
			(type solid)
		)
		(fill yes)
		(layer "In11.Cu")
		(net "M_D_CPU1_SA_CS_N<1>")
	)
	(gr_poly
		(pts
			(xy 86.553294 -257.784854) (xy 86.553294 -257.740404) (xy 86.197694 -257.740404) (xy 86.197694 -257.784854)
			(xy 86.244684 -257.937254) (xy 86.506304 -257.937254)
		)
		(stroke
			(width 0)
			(type solid)
		)
		(fill yes)
		(layer "In11.Cu")
		(net "M_D_CPU1_SA_CA<0>")
	)
	(gr_poly
		(pts
			(xy 86.553294 -256.565654) (xy 86.506304 -256.413254) (xy 86.244684 -256.413254) (xy 86.197694 -256.565654)
			(xy 86.197694 -256.610104) (xy 86.553294 -256.610104)
		)
		(stroke
			(width 0)
			(type solid)
		)
		(fill yes)
		(layer "In11.Cu")
		(net "M_D_CPU1_SA_CA<3>")
	)
	(gr_poly
		(pts
			(xy 86.553294 -256.157222) (xy 86.553294 -256.112772) (xy 86.197694 -256.112772) (xy 86.197694 -256.157222)
			(xy 86.244684 -256.309622) (xy 86.506304 -256.309622)
		)
		(stroke
			(width 0)
			(type solid)
		)
		(fill yes)
		(layer "In11.Cu")
		(net "M_D_CPU1_SA_CA<4>")
	)
	(gr_poly
		(pts
			(xy 86.55939 -272.435066) (xy 86.55939 -272.39087) (xy 86.20379 -272.39087) (xy 86.20379 -272.435066)
			(xy 86.25078 -272.587466) (xy 86.5124 -272.587466)
		)
		(stroke
			(width 0)
			(type solid)
		)
		(fill yes)
		(layer "In11.Cu")
		(net "M_D_CPU1_SA_DQS_DN<7>")
	)
	(gr_poly
		(pts
			(xy 86.561676 -274.47113) (xy 86.514686 -274.31873) (xy 86.253066 -274.31873) (xy 86.206076 -274.47113)
			(xy 86.206076 -274.515326) (xy 86.561676 -274.515326)
		)
		(stroke
			(width 0)
			(type solid)
		)
		(fill yes)
		(layer "In11.Cu")
		(net "M_D_CPU1_SA_DQ<18>")
	)
	(gr_poly
		(pts
			(xy 86.76894 -229.735634) (xy 86.807294 -229.713536) (xy 86.629494 -229.405688) (xy 86.59114 -229.427786)
			(xy 86.482682 -229.544626) (xy 86.613492 -229.771194)
		)
		(stroke
			(width 0)
			(type solid)
		)
		(fill yes)
		(layer "In11.Cu")
		(net "M_D_CPU1_SB_DQ<24>")
	)
	(gr_poly
		(pts
			(xy 86.76894 -228.107748) (xy 86.807294 -228.08565) (xy 86.629494 -227.777802) (xy 86.59114 -227.7999)
			(xy 86.482682 -227.91674) (xy 86.613492 -228.143308)
		)
		(stroke
			(width 0)
			(type solid)
		)
		(fill yes)
		(layer "In11.Cu")
		(net "M_D_CPU1_SB_DQ<25>")
	)
	(gr_poly
		(pts
			(xy 86.769956 -242.759738) (xy 86.80831 -242.73764) (xy 86.63051 -242.429792) (xy 86.592156 -242.45189)
			(xy 86.483698 -242.56873) (xy 86.614508 -242.795298)
		)
		(stroke
			(width 0)
			(type solid)
		)
		(fill yes)
		(layer "In11.Cu")
		(net "M_D_CPU1_SB_CB<1>")
	)
	(gr_poly
		(pts
			(xy 86.77021 -239.504728) (xy 86.808564 -239.48263) (xy 86.630764 -239.174782) (xy 86.59241 -239.19688)
			(xy 86.483952 -239.31372) (xy 86.614762 -239.540288)
		)
		(stroke
			(width 0)
			(type solid)
		)
		(fill yes)
		(layer "In11.Cu")
		(net "M_D_CPU1_SB_DQS_DP<0>")
	)
	(gr_poly
		(pts
			(xy 86.879938 -242.139978) (xy 86.988396 -242.023138) (xy 86.857586 -241.79657) (xy 86.702138 -241.83213)
			(xy 86.663784 -241.854228) (xy 86.841584 -242.162076)
		)
		(stroke
			(width 0)
			(type solid)
		)
		(fill yes)
		(layer "In11.Cu")
		(net "M_D_CPU1_SB_CB<3>")
	)
	(gr_poly
		(pts
			(xy 86.879938 -238.88446) (xy 86.988396 -238.76762) (xy 86.857586 -238.541052) (xy 86.702138 -238.576612)
			(xy 86.663784 -238.59871) (xy 86.841584 -238.906558)
		)
		(stroke
			(width 0)
			(type solid)
		)
		(fill yes)
		(layer "In11.Cu")
		(net "M_D_CPU1_SB_DQS_DN<0>")
	)
	(gr_poly
		(pts
			(xy 86.879938 -229.117906) (xy 86.988396 -229.001066) (xy 86.857586 -228.774498) (xy 86.702138 -228.810058)
			(xy 86.663784 -228.832156) (xy 86.841584 -229.140004)
		)
		(stroke
			(width 0)
			(type solid)
		)
		(fill yes)
		(layer "In11.Cu")
		(net "M_D_CPU1_SB_DQ<26>")
	)
	(gr_poly
		(pts
			(xy 86.884256 -227.497132) (xy 86.992714 -227.380292) (xy 86.861904 -227.153724) (xy 86.706456 -227.189284)
			(xy 86.668102 -227.211382) (xy 86.845902 -227.51923)
		)
		(stroke
			(width 0)
			(type solid)
		)
		(fill yes)
		(layer "In11.Cu")
		(net "M_D_CPU1_SB_DQ<27>")
	)
	(gr_poly
		(pts
			(xy 86.90483 -243.718842) (xy 86.90483 -243.674392) (xy 86.54923 -243.674392) (xy 86.54923 -243.718842)
			(xy 86.59622 -243.871242) (xy 86.85784 -243.871242)
		)
		(stroke
			(width 0)
			(type solid)
		)
		(fill yes)
		(layer "In11.Cu")
		(net "M_D_CPU1_SB_CB<0>")
	)
	(gr_poly
		(pts
			(xy 86.90737 -237.616238) (xy 86.86038 -237.463838) (xy 86.59876 -237.463838) (xy 86.55177 -237.616238)
			(xy 86.55177 -237.660434) (xy 86.90737 -237.660434)
		)
		(stroke
			(width 0)
			(type solid)
		)
		(fill yes)
		(layer "In11.Cu")
		(net "M_D_CPU1_SB_DQS_DP<5>")
	)
	(gr_poly
		(pts
			(xy 86.90737 -237.207298) (xy 86.90737 -237.163102) (xy 86.55177 -237.163102) (xy 86.55177 -237.207298)
			(xy 86.59876 -237.359698) (xy 86.86038 -237.359698)
		)
		(stroke
			(width 0)
			(type solid)
		)
		(fill yes)
		(layer "In11.Cu")
		(net "M_D_CPU1_SB_DQ<4>")
	)
	(gr_poly
		(pts
			(xy 86.90737 -225.812858) (xy 86.90737 -225.768662) (xy 86.55177 -225.768662) (xy 86.55177 -225.812858)
			(xy 86.59876 -225.965258) (xy 86.86038 -225.965258)
		)
		(stroke
			(width 0)
			(type solid)
		)
		(fill yes)
		(layer "In11.Cu")
		(net "M_D_CPU1_SB_DQS_DN<8>")
	)
	(gr_poly
		(pts
			(xy 86.913212 -244.127274) (xy 86.866222 -243.974874) (xy 86.604602 -243.974874) (xy 86.557612 -244.127274)
			(xy 86.557612 -244.17147) (xy 86.913212 -244.17147)
		)
		(stroke
			(width 0)
			(type solid)
		)
		(fill yes)
		(layer "In11.Cu")
		(net "M_D_CPU1_SB_DQS_DP<4>")
	)
	(gr_poly
		(pts
			(xy 86.913466 -248.601738) (xy 86.913466 -248.557542) (xy 86.557866 -248.557542) (xy 86.557866 -248.601738)
			(xy 86.604856 -248.754138) (xy 86.866476 -248.754138)
		)
		(stroke
			(width 0)
			(type solid)
		)
		(fill yes)
		(layer "In11.Cu")
		(net "M_D_CPU1_SB_CA<4>")
	)
	(gr_poly
		(pts
			(xy 86.913466 -247.382538) (xy 86.866476 -247.230138) (xy 86.604856 -247.230138) (xy 86.557866 -247.382538)
			(xy 86.557866 -247.426988) (xy 86.913466 -247.426988)
		)
		(stroke
			(width 0)
			(type solid)
		)
		(fill yes)
		(layer "In11.Cu")
		(net "M_D_CPU1_SB_CA<6>")
	)
	(gr_poly
		(pts
			(xy 86.913466 -246.974106) (xy 86.913466 -246.929656) (xy 86.557866 -246.929656) (xy 86.557866 -246.974106)
			(xy 86.604856 -247.126506) (xy 86.866476 -247.126506)
		)
		(stroke
			(width 0)
			(type solid)
		)
		(fill yes)
		(layer "In11.Cu")
		(net "M_D_CPU1_SB_CB<4>")
	)
	(gr_poly
		(pts
			(xy 86.913466 -245.754906) (xy 86.866476 -245.602506) (xy 86.604856 -245.602506) (xy 86.557866 -245.754906)
			(xy 86.557866 -245.799356) (xy 86.913466 -245.799356)
		)
		(stroke
			(width 0)
			(type solid)
		)
		(fill yes)
		(layer "In11.Cu")
		(net "M_D_CPU1_SB_CB<7>")
	)
	(gr_poly
		(pts
			(xy 86.913466 -240.871502) (xy 86.866476 -240.719102) (xy 86.604856 -240.719102) (xy 86.557866 -240.871502)
			(xy 86.557866 -240.915952) (xy 86.913466 -240.915952)
		)
		(stroke
			(width 0)
			(type solid)
		)
		(fill yes)
		(layer "In11.Cu")
		(net "M_D_CPU1_SB_DQ<2>")
	)
	(gr_poly
		(pts
			(xy 86.913466 -235.988098) (xy 86.866476 -235.835698) (xy 86.604856 -235.835698) (xy 86.557866 -235.988098)
			(xy 86.557866 -236.032548) (xy 86.913466 -236.032548)
		)
		(stroke
			(width 0)
			(type solid)
		)
		(fill yes)
		(layer "In11.Cu")
		(net "M_D_CPU1_SB_DQ<7>")
	)
	(gr_poly
		(pts
			(xy 86.913466 -233.952034) (xy 86.913466 -233.907584) (xy 86.557866 -233.907584) (xy 86.557866 -233.952034)
			(xy 86.604856 -234.104434) (xy 86.866476 -234.104434)
		)
		(stroke
			(width 0)
			(type solid)
		)
		(fill yes)
		(layer "In11.Cu")
		(net "M_D_CPU1_SB_DQ<9>")
	)
	(gr_poly
		(pts
			(xy 86.913466 -232.732834) (xy 86.866476 -232.580434) (xy 86.604856 -232.580434) (xy 86.557866 -232.732834)
			(xy 86.557866 -232.77703) (xy 86.913466 -232.77703)
		)
		(stroke
			(width 0)
			(type solid)
		)
		(fill yes)
		(layer "In11.Cu")
		(net "M_D_CPU1_SB_DQS_DN<1>")
	)
	(gr_poly
		(pts
			(xy 86.913466 -232.323894) (xy 86.913466 -232.279698) (xy 86.557866 -232.279698) (xy 86.557866 -232.323894)
			(xy 86.604856 -232.476294) (xy 86.866476 -232.476294)
		)
		(stroke
			(width 0)
			(type solid)
		)
		(fill yes)
		(layer "In11.Cu")
		(net "M_D_CPU1_SB_DQS_DN<6>")
	)
	(gr_poly
		(pts
			(xy 86.913466 -231.104694) (xy 86.866476 -230.952294) (xy 86.604856 -230.952294) (xy 86.557866 -231.104694)
			(xy 86.557866 -231.149144) (xy 86.913466 -231.149144)
		)
		(stroke
			(width 0)
			(type solid)
		)
		(fill yes)
		(layer "In11.Cu")
		(net "M_D_CPU1_SB_DQ<14>")
	)
	(gr_poly
		(pts
			(xy 86.913466 -224.593658) (xy 86.866476 -224.441258) (xy 86.604856 -224.441258) (xy 86.557866 -224.593658)
			(xy 86.557866 -224.638108) (xy 86.913466 -224.638108)
		)
		(stroke
			(width 0)
			(type solid)
		)
		(fill yes)
		(layer "In11.Cu")
		(net "M_D_CPU1_SB_DQ<30>")
	)
	(gr_poly
		(pts
			(xy 86.913466 -224.185226) (xy 86.913466 -224.140776) (xy 86.557866 -224.140776) (xy 86.557866 -224.185226)
			(xy 86.604856 -224.337626) (xy 86.866476 -224.337626)
		)
		(stroke
			(width 0)
			(type solid)
		)
		(fill yes)
		(layer "In11.Cu")
		(net "M_D_CPU1_SB_DQ<29>")
	)
	(gr_poly
		(pts
			(xy 86.919308 -226.221798) (xy 86.872318 -226.069398) (xy 86.610698 -226.069398) (xy 86.563708 -226.221798)
			(xy 86.563708 -226.265994) (xy 86.919308 -226.265994)
		)
		(stroke
			(width 0)
			(type solid)
		)
		(fill yes)
		(layer "In11.Cu")
		(net "M_D_CPU1_SB_DQS_DN<3>")
	)
	(gr_poly
		(pts
			(xy 86.921848 -249.01017) (xy 86.874858 -248.85777) (xy 86.613238 -248.85777) (xy 86.566248 -249.01017)
			(xy 86.566248 -249.05462) (xy 86.921848 -249.05462)
		)
		(stroke
			(width 0)
			(type solid)
		)
		(fill yes)
		(layer "In11.Cu")
		(net "M_D_CPU1_SB_CA<3>")
	)
	(gr_poly
		(pts
			(xy 86.921848 -245.346474) (xy 86.921848 -245.302278) (xy 86.566248 -245.302278) (xy 86.566248 -245.346474)
			(xy 86.613238 -245.498874) (xy 86.874858 -245.498874)
		)
		(stroke
			(width 0)
			(type solid)
		)
		(fill yes)
		(layer "In11.Cu")
		(net "M_D_CPU1_SB_DQS_DP<9>")
	)
	(gr_poly
		(pts
			(xy 86.921848 -240.46307) (xy 86.921848 -240.418874) (xy 86.566248 -240.418874) (xy 86.566248 -240.46307)
			(xy 86.613238 -240.61547) (xy 86.874858 -240.61547)
		)
		(stroke
			(width 0)
			(type solid)
		)
		(fill yes)
		(layer "In11.Cu")
		(net "M_D_CPU1_SB_DQ<1>")
	)
	(gr_poly
		(pts
			(xy 86.921848 -234.360466) (xy 86.874858 -234.208066) (xy 86.613238 -234.208066) (xy 86.566248 -234.360466)
			(xy 86.566248 -234.404662) (xy 86.921848 -234.404662)
		)
		(stroke
			(width 0)
			(type solid)
		)
		(fill yes)
		(layer "In11.Cu")
		(net "M_D_CPU1_SB_DQ<10>")
	)
	(gr_poly
		(pts
			(xy 86.921848 -230.696262) (xy 86.921848 -230.652066) (xy 86.566248 -230.652066) (xy 86.566248 -230.696262)
			(xy 86.613238 -230.848662) (xy 86.874858 -230.848662)
		)
		(stroke
			(width 0)
			(type solid)
		)
		(fill yes)
		(layer "In11.Cu")
		(net "M_D_CPU1_SB_DQ<13>")
	)
	(gr_poly
		(pts
			(xy 87.014558 -274.876514) (xy 87.014558 -274.832318) (xy 86.658958 -274.832318) (xy 86.658958 -274.876514)
			(xy 86.705948 -275.028914) (xy 86.967568 -275.028914)
		)
		(stroke
			(width 0)
			(type solid)
		)
		(fill yes)
		(layer "In11.Cu")
		(net "M_D_CPU1_SA_DQ<16>")
	)
	(gr_poly
		(pts
			(xy 87.014812 -272.029174) (xy 86.967822 -271.876774) (xy 86.706202 -271.876774) (xy 86.659212 -272.029174)
			(xy 86.659212 -272.073624) (xy 87.014812 -272.073624)
		)
		(stroke
			(width 0)
			(type solid)
		)
		(fill yes)
		(layer "In11.Cu")
		(net "M_D_CPU1_SA_DQS_DP<7>")
	)
	(gr_poly
		(pts
			(xy 87.017352 -273.248882) (xy 87.017352 -273.204432) (xy 86.661752 -273.204432) (xy 86.661752 -273.248882)
			(xy 86.708742 -273.401282) (xy 86.970362 -273.401282)
		)
		(stroke
			(width 0)
			(type solid)
		)
		(fill yes)
		(layer "In11.Cu")
		(net "M_D_CPU1_SA_DQS_DP<2>")
	)
	(gr_poly
		(pts
			(xy 87.023194 -271.620742) (xy 87.023194 -271.576546) (xy 86.667594 -271.576546) (xy 86.667594 -271.620742)
			(xy 86.714584 -271.773142) (xy 86.976204 -271.773142)
		)
		(stroke
			(width 0)
			(type solid)
		)
		(fill yes)
		(layer "In11.Cu")
		(net "M_D_CPU1_SA_DQ<20>")
	)
	(gr_poly
		(pts
			(xy 87.023194 -270.40205) (xy 86.976204 -270.24965) (xy 86.714584 -270.24965) (xy 86.667594 -270.40205)
			(xy 86.667594 -270.446246) (xy 87.023194 -270.446246)
		)
		(stroke
			(width 0)
			(type solid)
		)
		(fill yes)
		(layer "In11.Cu")
		(net "M_D_CPU1_SA_DQ<23>")
	)
	(gr_poly
		(pts
			(xy 87.023194 -269.99311) (xy 87.023194 -269.948914) (xy 86.667594 -269.948914) (xy 86.667594 -269.99311)
			(xy 86.714584 -270.14551) (xy 86.976204 -270.14551)
		)
		(stroke
			(width 0)
			(type solid)
		)
		(fill yes)
		(layer "In11.Cu")
		(net "M_D_CPU1_SA_DQ<24>")
	)
	(gr_poly
		(pts
			(xy 87.023194 -268.77391) (xy 86.976204 -268.62151) (xy 86.714584 -268.62151) (xy 86.667594 -268.77391)
			(xy 86.667594 -268.81836) (xy 87.023194 -268.81836)
		)
		(stroke
			(width 0)
			(type solid)
		)
		(fill yes)
		(layer "In11.Cu")
		(net "M_D_CPU1_SA_DQ<27>")
	)
	(gr_poly
		(pts
			(xy 87.023194 -268.365478) (xy 87.023194 -268.321028) (xy 86.667594 -268.321028) (xy 86.667594 -268.365478)
			(xy 86.714584 -268.517878) (xy 86.976204 -268.517878)
		)
		(stroke
			(width 0)
			(type solid)
		)
		(fill yes)
		(layer "In11.Cu")
		(net "M_D_CPU1_SA_DQS_DP<3>")
	)
	(gr_poly
		(pts
			(xy 87.023194 -267.146278) (xy 86.976204 -266.993878) (xy 86.714584 -266.993878) (xy 86.667594 -267.146278)
			(xy 86.667594 -267.190474) (xy 87.023194 -267.190474)
		)
		(stroke
			(width 0)
			(type solid)
		)
		(fill yes)
		(layer "In11.Cu")
		(net "M_D_CPU1_SA_DQS_DP<8>")
	)
	(gr_poly
		(pts
			(xy 87.023194 -266.737846) (xy 87.023194 -266.693396) (xy 86.667594 -266.693396) (xy 86.667594 -266.737846)
			(xy 86.714584 -266.890246) (xy 86.976204 -266.890246)
		)
		(stroke
			(width 0)
			(type solid)
		)
		(fill yes)
		(layer "In11.Cu")
		(net "M_D_CPU1_SA_DQ<28>")
	)
	(gr_poly
		(pts
			(xy 87.023194 -265.518646) (xy 86.976204 -265.366246) (xy 86.714584 -265.366246) (xy 86.667594 -265.518646)
			(xy 86.667594 -265.562842) (xy 87.023194 -265.562842)
		)
		(stroke
			(width 0)
			(type solid)
		)
		(fill yes)
		(layer "In11.Cu")
		(net "M_D_CPU1_SA_DQ<31>")
	)
	(gr_poly
		(pts
			(xy 87.023194 -265.109706) (xy 87.023194 -265.06551) (xy 86.667594 -265.06551) (xy 86.667594 -265.109706)
			(xy 86.714584 -265.262106) (xy 86.976204 -265.262106)
		)
		(stroke
			(width 0)
			(type solid)
		)
		(fill yes)
		(layer "In11.Cu")
		(net "M_D_CPU1_SA_CB<0>")
	)
	(gr_poly
		(pts
			(xy 87.023194 -263.891014) (xy 86.976204 -263.738614) (xy 86.714584 -263.738614) (xy 86.667594 -263.891014)
			(xy 86.667594 -263.93521) (xy 87.023194 -263.93521)
		)
		(stroke
			(width 0)
			(type solid)
		)
		(fill yes)
		(layer "In11.Cu")
		(net "M_D_CPU1_SA_CB<3>")
	)
	(gr_poly
		(pts
			(xy 87.023194 -263.482074) (xy 87.023194 -263.437878) (xy 86.667594 -263.437878) (xy 86.667594 -263.482074)
			(xy 86.714584 -263.634474) (xy 86.976204 -263.634474)
		)
		(stroke
			(width 0)
			(type solid)
		)
		(fill yes)
		(layer "In11.Cu")
		(net "M_D_CPU1_SA_DQS_DP<4>")
	)
	(gr_poly
		(pts
			(xy 87.023194 -262.262874) (xy 86.976204 -262.110474) (xy 86.714584 -262.110474) (xy 86.667594 -262.262874)
			(xy 86.667594 -262.307324) (xy 87.023194 -262.307324)
		)
		(stroke
			(width 0)
			(type solid)
		)
		(fill yes)
		(layer "In11.Cu")
		(net "M_D_CPU1_SA_DQS_DP<9>")
	)
	(gr_poly
		(pts
			(xy 87.023194 -261.854442) (xy 87.023194 -261.809992) (xy 86.667594 -261.809992) (xy 86.667594 -261.854442)
			(xy 86.714584 -262.006842) (xy 86.976204 -262.006842)
		)
		(stroke
			(width 0)
			(type solid)
		)
		(fill yes)
		(layer "In11.Cu")
		(net "M_D_CPU1_SA_CB<4>")
	)
	(gr_poly
		(pts
			(xy 87.023194 -260.635242) (xy 86.976204 -260.482842) (xy 86.714584 -260.482842) (xy 86.667594 -260.635242)
			(xy 86.667594 -260.679438) (xy 87.023194 -260.679438)
		)
		(stroke
			(width 0)
			(type solid)
		)
		(fill yes)
		(layer "In11.Cu")
		(net "M_D_CPU1_SA_CB<7>")
	)
	(gr_poly
		(pts
			(xy 87.023194 -259.00761) (xy 86.976204 -258.85521) (xy 86.714584 -258.85521) (xy 86.667594 -259.00761)
			(xy 86.667594 -259.051806) (xy 87.023194 -259.051806)
		)
		(stroke
			(width 0)
			(type solid)
		)
		(fill yes)
		(layer "In11.Cu")
		(net "M_D_CPU1_SA_CS_N<0>")
	)
	(gr_poly
		(pts
			(xy 87.023194 -258.59867) (xy 87.023194 -258.554474) (xy 86.667594 -258.554474) (xy 86.667594 -258.59867)
			(xy 86.714584 -258.75107) (xy 86.976204 -258.75107)
		)
		(stroke
			(width 0)
			(type solid)
		)
		(fill yes)
		(layer "In11.Cu")
		(net "M_D_CPU1_SA_CS_N<3>")
	)
	(gr_poly
		(pts
			(xy 87.023194 -257.37947) (xy 86.976204 -257.22707) (xy 86.714584 -257.22707) (xy 86.667594 -257.37947)
			(xy 86.667594 -257.42392) (xy 87.023194 -257.42392)
		)
		(stroke
			(width 0)
			(type solid)
		)
		(fill yes)
		(layer "In11.Cu")
		(net "M_D_CPU1_SA_CA<1>")
	)
	(gr_poly
		(pts
			(xy 87.023194 -256.971038) (xy 87.023194 -256.926588) (xy 86.667594 -256.926588) (xy 86.667594 -256.971038)
			(xy 86.714584 -257.123438) (xy 86.976204 -257.123438)
		)
		(stroke
			(width 0)
			(type solid)
		)
		(fill yes)
		(layer "In11.Cu")
		(net "M_D_CPU1_SA_CA<2>")
	)
	(gr_poly
		(pts
			(xy 87.023194 -255.751838) (xy 86.976204 -255.599438) (xy 86.714584 -255.599438) (xy 86.667594 -255.751838)
			(xy 86.667594 -255.796288) (xy 87.023194 -255.796288)
		)
		(stroke
			(width 0)
			(type solid)
		)
		(fill yes)
		(layer "In11.Cu")
		(net "M_D_CPU1_SA_CA<5>")
	)
	(gr_poly
		(pts
			(xy 87.02929 -273.657314) (xy 86.9823 -273.504914) (xy 86.72068 -273.504914) (xy 86.67369 -273.657314)
			(xy 86.67369 -273.701764) (xy 87.02929 -273.701764)
		)
		(stroke
			(width 0)
			(type solid)
		)
		(fill yes)
		(layer "In11.Cu")
		(net "M_D_CPU1_SA_DQ<19>")
	)
	(gr_poly
		(pts
			(xy 87.234522 -227.286566) (xy 87.272876 -227.264468) (xy 87.095076 -226.95662) (xy 87.056722 -226.978718)
			(xy 86.948264 -227.095558) (xy 87.079074 -227.322126)
		)
		(stroke
			(width 0)
			(type solid)
		)
		(fill yes)
		(layer "In11.Cu")
		(net "M_D_CPU1_SB_DQS_DP<3>")
	)
	(gr_poly
		(pts
			(xy 87.239094 -238.688372) (xy 87.277448 -238.666274) (xy 87.099648 -238.358426) (xy 87.061294 -238.380524)
			(xy 86.952836 -238.497364) (xy 87.083646 -238.723932)
		)
		(stroke
			(width 0)
			(type solid)
		)
		(fill yes)
		(layer "In11.Cu")
		(net "M_D_CPU1_SB_DQS_DN<5>")
	)
	(gr_poly
		(pts
			(xy 87.24011 -241.94643) (xy 87.278464 -241.924332) (xy 87.100664 -241.616484) (xy 87.06231 -241.638582)
			(xy 86.953852 -241.755422) (xy 87.084662 -241.98199)
		)
		(stroke
			(width 0)
			(type solid)
		)
		(fill yes)
		(layer "In11.Cu")
		(net "M_D_CPU1_SB_DQ<0>")
	)
	(gr_poly
		(pts
			(xy 87.241126 -228.925882) (xy 87.27948 -228.903784) (xy 87.10168 -228.595936) (xy 87.063326 -228.618034)
			(xy 86.954868 -228.734874) (xy 87.085678 -228.961442)
		)
		(stroke
			(width 0)
			(type solid)
		)
		(fill yes)
		(layer "In11.Cu")
		(net "M_D_CPU1_SB_DQ<25>")
	)
	(gr_poly
		(pts
			(xy 87.349838 -241.326162) (xy 87.458296 -241.209322) (xy 87.327486 -240.982754) (xy 87.172038 -241.018314)
			(xy 87.133684 -241.040412) (xy 87.311484 -241.34826)
		)
		(stroke
			(width 0)
			(type solid)
		)
		(fill yes)
		(layer "In11.Cu")
		(net "M_D_CPU1_SB_DQ<2>")
	)
	(gr_poly
		(pts
			(xy 87.354156 -238.077756) (xy 87.462614 -237.960916) (xy 87.331804 -237.734348) (xy 87.176356 -237.769908)
			(xy 87.138002 -237.792006) (xy 87.315802 -238.099854)
		)
		(stroke
			(width 0)
			(type solid)
		)
		(fill yes)
		(layer "In11.Cu")
		(net "M_D_CPU1_SB_DQS_DP<5>")
	)
	(gr_poly
		(pts
			(xy 87.355934 -228.31425) (xy 87.464392 -228.19741) (xy 87.333582 -227.970842) (xy 87.178134 -228.006402)
			(xy 87.13978 -228.0285) (xy 87.31758 -228.336348)
		)
		(stroke
			(width 0)
			(type solid)
		)
		(fill yes)
		(layer "In11.Cu")
		(net "M_D_CPU1_SB_DQ<27>")
	)
	(gr_poly
		(pts
			(xy 87.355934 -226.686364) (xy 87.464392 -226.569524) (xy 87.333582 -226.342956) (xy 87.178134 -226.378516)
			(xy 87.13978 -226.400614) (xy 87.31758 -226.708462)
		)
		(stroke
			(width 0)
			(type solid)
		)
		(fill yes)
		(layer "In11.Cu")
		(net "M_D_CPU1_SB_DQS_DN<3>")
	)
	(gr_poly
		(pts
			(xy 87.37473 -249.416062) (xy 87.37473 -249.371612) (xy 87.01913 -249.371612) (xy 87.01913 -249.416062)
			(xy 87.06612 -249.568462) (xy 87.32774 -249.568462)
		)
		(stroke
			(width 0)
			(type solid)
		)
		(fill yes)
		(layer "In11.Cu")
		(net "M_D_CPU1_SB_CA<2>")
	)
	(gr_poly
		(pts
			(xy 87.37473 -244.940582) (xy 87.32774 -244.788182) (xy 87.06612 -244.788182) (xy 87.01913 -244.940582)
			(xy 87.01913 -244.985032) (xy 87.37473 -244.985032)
		)
		(stroke
			(width 0)
			(type solid)
		)
		(fill yes)
		(layer "In11.Cu")
		(net "M_D_CPU1_SB_DQS_DN<9>")
	)
	(gr_poly
		(pts
			(xy 87.37473 -240.057178) (xy 87.32774 -239.904778) (xy 87.06612 -239.904778) (xy 87.01913 -240.057178)
			(xy 87.01913 -240.101628) (xy 87.37473 -240.101628)
		)
		(stroke
			(width 0)
			(type solid)
		)
		(fill yes)
		(layer "In11.Cu")
		(net "M_D_CPU1_SB_DQ<3>")
	)
	(gr_poly
		(pts
			(xy 87.37473 -239.649254) (xy 87.37473 -239.604804) (xy 87.01913 -239.604804) (xy 87.01913 -239.649254)
			(xy 87.06612 -239.801654) (xy 87.32774 -239.801654)
		)
		(stroke
			(width 0)
			(type solid)
		)
		(fill yes)
		(layer "In11.Cu")
		(net "M_D_CPU1_SB_DQS_DP<0>")
	)
	(gr_poly
		(pts
			(xy 87.37473 -234.76585) (xy 87.37473 -234.721654) (xy 87.01913 -234.721654) (xy 87.01913 -234.76585)
			(xy 87.06612 -234.91825) (xy 87.32774 -234.91825)
		)
		(stroke
			(width 0)
			(type solid)
		)
		(fill yes)
		(layer "In11.Cu")
		(net "M_D_CPU1_SB_DQ<8>")
	)
	(gr_poly
		(pts
			(xy 87.37473 -230.290878) (xy 87.32774 -230.138478) (xy 87.06612 -230.138478) (xy 87.01913 -230.290878)
			(xy 87.01913 -230.335074) (xy 87.37473 -230.335074)
		)
		(stroke
			(width 0)
			(type solid)
		)
		(fill yes)
		(layer "In11.Cu")
		(net "M_D_CPU1_SB_DQ<15>")
	)
	(gr_poly
		(pts
			(xy 87.383112 -244.53215) (xy 87.383112 -244.487954) (xy 87.027512 -244.487954) (xy 87.027512 -244.53215)
			(xy 87.074502 -244.68455) (xy 87.336122 -244.68455)
		)
		(stroke
			(width 0)
			(type solid)
		)
		(fill yes)
		(layer "In11.Cu")
		(net "M_D_CPU1_SB_DQS_DN<4>")
	)
	(gr_poly
		(pts
			(xy 87.383112 -229.882446) (xy 87.383112 -229.83825) (xy 87.027512 -229.83825) (xy 87.027512 -229.882446)
			(xy 87.074502 -230.034846) (xy 87.336122 -230.034846)
		)
		(stroke
			(width 0)
			(type solid)
		)
		(fill yes)
		(layer "In11.Cu")
		(net "M_D_CPU1_SB_DQ<24>")
	)
	(gr_poly
		(pts
			(xy 87.383366 -248.196354) (xy 87.336376 -248.043954) (xy 87.074756 -248.043954) (xy 87.027766 -248.196354)
			(xy 87.027766 -248.240804) (xy 87.383366 -248.240804)
		)
		(stroke
			(width 0)
			(type solid)
		)
		(fill yes)
		(layer "In11.Cu")
		(net "M_D_CPU1_SB_CA<5>")
	)
	(gr_poly
		(pts
			(xy 87.383366 -247.787922) (xy 87.383366 -247.743472) (xy 87.027766 -247.743472) (xy 87.027766 -247.787922)
			(xy 87.074756 -247.940322) (xy 87.336376 -247.940322)
		)
		(stroke
			(width 0)
			(type solid)
		)
		(fill yes)
		(layer "In11.Cu")
		(net "M_D_CPU1_SB_PAR")
	)
	(gr_poly
		(pts
			(xy 87.383366 -246.568722) (xy 87.336376 -246.416322) (xy 87.074756 -246.416322) (xy 87.027766 -246.568722)
			(xy 87.027766 -246.613172) (xy 87.383366 -246.613172)
		)
		(stroke
			(width 0)
			(type solid)
		)
		(fill yes)
		(layer "In11.Cu")
		(net "M_D_CPU1_SB_CB<6>")
	)
	(gr_poly
		(pts
			(xy 87.383366 -246.16029) (xy 87.383366 -246.11584) (xy 87.027766 -246.11584) (xy 87.027766 -246.16029)
			(xy 87.074756 -246.31269) (xy 87.336376 -246.31269)
		)
		(stroke
			(width 0)
			(type solid)
		)
		(fill yes)
		(layer "In11.Cu")
		(net "M_D_CPU1_SB_CB<5>")
	)
	(gr_poly
		(pts
			(xy 87.383366 -236.393482) (xy 87.383366 -236.349286) (xy 87.027766 -236.349286) (xy 87.027766 -236.393482)
			(xy 87.074756 -236.545882) (xy 87.336376 -236.545882)
		)
		(stroke
			(width 0)
			(type solid)
		)
		(fill yes)
		(layer "In11.Cu")
		(net "M_D_CPU1_SB_DQ<5>")
	)
	(gr_poly
		(pts
			(xy 87.383366 -233.54665) (xy 87.336376 -233.39425) (xy 87.074756 -233.39425) (xy 87.027766 -233.54665)
			(xy 87.027766 -233.590846) (xy 87.383366 -233.590846)
		)
		(stroke
			(width 0)
			(type solid)
		)
		(fill yes)
		(layer "In11.Cu")
		(net "M_D_CPU1_SB_DQ<11>")
	)
	(gr_poly
		(pts
			(xy 87.383366 -233.13771) (xy 87.383366 -233.093514) (xy 87.027766 -233.093514) (xy 87.027766 -233.13771)
			(xy 87.074756 -233.29011) (xy 87.336376 -233.29011)
		)
		(stroke
			(width 0)
			(type solid)
		)
		(fill yes)
		(layer "In11.Cu")
		(net "M_D_CPU1_SB_DQS_DP<1>")
	)
	(gr_poly
		(pts
			(xy 87.383366 -231.919018) (xy 87.336376 -231.766618) (xy 87.074756 -231.766618) (xy 87.027766 -231.919018)
			(xy 87.027766 -231.963214) (xy 87.383366 -231.963214)
		)
		(stroke
			(width 0)
			(type solid)
		)
		(fill yes)
		(layer "In11.Cu")
		(net "M_D_CPU1_SB_DQS_DP<6>")
	)
	(gr_poly
		(pts
			(xy 87.383366 -231.510078) (xy 87.383366 -231.465882) (xy 87.027766 -231.465882) (xy 87.027766 -231.510078)
			(xy 87.074756 -231.662478) (xy 87.336376 -231.662478)
		)
		(stroke
			(width 0)
			(type solid)
		)
		(fill yes)
		(layer "In11.Cu")
		(net "M_D_CPU1_SB_DQ<12>")
	)
	(gr_poly
		(pts
			(xy 87.383366 -224.999042) (xy 87.383366 -224.954592) (xy 87.027766 -224.954592) (xy 87.027766 -224.999042)
			(xy 87.074756 -225.151442) (xy 87.336376 -225.151442)
		)
		(stroke
			(width 0)
			(type solid)
		)
		(fill yes)
		(layer "In11.Cu")
		(net "M_D_CPU1_SB_DQ<28>")
	)
	(gr_poly
		(pts
			(xy 87.383366 -223.779842) (xy 87.336376 -223.627442) (xy 87.074756 -223.627442) (xy 87.027766 -223.779842)
			(xy 87.027766 -223.824292) (xy 87.383366 -223.824292)
		)
		(stroke
			(width 0)
			(type solid)
		)
		(fill yes)
		(layer "In11.Cu")
		(net "M_D_CPU1_SB_DQ<31>")
	)
	(gr_poly
		(pts
			(xy 87.391748 -243.31295) (xy 87.344758 -243.16055) (xy 87.083138 -243.16055) (xy 87.036148 -243.31295)
			(xy 87.036148 -243.3574) (xy 87.391748 -243.3574)
		)
		(stroke
			(width 0)
			(type solid)
		)
		(fill yes)
		(layer "In11.Cu")
		(net "M_D_CPU1_SB_CB<2>")
	)
	(gr_poly
		(pts
			(xy 87.391748 -242.905026) (xy 87.391748 -242.860576) (xy 87.036148 -242.860576) (xy 87.036148 -242.905026)
			(xy 87.083138 -243.057426) (xy 87.344758 -243.057426)
		)
		(stroke
			(width 0)
			(type solid)
		)
		(fill yes)
		(layer "In11.Cu")
		(net "M_D_CPU1_SB_CB<1>")
	)
	(gr_poly
		(pts
			(xy 87.391748 -236.801914) (xy 87.344758 -236.649514) (xy 87.083138 -236.649514) (xy 87.036148 -236.801914)
			(xy 87.036148 -236.846364) (xy 87.391748 -236.846364)
		)
		(stroke
			(width 0)
			(type solid)
		)
		(fill yes)
		(layer "In11.Cu")
		(net "M_D_CPU1_SB_DQ<6>")
	)
	(gr_poly
		(pts
			(xy 87.391748 -225.407474) (xy 87.344758 -225.255074) (xy 87.083138 -225.255074) (xy 87.036148 -225.407474)
			(xy 87.036148 -225.45167) (xy 87.391748 -225.45167)
		)
		(stroke
			(width 0)
			(type solid)
		)
		(fill yes)
		(layer "In11.Cu")
		(net "M_D_CPU1_SB_DQS_DP<8>")
	)
	(gr_poly
		(pts
			(xy 87.493094 -274.062698) (xy 87.493094 -274.018248) (xy 87.137494 -274.018248) (xy 87.137494 -274.062698)
			(xy 87.184484 -274.215098) (xy 87.446104 -274.215098)
		)
		(stroke
			(width 0)
			(type solid)
		)
		(fill yes)
		(layer "In11.Cu")
		(net "M_D_CPU1_SA_DQ<17>")
	)
	(gr_poly
		(pts
			(xy 87.493094 -271.215866) (xy 87.446104 -271.063466) (xy 87.184484 -271.063466) (xy 87.137494 -271.215866)
			(xy 87.137494 -271.260062) (xy 87.493094 -271.260062)
		)
		(stroke
			(width 0)
			(type solid)
		)
		(fill yes)
		(layer "In11.Cu")
		(net "M_D_CPU1_SA_DQ<22>")
	)
	(gr_poly
		(pts
			(xy 87.493094 -270.806926) (xy 87.493094 -270.76273) (xy 87.137494 -270.76273) (xy 87.137494 -270.806926)
			(xy 87.184484 -270.959326) (xy 87.446104 -270.959326)
		)
		(stroke
			(width 0)
			(type solid)
		)
		(fill yes)
		(layer "In11.Cu")
		(net "M_D_CPU1_SA_DQ<21>")
	)
	(gr_poly
		(pts
			(xy 87.493094 -269.587726) (xy 87.446104 -269.435326) (xy 87.184484 -269.435326) (xy 87.137494 -269.587726)
			(xy 87.137494 -269.632176) (xy 87.493094 -269.632176)
		)
		(stroke
			(width 0)
			(type solid)
		)
		(fill yes)
		(layer "In11.Cu")
		(net "M_D_CPU1_SA_DQ<26>")
	)
	(gr_poly
		(pts
			(xy 87.493094 -269.179294) (xy 87.493094 -269.134844) (xy 87.137494 -269.134844) (xy 87.137494 -269.179294)
			(xy 87.184484 -269.331694) (xy 87.446104 -269.331694)
		)
		(stroke
			(width 0)
			(type solid)
		)
		(fill yes)
		(layer "In11.Cu")
		(net "M_D_CPU1_SA_DQ<25>")
	)
	(gr_poly
		(pts
			(xy 87.493094 -267.960094) (xy 87.446104 -267.807694) (xy 87.184484 -267.807694) (xy 87.137494 -267.960094)
			(xy 87.137494 -268.004544) (xy 87.493094 -268.004544)
		)
		(stroke
			(width 0)
			(type solid)
		)
		(fill yes)
		(layer "In11.Cu")
		(net "M_D_CPU1_SA_DQS_DN<3>")
	)
	(gr_poly
		(pts
			(xy 87.493094 -267.551662) (xy 87.493094 -267.507212) (xy 87.137494 -267.507212) (xy 87.137494 -267.551662)
			(xy 87.184484 -267.704062) (xy 87.446104 -267.704062)
		)
		(stroke
			(width 0)
			(type solid)
		)
		(fill yes)
		(layer "In11.Cu")
		(net "M_D_CPU1_SA_DQS_DN<8>")
	)
	(gr_poly
		(pts
			(xy 87.493094 -266.332462) (xy 87.446104 -266.180062) (xy 87.184484 -266.180062) (xy 87.137494 -266.332462)
			(xy 87.137494 -266.376658) (xy 87.493094 -266.376658)
		)
		(stroke
			(width 0)
			(type solid)
		)
		(fill yes)
		(layer "In11.Cu")
		(net "M_D_CPU1_SA_DQ<30>")
	)
	(gr_poly
		(pts
			(xy 87.493094 -265.92403) (xy 87.493094 -265.87958) (xy 87.137494 -265.87958) (xy 87.137494 -265.92403)
			(xy 87.184484 -266.07643) (xy 87.446104 -266.07643)
		)
		(stroke
			(width 0)
			(type solid)
		)
		(fill yes)
		(layer "In11.Cu")
		(net "M_D_CPU1_SA_DQ<29>")
	)
	(gr_poly
		(pts
			(xy 87.493094 -264.70483) (xy 87.446104 -264.55243) (xy 87.184484 -264.55243) (xy 87.137494 -264.70483)
			(xy 87.137494 -264.749026) (xy 87.493094 -264.749026)
		)
		(stroke
			(width 0)
			(type solid)
		)
		(fill yes)
		(layer "In11.Cu")
		(net "M_D_CPU1_SA_CB<2>")
	)
	(gr_poly
		(pts
			(xy 87.493094 -264.29589) (xy 87.493094 -264.251694) (xy 87.137494 -264.251694) (xy 87.137494 -264.29589)
			(xy 87.184484 -264.44829) (xy 87.446104 -264.44829)
		)
		(stroke
			(width 0)
			(type solid)
		)
		(fill yes)
		(layer "In11.Cu")
		(net "M_D_CPU1_SA_CB<1>")
	)
	(gr_poly
		(pts
			(xy 87.493094 -263.07669) (xy 87.446104 -262.92429) (xy 87.184484 -262.92429) (xy 87.137494 -263.07669)
			(xy 87.137494 -263.12114) (xy 87.493094 -263.12114)
		)
		(stroke
			(width 0)
			(type solid)
		)
		(fill yes)
		(layer "In11.Cu")
		(net "M_D_CPU1_SA_DQS_DN<4>")
	)
	(gr_poly
		(pts
			(xy 87.493094 -262.668258) (xy 87.493094 -262.623808) (xy 87.137494 -262.623808) (xy 87.137494 -262.668258)
			(xy 87.184484 -262.820658) (xy 87.446104 -262.820658)
		)
		(stroke
			(width 0)
			(type solid)
		)
		(fill yes)
		(layer "In11.Cu")
		(net "M_D_CPU1_SA_DQS_DN<9>")
	)
	(gr_poly
		(pts
			(xy 87.493094 -261.449058) (xy 87.446104 -261.296658) (xy 87.184484 -261.296658) (xy 87.137494 -261.449058)
			(xy 87.137494 -261.493508) (xy 87.493094 -261.493508)
		)
		(stroke
			(width 0)
			(type solid)
		)
		(fill yes)
		(layer "In11.Cu")
		(net "M_D_CPU1_SA_CB<6>")
	)
	(gr_poly
		(pts
			(xy 87.493094 -261.040626) (xy 87.493094 -260.996176) (xy 87.137494 -260.996176) (xy 87.137494 -261.040626)
			(xy 87.184484 -261.193026) (xy 87.446104 -261.193026)
		)
		(stroke
			(width 0)
			(type solid)
		)
		(fill yes)
		(layer "In11.Cu")
		(net "M_D_CPU1_SA_CB<5>")
	)
	(gr_poly
		(pts
			(xy 87.493094 -259.412486) (xy 87.493094 -259.36829) (xy 87.137494 -259.36829) (xy 87.137494 -259.412486)
			(xy 87.184484 -259.564886) (xy 87.446104 -259.564886)
		)
		(stroke
			(width 0)
			(type solid)
		)
		(fill yes)
		(layer "In11.Cu")
		(net "M_D_CPU1_SA_CS_N<2>")
	)
	(gr_poly
		(pts
			(xy 87.493094 -258.193286) (xy 87.446104 -258.040886) (xy 87.184484 -258.040886) (xy 87.137494 -258.193286)
			(xy 87.137494 -258.237736) (xy 87.493094 -258.237736)
		)
		(stroke
			(width 0)
			(type solid)
		)
		(fill yes)
		(layer "In11.Cu")
		(net "M_D_CPU1_SA_CS_N<1>")
	)
	(gr_poly
		(pts
			(xy 87.493094 -257.784854) (xy 87.493094 -257.740404) (xy 87.137494 -257.740404) (xy 87.137494 -257.784854)
			(xy 87.184484 -257.937254) (xy 87.446104 -257.937254)
		)
		(stroke
			(width 0)
			(type solid)
		)
		(fill yes)
		(layer "In11.Cu")
		(net "M_D_CPU1_SA_CA<0>")
	)
	(gr_poly
		(pts
			(xy 87.493094 -256.565654) (xy 87.446104 -256.413254) (xy 87.184484 -256.413254) (xy 87.137494 -256.565654)
			(xy 87.137494 -256.610104) (xy 87.493094 -256.610104)
		)
		(stroke
			(width 0)
			(type solid)
		)
		(fill yes)
		(layer "In11.Cu")
		(net "M_D_CPU1_SA_CA<3>")
	)
	(gr_poly
		(pts
			(xy 87.493094 -256.157222) (xy 87.493094 -256.112772) (xy 87.137494 -256.112772) (xy 87.137494 -256.157222)
			(xy 87.184484 -256.309622) (xy 87.446104 -256.309622)
		)
		(stroke
			(width 0)
			(type solid)
		)
		(fill yes)
		(layer "In11.Cu")
		(net "M_D_CPU1_SA_CA<4>")
	)
	(gr_poly
		(pts
			(xy 87.49919 -272.843498) (xy 87.4522 -272.691098) (xy 87.19058 -272.691098) (xy 87.14359 -272.843498)
			(xy 87.14359 -272.887948) (xy 87.49919 -272.887948)
		)
		(stroke
			(width 0)
			(type solid)
		)
		(fill yes)
		(layer "In11.Cu")
		(net "M_D_CPU1_SA_DQS_DN<2>")
	)
	(gr_poly
		(pts
			(xy 87.49919 -272.435066) (xy 87.49919 -272.390616) (xy 87.14359 -272.390616) (xy 87.14359 -272.435066)
			(xy 87.19058 -272.587466) (xy 87.4522 -272.587466)
		)
		(stroke
			(width 0)
			(type solid)
		)
		(fill yes)
		(layer "In11.Cu")
		(net "M_D_CPU1_SA_DQS_DN<7>")
	)
	(gr_poly
		(pts
			(xy 87.501476 -274.47113) (xy 87.454486 -274.31873) (xy 87.192866 -274.31873) (xy 87.145876 -274.47113)
			(xy 87.145876 -274.515326) (xy 87.501476 -274.515326)
		)
		(stroke
			(width 0)
			(type solid)
		)
		(fill yes)
		(layer "In11.Cu")
		(net "M_D_CPU1_SA_DQ<18>")
	)
	(gr_poly
		(pts
			(xy 87.702644 -226.469956) (xy 87.740998 -226.447858) (xy 87.563198 -226.14001) (xy 87.524844 -226.162108)
			(xy 87.416386 -226.278948) (xy 87.547196 -226.505516)
		)
		(stroke
			(width 0)
			(type solid)
		)
		(fill yes)
		(layer "In11.Cu")
		(net "M_D_CPU1_SB_DQS_DN<8>")
	)
	(gr_poly
		(pts
			(xy 87.708232 -237.87354) (xy 87.746586 -237.851442) (xy 87.568786 -237.543594) (xy 87.530432 -237.565692)
			(xy 87.421974 -237.682532) (xy 87.552784 -237.9091)
		)
		(stroke
			(width 0)
			(type solid)
		)
		(fill yes)
		(layer "In11.Cu")
		(net "M_D_CPU1_SB_DQ<4>")
	)
	(gr_poly
		(pts
			(xy 87.708232 -228.106986) (xy 87.746586 -228.084888) (xy 87.568786 -227.77704) (xy 87.530432 -227.799138)
			(xy 87.421974 -227.915978) (xy 87.552784 -228.142546)
		)
		(stroke
			(width 0)
			(type solid)
		)
		(fill yes)
		(layer "In11.Cu")
		(net "M_D_CPU1_SB_DQS_DP<3>")
	)
	(gr_poly
		(pts
			(xy 87.708994 -241.130074) (xy 87.747348 -241.107976) (xy 87.569548 -240.800128) (xy 87.531194 -240.822226)
			(xy 87.422736 -240.939066) (xy 87.553546 -241.165634)
		)
		(stroke
			(width 0)
			(type solid)
		)
		(fill yes)
		(layer "In11.Cu")
		(net "M_D_CPU1_SB_DQ<1>")
	)
	(gr_poly
		(pts
			(xy 87.818722 -240.510314) (xy 87.92718 -240.393474) (xy 87.79637 -240.166906) (xy 87.640922 -240.202466)
			(xy 87.602568 -240.224564) (xy 87.780368 -240.532412)
		)
		(stroke
			(width 0)
			(type solid)
		)
		(fill yes)
		(layer "In11.Cu")
		(net "M_D_CPU1_SB_DQ<3>")
	)
	(gr_poly
		(pts
			(xy 87.818722 -225.860356) (xy 87.92718 -225.743516) (xy 87.79637 -225.516948) (xy 87.640922 -225.552508)
			(xy 87.602568 -225.574606) (xy 87.780368 -225.882454)
		)
		(stroke
			(width 0)
			(type solid)
		)
		(fill yes)
		(layer "In11.Cu")
		(net "M_D_CPU1_SB_DQS_DP<8>")
	)
	(gr_poly
		(pts
			(xy 87.824056 -237.26394) (xy 87.932514 -237.1471) (xy 87.801704 -236.920532) (xy 87.646256 -236.956092)
			(xy 87.607902 -236.97819) (xy 87.785702 -237.286038)
		)
		(stroke
			(width 0)
			(type solid)
		)
		(fill yes)
		(layer "In11.Cu")
		(net "M_D_CPU1_SB_DQ<6>")
	)
	(gr_poly
		(pts
			(xy 87.824056 -227.497386) (xy 87.932514 -227.380546) (xy 87.801704 -227.153978) (xy 87.646256 -227.189538)
			(xy 87.607902 -227.211636) (xy 87.785702 -227.519484)
		)
		(stroke
			(width 0)
			(type solid)
		)
		(fill yes)
		(layer "In11.Cu")
		(net "M_D_CPU1_SB_DQS_DN<3>")
	)
	(gr_poly
		(pts
			(xy 87.84717 -243.718842) (xy 87.84717 -243.674392) (xy 87.49157 -243.674392) (xy 87.49157 -243.718842)
			(xy 87.53856 -243.871242) (xy 87.80018 -243.871242)
		)
		(stroke
			(width 0)
			(type solid)
		)
		(fill yes)
		(layer "In11.Cu")
		(net "M_D_CPU1_SB_CB<0>")
	)
	(gr_poly
		(pts
			(xy 87.84717 -229.477062) (xy 87.80018 -229.324662) (xy 87.53856 -229.324662) (xy 87.49157 -229.477062)
			(xy 87.49157 -229.521258) (xy 87.84717 -229.521258)
		)
		(stroke
			(width 0)
			(type solid)
		)
		(fill yes)
		(layer "In11.Cu")
		(net "M_D_CPU1_SB_DQ<26>")
	)
	(gr_poly
		(pts
			(xy 87.853266 -248.601738) (xy 87.853266 -248.557542) (xy 87.497666 -248.557542) (xy 87.497666 -248.601738)
			(xy 87.544656 -248.754138) (xy 87.806276 -248.754138)
		)
		(stroke
			(width 0)
			(type solid)
		)
		(fill yes)
		(layer "In11.Cu")
		(net "M_D_CPU1_SB_CA<4>")
	)
	(gr_poly
		(pts
			(xy 87.853266 -247.382538) (xy 87.806276 -247.230138) (xy 87.544656 -247.230138) (xy 87.497666 -247.382538)
			(xy 87.497666 -247.426988) (xy 87.853266 -247.426988)
		)
		(stroke
			(width 0)
			(type solid)
		)
		(fill yes)
		(layer "In11.Cu")
		(net "M_D_CPU1_SB_CA<6>")
	)
	(gr_poly
		(pts
			(xy 87.853266 -246.974106) (xy 87.853266 -246.929656) (xy 87.497666 -246.929656) (xy 87.497666 -246.974106)
			(xy 87.544656 -247.126506) (xy 87.806276 -247.126506)
		)
		(stroke
			(width 0)
			(type solid)
		)
		(fill yes)
		(layer "In11.Cu")
		(net "M_D_CPU1_SB_CB<4>")
	)
	(gr_poly
		(pts
			(xy 87.853266 -245.754906) (xy 87.806276 -245.602506) (xy 87.544656 -245.602506) (xy 87.497666 -245.754906)
			(xy 87.497666 -245.799356) (xy 87.853266 -245.799356)
		)
		(stroke
			(width 0)
			(type solid)
		)
		(fill yes)
		(layer "In11.Cu")
		(net "M_D_CPU1_SB_CB<7>")
	)
	(gr_poly
		(pts
			(xy 87.853266 -242.499134) (xy 87.806276 -242.346734) (xy 87.544656 -242.346734) (xy 87.497666 -242.499134)
			(xy 87.497666 -242.54333) (xy 87.853266 -242.54333)
		)
		(stroke
			(width 0)
			(type solid)
		)
		(fill yes)
		(layer "In11.Cu")
		(net "M_D_CPU1_SB_CB<3>")
	)
	(gr_poly
		(pts
			(xy 87.853266 -242.090702) (xy 87.853266 -242.046506) (xy 87.497666 -242.046506) (xy 87.497666 -242.090702)
			(xy 87.544656 -242.243102) (xy 87.806276 -242.243102)
		)
		(stroke
			(width 0)
			(type solid)
		)
		(fill yes)
		(layer "In11.Cu")
		(net "M_D_CPU1_SB_DQ<0>")
	)
	(gr_poly
		(pts
			(xy 87.853266 -238.83493) (xy 87.853266 -238.790734) (xy 87.497666 -238.790734) (xy 87.497666 -238.83493)
			(xy 87.544656 -238.98733) (xy 87.806276 -238.98733)
		)
		(stroke
			(width 0)
			(type solid)
		)
		(fill yes)
		(layer "In11.Cu")
		(net "M_D_CPU1_SB_DQS_DN<5>")
	)
	(gr_poly
		(pts
			(xy 87.853266 -235.988098) (xy 87.806276 -235.835698) (xy 87.544656 -235.835698) (xy 87.497666 -235.988098)
			(xy 87.497666 -236.032548) (xy 87.853266 -236.032548)
		)
		(stroke
			(width 0)
			(type solid)
		)
		(fill yes)
		(layer "In11.Cu")
		(net "M_D_CPU1_SB_DQ<7>")
	)
	(gr_poly
		(pts
			(xy 87.853266 -233.952034) (xy 87.853266 -233.907584) (xy 87.497666 -233.907584) (xy 87.497666 -233.952034)
			(xy 87.544656 -234.104434) (xy 87.806276 -234.104434)
		)
		(stroke
			(width 0)
			(type solid)
		)
		(fill yes)
		(layer "In11.Cu")
		(net "M_D_CPU1_SB_DQ<9>")
	)
	(gr_poly
		(pts
			(xy 87.853266 -232.732834) (xy 87.806276 -232.580434) (xy 87.544656 -232.580434) (xy 87.497666 -232.732834)
			(xy 87.497666 -232.77703) (xy 87.853266 -232.77703)
		)
		(stroke
			(width 0)
			(type solid)
		)
		(fill yes)
		(layer "In11.Cu")
		(net "M_D_CPU1_SB_DQS_DN<1>")
	)
	(gr_poly
		(pts
			(xy 87.853266 -232.323894) (xy 87.853266 -232.279698) (xy 87.497666 -232.279698) (xy 87.497666 -232.323894)
			(xy 87.544656 -232.476294) (xy 87.806276 -232.476294)
		)
		(stroke
			(width 0)
			(type solid)
		)
		(fill yes)
		(layer "In11.Cu")
		(net "M_D_CPU1_SB_DQS_DN<6>")
	)
	(gr_poly
		(pts
			(xy 87.853266 -231.104694) (xy 87.806276 -230.952294) (xy 87.544656 -230.952294) (xy 87.497666 -231.104694)
			(xy 87.497666 -231.149144) (xy 87.853266 -231.149144)
		)
		(stroke
			(width 0)
			(type solid)
		)
		(fill yes)
		(layer "In11.Cu")
		(net "M_D_CPU1_SB_DQ<14>")
	)
	(gr_poly
		(pts
			(xy 87.853266 -229.06863) (xy 87.853266 -229.02418) (xy 87.497666 -229.02418) (xy 87.497666 -229.06863)
			(xy 87.544656 -229.22103) (xy 87.806276 -229.22103)
		)
		(stroke
			(width 0)
			(type solid)
		)
		(fill yes)
		(layer "In11.Cu")
		(net "M_D_CPU1_SB_DQ<25>")
	)
	(gr_poly
		(pts
			(xy 87.853266 -224.593658) (xy 87.806276 -224.441258) (xy 87.544656 -224.441258) (xy 87.497666 -224.593658)
			(xy 87.497666 -224.638108) (xy 87.853266 -224.638108)
		)
		(stroke
			(width 0)
			(type solid)
		)
		(fill yes)
		(layer "In11.Cu")
		(net "M_D_CPU1_SB_DQ<30>")
	)
	(gr_poly
		(pts
			(xy 87.853266 -224.185226) (xy 87.853266 -224.140776) (xy 87.497666 -224.140776) (xy 87.497666 -224.185226)
			(xy 87.544656 -224.337626) (xy 87.806276 -224.337626)
		)
		(stroke
			(width 0)
			(type solid)
		)
		(fill yes)
		(layer "In11.Cu")
		(net "M_D_CPU1_SB_DQ<29>")
	)
	(gr_poly
		(pts
			(xy 87.859108 -244.126766) (xy 87.812118 -243.974366) (xy 87.550498 -243.974366) (xy 87.503508 -244.126766)
			(xy 87.503508 -244.171216) (xy 87.859108 -244.171216)
		)
		(stroke
			(width 0)
			(type solid)
		)
		(fill yes)
		(layer "In11.Cu")
		(net "M_D_CPU1_SB_DQS_DP<4>")
	)
	(gr_poly
		(pts
			(xy 87.861648 -249.01017) (xy 87.814658 -248.85777) (xy 87.553038 -248.85777) (xy 87.506048 -249.01017)
			(xy 87.506048 -249.05462) (xy 87.861648 -249.05462)
		)
		(stroke
			(width 0)
			(type solid)
		)
		(fill yes)
		(layer "In11.Cu")
		(net "M_D_CPU1_SB_CA<3>")
	)
	(gr_poly
		(pts
			(xy 87.861648 -245.346474) (xy 87.861648 -245.302278) (xy 87.506048 -245.302278) (xy 87.506048 -245.346474)
			(xy 87.553038 -245.498874) (xy 87.814658 -245.498874)
		)
		(stroke
			(width 0)
			(type solid)
		)
		(fill yes)
		(layer "In11.Cu")
		(net "M_D_CPU1_SB_DQS_DP<9>")
	)
	(gr_poly
		(pts
			(xy 87.861648 -239.243362) (xy 87.814658 -239.090962) (xy 87.553038 -239.090962) (xy 87.506048 -239.243362)
			(xy 87.506048 -239.287812) (xy 87.861648 -239.287812)
		)
		(stroke
			(width 0)
			(type solid)
		)
		(fill yes)
		(layer "In11.Cu")
		(net "M_D_CPU1_SB_DQS_DN<0>")
	)
	(gr_poly
		(pts
			(xy 87.861648 -234.360466) (xy 87.814658 -234.208066) (xy 87.553038 -234.208066) (xy 87.506048 -234.360466)
			(xy 87.506048 -234.404662) (xy 87.861648 -234.404662)
		)
		(stroke
			(width 0)
			(type solid)
		)
		(fill yes)
		(layer "In11.Cu")
		(net "M_D_CPU1_SB_DQ<10>")
	)
	(gr_poly
		(pts
			(xy 87.861648 -230.696262) (xy 87.861648 -230.652066) (xy 87.506048 -230.652066) (xy 87.506048 -230.696262)
			(xy 87.553038 -230.848662) (xy 87.814658 -230.848662)
		)
		(stroke
			(width 0)
			(type solid)
		)
		(fill yes)
		(layer "In11.Cu")
		(net "M_D_CPU1_SB_DQ<13>")
	)
	(gr_poly
		(pts
			(xy 87.956898 -274.876514) (xy 87.956898 -274.832318) (xy 87.601298 -274.832318) (xy 87.601298 -274.876514)
			(xy 87.648288 -275.028914) (xy 87.909908 -275.028914)
		)
		(stroke
			(width 0)
			(type solid)
		)
		(fill yes)
		(layer "In11.Cu")
		(net "M_D_CPU1_SA_DQ<16>")
	)
	(gr_poly
		(pts
			(xy 87.962994 -273.657314) (xy 87.916004 -273.504914) (xy 87.654384 -273.504914) (xy 87.607394 -273.657314)
			(xy 87.607394 -273.701764) (xy 87.962994 -273.701764)
		)
		(stroke
			(width 0)
			(type solid)
		)
		(fill yes)
		(layer "In11.Cu")
		(net "M_D_CPU1_SA_DQ<19>")
	)
	(gr_poly
		(pts
			(xy 87.962994 -273.248882) (xy 87.962994 -273.204432) (xy 87.607394 -273.204432) (xy 87.607394 -273.248882)
			(xy 87.654384 -273.401282) (xy 87.916004 -273.401282)
		)
		(stroke
			(width 0)
			(type solid)
		)
		(fill yes)
		(layer "In11.Cu")
		(net "M_D_CPU1_SA_DQS_DP<2>")
	)
	(gr_poly
		(pts
			(xy 87.962994 -272.029682) (xy 87.916004 -271.877282) (xy 87.654384 -271.877282) (xy 87.607394 -272.029682)
			(xy 87.607394 -272.073878) (xy 87.962994 -272.073878)
		)
		(stroke
			(width 0)
			(type solid)
		)
		(fill yes)
		(layer "In11.Cu")
		(net "M_D_CPU1_SA_DQS_DP<7>")
	)
	(gr_poly
		(pts
			(xy 87.962994 -271.620742) (xy 87.962994 -271.576546) (xy 87.607394 -271.576546) (xy 87.607394 -271.620742)
			(xy 87.654384 -271.773142) (xy 87.916004 -271.773142)
		)
		(stroke
			(width 0)
			(type solid)
		)
		(fill yes)
		(layer "In11.Cu")
		(net "M_D_CPU1_SA_DQ<20>")
	)
	(gr_poly
		(pts
			(xy 87.962994 -270.40205) (xy 87.916004 -270.24965) (xy 87.654384 -270.24965) (xy 87.607394 -270.40205)
			(xy 87.607394 -270.446246) (xy 87.962994 -270.446246)
		)
		(stroke
			(width 0)
			(type solid)
		)
		(fill yes)
		(layer "In11.Cu")
		(net "M_D_CPU1_SA_DQ<23>")
	)
	(gr_poly
		(pts
			(xy 87.962994 -269.99311) (xy 87.962994 -269.948914) (xy 87.607394 -269.948914) (xy 87.607394 -269.99311)
			(xy 87.654384 -270.14551) (xy 87.916004 -270.14551)
		)
		(stroke
			(width 0)
			(type solid)
		)
		(fill yes)
		(layer "In11.Cu")
		(net "M_D_CPU1_SA_DQ<24>")
	)
	(gr_poly
		(pts
			(xy 87.962994 -268.77391) (xy 87.916004 -268.62151) (xy 87.654384 -268.62151) (xy 87.607394 -268.77391)
			(xy 87.607394 -268.81836) (xy 87.962994 -268.81836)
		)
		(stroke
			(width 0)
			(type solid)
		)
		(fill yes)
		(layer "In11.Cu")
		(net "M_D_CPU1_SA_DQ<27>")
	)
	(gr_poly
		(pts
			(xy 87.962994 -268.365478) (xy 87.962994 -268.321028) (xy 87.607394 -268.321028) (xy 87.607394 -268.365478)
			(xy 87.654384 -268.517878) (xy 87.916004 -268.517878)
		)
		(stroke
			(width 0)
			(type solid)
		)
		(fill yes)
		(layer "In11.Cu")
		(net "M_D_CPU1_SA_DQS_DP<3>")
	)
	(gr_poly
		(pts
			(xy 87.962994 -267.146278) (xy 87.916004 -266.993878) (xy 87.654384 -266.993878) (xy 87.607394 -267.146278)
			(xy 87.607394 -267.190474) (xy 87.962994 -267.190474)
		)
		(stroke
			(width 0)
			(type solid)
		)
		(fill yes)
		(layer "In11.Cu")
		(net "M_D_CPU1_SA_DQS_DP<8>")
	)
	(gr_poly
		(pts
			(xy 87.962994 -266.737846) (xy 87.962994 -266.693396) (xy 87.607394 -266.693396) (xy 87.607394 -266.737846)
			(xy 87.654384 -266.890246) (xy 87.916004 -266.890246)
		)
		(stroke
			(width 0)
			(type solid)
		)
		(fill yes)
		(layer "In11.Cu")
		(net "M_D_CPU1_SA_DQ<28>")
	)
	(gr_poly
		(pts
			(xy 87.962994 -265.518646) (xy 87.916004 -265.366246) (xy 87.654384 -265.366246) (xy 87.607394 -265.518646)
			(xy 87.607394 -265.562842) (xy 87.962994 -265.562842)
		)
		(stroke
			(width 0)
			(type solid)
		)
		(fill yes)
		(layer "In11.Cu")
		(net "M_D_CPU1_SA_DQ<31>")
	)
	(gr_poly
		(pts
			(xy 87.962994 -265.109706) (xy 87.962994 -265.06551) (xy 87.607394 -265.06551) (xy 87.607394 -265.109706)
			(xy 87.654384 -265.262106) (xy 87.916004 -265.262106)
		)
		(stroke
			(width 0)
			(type solid)
		)
		(fill yes)
		(layer "In11.Cu")
		(net "M_D_CPU1_SA_CB<0>")
	)
	(gr_poly
		(pts
			(xy 87.962994 -263.891014) (xy 87.916004 -263.738614) (xy 87.654384 -263.738614) (xy 87.607394 -263.891014)
			(xy 87.607394 -263.93521) (xy 87.962994 -263.93521)
		)
		(stroke
			(width 0)
			(type solid)
		)
		(fill yes)
		(layer "In11.Cu")
		(net "M_D_CPU1_SA_CB<3>")
	)
	(gr_poly
		(pts
			(xy 87.962994 -263.482074) (xy 87.962994 -263.437878) (xy 87.607394 -263.437878) (xy 87.607394 -263.482074)
			(xy 87.654384 -263.634474) (xy 87.916004 -263.634474)
		)
		(stroke
			(width 0)
			(type solid)
		)
		(fill yes)
		(layer "In11.Cu")
		(net "M_D_CPU1_SA_DQS_DP<4>")
	)
	(gr_poly
		(pts
			(xy 87.962994 -262.262874) (xy 87.916004 -262.110474) (xy 87.654384 -262.110474) (xy 87.607394 -262.262874)
			(xy 87.607394 -262.307324) (xy 87.962994 -262.307324)
		)
		(stroke
			(width 0)
			(type solid)
		)
		(fill yes)
		(layer "In11.Cu")
		(net "M_D_CPU1_SA_DQS_DP<9>")
	)
	(gr_poly
		(pts
			(xy 87.962994 -261.854442) (xy 87.962994 -261.809992) (xy 87.607394 -261.809992) (xy 87.607394 -261.854442)
			(xy 87.654384 -262.006842) (xy 87.916004 -262.006842)
		)
		(stroke
			(width 0)
			(type solid)
		)
		(fill yes)
		(layer "In11.Cu")
		(net "M_D_CPU1_SA_CB<4>")
	)
	(gr_poly
		(pts
			(xy 87.962994 -260.635242) (xy 87.916004 -260.482842) (xy 87.654384 -260.482842) (xy 87.607394 -260.635242)
			(xy 87.607394 -260.679438) (xy 87.962994 -260.679438)
		)
		(stroke
			(width 0)
			(type solid)
		)
		(fill yes)
		(layer "In11.Cu")
		(net "M_D_CPU1_SA_CB<7>")
	)
	(gr_poly
		(pts
			(xy 87.962994 -259.00761) (xy 87.916004 -258.85521) (xy 87.654384 -258.85521) (xy 87.607394 -259.00761)
			(xy 87.607394 -259.051806) (xy 87.962994 -259.051806)
		)
		(stroke
			(width 0)
			(type solid)
		)
		(fill yes)
		(layer "In11.Cu")
		(net "M_D_CPU1_SA_CS_N<0>")
	)
	(gr_poly
		(pts
			(xy 87.962994 -258.59867) (xy 87.962994 -258.554474) (xy 87.607394 -258.554474) (xy 87.607394 -258.59867)
			(xy 87.654384 -258.75107) (xy 87.916004 -258.75107)
		)
		(stroke
			(width 0)
			(type solid)
		)
		(fill yes)
		(layer "In11.Cu")
		(net "M_D_CPU1_SA_CS_N<3>")
	)
	(gr_poly
		(pts
			(xy 87.962994 -257.37947) (xy 87.916004 -257.22707) (xy 87.654384 -257.22707) (xy 87.607394 -257.37947)
			(xy 87.607394 -257.42392) (xy 87.962994 -257.42392)
		)
		(stroke
			(width 0)
			(type solid)
		)
		(fill yes)
		(layer "In11.Cu")
		(net "M_D_CPU1_SA_CA<1>")
	)
	(gr_poly
		(pts
			(xy 87.962994 -256.971038) (xy 87.962994 -256.926588) (xy 87.607394 -256.926588) (xy 87.607394 -256.971038)
			(xy 87.654384 -257.123438) (xy 87.916004 -257.123438)
		)
		(stroke
			(width 0)
			(type solid)
		)
		(fill yes)
		(layer "In11.Cu")
		(net "M_D_CPU1_SA_CA<2>")
	)
	(gr_poly
		(pts
			(xy 87.962994 -255.751838) (xy 87.916004 -255.599438) (xy 87.654384 -255.599438) (xy 87.607394 -255.751838)
			(xy 87.607394 -255.796288) (xy 87.962994 -255.796288)
		)
		(stroke
			(width 0)
			(type solid)
		)
		(fill yes)
		(layer "In11.Cu")
		(net "M_D_CPU1_SA_CA<5>")
	)
	(gr_poly
		(pts
			(xy 87.968836 -275.284946) (xy 87.921846 -275.132546) (xy 87.660226 -275.132546) (xy 87.613236 -275.284946)
			(xy 87.613236 -275.329142) (xy 87.968836 -275.329142)
		)
		(stroke
			(width 0)
			(type solid)
		)
		(fill yes)
		(layer "In11.Cu")
		(net "M_D_CPU1_SA_DQ<15>")
	)
	(gr_poly
		(pts
			(xy 87.971376 -276.5044) (xy 87.971376 -276.460204) (xy 87.615776 -276.460204) (xy 87.615776 -276.5044)
			(xy 87.662766 -276.6568) (xy 87.924386 -276.6568)
		)
		(stroke
			(width 0)
			(type solid)
		)
		(fill yes)
		(layer "In11.Cu")
		(net "M_D_CPU1_SA_DQ<12>")
	)
	(gr_poly
		(pts
			(xy 88.037924 -278.608282) (xy 87.929466 -278.491442) (xy 87.891112 -278.469344) (xy 87.713312 -278.777192)
			(xy 87.751666 -278.79929) (xy 87.907114 -278.83485)
		)
		(stroke
			(width 0)
			(type solid)
		)
		(fill yes)
		(layer "In11.Cu")
		(net "M_D_CPU1_SA_DQS_DP<1>")
	)
	(gr_poly
		(pts
			(xy 88.174322 -235.425742) (xy 88.212676 -235.403644) (xy 88.034876 -235.095796) (xy 87.996522 -235.117894)
			(xy 87.888064 -235.234734) (xy 88.018874 -235.461302)
		)
		(stroke
			(width 0)
			(type solid)
		)
		(fill yes)
		(layer "In11.Cu")
		(net "M_D_CPU1_SB_DQ<8>")
	)
	(gr_poly
		(pts
			(xy 88.174322 -227.28682) (xy 88.212676 -227.264722) (xy 88.034876 -226.956874) (xy 87.996522 -226.978972)
			(xy 87.888064 -227.095812) (xy 88.018874 -227.32238)
		)
		(stroke
			(width 0)
			(type solid)
		)
		(fill yes)
		(layer "In11.Cu")
		(net "M_D_CPU1_SB_DQS_DN<8>")
	)
	(gr_poly
		(pts
			(xy 88.179656 -240.318036) (xy 88.21801 -240.295938) (xy 88.04021 -239.98809) (xy 88.001856 -240.010188)
			(xy 87.893398 -240.127028) (xy 88.024208 -240.353596)
		)
		(stroke
			(width 0)
			(type solid)
		)
		(fill yes)
		(layer "In11.Cu")
		(net "M_D_CPU1_SB_DQS_DP<0>")
	)
	(gr_poly
		(pts
			(xy 88.180926 -225.67011) (xy 88.21928 -225.648012) (xy 88.04148 -225.340164) (xy 88.003126 -225.362262)
			(xy 87.894668 -225.479102) (xy 88.025478 -225.70567)
		)
		(stroke
			(width 0)
			(type solid)
		)
		(fill yes)
		(layer "In11.Cu")
		(net "M_D_CPU1_SB_DQ<28>")
	)
	(gr_poly
		(pts
			(xy 88.288368 -239.695736) (xy 88.396826 -239.578896) (xy 88.266016 -239.352328) (xy 88.110568 -239.387888)
			(xy 88.072214 -239.409986) (xy 88.250014 -239.717834)
		)
		(stroke
			(width 0)
			(type solid)
		)
		(fill yes)
		(layer "In11.Cu")
		(net "M_D_CPU1_SB_DQS_DN<0>")
	)
	(gr_poly
		(pts
			(xy 88.288368 -234.812586) (xy 88.396826 -234.695746) (xy 88.266016 -234.469178) (xy 88.110568 -234.504738)
			(xy 88.072214 -234.526836) (xy 88.250014 -234.834684)
		)
		(stroke
			(width 0)
			(type solid)
		)
		(fill yes)
		(layer "In11.Cu")
		(net "M_D_CPU1_SB_DQ<10>")
	)
	(gr_poly
		(pts
			(xy 88.289638 -226.676204) (xy 88.398096 -226.559364) (xy 88.267286 -226.332796) (xy 88.111838 -226.368356)
			(xy 88.073484 -226.390454) (xy 88.251284 -226.698302)
		)
		(stroke
			(width 0)
			(type solid)
		)
		(fill yes)
		(layer "In11.Cu")
		(net "M_D_CPU1_SB_DQS_DP<8>")
	)
	(gr_poly
		(pts
			(xy 88.289638 -225.048318) (xy 88.398096 -224.931478) (xy 88.267286 -224.70491) (xy 88.111838 -224.74047)
			(xy 88.073484 -224.762568) (xy 88.251284 -225.070416)
		)
		(stroke
			(width 0)
			(type solid)
		)
		(fill yes)
		(layer "In11.Cu")
		(net "M_D_CPU1_SB_DQ<30>")
	)
	(gr_poly
		(pts
			(xy 88.31453 -249.416062) (xy 88.31453 -249.371612) (xy 87.95893 -249.371612) (xy 87.95893 -249.416062)
			(xy 88.00592 -249.568462) (xy 88.26754 -249.568462)
		)
		(stroke
			(width 0)
			(type solid)
		)
		(fill yes)
		(layer "In11.Cu")
		(net "M_D_CPU1_SB_CA<2>")
	)
	(gr_poly
		(pts
			(xy 88.31453 -244.940582) (xy 88.26754 -244.788182) (xy 88.00592 -244.788182) (xy 87.95893 -244.940582)
			(xy 87.95893 -244.985032) (xy 88.31453 -244.985032)
		)
		(stroke
			(width 0)
			(type solid)
		)
		(fill yes)
		(layer "In11.Cu")
		(net "M_D_CPU1_SB_DQS_DN<9>")
	)
	(gr_poly
		(pts
			(xy 88.31453 -244.532658) (xy 88.31453 -244.488208) (xy 87.95893 -244.488208) (xy 87.95893 -244.532658)
			(xy 88.00592 -244.685058) (xy 88.26754 -244.685058)
		)
		(stroke
			(width 0)
			(type solid)
		)
		(fill yes)
		(layer "In11.Cu")
		(net "M_D_CPU1_SB_DQS_DN<4>")
	)
	(gr_poly
		(pts
			(xy 88.31453 -230.290878) (xy 88.26754 -230.138478) (xy 88.00592 -230.138478) (xy 87.95893 -230.290878)
			(xy 87.95893 -230.335074) (xy 88.31453 -230.335074)
		)
		(stroke
			(width 0)
			(type solid)
		)
		(fill yes)
		(layer "In11.Cu")
		(net "M_D_CPU1_SB_DQ<15>")
	)
	(gr_poly
		(pts
			(xy 88.31453 -229.882446) (xy 88.31453 -229.83825) (xy 87.95893 -229.83825) (xy 87.95893 -229.882446)
			(xy 88.00592 -230.034846) (xy 88.26754 -230.034846)
		)
		(stroke
			(width 0)
			(type solid)
		)
		(fill yes)
		(layer "In11.Cu")
		(net "M_D_CPU1_SB_DQ<24>")
	)
	(gr_poly
		(pts
			(xy 88.314784 -242.905026) (xy 88.314784 -242.860576) (xy 87.959184 -242.860576) (xy 87.959184 -242.905026)
			(xy 88.006174 -243.057426) (xy 88.267794 -243.057426)
		)
		(stroke
			(width 0)
			(type solid)
		)
		(fill yes)
		(layer "In11.Cu")
		(net "M_D_CPU1_SB_CB<1>")
	)
	(gr_poly
		(pts
			(xy 88.314784 -241.685318) (xy 88.267794 -241.532918) (xy 88.006174 -241.532918) (xy 87.959184 -241.685318)
			(xy 87.959184 -241.729514) (xy 88.314784 -241.729514)
		)
		(stroke
			(width 0)
			(type solid)
		)
		(fill yes)
		(layer "In11.Cu")
		(net "M_D_CPU1_SB_DQ<2>")
	)
	(gr_poly
		(pts
			(xy 88.31707 -248.196354) (xy 88.27008 -248.043954) (xy 88.00846 -248.043954) (xy 87.96147 -248.196354)
			(xy 87.96147 -248.240804) (xy 88.31707 -248.240804)
		)
		(stroke
			(width 0)
			(type solid)
		)
		(fill yes)
		(layer "In11.Cu")
		(net "M_D_CPU1_SB_CA<5>")
	)
	(gr_poly
		(pts
			(xy 88.31707 -247.787922) (xy 88.31707 -247.743472) (xy 87.96147 -247.743472) (xy 87.96147 -247.787922)
			(xy 88.00846 -247.940322) (xy 88.27008 -247.940322)
		)
		(stroke
			(width 0)
			(type solid)
		)
		(fill yes)
		(layer "In11.Cu")
		(net "M_D_CPU1_SB_PAR")
	)
	(gr_poly
		(pts
			(xy 88.31707 -246.568722) (xy 88.27008 -246.416322) (xy 88.00846 -246.416322) (xy 87.96147 -246.568722)
			(xy 87.96147 -246.613172) (xy 88.31707 -246.613172)
		)
		(stroke
			(width 0)
			(type solid)
		)
		(fill yes)
		(layer "In11.Cu")
		(net "M_D_CPU1_SB_CB<6>")
	)
	(gr_poly
		(pts
			(xy 88.31707 -246.16029) (xy 88.31707 -246.11584) (xy 87.96147 -246.11584) (xy 87.96147 -246.16029)
			(xy 88.00846 -246.31269) (xy 88.27008 -246.31269)
		)
		(stroke
			(width 0)
			(type solid)
		)
		(fill yes)
		(layer "In11.Cu")
		(net "M_D_CPU1_SB_CB<5>")
	)
	(gr_poly
		(pts
			(xy 88.31707 -243.313458) (xy 88.27008 -243.161058) (xy 88.00846 -243.161058) (xy 87.96147 -243.313458)
			(xy 87.96147 -243.357654) (xy 88.31707 -243.357654)
		)
		(stroke
			(width 0)
			(type solid)
		)
		(fill yes)
		(layer "In11.Cu")
		(net "M_D_CPU1_SB_CB<2>")
	)
	(gr_poly
		(pts
			(xy 88.31707 -241.276886) (xy 88.31707 -241.232436) (xy 87.96147 -241.232436) (xy 87.96147 -241.276886)
			(xy 88.00846 -241.429286) (xy 88.27008 -241.429286)
		)
		(stroke
			(width 0)
			(type solid)
		)
		(fill yes)
		(layer "In11.Cu")
		(net "M_D_CPU1_SB_DQ<1>")
	)
	(gr_poly
		(pts
			(xy 88.31707 -238.430054) (xy 88.27008 -238.277654) (xy 88.00846 -238.277654) (xy 87.96147 -238.430054)
			(xy 87.96147 -238.47425) (xy 88.31707 -238.47425)
		)
		(stroke
			(width 0)
			(type solid)
		)
		(fill yes)
		(layer "In11.Cu")
		(net "M_D_CPU1_SB_DQS_DP<5>")
	)
	(gr_poly
		(pts
			(xy 88.31707 -238.021114) (xy 88.31707 -237.976918) (xy 87.96147 -237.976918) (xy 87.96147 -238.021114)
			(xy 88.00846 -238.173514) (xy 88.27008 -238.173514)
		)
		(stroke
			(width 0)
			(type solid)
		)
		(fill yes)
		(layer "In11.Cu")
		(net "M_D_CPU1_SB_DQ<4>")
	)
	(gr_poly
		(pts
			(xy 88.31707 -233.54665) (xy 88.27008 -233.39425) (xy 88.00846 -233.39425) (xy 87.96147 -233.54665)
			(xy 87.96147 -233.590846) (xy 88.31707 -233.590846)
		)
		(stroke
			(width 0)
			(type solid)
		)
		(fill yes)
		(layer "In11.Cu")
		(net "M_D_CPU1_SB_DQ<11>")
	)
	(gr_poly
		(pts
			(xy 88.31707 -233.13771) (xy 88.31707 -233.093514) (xy 87.96147 -233.093514) (xy 87.96147 -233.13771)
			(xy 88.00846 -233.29011) (xy 88.27008 -233.29011)
		)
		(stroke
			(width 0)
			(type solid)
		)
		(fill yes)
		(layer "In11.Cu")
		(net "M_D_CPU1_SB_DQS_DP<1>")
	)
	(gr_poly
		(pts
			(xy 88.31707 -231.919018) (xy 88.27008 -231.766618) (xy 88.00846 -231.766618) (xy 87.96147 -231.919018)
			(xy 87.96147 -231.963214) (xy 88.31707 -231.963214)
		)
		(stroke
			(width 0)
			(type solid)
		)
		(fill yes)
		(layer "In11.Cu")
		(net "M_D_CPU1_SB_DQS_DP<6>")
	)
	(gr_poly
		(pts
			(xy 88.31707 -231.510078) (xy 88.31707 -231.465882) (xy 87.96147 -231.465882) (xy 87.96147 -231.510078)
			(xy 88.00846 -231.662478) (xy 88.27008 -231.662478)
		)
		(stroke
			(width 0)
			(type solid)
		)
		(fill yes)
		(layer "In11.Cu")
		(net "M_D_CPU1_SB_DQ<12>")
	)
	(gr_poly
		(pts
			(xy 88.31707 -228.663246) (xy 88.27008 -228.510846) (xy 88.00846 -228.510846) (xy 87.96147 -228.663246)
			(xy 87.96147 -228.707696) (xy 88.31707 -228.707696)
		)
		(stroke
			(width 0)
			(type solid)
		)
		(fill yes)
		(layer "In11.Cu")
		(net "M_D_CPU1_SB_DQ<27>")
	)
	(gr_poly
		(pts
			(xy 88.31707 -228.254814) (xy 88.31707 -228.210364) (xy 87.96147 -228.210364) (xy 87.96147 -228.254814)
			(xy 88.00846 -228.407214) (xy 88.27008 -228.407214)
		)
		(stroke
			(width 0)
			(type solid)
		)
		(fill yes)
		(layer "In11.Cu")
		(net "M_D_CPU1_SB_DQS_DP<3>")
	)
	(gr_poly
		(pts
			(xy 88.31707 -223.779842) (xy 88.27008 -223.627442) (xy 88.00846 -223.627442) (xy 87.96147 -223.779842)
			(xy 87.96147 -223.824292) (xy 88.31707 -223.824292)
		)
		(stroke
			(width 0)
			(type solid)
		)
		(fill yes)
		(layer "In11.Cu")
		(net "M_D_CPU1_SB_DQ<31>")
	)
	(gr_poly
		(pts
			(xy 88.323166 -236.393482) (xy 88.323166 -236.349286) (xy 87.967566 -236.349286) (xy 87.967566 -236.393482)
			(xy 88.014556 -236.545882) (xy 88.276176 -236.545882)
		)
		(stroke
			(width 0)
			(type solid)
		)
		(fill yes)
		(layer "In11.Cu")
		(net "M_D_CPU1_SB_DQ<5>")
	)
	(gr_poly
		(pts
			(xy 88.326976 -278.709628) (xy 88.288622 -278.68753) (xy 88.133174 -278.65197) (xy 88.002364 -278.878538)
			(xy 88.110822 -278.995378) (xy 88.149176 -279.017476)
		)
		(stroke
			(width 0)
			(type solid)
		)
		(fill yes)
		(layer "In11.Cu")
		(net "M_D_CPU1_SA_DQ<11>")
	)
	(gr_poly
		(pts
			(xy 88.426798 -276.098762) (xy 88.379808 -275.946362) (xy 88.118188 -275.946362) (xy 88.071198 -276.098762)
			(xy 88.071198 -276.143212) (xy 88.426798 -276.143212)
		)
		(stroke
			(width 0)
			(type solid)
		)
		(fill yes)
		(layer "In11.Cu")
		(net "M_D_CPU1_SA_DQ<14>")
	)
	(gr_poly
		(pts
			(xy 88.426798 -275.690584) (xy 88.426798 -275.646388) (xy 88.071198 -275.646388) (xy 88.071198 -275.690584)
			(xy 88.118188 -275.842984) (xy 88.379808 -275.842984)
		)
		(stroke
			(width 0)
			(type solid)
		)
		(fill yes)
		(layer "In11.Cu")
		(net "M_D_CPU1_SA_DQ<13>")
	)
	(gr_poly
		(pts
			(xy 88.432894 -274.47113) (xy 88.385904 -274.31873) (xy 88.124284 -274.31873) (xy 88.077294 -274.47113)
			(xy 88.077294 -274.51558) (xy 88.432894 -274.51558)
		)
		(stroke
			(width 0)
			(type solid)
		)
		(fill yes)
		(layer "In11.Cu")
		(net "M_D_CPU1_SA_DQ<18>")
	)
	(gr_poly
		(pts
			(xy 88.432894 -274.062698) (xy 88.432894 -274.018248) (xy 88.077294 -274.018248) (xy 88.077294 -274.062698)
			(xy 88.124284 -274.215098) (xy 88.385904 -274.215098)
		)
		(stroke
			(width 0)
			(type solid)
		)
		(fill yes)
		(layer "In11.Cu")
		(net "M_D_CPU1_SA_DQ<17>")
	)
	(gr_poly
		(pts
			(xy 88.432894 -271.215866) (xy 88.385904 -271.063466) (xy 88.124284 -271.063466) (xy 88.077294 -271.215866)
			(xy 88.077294 -271.260062) (xy 88.432894 -271.260062)
		)
		(stroke
			(width 0)
			(type solid)
		)
		(fill yes)
		(layer "In11.Cu")
		(net "M_D_CPU1_SA_DQ<22>")
	)
	(gr_poly
		(pts
			(xy 88.432894 -270.806926) (xy 88.432894 -270.76273) (xy 88.077294 -270.76273) (xy 88.077294 -270.806926)
			(xy 88.124284 -270.959326) (xy 88.385904 -270.959326)
		)
		(stroke
			(width 0)
			(type solid)
		)
		(fill yes)
		(layer "In11.Cu")
		(net "M_D_CPU1_SA_DQ<21>")
	)
	(gr_poly
		(pts
			(xy 88.432894 -269.587726) (xy 88.385904 -269.435326) (xy 88.124284 -269.435326) (xy 88.077294 -269.587726)
			(xy 88.077294 -269.632176) (xy 88.432894 -269.632176)
		)
		(stroke
			(width 0)
			(type solid)
		)
		(fill yes)
		(layer "In11.Cu")
		(net "M_D_CPU1_SA_DQ<26>")
	)
	(gr_poly
		(pts
			(xy 88.432894 -269.179294) (xy 88.432894 -269.134844) (xy 88.077294 -269.134844) (xy 88.077294 -269.179294)
			(xy 88.124284 -269.331694) (xy 88.385904 -269.331694)
		)
		(stroke
			(width 0)
			(type solid)
		)
		(fill yes)
		(layer "In11.Cu")
		(net "M_D_CPU1_SA_DQ<25>")
	)
	(gr_poly
		(pts
			(xy 88.432894 -267.960094) (xy 88.385904 -267.807694) (xy 88.124284 -267.807694) (xy 88.077294 -267.960094)
			(xy 88.077294 -268.004544) (xy 88.432894 -268.004544)
		)
		(stroke
			(width 0)
			(type solid)
		)
		(fill yes)
		(layer "In11.Cu")
		(net "M_D_CPU1_SA_DQS_DN<3>")
	)
	(gr_poly
		(pts
			(xy 88.432894 -267.551662) (xy 88.432894 -267.507212) (xy 88.077294 -267.507212) (xy 88.077294 -267.551662)
			(xy 88.124284 -267.704062) (xy 88.385904 -267.704062)
		)
		(stroke
			(width 0)
			(type solid)
		)
		(fill yes)
		(layer "In11.Cu")
		(net "M_D_CPU1_SA_DQS_DN<8>")
	)
	(gr_poly
		(pts
			(xy 88.432894 -266.332462) (xy 88.385904 -266.180062) (xy 88.124284 -266.180062) (xy 88.077294 -266.332462)
			(xy 88.077294 -266.376658) (xy 88.432894 -266.376658)
		)
		(stroke
			(width 0)
			(type solid)
		)
		(fill yes)
		(layer "In11.Cu")
		(net "M_D_CPU1_SA_DQ<30>")
	)
	(gr_poly
		(pts
			(xy 88.432894 -265.92403) (xy 88.432894 -265.87958) (xy 88.077294 -265.87958) (xy 88.077294 -265.92403)
			(xy 88.124284 -266.07643) (xy 88.385904 -266.07643)
		)
		(stroke
			(width 0)
			(type solid)
		)
		(fill yes)
		(layer "In11.Cu")
		(net "M_D_CPU1_SA_DQ<29>")
	)
	(gr_poly
		(pts
			(xy 88.432894 -264.70483) (xy 88.385904 -264.55243) (xy 88.124284 -264.55243) (xy 88.077294 -264.70483)
			(xy 88.077294 -264.749026) (xy 88.432894 -264.749026)
		)
		(stroke
			(width 0)
			(type solid)
		)
		(fill yes)
		(layer "In11.Cu")
		(net "M_D_CPU1_SA_CB<2>")
	)
	(gr_poly
		(pts
			(xy 88.432894 -264.29589) (xy 88.432894 -264.251694) (xy 88.077294 -264.251694) (xy 88.077294 -264.29589)
			(xy 88.124284 -264.44829) (xy 88.385904 -264.44829)
		)
		(stroke
			(width 0)
			(type solid)
		)
		(fill yes)
		(layer "In11.Cu")
		(net "M_D_CPU1_SA_CB<1>")
	)
	(gr_poly
		(pts
			(xy 88.432894 -263.07669) (xy 88.385904 -262.92429) (xy 88.124284 -262.92429) (xy 88.077294 -263.07669)
			(xy 88.077294 -263.12114) (xy 88.432894 -263.12114)
		)
		(stroke
			(width 0)
			(type solid)
		)
		(fill yes)
		(layer "In11.Cu")
		(net "M_D_CPU1_SA_DQS_DN<4>")
	)
	(gr_poly
		(pts
			(xy 88.432894 -262.668258) (xy 88.432894 -262.623808) (xy 88.077294 -262.623808) (xy 88.077294 -262.668258)
			(xy 88.124284 -262.820658) (xy 88.385904 -262.820658)
		)
		(stroke
			(width 0)
			(type solid)
		)
		(fill yes)
		(layer "In11.Cu")
		(net "M_D_CPU1_SA_DQS_DN<9>")
	)
	(gr_poly
		(pts
			(xy 88.432894 -261.449058) (xy 88.385904 -261.296658) (xy 88.124284 -261.296658) (xy 88.077294 -261.449058)
			(xy 88.077294 -261.493508) (xy 88.432894 -261.493508)
		)
		(stroke
			(width 0)
			(type solid)
		)
		(fill yes)
		(layer "In11.Cu")
		(net "M_D_CPU1_SA_CB<6>")
	)
	(gr_poly
		(pts
			(xy 88.432894 -261.040626) (xy 88.432894 -260.996176) (xy 88.077294 -260.996176) (xy 88.077294 -261.040626)
			(xy 88.124284 -261.193026) (xy 88.385904 -261.193026)
		)
		(stroke
			(width 0)
			(type solid)
		)
		(fill yes)
		(layer "In11.Cu")
		(net "M_D_CPU1_SA_CB<5>")
	)
	(gr_poly
		(pts
			(xy 88.432894 -259.412486) (xy 88.432894 -259.36829) (xy 88.077294 -259.36829) (xy 88.077294 -259.412486)
			(xy 88.124284 -259.564886) (xy 88.385904 -259.564886)
		)
		(stroke
			(width 0)
			(type solid)
		)
		(fill yes)
		(layer "In11.Cu")
		(net "M_D_CPU1_SA_CS_N<2>")
	)
	(gr_poly
		(pts
			(xy 88.432894 -258.193286) (xy 88.385904 -258.040886) (xy 88.124284 -258.040886) (xy 88.077294 -258.193286)
			(xy 88.077294 -258.237736) (xy 88.432894 -258.237736)
		)
		(stroke
			(width 0)
			(type solid)
		)
		(fill yes)
		(layer "In11.Cu")
		(net "M_D_CPU1_SA_CS_N<1>")
	)
	(gr_poly
		(pts
			(xy 88.432894 -257.784854) (xy 88.432894 -257.740404) (xy 88.077294 -257.740404) (xy 88.077294 -257.784854)
			(xy 88.124284 -257.937254) (xy 88.385904 -257.937254)
		)
		(stroke
			(width 0)
			(type solid)
		)
		(fill yes)
		(layer "In11.Cu")
		(net "M_D_CPU1_SA_CA<0>")
	)
	(gr_poly
		(pts
			(xy 88.432894 -256.565654) (xy 88.385904 -256.413254) (xy 88.124284 -256.413254) (xy 88.077294 -256.565654)
			(xy 88.077294 -256.610104) (xy 88.432894 -256.610104)
		)
		(stroke
			(width 0)
			(type solid)
		)
		(fill yes)
		(layer "In11.Cu")
		(net "M_D_CPU1_SA_CA<3>")
	)
	(gr_poly
		(pts
			(xy 88.432894 -256.157222) (xy 88.432894 -256.112772) (xy 88.077294 -256.112772) (xy 88.077294 -256.157222)
			(xy 88.124284 -256.309622) (xy 88.385904 -256.309622)
		)
		(stroke
			(width 0)
			(type solid)
		)
		(fill yes)
		(layer "In11.Cu")
		(net "M_D_CPU1_SA_CA<4>")
	)
	(gr_poly
		(pts
			(xy 88.43899 -272.843498) (xy 88.392 -272.691098) (xy 88.13038 -272.691098) (xy 88.08339 -272.843498)
			(xy 88.08339 -272.887694) (xy 88.43899 -272.887694)
		)
		(stroke
			(width 0)
			(type solid)
		)
		(fill yes)
		(layer "In11.Cu")
		(net "M_D_CPU1_SA_DQS_DN<2>")
	)
	(gr_poly
		(pts
			(xy 88.43899 -272.435066) (xy 88.43899 -272.39087) (xy 88.08339 -272.39087) (xy 88.08339 -272.435066)
			(xy 88.13038 -272.587466) (xy 88.392 -272.587466)
		)
		(stroke
			(width 0)
			(type solid)
		)
		(fill yes)
		(layer "In11.Cu")
		(net "M_D_CPU1_SA_DQS_DN<7>")
	)
	(gr_poly
		(pts
			(xy 88.507824 -279.422098) (xy 88.399366 -279.305258) (xy 88.361012 -279.28316) (xy 88.183212 -279.591008)
			(xy 88.221566 -279.613106) (xy 88.377014 -279.648666)
		)
		(stroke
			(width 0)
			(type solid)
		)
		(fill yes)
		(layer "In11.Cu")
		(net "M_D_CPU1_SA_DQ<9>")
	)
	(gr_poly
		(pts
			(xy 88.648794 -224.85223) (xy 88.687148 -224.830132) (xy 88.509348 -224.522284) (xy 88.470994 -224.544382)
			(xy 88.362536 -224.661222) (xy 88.493346 -224.88779)
		)
		(stroke
			(width 0)
			(type solid)
		)
		(fill yes)
		(layer "In11.Cu")
		(net "M_D_CPU1_SB_DQ<29>")
	)
	(gr_poly
		(pts
			(xy 88.64981 -239.504728) (xy 88.688164 -239.48263) (xy 88.510364 -239.174782) (xy 88.47201 -239.19688)
			(xy 88.363552 -239.31372) (xy 88.494362 -239.540288)
		)
		(stroke
			(width 0)
			(type solid)
		)
		(fill yes)
		(layer "In11.Cu")
		(net "M_D_CPU1_SB_DQS_DN<5>")
	)
	(gr_poly
		(pts
			(xy 88.64981 -234.621578) (xy 88.688164 -234.59948) (xy 88.510364 -234.291632) (xy 88.47201 -234.31373)
			(xy 88.363552 -234.43057) (xy 88.494362 -234.657138)
		)
		(stroke
			(width 0)
			(type solid)
		)
		(fill yes)
		(layer "In11.Cu")
		(net "M_D_CPU1_SB_DQ<9>")
	)
	(gr_poly
		(pts
			(xy 88.64981 -226.482656) (xy 88.688164 -226.460558) (xy 88.510364 -226.15271) (xy 88.47201 -226.174808)
			(xy 88.363552 -226.291648) (xy 88.494362 -226.518216)
		)
		(stroke
			(width 0)
			(type solid)
		)
		(fill yes)
		(layer "In11.Cu")
		(net "M_D_CPU1_SB_DQ<28>")
	)
	(gr_poly
		(pts
			(xy 88.757506 -225.858324) (xy 88.865964 -225.741484) (xy 88.735154 -225.514916) (xy 88.579706 -225.550476)
			(xy 88.541352 -225.572574) (xy 88.719152 -225.880422)
		)
		(stroke
			(width 0)
			(type solid)
		)
		(fill yes)
		(layer "In11.Cu")
		(net "M_D_CPU1_SB_DQ<30>")
	)
	(gr_poly
		(pts
			(xy 88.758522 -233.999278) (xy 88.86698 -233.882438) (xy 88.73617 -233.65587) (xy 88.580722 -233.69143)
			(xy 88.542368 -233.713528) (xy 88.720168 -234.021376)
		)
		(stroke
			(width 0)
			(type solid)
		)
		(fill yes)
		(layer "In11.Cu")
		(net "M_D_CPU1_SB_DQ<11>")
	)
	(gr_poly
		(pts
			(xy 88.763856 -238.891572) (xy 88.872314 -238.774732) (xy 88.741504 -238.548164) (xy 88.586056 -238.583724)
			(xy 88.547702 -238.605822) (xy 88.725502 -238.91367)
		)
		(stroke
			(width 0)
			(type solid)
		)
		(fill yes)
		(layer "In11.Cu")
		(net "M_D_CPU1_SB_DQS_DP<5>")
	)
	(gr_poly
		(pts
			(xy 88.763856 -224.241614) (xy 88.872314 -224.124774) (xy 88.741504 -223.898206) (xy 88.586056 -223.933766)
			(xy 88.547702 -223.955864) (xy 88.725502 -224.263712)
		)
		(stroke
			(width 0)
			(type solid)
		)
		(fill yes)
		(layer "In11.Cu")
		(net "M_D_CPU1_SB_DQ<31>")
	)
	(gr_poly
		(pts
			(xy 88.793066 -235.988098) (xy 88.746076 -235.835698) (xy 88.484456 -235.835698) (xy 88.437466 -235.988098)
			(xy 88.437466 -236.032548) (xy 88.793066 -236.032548)
		)
		(stroke
			(width 0)
			(type solid)
		)
		(fill yes)
		(layer "In11.Cu")
		(net "M_D_CPU1_SB_DQ<7>")
	)
	(gr_poly
		(pts
			(xy 88.796876 -279.523444) (xy 88.758522 -279.501346) (xy 88.603074 -279.465786) (xy 88.472264 -279.692354)
			(xy 88.580722 -279.809194) (xy 88.619076 -279.831292)
		)
		(stroke
			(width 0)
			(type solid)
		)
		(fill yes)
		(layer "In11.Cu")
		(net "M_D_CPU1_SA_DQ<10>")
	)
	(gr_poly
		(pts
			(xy 88.801448 -249.01017) (xy 88.754458 -248.85777) (xy 88.492838 -248.85777) (xy 88.445848 -249.01017)
			(xy 88.445848 -249.05462) (xy 88.801448 -249.05462)
		)
		(stroke
			(width 0)
			(type solid)
		)
		(fill yes)
		(layer "In11.Cu")
		(net "M_D_CPU1_SB_CA<3>")
	)
	(gr_poly
		(pts
			(xy 88.801448 -248.602246) (xy 88.801448 -248.557796) (xy 88.445848 -248.557796) (xy 88.445848 -248.602246)
			(xy 88.492838 -248.754646) (xy 88.754458 -248.754646)
		)
		(stroke
			(width 0)
			(type solid)
		)
		(fill yes)
		(layer "In11.Cu")
		(net "M_D_CPU1_SB_CA<4>")
	)
	(gr_poly
		(pts
			(xy 88.801448 -247.382538) (xy 88.754458 -247.230138) (xy 88.492838 -247.230138) (xy 88.445848 -247.382538)
			(xy 88.445848 -247.426734) (xy 88.801448 -247.426734)
		)
		(stroke
			(width 0)
			(type solid)
		)
		(fill yes)
		(layer "In11.Cu")
		(net "M_D_CPU1_SB_CA<6>")
	)
	(gr_poly
		(pts
			(xy 88.801448 -246.974106) (xy 88.801448 -246.92991) (xy 88.445848 -246.92991) (xy 88.445848 -246.974106)
			(xy 88.492838 -247.126506) (xy 88.754458 -247.126506)
		)
		(stroke
			(width 0)
			(type solid)
		)
		(fill yes)
		(layer "In11.Cu")
		(net "M_D_CPU1_SB_CB<4>")
	)
	(gr_poly
		(pts
			(xy 88.801448 -245.754906) (xy 88.754458 -245.602506) (xy 88.492838 -245.602506) (xy 88.445848 -245.754906)
			(xy 88.445848 -245.799102) (xy 88.801448 -245.799102)
		)
		(stroke
			(width 0)
			(type solid)
		)
		(fill yes)
		(layer "In11.Cu")
		(net "M_D_CPU1_SB_CB<7>")
	)
	(gr_poly
		(pts
			(xy 88.801448 -245.346474) (xy 88.801448 -245.302278) (xy 88.445848 -245.302278) (xy 88.445848 -245.346474)
			(xy 88.492838 -245.498874) (xy 88.754458 -245.498874)
		)
		(stroke
			(width 0)
			(type solid)
		)
		(fill yes)
		(layer "In11.Cu")
		(net "M_D_CPU1_SB_DQS_DP<9>")
	)
	(gr_poly
		(pts
			(xy 88.801448 -244.126766) (xy 88.754458 -243.974366) (xy 88.492838 -243.974366) (xy 88.445848 -244.126766)
			(xy 88.445848 -244.171216) (xy 88.801448 -244.171216)
		)
		(stroke
			(width 0)
			(type solid)
		)
		(fill yes)
		(layer "In11.Cu")
		(net "M_D_CPU1_SB_DQS_DP<4>")
	)
	(gr_poly
		(pts
			(xy 88.801448 -243.718842) (xy 88.801448 -243.674392) (xy 88.445848 -243.674392) (xy 88.445848 -243.718842)
			(xy 88.492838 -243.871242) (xy 88.754458 -243.871242)
		)
		(stroke
			(width 0)
			(type solid)
		)
		(fill yes)
		(layer "In11.Cu")
		(net "M_D_CPU1_SB_CB<0>")
	)
	(gr_poly
		(pts
			(xy 88.801448 -242.499134) (xy 88.754458 -242.346734) (xy 88.492838 -242.346734) (xy 88.445848 -242.499134)
			(xy 88.445848 -242.54333) (xy 88.801448 -242.54333)
		)
		(stroke
			(width 0)
			(type solid)
		)
		(fill yes)
		(layer "In11.Cu")
		(net "M_D_CPU1_SB_CB<3>")
	)
	(gr_poly
		(pts
			(xy 88.801448 -242.090702) (xy 88.801448 -242.046506) (xy 88.445848 -242.046506) (xy 88.445848 -242.090702)
			(xy 88.492838 -242.243102) (xy 88.754458 -242.243102)
		)
		(stroke
			(width 0)
			(type solid)
		)
		(fill yes)
		(layer "In11.Cu")
		(net "M_D_CPU1_SB_DQ<0>")
	)
	(gr_poly
		(pts
			(xy 88.801448 -240.871502) (xy 88.754458 -240.719102) (xy 88.492838 -240.719102) (xy 88.445848 -240.871502)
			(xy 88.445848 -240.915698) (xy 88.801448 -240.915698)
		)
		(stroke
			(width 0)
			(type solid)
		)
		(fill yes)
		(layer "In11.Cu")
		(net "M_D_CPU1_SB_DQ<3>")
	)
	(gr_poly
		(pts
			(xy 88.801448 -240.46307) (xy 88.801448 -240.418874) (xy 88.445848 -240.418874) (xy 88.445848 -240.46307)
			(xy 88.492838 -240.61547) (xy 88.754458 -240.61547)
		)
		(stroke
			(width 0)
			(type solid)
		)
		(fill yes)
		(layer "In11.Cu")
		(net "M_D_CPU1_SB_DQS_DP<0>")
	)
	(gr_poly
		(pts
			(xy 88.801448 -237.61573) (xy 88.754458 -237.46333) (xy 88.492838 -237.46333) (xy 88.445848 -237.61573)
			(xy 88.445848 -237.659926) (xy 88.801448 -237.659926)
		)
		(stroke
			(width 0)
			(type solid)
		)
		(fill yes)
		(layer "In11.Cu")
		(net "M_D_CPU1_SB_DQ<6>")
	)
	(gr_poly
		(pts
			(xy 88.801448 -235.579666) (xy 88.801448 -235.53547) (xy 88.445848 -235.53547) (xy 88.445848 -235.579666)
			(xy 88.492838 -235.732066) (xy 88.754458 -235.732066)
		)
		(stroke
			(width 0)
			(type solid)
		)
		(fill yes)
		(layer "In11.Cu")
		(net "M_D_CPU1_SB_DQ<8>")
	)
	(gr_poly
		(pts
			(xy 88.801448 -232.732326) (xy 88.754458 -232.579926) (xy 88.492838 -232.579926) (xy 88.445848 -232.732326)
			(xy 88.445848 -232.776776) (xy 88.801448 -232.776776)
		)
		(stroke
			(width 0)
			(type solid)
		)
		(fill yes)
		(layer "In11.Cu")
		(net "M_D_CPU1_SB_DQS_DN<1>")
	)
	(gr_poly
		(pts
			(xy 88.801448 -232.324402) (xy 88.801448 -232.279952) (xy 88.445848 -232.279952) (xy 88.445848 -232.324402)
			(xy 88.492838 -232.476802) (xy 88.754458 -232.476802)
		)
		(stroke
			(width 0)
			(type solid)
		)
		(fill yes)
		(layer "In11.Cu")
		(net "M_D_CPU1_SB_DQS_DN<6>")
	)
	(gr_poly
		(pts
			(xy 88.801448 -231.104694) (xy 88.754458 -230.952294) (xy 88.492838 -230.952294) (xy 88.445848 -231.104694)
			(xy 88.445848 -231.14889) (xy 88.801448 -231.14889)
		)
		(stroke
			(width 0)
			(type solid)
		)
		(fill yes)
		(layer "In11.Cu")
		(net "M_D_CPU1_SB_DQ<14>")
	)
	(gr_poly
		(pts
			(xy 88.801448 -230.696262) (xy 88.801448 -230.652066) (xy 88.445848 -230.652066) (xy 88.445848 -230.696262)
			(xy 88.492838 -230.848662) (xy 88.754458 -230.848662)
		)
		(stroke
			(width 0)
			(type solid)
		)
		(fill yes)
		(layer "In11.Cu")
		(net "M_D_CPU1_SB_DQ<13>")
	)
	(gr_poly
		(pts
			(xy 88.801448 -229.477062) (xy 88.754458 -229.324662) (xy 88.492838 -229.324662) (xy 88.445848 -229.477062)
			(xy 88.445848 -229.521258) (xy 88.801448 -229.521258)
		)
		(stroke
			(width 0)
			(type solid)
		)
		(fill yes)
		(layer "In11.Cu")
		(net "M_D_CPU1_SB_DQ<26>")
	)
	(gr_poly
		(pts
			(xy 88.801448 -229.06863) (xy 88.801448 -229.024434) (xy 88.445848 -229.024434) (xy 88.445848 -229.06863)
			(xy 88.492838 -229.22103) (xy 88.754458 -229.22103)
		)
		(stroke
			(width 0)
			(type solid)
		)
		(fill yes)
		(layer "In11.Cu")
		(net "M_D_CPU1_SB_DQ<25>")
	)
	(gr_poly
		(pts
			(xy 88.801448 -227.848922) (xy 88.754458 -227.696522) (xy 88.492838 -227.696522) (xy 88.445848 -227.848922)
			(xy 88.445848 -227.893372) (xy 88.801448 -227.893372)
		)
		(stroke
			(width 0)
			(type solid)
		)
		(fill yes)
		(layer "In11.Cu")
		(net "M_D_CPU1_SB_DQS_DN<3>")
	)
	(gr_poly
		(pts
			(xy 88.801448 -227.440998) (xy 88.801448 -227.396548) (xy 88.445848 -227.396548) (xy 88.445848 -227.440998)
			(xy 88.492838 -227.593398) (xy 88.754458 -227.593398)
		)
		(stroke
			(width 0)
			(type solid)
		)
		(fill yes)
		(layer "In11.Cu")
		(net "M_D_CPU1_SB_DQS_DN<8>")
	)
	(gr_poly
		(pts
			(xy 88.894412 -273.248882) (xy 88.894412 -273.204686) (xy 88.538812 -273.204686) (xy 88.538812 -273.248882)
			(xy 88.585802 -273.401282) (xy 88.847422 -273.401282)
		)
		(stroke
			(width 0)
			(type solid)
		)
		(fill yes)
		(layer "In11.Cu")
		(net "M_D_CPU1_SA_DQS_DP<2>")
	)
	(gr_poly
		(pts
			(xy 88.896952 -272.029174) (xy 88.849962 -271.876774) (xy 88.588342 -271.876774) (xy 88.541352 -272.029174)
			(xy 88.541352 -272.073624) (xy 88.896952 -272.073624)
		)
		(stroke
			(width 0)
			(type solid)
		)
		(fill yes)
		(layer "In11.Cu")
		(net "M_D_CPU1_SA_DQS_DP<7>")
	)
	(gr_poly
		(pts
			(xy 88.902794 -278.540718) (xy 88.855804 -278.388318) (xy 88.594184 -278.388318) (xy 88.547194 -278.540718)
			(xy 88.547194 -278.585168) (xy 88.902794 -278.585168)
		)
		(stroke
			(width 0)
			(type solid)
		)
		(fill yes)
		(layer "In11.Cu")
		(net "M_D_CPU1_SA_DQ<11>")
	)
	(gr_poly
		(pts
			(xy 88.902794 -276.504146) (xy 88.902794 -276.45995) (xy 88.547194 -276.45995) (xy 88.547194 -276.504146)
			(xy 88.594184 -276.656546) (xy 88.855804 -276.656546)
		)
		(stroke
			(width 0)
			(type solid)
		)
		(fill yes)
		(layer "In11.Cu")
		(net "M_D_CPU1_SA_DQ<12>")
	)
	(gr_poly
		(pts
			(xy 88.902794 -275.284946) (xy 88.855804 -275.132546) (xy 88.594184 -275.132546) (xy 88.547194 -275.284946)
			(xy 88.547194 -275.329396) (xy 88.902794 -275.329396)
		)
		(stroke
			(width 0)
			(type solid)
		)
		(fill yes)
		(layer "In11.Cu")
		(net "M_D_CPU1_SA_DQ<15>")
	)
	(gr_poly
		(pts
			(xy 88.902794 -274.876514) (xy 88.902794 -274.832064) (xy 88.547194 -274.832064) (xy 88.547194 -274.876514)
			(xy 88.594184 -275.028914) (xy 88.855804 -275.028914)
		)
		(stroke
			(width 0)
			(type solid)
		)
		(fill yes)
		(layer "In11.Cu")
		(net "M_D_CPU1_SA_DQ<16>")
	)
	(gr_poly
		(pts
			(xy 88.902794 -273.657314) (xy 88.855804 -273.504914) (xy 88.594184 -273.504914) (xy 88.547194 -273.657314)
			(xy 88.547194 -273.701764) (xy 88.902794 -273.701764)
		)
		(stroke
			(width 0)
			(type solid)
		)
		(fill yes)
		(layer "In11.Cu")
		(net "M_D_CPU1_SA_DQ<19>")
	)
	(gr_poly
		(pts
			(xy 88.902794 -270.40205) (xy 88.855804 -270.24965) (xy 88.594184 -270.24965) (xy 88.547194 -270.40205)
			(xy 88.547194 -270.446246) (xy 88.902794 -270.446246)
		)
		(stroke
			(width 0)
			(type solid)
		)
		(fill yes)
		(layer "In11.Cu")
		(net "M_D_CPU1_SA_DQ<23>")
	)
	(gr_poly
		(pts
			(xy 88.902794 -269.99311) (xy 88.902794 -269.948914) (xy 88.547194 -269.948914) (xy 88.547194 -269.99311)
			(xy 88.594184 -270.14551) (xy 88.855804 -270.14551)
		)
		(stroke
			(width 0)
			(type solid)
		)
		(fill yes)
		(layer "In11.Cu")
		(net "M_D_CPU1_SA_DQ<24>")
	)
	(gr_poly
		(pts
			(xy 88.902794 -268.77391) (xy 88.855804 -268.62151) (xy 88.594184 -268.62151) (xy 88.547194 -268.77391)
			(xy 88.547194 -268.81836) (xy 88.902794 -268.81836)
		)
		(stroke
			(width 0)
			(type solid)
		)
		(fill yes)
		(layer "In11.Cu")
		(net "M_D_CPU1_SA_DQ<27>")
	)
	(gr_poly
		(pts
			(xy 88.902794 -268.365478) (xy 88.902794 -268.321028) (xy 88.547194 -268.321028) (xy 88.547194 -268.365478)
			(xy 88.594184 -268.517878) (xy 88.855804 -268.517878)
		)
		(stroke
			(width 0)
			(type solid)
		)
		(fill yes)
		(layer "In11.Cu")
		(net "M_D_CPU1_SA_DQS_DP<3>")
	)
	(gr_poly
		(pts
			(xy 88.902794 -267.146786) (xy 88.855804 -266.994386) (xy 88.594184 -266.994386) (xy 88.547194 -267.146786)
			(xy 88.547194 -267.191236) (xy 88.902794 -267.191236)
		)
		(stroke
			(width 0)
			(type solid)
		)
		(fill yes)
		(layer "In11.Cu")
		(net "M_D_CPU1_SA_DQS_DP<8>")
	)
	(gr_poly
		(pts
			(xy 88.902794 -266.737846) (xy 88.902794 -266.693396) (xy 88.547194 -266.693396) (xy 88.547194 -266.737846)
			(xy 88.594184 -266.890246) (xy 88.855804 -266.890246)
		)
		(stroke
			(width 0)
			(type solid)
		)
		(fill yes)
		(layer "In11.Cu")
		(net "M_D_CPU1_SA_DQ<28>")
	)
	(gr_poly
		(pts
			(xy 88.902794 -265.518646) (xy 88.855804 -265.366246) (xy 88.594184 -265.366246) (xy 88.547194 -265.518646)
			(xy 88.547194 -265.562842) (xy 88.902794 -265.562842)
		)
		(stroke
			(width 0)
			(type solid)
		)
		(fill yes)
		(layer "In11.Cu")
		(net "M_D_CPU1_SA_DQ<31>")
	)
	(gr_poly
		(pts
			(xy 88.902794 -265.109706) (xy 88.902794 -265.06551) (xy 88.547194 -265.06551) (xy 88.547194 -265.109706)
			(xy 88.594184 -265.262106) (xy 88.855804 -265.262106)
		)
		(stroke
			(width 0)
			(type solid)
		)
		(fill yes)
		(layer "In11.Cu")
		(net "M_D_CPU1_SA_CB<0>")
	)
	(gr_poly
		(pts
			(xy 88.902794 -263.891014) (xy 88.855804 -263.738614) (xy 88.594184 -263.738614) (xy 88.547194 -263.891014)
			(xy 88.547194 -263.93521) (xy 88.902794 -263.93521)
		)
		(stroke
			(width 0)
			(type solid)
		)
		(fill yes)
		(layer "In11.Cu")
		(net "M_D_CPU1_SA_CB<3>")
	)
	(gr_poly
		(pts
			(xy 88.902794 -263.482074) (xy 88.902794 -263.437878) (xy 88.547194 -263.437878) (xy 88.547194 -263.482074)
			(xy 88.594184 -263.634474) (xy 88.855804 -263.634474)
		)
		(stroke
			(width 0)
			(type solid)
		)
		(fill yes)
		(layer "In11.Cu")
		(net "M_D_CPU1_SA_DQS_DP<4>")
	)
	(gr_poly
		(pts
			(xy 88.902794 -259.00761) (xy 88.855804 -258.85521) (xy 88.594184 -258.85521) (xy 88.547194 -259.00761)
			(xy 88.547194 -259.051806) (xy 88.902794 -259.051806)
		)
		(stroke
			(width 0)
			(type solid)
		)
		(fill yes)
		(layer "In11.Cu")
		(net "M_D_CPU1_SA_CS_N<0>")
	)
	(gr_poly
		(pts
			(xy 88.902794 -258.59867) (xy 88.902794 -258.554474) (xy 88.547194 -258.554474) (xy 88.547194 -258.59867)
			(xy 88.594184 -258.75107) (xy 88.855804 -258.75107)
		)
		(stroke
			(width 0)
			(type solid)
		)
		(fill yes)
		(layer "In11.Cu")
		(net "M_D_CPU1_SA_CS_N<3>")
	)
	(gr_poly
		(pts
			(xy 88.902794 -257.37947) (xy 88.855804 -257.22707) (xy 88.594184 -257.22707) (xy 88.547194 -257.37947)
			(xy 88.547194 -257.42392) (xy 88.902794 -257.42392)
		)
		(stroke
			(width 0)
			(type solid)
		)
		(fill yes)
		(layer "In11.Cu")
		(net "M_D_CPU1_SA_CA<1>")
	)
	(gr_poly
		(pts
			(xy 88.902794 -256.971038) (xy 88.902794 -256.926588) (xy 88.547194 -256.926588) (xy 88.547194 -256.971038)
			(xy 88.594184 -257.123438) (xy 88.855804 -257.123438)
		)
		(stroke
			(width 0)
			(type solid)
		)
		(fill yes)
		(layer "In11.Cu")
		(net "M_D_CPU1_SA_CA<2>")
	)
	(gr_poly
		(pts
			(xy 88.90889 -271.62125) (xy 88.90889 -271.5768) (xy 88.55329 -271.5768) (xy 88.55329 -271.62125)
			(xy 88.60028 -271.77365) (xy 88.8619 -271.77365)
		)
		(stroke
			(width 0)
			(type solid)
		)
		(fill yes)
		(layer "In11.Cu")
		(net "M_D_CPU1_SA_DQ<20>")
	)
	(gr_poly
		(pts
			(xy 88.90889 -262.262874) (xy 88.8619 -262.110474) (xy 88.60028 -262.110474) (xy 88.55329 -262.262874)
			(xy 88.55329 -262.30707) (xy 88.90889 -262.30707)
		)
		(stroke
			(width 0)
			(type solid)
		)
		(fill yes)
		(layer "In11.Cu")
		(net "M_D_CPU1_SA_DQS_DP<9>")
	)
	(gr_poly
		(pts
			(xy 88.90889 -261.854442) (xy 88.90889 -261.810246) (xy 88.55329 -261.810246) (xy 88.55329 -261.854442)
			(xy 88.60028 -262.006842) (xy 88.8619 -262.006842)
		)
		(stroke
			(width 0)
			(type solid)
		)
		(fill yes)
		(layer "In11.Cu")
		(net "M_D_CPU1_SA_CB<4>")
	)
	(gr_poly
		(pts
			(xy 88.90889 -260.634734) (xy 88.8619 -260.482334) (xy 88.60028 -260.482334) (xy 88.55329 -260.634734)
			(xy 88.55329 -260.679184) (xy 88.90889 -260.679184)
		)
		(stroke
			(width 0)
			(type solid)
		)
		(fill yes)
		(layer "In11.Cu")
		(net "M_D_CPU1_SA_CB<7>")
	)
	(gr_poly
		(pts
			(xy 88.90889 -255.751838) (xy 88.8619 -255.599438) (xy 88.60028 -255.599438) (xy 88.55329 -255.751838)
			(xy 88.55329 -255.796034) (xy 88.90889 -255.796034)
		)
		(stroke
			(width 0)
			(type solid)
		)
		(fill yes)
		(layer "In11.Cu")
		(net "M_D_CPU1_SA_CA<5>")
	)
	(gr_poly
		(pts
			(xy 88.911176 -278.132286) (xy 88.911176 -278.08809) (xy 88.555576 -278.08809) (xy 88.555576 -278.132286)
			(xy 88.602566 -278.284686) (xy 88.864186 -278.284686)
		)
		(stroke
			(width 0)
			(type solid)
		)
		(fill yes)
		(layer "In11.Cu")
		(net "M_D_CPU1_SA_DQS_DP<1>")
	)
	(gr_poly
		(pts
			(xy 88.911176 -276.912578) (xy 88.864186 -276.760178) (xy 88.602566 -276.760178) (xy 88.555576 -276.912578)
			(xy 88.555576 -276.957028) (xy 88.911176 -276.957028)
		)
		(stroke
			(width 0)
			(type solid)
		)
		(fill yes)
		(layer "In11.Cu")
		(net "M_D_CPU1_SA_DQS_DP<6>")
	)
	(gr_poly
		(pts
			(xy 89.114122 -238.68126) (xy 89.152476 -238.659162) (xy 88.974676 -238.351314) (xy 88.936322 -238.373412)
			(xy 88.827864 -238.490252) (xy 88.958674 -238.71682)
		)
		(stroke
			(width 0)
			(type solid)
		)
		(fill yes)
		(layer "In11.Cu")
		(net "M_D_CPU1_SB_DQ<4>")
	)
	(gr_poly
		(pts
			(xy 89.114122 -237.053628) (xy 89.152476 -237.03153) (xy 88.974676 -236.723682) (xy 88.936322 -236.74578)
			(xy 88.827864 -236.86262) (xy 88.958674 -237.089188)
		)
		(stroke
			(width 0)
			(type solid)
		)
		(fill yes)
		(layer "In11.Cu")
		(net "M_D_CPU1_SB_DQ<5>")
	)
	(gr_poly
		(pts
			(xy 89.119456 -233.807) (xy 89.15781 -233.784902) (xy 88.98001 -233.477054) (xy 88.941656 -233.499152)
			(xy 88.833198 -233.615992) (xy 88.964008 -233.84256)
		)
		(stroke
			(width 0)
			(type solid)
		)
		(fill yes)
		(layer "In11.Cu")
		(net "M_D_CPU1_SB_DQS_DP<1>")
	)
	(gr_poly
		(pts
			(xy 89.119456 -225.668078) (xy 89.15781 -225.64598) (xy 88.98001 -225.338132) (xy 88.941656 -225.36023)
			(xy 88.833198 -225.47707) (xy 88.964008 -225.703638)
		)
		(stroke
			(width 0)
			(type solid)
		)
		(fill yes)
		(layer "In11.Cu")
		(net "M_D_CPU1_SB_DQ<29>")
	)
	(gr_poly
		(pts
			(xy 89.22639 -238.06658) (xy 89.334848 -237.94974) (xy 89.204038 -237.723172) (xy 89.04859 -237.758732)
			(xy 89.010236 -237.78083) (xy 89.188036 -238.088678)
		)
		(stroke
			(width 0)
			(type solid)
		)
		(fill yes)
		(layer "In11.Cu")
		(net "M_D_CPU1_SB_DQ<6>")
	)
	(gr_poly
		(pts
			(xy 89.227406 -236.438948) (xy 89.335864 -236.322108) (xy 89.205054 -236.09554) (xy 89.049606 -236.1311)
			(xy 89.011252 -236.153198) (xy 89.189052 -236.461046)
		)
		(stroke
			(width 0)
			(type solid)
		)
		(fill yes)
		(layer "In11.Cu")
		(net "M_D_CPU1_SB_DQ<7>")
	)
	(gr_poly
		(pts
			(xy 89.228168 -233.1847) (xy 89.336626 -233.06786) (xy 89.205816 -232.841292) (xy 89.050368 -232.876852)
			(xy 89.012014 -232.89895) (xy 89.189814 -233.206798)
		)
		(stroke
			(width 0)
			(type solid)
		)
		(fill yes)
		(layer "In11.Cu")
		(net "M_D_CPU1_SB_DQS_DN<1>")
	)
	(gr_poly
		(pts
			(xy 89.229438 -225.048318) (xy 89.337896 -224.931478) (xy 89.207086 -224.70491) (xy 89.051638 -224.74047)
			(xy 89.013284 -224.762568) (xy 89.191084 -225.070416)
		)
		(stroke
			(width 0)
			(type solid)
		)
		(fill yes)
		(layer "In11.Cu")
		(net "M_D_CPU1_SB_DQ<31>")
	)
	(gr_poly
		(pts
			(xy 89.25433 -249.416062) (xy 89.25433 -249.371612) (xy 88.89873 -249.371612) (xy 88.89873 -249.416062)
			(xy 88.94572 -249.568462) (xy 89.20734 -249.568462)
		)
		(stroke
			(width 0)
			(type solid)
		)
		(fill yes)
		(layer "In11.Cu")
		(net "M_D_CPU1_SB_CA<2>")
	)
	(gr_poly
		(pts
			(xy 89.25433 -246.568722) (xy 89.20734 -246.416322) (xy 88.94572 -246.416322) (xy 88.89873 -246.568722)
			(xy 88.89873 -246.612918) (xy 89.25433 -246.612918)
		)
		(stroke
			(width 0)
			(type solid)
		)
		(fill yes)
		(layer "In11.Cu")
		(net "M_D_CPU1_SB_CB<6>")
	)
	(gr_poly
		(pts
			(xy 89.25433 -246.16029) (xy 89.25433 -246.116094) (xy 88.89873 -246.116094) (xy 88.89873 -246.16029)
			(xy 88.94572 -246.31269) (xy 89.20734 -246.31269)
		)
		(stroke
			(width 0)
			(type solid)
		)
		(fill yes)
		(layer "In11.Cu")
		(net "M_D_CPU1_SB_CB<5>")
	)
	(gr_poly
		(pts
			(xy 89.25433 -244.940582) (xy 89.20734 -244.788182) (xy 88.94572 -244.788182) (xy 88.89873 -244.940582)
			(xy 88.89873 -244.985032) (xy 89.25433 -244.985032)
		)
		(stroke
			(width 0)
			(type solid)
		)
		(fill yes)
		(layer "In11.Cu")
		(net "M_D_CPU1_SB_DQS_DN<9>")
	)
	(gr_poly
		(pts
			(xy 89.25433 -244.532658) (xy 89.25433 -244.488208) (xy 88.89873 -244.488208) (xy 88.89873 -244.532658)
			(xy 88.94572 -244.685058) (xy 89.20734 -244.685058)
		)
		(stroke
			(width 0)
			(type solid)
		)
		(fill yes)
		(layer "In11.Cu")
		(net "M_D_CPU1_SB_DQS_DN<4>")
	)
	(gr_poly
		(pts
			(xy 89.25433 -243.31295) (xy 89.20734 -243.16055) (xy 88.94572 -243.16055) (xy 88.89873 -243.31295)
			(xy 88.89873 -243.3574) (xy 89.25433 -243.3574)
		)
		(stroke
			(width 0)
			(type solid)
		)
		(fill yes)
		(layer "In11.Cu")
		(net "M_D_CPU1_SB_CB<2>")
	)
	(gr_poly
		(pts
			(xy 89.25433 -242.905026) (xy 89.25433 -242.860576) (xy 88.89873 -242.860576) (xy 88.89873 -242.905026)
			(xy 88.94572 -243.057426) (xy 89.20734 -243.057426)
		)
		(stroke
			(width 0)
			(type solid)
		)
		(fill yes)
		(layer "In11.Cu")
		(net "M_D_CPU1_SB_CB<1>")
	)
	(gr_poly
		(pts
			(xy 89.25433 -241.685318) (xy 89.20734 -241.532918) (xy 88.94572 -241.532918) (xy 88.89873 -241.685318)
			(xy 88.89873 -241.729514) (xy 89.25433 -241.729514)
		)
		(stroke
			(width 0)
			(type solid)
		)
		(fill yes)
		(layer "In11.Cu")
		(net "M_D_CPU1_SB_DQ<2>")
	)
	(gr_poly
		(pts
			(xy 89.25433 -241.276886) (xy 89.25433 -241.23269) (xy 88.89873 -241.23269) (xy 88.89873 -241.276886)
			(xy 88.94572 -241.429286) (xy 89.20734 -241.429286)
		)
		(stroke
			(width 0)
			(type solid)
		)
		(fill yes)
		(layer "In11.Cu")
		(net "M_D_CPU1_SB_DQ<1>")
	)
	(gr_poly
		(pts
			(xy 89.25433 -240.057178) (xy 89.20734 -239.904778) (xy 88.94572 -239.904778) (xy 88.89873 -240.057178)
			(xy 88.89873 -240.101628) (xy 89.25433 -240.101628)
		)
		(stroke
			(width 0)
			(type solid)
		)
		(fill yes)
		(layer "In11.Cu")
		(net "M_D_CPU1_SB_DQS_DN<0>")
	)
	(gr_poly
		(pts
			(xy 89.25433 -239.649254) (xy 89.25433 -239.604804) (xy 88.89873 -239.604804) (xy 88.89873 -239.649254)
			(xy 88.94572 -239.801654) (xy 89.20734 -239.801654)
		)
		(stroke
			(width 0)
			(type solid)
		)
		(fill yes)
		(layer "In11.Cu")
		(net "M_D_CPU1_SB_DQS_DN<5>")
	)
	(gr_poly
		(pts
			(xy 89.25433 -235.174282) (xy 89.20734 -235.021882) (xy 88.94572 -235.021882) (xy 88.89873 -235.174282)
			(xy 88.89873 -235.218478) (xy 89.25433 -235.218478)
		)
		(stroke
			(width 0)
			(type solid)
		)
		(fill yes)
		(layer "In11.Cu")
		(net "M_D_CPU1_SB_DQ<10>")
	)
	(gr_poly
		(pts
			(xy 89.25433 -234.76585) (xy 89.25433 -234.721654) (xy 88.89873 -234.721654) (xy 88.89873 -234.76585)
			(xy 88.94572 -234.91825) (xy 89.20734 -234.91825)
		)
		(stroke
			(width 0)
			(type solid)
		)
		(fill yes)
		(layer "In11.Cu")
		(net "M_D_CPU1_SB_DQ<9>")
	)
	(gr_poly
		(pts
			(xy 89.25433 -231.510586) (xy 89.25433 -231.466136) (xy 88.89873 -231.466136) (xy 88.89873 -231.510586)
			(xy 88.94572 -231.662986) (xy 89.20734 -231.662986)
		)
		(stroke
			(width 0)
			(type solid)
		)
		(fill yes)
		(layer "In11.Cu")
		(net "M_D_CPU1_SB_DQ<12>")
	)
	(gr_poly
		(pts
			(xy 89.25433 -230.290878) (xy 89.20734 -230.138478) (xy 88.94572 -230.138478) (xy 88.89873 -230.290878)
			(xy 88.89873 -230.335074) (xy 89.25433 -230.335074)
		)
		(stroke
			(width 0)
			(type solid)
		)
		(fill yes)
		(layer "In11.Cu")
		(net "M_D_CPU1_SB_DQ<15>")
	)
	(gr_poly
		(pts
			(xy 89.25433 -229.882446) (xy 89.25433 -229.83825) (xy 88.89873 -229.83825) (xy 88.89873 -229.882446)
			(xy 88.94572 -230.034846) (xy 89.20734 -230.034846)
		)
		(stroke
			(width 0)
			(type solid)
		)
		(fill yes)
		(layer "In11.Cu")
		(net "M_D_CPU1_SB_DQ<24>")
	)
	(gr_poly
		(pts
			(xy 89.25433 -228.663246) (xy 89.20734 -228.510846) (xy 88.94572 -228.510846) (xy 88.89873 -228.663246)
			(xy 88.89873 -228.707442) (xy 89.25433 -228.707442)
		)
		(stroke
			(width 0)
			(type solid)
		)
		(fill yes)
		(layer "In11.Cu")
		(net "M_D_CPU1_SB_DQ<27>")
	)
	(gr_poly
		(pts
			(xy 89.25433 -228.254814) (xy 89.25433 -228.210618) (xy 88.89873 -228.210618) (xy 88.89873 -228.254814)
			(xy 88.94572 -228.407214) (xy 89.20734 -228.407214)
		)
		(stroke
			(width 0)
			(type solid)
		)
		(fill yes)
		(layer "In11.Cu")
		(net "M_D_CPU1_SB_DQS_DP<3>")
	)
	(gr_poly
		(pts
			(xy 89.25433 -227.035106) (xy 89.20734 -226.882706) (xy 88.94572 -226.882706) (xy 88.89873 -227.035106)
			(xy 88.89873 -227.079556) (xy 89.25433 -227.079556)
		)
		(stroke
			(width 0)
			(type solid)
		)
		(fill yes)
		(layer "In11.Cu")
		(net "M_D_CPU1_SB_DQS_DP<8>")
	)
	(gr_poly
		(pts
			(xy 89.25433 -226.627182) (xy 89.25433 -226.582732) (xy 88.89873 -226.582732) (xy 88.89873 -226.627182)
			(xy 88.94572 -226.779582) (xy 89.20734 -226.779582)
		)
		(stroke
			(width 0)
			(type solid)
		)
		(fill yes)
		(layer "In11.Cu")
		(net "M_D_CPU1_SB_DQ<28>")
	)
	(gr_poly
		(pts
			(xy 89.25687 -248.196354) (xy 89.20988 -248.043954) (xy 88.94826 -248.043954) (xy 88.90127 -248.196354)
			(xy 88.90127 -248.24055) (xy 89.25687 -248.24055)
		)
		(stroke
			(width 0)
			(type solid)
		)
		(fill yes)
		(layer "In11.Cu")
		(net "M_D_CPU1_SB_CA<5>")
	)
	(gr_poly
		(pts
			(xy 89.25687 -247.787922) (xy 89.25687 -247.743726) (xy 88.90127 -247.743726) (xy 88.90127 -247.787922)
			(xy 88.94826 -247.940322) (xy 89.20988 -247.940322)
		)
		(stroke
			(width 0)
			(type solid)
		)
		(fill yes)
		(layer "In11.Cu")
		(net "M_D_CPU1_SB_PAR")
	)
	(gr_poly
		(pts
			(xy 89.26322 -231.919018) (xy 89.21623 -231.766618) (xy 88.95461 -231.766618) (xy 88.90762 -231.919018)
			(xy 88.90762 -231.963214) (xy 89.26322 -231.963214)
		)
		(stroke
			(width 0)
			(type solid)
		)
		(fill yes)
		(layer "In11.Cu")
		(net "M_D_CPU1_SB_DQS_DP<6>")
	)
	(gr_poly
		(pts
			(xy 89.364312 -271.215358) (xy 89.317322 -271.062958) (xy 89.055702 -271.062958) (xy 89.008712 -271.215358)
			(xy 89.008712 -271.259808) (xy 89.364312 -271.259808)
		)
		(stroke
			(width 0)
			(type solid)
		)
		(fill yes)
		(layer "In11.Cu")
		(net "M_D_CPU1_SA_DQ<22>")
	)
	(gr_poly
		(pts
			(xy 89.364312 -261.44855) (xy 89.317322 -261.29615) (xy 89.055702 -261.29615) (xy 89.008712 -261.44855)
			(xy 89.008712 -261.493) (xy 89.364312 -261.493)
		)
		(stroke
			(width 0)
			(type solid)
		)
		(fill yes)
		(layer "In11.Cu")
		(net "M_D_CPU1_SA_CB<6>")
	)
	(gr_poly
		(pts
			(xy 89.364312 -261.040626) (xy 89.364312 -260.99643) (xy 89.008712 -260.99643) (xy 89.008712 -261.040626)
			(xy 89.055702 -261.193026) (xy 89.317322 -261.193026)
		)
		(stroke
			(width 0)
			(type solid)
		)
		(fill yes)
		(layer "In11.Cu")
		(net "M_D_CPU1_SA_CB<5>")
	)
	(gr_poly
		(pts
			(xy 89.364312 -256.157222) (xy 89.364312 -256.113026) (xy 89.008712 -256.113026) (xy 89.008712 -256.157222)
			(xy 89.055702 -256.309622) (xy 89.317322 -256.309622)
		)
		(stroke
			(width 0)
			(type solid)
		)
		(fill yes)
		(layer "In11.Cu")
		(net "M_D_CPU1_SA_CA<4>")
	)
	(gr_poly
		(pts
			(xy 89.366852 -272.435066) (xy 89.366852 -272.390616) (xy 89.011252 -272.390616) (xy 89.011252 -272.435066)
			(xy 89.058242 -272.587466) (xy 89.319862 -272.587466)
		)
		(stroke
			(width 0)
			(type solid)
		)
		(fill yes)
		(layer "In11.Cu")
		(net "M_D_CPU1_SA_DQS_DN<7>")
	)
	(gr_poly
		(pts
			(xy 89.372694 -279.354788) (xy 89.325704 -279.202388) (xy 89.064084 -279.202388) (xy 89.017094 -279.354788)
			(xy 89.017094 -279.398984) (xy 89.372694 -279.398984)
		)
		(stroke
			(width 0)
			(type solid)
		)
		(fill yes)
		(layer "In11.Cu")
		(net "M_D_CPU1_SA_DQ<10>")
	)
	(gr_poly
		(pts
			(xy 89.372694 -278.945848) (xy 89.372694 -278.901652) (xy 89.017094 -278.901652) (xy 89.017094 -278.945848)
			(xy 89.064084 -279.098248) (xy 89.325704 -279.098248)
		)
		(stroke
			(width 0)
			(type solid)
		)
		(fill yes)
		(layer "In11.Cu")
		(net "M_D_CPU1_SA_DQ<9>")
	)
	(gr_poly
		(pts
			(xy 89.372694 -276.09927) (xy 89.325704 -275.94687) (xy 89.064084 -275.94687) (xy 89.017094 -276.09927)
			(xy 89.017094 -276.143466) (xy 89.372694 -276.143466)
		)
		(stroke
			(width 0)
			(type solid)
		)
		(fill yes)
		(layer "In11.Cu")
		(net "M_D_CPU1_SA_DQ<14>")
	)
	(gr_poly
		(pts
			(xy 89.372694 -275.690584) (xy 89.372694 -275.646134) (xy 89.017094 -275.646134) (xy 89.017094 -275.690584)
			(xy 89.064084 -275.842984) (xy 89.325704 -275.842984)
		)
		(stroke
			(width 0)
			(type solid)
		)
		(fill yes)
		(layer "In11.Cu")
		(net "M_D_CPU1_SA_DQ<13>")
	)
	(gr_poly
		(pts
			(xy 89.372694 -274.47113) (xy 89.325704 -274.31873) (xy 89.064084 -274.31873) (xy 89.017094 -274.47113)
			(xy 89.017094 -274.51558) (xy 89.372694 -274.51558)
		)
		(stroke
			(width 0)
			(type solid)
		)
		(fill yes)
		(layer "In11.Cu")
		(net "M_D_CPU1_SA_DQ<18>")
	)
	(gr_poly
		(pts
			(xy 89.372694 -274.062698) (xy 89.372694 -274.018248) (xy 89.017094 -274.018248) (xy 89.017094 -274.062698)
			(xy 89.064084 -274.215098) (xy 89.325704 -274.215098)
		)
		(stroke
			(width 0)
			(type solid)
		)
		(fill yes)
		(layer "In11.Cu")
		(net "M_D_CPU1_SA_DQ<17>")
	)
	(gr_poly
		(pts
			(xy 89.372694 -270.806926) (xy 89.372694 -270.76273) (xy 89.017094 -270.76273) (xy 89.017094 -270.806926)
			(xy 89.064084 -270.959326) (xy 89.325704 -270.959326)
		)
		(stroke
			(width 0)
			(type solid)
		)
		(fill yes)
		(layer "In11.Cu")
		(net "M_D_CPU1_SA_DQ<21>")
	)
	(gr_poly
		(pts
			(xy 89.372694 -269.587726) (xy 89.325704 -269.435326) (xy 89.064084 -269.435326) (xy 89.017094 -269.587726)
			(xy 89.017094 -269.632176) (xy 89.372694 -269.632176)
		)
		(stroke
			(width 0)
			(type solid)
		)
		(fill yes)
		(layer "In11.Cu")
		(net "M_D_CPU1_SA_DQ<26>")
	)
	(gr_poly
		(pts
			(xy 89.372694 -269.179294) (xy 89.372694 -269.134844) (xy 89.017094 -269.134844) (xy 89.017094 -269.179294)
			(xy 89.064084 -269.331694) (xy 89.325704 -269.331694)
		)
		(stroke
			(width 0)
			(type solid)
		)
		(fill yes)
		(layer "In11.Cu")
		(net "M_D_CPU1_SA_DQ<25>")
	)
	(gr_poly
		(pts
			(xy 89.372694 -267.960094) (xy 89.325704 -267.807694) (xy 89.064084 -267.807694) (xy 89.017094 -267.960094)
			(xy 89.017094 -268.004544) (xy 89.372694 -268.004544)
		)
		(stroke
			(width 0)
			(type solid)
		)
		(fill yes)
		(layer "In11.Cu")
		(net "M_D_CPU1_SA_DQS_DN<3>")
	)
	(gr_poly
		(pts
			(xy 89.372694 -267.551662) (xy 89.372694 -267.507212) (xy 89.017094 -267.507212) (xy 89.017094 -267.551662)
			(xy 89.064084 -267.704062) (xy 89.325704 -267.704062)
		)
		(stroke
			(width 0)
			(type solid)
		)
		(fill yes)
		(layer "In11.Cu")
		(net "M_D_CPU1_SA_DQS_DN<8>")
	)
	(gr_poly
		(pts
			(xy 89.372694 -266.332462) (xy 89.325704 -266.180062) (xy 89.064084 -266.180062) (xy 89.017094 -266.332462)
			(xy 89.017094 -266.376658) (xy 89.372694 -266.376658)
		)
		(stroke
			(width 0)
			(type solid)
		)
		(fill yes)
		(layer "In11.Cu")
		(net "M_D_CPU1_SA_DQ<30>")
	)
	(gr_poly
		(pts
			(xy 89.372694 -265.923522) (xy 89.372694 -265.879326) (xy 89.017094 -265.879326) (xy 89.017094 -265.923522)
			(xy 89.064084 -266.075922) (xy 89.325704 -266.075922)
		)
		(stroke
			(width 0)
			(type solid)
		)
		(fill yes)
		(layer "In11.Cu")
		(net "M_D_CPU1_SA_DQ<29>")
	)
	(gr_poly
		(pts
			(xy 89.372694 -264.70483) (xy 89.325704 -264.55243) (xy 89.064084 -264.55243) (xy 89.017094 -264.70483)
			(xy 89.017094 -264.749026) (xy 89.372694 -264.749026)
		)
		(stroke
			(width 0)
			(type solid)
		)
		(fill yes)
		(layer "In11.Cu")
		(net "M_D_CPU1_SA_CB<2>")
	)
	(gr_poly
		(pts
			(xy 89.372694 -264.29589) (xy 89.372694 -264.251694) (xy 89.017094 -264.251694) (xy 89.017094 -264.29589)
			(xy 89.064084 -264.44829) (xy 89.325704 -264.44829)
		)
		(stroke
			(width 0)
			(type solid)
		)
		(fill yes)
		(layer "In11.Cu")
		(net "M_D_CPU1_SA_CB<1>")
	)
	(gr_poly
		(pts
			(xy 89.372694 -263.07669) (xy 89.325704 -262.92429) (xy 89.064084 -262.92429) (xy 89.017094 -263.07669)
			(xy 89.017094 -263.12114) (xy 89.372694 -263.12114)
		)
		(stroke
			(width 0)
			(type solid)
		)
		(fill yes)
		(layer "In11.Cu")
		(net "M_D_CPU1_SA_DQS_DN<4>")
	)
	(gr_poly
		(pts
			(xy 89.372694 -259.412486) (xy 89.372694 -259.36829) (xy 89.017094 -259.36829) (xy 89.017094 -259.412486)
			(xy 89.064084 -259.564886) (xy 89.325704 -259.564886)
		)
		(stroke
			(width 0)
			(type solid)
		)
		(fill yes)
		(layer "In11.Cu")
		(net "M_D_CPU1_SA_CS_N<2>")
	)
	(gr_poly
		(pts
			(xy 89.372694 -258.193286) (xy 89.325704 -258.040886) (xy 89.064084 -258.040886) (xy 89.017094 -258.193286)
			(xy 89.017094 -258.237736) (xy 89.372694 -258.237736)
		)
		(stroke
			(width 0)
			(type solid)
		)
		(fill yes)
		(layer "In11.Cu")
		(net "M_D_CPU1_SA_CS_N<1>")
	)
	(gr_poly
		(pts
			(xy 89.372694 -257.784854) (xy 89.372694 -257.740404) (xy 89.017094 -257.740404) (xy 89.017094 -257.784854)
			(xy 89.064084 -257.937254) (xy 89.325704 -257.937254)
		)
		(stroke
			(width 0)
			(type solid)
		)
		(fill yes)
		(layer "In11.Cu")
		(net "M_D_CPU1_SA_CA<0>")
	)
	(gr_poly
		(pts
			(xy 89.372694 -256.565654) (xy 89.325704 -256.413254) (xy 89.064084 -256.413254) (xy 89.017094 -256.565654)
			(xy 89.017094 -256.610104) (xy 89.372694 -256.610104)
		)
		(stroke
			(width 0)
			(type solid)
		)
		(fill yes)
		(layer "In11.Cu")
		(net "M_D_CPU1_SA_CA<3>")
	)
	(gr_poly
		(pts
			(xy 89.372948 -262.66775) (xy 89.372948 -262.623554) (xy 89.017348 -262.623554) (xy 89.017348 -262.66775)
			(xy 89.064338 -262.82015) (xy 89.325958 -262.82015)
		)
		(stroke
			(width 0)
			(type solid)
		)
		(fill yes)
		(layer "In11.Cu")
		(net "M_D_CPU1_SA_DQS_DN<9>")
	)
	(gr_poly
		(pts
			(xy 89.377774 -277.726902) (xy 89.330784 -277.574502) (xy 89.069164 -277.574502) (xy 89.022174 -277.726902)
			(xy 89.022174 -277.771098) (xy 89.377774 -277.771098)
		)
		(stroke
			(width 0)
			(type solid)
		)
		(fill yes)
		(layer "In11.Cu")
		(net "M_D_CPU1_SA_DQS_DN<1>")
	)
	(gr_poly
		(pts
			(xy 89.37879 -277.317962) (xy 89.37879 -277.273766) (xy 89.02319 -277.273766) (xy 89.02319 -277.317962)
			(xy 89.07018 -277.470362) (xy 89.3318 -277.470362)
		)
		(stroke
			(width 0)
			(type solid)
		)
		(fill yes)
		(layer "In11.Cu")
		(net "M_D_CPU1_SA_DQS_DN<6>")
	)
	(gr_poly
		(pts
			(xy 89.37879 -272.843498) (xy 89.3318 -272.691098) (xy 89.07018 -272.691098) (xy 89.02319 -272.843498)
			(xy 89.02319 -272.887948) (xy 89.37879 -272.887948)
		)
		(stroke
			(width 0)
			(type solid)
		)
		(fill yes)
		(layer "In11.Cu")
		(net "M_D_CPU1_SA_DQS_DN<2>")
	)
	(gr_poly
		(pts
			(xy 89.591388 -237.878366) (xy 89.629742 -237.856268) (xy 89.451942 -237.54842) (xy 89.413588 -237.570518)
			(xy 89.30513 -237.687358) (xy 89.43594 -237.913926)
		)
		(stroke
			(width 0)
			(type solid)
		)
		(fill yes)
		(layer "In11.Cu")
		(net "M_D_CPU1_SB_DQ<5>")
	)
	(gr_poly
		(pts
			(xy 89.591388 -236.250734) (xy 89.629742 -236.228636) (xy 89.451942 -235.920788) (xy 89.413588 -235.942886)
			(xy 89.30513 -236.059726) (xy 89.43594 -236.286294)
		)
		(stroke
			(width 0)
			(type solid)
		)
		(fill yes)
		(layer "In11.Cu")
		(net "M_D_CPU1_SB_DQ<8>")
	)
	(gr_poly
		(pts
			(xy 89.703656 -237.263686) (xy 89.812114 -237.146846) (xy 89.681304 -236.920278) (xy 89.525856 -236.955838)
			(xy 89.487502 -236.977936) (xy 89.665302 -237.285784)
		)
		(stroke
			(width 0)
			(type solid)
		)
		(fill yes)
		(layer "In11.Cu")
		(net "M_D_CPU1_SB_DQ<7>")
	)
	(gr_poly
		(pts
			(xy 89.703656 -235.636054) (xy 89.812114 -235.519214) (xy 89.681304 -235.292646) (xy 89.525856 -235.328206)
			(xy 89.487502 -235.350304) (xy 89.665302 -235.658152)
		)
		(stroke
			(width 0)
			(type solid)
		)
		(fill yes)
		(layer "In11.Cu")
		(net "M_D_CPU1_SB_DQ<10>")
	)
	(gr_poly
		(pts
			(xy 89.72677 -247.382538) (xy 89.67978 -247.230138) (xy 89.41816 -247.230138) (xy 89.37117 -247.382538)
			(xy 89.37117 -247.426988) (xy 89.72677 -247.426988)
		)
		(stroke
			(width 0)
			(type solid)
		)
		(fill yes)
		(layer "In11.Cu")
		(net "M_D_CPU1_SB_CA<6>")
	)
	(gr_poly
		(pts
			(xy 89.732866 -248.601738) (xy 89.732866 -248.557542) (xy 89.377266 -248.557542) (xy 89.377266 -248.601738)
			(xy 89.424256 -248.754138) (xy 89.685876 -248.754138)
		)
		(stroke
			(width 0)
			(type solid)
		)
		(fill yes)
		(layer "In11.Cu")
		(net "M_D_CPU1_SB_CA<4>")
	)
	(gr_poly
		(pts
			(xy 89.738708 -246.974106) (xy 89.738708 -246.929656) (xy 89.383108 -246.929656) (xy 89.383108 -246.974106)
			(xy 89.430098 -247.126506) (xy 89.691718 -247.126506)
		)
		(stroke
			(width 0)
			(type solid)
		)
		(fill yes)
		(layer "In11.Cu")
		(net "M_D_CPU1_SB_CB<4>")
	)
	(gr_poly
		(pts
			(xy 89.741248 -249.01017) (xy 89.694258 -248.85777) (xy 89.432638 -248.85777) (xy 89.385648 -249.01017)
			(xy 89.385648 -249.05462) (xy 89.741248 -249.05462)
		)
		(stroke
			(width 0)
			(type solid)
		)
		(fill yes)
		(layer "In11.Cu")
		(net "M_D_CPU1_SB_CA<3>")
	)
	(gr_poly
		(pts
			(xy 89.741248 -245.754906) (xy 89.694258 -245.602506) (xy 89.432638 -245.602506) (xy 89.385648 -245.754906)
			(xy 89.385648 -245.799102) (xy 89.741248 -245.799102)
		)
		(stroke
			(width 0)
			(type solid)
		)
		(fill yes)
		(layer "In11.Cu")
		(net "M_D_CPU1_SB_CB<7>")
	)
	(gr_poly
		(pts
			(xy 89.741248 -245.346474) (xy 89.741248 -245.302278) (xy 89.385648 -245.302278) (xy 89.385648 -245.346474)
			(xy 89.432638 -245.498874) (xy 89.694258 -245.498874)
		)
		(stroke
			(width 0)
			(type solid)
		)
		(fill yes)
		(layer "In11.Cu")
		(net "M_D_CPU1_SB_DQS_DP<9>")
	)
	(gr_poly
		(pts
			(xy 89.741248 -244.126766) (xy 89.694258 -243.974366) (xy 89.432638 -243.974366) (xy 89.385648 -244.126766)
			(xy 89.385648 -244.171216) (xy 89.741248 -244.171216)
		)
		(stroke
			(width 0)
			(type solid)
		)
		(fill yes)
		(layer "In11.Cu")
		(net "M_D_CPU1_SB_DQS_DP<4>")
	)
	(gr_poly
		(pts
			(xy 89.741248 -243.718842) (xy 89.741248 -243.674392) (xy 89.385648 -243.674392) (xy 89.385648 -243.718842)
			(xy 89.432638 -243.871242) (xy 89.694258 -243.871242)
		)
		(stroke
			(width 0)
			(type solid)
		)
		(fill yes)
		(layer "In11.Cu")
		(net "M_D_CPU1_SB_CB<0>")
	)
	(gr_poly
		(pts
			(xy 89.741248 -242.499134) (xy 89.694258 -242.346734) (xy 89.432638 -242.346734) (xy 89.385648 -242.499134)
			(xy 89.385648 -242.54333) (xy 89.741248 -242.54333)
		)
		(stroke
			(width 0)
			(type solid)
		)
		(fill yes)
		(layer "In11.Cu")
		(net "M_D_CPU1_SB_CB<3>")
	)
	(gr_poly
		(pts
			(xy 89.741248 -242.090702) (xy 89.741248 -242.046506) (xy 89.385648 -242.046506) (xy 89.385648 -242.090702)
			(xy 89.432638 -242.243102) (xy 89.694258 -242.243102)
		)
		(stroke
			(width 0)
			(type solid)
		)
		(fill yes)
		(layer "In11.Cu")
		(net "M_D_CPU1_SB_DQ<0>")
	)
	(gr_poly
		(pts
			(xy 89.741248 -240.871502) (xy 89.694258 -240.719102) (xy 89.432638 -240.719102) (xy 89.385648 -240.871502)
			(xy 89.385648 -240.915698) (xy 89.741248 -240.915698)
		)
		(stroke
			(width 0)
			(type solid)
		)
		(fill yes)
		(layer "In11.Cu")
		(net "M_D_CPU1_SB_DQ<3>")
	)
	(gr_poly
		(pts
			(xy 89.741248 -240.46307) (xy 89.741248 -240.418874) (xy 89.385648 -240.418874) (xy 89.385648 -240.46307)
			(xy 89.432638 -240.61547) (xy 89.694258 -240.61547)
		)
		(stroke
			(width 0)
			(type solid)
		)
		(fill yes)
		(layer "In11.Cu")
		(net "M_D_CPU1_SB_DQS_DP<0>")
	)
	(gr_poly
		(pts
			(xy 89.741248 -239.243362) (xy 89.694258 -239.090962) (xy 89.432638 -239.090962) (xy 89.385648 -239.243362)
			(xy 89.385648 -239.287812) (xy 89.741248 -239.287812)
		)
		(stroke
			(width 0)
			(type solid)
		)
		(fill yes)
		(layer "In11.Cu")
		(net "M_D_CPU1_SB_DQS_DP<5>")
	)
	(gr_poly
		(pts
			(xy 89.741248 -238.835438) (xy 89.741248 -238.790988) (xy 89.385648 -238.790988) (xy 89.385648 -238.835438)
			(xy 89.432638 -238.987838) (xy 89.694258 -238.987838)
		)
		(stroke
			(width 0)
			(type solid)
		)
		(fill yes)
		(layer "In11.Cu")
		(net "M_D_CPU1_SB_DQ<4>")
	)
	(gr_poly
		(pts
			(xy 89.741248 -234.360466) (xy 89.694258 -234.208066) (xy 89.432638 -234.208066) (xy 89.385648 -234.360466)
			(xy 89.385648 -234.404662) (xy 89.741248 -234.404662)
		)
		(stroke
			(width 0)
			(type solid)
		)
		(fill yes)
		(layer "In11.Cu")
		(net "M_D_CPU1_SB_DQ<11>")
	)
	(gr_poly
		(pts
			(xy 89.741248 -233.952034) (xy 89.741248 -233.907838) (xy 89.385648 -233.907838) (xy 89.385648 -233.952034)
			(xy 89.432638 -234.104434) (xy 89.694258 -234.104434)
		)
		(stroke
			(width 0)
			(type solid)
		)
		(fill yes)
		(layer "In11.Cu")
		(net "M_D_CPU1_SB_DQS_DP<1>")
	)
	(gr_poly
		(pts
			(xy 89.741248 -232.324402) (xy 89.741248 -232.279952) (xy 89.385648 -232.279952) (xy 89.385648 -232.324402)
			(xy 89.432638 -232.476802) (xy 89.694258 -232.476802)
		)
		(stroke
			(width 0)
			(type solid)
		)
		(fill yes)
		(layer "In11.Cu")
		(net "M_D_CPU1_SB_DQS_DN<6>")
	)
	(gr_poly
		(pts
			(xy 89.741248 -231.104694) (xy 89.694258 -230.952294) (xy 89.432638 -230.952294) (xy 89.385648 -231.104694)
			(xy 89.385648 -231.14889) (xy 89.741248 -231.14889)
		)
		(stroke
			(width 0)
			(type solid)
		)
		(fill yes)
		(layer "In11.Cu")
		(net "M_D_CPU1_SB_DQ<14>")
	)
	(gr_poly
		(pts
			(xy 89.741248 -230.696262) (xy 89.741248 -230.652066) (xy 89.385648 -230.652066) (xy 89.385648 -230.696262)
			(xy 89.432638 -230.848662) (xy 89.694258 -230.848662)
		)
		(stroke
			(width 0)
			(type solid)
		)
		(fill yes)
		(layer "In11.Cu")
		(net "M_D_CPU1_SB_DQ<13>")
	)
	(gr_poly
		(pts
			(xy 89.741248 -229.477062) (xy 89.694258 -229.324662) (xy 89.432638 -229.324662) (xy 89.385648 -229.477062)
			(xy 89.385648 -229.521258) (xy 89.741248 -229.521258)
		)
		(stroke
			(width 0)
			(type solid)
		)
		(fill yes)
		(layer "In11.Cu")
		(net "M_D_CPU1_SB_DQ<26>")
	)
	(gr_poly
		(pts
			(xy 89.741248 -229.06863) (xy 89.741248 -229.024434) (xy 89.385648 -229.024434) (xy 89.385648 -229.06863)
			(xy 89.432638 -229.22103) (xy 89.694258 -229.22103)
		)
		(stroke
			(width 0)
			(type solid)
		)
		(fill yes)
		(layer "In11.Cu")
		(net "M_D_CPU1_SB_DQ<25>")
	)
	(gr_poly
		(pts
			(xy 89.741248 -227.848922) (xy 89.694258 -227.696522) (xy 89.432638 -227.696522) (xy 89.385648 -227.848922)
			(xy 89.385648 -227.893372) (xy 89.741248 -227.893372)
		)
		(stroke
			(width 0)
			(type solid)
		)
		(fill yes)
		(layer "In11.Cu")
		(net "M_D_CPU1_SB_DQS_DN<3>")
	)
	(gr_poly
		(pts
			(xy 89.741248 -227.440998) (xy 89.741248 -227.396548) (xy 89.385648 -227.396548) (xy 89.385648 -227.440998)
			(xy 89.432638 -227.593398) (xy 89.694258 -227.593398)
		)
		(stroke
			(width 0)
			(type solid)
		)
		(fill yes)
		(layer "In11.Cu")
		(net "M_D_CPU1_SB_DQS_DN<8>")
	)
	(gr_poly
		(pts
			(xy 89.741248 -226.22129) (xy 89.694258 -226.06889) (xy 89.432638 -226.06889) (xy 89.385648 -226.22129)
			(xy 89.385648 -226.26574) (xy 89.741248 -226.26574)
		)
		(stroke
			(width 0)
			(type solid)
		)
		(fill yes)
		(layer "In11.Cu")
		(net "M_D_CPU1_SB_DQ<30>")
	)
	(gr_poly
		(pts
			(xy 89.741248 -225.813366) (xy 89.741248 -225.768916) (xy 89.385648 -225.768916) (xy 89.385648 -225.813366)
			(xy 89.432638 -225.965766) (xy 89.694258 -225.965766)
		)
		(stroke
			(width 0)
			(type solid)
		)
		(fill yes)
		(layer "In11.Cu")
		(net "M_D_CPU1_SB_DQ<29>")
	)
	(gr_poly
		(pts
			(xy 89.842594 -278.540718) (xy 89.795604 -278.388318) (xy 89.533984 -278.388318) (xy 89.486994 -278.540718)
			(xy 89.486994 -278.585168) (xy 89.842594 -278.585168)
		)
		(stroke
			(width 0)
			(type solid)
		)
		(fill yes)
		(layer "In11.Cu")
		(net "M_D_CPU1_SA_DQ<11>")
	)
	(gr_poly
		(pts
			(xy 89.842594 -278.132032) (xy 89.842594 -278.087836) (xy 89.486994 -278.087836) (xy 89.486994 -278.132032)
			(xy 89.533984 -278.284432) (xy 89.795604 -278.284432)
		)
		(stroke
			(width 0)
			(type solid)
		)
		(fill yes)
		(layer "In11.Cu")
		(net "M_D_CPU1_SA_DQS_DP<1>")
	)
	(gr_poly
		(pts
			(xy 89.842594 -276.913086) (xy 89.795604 -276.760686) (xy 89.533984 -276.760686) (xy 89.486994 -276.913086)
			(xy 89.486994 -276.957282) (xy 89.842594 -276.957282)
		)
		(stroke
			(width 0)
			(type solid)
		)
		(fill yes)
		(layer "In11.Cu")
		(net "M_D_CPU1_SA_DQS_DP<6>")
	)
	(gr_poly
		(pts
			(xy 89.842594 -276.504146) (xy 89.842594 -276.45995) (xy 89.486994 -276.45995) (xy 89.486994 -276.504146)
			(xy 89.533984 -276.656546) (xy 89.795604 -276.656546)
		)
		(stroke
			(width 0)
			(type solid)
		)
		(fill yes)
		(layer "In11.Cu")
		(net "M_D_CPU1_SA_DQ<12>")
	)
	(gr_poly
		(pts
			(xy 89.842594 -275.284946) (xy 89.795604 -275.132546) (xy 89.533984 -275.132546) (xy 89.486994 -275.284946)
			(xy 89.486994 -275.329396) (xy 89.842594 -275.329396)
		)
		(stroke
			(width 0)
			(type solid)
		)
		(fill yes)
		(layer "In11.Cu")
		(net "M_D_CPU1_SA_DQ<15>")
	)
	(gr_poly
		(pts
			(xy 89.842594 -274.876514) (xy 89.842594 -274.832064) (xy 89.486994 -274.832064) (xy 89.486994 -274.876514)
			(xy 89.533984 -275.028914) (xy 89.795604 -275.028914)
		)
		(stroke
			(width 0)
			(type solid)
		)
		(fill yes)
		(layer "In11.Cu")
		(net "M_D_CPU1_SA_DQ<16>")
	)
	(gr_poly
		(pts
			(xy 89.842594 -273.657314) (xy 89.795604 -273.504914) (xy 89.533984 -273.504914) (xy 89.486994 -273.657314)
			(xy 89.486994 -273.701764) (xy 89.842594 -273.701764)
		)
		(stroke
			(width 0)
			(type solid)
		)
		(fill yes)
		(layer "In11.Cu")
		(net "M_D_CPU1_SA_DQ<19>")
	)
	(gr_poly
		(pts
			(xy 89.842594 -273.248882) (xy 89.842594 -273.204432) (xy 89.486994 -273.204432) (xy 89.486994 -273.248882)
			(xy 89.533984 -273.401282) (xy 89.795604 -273.401282)
		)
		(stroke
			(width 0)
			(type solid)
		)
		(fill yes)
		(layer "In11.Cu")
		(net "M_D_CPU1_SA_DQS_DP<2>")
	)
	(gr_poly
		(pts
			(xy 89.842594 -270.40205) (xy 89.795604 -270.24965) (xy 89.533984 -270.24965) (xy 89.486994 -270.40205)
			(xy 89.486994 -270.446246) (xy 89.842594 -270.446246)
		)
		(stroke
			(width 0)
			(type solid)
		)
		(fill yes)
		(layer "In11.Cu")
		(net "M_D_CPU1_SA_DQ<23>")
	)
	(gr_poly
		(pts
			(xy 89.842594 -269.99311) (xy 89.842594 -269.948914) (xy 89.486994 -269.948914) (xy 89.486994 -269.99311)
			(xy 89.533984 -270.14551) (xy 89.795604 -270.14551)
		)
		(stroke
			(width 0)
			(type solid)
		)
		(fill yes)
		(layer "In11.Cu")
		(net "M_D_CPU1_SA_DQ<24>")
	)
	(gr_poly
		(pts
			(xy 89.842594 -268.77391) (xy 89.795604 -268.62151) (xy 89.533984 -268.62151) (xy 89.486994 -268.77391)
			(xy 89.486994 -268.81836) (xy 89.842594 -268.81836)
		)
		(stroke
			(width 0)
			(type solid)
		)
		(fill yes)
		(layer "In11.Cu")
		(net "M_D_CPU1_SA_DQ<27>")
	)
	(gr_poly
		(pts
			(xy 89.842594 -268.365478) (xy 89.842594 -268.321028) (xy 89.486994 -268.321028) (xy 89.486994 -268.365478)
			(xy 89.533984 -268.517878) (xy 89.795604 -268.517878)
		)
		(stroke
			(width 0)
			(type solid)
		)
		(fill yes)
		(layer "In11.Cu")
		(net "M_D_CPU1_SA_DQS_DP<3>")
	)
	(gr_poly
		(pts
			(xy 89.842594 -267.146278) (xy 89.795604 -266.993878) (xy 89.533984 -266.993878) (xy 89.486994 -267.146278)
			(xy 89.486994 -267.190474) (xy 89.842594 -267.190474)
		)
		(stroke
			(width 0)
			(type solid)
		)
		(fill yes)
		(layer "In11.Cu")
		(net "M_D_CPU1_SA_DQS_DP<8>")
	)
	(gr_poly
		(pts
			(xy 89.842594 -266.737846) (xy 89.842594 -266.693396) (xy 89.486994 -266.693396) (xy 89.486994 -266.737846)
			(xy 89.533984 -266.890246) (xy 89.795604 -266.890246)
		)
		(stroke
			(width 0)
			(type solid)
		)
		(fill yes)
		(layer "In11.Cu")
		(net "M_D_CPU1_SA_DQ<28>")
	)
	(gr_poly
		(pts
			(xy 89.842594 -265.518646) (xy 89.795604 -265.366246) (xy 89.533984 -265.366246) (xy 89.486994 -265.518646)
			(xy 89.486994 -265.562842) (xy 89.842594 -265.562842)
		)
		(stroke
			(width 0)
			(type solid)
		)
		(fill yes)
		(layer "In11.Cu")
		(net "M_D_CPU1_SA_DQ<31>")
	)
	(gr_poly
		(pts
			(xy 89.842594 -265.109706) (xy 89.842594 -265.06551) (xy 89.486994 -265.06551) (xy 89.486994 -265.109706)
			(xy 89.533984 -265.262106) (xy 89.795604 -265.262106)
		)
		(stroke
			(width 0)
			(type solid)
		)
		(fill yes)
		(layer "In11.Cu")
		(net "M_D_CPU1_SA_CB<0>")
	)
	(gr_poly
		(pts
			(xy 89.842594 -263.891014) (xy 89.795604 -263.738614) (xy 89.533984 -263.738614) (xy 89.486994 -263.891014)
			(xy 89.486994 -263.93521) (xy 89.842594 -263.93521)
		)
		(stroke
			(width 0)
			(type solid)
		)
		(fill yes)
		(layer "In11.Cu")
		(net "M_D_CPU1_SA_CB<3>")
	)
	(gr_poly
		(pts
			(xy 89.842594 -263.482074) (xy 89.842594 -263.437878) (xy 89.486994 -263.437878) (xy 89.486994 -263.482074)
			(xy 89.533984 -263.634474) (xy 89.795604 -263.634474)
		)
		(stroke
			(width 0)
			(type solid)
		)
		(fill yes)
		(layer "In11.Cu")
		(net "M_D_CPU1_SA_DQS_DP<4>")
	)
	(gr_poly
		(pts
			(xy 89.842594 -259.00761) (xy 89.795604 -258.85521) (xy 89.533984 -258.85521) (xy 89.486994 -259.00761)
			(xy 89.486994 -259.051806) (xy 89.842594 -259.051806)
		)
		(stroke
			(width 0)
			(type solid)
		)
		(fill yes)
		(layer "In11.Cu")
		(net "M_D_CPU1_SA_CS_N<0>")
	)
	(gr_poly
		(pts
			(xy 89.842594 -258.59867) (xy 89.842594 -258.554474) (xy 89.486994 -258.554474) (xy 89.486994 -258.59867)
			(xy 89.533984 -258.75107) (xy 89.795604 -258.75107)
		)
		(stroke
			(width 0)
			(type solid)
		)
		(fill yes)
		(layer "In11.Cu")
		(net "M_D_CPU1_SA_CS_N<3>")
	)
	(gr_poly
		(pts
			(xy 89.842594 -257.37947) (xy 89.795604 -257.22707) (xy 89.533984 -257.22707) (xy 89.486994 -257.37947)
			(xy 89.486994 -257.42392) (xy 89.842594 -257.42392)
		)
		(stroke
			(width 0)
			(type solid)
		)
		(fill yes)
		(layer "In11.Cu")
		(net "M_D_CPU1_SA_CA<1>")
	)
	(gr_poly
		(pts
			(xy 89.842594 -256.971038) (xy 89.842594 -256.926588) (xy 89.486994 -256.926588) (xy 89.486994 -256.971038)
			(xy 89.533984 -257.123438) (xy 89.795604 -257.123438)
		)
		(stroke
			(width 0)
			(type solid)
		)
		(fill yes)
		(layer "In11.Cu")
		(net "M_D_CPU1_SA_CA<2>")
	)
	(gr_poly
		(pts
			(xy 89.842848 -262.262874) (xy 89.795858 -262.110474) (xy 89.534238 -262.110474) (xy 89.487248 -262.262874)
			(xy 89.487248 -262.307324) (xy 89.842848 -262.307324)
		)
		(stroke
			(width 0)
			(type solid)
		)
		(fill yes)
		(layer "In11.Cu")
		(net "M_D_CPU1_SA_DQS_DP<9>")
	)
	(gr_poly
		(pts
			(xy 89.84869 -272.029682) (xy 89.8017 -271.877282) (xy 89.54008 -271.877282) (xy 89.49309 -272.029682)
			(xy 89.49309 -272.073878) (xy 89.84869 -272.073878)
		)
		(stroke
			(width 0)
			(type solid)
		)
		(fill yes)
		(layer "In11.Cu")
		(net "M_D_CPU1_SA_DQS_DP<7>")
	)
	(gr_poly
		(pts
			(xy 89.84869 -271.620742) (xy 89.84869 -271.576546) (xy 89.49309 -271.576546) (xy 89.49309 -271.620742)
			(xy 89.54008 -271.773142) (xy 89.8017 -271.773142)
		)
		(stroke
			(width 0)
			(type solid)
		)
		(fill yes)
		(layer "In11.Cu")
		(net "M_D_CPU1_SA_DQ<20>")
	)
	(gr_poly
		(pts
			(xy 89.84869 -261.854442) (xy 89.84869 -261.809992) (xy 89.49309 -261.809992) (xy 89.49309 -261.854442)
			(xy 89.54008 -262.006842) (xy 89.8017 -262.006842)
		)
		(stroke
			(width 0)
			(type solid)
		)
		(fill yes)
		(layer "In11.Cu")
		(net "M_D_CPU1_SA_CB<4>")
	)
	(gr_poly
		(pts
			(xy 89.84869 -260.635242) (xy 89.8017 -260.482842) (xy 89.54008 -260.482842) (xy 89.49309 -260.635242)
			(xy 89.49309 -260.679438) (xy 89.84869 -260.679438)
		)
		(stroke
			(width 0)
			(type solid)
		)
		(fill yes)
		(layer "In11.Cu")
		(net "M_D_CPU1_SA_CB<7>")
	)
	(gr_poly
		(pts
			(xy 89.84869 -255.751838) (xy 89.8017 -255.599438) (xy 89.54008 -255.599438) (xy 89.49309 -255.751838)
			(xy 89.49309 -255.796288) (xy 89.84869 -255.796288)
		)
		(stroke
			(width 0)
			(type solid)
		)
		(fill yes)
		(layer "In11.Cu")
		(net "M_D_CPU1_SA_CA<5>")
	)
	(gr_poly
		(pts
			(xy 90.052144 -235.422694) (xy 90.090498 -235.400596) (xy 89.912698 -235.092748) (xy 89.874344 -235.114846)
			(xy 89.765886 -235.231686) (xy 89.896696 -235.458254)
		)
		(stroke
			(width 0)
			(type solid)
		)
		(fill yes)
		(layer "In11.Cu")
		(net "M_D_CPU1_SB_DQ<9>")
	)
	(gr_poly
		(pts
			(xy 90.053922 -237.053628) (xy 90.092276 -237.03153) (xy 89.914476 -236.723682) (xy 89.876122 -236.74578)
			(xy 89.767664 -236.86262) (xy 89.898474 -237.089188)
		)
		(stroke
			(width 0)
			(type solid)
		)
		(fill yes)
		(layer "In11.Cu")
		(net "M_D_CPU1_SB_DQ<8>")
	)
	(gr_poly
		(pts
			(xy 90.16619 -236.438948) (xy 90.274648 -236.322108) (xy 90.143838 -236.09554) (xy 89.98839 -236.1311)
			(xy 89.950036 -236.153198) (xy 90.127836 -236.461046)
		)
		(stroke
			(width 0)
			(type solid)
		)
		(fill yes)
		(layer "In11.Cu")
		(net "M_D_CPU1_SB_DQ<10>")
	)
	(gr_poly
		(pts
			(xy 90.173556 -234.822492) (xy 90.282014 -234.705652) (xy 90.151204 -234.479084) (xy 89.995756 -234.514644)
			(xy 89.957402 -234.536742) (xy 90.135202 -234.84459)
		)
		(stroke
			(width 0)
			(type solid)
		)
		(fill yes)
		(layer "In11.Cu")
		(net "M_D_CPU1_SB_DQ<11>")
	)
	(gr_poly
		(pts
			(xy 90.19413 -246.16029) (xy 90.19413 -246.116094) (xy 89.83853 -246.116094) (xy 89.83853 -246.16029)
			(xy 89.88552 -246.31269) (xy 90.14714 -246.31269)
		)
		(stroke
			(width 0)
			(type solid)
		)
		(fill yes)
		(layer "In11.Cu")
		(net "M_D_CPU1_SB_CB<5>")
	)
	(gr_poly
		(pts
			(xy 90.19413 -243.31295) (xy 90.14714 -243.16055) (xy 89.88552 -243.16055) (xy 89.83853 -243.31295)
			(xy 89.83853 -243.3574) (xy 90.19413 -243.3574)
		)
		(stroke
			(width 0)
			(type solid)
		)
		(fill yes)
		(layer "In11.Cu")
		(net "M_D_CPU1_SB_CB<2>")
	)
	(gr_poly
		(pts
			(xy 90.19413 -242.905026) (xy 90.19413 -242.860576) (xy 89.83853 -242.860576) (xy 89.83853 -242.905026)
			(xy 89.88552 -243.057426) (xy 90.14714 -243.057426)
		)
		(stroke
			(width 0)
			(type solid)
		)
		(fill yes)
		(layer "In11.Cu")
		(net "M_D_CPU1_SB_CB<1>")
	)
	(gr_poly
		(pts
			(xy 90.19413 -241.685318) (xy 90.14714 -241.532918) (xy 89.88552 -241.532918) (xy 89.83853 -241.685318)
			(xy 89.83853 -241.729514) (xy 90.19413 -241.729514)
		)
		(stroke
			(width 0)
			(type solid)
		)
		(fill yes)
		(layer "In11.Cu")
		(net "M_D_CPU1_SB_DQ<2>")
	)
	(gr_poly
		(pts
			(xy 90.19413 -241.276886) (xy 90.19413 -241.23269) (xy 89.83853 -241.23269) (xy 89.83853 -241.276886)
			(xy 89.88552 -241.429286) (xy 90.14714 -241.429286)
		)
		(stroke
			(width 0)
			(type solid)
		)
		(fill yes)
		(layer "In11.Cu")
		(net "M_D_CPU1_SB_DQ<1>")
	)
	(gr_poly
		(pts
			(xy 90.19413 -238.429546) (xy 90.14714 -238.277146) (xy 89.88552 -238.277146) (xy 89.83853 -238.429546)
			(xy 89.83853 -238.473996) (xy 90.19413 -238.473996)
		)
		(stroke
			(width 0)
			(type solid)
		)
		(fill yes)
		(layer "In11.Cu")
		(net "M_D_CPU1_SB_DQ<6>")
	)
	(gr_poly
		(pts
			(xy 90.19413 -238.021622) (xy 90.19413 -237.977172) (xy 89.83853 -237.977172) (xy 89.83853 -238.021622)
			(xy 89.88552 -238.174022) (xy 90.14714 -238.174022)
		)
		(stroke
			(width 0)
			(type solid)
		)
		(fill yes)
		(layer "In11.Cu")
		(net "M_D_CPU1_SB_DQ<5>")
	)
	(gr_poly
		(pts
			(xy 90.19413 -233.546142) (xy 90.14714 -233.393742) (xy 89.88552 -233.393742) (xy 89.83853 -233.546142)
			(xy 89.83853 -233.590592) (xy 90.19413 -233.590592)
		)
		(stroke
			(width 0)
			(type solid)
		)
		(fill yes)
		(layer "In11.Cu")
		(net "M_D_CPU1_SB_DQS_DN<1>")
	)
	(gr_poly
		(pts
			(xy 90.19413 -231.510586) (xy 90.19413 -231.466136) (xy 89.83853 -231.466136) (xy 89.83853 -231.510586)
			(xy 89.88552 -231.662986) (xy 90.14714 -231.662986)
		)
		(stroke
			(width 0)
			(type solid)
		)
		(fill yes)
		(layer "In11.Cu")
		(net "M_D_CPU1_SB_DQ<12>")
	)
	(gr_poly
		(pts
			(xy 90.19413 -228.663246) (xy 90.14714 -228.510846) (xy 89.88552 -228.510846) (xy 89.83853 -228.663246)
			(xy 89.83853 -228.707442) (xy 90.19413 -228.707442)
		)
		(stroke
			(width 0)
			(type solid)
		)
		(fill yes)
		(layer "In11.Cu")
		(net "M_D_CPU1_SB_DQ<27>")
	)
	(gr_poly
		(pts
			(xy 90.19413 -228.254814) (xy 90.19413 -228.210618) (xy 89.83853 -228.210618) (xy 89.83853 -228.254814)
			(xy 89.88552 -228.407214) (xy 90.14714 -228.407214)
		)
		(stroke
			(width 0)
			(type solid)
		)
		(fill yes)
		(layer "In11.Cu")
		(net "M_D_CPU1_SB_DQS_DP<3>")
	)
	(gr_poly
		(pts
			(xy 90.19413 -226.627182) (xy 90.19413 -226.582732) (xy 89.83853 -226.582732) (xy 89.83853 -226.627182)
			(xy 89.88552 -226.779582) (xy 90.14714 -226.779582)
		)
		(stroke
			(width 0)
			(type solid)
		)
		(fill yes)
		(layer "In11.Cu")
		(net "M_D_CPU1_SB_DQ<28>")
	)
	(gr_poly
		(pts
			(xy 90.19413 -225.407474) (xy 90.14714 -225.255074) (xy 89.88552 -225.255074) (xy 89.83853 -225.407474)
			(xy 89.83853 -225.45167) (xy 90.19413 -225.45167)
		)
		(stroke
			(width 0)
			(type solid)
		)
		(fill yes)
		(layer "In11.Cu")
		(net "M_D_CPU1_SB_DQ<31>")
	)
	(gr_poly
		(pts
			(xy 90.19667 -249.416062) (xy 90.19667 -249.371612) (xy 89.84107 -249.371612) (xy 89.84107 -249.416062)
			(xy 89.88806 -249.568462) (xy 90.14968 -249.568462)
		)
		(stroke
			(width 0)
			(type solid)
		)
		(fill yes)
		(layer "In11.Cu")
		(net "M_D_CPU1_SB_CA<2>")
	)
	(gr_poly
		(pts
			(xy 90.19667 -248.196354) (xy 90.14968 -248.043954) (xy 89.88806 -248.043954) (xy 89.84107 -248.196354)
			(xy 89.84107 -248.240804) (xy 90.19667 -248.240804)
		)
		(stroke
			(width 0)
			(type solid)
		)
		(fill yes)
		(layer "In11.Cu")
		(net "M_D_CPU1_SB_CA<5>")
	)
	(gr_poly
		(pts
			(xy 90.19667 -244.940582) (xy 90.14968 -244.788182) (xy 89.88806 -244.788182) (xy 89.84107 -244.940582)
			(xy 89.84107 -244.985032) (xy 90.19667 -244.985032)
		)
		(stroke
			(width 0)
			(type solid)
		)
		(fill yes)
		(layer "In11.Cu")
		(net "M_D_CPU1_SB_DQS_DN<9>")
	)
	(gr_poly
		(pts
			(xy 90.19667 -244.532658) (xy 90.19667 -244.488208) (xy 89.84107 -244.488208) (xy 89.84107 -244.532658)
			(xy 89.88806 -244.685058) (xy 90.14968 -244.685058)
		)
		(stroke
			(width 0)
			(type solid)
		)
		(fill yes)
		(layer "In11.Cu")
		(net "M_D_CPU1_SB_DQS_DN<4>")
	)
	(gr_poly
		(pts
			(xy 90.19667 -240.057178) (xy 90.14968 -239.904778) (xy 89.88806 -239.904778) (xy 89.84107 -240.057178)
			(xy 89.84107 -240.101628) (xy 90.19667 -240.101628)
		)
		(stroke
			(width 0)
			(type solid)
		)
		(fill yes)
		(layer "In11.Cu")
		(net "M_D_CPU1_SB_DQS_DN<0>")
	)
	(gr_poly
		(pts
			(xy 90.19667 -239.649254) (xy 90.19667 -239.604804) (xy 89.84107 -239.604804) (xy 89.84107 -239.649254)
			(xy 89.88806 -239.801654) (xy 90.14968 -239.801654)
		)
		(stroke
			(width 0)
			(type solid)
		)
		(fill yes)
		(layer "In11.Cu")
		(net "M_D_CPU1_SB_DQS_DN<5>")
	)
	(gr_poly
		(pts
			(xy 90.19667 -230.290878) (xy 90.14968 -230.138478) (xy 89.88806 -230.138478) (xy 89.84107 -230.290878)
			(xy 89.84107 -230.335074) (xy 90.19667 -230.335074)
		)
		(stroke
			(width 0)
			(type solid)
		)
		(fill yes)
		(layer "In11.Cu")
		(net "M_D_CPU1_SB_DQ<15>")
	)
	(gr_poly
		(pts
			(xy 90.19667 -229.882446) (xy 90.19667 -229.83825) (xy 89.84107 -229.83825) (xy 89.84107 -229.882446)
			(xy 89.88806 -230.034846) (xy 90.14968 -230.034846)
		)
		(stroke
			(width 0)
			(type solid)
		)
		(fill yes)
		(layer "In11.Cu")
		(net "M_D_CPU1_SB_DQ<24>")
	)
	(gr_poly
		(pts
			(xy 90.202512 -246.568722) (xy 90.155522 -246.416322) (xy 89.893902 -246.416322) (xy 89.846912 -246.568722)
			(xy 89.846912 -246.613172) (xy 90.202512 -246.613172)
		)
		(stroke
			(width 0)
			(type solid)
		)
		(fill yes)
		(layer "In11.Cu")
		(net "M_D_CPU1_SB_CB<6>")
	)
	(gr_poly
		(pts
			(xy 90.20302 -231.919018) (xy 90.15603 -231.766618) (xy 89.89441 -231.766618) (xy 89.84742 -231.919018)
			(xy 89.84742 -231.963214) (xy 90.20302 -231.963214)
		)
		(stroke
			(width 0)
			(type solid)
		)
		(fill yes)
		(layer "In11.Cu")
		(net "M_D_CPU1_SB_DQS_DP<6>")
	)
	(gr_poly
		(pts
			(xy 90.20302 -227.035614) (xy 90.15603 -226.883214) (xy 89.89441 -226.883214) (xy 89.84742 -227.035614)
			(xy 89.84742 -227.07981) (xy 90.20302 -227.07981)
		)
		(stroke
			(width 0)
			(type solid)
		)
		(fill yes)
		(layer "In11.Cu")
		(net "M_D_CPU1_SB_DQS_DP<8>")
	)
	(gr_poly
		(pts
			(xy 90.208608 -247.787922) (xy 90.208608 -247.743472) (xy 89.853008 -247.743472) (xy 89.853008 -247.787922)
			(xy 89.899998 -247.940322) (xy 90.161618 -247.940322)
		)
		(stroke
			(width 0)
			(type solid)
		)
		(fill yes)
		(layer "In11.Cu")
		(net "M_D_CPU1_SB_PAR")
	)
	(gr_poly
		(pts
			(xy 90.312494 -279.354788) (xy 90.265504 -279.202388) (xy 90.003884 -279.202388) (xy 89.956894 -279.354788)
			(xy 89.956894 -279.398984) (xy 90.312494 -279.398984)
		)
		(stroke
			(width 0)
			(type solid)
		)
		(fill yes)
		(layer "In11.Cu")
		(net "M_D_CPU1_SA_DQ<10>")
	)
	(gr_poly
		(pts
			(xy 90.312494 -278.945848) (xy 90.312494 -278.901652) (xy 89.956894 -278.901652) (xy 89.956894 -278.945848)
			(xy 90.003884 -279.098248) (xy 90.265504 -279.098248)
		)
		(stroke
			(width 0)
			(type solid)
		)
		(fill yes)
		(layer "In11.Cu")
		(net "M_D_CPU1_SA_DQ<9>")
	)
	(gr_poly
		(pts
			(xy 90.312494 -276.09927) (xy 90.265504 -275.94687) (xy 90.003884 -275.94687) (xy 89.956894 -276.09927)
			(xy 89.956894 -276.143466) (xy 90.312494 -276.143466)
		)
		(stroke
			(width 0)
			(type solid)
		)
		(fill yes)
		(layer "In11.Cu")
		(net "M_D_CPU1_SA_DQ<14>")
	)
	(gr_poly
		(pts
			(xy 90.312494 -275.690584) (xy 90.312494 -275.646134) (xy 89.956894 -275.646134) (xy 89.956894 -275.690584)
			(xy 90.003884 -275.842984) (xy 90.265504 -275.842984)
		)
		(stroke
			(width 0)
			(type solid)
		)
		(fill yes)
		(layer "In11.Cu")
		(net "M_D_CPU1_SA_DQ<13>")
	)
	(gr_poly
		(pts
			(xy 90.312494 -274.47113) (xy 90.265504 -274.31873) (xy 90.003884 -274.31873) (xy 89.956894 -274.47113)
			(xy 89.956894 -274.51558) (xy 90.312494 -274.51558)
		)
		(stroke
			(width 0)
			(type solid)
		)
		(fill yes)
		(layer "In11.Cu")
		(net "M_D_CPU1_SA_DQ<18>")
	)
	(gr_poly
		(pts
			(xy 90.312494 -274.062698) (xy 90.312494 -274.018248) (xy 89.956894 -274.018248) (xy 89.956894 -274.062698)
			(xy 90.003884 -274.215098) (xy 90.265504 -274.215098)
		)
		(stroke
			(width 0)
			(type solid)
		)
		(fill yes)
		(layer "In11.Cu")
		(net "M_D_CPU1_SA_DQ<17>")
	)
	(gr_poly
		(pts
			(xy 90.312494 -271.215866) (xy 90.265504 -271.063466) (xy 90.003884 -271.063466) (xy 89.956894 -271.215866)
			(xy 89.956894 -271.260062) (xy 90.312494 -271.260062)
		)
		(stroke
			(width 0)
			(type solid)
		)
		(fill yes)
		(layer "In11.Cu")
		(net "M_D_CPU1_SA_DQ<22>")
	)
	(gr_poly
		(pts
			(xy 90.312494 -270.806926) (xy 90.312494 -270.76273) (xy 89.956894 -270.76273) (xy 89.956894 -270.806926)
			(xy 90.003884 -270.959326) (xy 90.265504 -270.959326)
		)
		(stroke
			(width 0)
			(type solid)
		)
		(fill yes)
		(layer "In11.Cu")
		(net "M_D_CPU1_SA_DQ<21>")
	)
	(gr_poly
		(pts
			(xy 90.312494 -269.587726) (xy 90.265504 -269.435326) (xy 90.003884 -269.435326) (xy 89.956894 -269.587726)
			(xy 89.956894 -269.632176) (xy 90.312494 -269.632176)
		)
		(stroke
			(width 0)
			(type solid)
		)
		(fill yes)
		(layer "In11.Cu")
		(net "M_D_CPU1_SA_DQ<26>")
	)
	(gr_poly
		(pts
			(xy 90.312494 -269.179294) (xy 90.312494 -269.134844) (xy 89.956894 -269.134844) (xy 89.956894 -269.179294)
			(xy 90.003884 -269.331694) (xy 90.265504 -269.331694)
		)
		(stroke
			(width 0)
			(type solid)
		)
		(fill yes)
		(layer "In11.Cu")
		(net "M_D_CPU1_SA_DQ<25>")
	)
	(gr_poly
		(pts
			(xy 90.312494 -266.332462) (xy 90.265504 -266.180062) (xy 90.003884 -266.180062) (xy 89.956894 -266.332462)
			(xy 89.956894 -266.376658) (xy 90.312494 -266.376658)
		)
		(stroke
			(width 0)
			(type solid)
		)
		(fill yes)
		(layer "In11.Cu")
		(net "M_D_CPU1_SA_DQ<30>")
	)
	(gr_poly
		(pts
			(xy 90.312494 -265.923522) (xy 90.312494 -265.879326) (xy 89.956894 -265.879326) (xy 89.956894 -265.923522)
			(xy 90.003884 -266.075922) (xy 90.265504 -266.075922)
		)
		(stroke
			(width 0)
			(type solid)
		)
		(fill yes)
		(layer "In11.Cu")
		(net "M_D_CPU1_SA_DQ<29>")
	)
	(gr_poly
		(pts
			(xy 90.312494 -264.70483) (xy 90.265504 -264.55243) (xy 90.003884 -264.55243) (xy 89.956894 -264.70483)
			(xy 89.956894 -264.749026) (xy 90.312494 -264.749026)
		)
		(stroke
			(width 0)
			(type solid)
		)
		(fill yes)
		(layer "In11.Cu")
		(net "M_D_CPU1_SA_CB<2>")
	)
	(gr_poly
		(pts
			(xy 90.312494 -264.29589) (xy 90.312494 -264.251694) (xy 89.956894 -264.251694) (xy 89.956894 -264.29589)
			(xy 90.003884 -264.44829) (xy 90.265504 -264.44829)
		)
		(stroke
			(width 0)
			(type solid)
		)
		(fill yes)
		(layer "In11.Cu")
		(net "M_D_CPU1_SA_CB<1>")
	)
	(gr_poly
		(pts
			(xy 90.312494 -261.449058) (xy 90.265504 -261.296658) (xy 90.003884 -261.296658) (xy 89.956894 -261.449058)
			(xy 89.956894 -261.493508) (xy 90.312494 -261.493508)
		)
		(stroke
			(width 0)
			(type solid)
		)
		(fill yes)
		(layer "In11.Cu")
		(net "M_D_CPU1_SA_CB<6>")
	)
	(gr_poly
		(pts
			(xy 90.312494 -261.040626) (xy 90.312494 -260.996176) (xy 89.956894 -260.996176) (xy 89.956894 -261.040626)
			(xy 90.003884 -261.193026) (xy 90.265504 -261.193026)
		)
		(stroke
			(width 0)
			(type solid)
		)
		(fill yes)
		(layer "In11.Cu")
		(net "M_D_CPU1_SA_CB<5>")
	)
	(gr_poly
		(pts
			(xy 90.312494 -259.412486) (xy 90.312494 -259.36829) (xy 89.956894 -259.36829) (xy 89.956894 -259.412486)
			(xy 90.003884 -259.564886) (xy 90.265504 -259.564886)
		)
		(stroke
			(width 0)
			(type solid)
		)
		(fill yes)
		(layer "In11.Cu")
		(net "M_D_CPU1_SA_CS_N<2>")
	)
	(gr_poly
		(pts
			(xy 90.312494 -256.565654) (xy 90.265504 -256.413254) (xy 90.003884 -256.413254) (xy 89.956894 -256.565654)
			(xy 89.956894 -256.610104) (xy 90.312494 -256.610104)
		)
		(stroke
			(width 0)
			(type solid)
		)
		(fill yes)
		(layer "In11.Cu")
		(net "M_D_CPU1_SA_CA<3>")
	)
	(gr_poly
		(pts
			(xy 90.312494 -256.157222) (xy 90.312494 -256.112772) (xy 89.956894 -256.112772) (xy 89.956894 -256.157222)
			(xy 90.003884 -256.309622) (xy 90.265504 -256.309622)
		)
		(stroke
			(width 0)
			(type solid)
		)
		(fill yes)
		(layer "In11.Cu")
		(net "M_D_CPU1_SA_CA<4>")
	)
	(gr_poly
		(pts
			(xy 90.31478 -262.668258) (xy 90.31478 -262.623808) (xy 89.95918 -262.623808) (xy 89.95918 -262.668258)
			(xy 90.00617 -262.820658) (xy 90.26779 -262.820658)
		)
		(stroke
			(width 0)
			(type solid)
		)
		(fill yes)
		(layer "In11.Cu")
		(net "M_D_CPU1_SA_DQS_DN<9>")
	)
	(gr_poly
		(pts
			(xy 90.31859 -277.726394) (xy 90.2716 -277.573994) (xy 90.00998 -277.573994) (xy 89.96299 -277.726394)
			(xy 89.96299 -277.770844) (xy 90.31859 -277.770844)
		)
		(stroke
			(width 0)
			(type solid)
		)
		(fill yes)
		(layer "In11.Cu")
		(net "M_D_CPU1_SA_DQS_DN<1>")
	)
	(gr_poly
		(pts
			(xy 90.31859 -277.318216) (xy 90.31859 -277.27402) (xy 89.96299 -277.27402) (xy 89.96299 -277.318216)
			(xy 90.00998 -277.470616) (xy 90.2716 -277.470616)
		)
		(stroke
			(width 0)
			(type solid)
		)
		(fill yes)
		(layer "In11.Cu")
		(net "M_D_CPU1_SA_DQS_DN<6>")
	)
	(gr_poly
		(pts
			(xy 90.31859 -272.843498) (xy 90.2716 -272.691098) (xy 90.00998 -272.691098) (xy 89.96299 -272.843498)
			(xy 89.96299 -272.887694) (xy 90.31859 -272.887694)
		)
		(stroke
			(width 0)
			(type solid)
		)
		(fill yes)
		(layer "In11.Cu")
		(net "M_D_CPU1_SA_DQS_DN<2>")
	)
	(gr_poly
		(pts
			(xy 90.31859 -272.435066) (xy 90.31859 -272.39087) (xy 89.96299 -272.39087) (xy 89.96299 -272.435066)
			(xy 90.00998 -272.587466) (xy 90.2716 -272.587466)
		)
		(stroke
			(width 0)
			(type solid)
		)
		(fill yes)
		(layer "In11.Cu")
		(net "M_D_CPU1_SA_DQS_DN<7>")
	)
	(gr_poly
		(pts
			(xy 90.31859 -267.960094) (xy 90.2716 -267.807694) (xy 90.00998 -267.807694) (xy 89.96299 -267.960094)
			(xy 89.96299 -268.00429) (xy 90.31859 -268.00429)
		)
		(stroke
			(width 0)
			(type solid)
		)
		(fill yes)
		(layer "In11.Cu")
		(net "M_D_CPU1_SA_DQS_DN<3>")
	)
	(gr_poly
		(pts
			(xy 90.31859 -267.551662) (xy 90.31859 -267.507466) (xy 89.96299 -267.507466) (xy 89.96299 -267.551662)
			(xy 90.00998 -267.704062) (xy 90.2716 -267.704062)
		)
		(stroke
			(width 0)
			(type solid)
		)
		(fill yes)
		(layer "In11.Cu")
		(net "M_D_CPU1_SA_DQS_DN<8>")
	)
	(gr_poly
		(pts
			(xy 90.31859 -263.07669) (xy 90.2716 -262.92429) (xy 90.00998 -262.92429) (xy 89.96299 -263.07669)
			(xy 89.96299 -263.120886) (xy 90.31859 -263.120886)
		)
		(stroke
			(width 0)
			(type solid)
		)
		(fill yes)
		(layer "In11.Cu")
		(net "M_D_CPU1_SA_DQS_DN<4>")
	)
	(gr_poly
		(pts
			(xy 90.31859 -258.193286) (xy 90.2716 -258.040886) (xy 90.00998 -258.040886) (xy 89.96299 -258.193286)
			(xy 89.96299 -258.237482) (xy 90.31859 -258.237482)
		)
		(stroke
			(width 0)
			(type solid)
		)
		(fill yes)
		(layer "In11.Cu")
		(net "M_D_CPU1_SA_CS_N<1>")
	)
	(gr_poly
		(pts
			(xy 90.31859 -257.784854) (xy 90.31859 -257.740658) (xy 89.96299 -257.740658) (xy 89.96299 -257.784854)
			(xy 90.00998 -257.937254) (xy 90.2716 -257.937254)
		)
		(stroke
			(width 0)
			(type solid)
		)
		(fill yes)
		(layer "In11.Cu")
		(net "M_D_CPU1_SA_CA<0>")
	)
	(gr_poly
		(pts
			(xy 90.530172 -236.250734) (xy 90.568526 -236.228636) (xy 90.390726 -235.920788) (xy 90.352372 -235.942886)
			(xy 90.243914 -236.059726) (xy 90.374724 -236.286294)
		)
		(stroke
			(width 0)
			(type solid)
		)
		(fill yes)
		(layer "In11.Cu")
		(net "M_D_CPU1_SB_DQ<9>")
	)
	(gr_poly
		(pts
			(xy 90.639138 -235.628942) (xy 90.747596 -235.512102) (xy 90.616786 -235.285534) (xy 90.461338 -235.321094)
			(xy 90.422984 -235.343192) (xy 90.600784 -235.65104)
		)
		(stroke
			(width 0)
			(type solid)
		)
		(fill yes)
		(layer "In11.Cu")
		(net "M_D_CPU1_SB_DQ<11>")
	)
	(gr_poly
		(pts
			(xy 90.66657 -245.346474) (xy 90.66657 -245.302024) (xy 90.31097 -245.302024) (xy 90.31097 -245.346474)
			(xy 90.35796 -245.498874) (xy 90.61958 -245.498874)
		)
		(stroke
			(width 0)
			(type solid)
		)
		(fill yes)
		(layer "In11.Cu")
		(net "M_D_CPU1_SB_DQS_DP<9>")
	)
	(gr_poly
		(pts
			(xy 90.66657 -240.46307) (xy 90.66657 -240.41862) (xy 90.31097 -240.41862) (xy 90.31097 -240.46307)
			(xy 90.35796 -240.61547) (xy 90.61958 -240.61547)
		)
		(stroke
			(width 0)
			(type solid)
		)
		(fill yes)
		(layer "In11.Cu")
		(net "M_D_CPU1_SB_DQS_DP<0>")
	)
	(gr_poly
		(pts
			(xy 90.66657 -230.696262) (xy 90.66657 -230.651812) (xy 90.31097 -230.651812) (xy 90.31097 -230.696262)
			(xy 90.35796 -230.848662) (xy 90.61958 -230.848662)
		)
		(stroke
			(width 0)
			(type solid)
		)
		(fill yes)
		(layer "In11.Cu")
		(net "M_D_CPU1_SB_DQ<13>")
	)
	(gr_poly
		(pts
			(xy 90.672666 -249.010678) (xy 90.625676 -248.858278) (xy 90.364056 -248.858278) (xy 90.317066 -249.010678)
			(xy 90.317066 -249.054874) (xy 90.672666 -249.054874)
		)
		(stroke
			(width 0)
			(type solid)
		)
		(fill yes)
		(layer "In11.Cu")
		(net "M_D_CPU1_SB_CA<3>")
	)
	(gr_poly
		(pts
			(xy 90.672666 -244.127274) (xy 90.625676 -243.974874) (xy 90.364056 -243.974874) (xy 90.317066 -244.127274)
			(xy 90.317066 -244.17147) (xy 90.672666 -244.17147)
		)
		(stroke
			(width 0)
			(type solid)
		)
		(fill yes)
		(layer "In11.Cu")
		(net "M_D_CPU1_SB_DQS_DP<4>")
	)
	(gr_poly
		(pts
			(xy 90.672666 -239.24387) (xy 90.625676 -239.09147) (xy 90.364056 -239.09147) (xy 90.317066 -239.24387)
			(xy 90.317066 -239.288066) (xy 90.672666 -239.288066)
		)
		(stroke
			(width 0)
			(type solid)
		)
		(fill yes)
		(layer "In11.Cu")
		(net "M_D_CPU1_SB_DQS_DP<5>")
	)
	(gr_poly
		(pts
			(xy 90.672666 -229.477062) (xy 90.625676 -229.324662) (xy 90.364056 -229.324662) (xy 90.317066 -229.477062)
			(xy 90.317066 -229.521512) (xy 90.672666 -229.521512)
		)
		(stroke
			(width 0)
			(type solid)
		)
		(fill yes)
		(layer "In11.Cu")
		(net "M_D_CPU1_SB_DQ<26>")
	)
	(gr_poly
		(pts
			(xy 90.678508 -247.382538) (xy 90.631518 -247.230138) (xy 90.369898 -247.230138) (xy 90.322908 -247.382538)
			(xy 90.322908 -247.426734) (xy 90.678508 -247.426734)
		)
		(stroke
			(width 0)
			(type solid)
		)
		(fill yes)
		(layer "In11.Cu")
		(net "M_D_CPU1_SB_CA<6>")
	)
	(gr_poly
		(pts
			(xy 90.678508 -246.974106) (xy 90.678508 -246.92991) (xy 90.322908 -246.92991) (xy 90.322908 -246.974106)
			(xy 90.369898 -247.126506) (xy 90.631518 -247.126506)
		)
		(stroke
			(width 0)
			(type solid)
		)
		(fill yes)
		(layer "In11.Cu")
		(net "M_D_CPU1_SB_CB<4>")
	)
	(gr_poly
		(pts
			(xy 90.678508 -245.754906) (xy 90.631518 -245.602506) (xy 90.369898 -245.602506) (xy 90.322908 -245.754906)
			(xy 90.322908 -245.799356) (xy 90.678508 -245.799356)
		)
		(stroke
			(width 0)
			(type solid)
		)
		(fill yes)
		(layer "In11.Cu")
		(net "M_D_CPU1_SB_CB<7>")
	)
	(gr_poly
		(pts
			(xy 90.678508 -240.871502) (xy 90.631518 -240.719102) (xy 90.369898 -240.719102) (xy 90.322908 -240.871502)
			(xy 90.322908 -240.915952) (xy 90.678508 -240.915952)
		)
		(stroke
			(width 0)
			(type solid)
		)
		(fill yes)
		(layer "In11.Cu")
		(net "M_D_CPU1_SB_DQ<3>")
	)
	(gr_poly
		(pts
			(xy 90.678508 -231.104694) (xy 90.631518 -230.952294) (xy 90.369898 -230.952294) (xy 90.322908 -231.104694)
			(xy 90.322908 -231.149144) (xy 90.678508 -231.149144)
		)
		(stroke
			(width 0)
			(type solid)
		)
		(fill yes)
		(layer "In11.Cu")
		(net "M_D_CPU1_SB_DQ<14>")
	)
	(gr_poly
		(pts
			(xy 90.678508 -226.221798) (xy 90.631518 -226.069398) (xy 90.369898 -226.069398) (xy 90.322908 -226.221798)
			(xy 90.322908 -226.265994) (xy 90.678508 -226.265994)
		)
		(stroke
			(width 0)
			(type solid)
		)
		(fill yes)
		(layer "In11.Cu")
		(net "M_D_CPU1_SB_DQ<30>")
	)
	(gr_poly
		(pts
			(xy 90.678508 -225.812858) (xy 90.678508 -225.768662) (xy 90.322908 -225.768662) (xy 90.322908 -225.812858)
			(xy 90.369898 -225.965258) (xy 90.631518 -225.965258)
		)
		(stroke
			(width 0)
			(type solid)
		)
		(fill yes)
		(layer "In11.Cu")
		(net "M_D_CPU1_SB_DQ<29>")
	)
	(gr_poly
		(pts
			(xy 90.681048 -248.602246) (xy 90.681048 -248.557796) (xy 90.325448 -248.557796) (xy 90.325448 -248.602246)
			(xy 90.372438 -248.754646) (xy 90.634058 -248.754646)
		)
		(stroke
			(width 0)
			(type solid)
		)
		(fill yes)
		(layer "In11.Cu")
		(net "M_D_CPU1_SB_CA<4>")
	)
	(gr_poly
		(pts
			(xy 90.681048 -243.718842) (xy 90.681048 -243.674392) (xy 90.325448 -243.674392) (xy 90.325448 -243.718842)
			(xy 90.372438 -243.871242) (xy 90.634058 -243.871242)
		)
		(stroke
			(width 0)
			(type solid)
		)
		(fill yes)
		(layer "In11.Cu")
		(net "M_D_CPU1_SB_CB<0>")
	)
	(gr_poly
		(pts
			(xy 90.681048 -242.499134) (xy 90.634058 -242.346734) (xy 90.372438 -242.346734) (xy 90.325448 -242.499134)
			(xy 90.325448 -242.54333) (xy 90.681048 -242.54333)
		)
		(stroke
			(width 0)
			(type solid)
		)
		(fill yes)
		(layer "In11.Cu")
		(net "M_D_CPU1_SB_CB<3>")
	)
	(gr_poly
		(pts
			(xy 90.681048 -242.090702) (xy 90.681048 -242.046506) (xy 90.325448 -242.046506) (xy 90.325448 -242.090702)
			(xy 90.372438 -242.243102) (xy 90.634058 -242.243102)
		)
		(stroke
			(width 0)
			(type solid)
		)
		(fill yes)
		(layer "In11.Cu")
		(net "M_D_CPU1_SB_DQ<0>")
	)
	(gr_poly
		(pts
			(xy 90.681048 -238.835438) (xy 90.681048 -238.790988) (xy 90.325448 -238.790988) (xy 90.325448 -238.835438)
			(xy 90.372438 -238.987838) (xy 90.634058 -238.987838)
		)
		(stroke
			(width 0)
			(type solid)
		)
		(fill yes)
		(layer "In11.Cu")
		(net "M_D_CPU1_SB_DQ<4>")
	)
	(gr_poly
		(pts
			(xy 90.681048 -237.61573) (xy 90.634058 -237.46333) (xy 90.372438 -237.46333) (xy 90.325448 -237.61573)
			(xy 90.325448 -237.659926) (xy 90.681048 -237.659926)
		)
		(stroke
			(width 0)
			(type solid)
		)
		(fill yes)
		(layer "In11.Cu")
		(net "M_D_CPU1_SB_DQ<7>")
	)
	(gr_poly
		(pts
			(xy 90.681048 -237.207806) (xy 90.681048 -237.163356) (xy 90.325448 -237.163356) (xy 90.325448 -237.207806)
			(xy 90.372438 -237.360206) (xy 90.634058 -237.360206)
		)
		(stroke
			(width 0)
			(type solid)
		)
		(fill yes)
		(layer "In11.Cu")
		(net "M_D_CPU1_SB_DQ<8>")
	)
	(gr_poly
		(pts
			(xy 90.681048 -233.952034) (xy 90.681048 -233.907838) (xy 90.325448 -233.907838) (xy 90.325448 -233.952034)
			(xy 90.372438 -234.104434) (xy 90.634058 -234.104434)
		)
		(stroke
			(width 0)
			(type solid)
		)
		(fill yes)
		(layer "In11.Cu")
		(net "M_D_CPU1_SB_DQS_DP<1>")
	)
	(gr_poly
		(pts
			(xy 90.681048 -232.324402) (xy 90.681048 -232.279952) (xy 90.325448 -232.279952) (xy 90.325448 -232.324402)
			(xy 90.372438 -232.476802) (xy 90.634058 -232.476802)
		)
		(stroke
			(width 0)
			(type solid)
		)
		(fill yes)
		(layer "In11.Cu")
		(net "M_D_CPU1_SB_DQS_DN<6>")
	)
	(gr_poly
		(pts
			(xy 90.681048 -229.06863) (xy 90.681048 -229.024434) (xy 90.325448 -229.024434) (xy 90.325448 -229.06863)
			(xy 90.372438 -229.22103) (xy 90.634058 -229.22103)
		)
		(stroke
			(width 0)
			(type solid)
		)
		(fill yes)
		(layer "In11.Cu")
		(net "M_D_CPU1_SB_DQ<25>")
	)
	(gr_poly
		(pts
			(xy 90.681048 -227.848922) (xy 90.634058 -227.696522) (xy 90.372438 -227.696522) (xy 90.325448 -227.848922)
			(xy 90.325448 -227.893372) (xy 90.681048 -227.893372)
		)
		(stroke
			(width 0)
			(type solid)
		)
		(fill yes)
		(layer "In11.Cu")
		(net "M_D_CPU1_SB_DQS_DN<3>")
	)
	(gr_poly
		(pts
			(xy 90.681048 -227.440998) (xy 90.681048 -227.396548) (xy 90.325448 -227.396548) (xy 90.325448 -227.440998)
			(xy 90.372438 -227.593398) (xy 90.634058 -227.593398)
		)
		(stroke
			(width 0)
			(type solid)
		)
		(fill yes)
		(layer "In11.Cu")
		(net "M_D_CPU1_SB_DQS_DN<8>")
	)
	(gr_poly
		(pts
			(xy 90.774012 -278.132286) (xy 90.774012 -278.08809) (xy 90.418412 -278.08809) (xy 90.418412 -278.132286)
			(xy 90.465402 -278.284686) (xy 90.727022 -278.284686)
		)
		(stroke
			(width 0)
			(type solid)
		)
		(fill yes)
		(layer "In11.Cu")
		(net "M_D_CPU1_SA_DQS_DP<1>")
	)
	(gr_poly
		(pts
			(xy 90.774012 -276.912578) (xy 90.727022 -276.760178) (xy 90.465402 -276.760178) (xy 90.418412 -276.912578)
			(xy 90.418412 -276.957028) (xy 90.774012 -276.957028)
		)
		(stroke
			(width 0)
			(type solid)
		)
		(fill yes)
		(layer "In11.Cu")
		(net "M_D_CPU1_SA_DQS_DP<6>")
	)
	(gr_poly
		(pts
			(xy 90.774012 -272.029174) (xy 90.727022 -271.876774) (xy 90.465402 -271.876774) (xy 90.418412 -272.029174)
			(xy 90.418412 -272.073624) (xy 90.774012 -272.073624)
		)
		(stroke
			(width 0)
			(type solid)
		)
		(fill yes)
		(layer "In11.Cu")
		(net "M_D_CPU1_SA_DQS_DP<7>")
	)
	(gr_poly
		(pts
			(xy 90.774012 -267.14577) (xy 90.727022 -266.99337) (xy 90.465402 -266.99337) (xy 90.418412 -267.14577)
			(xy 90.418412 -267.19022) (xy 90.774012 -267.19022)
		)
		(stroke
			(width 0)
			(type solid)
		)
		(fill yes)
		(layer "In11.Cu")
		(net "M_D_CPU1_SA_DQS_DP<8>")
	)
	(gr_poly
		(pts
			(xy 90.774012 -257.37947) (xy 90.727022 -257.22707) (xy 90.465402 -257.22707) (xy 90.418412 -257.37947)
			(xy 90.418412 -257.423666) (xy 90.774012 -257.423666)
		)
		(stroke
			(width 0)
			(type solid)
		)
		(fill yes)
		(layer "In11.Cu")
		(net "M_D_CPU1_SA_CA<1>")
	)
	(gr_poly
		(pts
			(xy 90.776552 -273.248882) (xy 90.776552 -273.204686) (xy 90.420952 -273.204686) (xy 90.420952 -273.248882)
			(xy 90.467942 -273.401282) (xy 90.729562 -273.401282)
		)
		(stroke
			(width 0)
			(type solid)
		)
		(fill yes)
		(layer "In11.Cu")
		(net "M_D_CPU1_SA_DQS_DP<2>")
	)
	(gr_poly
		(pts
			(xy 90.776552 -268.365478) (xy 90.776552 -268.321282) (xy 90.420952 -268.321282) (xy 90.420952 -268.365478)
			(xy 90.467942 -268.517878) (xy 90.729562 -268.517878)
		)
		(stroke
			(width 0)
			(type solid)
		)
		(fill yes)
		(layer "In11.Cu")
		(net "M_D_CPU1_SA_DQS_DP<3>")
	)
	(gr_poly
		(pts
			(xy 90.776552 -263.482582) (xy 90.776552 -263.438132) (xy 90.420952 -263.438132) (xy 90.420952 -263.482582)
			(xy 90.467942 -263.634982) (xy 90.729562 -263.634982)
		)
		(stroke
			(width 0)
			(type solid)
		)
		(fill yes)
		(layer "In11.Cu")
		(net "M_D_CPU1_SA_DQS_DP<4>")
	)
	(gr_poly
		(pts
			(xy 90.776552 -258.599178) (xy 90.776552 -258.554728) (xy 90.420952 -258.554728) (xy 90.420952 -258.599178)
			(xy 90.467942 -258.751578) (xy 90.729562 -258.751578)
		)
		(stroke
			(width 0)
			(type solid)
		)
		(fill yes)
		(layer "In11.Cu")
		(net "M_D_CPU1_SA_CS_N<3>")
	)
	(gr_poly
		(pts
			(xy 90.779092 -262.262874) (xy 90.732102 -262.110474) (xy 90.470482 -262.110474) (xy 90.423492 -262.262874)
			(xy 90.423492 -262.307324) (xy 90.779092 -262.307324)
		)
		(stroke
			(width 0)
			(type solid)
		)
		(fill yes)
		(layer "In11.Cu")
		(net "M_D_CPU1_SA_DQS_DP<9>")
	)
	(gr_poly
		(pts
			(xy 90.782394 -278.540718) (xy 90.735404 -278.388318) (xy 90.473784 -278.388318) (xy 90.426794 -278.540718)
			(xy 90.426794 -278.585168) (xy 90.782394 -278.585168)
		)
		(stroke
			(width 0)
			(type solid)
		)
		(fill yes)
		(layer "In11.Cu")
		(net "M_D_CPU1_SA_DQ<11>")
	)
	(gr_poly
		(pts
			(xy 90.782394 -276.504146) (xy 90.782394 -276.45995) (xy 90.426794 -276.45995) (xy 90.426794 -276.504146)
			(xy 90.473784 -276.656546) (xy 90.735404 -276.656546)
		)
		(stroke
			(width 0)
			(type solid)
		)
		(fill yes)
		(layer "In11.Cu")
		(net "M_D_CPU1_SA_DQ<12>")
	)
	(gr_poly
		(pts
			(xy 90.782394 -271.620742) (xy 90.782394 -271.576546) (xy 90.426794 -271.576546) (xy 90.426794 -271.620742)
			(xy 90.473784 -271.773142) (xy 90.735404 -271.773142)
		)
		(stroke
			(width 0)
			(type solid)
		)
		(fill yes)
		(layer "In11.Cu")
		(net "M_D_CPU1_SA_DQ<20>")
	)
	(gr_poly
		(pts
			(xy 90.782394 -266.737846) (xy 90.782394 -266.693396) (xy 90.426794 -266.693396) (xy 90.426794 -266.737846)
			(xy 90.473784 -266.890246) (xy 90.735404 -266.890246)
		)
		(stroke
			(width 0)
			(type solid)
		)
		(fill yes)
		(layer "In11.Cu")
		(net "M_D_CPU1_SA_DQ<28>")
	)
	(gr_poly
		(pts
			(xy 90.782394 -261.854442) (xy 90.782394 -261.809992) (xy 90.426794 -261.809992) (xy 90.426794 -261.854442)
			(xy 90.473784 -262.006842) (xy 90.735404 -262.006842)
		)
		(stroke
			(width 0)
			(type solid)
		)
		(fill yes)
		(layer "In11.Cu")
		(net "M_D_CPU1_SA_CB<4>")
	)
	(gr_poly
		(pts
			(xy 90.782394 -256.971038) (xy 90.782394 -256.926588) (xy 90.426794 -256.926588) (xy 90.426794 -256.971038)
			(xy 90.473784 -257.123438) (xy 90.735404 -257.123438)
		)
		(stroke
			(width 0)
			(type solid)
		)
		(fill yes)
		(layer "In11.Cu")
		(net "M_D_CPU1_SA_CA<2>")
	)
	(gr_poly
		(pts
			(xy 90.78849 -279.759918) (xy 90.78849 -279.715722) (xy 90.43289 -279.715722) (xy 90.43289 -279.759918)
			(xy 90.47988 -279.912318) (xy 90.7415 -279.912318)
		)
		(stroke
			(width 0)
			(type solid)
		)
		(fill yes)
		(layer "In11.Cu")
		(net "M_D_CPU1_SA_DQ<8>")
	)
	(gr_poly
		(pts
			(xy 90.78849 -275.284946) (xy 90.7415 -275.132546) (xy 90.47988 -275.132546) (xy 90.43289 -275.284946)
			(xy 90.43289 -275.329142) (xy 90.78849 -275.329142)
		)
		(stroke
			(width 0)
			(type solid)
		)
		(fill yes)
		(layer "In11.Cu")
		(net "M_D_CPU1_SA_DQ<15>")
	)
	(gr_poly
		(pts
			(xy 90.78849 -274.876514) (xy 90.78849 -274.832318) (xy 90.43289 -274.832318) (xy 90.43289 -274.876514)
			(xy 90.47988 -275.028914) (xy 90.7415 -275.028914)
		)
		(stroke
			(width 0)
			(type solid)
		)
		(fill yes)
		(layer "In11.Cu")
		(net "M_D_CPU1_SA_DQ<16>")
	)
	(gr_poly
		(pts
			(xy 90.78849 -273.657314) (xy 90.7415 -273.504914) (xy 90.47988 -273.504914) (xy 90.43289 -273.657314)
			(xy 90.43289 -273.70151) (xy 90.78849 -273.70151)
		)
		(stroke
			(width 0)
			(type solid)
		)
		(fill yes)
		(layer "In11.Cu")
		(net "M_D_CPU1_SA_DQ<19>")
	)
	(gr_poly
		(pts
			(xy 90.78849 -270.401542) (xy 90.7415 -270.249142) (xy 90.47988 -270.249142) (xy 90.43289 -270.401542)
			(xy 90.43289 -270.445992) (xy 90.78849 -270.445992)
		)
		(stroke
			(width 0)
			(type solid)
		)
		(fill yes)
		(layer "In11.Cu")
		(net "M_D_CPU1_SA_DQ<23>")
	)
	(gr_poly
		(pts
			(xy 90.78849 -269.993618) (xy 90.78849 -269.949168) (xy 90.43289 -269.949168) (xy 90.43289 -269.993618)
			(xy 90.47988 -270.146018) (xy 90.7415 -270.146018)
		)
		(stroke
			(width 0)
			(type solid)
		)
		(fill yes)
		(layer "In11.Cu")
		(net "M_D_CPU1_SA_DQ<24>")
	)
	(gr_poly
		(pts
			(xy 90.78849 -268.77391) (xy 90.7415 -268.62151) (xy 90.47988 -268.62151) (xy 90.43289 -268.77391)
			(xy 90.43289 -268.818106) (xy 90.78849 -268.818106)
		)
		(stroke
			(width 0)
			(type solid)
		)
		(fill yes)
		(layer "In11.Cu")
		(net "M_D_CPU1_SA_DQ<27>")
	)
	(gr_poly
		(pts
			(xy 90.78849 -265.518138) (xy 90.7415 -265.365738) (xy 90.47988 -265.365738) (xy 90.43289 -265.518138)
			(xy 90.43289 -265.562588) (xy 90.78849 -265.562588)
		)
		(stroke
			(width 0)
			(type solid)
		)
		(fill yes)
		(layer "In11.Cu")
		(net "M_D_CPU1_SA_DQ<31>")
	)
	(gr_poly
		(pts
			(xy 90.78849 -265.110214) (xy 90.78849 -265.065764) (xy 90.43289 -265.065764) (xy 90.43289 -265.110214)
			(xy 90.47988 -265.262614) (xy 90.7415 -265.262614)
		)
		(stroke
			(width 0)
			(type solid)
		)
		(fill yes)
		(layer "In11.Cu")
		(net "M_D_CPU1_SA_CB<0>")
	)
	(gr_poly
		(pts
			(xy 90.78849 -263.890506) (xy 90.7415 -263.738106) (xy 90.47988 -263.738106) (xy 90.43289 -263.890506)
			(xy 90.43289 -263.934956) (xy 90.78849 -263.934956)
		)
		(stroke
			(width 0)
			(type solid)
		)
		(fill yes)
		(layer "In11.Cu")
		(net "M_D_CPU1_SA_CB<3>")
	)
	(gr_poly
		(pts
			(xy 90.78849 -260.634734) (xy 90.7415 -260.482334) (xy 90.47988 -260.482334) (xy 90.43289 -260.634734)
			(xy 90.43289 -260.679184) (xy 90.78849 -260.679184)
		)
		(stroke
			(width 0)
			(type solid)
		)
		(fill yes)
		(layer "In11.Cu")
		(net "M_D_CPU1_SA_CB<7>")
	)
	(gr_poly
		(pts
			(xy 90.78849 -259.007102) (xy 90.7415 -258.854702) (xy 90.47988 -258.854702) (xy 90.43289 -259.007102)
			(xy 90.43289 -259.051552) (xy 90.78849 -259.051552)
		)
		(stroke
			(width 0)
			(type solid)
		)
		(fill yes)
		(layer "In11.Cu")
		(net "M_D_CPU1_SA_CS_N<0>")
	)
	(gr_poly
		(pts
			(xy 90.78849 -255.751838) (xy 90.7415 -255.599438) (xy 90.47988 -255.599438) (xy 90.43289 -255.751838)
			(xy 90.43289 -255.796034) (xy 90.78849 -255.796034)
		)
		(stroke
			(width 0)
			(type solid)
		)
		(fill yes)
		(layer "In11.Cu")
		(net "M_D_CPU1_SA_CA<5>")
	)
	(gr_poly
		(pts
			(xy 91.13393 -246.568722) (xy 91.08694 -246.416322) (xy 90.82532 -246.416322) (xy 90.77833 -246.568722)
			(xy 90.77833 -246.612918) (xy 91.13393 -246.612918)
		)
		(stroke
			(width 0)
			(type solid)
		)
		(fill yes)
		(layer "In11.Cu")
		(net "M_D_CPU1_SB_CB<6>")
	)
	(gr_poly
		(pts
			(xy 91.13393 -241.685318) (xy 91.08694 -241.532918) (xy 90.82532 -241.532918) (xy 90.77833 -241.685318)
			(xy 90.77833 -241.729514) (xy 91.13393 -241.729514)
		)
		(stroke
			(width 0)
			(type solid)
		)
		(fill yes)
		(layer "In11.Cu")
		(net "M_D_CPU1_SB_DQ<2>")
	)
	(gr_poly
		(pts
			(xy 91.13393 -236.801914) (xy 91.08694 -236.649514) (xy 90.82532 -236.649514) (xy 90.77833 -236.801914)
			(xy 90.77833 -236.84611) (xy 91.13393 -236.84611)
		)
		(stroke
			(width 0)
			(type solid)
		)
		(fill yes)
		(layer "In11.Cu")
		(net "M_D_CPU1_SB_DQ<10>")
	)
	(gr_poly
		(pts
			(xy 91.13647 -249.415554) (xy 91.13647 -249.371358) (xy 90.78087 -249.371358) (xy 90.78087 -249.415554)
			(xy 90.82786 -249.567954) (xy 91.08948 -249.567954)
		)
		(stroke
			(width 0)
			(type solid)
		)
		(fill yes)
		(layer "In11.Cu")
		(net "M_D_CPU1_SB_CA<2>")
	)
	(gr_poly
		(pts
			(xy 91.13647 -248.196354) (xy 91.08948 -248.043954) (xy 90.82786 -248.043954) (xy 90.78087 -248.196354)
			(xy 90.78087 -248.24055) (xy 91.13647 -248.24055)
		)
		(stroke
			(width 0)
			(type solid)
		)
		(fill yes)
		(layer "In11.Cu")
		(net "M_D_CPU1_SB_CA<5>")
	)
	(gr_poly
		(pts
			(xy 91.13647 -247.787922) (xy 91.13647 -247.743726) (xy 90.78087 -247.743726) (xy 90.78087 -247.787922)
			(xy 90.82786 -247.940322) (xy 91.08948 -247.940322)
		)
		(stroke
			(width 0)
			(type solid)
		)
		(fill yes)
		(layer "In11.Cu")
		(net "M_D_CPU1_SB_PAR")
	)
	(gr_poly
		(pts
			(xy 91.13647 -244.53215) (xy 91.13647 -244.487954) (xy 90.78087 -244.487954) (xy 90.78087 -244.53215)
			(xy 90.82786 -244.68455) (xy 91.08948 -244.68455)
		)
		(stroke
			(width 0)
			(type solid)
		)
		(fill yes)
		(layer "In11.Cu")
		(net "M_D_CPU1_SB_DQS_DN<4>")
	)
	(gr_poly
		(pts
			(xy 91.13647 -243.31295) (xy 91.08948 -243.16055) (xy 90.82786 -243.16055) (xy 90.78087 -243.31295)
			(xy 90.78087 -243.3574) (xy 91.13647 -243.3574)
		)
		(stroke
			(width 0)
			(type solid)
		)
		(fill yes)
		(layer "In11.Cu")
		(net "M_D_CPU1_SB_CB<2>")
	)
	(gr_poly
		(pts
			(xy 91.13647 -242.905026) (xy 91.13647 -242.860576) (xy 90.78087 -242.860576) (xy 90.78087 -242.905026)
			(xy 90.82786 -243.057426) (xy 91.08948 -243.057426)
		)
		(stroke
			(width 0)
			(type solid)
		)
		(fill yes)
		(layer "In11.Cu")
		(net "M_D_CPU1_SB_CB<1>")
	)
	(gr_poly
		(pts
			(xy 91.13647 -239.648746) (xy 91.13647 -239.60455) (xy 90.78087 -239.60455) (xy 90.78087 -239.648746)
			(xy 90.82786 -239.801146) (xy 91.08948 -239.801146)
		)
		(stroke
			(width 0)
			(type solid)
		)
		(fill yes)
		(layer "In11.Cu")
		(net "M_D_CPU1_SB_DQS_DN<5>")
	)
	(gr_poly
		(pts
			(xy 91.13647 -238.429546) (xy 91.08948 -238.277146) (xy 90.82786 -238.277146) (xy 90.78087 -238.429546)
			(xy 90.78087 -238.473996) (xy 91.13647 -238.473996)
		)
		(stroke
			(width 0)
			(type solid)
		)
		(fill yes)
		(layer "In11.Cu")
		(net "M_D_CPU1_SB_DQ<6>")
	)
	(gr_poly
		(pts
			(xy 91.13647 -238.021622) (xy 91.13647 -237.977172) (xy 90.78087 -237.977172) (xy 90.78087 -238.021622)
			(xy 90.82786 -238.174022) (xy 91.08948 -238.174022)
		)
		(stroke
			(width 0)
			(type solid)
		)
		(fill yes)
		(layer "In11.Cu")
		(net "M_D_CPU1_SB_DQ<5>")
	)
	(gr_poly
		(pts
			(xy 91.13647 -233.546142) (xy 91.08948 -233.393742) (xy 90.82786 -233.393742) (xy 90.78087 -233.546142)
			(xy 90.78087 -233.590592) (xy 91.13647 -233.590592)
		)
		(stroke
			(width 0)
			(type solid)
		)
		(fill yes)
		(layer "In11.Cu")
		(net "M_D_CPU1_SB_DQS_DN<1>")
	)
	(gr_poly
		(pts
			(xy 91.13647 -229.882446) (xy 91.13647 -229.837996) (xy 90.78087 -229.837996) (xy 90.78087 -229.882446)
			(xy 90.82786 -230.034846) (xy 91.08948 -230.034846)
		)
		(stroke
			(width 0)
			(type solid)
		)
		(fill yes)
		(layer "In11.Cu")
		(net "M_D_CPU1_SB_DQ<24>")
	)
	(gr_poly
		(pts
			(xy 91.13647 -228.663246) (xy 91.08948 -228.510846) (xy 90.82786 -228.510846) (xy 90.78087 -228.663246)
			(xy 90.78087 -228.707442) (xy 91.13647 -228.707442)
		)
		(stroke
			(width 0)
			(type solid)
		)
		(fill yes)
		(layer "In11.Cu")
		(net "M_D_CPU1_SB_DQ<27>")
	)
	(gr_poly
		(pts
			(xy 91.13647 -228.254814) (xy 91.13647 -228.210618) (xy 90.78087 -228.210618) (xy 90.78087 -228.254814)
			(xy 90.82786 -228.407214) (xy 91.08948 -228.407214)
		)
		(stroke
			(width 0)
			(type solid)
		)
		(fill yes)
		(layer "In11.Cu")
		(net "M_D_CPU1_SB_DQS_DP<3>")
	)
	(gr_poly
		(pts
			(xy 91.142312 -246.16029) (xy 91.142312 -246.11584) (xy 90.786712 -246.11584) (xy 90.786712 -246.16029)
			(xy 90.833702 -246.31269) (xy 91.095322 -246.31269)
		)
		(stroke
			(width 0)
			(type solid)
		)
		(fill yes)
		(layer "In11.Cu")
		(net "M_D_CPU1_SB_CB<5>")
	)
	(gr_poly
		(pts
			(xy 91.142312 -241.276886) (xy 91.142312 -241.232436) (xy 90.786712 -241.232436) (xy 90.786712 -241.276886)
			(xy 90.833702 -241.429286) (xy 91.095322 -241.429286)
		)
		(stroke
			(width 0)
			(type solid)
		)
		(fill yes)
		(layer "In11.Cu")
		(net "M_D_CPU1_SB_DQ<1>")
	)
	(gr_poly
		(pts
			(xy 91.142312 -236.393482) (xy 91.142312 -236.349286) (xy 90.786712 -236.349286) (xy 90.786712 -236.393482)
			(xy 90.833702 -236.545882) (xy 91.095322 -236.545882)
		)
		(stroke
			(width 0)
			(type solid)
		)
		(fill yes)
		(layer "In11.Cu")
		(net "M_D_CPU1_SB_DQ<9>")
	)
	(gr_poly
		(pts
			(xy 91.142312 -231.919018) (xy 91.095322 -231.766618) (xy 90.833702 -231.766618) (xy 90.786712 -231.919018)
			(xy 90.786712 -231.963214) (xy 91.142312 -231.963214)
		)
		(stroke
			(width 0)
			(type solid)
		)
		(fill yes)
		(layer "In11.Cu")
		(net "M_D_CPU1_SB_DQS_DP<6>")
	)
	(gr_poly
		(pts
			(xy 91.142312 -231.510078) (xy 91.142312 -231.465882) (xy 90.786712 -231.465882) (xy 90.786712 -231.510078)
			(xy 90.833702 -231.662478) (xy 91.095322 -231.662478)
		)
		(stroke
			(width 0)
			(type solid)
		)
		(fill yes)
		(layer "In11.Cu")
		(net "M_D_CPU1_SB_DQ<12>")
	)
	(gr_poly
		(pts
			(xy 91.142312 -227.035614) (xy 91.095322 -226.883214) (xy 90.833702 -226.883214) (xy 90.786712 -227.035614)
			(xy 90.786712 -227.07981) (xy 91.142312 -227.07981)
		)
		(stroke
			(width 0)
			(type solid)
		)
		(fill yes)
		(layer "In11.Cu")
		(net "M_D_CPU1_SB_DQS_DP<8>")
	)
	(gr_poly
		(pts
			(xy 91.142312 -225.407474) (xy 91.095322 -225.255074) (xy 90.833702 -225.255074) (xy 90.786712 -225.407474)
			(xy 90.786712 -225.451924) (xy 91.142312 -225.451924)
		)
		(stroke
			(width 0)
			(type solid)
		)
		(fill yes)
		(layer "In11.Cu")
		(net "M_D_CPU1_SB_DQ<31>")
	)
	(gr_poly
		(pts
			(xy 91.148408 -244.94109) (xy 91.101418 -244.78869) (xy 90.839798 -244.78869) (xy 90.792808 -244.94109)
			(xy 90.792808 -244.985286) (xy 91.148408 -244.985286)
		)
		(stroke
			(width 0)
			(type solid)
		)
		(fill yes)
		(layer "In11.Cu")
		(net "M_D_CPU1_SB_DQS_DN<9>")
	)
	(gr_poly
		(pts
			(xy 91.148408 -240.057686) (xy 91.101418 -239.905286) (xy 90.839798 -239.905286) (xy 90.792808 -240.057686)
			(xy 90.792808 -240.101882) (xy 91.148408 -240.101882)
		)
		(stroke
			(width 0)
			(type solid)
		)
		(fill yes)
		(layer "In11.Cu")
		(net "M_D_CPU1_SB_DQS_DN<0>")
	)
	(gr_poly
		(pts
			(xy 91.148408 -230.290878) (xy 91.101418 -230.138478) (xy 90.839798 -230.138478) (xy 90.792808 -230.290878)
			(xy 90.792808 -230.335328) (xy 91.148408 -230.335328)
		)
		(stroke
			(width 0)
			(type solid)
		)
		(fill yes)
		(layer "In11.Cu")
		(net "M_D_CPU1_SB_DQ<15>")
	)
	(gr_poly
		(pts
			(xy 91.148408 -226.627182) (xy 91.148408 -226.582732) (xy 90.792808 -226.582732) (xy 90.792808 -226.627182)
			(xy 90.839798 -226.779582) (xy 91.101418 -226.779582)
		)
		(stroke
			(width 0)
			(type solid)
		)
		(fill yes)
		(layer "In11.Cu")
		(net "M_D_CPU1_SB_DQ<28>")
	)
	(gr_poly
		(pts
			(xy 91.243912 -279.354534) (xy 91.196922 -279.202134) (xy 90.935302 -279.202134) (xy 90.888312 -279.354534)
			(xy 90.888312 -279.39873) (xy 91.243912 -279.39873)
		)
		(stroke
			(width 0)
			(type solid)
		)
		(fill yes)
		(layer "In11.Cu")
		(net "M_D_CPU1_SA_DQ<10>")
	)
	(gr_poly
		(pts
			(xy 91.243912 -275.690584) (xy 91.243912 -275.646388) (xy 90.888312 -275.646388) (xy 90.888312 -275.690584)
			(xy 90.935302 -275.842984) (xy 91.196922 -275.842984)
		)
		(stroke
			(width 0)
			(type solid)
		)
		(fill yes)
		(layer "In11.Cu")
		(net "M_D_CPU1_SA_DQ<13>")
	)
	(gr_poly
		(pts
			(xy 91.243912 -270.807434) (xy 91.243912 -270.762984) (xy 90.888312 -270.762984) (xy 90.888312 -270.807434)
			(xy 90.935302 -270.959834) (xy 91.196922 -270.959834)
		)
		(stroke
			(width 0)
			(type solid)
		)
		(fill yes)
		(layer "In11.Cu")
		(net "M_D_CPU1_SA_DQ<21>")
	)
	(gr_poly
		(pts
			(xy 91.243912 -265.92403) (xy 91.243912 -265.87958) (xy 90.888312 -265.87958) (xy 90.888312 -265.92403)
			(xy 90.935302 -266.07643) (xy 91.196922 -266.07643)
		)
		(stroke
			(width 0)
			(type solid)
		)
		(fill yes)
		(layer "In11.Cu")
		(net "M_D_CPU1_SA_DQ<29>")
	)
	(gr_poly
		(pts
			(xy 91.243912 -261.040626) (xy 91.243912 -260.99643) (xy 90.888312 -260.99643) (xy 90.888312 -261.040626)
			(xy 90.935302 -261.193026) (xy 91.196922 -261.193026)
		)
		(stroke
			(width 0)
			(type solid)
		)
		(fill yes)
		(layer "In11.Cu")
		(net "M_D_CPU1_SA_CB<5>")
	)
	(gr_poly
		(pts
			(xy 91.243912 -256.157222) (xy 91.243912 -256.113026) (xy 90.888312 -256.113026) (xy 90.888312 -256.157222)
			(xy 90.935302 -256.309622) (xy 91.196922 -256.309622)
		)
		(stroke
			(width 0)
			(type solid)
		)
		(fill yes)
		(layer "In11.Cu")
		(net "M_D_CPU1_SA_CA<4>")
	)
	(gr_poly
		(pts
			(xy 91.246452 -274.47113) (xy 91.199462 -274.31873) (xy 90.937842 -274.31873) (xy 90.890852 -274.47113)
			(xy 90.890852 -274.515326) (xy 91.246452 -274.515326)
		)
		(stroke
			(width 0)
			(type solid)
		)
		(fill yes)
		(layer "In11.Cu")
		(net "M_D_CPU1_SA_DQ<18>")
	)
	(gr_poly
		(pts
			(xy 91.246452 -274.062698) (xy 91.246452 -274.018502) (xy 90.890852 -274.018502) (xy 90.890852 -274.062698)
			(xy 90.937842 -274.215098) (xy 91.199462 -274.215098)
		)
		(stroke
			(width 0)
			(type solid)
		)
		(fill yes)
		(layer "In11.Cu")
		(net "M_D_CPU1_SA_DQ<17>")
	)
	(gr_poly
		(pts
			(xy 91.246452 -272.843498) (xy 91.199462 -272.691098) (xy 90.937842 -272.691098) (xy 90.890852 -272.843498)
			(xy 90.890852 -272.887948) (xy 91.246452 -272.887948)
		)
		(stroke
			(width 0)
			(type solid)
		)
		(fill yes)
		(layer "In11.Cu")
		(net "M_D_CPU1_SA_DQS_DN<2>")
	)
	(gr_poly
		(pts
			(xy 91.246452 -269.587726) (xy 91.199462 -269.435326) (xy 90.937842 -269.435326) (xy 90.890852 -269.587726)
			(xy 90.890852 -269.631922) (xy 91.246452 -269.631922)
		)
		(stroke
			(width 0)
			(type solid)
		)
		(fill yes)
		(layer "In11.Cu")
		(net "M_D_CPU1_SA_DQ<26>")
	)
	(gr_poly
		(pts
			(xy 91.246452 -269.179294) (xy 91.246452 -269.135098) (xy 90.890852 -269.135098) (xy 90.890852 -269.179294)
			(xy 90.937842 -269.331694) (xy 91.199462 -269.331694)
		)
		(stroke
			(width 0)
			(type solid)
		)
		(fill yes)
		(layer "In11.Cu")
		(net "M_D_CPU1_SA_DQ<25>")
	)
	(gr_poly
		(pts
			(xy 91.246452 -267.960094) (xy 91.199462 -267.807694) (xy 90.937842 -267.807694) (xy 90.890852 -267.960094)
			(xy 90.890852 -268.004544) (xy 91.246452 -268.004544)
		)
		(stroke
			(width 0)
			(type solid)
		)
		(fill yes)
		(layer "In11.Cu")
		(net "M_D_CPU1_SA_DQS_DN<3>")
	)
	(gr_poly
		(pts
			(xy 91.246452 -264.704322) (xy 91.199462 -264.551922) (xy 90.937842 -264.551922) (xy 90.890852 -264.704322)
			(xy 90.890852 -264.748772) (xy 91.246452 -264.748772)
		)
		(stroke
			(width 0)
			(type solid)
		)
		(fill yes)
		(layer "In11.Cu")
		(net "M_D_CPU1_SA_CB<2>")
	)
	(gr_poly
		(pts
			(xy 91.246452 -264.296398) (xy 91.246452 -264.251948) (xy 90.890852 -264.251948) (xy 90.890852 -264.296398)
			(xy 90.937842 -264.448798) (xy 91.199462 -264.448798)
		)
		(stroke
			(width 0)
			(type solid)
		)
		(fill yes)
		(layer "In11.Cu")
		(net "M_D_CPU1_SA_CB<1>")
	)
	(gr_poly
		(pts
			(xy 91.246452 -263.07669) (xy 91.199462 -262.92429) (xy 90.937842 -262.92429) (xy 90.890852 -263.07669)
			(xy 90.890852 -263.12114) (xy 91.246452 -263.12114)
		)
		(stroke
			(width 0)
			(type solid)
		)
		(fill yes)
		(layer "In11.Cu")
		(net "M_D_CPU1_SA_DQS_DN<4>")
	)
	(gr_poly
		(pts
			(xy 91.246452 -259.412994) (xy 91.246452 -259.368544) (xy 90.890852 -259.368544) (xy 90.890852 -259.412994)
			(xy 90.937842 -259.565394) (xy 91.199462 -259.565394)
		)
		(stroke
			(width 0)
			(type solid)
		)
		(fill yes)
		(layer "In11.Cu")
		(net "M_D_CPU1_SA_CS_N<2>")
	)
	(gr_poly
		(pts
			(xy 91.246452 -258.193286) (xy 91.199462 -258.040886) (xy 90.937842 -258.040886) (xy 90.890852 -258.193286)
			(xy 90.890852 -258.237736) (xy 91.246452 -258.237736)
		)
		(stroke
			(width 0)
			(type solid)
		)
		(fill yes)
		(layer "In11.Cu")
		(net "M_D_CPU1_SA_CS_N<1>")
	)
	(gr_poly
		(pts
			(xy 91.252294 -278.945848) (xy 91.252294 -278.901652) (xy 90.896694 -278.901652) (xy 90.896694 -278.945848)
			(xy 90.943684 -279.098248) (xy 91.205304 -279.098248)
		)
		(stroke
			(width 0)
			(type solid)
		)
		(fill yes)
		(layer "In11.Cu")
		(net "M_D_CPU1_SA_DQ<9>")
	)
	(gr_poly
		(pts
			(xy 91.252294 -276.09927) (xy 91.205304 -275.94687) (xy 90.943684 -275.94687) (xy 90.896694 -276.09927)
			(xy 90.896694 -276.143466) (xy 91.252294 -276.143466)
		)
		(stroke
			(width 0)
			(type solid)
		)
		(fill yes)
		(layer "In11.Cu")
		(net "M_D_CPU1_SA_DQ<14>")
	)
	(gr_poly
		(pts
			(xy 91.252294 -271.215866) (xy 91.205304 -271.063466) (xy 90.943684 -271.063466) (xy 90.896694 -271.215866)
			(xy 90.896694 -271.260062) (xy 91.252294 -271.260062)
		)
		(stroke
			(width 0)
			(type solid)
		)
		(fill yes)
		(layer "In11.Cu")
		(net "M_D_CPU1_SA_DQ<22>")
	)
	(gr_poly
		(pts
			(xy 91.252294 -266.332462) (xy 91.205304 -266.180062) (xy 90.943684 -266.180062) (xy 90.896694 -266.332462)
			(xy 90.896694 -266.376658) (xy 91.252294 -266.376658)
		)
		(stroke
			(width 0)
			(type solid)
		)
		(fill yes)
		(layer "In11.Cu")
		(net "M_D_CPU1_SA_DQ<30>")
	)
	(gr_poly
		(pts
			(xy 91.252294 -261.449058) (xy 91.205304 -261.296658) (xy 90.943684 -261.296658) (xy 90.896694 -261.449058)
			(xy 90.896694 -261.493508) (xy 91.252294 -261.493508)
		)
		(stroke
			(width 0)
			(type solid)
		)
		(fill yes)
		(layer "In11.Cu")
		(net "M_D_CPU1_SA_CB<6>")
	)
	(gr_poly
		(pts
			(xy 91.252294 -256.565654) (xy 91.205304 -256.413254) (xy 90.943684 -256.413254) (xy 90.896694 -256.565654)
			(xy 90.896694 -256.610104) (xy 91.252294 -256.610104)
		)
		(stroke
			(width 0)
			(type solid)
		)
		(fill yes)
		(layer "In11.Cu")
		(net "M_D_CPU1_SA_CA<3>")
	)
	(gr_poly
		(pts
			(xy 91.25585 -262.668258) (xy 91.25585 -262.623808) (xy 90.90025 -262.623808) (xy 90.90025 -262.668258)
			(xy 90.94724 -262.820658) (xy 91.20886 -262.820658)
		)
		(stroke
			(width 0)
			(type solid)
		)
		(fill yes)
		(layer "In11.Cu")
		(net "M_D_CPU1_SA_DQS_DN<9>")
	)
	(gr_poly
		(pts
			(xy 91.25839 -277.726902) (xy 91.2114 -277.574502) (xy 90.94978 -277.574502) (xy 90.90279 -277.726902)
			(xy 90.90279 -277.771098) (xy 91.25839 -277.771098)
		)
		(stroke
			(width 0)
			(type solid)
		)
		(fill yes)
		(layer "In11.Cu")
		(net "M_D_CPU1_SA_DQS_DN<1>")
	)
	(gr_poly
		(pts
			(xy 91.25839 -277.317962) (xy 91.25839 -277.273766) (xy 90.90279 -277.273766) (xy 90.90279 -277.317962)
			(xy 90.94978 -277.470362) (xy 91.2114 -277.470362)
		)
		(stroke
			(width 0)
			(type solid)
		)
		(fill yes)
		(layer "In11.Cu")
		(net "M_D_CPU1_SA_DQS_DN<6>")
	)
	(gr_poly
		(pts
			(xy 91.25839 -272.435066) (xy 91.25839 -272.390616) (xy 90.90279 -272.390616) (xy 90.90279 -272.435066)
			(xy 90.94978 -272.587466) (xy 91.2114 -272.587466)
		)
		(stroke
			(width 0)
			(type solid)
		)
		(fill yes)
		(layer "In11.Cu")
		(net "M_D_CPU1_SA_DQS_DN<7>")
	)
	(gr_poly
		(pts
			(xy 91.25839 -267.551662) (xy 91.25839 -267.507212) (xy 90.90279 -267.507212) (xy 90.90279 -267.551662)
			(xy 90.94978 -267.704062) (xy 91.2114 -267.704062)
		)
		(stroke
			(width 0)
			(type solid)
		)
		(fill yes)
		(layer "In11.Cu")
		(net "M_D_CPU1_SA_DQS_DN<8>")
	)
	(gr_poly
		(pts
			(xy 91.25839 -257.784854) (xy 91.25839 -257.740404) (xy 90.90279 -257.740404) (xy 90.90279 -257.784854)
			(xy 90.94978 -257.937254) (xy 91.2114 -257.937254)
		)
		(stroke
			(width 0)
			(type solid)
		)
		(fill yes)
		(layer "In11.Cu")
		(net "M_D_CPU1_SA_CA<0>")
	)
	(gr_poly
		(pts
			(xy 91.60637 -247.382538) (xy 91.55938 -247.230138) (xy 91.29776 -247.230138) (xy 91.25077 -247.382538)
			(xy 91.25077 -247.426988) (xy 91.60637 -247.426988)
		)
		(stroke
			(width 0)
			(type solid)
		)
		(fill yes)
		(layer "In11.Cu")
		(net "M_D_CPU1_SB_CA<6>")
	)
	(gr_poly
		(pts
			(xy 91.60637 -237.61573) (xy 91.55938 -237.46333) (xy 91.29776 -237.46333) (xy 91.25077 -237.61573)
			(xy 91.25077 -237.66018) (xy 91.60637 -237.66018)
		)
		(stroke
			(width 0)
			(type solid)
		)
		(fill yes)
		(layer "In11.Cu")
		(net "M_D_CPU1_SB_DQ<7>")
	)
	(gr_poly
		(pts
			(xy 91.60637 -227.84943) (xy 91.55938 -227.69703) (xy 91.29776 -227.69703) (xy 91.25077 -227.84943)
			(xy 91.25077 -227.893626) (xy 91.60637 -227.893626)
		)
		(stroke
			(width 0)
			(type solid)
		)
		(fill yes)
		(layer "In11.Cu")
		(net "M_D_CPU1_SB_DQS_DN<3>")
	)
	(gr_poly
		(pts
			(xy 91.60637 -227.44049) (xy 91.60637 -227.396294) (xy 91.25077 -227.396294) (xy 91.25077 -227.44049)
			(xy 91.29776 -227.59289) (xy 91.55938 -227.59289)
		)
		(stroke
			(width 0)
			(type solid)
		)
		(fill yes)
		(layer "In11.Cu")
		(net "M_D_CPU1_SB_DQS_DN<8>")
	)
	(gr_poly
		(pts
			(xy 91.60637 -226.22129) (xy 91.55938 -226.06889) (xy 91.29776 -226.06889) (xy 91.25077 -226.22129)
			(xy 91.25077 -226.26574) (xy 91.60637 -226.26574)
		)
		(stroke
			(width 0)
			(type solid)
		)
		(fill yes)
		(layer "In11.Cu")
		(net "M_D_CPU1_SB_DQ<30>")
	)
	(gr_poly
		(pts
			(xy 91.612466 -248.601738) (xy 91.612466 -248.557542) (xy 91.256866 -248.557542) (xy 91.256866 -248.601738)
			(xy 91.303856 -248.754138) (xy 91.565476 -248.754138)
		)
		(stroke
			(width 0)
			(type solid)
		)
		(fill yes)
		(layer "In11.Cu")
		(net "M_D_CPU1_SB_CA<4>")
	)
	(gr_poly
		(pts
			(xy 91.612466 -243.718334) (xy 91.612466 -243.674138) (xy 91.256866 -243.674138) (xy 91.256866 -243.718334)
			(xy 91.303856 -243.870734) (xy 91.565476 -243.870734)
		)
		(stroke
			(width 0)
			(type solid)
		)
		(fill yes)
		(layer "In11.Cu")
		(net "M_D_CPU1_SB_CB<0>")
	)
	(gr_poly
		(pts
			(xy 91.612466 -242.499134) (xy 91.565476 -242.346734) (xy 91.303856 -242.346734) (xy 91.256866 -242.499134)
			(xy 91.256866 -242.543584) (xy 91.612466 -242.543584)
		)
		(stroke
			(width 0)
			(type solid)
		)
		(fill yes)
		(layer "In11.Cu")
		(net "M_D_CPU1_SB_CB<3>")
	)
	(gr_poly
		(pts
			(xy 91.612466 -238.83493) (xy 91.612466 -238.790734) (xy 91.256866 -238.790734) (xy 91.256866 -238.83493)
			(xy 91.303856 -238.98733) (xy 91.565476 -238.98733)
		)
		(stroke
			(width 0)
			(type solid)
		)
		(fill yes)
		(layer "In11.Cu")
		(net "M_D_CPU1_SB_DQ<4>")
	)
	(gr_poly
		(pts
			(xy 91.612466 -233.952034) (xy 91.612466 -233.907584) (xy 91.256866 -233.907584) (xy 91.256866 -233.952034)
			(xy 91.303856 -234.104434) (xy 91.565476 -234.104434)
		)
		(stroke
			(width 0)
			(type solid)
		)
		(fill yes)
		(layer "In11.Cu")
		(net "M_D_CPU1_SB_DQS_DP<1>")
	)
	(gr_poly
		(pts
			(xy 91.612466 -229.06863) (xy 91.612466 -229.02418) (xy 91.256866 -229.02418) (xy 91.256866 -229.06863)
			(xy 91.303856 -229.22103) (xy 91.565476 -229.22103)
		)
		(stroke
			(width 0)
			(type solid)
		)
		(fill yes)
		(layer "In11.Cu")
		(net "M_D_CPU1_SB_DQ<25>")
	)
	(gr_poly
		(pts
			(xy 91.618308 -246.974106) (xy 91.618308 -246.929656) (xy 91.262708 -246.929656) (xy 91.262708 -246.974106)
			(xy 91.309698 -247.126506) (xy 91.571318 -247.126506)
		)
		(stroke
			(width 0)
			(type solid)
		)
		(fill yes)
		(layer "In11.Cu")
		(net "M_D_CPU1_SB_CB<4>")
	)
	(gr_poly
		(pts
			(xy 91.618308 -245.754906) (xy 91.571318 -245.602506) (xy 91.309698 -245.602506) (xy 91.262708 -245.754906)
			(xy 91.262708 -245.799102) (xy 91.618308 -245.799102)
		)
		(stroke
			(width 0)
			(type solid)
		)
		(fill yes)
		(layer "In11.Cu")
		(net "M_D_CPU1_SB_CB<7>")
	)
	(gr_poly
		(pts
			(xy 91.618308 -245.346474) (xy 91.618308 -245.302278) (xy 91.262708 -245.302278) (xy 91.262708 -245.346474)
			(xy 91.309698 -245.498874) (xy 91.571318 -245.498874)
		)
		(stroke
			(width 0)
			(type solid)
		)
		(fill yes)
		(layer "In11.Cu")
		(net "M_D_CPU1_SB_DQS_DP<9>")
	)
	(gr_poly
		(pts
			(xy 91.618308 -240.871502) (xy 91.571318 -240.719102) (xy 91.309698 -240.719102) (xy 91.262708 -240.871502)
			(xy 91.262708 -240.915698) (xy 91.618308 -240.915698)
		)
		(stroke
			(width 0)
			(type solid)
		)
		(fill yes)
		(layer "In11.Cu")
		(net "M_D_CPU1_SB_DQ<3>")
	)
	(gr_poly
		(pts
			(xy 91.618308 -240.46307) (xy 91.618308 -240.418874) (xy 91.262708 -240.418874) (xy 91.262708 -240.46307)
			(xy 91.309698 -240.61547) (xy 91.571318 -240.61547)
		)
		(stroke
			(width 0)
			(type solid)
		)
		(fill yes)
		(layer "In11.Cu")
		(net "M_D_CPU1_SB_DQS_DP<0>")
	)
	(gr_poly
		(pts
			(xy 91.618308 -237.207298) (xy 91.618308 -237.163102) (xy 91.262708 -237.163102) (xy 91.262708 -237.207298)
			(xy 91.309698 -237.359698) (xy 91.571318 -237.359698)
		)
		(stroke
			(width 0)
			(type solid)
		)
		(fill yes)
		(layer "In11.Cu")
		(net "M_D_CPU1_SB_DQ<8>")
	)
	(gr_poly
		(pts
			(xy 91.618308 -235.988098) (xy 91.571318 -235.835698) (xy 91.309698 -235.835698) (xy 91.262708 -235.988098)
			(xy 91.262708 -236.032294) (xy 91.618308 -236.032294)
		)
		(stroke
			(width 0)
			(type solid)
		)
		(fill yes)
		(layer "In11.Cu")
		(net "M_D_CPU1_SB_DQ<11>")
	)
	(gr_poly
		(pts
			(xy 91.618308 -232.323894) (xy 91.618308 -232.279698) (xy 91.262708 -232.279698) (xy 91.262708 -232.323894)
			(xy 91.309698 -232.476294) (xy 91.571318 -232.476294)
		)
		(stroke
			(width 0)
			(type solid)
		)
		(fill yes)
		(layer "In11.Cu")
		(net "M_D_CPU1_SB_DQS_DN<6>")
	)
	(gr_poly
		(pts
			(xy 91.618308 -231.104694) (xy 91.571318 -230.952294) (xy 91.309698 -230.952294) (xy 91.262708 -231.104694)
			(xy 91.262708 -231.14889) (xy 91.618308 -231.14889)
		)
		(stroke
			(width 0)
			(type solid)
		)
		(fill yes)
		(layer "In11.Cu")
		(net "M_D_CPU1_SB_DQ<14>")
	)
	(gr_poly
		(pts
			(xy 91.618308 -230.696262) (xy 91.618308 -230.652066) (xy 91.262708 -230.652066) (xy 91.262708 -230.696262)
			(xy 91.309698 -230.848662) (xy 91.571318 -230.848662)
		)
		(stroke
			(width 0)
			(type solid)
		)
		(fill yes)
		(layer "In11.Cu")
		(net "M_D_CPU1_SB_DQ<13>")
	)
	(gr_poly
		(pts
			(xy 91.618308 -225.813366) (xy 91.618308 -225.768916) (xy 91.262708 -225.768916) (xy 91.262708 -225.813366)
			(xy 91.309698 -225.965766) (xy 91.571318 -225.965766)
		)
		(stroke
			(width 0)
			(type solid)
		)
		(fill yes)
		(layer "In11.Cu")
		(net "M_D_CPU1_SB_DQ<29>")
	)
	(gr_poly
		(pts
			(xy 91.620848 -249.01017) (xy 91.573858 -248.85777) (xy 91.312238 -248.85777) (xy 91.265248 -249.01017)
			(xy 91.265248 -249.05462) (xy 91.620848 -249.05462)
		)
		(stroke
			(width 0)
			(type solid)
		)
		(fill yes)
		(layer "In11.Cu")
		(net "M_D_CPU1_SB_CA<3>")
	)
	(gr_poly
		(pts
			(xy 91.620848 -244.126766) (xy 91.573858 -243.974366) (xy 91.312238 -243.974366) (xy 91.265248 -244.126766)
			(xy 91.265248 -244.171216) (xy 91.620848 -244.171216)
		)
		(stroke
			(width 0)
			(type solid)
		)
		(fill yes)
		(layer "In11.Cu")
		(net "M_D_CPU1_SB_DQS_DP<4>")
	)
	(gr_poly
		(pts
			(xy 91.620848 -242.090702) (xy 91.620848 -242.046506) (xy 91.265248 -242.046506) (xy 91.265248 -242.090702)
			(xy 91.312238 -242.243102) (xy 91.573858 -242.243102)
		)
		(stroke
			(width 0)
			(type solid)
		)
		(fill yes)
		(layer "In11.Cu")
		(net "M_D_CPU1_SB_DQ<0>")
	)
	(gr_poly
		(pts
			(xy 91.620848 -239.243362) (xy 91.573858 -239.090962) (xy 91.312238 -239.090962) (xy 91.265248 -239.243362)
			(xy 91.265248 -239.287812) (xy 91.620848 -239.287812)
		)
		(stroke
			(width 0)
			(type solid)
		)
		(fill yes)
		(layer "In11.Cu")
		(net "M_D_CPU1_SB_DQS_DP<5>")
	)
	(gr_poly
		(pts
			(xy 91.620848 -229.477062) (xy 91.573858 -229.324662) (xy 91.312238 -229.324662) (xy 91.265248 -229.477062)
			(xy 91.265248 -229.521258) (xy 91.620848 -229.521258)
		)
		(stroke
			(width 0)
			(type solid)
		)
		(fill yes)
		(layer "In11.Cu")
		(net "M_D_CPU1_SB_DQ<26>")
	)
	(gr_poly
		(pts
			(xy 91.716352 -274.876514) (xy 91.716352 -274.832064) (xy 91.360752 -274.832064) (xy 91.360752 -274.876514)
			(xy 91.407742 -275.028914) (xy 91.669362 -275.028914)
		)
		(stroke
			(width 0)
			(type solid)
		)
		(fill yes)
		(layer "In11.Cu")
		(net "M_D_CPU1_SA_DQ<16>")
	)
	(gr_poly
		(pts
			(xy 91.716352 -269.99311) (xy 91.716352 -269.948914) (xy 91.360752 -269.948914) (xy 91.360752 -269.99311)
			(xy 91.407742 -270.14551) (xy 91.669362 -270.14551)
		)
		(stroke
			(width 0)
			(type solid)
		)
		(fill yes)
		(layer "In11.Cu")
		(net "M_D_CPU1_SA_DQ<24>")
	)
	(gr_poly
		(pts
			(xy 91.716352 -265.109706) (xy 91.716352 -265.06551) (xy 91.360752 -265.06551) (xy 91.360752 -265.109706)
			(xy 91.407742 -265.262106) (xy 91.669362 -265.262106)
		)
		(stroke
			(width 0)
			(type solid)
		)
		(fill yes)
		(layer "In11.Cu")
		(net "M_D_CPU1_SA_CB<0>")
	)
	(gr_poly
		(pts
			(xy 91.718892 -262.262874) (xy 91.671902 -262.110474) (xy 91.410282 -262.110474) (xy 91.363292 -262.262874)
			(xy 91.363292 -262.307324) (xy 91.718892 -262.307324)
		)
		(stroke
			(width 0)
			(type solid)
		)
		(fill yes)
		(layer "In11.Cu")
		(net "M_D_CPU1_SA_DQS_DP<9>")
	)
	(gr_poly
		(pts
			(xy 91.722448 -273.657314) (xy 91.675458 -273.504914) (xy 91.413838 -273.504914) (xy 91.366848 -273.657314)
			(xy 91.366848 -273.701764) (xy 91.722448 -273.701764)
		)
		(stroke
			(width 0)
			(type solid)
		)
		(fill yes)
		(layer "In11.Cu")
		(net "M_D_CPU1_SA_DQ<19>")
	)
	(gr_poly
		(pts
			(xy 91.722448 -268.77391) (xy 91.675458 -268.62151) (xy 91.413838 -268.62151) (xy 91.366848 -268.77391)
			(xy 91.366848 -268.81836) (xy 91.722448 -268.81836)
		)
		(stroke
			(width 0)
			(type solid)
		)
		(fill yes)
		(layer "In11.Cu")
		(net "M_D_CPU1_SA_DQ<27>")
	)
	(gr_poly
		(pts
			(xy 91.722448 -263.891014) (xy 91.675458 -263.738614) (xy 91.413838 -263.738614) (xy 91.366848 -263.891014)
			(xy 91.366848 -263.93521) (xy 91.722448 -263.93521)
		)
		(stroke
			(width 0)
			(type solid)
		)
		(fill yes)
		(layer "In11.Cu")
		(net "M_D_CPU1_SA_CB<3>")
	)
	(gr_poly
		(pts
			(xy 91.722448 -259.00761) (xy 91.675458 -258.85521) (xy 91.413838 -258.85521) (xy 91.366848 -259.00761)
			(xy 91.366848 -259.051806) (xy 91.722448 -259.051806)
		)
		(stroke
			(width 0)
			(type solid)
		)
		(fill yes)
		(layer "In11.Cu")
		(net "M_D_CPU1_SA_CS_N<0>")
	)
	(gr_poly
		(pts
			(xy 91.72829 -278.540718) (xy 91.6813 -278.388318) (xy 91.41968 -278.388318) (xy 91.37269 -278.540718)
			(xy 91.37269 -278.584914) (xy 91.72829 -278.584914)
		)
		(stroke
			(width 0)
			(type solid)
		)
		(fill yes)
		(layer "In11.Cu")
		(net "M_D_CPU1_SA_DQ<11>")
	)
	(gr_poly
		(pts
			(xy 91.72829 -278.132286) (xy 91.72829 -278.08809) (xy 91.37269 -278.08809) (xy 91.37269 -278.132286)
			(xy 91.41968 -278.284686) (xy 91.6813 -278.284686)
		)
		(stroke
			(width 0)
			(type solid)
		)
		(fill yes)
		(layer "In11.Cu")
		(net "M_D_CPU1_SA_DQS_DP<1>")
	)
	(gr_poly
		(pts
			(xy 91.72829 -276.912578) (xy 91.6813 -276.760178) (xy 91.41968 -276.760178) (xy 91.37269 -276.912578)
			(xy 91.37269 -276.957028) (xy 91.72829 -276.957028)
		)
		(stroke
			(width 0)
			(type solid)
		)
		(fill yes)
		(layer "In11.Cu")
		(net "M_D_CPU1_SA_DQS_DP<6>")
	)
	(gr_poly
		(pts
			(xy 91.72829 -276.5044) (xy 91.72829 -276.460204) (xy 91.37269 -276.460204) (xy 91.37269 -276.5044)
			(xy 91.41968 -276.6568) (xy 91.6813 -276.6568)
		)
		(stroke
			(width 0)
			(type solid)
		)
		(fill yes)
		(layer "In11.Cu")
		(net "M_D_CPU1_SA_DQ<12>")
	)
	(gr_poly
		(pts
			(xy 91.72829 -275.284946) (xy 91.6813 -275.132546) (xy 91.41968 -275.132546) (xy 91.37269 -275.284946)
			(xy 91.37269 -275.329396) (xy 91.72829 -275.329396)
		)
		(stroke
			(width 0)
			(type solid)
		)
		(fill yes)
		(layer "In11.Cu")
		(net "M_D_CPU1_SA_DQ<15>")
	)
	(gr_poly
		(pts
			(xy 91.72829 -272.029174) (xy 91.6813 -271.876774) (xy 91.41968 -271.876774) (xy 91.37269 -272.029174)
			(xy 91.37269 -272.073624) (xy 91.72829 -272.073624)
		)
		(stroke
			(width 0)
			(type solid)
		)
		(fill yes)
		(layer "In11.Cu")
		(net "M_D_CPU1_SA_DQS_DP<7>")
	)
	(gr_poly
		(pts
			(xy 91.72829 -271.62125) (xy 91.72829 -271.5768) (xy 91.37269 -271.5768) (xy 91.37269 -271.62125)
			(xy 91.41968 -271.77365) (xy 91.6813 -271.77365)
		)
		(stroke
			(width 0)
			(type solid)
		)
		(fill yes)
		(layer "In11.Cu")
		(net "M_D_CPU1_SA_DQ<20>")
	)
	(gr_poly
		(pts
			(xy 91.72829 -270.40205) (xy 91.6813 -270.24965) (xy 91.41968 -270.24965) (xy 91.37269 -270.40205)
			(xy 91.37269 -270.446246) (xy 91.72829 -270.446246)
		)
		(stroke
			(width 0)
			(type solid)
		)
		(fill yes)
		(layer "In11.Cu")
		(net "M_D_CPU1_SA_DQ<23>")
	)
	(gr_poly
		(pts
			(xy 91.72829 -267.14577) (xy 91.6813 -266.99337) (xy 91.41968 -266.99337) (xy 91.37269 -267.14577)
			(xy 91.37269 -267.19022) (xy 91.72829 -267.19022)
		)
		(stroke
			(width 0)
			(type solid)
		)
		(fill yes)
		(layer "In11.Cu")
		(net "M_D_CPU1_SA_DQS_DP<8>")
	)
	(gr_poly
		(pts
			(xy 91.72829 -266.737846) (xy 91.72829 -266.69365) (xy 91.37269 -266.69365) (xy 91.37269 -266.737846)
			(xy 91.41968 -266.890246) (xy 91.6813 -266.890246)
		)
		(stroke
			(width 0)
			(type solid)
		)
		(fill yes)
		(layer "In11.Cu")
		(net "M_D_CPU1_SA_DQ<28>")
	)
	(gr_poly
		(pts
			(xy 91.72829 -265.518646) (xy 91.6813 -265.366246) (xy 91.41968 -265.366246) (xy 91.37269 -265.518646)
			(xy 91.37269 -265.562842) (xy 91.72829 -265.562842)
		)
		(stroke
			(width 0)
			(type solid)
		)
		(fill yes)
		(layer "In11.Cu")
		(net "M_D_CPU1_SA_DQ<31>")
	)
	(gr_poly
		(pts
			(xy 91.72829 -261.854442) (xy 91.72829 -261.810246) (xy 91.37269 -261.810246) (xy 91.37269 -261.854442)
			(xy 91.41968 -262.006842) (xy 91.6813 -262.006842)
		)
		(stroke
			(width 0)
			(type solid)
		)
		(fill yes)
		(layer "In11.Cu")
		(net "M_D_CPU1_SA_CB<4>")
	)
	(gr_poly
		(pts
			(xy 91.72829 -260.635242) (xy 91.6813 -260.482842) (xy 91.41968 -260.482842) (xy 91.37269 -260.635242)
			(xy 91.37269 -260.679438) (xy 91.72829 -260.679438)
		)
		(stroke
			(width 0)
			(type solid)
		)
		(fill yes)
		(layer "In11.Cu")
		(net "M_D_CPU1_SA_CB<7>")
	)
	(gr_poly
		(pts
			(xy 91.72829 -257.37947) (xy 91.6813 -257.22707) (xy 91.41968 -257.22707) (xy 91.37269 -257.37947)
			(xy 91.37269 -257.423666) (xy 91.72829 -257.423666)
		)
		(stroke
			(width 0)
			(type solid)
		)
		(fill yes)
		(layer "In11.Cu")
		(net "M_D_CPU1_SA_CA<1>")
	)
	(gr_poly
		(pts
			(xy 91.72829 -256.971038) (xy 91.72829 -256.926842) (xy 91.37269 -256.926842) (xy 91.37269 -256.971038)
			(xy 91.41968 -257.123438) (xy 91.6813 -257.123438)
		)
		(stroke
			(width 0)
			(type solid)
		)
		(fill yes)
		(layer "In11.Cu")
		(net "M_D_CPU1_SA_CA<2>")
	)
	(gr_poly
		(pts
			(xy 91.72829 -255.751838) (xy 91.6813 -255.599438) (xy 91.41968 -255.599438) (xy 91.37269 -255.751838)
			(xy 91.37269 -255.796288) (xy 91.72829 -255.796288)
		)
		(stroke
			(width 0)
			(type solid)
		)
		(fill yes)
		(layer "In11.Cu")
		(net "M_D_CPU1_SA_CA<5>")
	)
	(gr_poly
		(pts
			(xy 91.73083 -279.759918) (xy 91.73083 -279.715722) (xy 91.37523 -279.715722) (xy 91.37523 -279.759918)
			(xy 91.42222 -279.912318) (xy 91.68384 -279.912318)
		)
		(stroke
			(width 0)
			(type solid)
		)
		(fill yes)
		(layer "In11.Cu")
		(net "M_D_CPU1_SA_DQ<8>")
	)
	(gr_poly
		(pts
			(xy 91.73083 -273.248882) (xy 91.73083 -273.204686) (xy 91.37523 -273.204686) (xy 91.37523 -273.248882)
			(xy 91.42222 -273.401282) (xy 91.68384 -273.401282)
		)
		(stroke
			(width 0)
			(type solid)
		)
		(fill yes)
		(layer "In11.Cu")
		(net "M_D_CPU1_SA_DQS_DP<2>")
	)
	(gr_poly
		(pts
			(xy 91.73083 -268.365478) (xy 91.73083 -268.321282) (xy 91.37523 -268.321282) (xy 91.37523 -268.365478)
			(xy 91.42222 -268.517878) (xy 91.68384 -268.517878)
		)
		(stroke
			(width 0)
			(type solid)
		)
		(fill yes)
		(layer "In11.Cu")
		(net "M_D_CPU1_SA_DQS_DP<3>")
	)
	(gr_poly
		(pts
			(xy 91.73083 -263.482582) (xy 91.73083 -263.438132) (xy 91.37523 -263.438132) (xy 91.37523 -263.482582)
			(xy 91.42222 -263.634982) (xy 91.68384 -263.634982)
		)
		(stroke
			(width 0)
			(type solid)
		)
		(fill yes)
		(layer "In11.Cu")
		(net "M_D_CPU1_SA_DQS_DP<4>")
	)
	(gr_poly
		(pts
			(xy 91.73083 -258.599178) (xy 91.73083 -258.554728) (xy 91.37523 -258.554728) (xy 91.37523 -258.599178)
			(xy 91.42222 -258.751578) (xy 91.68384 -258.751578)
		)
		(stroke
			(width 0)
			(type solid)
		)
		(fill yes)
		(layer "In11.Cu")
		(net "M_D_CPU1_SA_CS_N<3>")
	)
	(gr_poly
		(pts
			(xy 92.07373 -249.416062) (xy 92.07373 -249.371612) (xy 91.71813 -249.371612) (xy 91.71813 -249.416062)
			(xy 91.76512 -249.568462) (xy 92.02674 -249.568462)
		)
		(stroke
			(width 0)
			(type solid)
		)
		(fill yes)
		(layer "In11.Cu")
		(net "M_D_CPU1_SB_CA<2>")
	)
	(gr_poly
		(pts
			(xy 92.07373 -246.16029) (xy 92.07373 -246.116094) (xy 91.71813 -246.116094) (xy 91.71813 -246.16029)
			(xy 91.76512 -246.31269) (xy 92.02674 -246.31269)
		)
		(stroke
			(width 0)
			(type solid)
		)
		(fill yes)
		(layer "In11.Cu")
		(net "M_D_CPU1_SB_CB<5>")
	)
	(gr_poly
		(pts
			(xy 92.07373 -241.685318) (xy 92.02674 -241.532918) (xy 91.76512 -241.532918) (xy 91.71813 -241.685318)
			(xy 91.71813 -241.729514) (xy 92.07373 -241.729514)
		)
		(stroke
			(width 0)
			(type solid)
		)
		(fill yes)
		(layer "In11.Cu")
		(net "M_D_CPU1_SB_DQ<2>")
	)
	(gr_poly
		(pts
			(xy 92.07373 -241.276886) (xy 92.07373 -241.23269) (xy 91.71813 -241.23269) (xy 91.71813 -241.276886)
			(xy 91.76512 -241.429286) (xy 92.02674 -241.429286)
		)
		(stroke
			(width 0)
			(type solid)
		)
		(fill yes)
		(layer "In11.Cu")
		(net "M_D_CPU1_SB_DQ<1>")
	)
	(gr_poly
		(pts
			(xy 92.07373 -240.057178) (xy 92.02674 -239.904778) (xy 91.76512 -239.904778) (xy 91.71813 -240.057178)
			(xy 91.71813 -240.101628) (xy 92.07373 -240.101628)
		)
		(stroke
			(width 0)
			(type solid)
		)
		(fill yes)
		(layer "In11.Cu")
		(net "M_D_CPU1_SB_DQS_DN<0>")
	)
	(gr_poly
		(pts
			(xy 92.07373 -239.649254) (xy 92.07373 -239.604804) (xy 91.71813 -239.604804) (xy 91.71813 -239.649254)
			(xy 91.76512 -239.801654) (xy 92.02674 -239.801654)
		)
		(stroke
			(width 0)
			(type solid)
		)
		(fill yes)
		(layer "In11.Cu")
		(net "M_D_CPU1_SB_DQS_DN<5>")
	)
	(gr_poly
		(pts
			(xy 92.07373 -236.39399) (xy 92.07373 -236.34954) (xy 91.71813 -236.34954) (xy 91.71813 -236.39399)
			(xy 91.76512 -236.54639) (xy 92.02674 -236.54639)
		)
		(stroke
			(width 0)
			(type solid)
		)
		(fill yes)
		(layer "In11.Cu")
		(net "M_D_CPU1_SB_DQ<9>")
	)
	(gr_poly
		(pts
			(xy 92.07373 -231.510586) (xy 92.07373 -231.466136) (xy 91.71813 -231.466136) (xy 91.71813 -231.510586)
			(xy 91.76512 -231.662986) (xy 92.02674 -231.662986)
		)
		(stroke
			(width 0)
			(type solid)
		)
		(fill yes)
		(layer "In11.Cu")
		(net "M_D_CPU1_SB_DQ<12>")
	)
	(gr_poly
		(pts
			(xy 92.07373 -230.290878) (xy 92.02674 -230.138478) (xy 91.76512 -230.138478) (xy 91.71813 -230.290878)
			(xy 91.71813 -230.335074) (xy 92.07373 -230.335074)
		)
		(stroke
			(width 0)
			(type solid)
		)
		(fill yes)
		(layer "In11.Cu")
		(net "M_D_CPU1_SB_DQ<15>")
	)
	(gr_poly
		(pts
			(xy 92.07373 -229.882446) (xy 92.07373 -229.83825) (xy 91.71813 -229.83825) (xy 91.71813 -229.882446)
			(xy 91.76512 -230.034846) (xy 92.02674 -230.034846)
		)
		(stroke
			(width 0)
			(type solid)
		)
		(fill yes)
		(layer "In11.Cu")
		(net "M_D_CPU1_SB_DQ<24>")
	)
	(gr_poly
		(pts
			(xy 92.07373 -225.407474) (xy 92.02674 -225.255074) (xy 91.76512 -225.255074) (xy 91.71813 -225.407474)
			(xy 91.71813 -225.45167) (xy 92.07373 -225.45167)
		)
		(stroke
			(width 0)
			(type solid)
		)
		(fill yes)
		(layer "In11.Cu")
		(net "M_D_CPU1_SB_DQ<31>")
	)
	(gr_poly
		(pts
			(xy 92.07627 -248.196354) (xy 92.02928 -248.043954) (xy 91.76766 -248.043954) (xy 91.72067 -248.196354)
			(xy 91.72067 -248.240804) (xy 92.07627 -248.240804)
		)
		(stroke
			(width 0)
			(type solid)
		)
		(fill yes)
		(layer "In11.Cu")
		(net "M_D_CPU1_SB_CA<5>")
	)
	(gr_poly
		(pts
			(xy 92.07627 -244.940582) (xy 92.02928 -244.788182) (xy 91.76766 -244.788182) (xy 91.72067 -244.940582)
			(xy 91.72067 -244.985032) (xy 92.07627 -244.985032)
		)
		(stroke
			(width 0)
			(type solid)
		)
		(fill yes)
		(layer "In11.Cu")
		(net "M_D_CPU1_SB_DQS_DN<9>")
	)
	(gr_poly
		(pts
			(xy 92.07627 -244.532658) (xy 92.07627 -244.488208) (xy 91.72067 -244.488208) (xy 91.72067 -244.532658)
			(xy 91.76766 -244.685058) (xy 92.02928 -244.685058)
		)
		(stroke
			(width 0)
			(type solid)
		)
		(fill yes)
		(layer "In11.Cu")
		(net "M_D_CPU1_SB_DQS_DN<4>")
	)
	(gr_poly
		(pts
			(xy 92.07627 -243.313458) (xy 92.02928 -243.161058) (xy 91.76766 -243.161058) (xy 91.72067 -243.313458)
			(xy 91.72067 -243.357654) (xy 92.07627 -243.357654)
		)
		(stroke
			(width 0)
			(type solid)
		)
		(fill yes)
		(layer "In11.Cu")
		(net "M_D_CPU1_SB_CB<2>")
	)
	(gr_poly
		(pts
			(xy 92.07627 -242.904518) (xy 92.07627 -242.860322) (xy 91.72067 -242.860322) (xy 91.72067 -242.904518)
			(xy 91.76766 -243.056918) (xy 92.02928 -243.056918)
		)
		(stroke
			(width 0)
			(type solid)
		)
		(fill yes)
		(layer "In11.Cu")
		(net "M_D_CPU1_SB_CB<1>")
	)
	(gr_poly
		(pts
			(xy 92.07627 -238.430054) (xy 92.02928 -238.277654) (xy 91.76766 -238.277654) (xy 91.72067 -238.430054)
			(xy 91.72067 -238.47425) (xy 92.07627 -238.47425)
		)
		(stroke
			(width 0)
			(type solid)
		)
		(fill yes)
		(layer "In11.Cu")
		(net "M_D_CPU1_SB_DQ<6>")
	)
	(gr_poly
		(pts
			(xy 92.07627 -233.54665) (xy 92.02928 -233.39425) (xy 91.76766 -233.39425) (xy 91.72067 -233.54665)
			(xy 91.72067 -233.590846) (xy 92.07627 -233.590846)
		)
		(stroke
			(width 0)
			(type solid)
		)
		(fill yes)
		(layer "In11.Cu")
		(net "M_D_CPU1_SB_DQS_DN<1>")
	)
	(gr_poly
		(pts
			(xy 92.07627 -228.663246) (xy 92.02928 -228.510846) (xy 91.76766 -228.510846) (xy 91.72067 -228.663246)
			(xy 91.72067 -228.707696) (xy 92.07627 -228.707696)
		)
		(stroke
			(width 0)
			(type solid)
		)
		(fill yes)
		(layer "In11.Cu")
		(net "M_D_CPU1_SB_DQ<27>")
	)
	(gr_poly
		(pts
			(xy 92.07627 -226.626674) (xy 92.07627 -226.582478) (xy 91.72067 -226.582478) (xy 91.72067 -226.626674)
			(xy 91.76766 -226.779074) (xy 92.02928 -226.779074)
		)
		(stroke
			(width 0)
			(type solid)
		)
		(fill yes)
		(layer "In11.Cu")
		(net "M_D_CPU1_SB_DQ<28>")
	)
	(gr_poly
		(pts
			(xy 92.082112 -246.568722) (xy 92.035122 -246.416322) (xy 91.773502 -246.416322) (xy 91.726512 -246.568722)
			(xy 91.726512 -246.613172) (xy 92.082112 -246.613172)
		)
		(stroke
			(width 0)
			(type solid)
		)
		(fill yes)
		(layer "In11.Cu")
		(net "M_D_CPU1_SB_CB<6>")
	)
	(gr_poly
		(pts
			(xy 92.082112 -236.801914) (xy 92.035122 -236.649514) (xy 91.773502 -236.649514) (xy 91.726512 -236.801914)
			(xy 91.726512 -236.846364) (xy 92.082112 -236.846364)
		)
		(stroke
			(width 0)
			(type solid)
		)
		(fill yes)
		(layer "In11.Cu")
		(net "M_D_CPU1_SB_DQ<10>")
	)
	(gr_poly
		(pts
			(xy 92.082112 -231.919018) (xy 92.035122 -231.766618) (xy 91.773502 -231.766618) (xy 91.726512 -231.919018)
			(xy 91.726512 -231.963214) (xy 92.082112 -231.963214)
		)
		(stroke
			(width 0)
			(type solid)
		)
		(fill yes)
		(layer "In11.Cu")
		(net "M_D_CPU1_SB_DQS_DP<6>")
	)
	(gr_poly
		(pts
			(xy 92.082112 -227.035614) (xy 92.035122 -226.883214) (xy 91.773502 -226.883214) (xy 91.726512 -227.035614)
			(xy 91.726512 -227.07981) (xy 92.082112 -227.07981)
		)
		(stroke
			(width 0)
			(type solid)
		)
		(fill yes)
		(layer "In11.Cu")
		(net "M_D_CPU1_SB_DQS_DP<8>")
	)
	(gr_poly
		(pts
			(xy 92.088208 -247.787922) (xy 92.088208 -247.743472) (xy 91.732608 -247.743472) (xy 91.732608 -247.787922)
			(xy 91.779598 -247.940322) (xy 92.041218 -247.940322)
		)
		(stroke
			(width 0)
			(type solid)
		)
		(fill yes)
		(layer "In11.Cu")
		(net "M_D_CPU1_SB_PAR")
	)
	(gr_poly
		(pts
			(xy 92.088208 -238.021114) (xy 92.088208 -237.976918) (xy 91.732608 -237.976918) (xy 91.732608 -238.021114)
			(xy 91.779598 -238.173514) (xy 92.041218 -238.173514)
		)
		(stroke
			(width 0)
			(type solid)
		)
		(fill yes)
		(layer "In11.Cu")
		(net "M_D_CPU1_SB_DQ<5>")
	)
	(gr_poly
		(pts
			(xy 92.088208 -228.254814) (xy 92.088208 -228.210364) (xy 91.732608 -228.210364) (xy 91.732608 -228.254814)
			(xy 91.779598 -228.407214) (xy 92.041218 -228.407214)
		)
		(stroke
			(width 0)
			(type solid)
		)
		(fill yes)
		(layer "In11.Cu")
		(net "M_D_CPU1_SB_DQS_DP<3>")
	)
	(gr_poly
		(pts
			(xy 92.183712 -279.354534) (xy 92.136722 -279.202134) (xy 91.875102 -279.202134) (xy 91.828112 -279.354534)
			(xy 91.828112 -279.39873) (xy 92.183712 -279.39873)
		)
		(stroke
			(width 0)
			(type solid)
		)
		(fill yes)
		(layer "In11.Cu")
		(net "M_D_CPU1_SA_DQ<10>")
	)
	(gr_poly
		(pts
			(xy 92.183712 -278.946102) (xy 92.183712 -278.901906) (xy 91.828112 -278.901906) (xy 91.828112 -278.946102)
			(xy 91.875102 -279.098502) (xy 92.136722 -279.098502)
		)
		(stroke
			(width 0)
			(type solid)
		)
		(fill yes)
		(layer "In11.Cu")
		(net "M_D_CPU1_SA_DQ<9>")
	)
	(gr_poly
		(pts
			(xy 92.183712 -277.726394) (xy 92.136722 -277.573994) (xy 91.875102 -277.573994) (xy 91.828112 -277.726394)
			(xy 91.828112 -277.770844) (xy 92.183712 -277.770844)
		)
		(stroke
			(width 0)
			(type solid)
		)
		(fill yes)
		(layer "In11.Cu")
		(net "M_D_CPU1_SA_DQS_DN<1>")
	)
	(gr_poly
		(pts
			(xy 92.183712 -277.318216) (xy 92.183712 -277.27402) (xy 91.828112 -277.27402) (xy 91.828112 -277.318216)
			(xy 91.875102 -277.470616) (xy 92.136722 -277.470616)
		)
		(stroke
			(width 0)
			(type solid)
		)
		(fill yes)
		(layer "In11.Cu")
		(net "M_D_CPU1_SA_DQS_DN<6>")
	)
	(gr_poly
		(pts
			(xy 92.183712 -276.098762) (xy 92.136722 -275.946362) (xy 91.875102 -275.946362) (xy 91.828112 -276.098762)
			(xy 91.828112 -276.143212) (xy 92.183712 -276.143212)
		)
		(stroke
			(width 0)
			(type solid)
		)
		(fill yes)
		(layer "In11.Cu")
		(net "M_D_CPU1_SA_DQ<14>")
	)
	(gr_poly
		(pts
			(xy 92.183712 -272.843498) (xy 92.136722 -272.691098) (xy 91.875102 -272.691098) (xy 91.828112 -272.843498)
			(xy 91.828112 -272.887694) (xy 92.183712 -272.887694)
		)
		(stroke
			(width 0)
			(type solid)
		)
		(fill yes)
		(layer "In11.Cu")
		(net "M_D_CPU1_SA_DQS_DN<2>")
	)
	(gr_poly
		(pts
			(xy 92.183712 -272.435066) (xy 92.183712 -272.39087) (xy 91.828112 -272.39087) (xy 91.828112 -272.435066)
			(xy 91.875102 -272.587466) (xy 92.136722 -272.587466)
		)
		(stroke
			(width 0)
			(type solid)
		)
		(fill yes)
		(layer "In11.Cu")
		(net "M_D_CPU1_SA_DQS_DN<7>")
	)
	(gr_poly
		(pts
			(xy 92.183712 -271.215358) (xy 92.136722 -271.062958) (xy 91.875102 -271.062958) (xy 91.828112 -271.215358)
			(xy 91.828112 -271.259808) (xy 92.183712 -271.259808)
		)
		(stroke
			(width 0)
			(type solid)
		)
		(fill yes)
		(layer "In11.Cu")
		(net "M_D_CPU1_SA_DQ<22>")
	)
	(gr_poly
		(pts
			(xy 92.183712 -267.960094) (xy 92.136722 -267.807694) (xy 91.875102 -267.807694) (xy 91.828112 -267.960094)
			(xy 91.828112 -268.00429) (xy 92.183712 -268.00429)
		)
		(stroke
			(width 0)
			(type solid)
		)
		(fill yes)
		(layer "In11.Cu")
		(net "M_D_CPU1_SA_DQS_DN<3>")
	)
	(gr_poly
		(pts
			(xy 92.183712 -267.551662) (xy 92.183712 -267.507466) (xy 91.828112 -267.507466) (xy 91.828112 -267.551662)
			(xy 91.875102 -267.704062) (xy 92.136722 -267.704062)
		)
		(stroke
			(width 0)
			(type solid)
		)
		(fill yes)
		(layer "In11.Cu")
		(net "M_D_CPU1_SA_DQS_DN<8>")
	)
	(gr_poly
		(pts
			(xy 92.183712 -266.331954) (xy 92.136722 -266.179554) (xy 91.875102 -266.179554) (xy 91.828112 -266.331954)
			(xy 91.828112 -266.376404) (xy 92.183712 -266.376404)
		)
		(stroke
			(width 0)
			(type solid)
		)
		(fill yes)
		(layer "In11.Cu")
		(net "M_D_CPU1_SA_DQ<30>")
	)
	(gr_poly
		(pts
			(xy 92.183712 -263.07669) (xy 92.136722 -262.92429) (xy 91.875102 -262.92429) (xy 91.828112 -263.07669)
			(xy 91.828112 -263.120886) (xy 92.183712 -263.120886)
		)
		(stroke
			(width 0)
			(type solid)
		)
		(fill yes)
		(layer "In11.Cu")
		(net "M_D_CPU1_SA_DQS_DN<4>")
	)
	(gr_poly
		(pts
			(xy 92.183712 -261.449058) (xy 92.136722 -261.296658) (xy 91.875102 -261.296658) (xy 91.828112 -261.449058)
			(xy 91.828112 -261.493254) (xy 92.183712 -261.493254)
		)
		(stroke
			(width 0)
			(type solid)
		)
		(fill yes)
		(layer "In11.Cu")
		(net "M_D_CPU1_SA_CB<6>")
	)
	(gr_poly
		(pts
			(xy 92.183712 -256.565654) (xy 92.136722 -256.413254) (xy 91.875102 -256.413254) (xy 91.828112 -256.565654)
			(xy 91.828112 -256.60985) (xy 92.183712 -256.60985)
		)
		(stroke
			(width 0)
			(type solid)
		)
		(fill yes)
		(layer "In11.Cu")
		(net "M_D_CPU1_SA_CA<3>")
	)
	(gr_poly
		(pts
			(xy 92.186252 -274.062698) (xy 92.186252 -274.018248) (xy 91.830652 -274.018248) (xy 91.830652 -274.062698)
			(xy 91.877642 -274.215098) (xy 92.139262 -274.215098)
		)
		(stroke
			(width 0)
			(type solid)
		)
		(fill yes)
		(layer "In11.Cu")
		(net "M_D_CPU1_SA_DQ<17>")
	)
	(gr_poly
		(pts
			(xy 92.186252 -269.179294) (xy 92.186252 -269.134844) (xy 91.830652 -269.134844) (xy 91.830652 -269.179294)
			(xy 91.877642 -269.331694) (xy 92.139262 -269.331694)
		)
		(stroke
			(width 0)
			(type solid)
		)
		(fill yes)
		(layer "In11.Cu")
		(net "M_D_CPU1_SA_DQ<25>")
	)
	(gr_poly
		(pts
			(xy 92.186252 -264.29589) (xy 92.186252 -264.251694) (xy 91.830652 -264.251694) (xy 91.830652 -264.29589)
			(xy 91.877642 -264.44829) (xy 92.139262 -264.44829)
		)
		(stroke
			(width 0)
			(type solid)
		)
		(fill yes)
		(layer "In11.Cu")
		(net "M_D_CPU1_SA_CB<1>")
	)
	(gr_poly
		(pts
			(xy 92.186252 -259.412486) (xy 92.186252 -259.36829) (xy 91.830652 -259.36829) (xy 91.830652 -259.412486)
			(xy 91.877642 -259.564886) (xy 92.139262 -259.564886)
		)
		(stroke
			(width 0)
			(type solid)
		)
		(fill yes)
		(layer "In11.Cu")
		(net "M_D_CPU1_SA_CS_N<2>")
	)
	(gr_poly
		(pts
			(xy 92.186252 -258.193286) (xy 92.139262 -258.040886) (xy 91.877642 -258.040886) (xy 91.830652 -258.193286)
			(xy 91.830652 -258.237482) (xy 92.186252 -258.237482)
		)
		(stroke
			(width 0)
			(type solid)
		)
		(fill yes)
		(layer "In11.Cu")
		(net "M_D_CPU1_SA_CS_N<1>")
	)
	(gr_poly
		(pts
			(xy 92.186252 -257.784854) (xy 92.186252 -257.740658) (xy 91.830652 -257.740658) (xy 91.830652 -257.784854)
			(xy 91.877642 -257.937254) (xy 92.139262 -257.937254)
		)
		(stroke
			(width 0)
			(type solid)
		)
		(fill yes)
		(layer "In11.Cu")
		(net "M_D_CPU1_SA_CA<0>")
	)
	(gr_poly
		(pts
			(xy 92.192094 -275.690584) (xy 92.192094 -275.646134) (xy 91.836494 -275.646134) (xy 91.836494 -275.690584)
			(xy 91.883484 -275.842984) (xy 92.145104 -275.842984)
		)
		(stroke
			(width 0)
			(type solid)
		)
		(fill yes)
		(layer "In11.Cu")
		(net "M_D_CPU1_SA_DQ<13>")
	)
	(gr_poly
		(pts
			(xy 92.192094 -270.806926) (xy 92.192094 -270.76273) (xy 91.836494 -270.76273) (xy 91.836494 -270.806926)
			(xy 91.883484 -270.959326) (xy 92.145104 -270.959326)
		)
		(stroke
			(width 0)
			(type solid)
		)
		(fill yes)
		(layer "In11.Cu")
		(net "M_D_CPU1_SA_DQ<21>")
	)
	(gr_poly
		(pts
			(xy 92.192094 -265.923522) (xy 92.192094 -265.879326) (xy 91.836494 -265.879326) (xy 91.836494 -265.923522)
			(xy 91.883484 -266.075922) (xy 92.145104 -266.075922)
		)
		(stroke
			(width 0)
			(type solid)
		)
		(fill yes)
		(layer "In11.Cu")
		(net "M_D_CPU1_SA_DQ<29>")
	)
	(gr_poly
		(pts
			(xy 92.192094 -261.040626) (xy 92.192094 -260.996176) (xy 91.836494 -260.996176) (xy 91.836494 -261.040626)
			(xy 91.883484 -261.193026) (xy 92.145104 -261.193026)
		)
		(stroke
			(width 0)
			(type solid)
		)
		(fill yes)
		(layer "In11.Cu")
		(net "M_D_CPU1_SA_CB<5>")
	)
	(gr_poly
		(pts
			(xy 92.192094 -256.157222) (xy 92.192094 -256.112772) (xy 91.836494 -256.112772) (xy 91.836494 -256.157222)
			(xy 91.883484 -256.309622) (xy 92.145104 -256.309622)
		)
		(stroke
			(width 0)
			(type solid)
		)
		(fill yes)
		(layer "In11.Cu")
		(net "M_D_CPU1_SA_CA<4>")
	)
	(gr_poly
		(pts
			(xy 92.19565 -262.668258) (xy 92.19565 -262.623808) (xy 91.84005 -262.623808) (xy 91.84005 -262.668258)
			(xy 91.88704 -262.820658) (xy 92.14866 -262.820658)
		)
		(stroke
			(width 0)
			(type solid)
		)
		(fill yes)
		(layer "In11.Cu")
		(net "M_D_CPU1_SA_DQS_DN<9>")
	)
	(gr_poly
		(pts
			(xy 92.19819 -274.47113) (xy 92.1512 -274.31873) (xy 91.88958 -274.31873) (xy 91.84259 -274.47113)
			(xy 91.84259 -274.51558) (xy 92.19819 -274.51558)
		)
		(stroke
			(width 0)
			(type solid)
		)
		(fill yes)
		(layer "In11.Cu")
		(net "M_D_CPU1_SA_DQ<18>")
	)
	(gr_poly
		(pts
			(xy 92.19819 -269.587726) (xy 92.1512 -269.435326) (xy 91.88958 -269.435326) (xy 91.84259 -269.587726)
			(xy 91.84259 -269.632176) (xy 92.19819 -269.632176)
		)
		(stroke
			(width 0)
			(type solid)
		)
		(fill yes)
		(layer "In11.Cu")
		(net "M_D_CPU1_SA_DQ<26>")
	)
	(gr_poly
		(pts
			(xy 92.19819 -264.70483) (xy 92.1512 -264.55243) (xy 91.88958 -264.55243) (xy 91.84259 -264.70483)
			(xy 91.84259 -264.749026) (xy 92.19819 -264.749026)
		)
		(stroke
			(width 0)
			(type solid)
		)
		(fill yes)
		(layer "In11.Cu")
		(net "M_D_CPU1_SA_CB<2>")
	)
	(gr_poly
		(pts
			(xy 92.40901 -234.621578) (xy 92.447364 -234.59948) (xy 92.269564 -234.291632) (xy 92.23121 -234.31373)
			(xy 92.122752 -234.43057) (xy 92.253562 -234.657138)
		)
		(stroke
			(width 0)
			(type solid)
		)
		(fill yes)
		(layer "In11.Cu")
		(net "M_D_CPU1_SB_DQS_DP<1>")
	)
	(gr_poly
		(pts
			(xy 92.517722 -233.999278) (xy 92.62618 -233.882438) (xy 92.49537 -233.65587) (xy 92.339922 -233.69143)
			(xy 92.301568 -233.713528) (xy 92.479368 -234.021376)
		)
		(stroke
			(width 0)
			(type solid)
		)
		(fill yes)
		(layer "In11.Cu")
		(net "M_D_CPU1_SB_DQS_DN<1>")
	)
	(gr_poly
		(pts
			(xy 92.54617 -245.346474) (xy 92.54617 -245.302024) (xy 92.19057 -245.302024) (xy 92.19057 -245.346474)
			(xy 92.23756 -245.498874) (xy 92.49918 -245.498874)
		)
		(stroke
			(width 0)
			(type solid)
		)
		(fill yes)
		(layer "In11.Cu")
		(net "M_D_CPU1_SB_DQS_DP<9>")
	)
	(gr_poly
		(pts
			(xy 92.552266 -244.127274) (xy 92.505276 -243.974874) (xy 92.243656 -243.974874) (xy 92.196666 -244.127274)
			(xy 92.196666 -244.17147) (xy 92.552266 -244.17147)
		)
		(stroke
			(width 0)
			(type solid)
		)
		(fill yes)
		(layer "In11.Cu")
		(net "M_D_CPU1_SB_DQS_DP<4>")
	)
	(gr_poly
		(pts
			(xy 92.558108 -247.382538) (xy 92.511118 -247.230138) (xy 92.249498 -247.230138) (xy 92.202508 -247.382538)
			(xy 92.202508 -247.426734) (xy 92.558108 -247.426734)
		)
		(stroke
			(width 0)
			(type solid)
		)
		(fill yes)
		(layer "In11.Cu")
		(net "M_D_CPU1_SB_CA<6>")
	)
	(gr_poly
		(pts
			(xy 92.558108 -246.974106) (xy 92.558108 -246.92991) (xy 92.202508 -246.92991) (xy 92.202508 -246.974106)
			(xy 92.249498 -247.126506) (xy 92.511118 -247.126506)
		)
		(stroke
			(width 0)
			(type solid)
		)
		(fill yes)
		(layer "In11.Cu")
		(net "M_D_CPU1_SB_CB<4>")
	)
	(gr_poly
		(pts
			(xy 92.558108 -245.754906) (xy 92.511118 -245.602506) (xy 92.249498 -245.602506) (xy 92.202508 -245.754906)
			(xy 92.202508 -245.799356) (xy 92.558108 -245.799356)
		)
		(stroke
			(width 0)
			(type solid)
		)
		(fill yes)
		(layer "In11.Cu")
		(net "M_D_CPU1_SB_CB<7>")
	)
	(gr_poly
		(pts
			(xy 92.558108 -237.61573) (xy 92.511118 -237.46333) (xy 92.249498 -237.46333) (xy 92.202508 -237.61573)
			(xy 92.202508 -237.659926) (xy 92.558108 -237.659926)
		)
		(stroke
			(width 0)
			(type solid)
		)
		(fill yes)
		(layer "In11.Cu")
		(net "M_D_CPU1_SB_DQ<7>")
	)
	(gr_poly
		(pts
			(xy 92.558108 -237.207806) (xy 92.558108 -237.163356) (xy 92.202508 -237.163356) (xy 92.202508 -237.207806)
			(xy 92.249498 -237.360206) (xy 92.511118 -237.360206)
		)
		(stroke
			(width 0)
			(type solid)
		)
		(fill yes)
		(layer "In11.Cu")
		(net "M_D_CPU1_SB_DQ<8>")
	)
	(gr_poly
		(pts
			(xy 92.558108 -232.324402) (xy 92.558108 -232.279952) (xy 92.202508 -232.279952) (xy 92.202508 -232.324402)
			(xy 92.249498 -232.476802) (xy 92.511118 -232.476802)
		)
		(stroke
			(width 0)
			(type solid)
		)
		(fill yes)
		(layer "In11.Cu")
		(net "M_D_CPU1_SB_DQS_DN<6>")
	)
	(gr_poly
		(pts
			(xy 92.558108 -227.848922) (xy 92.511118 -227.696522) (xy 92.249498 -227.696522) (xy 92.202508 -227.848922)
			(xy 92.202508 -227.893372) (xy 92.558108 -227.893372)
		)
		(stroke
			(width 0)
			(type solid)
		)
		(fill yes)
		(layer "In11.Cu")
		(net "M_D_CPU1_SB_DQS_DN<3>")
	)
	(gr_poly
		(pts
			(xy 92.558108 -227.440998) (xy 92.558108 -227.396548) (xy 92.202508 -227.396548) (xy 92.202508 -227.440998)
			(xy 92.249498 -227.593398) (xy 92.511118 -227.593398)
		)
		(stroke
			(width 0)
			(type solid)
		)
		(fill yes)
		(layer "In11.Cu")
		(net "M_D_CPU1_SB_DQS_DN<8>")
	)
	(gr_poly
		(pts
			(xy 92.560648 -249.01017) (xy 92.513658 -248.85777) (xy 92.252038 -248.85777) (xy 92.205048 -249.01017)
			(xy 92.205048 -249.05462) (xy 92.560648 -249.05462)
		)
		(stroke
			(width 0)
			(type solid)
		)
		(fill yes)
		(layer "In11.Cu")
		(net "M_D_CPU1_SB_CA<3>")
	)
	(gr_poly
		(pts
			(xy 92.560648 -248.602246) (xy 92.560648 -248.557796) (xy 92.205048 -248.557796) (xy 92.205048 -248.602246)
			(xy 92.252038 -248.754646) (xy 92.513658 -248.754646)
		)
		(stroke
			(width 0)
			(type solid)
		)
		(fill yes)
		(layer "In11.Cu")
		(net "M_D_CPU1_SB_CA<4>")
	)
	(gr_poly
		(pts
			(xy 92.560648 -243.718842) (xy 92.560648 -243.674392) (xy 92.205048 -243.674392) (xy 92.205048 -243.718842)
			(xy 92.252038 -243.871242) (xy 92.513658 -243.871242)
		)
		(stroke
			(width 0)
			(type solid)
		)
		(fill yes)
		(layer "In11.Cu")
		(net "M_D_CPU1_SB_CB<0>")
	)
	(gr_poly
		(pts
			(xy 92.560648 -242.499134) (xy 92.513658 -242.346734) (xy 92.252038 -242.346734) (xy 92.205048 -242.499134)
			(xy 92.205048 -242.54333) (xy 92.560648 -242.54333)
		)
		(stroke
			(width 0)
			(type solid)
		)
		(fill yes)
		(layer "In11.Cu")
		(net "M_D_CPU1_SB_CB<3>")
	)
	(gr_poly
		(pts
			(xy 92.560648 -242.090702) (xy 92.560648 -242.046506) (xy 92.205048 -242.046506) (xy 92.205048 -242.090702)
			(xy 92.252038 -242.243102) (xy 92.513658 -242.243102)
		)
		(stroke
			(width 0)
			(type solid)
		)
		(fill yes)
		(layer "In11.Cu")
		(net "M_D_CPU1_SB_DQ<0>")
	)
	(gr_poly
		(pts
			(xy 92.560648 -240.871502) (xy 92.513658 -240.719102) (xy 92.252038 -240.719102) (xy 92.205048 -240.871502)
			(xy 92.205048 -240.915698) (xy 92.560648 -240.915698)
		)
		(stroke
			(width 0)
			(type solid)
		)
		(fill yes)
		(layer "In11.Cu")
		(net "M_D_CPU1_SB_DQ<3>")
	)
	(gr_poly
		(pts
			(xy 92.560648 -240.46307) (xy 92.560648 -240.418874) (xy 92.205048 -240.418874) (xy 92.205048 -240.46307)
			(xy 92.252038 -240.61547) (xy 92.513658 -240.61547)
		)
		(stroke
			(width 0)
			(type solid)
		)
		(fill yes)
		(layer "In11.Cu")
		(net "M_D_CPU1_SB_DQS_DP<0>")
	)
	(gr_poly
		(pts
			(xy 92.560648 -239.243362) (xy 92.513658 -239.090962) (xy 92.252038 -239.090962) (xy 92.205048 -239.243362)
			(xy 92.205048 -239.287812) (xy 92.560648 -239.287812)
		)
		(stroke
			(width 0)
			(type solid)
		)
		(fill yes)
		(layer "In11.Cu")
		(net "M_D_CPU1_SB_DQS_DP<5>")
	)
	(gr_poly
		(pts
			(xy 92.560648 -238.835438) (xy 92.560648 -238.790988) (xy 92.205048 -238.790988) (xy 92.205048 -238.835438)
			(xy 92.252038 -238.987838) (xy 92.513658 -238.987838)
		)
		(stroke
			(width 0)
			(type solid)
		)
		(fill yes)
		(layer "In11.Cu")
		(net "M_D_CPU1_SB_DQ<4>")
	)
	(gr_poly
		(pts
			(xy 92.560648 -235.988098) (xy 92.513658 -235.835698) (xy 92.252038 -235.835698) (xy 92.205048 -235.988098)
			(xy 92.205048 -236.032294) (xy 92.560648 -236.032294)
		)
		(stroke
			(width 0)
			(type solid)
		)
		(fill yes)
		(layer "In11.Cu")
		(net "M_D_CPU1_SB_DQ<11>")
	)
	(gr_poly
		(pts
			(xy 92.560648 -231.104694) (xy 92.513658 -230.952294) (xy 92.252038 -230.952294) (xy 92.205048 -231.104694)
			(xy 92.205048 -231.14889) (xy 92.560648 -231.14889)
		)
		(stroke
			(width 0)
			(type solid)
		)
		(fill yes)
		(layer "In11.Cu")
		(net "M_D_CPU1_SB_DQ<14>")
	)
	(gr_poly
		(pts
			(xy 92.560648 -230.696262) (xy 92.560648 -230.652066) (xy 92.205048 -230.652066) (xy 92.205048 -230.696262)
			(xy 92.252038 -230.848662) (xy 92.513658 -230.848662)
		)
		(stroke
			(width 0)
			(type solid)
		)
		(fill yes)
		(layer "In11.Cu")
		(net "M_D_CPU1_SB_DQ<13>")
	)
	(gr_poly
		(pts
			(xy 92.560648 -229.477062) (xy 92.513658 -229.324662) (xy 92.252038 -229.324662) (xy 92.205048 -229.477062)
			(xy 92.205048 -229.521258) (xy 92.560648 -229.521258)
		)
		(stroke
			(width 0)
			(type solid)
		)
		(fill yes)
		(layer "In11.Cu")
		(net "M_D_CPU1_SB_DQ<26>")
	)
	(gr_poly
		(pts
			(xy 92.560648 -229.06863) (xy 92.560648 -229.024434) (xy 92.205048 -229.024434) (xy 92.205048 -229.06863)
			(xy 92.252038 -229.22103) (xy 92.513658 -229.22103)
		)
		(stroke
			(width 0)
			(type solid)
		)
		(fill yes)
		(layer "In11.Cu")
		(net "M_D_CPU1_SB_DQ<25>")
	)
	(gr_poly
		(pts
			(xy 92.560648 -226.22129) (xy 92.513658 -226.06889) (xy 92.252038 -226.06889) (xy 92.205048 -226.22129)
			(xy 92.205048 -226.26574) (xy 92.560648 -226.26574)
		)
		(stroke
			(width 0)
			(type solid)
		)
		(fill yes)
		(layer "In11.Cu")
		(net "M_D_CPU1_SB_DQ<30>")
	)
	(gr_poly
		(pts
			(xy 92.560648 -225.813366) (xy 92.560648 -225.768916) (xy 92.205048 -225.768916) (xy 92.205048 -225.813366)
			(xy 92.252038 -225.965766) (xy 92.513658 -225.965766)
		)
		(stroke
			(width 0)
			(type solid)
		)
		(fill yes)
		(layer "In11.Cu")
		(net "M_D_CPU1_SB_DQ<29>")
	)
	(gr_poly
		(pts
			(xy 92.656152 -257.37947) (xy 92.609162 -257.22707) (xy 92.347542 -257.22707) (xy 92.300552 -257.37947)
			(xy 92.300552 -257.42392) (xy 92.656152 -257.42392)
		)
		(stroke
			(width 0)
			(type solid)
		)
		(fill yes)
		(layer "In11.Cu")
		(net "M_D_CPU1_SA_CA<1>")
	)
	(gr_poly
		(pts
			(xy 92.658692 -262.262874) (xy 92.611702 -262.110474) (xy 92.350082 -262.110474) (xy 92.303092 -262.262874)
			(xy 92.303092 -262.307324) (xy 92.658692 -262.307324)
		)
		(stroke
			(width 0)
			(type solid)
		)
		(fill yes)
		(layer "In11.Cu")
		(net "M_D_CPU1_SA_DQS_DP<9>")
	)
	(gr_poly
		(pts
			(xy 92.662248 -258.59867) (xy 92.662248 -258.554474) (xy 92.306648 -258.554474) (xy 92.306648 -258.59867)
			(xy 92.353638 -258.75107) (xy 92.615258 -258.75107)
		)
		(stroke
			(width 0)
			(type solid)
		)
		(fill yes)
		(layer "In11.Cu")
		(net "M_D_CPU1_SA_CS_N<3>")
	)
	(gr_poly
		(pts
			(xy 92.66809 -275.284946) (xy 92.6211 -275.132546) (xy 92.35948 -275.132546) (xy 92.31249 -275.284946)
			(xy 92.31249 -275.329142) (xy 92.66809 -275.329142)
		)
		(stroke
			(width 0)
			(type solid)
		)
		(fill yes)
		(layer "In11.Cu")
		(net "M_D_CPU1_SA_DQ<15>")
	)
	(gr_poly
		(pts
			(xy 92.66809 -274.876514) (xy 92.66809 -274.832318) (xy 92.31249 -274.832318) (xy 92.31249 -274.876514)
			(xy 92.35948 -275.028914) (xy 92.6211 -275.028914)
		)
		(stroke
			(width 0)
			(type solid)
		)
		(fill yes)
		(layer "In11.Cu")
		(net "M_D_CPU1_SA_DQ<16>")
	)
	(gr_poly
		(pts
			(xy 92.66809 -270.401542) (xy 92.6211 -270.249142) (xy 92.35948 -270.249142) (xy 92.31249 -270.401542)
			(xy 92.31249 -270.445992) (xy 92.66809 -270.445992)
		)
		(stroke
			(width 0)
			(type solid)
		)
		(fill yes)
		(layer "In11.Cu")
		(net "M_D_CPU1_SA_DQ<23>")
	)
	(gr_poly
		(pts
			(xy 92.66809 -269.993618) (xy 92.66809 -269.949168) (xy 92.31249 -269.949168) (xy 92.31249 -269.993618)
			(xy 92.35948 -270.146018) (xy 92.6211 -270.146018)
		)
		(stroke
			(width 0)
			(type solid)
		)
		(fill yes)
		(layer "In11.Cu")
		(net "M_D_CPU1_SA_DQ<24>")
	)
	(gr_poly
		(pts
			(xy 92.66809 -265.518138) (xy 92.6211 -265.365738) (xy 92.35948 -265.365738) (xy 92.31249 -265.518138)
			(xy 92.31249 -265.562588) (xy 92.66809 -265.562588)
		)
		(stroke
			(width 0)
			(type solid)
		)
		(fill yes)
		(layer "In11.Cu")
		(net "M_D_CPU1_SA_DQ<31>")
	)
	(gr_poly
		(pts
			(xy 92.66809 -265.110214) (xy 92.66809 -265.065764) (xy 92.31249 -265.065764) (xy 92.31249 -265.110214)
			(xy 92.35948 -265.262614) (xy 92.6211 -265.262614)
		)
		(stroke
			(width 0)
			(type solid)
		)
		(fill yes)
		(layer "In11.Cu")
		(net "M_D_CPU1_SA_CB<0>")
	)
	(gr_poly
		(pts
			(xy 92.66809 -260.634734) (xy 92.6211 -260.482334) (xy 92.35948 -260.482334) (xy 92.31249 -260.634734)
			(xy 92.31249 -260.679184) (xy 92.66809 -260.679184)
		)
		(stroke
			(width 0)
			(type solid)
		)
		(fill yes)
		(layer "In11.Cu")
		(net "M_D_CPU1_SA_CB<7>")
	)
	(gr_poly
		(pts
			(xy 92.66809 -256.971038) (xy 92.66809 -256.926588) (xy 92.31249 -256.926588) (xy 92.31249 -256.971038)
			(xy 92.35948 -257.123438) (xy 92.6211 -257.123438)
		)
		(stroke
			(width 0)
			(type solid)
		)
		(fill yes)
		(layer "In11.Cu")
		(net "M_D_CPU1_SA_CA<2>")
	)
	(gr_poly
		(pts
			(xy 92.66809 -255.751838) (xy 92.6211 -255.599438) (xy 92.35948 -255.599438) (xy 92.31249 -255.751838)
			(xy 92.31249 -255.796034) (xy 92.66809 -255.796034)
		)
		(stroke
			(width 0)
			(type solid)
		)
		(fill yes)
		(layer "In11.Cu")
		(net "M_D_CPU1_SA_CA<5>")
	)
	(gr_poly
		(pts
			(xy 92.67063 -279.759918) (xy 92.67063 -279.715722) (xy 92.31503 -279.715722) (xy 92.31503 -279.759918)
			(xy 92.36202 -279.912318) (xy 92.62364 -279.912318)
		)
		(stroke
			(width 0)
			(type solid)
		)
		(fill yes)
		(layer "In11.Cu")
		(net "M_D_CPU1_SA_DQ<8>")
	)
	(gr_poly
		(pts
			(xy 92.67063 -278.540718) (xy 92.62364 -278.388318) (xy 92.36202 -278.388318) (xy 92.31503 -278.540718)
			(xy 92.31503 -278.584914) (xy 92.67063 -278.584914)
		)
		(stroke
			(width 0)
			(type solid)
		)
		(fill yes)
		(layer "In11.Cu")
		(net "M_D_CPU1_SA_DQ<11>")
	)
	(gr_poly
		(pts
			(xy 92.67063 -278.132286) (xy 92.67063 -278.08809) (xy 92.31503 -278.08809) (xy 92.31503 -278.132286)
			(xy 92.36202 -278.284686) (xy 92.62364 -278.284686)
		)
		(stroke
			(width 0)
			(type solid)
		)
		(fill yes)
		(layer "In11.Cu")
		(net "M_D_CPU1_SA_DQS_DP<1>")
	)
	(gr_poly
		(pts
			(xy 92.67063 -276.912578) (xy 92.62364 -276.760178) (xy 92.36202 -276.760178) (xy 92.31503 -276.912578)
			(xy 92.31503 -276.957028) (xy 92.67063 -276.957028)
		)
		(stroke
			(width 0)
			(type solid)
		)
		(fill yes)
		(layer "In11.Cu")
		(net "M_D_CPU1_SA_DQS_DP<6>")
	)
	(gr_poly
		(pts
			(xy 92.67063 -276.5044) (xy 92.67063 -276.460204) (xy 92.31503 -276.460204) (xy 92.31503 -276.5044)
			(xy 92.36202 -276.6568) (xy 92.62364 -276.6568)
		)
		(stroke
			(width 0)
			(type solid)
		)
		(fill yes)
		(layer "In11.Cu")
		(net "M_D_CPU1_SA_DQ<12>")
	)
	(gr_poly
		(pts
			(xy 92.67063 -273.657314) (xy 92.62364 -273.504914) (xy 92.36202 -273.504914) (xy 92.31503 -273.657314)
			(xy 92.31503 -273.70151) (xy 92.67063 -273.70151)
		)
		(stroke
			(width 0)
			(type solid)
		)
		(fill yes)
		(layer "In11.Cu")
		(net "M_D_CPU1_SA_DQ<19>")
	)
	(gr_poly
		(pts
			(xy 92.67063 -273.248882) (xy 92.67063 -273.204686) (xy 92.31503 -273.204686) (xy 92.31503 -273.248882)
			(xy 92.36202 -273.401282) (xy 92.62364 -273.401282)
		)
		(stroke
			(width 0)
			(type solid)
		)
		(fill yes)
		(layer "In11.Cu")
		(net "M_D_CPU1_SA_DQS_DP<2>")
	)
	(gr_poly
		(pts
			(xy 92.67063 -272.029174) (xy 92.62364 -271.876774) (xy 92.36202 -271.876774) (xy 92.31503 -272.029174)
			(xy 92.31503 -272.073624) (xy 92.67063 -272.073624)
		)
		(stroke
			(width 0)
			(type solid)
		)
		(fill yes)
		(layer "In11.Cu")
		(net "M_D_CPU1_SA_DQS_DP<7>")
	)
	(gr_poly
		(pts
			(xy 92.67063 -271.62125) (xy 92.67063 -271.5768) (xy 92.31503 -271.5768) (xy 92.31503 -271.62125)
			(xy 92.36202 -271.77365) (xy 92.62364 -271.77365)
		)
		(stroke
			(width 0)
			(type solid)
		)
		(fill yes)
		(layer "In11.Cu")
		(net "M_D_CPU1_SA_DQ<20>")
	)
	(gr_poly
		(pts
			(xy 92.67063 -268.77391) (xy 92.62364 -268.62151) (xy 92.36202 -268.62151) (xy 92.31503 -268.77391)
			(xy 92.31503 -268.818106) (xy 92.67063 -268.818106)
		)
		(stroke
			(width 0)
			(type solid)
		)
		(fill yes)
		(layer "In11.Cu")
		(net "M_D_CPU1_SA_DQ<27>")
	)
	(gr_poly
		(pts
			(xy 92.67063 -268.365478) (xy 92.67063 -268.321282) (xy 92.31503 -268.321282) (xy 92.31503 -268.365478)
			(xy 92.36202 -268.517878) (xy 92.62364 -268.517878)
		)
		(stroke
			(width 0)
			(type solid)
		)
		(fill yes)
		(layer "In11.Cu")
		(net "M_D_CPU1_SA_DQS_DP<3>")
	)
	(gr_poly
		(pts
			(xy 92.67063 -267.14577) (xy 92.62364 -266.99337) (xy 92.36202 -266.99337) (xy 92.31503 -267.14577)
			(xy 92.31503 -267.19022) (xy 92.67063 -267.19022)
		)
		(stroke
			(width 0)
			(type solid)
		)
		(fill yes)
		(layer "In11.Cu")
		(net "M_D_CPU1_SA_DQS_DP<8>")
	)
	(gr_poly
		(pts
			(xy 92.67063 -266.737846) (xy 92.67063 -266.69365) (xy 92.31503 -266.69365) (xy 92.31503 -266.737846)
			(xy 92.36202 -266.890246) (xy 92.62364 -266.890246)
		)
		(stroke
			(width 0)
			(type solid)
		)
		(fill yes)
		(layer "In11.Cu")
		(net "M_D_CPU1_SA_DQ<28>")
	)
	(gr_poly
		(pts
			(xy 92.67063 -263.890506) (xy 92.62364 -263.738106) (xy 92.36202 -263.738106) (xy 92.31503 -263.890506)
			(xy 92.31503 -263.934956) (xy 92.67063 -263.934956)
		)
		(stroke
			(width 0)
			(type solid)
		)
		(fill yes)
		(layer "In11.Cu")
		(net "M_D_CPU1_SA_CB<3>")
	)
	(gr_poly
		(pts
			(xy 92.67063 -263.482582) (xy 92.67063 -263.438132) (xy 92.31503 -263.438132) (xy 92.31503 -263.482582)
			(xy 92.36202 -263.634982) (xy 92.62364 -263.634982)
		)
		(stroke
			(width 0)
			(type solid)
		)
		(fill yes)
		(layer "In11.Cu")
		(net "M_D_CPU1_SA_DQS_DP<4>")
	)
	(gr_poly
		(pts
			(xy 92.67063 -261.854442) (xy 92.67063 -261.810246) (xy 92.31503 -261.810246) (xy 92.31503 -261.854442)
			(xy 92.36202 -262.006842) (xy 92.62364 -262.006842)
		)
		(stroke
			(width 0)
			(type solid)
		)
		(fill yes)
		(layer "In11.Cu")
		(net "M_D_CPU1_SA_CB<4>")
	)
	(gr_poly
		(pts
			(xy 92.67063 -259.007102) (xy 92.62364 -258.854702) (xy 92.36202 -258.854702) (xy 92.31503 -259.007102)
			(xy 92.31503 -259.051552) (xy 92.67063 -259.051552)
		)
		(stroke
			(width 0)
			(type solid)
		)
		(fill yes)
		(layer "In11.Cu")
		(net "M_D_CPU1_SA_CS_N<0>")
	)
	(gr_poly
		(pts
			(xy 92.873322 -235.425742) (xy 92.911676 -235.403644) (xy 92.733876 -235.095796) (xy 92.695522 -235.117894)
			(xy 92.587064 -235.234734) (xy 92.717874 -235.461302)
		)
		(stroke
			(width 0)
			(type solid)
		)
		(fill yes)
		(layer "In11.Cu")
		(net "M_D_CPU1_SB_DQS_DP<1>")
	)
	(gr_poly
		(pts
			(xy 92.987368 -234.812586) (xy 93.095826 -234.695746) (xy 92.965016 -234.469178) (xy 92.809568 -234.504738)
			(xy 92.771214 -234.526836) (xy 92.949014 -234.834684)
		)
		(stroke
			(width 0)
			(type solid)
		)
		(fill yes)
		(layer "In11.Cu")
		(net "M_D_CPU1_SB_DQS_DN<1>")
	)
	(gr_poly
		(pts
			(xy 93.01353 -249.416062) (xy 93.01353 -249.371612) (xy 92.65793 -249.371612) (xy 92.65793 -249.416062)
			(xy 92.70492 -249.568462) (xy 92.96654 -249.568462)
		)
		(stroke
			(width 0)
			(type solid)
		)
		(fill yes)
		(layer "In11.Cu")
		(net "M_D_CPU1_SB_CA<2>")
	)
	(gr_poly
		(pts
			(xy 93.01353 -248.196354) (xy 92.96654 -248.043954) (xy 92.70492 -248.043954) (xy 92.65793 -248.196354)
			(xy 92.65793 -248.24055) (xy 93.01353 -248.24055)
		)
		(stroke
			(width 0)
			(type solid)
		)
		(fill yes)
		(layer "In11.Cu")
		(net "M_D_CPU1_SB_CA<5>")
	)
	(gr_poly
		(pts
			(xy 93.01353 -247.787922) (xy 93.01353 -247.743726) (xy 92.65793 -247.743726) (xy 92.65793 -247.787922)
			(xy 92.70492 -247.940322) (xy 92.96654 -247.940322)
		)
		(stroke
			(width 0)
			(type solid)
		)
		(fill yes)
		(layer "In11.Cu")
		(net "M_D_CPU1_SB_PAR")
	)
	(gr_poly
		(pts
			(xy 93.01353 -246.568722) (xy 92.96654 -246.416322) (xy 92.70492 -246.416322) (xy 92.65793 -246.568722)
			(xy 92.65793 -246.612918) (xy 93.01353 -246.612918)
		)
		(stroke
			(width 0)
			(type solid)
		)
		(fill yes)
		(layer "In11.Cu")
		(net "M_D_CPU1_SB_CB<6>")
	)
	(gr_poly
		(pts
			(xy 93.01353 -243.31295) (xy 92.96654 -243.16055) (xy 92.70492 -243.16055) (xy 92.65793 -243.31295)
			(xy 92.65793 -243.3574) (xy 93.01353 -243.3574)
		)
		(stroke
			(width 0)
			(type solid)
		)
		(fill yes)
		(layer "In11.Cu")
		(net "M_D_CPU1_SB_CB<2>")
	)
	(gr_poly
		(pts
			(xy 93.01353 -242.905026) (xy 93.01353 -242.860576) (xy 92.65793 -242.860576) (xy 92.65793 -242.905026)
			(xy 92.70492 -243.057426) (xy 92.96654 -243.057426)
		)
		(stroke
			(width 0)
			(type solid)
		)
		(fill yes)
		(layer "In11.Cu")
		(net "M_D_CPU1_SB_CB<1>")
	)
	(gr_poly
		(pts
			(xy 93.01353 -241.685318) (xy 92.96654 -241.532918) (xy 92.70492 -241.532918) (xy 92.65793 -241.685318)
			(xy 92.65793 -241.729514) (xy 93.01353 -241.729514)
		)
		(stroke
			(width 0)
			(type solid)
		)
		(fill yes)
		(layer "In11.Cu")
		(net "M_D_CPU1_SB_DQ<2>")
	)
	(gr_poly
		(pts
			(xy 93.01353 -241.276886) (xy 93.01353 -241.23269) (xy 92.65793 -241.23269) (xy 92.65793 -241.276886)
			(xy 92.70492 -241.429286) (xy 92.96654 -241.429286)
		)
		(stroke
			(width 0)
			(type solid)
		)
		(fill yes)
		(layer "In11.Cu")
		(net "M_D_CPU1_SB_DQ<1>")
	)
	(gr_poly
		(pts
			(xy 93.01353 -240.057178) (xy 92.96654 -239.904778) (xy 92.70492 -239.904778) (xy 92.65793 -240.057178)
			(xy 92.65793 -240.101628) (xy 93.01353 -240.101628)
		)
		(stroke
			(width 0)
			(type solid)
		)
		(fill yes)
		(layer "In11.Cu")
		(net "M_D_CPU1_SB_DQS_DN<0>")
	)
	(gr_poly
		(pts
			(xy 93.01353 -239.649254) (xy 93.01353 -239.604804) (xy 92.65793 -239.604804) (xy 92.65793 -239.649254)
			(xy 92.70492 -239.801654) (xy 92.96654 -239.801654)
		)
		(stroke
			(width 0)
			(type solid)
		)
		(fill yes)
		(layer "In11.Cu")
		(net "M_D_CPU1_SB_DQS_DN<5>")
	)
	(gr_poly
		(pts
			(xy 93.01353 -238.429546) (xy 92.96654 -238.277146) (xy 92.70492 -238.277146) (xy 92.65793 -238.429546)
			(xy 92.65793 -238.473996) (xy 93.01353 -238.473996)
		)
		(stroke
			(width 0)
			(type solid)
		)
		(fill yes)
		(layer "In11.Cu")
		(net "M_D_CPU1_SB_DQ<6>")
	)
	(gr_poly
		(pts
			(xy 93.01353 -238.021622) (xy 93.01353 -237.977172) (xy 92.65793 -237.977172) (xy 92.65793 -238.021622)
			(xy 92.70492 -238.174022) (xy 92.96654 -238.174022)
		)
		(stroke
			(width 0)
			(type solid)
		)
		(fill yes)
		(layer "In11.Cu")
		(net "M_D_CPU1_SB_DQ<5>")
	)
	(gr_poly
		(pts
			(xy 93.01353 -236.801914) (xy 92.96654 -236.649514) (xy 92.70492 -236.649514) (xy 92.65793 -236.801914)
			(xy 92.65793 -236.84611) (xy 93.01353 -236.84611)
		)
		(stroke
			(width 0)
			(type solid)
		)
		(fill yes)
		(layer "In11.Cu")
		(net "M_D_CPU1_SB_DQ<10>")
	)
	(gr_poly
		(pts
			(xy 93.01353 -236.39399) (xy 93.01353 -236.34954) (xy 92.65793 -236.34954) (xy 92.65793 -236.39399)
			(xy 92.70492 -236.54639) (xy 92.96654 -236.54639)
		)
		(stroke
			(width 0)
			(type solid)
		)
		(fill yes)
		(layer "In11.Cu")
		(net "M_D_CPU1_SB_DQ<9>")
	)
	(gr_poly
		(pts
			(xy 93.01353 -231.91851) (xy 92.96654 -231.76611) (xy 92.70492 -231.76611) (xy 92.65793 -231.91851)
			(xy 92.65793 -231.96296) (xy 93.01353 -231.96296)
		)
		(stroke
			(width 0)
			(type solid)
		)
		(fill yes)
		(layer "In11.Cu")
		(net "M_D_CPU1_SB_DQS_DP<6>")
	)
	(gr_poly
		(pts
			(xy 93.01353 -231.510586) (xy 93.01353 -231.466136) (xy 92.65793 -231.466136) (xy 92.65793 -231.510586)
			(xy 92.70492 -231.662986) (xy 92.96654 -231.662986)
		)
		(stroke
			(width 0)
			(type solid)
		)
		(fill yes)
		(layer "In11.Cu")
		(net "M_D_CPU1_SB_DQ<12>")
	)
	(gr_poly
		(pts
			(xy 93.01353 -230.290878) (xy 92.96654 -230.138478) (xy 92.70492 -230.138478) (xy 92.65793 -230.290878)
			(xy 92.65793 -230.335074) (xy 93.01353 -230.335074)
		)
		(stroke
			(width 0)
			(type solid)
		)
		(fill yes)
		(layer "In11.Cu")
		(net "M_D_CPU1_SB_DQ<15>")
	)
	(gr_poly
		(pts
			(xy 93.01353 -229.882446) (xy 93.01353 -229.83825) (xy 92.65793 -229.83825) (xy 92.65793 -229.882446)
			(xy 92.70492 -230.034846) (xy 92.96654 -230.034846)
		)
		(stroke
			(width 0)
			(type solid)
		)
		(fill yes)
		(layer "In11.Cu")
		(net "M_D_CPU1_SB_DQ<24>")
	)
	(gr_poly
		(pts
			(xy 93.01353 -228.663246) (xy 92.96654 -228.510846) (xy 92.70492 -228.510846) (xy 92.65793 -228.663246)
			(xy 92.65793 -228.707442) (xy 93.01353 -228.707442)
		)
		(stroke
			(width 0)
			(type solid)
		)
		(fill yes)
		(layer "In11.Cu")
		(net "M_D_CPU1_SB_DQ<27>")
	)
	(gr_poly
		(pts
			(xy 93.01353 -228.254814) (xy 93.01353 -228.210618) (xy 92.65793 -228.210618) (xy 92.65793 -228.254814)
			(xy 92.70492 -228.407214) (xy 92.96654 -228.407214)
		)
		(stroke
			(width 0)
			(type solid)
		)
		(fill yes)
		(layer "In11.Cu")
		(net "M_D_CPU1_SB_DQS_DP<3>")
	)
	(gr_poly
		(pts
			(xy 93.01353 -226.627182) (xy 93.01353 -226.582732) (xy 92.65793 -226.582732) (xy 92.65793 -226.627182)
			(xy 92.70492 -226.779582) (xy 92.96654 -226.779582)
		)
		(stroke
			(width 0)
			(type solid)
		)
		(fill yes)
		(layer "In11.Cu")
		(net "M_D_CPU1_SB_DQ<28>")
	)
	(gr_poly
		(pts
			(xy 93.01353 -225.407474) (xy 92.96654 -225.255074) (xy 92.70492 -225.255074) (xy 92.65793 -225.407474)
			(xy 92.65793 -225.45167) (xy 93.01353 -225.45167)
		)
		(stroke
			(width 0)
			(type solid)
		)
		(fill yes)
		(layer "In11.Cu")
		(net "M_D_CPU1_SB_DQ<31>")
	)
	(gr_poly
		(pts
			(xy 93.01607 -244.53215) (xy 93.01607 -244.487954) (xy 92.66047 -244.487954) (xy 92.66047 -244.53215)
			(xy 92.70746 -244.68455) (xy 92.96908 -244.68455)
		)
		(stroke
			(width 0)
			(type solid)
		)
		(fill yes)
		(layer "In11.Cu")
		(net "M_D_CPU1_SB_DQS_DN<4>")
	)
	(gr_poly
		(pts
			(xy 93.021912 -246.16029) (xy 93.021912 -246.11584) (xy 92.666312 -246.11584) (xy 92.666312 -246.16029)
			(xy 92.713302 -246.31269) (xy 92.974922 -246.31269)
		)
		(stroke
			(width 0)
			(type solid)
		)
		(fill yes)
		(layer "In11.Cu")
		(net "M_D_CPU1_SB_CB<5>")
	)
	(gr_poly
		(pts
			(xy 93.022674 -227.035614) (xy 92.975684 -226.883214) (xy 92.714064 -226.883214) (xy 92.667074 -227.035614)
			(xy 92.667074 -227.07981) (xy 93.022674 -227.07981)
		)
		(stroke
			(width 0)
			(type solid)
		)
		(fill yes)
		(layer "In11.Cu")
		(net "M_D_CPU1_SB_DQS_DP<8>")
	)
	(gr_poly
		(pts
			(xy 93.028008 -244.94109) (xy 92.981018 -244.78869) (xy 92.719398 -244.78869) (xy 92.672408 -244.94109)
			(xy 92.672408 -244.985286) (xy 93.028008 -244.985286)
		)
		(stroke
			(width 0)
			(type solid)
		)
		(fill yes)
		(layer "In11.Cu")
		(net "M_D_CPU1_SB_DQS_DN<9>")
	)
	(gr_poly
		(pts
			(xy 93.123512 -279.354534) (xy 93.076522 -279.202134) (xy 92.814902 -279.202134) (xy 92.767912 -279.354534)
			(xy 92.767912 -279.39873) (xy 93.123512 -279.39873)
		)
		(stroke
			(width 0)
			(type solid)
		)
		(fill yes)
		(layer "In11.Cu")
		(net "M_D_CPU1_SA_DQ<10>")
	)
	(gr_poly
		(pts
			(xy 93.123512 -278.946102) (xy 93.123512 -278.901906) (xy 92.767912 -278.901906) (xy 92.767912 -278.946102)
			(xy 92.814902 -279.098502) (xy 93.076522 -279.098502)
		)
		(stroke
			(width 0)
			(type solid)
		)
		(fill yes)
		(layer "In11.Cu")
		(net "M_D_CPU1_SA_DQ<9>")
	)
	(gr_poly
		(pts
			(xy 93.123512 -277.726394) (xy 93.076522 -277.573994) (xy 92.814902 -277.573994) (xy 92.767912 -277.726394)
			(xy 92.767912 -277.770844) (xy 93.123512 -277.770844)
		)
		(stroke
			(width 0)
			(type solid)
		)
		(fill yes)
		(layer "In11.Cu")
		(net "M_D_CPU1_SA_DQS_DN<1>")
	)
	(gr_poly
		(pts
			(xy 93.123512 -277.318216) (xy 93.123512 -277.27402) (xy 92.767912 -277.27402) (xy 92.767912 -277.318216)
			(xy 92.814902 -277.470616) (xy 93.076522 -277.470616)
		)
		(stroke
			(width 0)
			(type solid)
		)
		(fill yes)
		(layer "In11.Cu")
		(net "M_D_CPU1_SA_DQS_DN<6>")
	)
	(gr_poly
		(pts
			(xy 93.123512 -276.098762) (xy 93.076522 -275.946362) (xy 92.814902 -275.946362) (xy 92.767912 -276.098762)
			(xy 92.767912 -276.143212) (xy 93.123512 -276.143212)
		)
		(stroke
			(width 0)
			(type solid)
		)
		(fill yes)
		(layer "In11.Cu")
		(net "M_D_CPU1_SA_DQ<14>")
	)
	(gr_poly
		(pts
			(xy 93.123512 -275.690584) (xy 93.123512 -275.646388) (xy 92.767912 -275.646388) (xy 92.767912 -275.690584)
			(xy 92.814902 -275.842984) (xy 93.076522 -275.842984)
		)
		(stroke
			(width 0)
			(type solid)
		)
		(fill yes)
		(layer "In11.Cu")
		(net "M_D_CPU1_SA_DQ<13>")
	)
	(gr_poly
		(pts
			(xy 93.123512 -274.47113) (xy 93.076522 -274.31873) (xy 92.814902 -274.31873) (xy 92.767912 -274.47113)
			(xy 92.767912 -274.515326) (xy 93.123512 -274.515326)
		)
		(stroke
			(width 0)
			(type solid)
		)
		(fill yes)
		(layer "In11.Cu")
		(net "M_D_CPU1_SA_DQ<18>")
	)
	(gr_poly
		(pts
			(xy 93.123512 -274.062698) (xy 93.123512 -274.018502) (xy 92.767912 -274.018502) (xy 92.767912 -274.062698)
			(xy 92.814902 -274.215098) (xy 93.076522 -274.215098)
		)
		(stroke
			(width 0)
			(type solid)
		)
		(fill yes)
		(layer "In11.Cu")
		(net "M_D_CPU1_SA_DQ<17>")
	)
	(gr_poly
		(pts
			(xy 93.123512 -272.843498) (xy 93.076522 -272.691098) (xy 92.814902 -272.691098) (xy 92.767912 -272.843498)
			(xy 92.767912 -272.887694) (xy 93.123512 -272.887694)
		)
		(stroke
			(width 0)
			(type solid)
		)
		(fill yes)
		(layer "In11.Cu")
		(net "M_D_CPU1_SA_DQS_DN<2>")
	)
	(gr_poly
		(pts
			(xy 93.123512 -272.435066) (xy 93.123512 -272.39087) (xy 92.767912 -272.39087) (xy 92.767912 -272.435066)
			(xy 92.814902 -272.587466) (xy 93.076522 -272.587466)
		)
		(stroke
			(width 0)
			(type solid)
		)
		(fill yes)
		(layer "In11.Cu")
		(net "M_D_CPU1_SA_DQS_DN<7>")
	)
	(gr_poly
		(pts
			(xy 93.123512 -271.215358) (xy 93.076522 -271.062958) (xy 92.814902 -271.062958) (xy 92.767912 -271.215358)
			(xy 92.767912 -271.259808) (xy 93.123512 -271.259808)
		)
		(stroke
			(width 0)
			(type solid)
		)
		(fill yes)
		(layer "In11.Cu")
		(net "M_D_CPU1_SA_DQ<22>")
	)
	(gr_poly
		(pts
			(xy 93.123512 -270.807434) (xy 93.123512 -270.762984) (xy 92.767912 -270.762984) (xy 92.767912 -270.807434)
			(xy 92.814902 -270.959834) (xy 93.076522 -270.959834)
		)
		(stroke
			(width 0)
			(type solid)
		)
		(fill yes)
		(layer "In11.Cu")
		(net "M_D_CPU1_SA_DQ<21>")
	)
	(gr_poly
		(pts
			(xy 93.123512 -269.587726) (xy 93.076522 -269.435326) (xy 92.814902 -269.435326) (xy 92.767912 -269.587726)
			(xy 92.767912 -269.631922) (xy 93.123512 -269.631922)
		)
		(stroke
			(width 0)
			(type solid)
		)
		(fill yes)
		(layer "In11.Cu")
		(net "M_D_CPU1_SA_DQ<26>")
	)
	(gr_poly
		(pts
			(xy 93.123512 -269.179294) (xy 93.123512 -269.135098) (xy 92.767912 -269.135098) (xy 92.767912 -269.179294)
			(xy 92.814902 -269.331694) (xy 93.076522 -269.331694)
		)
		(stroke
			(width 0)
			(type solid)
		)
		(fill yes)
		(layer "In11.Cu")
		(net "M_D_CPU1_SA_DQ<25>")
	)
	(gr_poly
		(pts
			(xy 93.123512 -267.960094) (xy 93.076522 -267.807694) (xy 92.814902 -267.807694) (xy 92.767912 -267.960094)
			(xy 92.767912 -268.00429) (xy 93.123512 -268.00429)
		)
		(stroke
			(width 0)
			(type solid)
		)
		(fill yes)
		(layer "In11.Cu")
		(net "M_D_CPU1_SA_DQS_DN<3>")
	)
	(gr_poly
		(pts
			(xy 93.123512 -267.551662) (xy 93.123512 -267.507466) (xy 92.767912 -267.507466) (xy 92.767912 -267.551662)
			(xy 92.814902 -267.704062) (xy 93.076522 -267.704062)
		)
		(stroke
			(width 0)
			(type solid)
		)
		(fill yes)
		(layer "In11.Cu")
		(net "M_D_CPU1_SA_DQS_DN<8>")
	)
	(gr_poly
		(pts
			(xy 93.123512 -266.331954) (xy 93.076522 -266.179554) (xy 92.814902 -266.179554) (xy 92.767912 -266.331954)
			(xy 92.767912 -266.376404) (xy 93.123512 -266.376404)
		)
		(stroke
			(width 0)
			(type solid)
		)
		(fill yes)
		(layer "In11.Cu")
		(net "M_D_CPU1_SA_DQ<30>")
	)
	(gr_poly
		(pts
			(xy 93.123512 -265.92403) (xy 93.123512 -265.87958) (xy 92.767912 -265.87958) (xy 92.767912 -265.92403)
			(xy 92.814902 -266.07643) (xy 93.076522 -266.07643)
		)
		(stroke
			(width 0)
			(type solid)
		)
		(fill yes)
		(layer "In11.Cu")
		(net "M_D_CPU1_SA_DQ<29>")
	)
	(gr_poly
		(pts
			(xy 93.123512 -264.704322) (xy 93.076522 -264.551922) (xy 92.814902 -264.551922) (xy 92.767912 -264.704322)
			(xy 92.767912 -264.748772) (xy 93.123512 -264.748772)
		)
		(stroke
			(width 0)
			(type solid)
		)
		(fill yes)
		(layer "In11.Cu")
		(net "M_D_CPU1_SA_CB<2>")
	)
	(gr_poly
		(pts
			(xy 93.123512 -264.296398) (xy 93.123512 -264.251948) (xy 92.767912 -264.251948) (xy 92.767912 -264.296398)
			(xy 92.814902 -264.448798) (xy 93.076522 -264.448798)
		)
		(stroke
			(width 0)
			(type solid)
		)
		(fill yes)
		(layer "In11.Cu")
		(net "M_D_CPU1_SA_CB<1>")
	)
	(gr_poly
		(pts
			(xy 93.123512 -263.07669) (xy 93.076522 -262.92429) (xy 92.814902 -262.92429) (xy 92.767912 -263.07669)
			(xy 92.767912 -263.120886) (xy 93.123512 -263.120886)
		)
		(stroke
			(width 0)
			(type solid)
		)
		(fill yes)
		(layer "In11.Cu")
		(net "M_D_CPU1_SA_DQS_DN<4>")
	)
	(gr_poly
		(pts
			(xy 93.123512 -261.449058) (xy 93.076522 -261.296658) (xy 92.814902 -261.296658) (xy 92.767912 -261.449058)
			(xy 92.767912 -261.493254) (xy 93.123512 -261.493254)
		)
		(stroke
			(width 0)
			(type solid)
		)
		(fill yes)
		(layer "In11.Cu")
		(net "M_D_CPU1_SA_CB<6>")
	)
	(gr_poly
		(pts
			(xy 93.123512 -261.040626) (xy 93.123512 -260.99643) (xy 92.767912 -260.99643) (xy 92.767912 -261.040626)
			(xy 92.814902 -261.193026) (xy 93.076522 -261.193026)
		)
		(stroke
			(width 0)
			(type solid)
		)
		(fill yes)
		(layer "In11.Cu")
		(net "M_D_CPU1_SA_CB<5>")
	)
	(gr_poly
		(pts
			(xy 93.123512 -259.412994) (xy 93.123512 -259.368544) (xy 92.767912 -259.368544) (xy 92.767912 -259.412994)
			(xy 92.814902 -259.565394) (xy 93.076522 -259.565394)
		)
		(stroke
			(width 0)
			(type solid)
		)
		(fill yes)
		(layer "In11.Cu")
		(net "M_D_CPU1_SA_CS_N<2>")
	)
	(gr_poly
		(pts
			(xy 93.123512 -256.157222) (xy 93.123512 -256.113026) (xy 92.767912 -256.113026) (xy 92.767912 -256.157222)
			(xy 92.814902 -256.309622) (xy 93.076522 -256.309622)
		)
		(stroke
			(width 0)
			(type solid)
		)
		(fill yes)
		(layer "In11.Cu")
		(net "M_D_CPU1_SA_CA<4>")
	)
	(gr_poly
		(pts
			(xy 93.126052 -258.193286) (xy 93.079062 -258.040886) (xy 92.817442 -258.040886) (xy 92.770452 -258.193286)
			(xy 92.770452 -258.237736) (xy 93.126052 -258.237736)
		)
		(stroke
			(width 0)
			(type solid)
		)
		(fill yes)
		(layer "In11.Cu")
		(net "M_D_CPU1_SA_CS_N<1>")
	)
	(gr_poly
		(pts
			(xy 93.131894 -256.565654) (xy 93.084904 -256.413254) (xy 92.823284 -256.413254) (xy 92.776294 -256.565654)
			(xy 92.776294 -256.610104) (xy 93.131894 -256.610104)
		)
		(stroke
			(width 0)
			(type solid)
		)
		(fill yes)
		(layer "In11.Cu")
		(net "M_D_CPU1_SA_CA<3>")
	)
	(gr_poly
		(pts
			(xy 93.13545 -262.668258) (xy 93.13545 -262.623808) (xy 92.77985 -262.623808) (xy 92.77985 -262.668258)
			(xy 92.82684 -262.820658) (xy 93.08846 -262.820658)
		)
		(stroke
			(width 0)
			(type solid)
		)
		(fill yes)
		(layer "In11.Cu")
		(net "M_D_CPU1_SA_DQS_DN<9>")
	)
	(gr_poly
		(pts
			(xy 93.13799 -257.784854) (xy 93.13799 -257.740404) (xy 92.78239 -257.740404) (xy 92.78239 -257.784854)
			(xy 92.82938 -257.937254) (xy 93.091 -257.937254)
		)
		(stroke
			(width 0)
			(type solid)
		)
		(fill yes)
		(layer "In11.Cu")
		(net "M_D_CPU1_SA_CA<0>")
	)
	(gr_poly
		(pts
			(xy 93.34881 -232.993692) (xy 93.387164 -232.971594) (xy 93.209364 -232.663746) (xy 93.17101 -232.685844)
			(xy 93.062552 -232.802684) (xy 93.193362 -233.029252)
		)
		(stroke
			(width 0)
			(type solid)
		)
		(fill yes)
		(layer "In11.Cu")
		(net "M_D_CPU1_SB_DQS_DN<6>")
	)
	(gr_poly
		(pts
			(xy 93.462856 -232.380536) (xy 93.571314 -232.263696) (xy 93.440504 -232.037128) (xy 93.285056 -232.072688)
			(xy 93.246702 -232.094786) (xy 93.424502 -232.402634)
		)
		(stroke
			(width 0)
			(type solid)
		)
		(fill yes)
		(layer "In11.Cu")
		(net "M_D_CPU1_SB_DQS_DP<6>")
	)
	(gr_poly
		(pts
			(xy 93.497908 -245.754906) (xy 93.450918 -245.602506) (xy 93.189298 -245.602506) (xy 93.142308 -245.754906)
			(xy 93.142308 -245.799102) (xy 93.497908 -245.799102)
		)
		(stroke
			(width 0)
			(type solid)
		)
		(fill yes)
		(layer "In11.Cu")
		(net "M_D_CPU1_SB_CB<7>")
	)
	(gr_poly
		(pts
			(xy 93.497908 -245.346474) (xy 93.497908 -245.302278) (xy 93.142308 -245.302278) (xy 93.142308 -245.346474)
			(xy 93.189298 -245.498874) (xy 93.450918 -245.498874)
		)
		(stroke
			(width 0)
			(type solid)
		)
		(fill yes)
		(layer "In11.Cu")
		(net "M_D_CPU1_SB_DQS_DP<9>")
	)
	(gr_poly
		(pts
			(xy 93.500448 -249.01017) (xy 93.453458 -248.85777) (xy 93.191838 -248.85777) (xy 93.144848 -249.01017)
			(xy 93.144848 -249.05462) (xy 93.500448 -249.05462)
		)
		(stroke
			(width 0)
			(type solid)
		)
		(fill yes)
		(layer "In11.Cu")
		(net "M_D_CPU1_SB_CA<3>")
	)
	(gr_poly
		(pts
			(xy 93.500448 -248.602246) (xy 93.500448 -248.557796) (xy 93.144848 -248.557796) (xy 93.144848 -248.602246)
			(xy 93.191838 -248.754646) (xy 93.453458 -248.754646)
		)
		(stroke
			(width 0)
			(type solid)
		)
		(fill yes)
		(layer "In11.Cu")
		(net "M_D_CPU1_SB_CA<4>")
	)
	(gr_poly
		(pts
			(xy 93.500448 -247.382538) (xy 93.453458 -247.230138) (xy 93.191838 -247.230138) (xy 93.144848 -247.382538)
			(xy 93.144848 -247.426734) (xy 93.500448 -247.426734)
		)
		(stroke
			(width 0)
			(type solid)
		)
		(fill yes)
		(layer "In11.Cu")
		(net "M_D_CPU1_SB_CA<6>")
	)
	(gr_poly
		(pts
			(xy 93.500448 -246.974106) (xy 93.500448 -246.92991) (xy 93.144848 -246.92991) (xy 93.144848 -246.974106)
			(xy 93.191838 -247.126506) (xy 93.453458 -247.126506)
		)
		(stroke
			(width 0)
			(type solid)
		)
		(fill yes)
		(layer "In11.Cu")
		(net "M_D_CPU1_SB_CB<4>")
	)
	(gr_poly
		(pts
			(xy 93.500448 -244.126766) (xy 93.453458 -243.974366) (xy 93.191838 -243.974366) (xy 93.144848 -244.126766)
			(xy 93.144848 -244.171216) (xy 93.500448 -244.171216)
		)
		(stroke
			(width 0)
			(type solid)
		)
		(fill yes)
		(layer "In11.Cu")
		(net "M_D_CPU1_SB_DQS_DP<4>")
	)
	(gr_poly
		(pts
			(xy 93.500448 -243.718842) (xy 93.500448 -243.674392) (xy 93.144848 -243.674392) (xy 93.144848 -243.718842)
			(xy 93.191838 -243.871242) (xy 93.453458 -243.871242)
		)
		(stroke
			(width 0)
			(type solid)
		)
		(fill yes)
		(layer "In11.Cu")
		(net "M_D_CPU1_SB_CB<0>")
	)
	(gr_poly
		(pts
			(xy 93.500448 -242.499134) (xy 93.453458 -242.346734) (xy 93.191838 -242.346734) (xy 93.144848 -242.499134)
			(xy 93.144848 -242.54333) (xy 93.500448 -242.54333)
		)
		(stroke
			(width 0)
			(type solid)
		)
		(fill yes)
		(layer "In11.Cu")
		(net "M_D_CPU1_SB_CB<3>")
	)
	(gr_poly
		(pts
			(xy 93.500448 -242.090702) (xy 93.500448 -242.046506) (xy 93.144848 -242.046506) (xy 93.144848 -242.090702)
			(xy 93.191838 -242.243102) (xy 93.453458 -242.243102)
		)
		(stroke
			(width 0)
			(type solid)
		)
		(fill yes)
		(layer "In11.Cu")
		(net "M_D_CPU1_SB_DQ<0>")
	)
	(gr_poly
		(pts
			(xy 93.500448 -240.871502) (xy 93.453458 -240.719102) (xy 93.191838 -240.719102) (xy 93.144848 -240.871502)
			(xy 93.144848 -240.915698) (xy 93.500448 -240.915698)
		)
		(stroke
			(width 0)
			(type solid)
		)
		(fill yes)
		(layer "In11.Cu")
		(net "M_D_CPU1_SB_DQ<3>")
	)
	(gr_poly
		(pts
			(xy 93.500448 -240.46307) (xy 93.500448 -240.418874) (xy 93.144848 -240.418874) (xy 93.144848 -240.46307)
			(xy 93.191838 -240.61547) (xy 93.453458 -240.61547)
		)
		(stroke
			(width 0)
			(type solid)
		)
		(fill yes)
		(layer "In11.Cu")
		(net "M_D_CPU1_SB_DQS_DP<0>")
	)
	(gr_poly
		(pts
			(xy 93.500448 -239.243362) (xy 93.453458 -239.090962) (xy 93.191838 -239.090962) (xy 93.144848 -239.243362)
			(xy 93.144848 -239.287812) (xy 93.500448 -239.287812)
		)
		(stroke
			(width 0)
			(type solid)
		)
		(fill yes)
		(layer "In11.Cu")
		(net "M_D_CPU1_SB_DQS_DP<5>")
	)
	(gr_poly
		(pts
			(xy 93.500448 -238.835438) (xy 93.500448 -238.790988) (xy 93.144848 -238.790988) (xy 93.144848 -238.835438)
			(xy 93.191838 -238.987838) (xy 93.453458 -238.987838)
		)
		(stroke
			(width 0)
			(type solid)
		)
		(fill yes)
		(layer "In11.Cu")
		(net "M_D_CPU1_SB_DQ<4>")
	)
	(gr_poly
		(pts
			(xy 93.500448 -237.61573) (xy 93.453458 -237.46333) (xy 93.191838 -237.46333) (xy 93.144848 -237.61573)
			(xy 93.144848 -237.659926) (xy 93.500448 -237.659926)
		)
		(stroke
			(width 0)
			(type solid)
		)
		(fill yes)
		(layer "In11.Cu")
		(net "M_D_CPU1_SB_DQ<7>")
	)
	(gr_poly
		(pts
			(xy 93.500448 -237.207806) (xy 93.500448 -237.163356) (xy 93.144848 -237.163356) (xy 93.144848 -237.207806)
			(xy 93.191838 -237.360206) (xy 93.453458 -237.360206)
		)
		(stroke
			(width 0)
			(type solid)
		)
		(fill yes)
		(layer "In11.Cu")
		(net "M_D_CPU1_SB_DQ<8>")
	)
	(gr_poly
		(pts
			(xy 93.500448 -235.988098) (xy 93.453458 -235.835698) (xy 93.191838 -235.835698) (xy 93.144848 -235.988098)
			(xy 93.144848 -236.032294) (xy 93.500448 -236.032294)
		)
		(stroke
			(width 0)
			(type solid)
		)
		(fill yes)
		(layer "In11.Cu")
		(net "M_D_CPU1_SB_DQ<11>")
	)
	(gr_poly
		(pts
			(xy 93.500448 -235.579666) (xy 93.500448 -235.53547) (xy 93.144848 -235.53547) (xy 93.144848 -235.579666)
			(xy 93.191838 -235.732066) (xy 93.453458 -235.732066)
		)
		(stroke
			(width 0)
			(type solid)
		)
		(fill yes)
		(layer "In11.Cu")
		(net "M_D_CPU1_SB_DQS_DP<1>")
	)
	(gr_poly
		(pts
			(xy 93.500448 -231.104694) (xy 93.453458 -230.952294) (xy 93.191838 -230.952294) (xy 93.144848 -231.104694)
			(xy 93.144848 -231.14889) (xy 93.500448 -231.14889)
		)
		(stroke
			(width 0)
			(type solid)
		)
		(fill yes)
		(layer "In11.Cu")
		(net "M_D_CPU1_SB_DQ<14>")
	)
	(gr_poly
		(pts
			(xy 93.500448 -230.696262) (xy 93.500448 -230.652066) (xy 93.144848 -230.652066) (xy 93.144848 -230.696262)
			(xy 93.191838 -230.848662) (xy 93.453458 -230.848662)
		)
		(stroke
			(width 0)
			(type solid)
		)
		(fill yes)
		(layer "In11.Cu")
		(net "M_D_CPU1_SB_DQ<13>")
	)
	(gr_poly
		(pts
			(xy 93.500448 -229.477062) (xy 93.453458 -229.324662) (xy 93.191838 -229.324662) (xy 93.144848 -229.477062)
			(xy 93.144848 -229.521258) (xy 93.500448 -229.521258)
		)
		(stroke
			(width 0)
			(type solid)
		)
		(fill yes)
		(layer "In11.Cu")
		(net "M_D_CPU1_SB_DQ<26>")
	)
	(gr_poly
		(pts
			(xy 93.500448 -229.06863) (xy 93.500448 -229.024434) (xy 93.144848 -229.024434) (xy 93.144848 -229.06863)
			(xy 93.191838 -229.22103) (xy 93.453458 -229.22103)
		)
		(stroke
			(width 0)
			(type solid)
		)
		(fill yes)
		(layer "In11.Cu")
		(net "M_D_CPU1_SB_DQ<25>")
	)
	(gr_poly
		(pts
			(xy 93.500448 -227.848922) (xy 93.453458 -227.696522) (xy 93.191838 -227.696522) (xy 93.144848 -227.848922)
			(xy 93.144848 -227.893372) (xy 93.500448 -227.893372)
		)
		(stroke
			(width 0)
			(type solid)
		)
		(fill yes)
		(layer "In11.Cu")
		(net "M_D_CPU1_SB_DQS_DN<3>")
	)
	(gr_poly
		(pts
			(xy 93.500448 -227.440998) (xy 93.500448 -227.396548) (xy 93.144848 -227.396548) (xy 93.144848 -227.440998)
			(xy 93.191838 -227.593398) (xy 93.453458 -227.593398)
		)
		(stroke
			(width 0)
			(type solid)
		)
		(fill yes)
		(layer "In11.Cu")
		(net "M_D_CPU1_SB_DQS_DN<8>")
	)
	(gr_poly
		(pts
			(xy 93.500448 -226.22129) (xy 93.453458 -226.06889) (xy 93.191838 -226.06889) (xy 93.144848 -226.22129)
			(xy 93.144848 -226.26574) (xy 93.500448 -226.26574)
		)
		(stroke
			(width 0)
			(type solid)
		)
		(fill yes)
		(layer "In11.Cu")
		(net "M_D_CPU1_SB_DQ<30>")
	)
	(gr_poly
		(pts
			(xy 93.500448 -225.813366) (xy 93.500448 -225.768916) (xy 93.144848 -225.768916) (xy 93.144848 -225.813366)
			(xy 93.191838 -225.965766) (xy 93.453458 -225.965766)
		)
		(stroke
			(width 0)
			(type solid)
		)
		(fill yes)
		(layer "In11.Cu")
		(net "M_D_CPU1_SB_DQ<29>")
	)
	(gr_poly
		(pts
			(xy 93.598492 -268.77391) (xy 93.551502 -268.62151) (xy 93.289882 -268.62151) (xy 93.242892 -268.77391)
			(xy 93.242892 -268.81836) (xy 93.598492 -268.81836)
		)
		(stroke
			(width 0)
			(type solid)
		)
		(fill yes)
		(layer "In11.Cu")
		(net "M_D_CPU1_SA_DQ<27>")
	)
	(gr_poly
		(pts
			(xy 93.598492 -262.262874) (xy 93.551502 -262.110474) (xy 93.289882 -262.110474) (xy 93.242892 -262.262874)
			(xy 93.242892 -262.307324) (xy 93.598492 -262.307324)
		)
		(stroke
			(width 0)
			(type solid)
		)
		(fill yes)
		(layer "In11.Cu")
		(net "M_D_CPU1_SA_DQS_DP<9>")
	)
	(gr_poly
		(pts
			(xy 93.60789 -279.759664) (xy 93.60789 -279.715468) (xy 93.25229 -279.715468) (xy 93.25229 -279.759664)
			(xy 93.29928 -279.912064) (xy 93.5609 -279.912064)
		)
		(stroke
			(width 0)
			(type solid)
		)
		(fill yes)
		(layer "In11.Cu")
		(net "M_D_CPU1_SA_DQ<8>")
	)
	(gr_poly
		(pts
			(xy 93.60789 -257.37947) (xy 93.5609 -257.22707) (xy 93.29928 -257.22707) (xy 93.25229 -257.37947)
			(xy 93.25229 -257.423666) (xy 93.60789 -257.423666)
		)
		(stroke
			(width 0)
			(type solid)
		)
		(fill yes)
		(layer "In11.Cu")
		(net "M_D_CPU1_SA_CA<1>")
	)
	(gr_poly
		(pts
			(xy 93.60789 -256.971038) (xy 93.60789 -256.926842) (xy 93.25229 -256.926842) (xy 93.25229 -256.971038)
			(xy 93.29928 -257.123438) (xy 93.5609 -257.123438)
		)
		(stroke
			(width 0)
			(type solid)
		)
		(fill yes)
		(layer "In11.Cu")
		(net "M_D_CPU1_SA_CA<2>")
	)
	(gr_poly
		(pts
			(xy 93.61043 -278.540718) (xy 93.56344 -278.388318) (xy 93.30182 -278.388318) (xy 93.25483 -278.540718)
			(xy 93.25483 -278.584914) (xy 93.61043 -278.584914)
		)
		(stroke
			(width 0)
			(type solid)
		)
		(fill yes)
		(layer "In11.Cu")
		(net "M_D_CPU1_SA_DQ<11>")
	)
	(gr_poly
		(pts
			(xy 93.61043 -278.132286) (xy 93.61043 -278.08809) (xy 93.25483 -278.08809) (xy 93.25483 -278.132286)
			(xy 93.30182 -278.284686) (xy 93.56344 -278.284686)
		)
		(stroke
			(width 0)
			(type solid)
		)
		(fill yes)
		(layer "In11.Cu")
		(net "M_D_CPU1_SA_DQS_DP<1>")
	)
	(gr_poly
		(pts
			(xy 93.61043 -276.912578) (xy 93.56344 -276.760178) (xy 93.30182 -276.760178) (xy 93.25483 -276.912578)
			(xy 93.25483 -276.957028) (xy 93.61043 -276.957028)
		)
		(stroke
			(width 0)
			(type solid)
		)
		(fill yes)
		(layer "In11.Cu")
		(net "M_D_CPU1_SA_DQS_DP<6>")
	)
	(gr_poly
		(pts
			(xy 93.61043 -276.5044) (xy 93.61043 -276.460204) (xy 93.25483 -276.460204) (xy 93.25483 -276.5044)
			(xy 93.30182 -276.6568) (xy 93.56344 -276.6568)
		)
		(stroke
			(width 0)
			(type solid)
		)
		(fill yes)
		(layer "In11.Cu")
		(net "M_D_CPU1_SA_DQ<12>")
	)
	(gr_poly
		(pts
			(xy 93.61043 -275.284946) (xy 93.56344 -275.132546) (xy 93.30182 -275.132546) (xy 93.25483 -275.284946)
			(xy 93.25483 -275.329142) (xy 93.61043 -275.329142)
		)
		(stroke
			(width 0)
			(type solid)
		)
		(fill yes)
		(layer "In11.Cu")
		(net "M_D_CPU1_SA_DQ<15>")
	)
	(gr_poly
		(pts
			(xy 93.61043 -274.876514) (xy 93.61043 -274.832318) (xy 93.25483 -274.832318) (xy 93.25483 -274.876514)
			(xy 93.30182 -275.028914) (xy 93.56344 -275.028914)
		)
		(stroke
			(width 0)
			(type solid)
		)
		(fill yes)
		(layer "In11.Cu")
		(net "M_D_CPU1_SA_DQ<16>")
	)
	(gr_poly
		(pts
			(xy 93.61043 -273.657314) (xy 93.56344 -273.504914) (xy 93.30182 -273.504914) (xy 93.25483 -273.657314)
			(xy 93.25483 -273.70151) (xy 93.61043 -273.70151)
		)
		(stroke
			(width 0)
			(type solid)
		)
		(fill yes)
		(layer "In11.Cu")
		(net "M_D_CPU1_SA_DQ<19>")
	)
	(gr_poly
		(pts
			(xy 93.61043 -273.248882) (xy 93.61043 -273.204686) (xy 93.25483 -273.204686) (xy 93.25483 -273.248882)
			(xy 93.30182 -273.401282) (xy 93.56344 -273.401282)
		)
		(stroke
			(width 0)
			(type solid)
		)
		(fill yes)
		(layer "In11.Cu")
		(net "M_D_CPU1_SA_DQS_DP<2>")
	)
	(gr_poly
		(pts
			(xy 93.61043 -272.029174) (xy 93.56344 -271.876774) (xy 93.30182 -271.876774) (xy 93.25483 -272.029174)
			(xy 93.25483 -272.073624) (xy 93.61043 -272.073624)
		)
		(stroke
			(width 0)
			(type solid)
		)
		(fill yes)
		(layer "In11.Cu")
		(net "M_D_CPU1_SA_DQS_DP<7>")
	)
	(gr_poly
		(pts
			(xy 93.61043 -271.62125) (xy 93.61043 -271.5768) (xy 93.25483 -271.5768) (xy 93.25483 -271.62125)
			(xy 93.30182 -271.77365) (xy 93.56344 -271.77365)
		)
		(stroke
			(width 0)
			(type solid)
		)
		(fill yes)
		(layer "In11.Cu")
		(net "M_D_CPU1_SA_DQ<20>")
	)
	(gr_poly
		(pts
			(xy 93.61043 -270.401542) (xy 93.56344 -270.249142) (xy 93.30182 -270.249142) (xy 93.25483 -270.401542)
			(xy 93.25483 -270.445992) (xy 93.61043 -270.445992)
		)
		(stroke
			(width 0)
			(type solid)
		)
		(fill yes)
		(layer "In11.Cu")
		(net "M_D_CPU1_SA_DQ<23>")
	)
	(gr_poly
		(pts
			(xy 93.61043 -269.993618) (xy 93.61043 -269.949168) (xy 93.25483 -269.949168) (xy 93.25483 -269.993618)
			(xy 93.30182 -270.146018) (xy 93.56344 -270.146018)
		)
		(stroke
			(width 0)
			(type solid)
		)
		(fill yes)
		(layer "In11.Cu")
		(net "M_D_CPU1_SA_DQ<24>")
	)
	(gr_poly
		(pts
			(xy 93.61043 -268.365478) (xy 93.61043 -268.321282) (xy 93.25483 -268.321282) (xy 93.25483 -268.365478)
			(xy 93.30182 -268.517878) (xy 93.56344 -268.517878)
		)
		(stroke
			(width 0)
			(type solid)
		)
		(fill yes)
		(layer "In11.Cu")
		(net "M_D_CPU1_SA_DQS_DP<3>")
	)
	(gr_poly
		(pts
			(xy 93.61043 -267.14577) (xy 93.56344 -266.99337) (xy 93.30182 -266.99337) (xy 93.25483 -267.14577)
			(xy 93.25483 -267.19022) (xy 93.61043 -267.19022)
		)
		(stroke
			(width 0)
			(type solid)
		)
		(fill yes)
		(layer "In11.Cu")
		(net "M_D_CPU1_SA_DQS_DP<8>")
	)
	(gr_poly
		(pts
			(xy 93.61043 -266.737846) (xy 93.61043 -266.69365) (xy 93.25483 -266.69365) (xy 93.25483 -266.737846)
			(xy 93.30182 -266.890246) (xy 93.56344 -266.890246)
		)
		(stroke
			(width 0)
			(type solid)
		)
		(fill yes)
		(layer "In11.Cu")
		(net "M_D_CPU1_SA_DQ<28>")
	)
	(gr_poly
		(pts
			(xy 93.61043 -265.518138) (xy 93.56344 -265.365738) (xy 93.30182 -265.365738) (xy 93.25483 -265.518138)
			(xy 93.25483 -265.562588) (xy 93.61043 -265.562588)
		)
		(stroke
			(width 0)
			(type solid)
		)
		(fill yes)
		(layer "In11.Cu")
		(net "M_D_CPU1_SA_DQ<31>")
	)
	(gr_poly
		(pts
			(xy 93.61043 -265.110214) (xy 93.61043 -265.065764) (xy 93.25483 -265.065764) (xy 93.25483 -265.110214)
			(xy 93.30182 -265.262614) (xy 93.56344 -265.262614)
		)
		(stroke
			(width 0)
			(type solid)
		)
		(fill yes)
		(layer "In11.Cu")
		(net "M_D_CPU1_SA_CB<0>")
	)
	(gr_poly
		(pts
			(xy 93.61043 -263.890506) (xy 93.56344 -263.738106) (xy 93.30182 -263.738106) (xy 93.25483 -263.890506)
			(xy 93.25483 -263.934956) (xy 93.61043 -263.934956)
		)
		(stroke
			(width 0)
			(type solid)
		)
		(fill yes)
		(layer "In11.Cu")
		(net "M_D_CPU1_SA_CB<3>")
	)
	(gr_poly
		(pts
			(xy 93.61043 -263.482582) (xy 93.61043 -263.438132) (xy 93.25483 -263.438132) (xy 93.25483 -263.482582)
			(xy 93.30182 -263.634982) (xy 93.56344 -263.634982)
		)
		(stroke
			(width 0)
			(type solid)
		)
		(fill yes)
		(layer "In11.Cu")
		(net "M_D_CPU1_SA_DQS_DP<4>")
	)
	(gr_poly
		(pts
			(xy 93.61043 -261.854442) (xy 93.61043 -261.810246) (xy 93.25483 -261.810246) (xy 93.25483 -261.854442)
			(xy 93.30182 -262.006842) (xy 93.56344 -262.006842)
		)
		(stroke
			(width 0)
			(type solid)
		)
		(fill yes)
		(layer "In11.Cu")
		(net "M_D_CPU1_SA_CB<4>")
	)
	(gr_poly
		(pts
			(xy 93.61043 -260.634734) (xy 93.56344 -260.482334) (xy 93.30182 -260.482334) (xy 93.25483 -260.634734)
			(xy 93.25483 -260.679184) (xy 93.61043 -260.679184)
		)
		(stroke
			(width 0)
			(type solid)
		)
		(fill yes)
		(layer "In11.Cu")
		(net "M_D_CPU1_SA_CB<7>")
	)
	(gr_poly
		(pts
			(xy 93.61043 -259.007102) (xy 93.56344 -258.854702) (xy 93.30182 -258.854702) (xy 93.25483 -259.007102)
			(xy 93.25483 -259.051552) (xy 93.61043 -259.051552)
		)
		(stroke
			(width 0)
			(type solid)
		)
		(fill yes)
		(layer "In11.Cu")
		(net "M_D_CPU1_SA_CS_N<0>")
	)
	(gr_poly
		(pts
			(xy 93.61043 -258.599178) (xy 93.61043 -258.554728) (xy 93.25483 -258.554728) (xy 93.25483 -258.599178)
			(xy 93.30182 -258.751578) (xy 93.56344 -258.751578)
		)
		(stroke
			(width 0)
			(type solid)
		)
		(fill yes)
		(layer "In11.Cu")
		(net "M_D_CPU1_SA_CS_N<3>")
	)
	(gr_poly
		(pts
			(xy 93.61043 -255.751838) (xy 93.56344 -255.599438) (xy 93.30182 -255.599438) (xy 93.25483 -255.751838)
			(xy 93.25483 -255.796034) (xy 93.61043 -255.796034)
		)
		(stroke
			(width 0)
			(type solid)
		)
		(fill yes)
		(layer "In11.Cu")
		(net "M_D_CPU1_SA_CA<5>")
	)
	(gr_poly
		(pts
			(xy 93.811344 -232.167176) (xy 93.849698 -232.145078) (xy 93.671898 -231.83723) (xy 93.633544 -231.859328)
			(xy 93.525086 -231.976168) (xy 93.655896 -232.202736)
		)
		(stroke
			(width 0)
			(type solid)
		)
		(fill yes)
		(layer "In11.Cu")
		(net "M_D_CPU1_SB_DQ<12>")
	)
	(gr_poly
		(pts
			(xy 93.818456 -233.807) (xy 93.85681 -233.784902) (xy 93.67901 -233.477054) (xy 93.640656 -233.499152)
			(xy 93.532198 -233.615992) (xy 93.663008 -233.84256)
		)
		(stroke
			(width 0)
			(type solid)
		)
		(fill yes)
		(layer "In11.Cu")
		(net "M_D_CPU1_SB_DQS_DN<6>")
	)
	(gr_poly
		(pts
			(xy 93.927168 -233.1847) (xy 94.035626 -233.06786) (xy 93.904816 -232.841292) (xy 93.749368 -232.876852)
			(xy 93.711014 -232.89895) (xy 93.888814 -233.206798)
		)
		(stroke
			(width 0)
			(type solid)
		)
		(fill yes)
		(layer "In11.Cu")
		(net "M_D_CPU1_SB_DQS_DP<6>")
	)
	(gr_poly
		(pts
			(xy 93.927422 -231.557576) (xy 94.03588 -231.440736) (xy 93.90507 -231.214168) (xy 93.749622 -231.249728)
			(xy 93.711268 -231.271826) (xy 93.889068 -231.579674)
		)
		(stroke
			(width 0)
			(type solid)
		)
		(fill yes)
		(layer "In11.Cu")
		(net "M_D_CPU1_SB_DQ<14>")
	)
	(gr_poly
		(pts
			(xy 93.95333 -249.416062) (xy 93.95333 -249.371612) (xy 93.59773 -249.371612) (xy 93.59773 -249.416062)
			(xy 93.64472 -249.568462) (xy 93.90634 -249.568462)
		)
		(stroke
			(width 0)
			(type solid)
		)
		(fill yes)
		(layer "In11.Cu")
		(net "M_D_CPU1_SB_CA<2>")
	)
	(gr_poly
		(pts
			(xy 93.95333 -248.196354) (xy 93.90634 -248.043954) (xy 93.64472 -248.043954) (xy 93.59773 -248.196354)
			(xy 93.59773 -248.24055) (xy 93.95333 -248.24055)
		)
		(stroke
			(width 0)
			(type solid)
		)
		(fill yes)
		(layer "In11.Cu")
		(net "M_D_CPU1_SB_CA<5>")
	)
	(gr_poly
		(pts
			(xy 93.95333 -247.787922) (xy 93.95333 -247.743726) (xy 93.59773 -247.743726) (xy 93.59773 -247.787922)
			(xy 93.64472 -247.940322) (xy 93.90634 -247.940322)
		)
		(stroke
			(width 0)
			(type solid)
		)
		(fill yes)
		(layer "In11.Cu")
		(net "M_D_CPU1_SB_PAR")
	)
	(gr_poly
		(pts
			(xy 93.95333 -244.940582) (xy 93.90634 -244.788182) (xy 93.64472 -244.788182) (xy 93.59773 -244.940582)
			(xy 93.59773 -244.985032) (xy 93.95333 -244.985032)
		)
		(stroke
			(width 0)
			(type solid)
		)
		(fill yes)
		(layer "In11.Cu")
		(net "M_D_CPU1_SB_DQS_DN<9>")
	)
	(gr_poly
		(pts
			(xy 93.95333 -244.532658) (xy 93.95333 -244.488208) (xy 93.59773 -244.488208) (xy 93.59773 -244.532658)
			(xy 93.64472 -244.685058) (xy 93.90634 -244.685058)
		)
		(stroke
			(width 0)
			(type solid)
		)
		(fill yes)
		(layer "In11.Cu")
		(net "M_D_CPU1_SB_DQS_DN<4>")
	)
	(gr_poly
		(pts
			(xy 93.95333 -243.31295) (xy 93.90634 -243.16055) (xy 93.64472 -243.16055) (xy 93.59773 -243.31295)
			(xy 93.59773 -243.3574) (xy 93.95333 -243.3574)
		)
		(stroke
			(width 0)
			(type solid)
		)
		(fill yes)
		(layer "In11.Cu")
		(net "M_D_CPU1_SB_CB<2>")
	)
	(gr_poly
		(pts
			(xy 93.95333 -242.905026) (xy 93.95333 -242.860576) (xy 93.59773 -242.860576) (xy 93.59773 -242.905026)
			(xy 93.64472 -243.057426) (xy 93.90634 -243.057426)
		)
		(stroke
			(width 0)
			(type solid)
		)
		(fill yes)
		(layer "In11.Cu")
		(net "M_D_CPU1_SB_CB<1>")
	)
	(gr_poly
		(pts
			(xy 93.95333 -240.057178) (xy 93.90634 -239.904778) (xy 93.64472 -239.904778) (xy 93.59773 -240.057178)
			(xy 93.59773 -240.101628) (xy 93.95333 -240.101628)
		)
		(stroke
			(width 0)
			(type solid)
		)
		(fill yes)
		(layer "In11.Cu")
		(net "M_D_CPU1_SB_DQS_DN<0>")
	)
	(gr_poly
		(pts
			(xy 93.95333 -239.649254) (xy 93.95333 -239.604804) (xy 93.59773 -239.604804) (xy 93.59773 -239.649254)
			(xy 93.64472 -239.801654) (xy 93.90634 -239.801654)
		)
		(stroke
			(width 0)
			(type solid)
		)
		(fill yes)
		(layer "In11.Cu")
		(net "M_D_CPU1_SB_DQS_DN<5>")
	)
	(gr_poly
		(pts
			(xy 93.95333 -238.429546) (xy 93.90634 -238.277146) (xy 93.64472 -238.277146) (xy 93.59773 -238.429546)
			(xy 93.59773 -238.473996) (xy 93.95333 -238.473996)
		)
		(stroke
			(width 0)
			(type solid)
		)
		(fill yes)
		(layer "In11.Cu")
		(net "M_D_CPU1_SB_DQ<6>")
	)
	(gr_poly
		(pts
			(xy 93.95333 -238.021622) (xy 93.95333 -237.977172) (xy 93.59773 -237.977172) (xy 93.59773 -238.021622)
			(xy 93.64472 -238.174022) (xy 93.90634 -238.174022)
		)
		(stroke
			(width 0)
			(type solid)
		)
		(fill yes)
		(layer "In11.Cu")
		(net "M_D_CPU1_SB_DQ<5>")
	)
	(gr_poly
		(pts
			(xy 93.95333 -235.174282) (xy 93.90634 -235.021882) (xy 93.64472 -235.021882) (xy 93.59773 -235.174282)
			(xy 93.59773 -235.218478) (xy 93.95333 -235.218478)
		)
		(stroke
			(width 0)
			(type solid)
		)
		(fill yes)
		(layer "In11.Cu")
		(net "M_D_CPU1_SB_DQS_DN<1>")
	)
	(gr_poly
		(pts
			(xy 93.95333 -230.290878) (xy 93.90634 -230.138478) (xy 93.64472 -230.138478) (xy 93.59773 -230.290878)
			(xy 93.59773 -230.335074) (xy 93.95333 -230.335074)
		)
		(stroke
			(width 0)
			(type solid)
		)
		(fill yes)
		(layer "In11.Cu")
		(net "M_D_CPU1_SB_DQ<15>")
	)
	(gr_poly
		(pts
			(xy 93.95333 -229.882446) (xy 93.95333 -229.83825) (xy 93.59773 -229.83825) (xy 93.59773 -229.882446)
			(xy 93.64472 -230.034846) (xy 93.90634 -230.034846)
		)
		(stroke
			(width 0)
			(type solid)
		)
		(fill yes)
		(layer "In11.Cu")
		(net "M_D_CPU1_SB_DQ<24>")
	)
	(gr_poly
		(pts
			(xy 93.95333 -228.663246) (xy 93.90634 -228.510846) (xy 93.64472 -228.510846) (xy 93.59773 -228.663246)
			(xy 93.59773 -228.707442) (xy 93.95333 -228.707442)
		)
		(stroke
			(width 0)
			(type solid)
		)
		(fill yes)
		(layer "In11.Cu")
		(net "M_D_CPU1_SB_DQ<27>")
	)
	(gr_poly
		(pts
			(xy 93.95333 -228.254814) (xy 93.95333 -228.210618) (xy 93.59773 -228.210618) (xy 93.59773 -228.254814)
			(xy 93.64472 -228.407214) (xy 93.90634 -228.407214)
		)
		(stroke
			(width 0)
			(type solid)
		)
		(fill yes)
		(layer "In11.Cu")
		(net "M_D_CPU1_SB_DQS_DP<3>")
	)
	(gr_poly
		(pts
			(xy 93.95333 -226.627182) (xy 93.95333 -226.582732) (xy 93.59773 -226.582732) (xy 93.59773 -226.627182)
			(xy 93.64472 -226.779582) (xy 93.90634 -226.779582)
		)
		(stroke
			(width 0)
			(type solid)
		)
		(fill yes)
		(layer "In11.Cu")
		(net "M_D_CPU1_SB_DQ<28>")
	)
	(gr_poly
		(pts
			(xy 93.95333 -225.407474) (xy 93.90634 -225.255074) (xy 93.64472 -225.255074) (xy 93.59773 -225.407474)
			(xy 93.59773 -225.45167) (xy 93.95333 -225.45167)
		)
		(stroke
			(width 0)
			(type solid)
		)
		(fill yes)
		(layer "In11.Cu")
		(net "M_D_CPU1_SB_DQ<31>")
	)
	(gr_poly
		(pts
			(xy 93.95587 -246.568722) (xy 93.90888 -246.416322) (xy 93.64726 -246.416322) (xy 93.60027 -246.568722)
			(xy 93.60027 -246.612918) (xy 93.95587 -246.612918)
		)
		(stroke
			(width 0)
			(type solid)
		)
		(fill yes)
		(layer "In11.Cu")
		(net "M_D_CPU1_SB_CB<6>")
	)
	(gr_poly
		(pts
			(xy 93.95587 -246.16029) (xy 93.95587 -246.116094) (xy 93.60027 -246.116094) (xy 93.60027 -246.16029)
			(xy 93.64726 -246.31269) (xy 93.90888 -246.31269)
		)
		(stroke
			(width 0)
			(type solid)
		)
		(fill yes)
		(layer "In11.Cu")
		(net "M_D_CPU1_SB_CB<5>")
	)
	(gr_poly
		(pts
			(xy 93.95587 -241.685318) (xy 93.90888 -241.532918) (xy 93.64726 -241.532918) (xy 93.60027 -241.685318)
			(xy 93.60027 -241.729514) (xy 93.95587 -241.729514)
		)
		(stroke
			(width 0)
			(type solid)
		)
		(fill yes)
		(layer "In11.Cu")
		(net "M_D_CPU1_SB_DQ<2>")
	)
	(gr_poly
		(pts
			(xy 93.95587 -241.276886) (xy 93.95587 -241.23269) (xy 93.60027 -241.23269) (xy 93.60027 -241.276886)
			(xy 93.64726 -241.429286) (xy 93.90888 -241.429286)
		)
		(stroke
			(width 0)
			(type solid)
		)
		(fill yes)
		(layer "In11.Cu")
		(net "M_D_CPU1_SB_DQ<1>")
	)
	(gr_poly
		(pts
			(xy 93.95587 -236.801914) (xy 93.90888 -236.649514) (xy 93.64726 -236.649514) (xy 93.60027 -236.801914)
			(xy 93.60027 -236.84611) (xy 93.95587 -236.84611)
		)
		(stroke
			(width 0)
			(type solid)
		)
		(fill yes)
		(layer "In11.Cu")
		(net "M_D_CPU1_SB_DQ<10>")
	)
	(gr_poly
		(pts
			(xy 93.95587 -236.39399) (xy 93.95587 -236.34954) (xy 93.60027 -236.34954) (xy 93.60027 -236.39399)
			(xy 93.64726 -236.54639) (xy 93.90888 -236.54639)
		)
		(stroke
			(width 0)
			(type solid)
		)
		(fill yes)
		(layer "In11.Cu")
		(net "M_D_CPU1_SB_DQ<9>")
	)
	(gr_poly
		(pts
			(xy 93.96222 -227.035614) (xy 93.91523 -226.883214) (xy 93.65361 -226.883214) (xy 93.60662 -227.035614)
			(xy 93.60662 -227.07981) (xy 93.96222 -227.07981)
		)
		(stroke
			(width 0)
			(type solid)
		)
		(fill yes)
		(layer "In11.Cu")
		(net "M_D_CPU1_SB_DQS_DP<8>")
	)
	(gr_poly
		(pts
			(xy 94.063312 -277.726394) (xy 94.016322 -277.573994) (xy 93.754702 -277.573994) (xy 93.707712 -277.726394)
			(xy 93.707712 -277.770844) (xy 94.063312 -277.770844)
		)
		(stroke
			(width 0)
			(type solid)
		)
		(fill yes)
		(layer "In11.Cu")
		(net "M_D_CPU1_SA_DQS_DN<1>")
	)
	(gr_poly
		(pts
			(xy 94.063312 -277.318216) (xy 94.063312 -277.27402) (xy 93.707712 -277.27402) (xy 93.707712 -277.318216)
			(xy 93.754702 -277.470616) (xy 94.016322 -277.470616)
		)
		(stroke
			(width 0)
			(type solid)
		)
		(fill yes)
		(layer "In11.Cu")
		(net "M_D_CPU1_SA_DQS_DN<6>")
	)
	(gr_poly
		(pts
			(xy 94.063312 -274.47113) (xy 94.016322 -274.31873) (xy 93.754702 -274.31873) (xy 93.707712 -274.47113)
			(xy 93.707712 -274.515326) (xy 94.063312 -274.515326)
		)
		(stroke
			(width 0)
			(type solid)
		)
		(fill yes)
		(layer "In11.Cu")
		(net "M_D_CPU1_SA_DQ<18>")
	)
	(gr_poly
		(pts
			(xy 94.063312 -274.062698) (xy 94.063312 -274.018502) (xy 93.707712 -274.018502) (xy 93.707712 -274.062698)
			(xy 93.754702 -274.215098) (xy 94.016322 -274.215098)
		)
		(stroke
			(width 0)
			(type solid)
		)
		(fill yes)
		(layer "In11.Cu")
		(net "M_D_CPU1_SA_DQ<17>")
	)
	(gr_poly
		(pts
			(xy 94.063312 -272.843498) (xy 94.016322 -272.691098) (xy 93.754702 -272.691098) (xy 93.707712 -272.843498)
			(xy 93.707712 -272.887694) (xy 94.063312 -272.887694)
		)
		(stroke
			(width 0)
			(type solid)
		)
		(fill yes)
		(layer "In11.Cu")
		(net "M_D_CPU1_SA_DQS_DN<2>")
	)
	(gr_poly
		(pts
			(xy 94.063312 -272.435066) (xy 94.063312 -272.39087) (xy 93.707712 -272.39087) (xy 93.707712 -272.435066)
			(xy 93.754702 -272.587466) (xy 94.016322 -272.587466)
		)
		(stroke
			(width 0)
			(type solid)
		)
		(fill yes)
		(layer "In11.Cu")
		(net "M_D_CPU1_SA_DQS_DN<7>")
	)
	(gr_poly
		(pts
			(xy 94.063312 -269.587726) (xy 94.016322 -269.435326) (xy 93.754702 -269.435326) (xy 93.707712 -269.587726)
			(xy 93.707712 -269.631922) (xy 94.063312 -269.631922)
		)
		(stroke
			(width 0)
			(type solid)
		)
		(fill yes)
		(layer "In11.Cu")
		(net "M_D_CPU1_SA_DQ<26>")
	)
	(gr_poly
		(pts
			(xy 94.063312 -267.960094) (xy 94.016322 -267.807694) (xy 93.754702 -267.807694) (xy 93.707712 -267.960094)
			(xy 93.707712 -268.00429) (xy 94.063312 -268.00429)
		)
		(stroke
			(width 0)
			(type solid)
		)
		(fill yes)
		(layer "In11.Cu")
		(net "M_D_CPU1_SA_DQS_DN<3>")
	)
	(gr_poly
		(pts
			(xy 94.063312 -267.551662) (xy 94.063312 -267.507466) (xy 93.707712 -267.507466) (xy 93.707712 -267.551662)
			(xy 93.754702 -267.704062) (xy 94.016322 -267.704062)
		)
		(stroke
			(width 0)
			(type solid)
		)
		(fill yes)
		(layer "In11.Cu")
		(net "M_D_CPU1_SA_DQS_DN<8>")
	)
	(gr_poly
		(pts
			(xy 94.063312 -266.331954) (xy 94.016322 -266.179554) (xy 93.754702 -266.179554) (xy 93.707712 -266.331954)
			(xy 93.707712 -266.376404) (xy 94.063312 -266.376404)
		)
		(stroke
			(width 0)
			(type solid)
		)
		(fill yes)
		(layer "In11.Cu")
		(net "M_D_CPU1_SA_DQ<30>")
	)
	(gr_poly
		(pts
			(xy 94.063312 -265.92403) (xy 94.063312 -265.87958) (xy 93.707712 -265.87958) (xy 93.707712 -265.92403)
			(xy 93.754702 -266.07643) (xy 94.016322 -266.07643)
		)
		(stroke
			(width 0)
			(type solid)
		)
		(fill yes)
		(layer "In11.Cu")
		(net "M_D_CPU1_SA_DQ<29>")
	)
	(gr_poly
		(pts
			(xy 94.063312 -264.704322) (xy 94.016322 -264.551922) (xy 93.754702 -264.551922) (xy 93.707712 -264.704322)
			(xy 93.707712 -264.748772) (xy 94.063312 -264.748772)
		)
		(stroke
			(width 0)
			(type solid)
		)
		(fill yes)
		(layer "In11.Cu")
		(net "M_D_CPU1_SA_CB<2>")
	)
	(gr_poly
		(pts
			(xy 94.063312 -264.296398) (xy 94.063312 -264.251948) (xy 93.707712 -264.251948) (xy 93.707712 -264.296398)
			(xy 93.754702 -264.448798) (xy 94.016322 -264.448798)
		)
		(stroke
			(width 0)
			(type solid)
		)
		(fill yes)
		(layer "In11.Cu")
		(net "M_D_CPU1_SA_CB<1>")
	)
	(gr_poly
		(pts
			(xy 94.063312 -263.07669) (xy 94.016322 -262.92429) (xy 93.754702 -262.92429) (xy 93.707712 -263.07669)
			(xy 93.707712 -263.120886) (xy 94.063312 -263.120886)
		)
		(stroke
			(width 0)
			(type solid)
		)
		(fill yes)
		(layer "In11.Cu")
		(net "M_D_CPU1_SA_DQS_DN<4>")
	)
	(gr_poly
		(pts
			(xy 94.063312 -261.449058) (xy 94.016322 -261.296658) (xy 93.754702 -261.296658) (xy 93.707712 -261.449058)
			(xy 93.707712 -261.493254) (xy 94.063312 -261.493254)
		)
		(stroke
			(width 0)
			(type solid)
		)
		(fill yes)
		(layer "In11.Cu")
		(net "M_D_CPU1_SA_CB<6>")
	)
	(gr_poly
		(pts
			(xy 94.063312 -261.040626) (xy 94.063312 -260.99643) (xy 93.707712 -260.99643) (xy 93.707712 -261.040626)
			(xy 93.754702 -261.193026) (xy 94.016322 -261.193026)
		)
		(stroke
			(width 0)
			(type solid)
		)
		(fill yes)
		(layer "In11.Cu")
		(net "M_D_CPU1_SA_CB<5>")
	)
	(gr_poly
		(pts
			(xy 94.063312 -259.412994) (xy 94.063312 -259.368544) (xy 93.707712 -259.368544) (xy 93.707712 -259.412994)
			(xy 93.754702 -259.565394) (xy 94.016322 -259.565394)
		)
		(stroke
			(width 0)
			(type solid)
		)
		(fill yes)
		(layer "In11.Cu")
		(net "M_D_CPU1_SA_CS_N<2>")
	)
	(gr_poly
		(pts
			(xy 94.063312 -258.193286) (xy 94.016322 -258.040886) (xy 93.754702 -258.040886) (xy 93.707712 -258.193286)
			(xy 93.707712 -258.237482) (xy 94.063312 -258.237482)
		)
		(stroke
			(width 0)
			(type solid)
		)
		(fill yes)
		(layer "In11.Cu")
		(net "M_D_CPU1_SA_CS_N<1>")
	)
	(gr_poly
		(pts
			(xy 94.063312 -257.784854) (xy 94.063312 -257.740658) (xy 93.707712 -257.740658) (xy 93.707712 -257.784854)
			(xy 93.754702 -257.937254) (xy 94.016322 -257.937254)
		)
		(stroke
			(width 0)
			(type solid)
		)
		(fill yes)
		(layer "In11.Cu")
		(net "M_D_CPU1_SA_CA<0>")
	)
	(gr_poly
		(pts
			(xy 94.065852 -276.098762) (xy 94.018862 -275.946362) (xy 93.757242 -275.946362) (xy 93.710252 -276.098762)
			(xy 93.710252 -276.143212) (xy 94.065852 -276.143212)
		)
		(stroke
			(width 0)
			(type solid)
		)
		(fill yes)
		(layer "In11.Cu")
		(net "M_D_CPU1_SA_DQ<14>")
	)
	(gr_poly
		(pts
			(xy 94.065852 -275.690584) (xy 94.065852 -275.646388) (xy 93.710252 -275.646388) (xy 93.710252 -275.690584)
			(xy 93.757242 -275.842984) (xy 94.018862 -275.842984)
		)
		(stroke
			(width 0)
			(type solid)
		)
		(fill yes)
		(layer "In11.Cu")
		(net "M_D_CPU1_SA_DQ<13>")
	)
	(gr_poly
		(pts
			(xy 94.065852 -271.215358) (xy 94.018862 -271.062958) (xy 93.757242 -271.062958) (xy 93.710252 -271.215358)
			(xy 93.710252 -271.259808) (xy 94.065852 -271.259808)
		)
		(stroke
			(width 0)
			(type solid)
		)
		(fill yes)
		(layer "In11.Cu")
		(net "M_D_CPU1_SA_DQ<22>")
	)
	(gr_poly
		(pts
			(xy 94.065852 -270.807434) (xy 94.065852 -270.762984) (xy 93.710252 -270.762984) (xy 93.710252 -270.807434)
			(xy 93.757242 -270.959834) (xy 94.018862 -270.959834)
		)
		(stroke
			(width 0)
			(type solid)
		)
		(fill yes)
		(layer "In11.Cu")
		(net "M_D_CPU1_SA_DQ<21>")
	)
	(gr_poly
		(pts
			(xy 94.065852 -256.565654) (xy 94.018862 -256.413254) (xy 93.757242 -256.413254) (xy 93.710252 -256.565654)
			(xy 93.710252 -256.60985) (xy 94.065852 -256.60985)
		)
		(stroke
			(width 0)
			(type solid)
		)
		(fill yes)
		(layer "In11.Cu")
		(net "M_D_CPU1_SA_CA<3>")
	)
	(gr_poly
		(pts
			(xy 94.065852 -256.157222) (xy 94.065852 -256.113026) (xy 93.710252 -256.113026) (xy 93.710252 -256.157222)
			(xy 93.757242 -256.309622) (xy 94.018862 -256.309622)
		)
		(stroke
			(width 0)
			(type solid)
		)
		(fill yes)
		(layer "In11.Cu")
		(net "M_D_CPU1_SA_CA<4>")
	)
	(gr_poly
		(pts
			(xy 94.071694 -278.945848) (xy 94.071694 -278.901652) (xy 93.716094 -278.901652) (xy 93.716094 -278.945848)
			(xy 93.763084 -279.098248) (xy 94.024704 -279.098248)
		)
		(stroke
			(width 0)
			(type solid)
		)
		(fill yes)
		(layer "In11.Cu")
		(net "M_D_CPU1_SA_DQ<9>")
	)
	(gr_poly
		(pts
			(xy 94.07525 -269.179294) (xy 94.07525 -269.134844) (xy 93.71965 -269.134844) (xy 93.71965 -269.179294)
			(xy 93.76664 -269.331694) (xy 94.02826 -269.331694)
		)
		(stroke
			(width 0)
			(type solid)
		)
		(fill yes)
		(layer "In11.Cu")
		(net "M_D_CPU1_SA_DQ<25>")
	)
	(gr_poly
		(pts
			(xy 94.07525 -262.668258) (xy 94.07525 -262.623808) (xy 93.71965 -262.623808) (xy 93.71965 -262.668258)
			(xy 93.76664 -262.820658) (xy 94.02826 -262.820658)
		)
		(stroke
			(width 0)
			(type solid)
		)
		(fill yes)
		(layer "In11.Cu")
		(net "M_D_CPU1_SA_DQS_DN<9>")
	)
	(gr_poly
		(pts
			(xy 94.07779 -279.354534) (xy 94.0308 -279.202134) (xy 93.76918 -279.202134) (xy 93.72219 -279.354534)
			(xy 93.72219 -279.39873) (xy 94.07779 -279.39873)
		)
		(stroke
			(width 0)
			(type solid)
		)
		(fill yes)
		(layer "In11.Cu")
		(net "M_D_CPU1_SA_DQ<10>")
	)
	(gr_poly
		(pts
			(xy 94.28734 -234.619038) (xy 94.325694 -234.59694) (xy 94.147894 -234.289092) (xy 94.10954 -234.31119)
			(xy 94.001082 -234.42803) (xy 94.131892 -234.654598)
		)
		(stroke
			(width 0)
			(type solid)
		)
		(fill yes)
		(layer "In11.Cu")
		(net "M_D_CPU1_SB_DQS_DN<6>")
	)
	(gr_poly
		(pts
			(xy 94.28861 -232.993692) (xy 94.326964 -232.971594) (xy 94.149164 -232.663746) (xy 94.11081 -232.685844)
			(xy 94.002352 -232.802684) (xy 94.133162 -233.029252)
		)
		(stroke
			(width 0)
			(type solid)
		)
		(fill yes)
		(layer "In11.Cu")
		(net "M_D_CPU1_SB_DQ<12>")
	)
	(gr_poly
		(pts
			(xy 94.398338 -232.373424) (xy 94.506796 -232.256584) (xy 94.375986 -232.030016) (xy 94.220538 -232.065576)
			(xy 94.182184 -232.087674) (xy 94.359984 -232.395522)
		)
		(stroke
			(width 0)
			(type solid)
		)
		(fill yes)
		(layer "In11.Cu")
		(net "M_D_CPU1_SB_DQ<14>")
	)
	(gr_poly
		(pts
			(xy 94.400878 -234.00512) (xy 94.509336 -233.88828) (xy 94.378526 -233.661712) (xy 94.223078 -233.697272)
			(xy 94.184724 -233.71937) (xy 94.362524 -234.027218)
		)
		(stroke
			(width 0)
			(type solid)
		)
		(fill yes)
		(layer "In11.Cu")
		(net "M_D_CPU1_SB_DQS_DP<6>")
	)
	(gr_poly
		(pts
			(xy 94.431866 -246.974106) (xy 94.431866 -246.929656) (xy 94.076266 -246.929656) (xy 94.076266 -246.974106)
			(xy 94.123256 -247.126506) (xy 94.384876 -247.126506)
		)
		(stroke
			(width 0)
			(type solid)
		)
		(fill yes)
		(layer "In11.Cu")
		(net "M_D_CPU1_SB_CB<4>")
	)
	(gr_poly
		(pts
			(xy 94.431866 -245.754906) (xy 94.384876 -245.602506) (xy 94.123256 -245.602506) (xy 94.076266 -245.754906)
			(xy 94.076266 -245.799356) (xy 94.431866 -245.799356)
		)
		(stroke
			(width 0)
			(type solid)
		)
		(fill yes)
		(layer "In11.Cu")
		(net "M_D_CPU1_SB_CB<7>")
	)
	(gr_poly
		(pts
			(xy 94.431866 -242.090702) (xy 94.431866 -242.046252) (xy 94.076266 -242.046252) (xy 94.076266 -242.090702)
			(xy 94.123256 -242.243102) (xy 94.384876 -242.243102)
		)
		(stroke
			(width 0)
			(type solid)
		)
		(fill yes)
		(layer "In11.Cu")
		(net "M_D_CPU1_SB_DQ<0>")
	)
	(gr_poly
		(pts
			(xy 94.431866 -240.871502) (xy 94.384876 -240.719102) (xy 94.123256 -240.719102) (xy 94.076266 -240.871502)
			(xy 94.076266 -240.915952) (xy 94.431866 -240.915952)
		)
		(stroke
			(width 0)
			(type solid)
		)
		(fill yes)
		(layer "In11.Cu")
		(net "M_D_CPU1_SB_DQ<3>")
	)
	(gr_poly
		(pts
			(xy 94.431866 -237.207298) (xy 94.431866 -237.163102) (xy 94.076266 -237.163102) (xy 94.076266 -237.207298)
			(xy 94.123256 -237.359698) (xy 94.384876 -237.359698)
		)
		(stroke
			(width 0)
			(type solid)
		)
		(fill yes)
		(layer "In11.Cu")
		(net "M_D_CPU1_SB_DQ<8>")
	)
	(gr_poly
		(pts
			(xy 94.431866 -235.988098) (xy 94.384876 -235.835698) (xy 94.123256 -235.835698) (xy 94.076266 -235.988098)
			(xy 94.076266 -236.032548) (xy 94.431866 -236.032548)
		)
		(stroke
			(width 0)
			(type solid)
		)
		(fill yes)
		(layer "In11.Cu")
		(net "M_D_CPU1_SB_DQ<11>")
	)
	(gr_poly
		(pts
			(xy 94.437708 -249.010678) (xy 94.390718 -248.858278) (xy 94.129098 -248.858278) (xy 94.082108 -249.010678)
			(xy 94.082108 -249.054874) (xy 94.437708 -249.054874)
		)
		(stroke
			(width 0)
			(type solid)
		)
		(fill yes)
		(layer "In11.Cu")
		(net "M_D_CPU1_SB_CA<3>")
	)
	(gr_poly
		(pts
			(xy 94.437708 -248.601738) (xy 94.437708 -248.557542) (xy 94.082108 -248.557542) (xy 94.082108 -248.601738)
			(xy 94.129098 -248.754138) (xy 94.390718 -248.754138)
		)
		(stroke
			(width 0)
			(type solid)
		)
		(fill yes)
		(layer "In11.Cu")
		(net "M_D_CPU1_SB_CA<4>")
	)
	(gr_poly
		(pts
			(xy 94.437708 -244.127274) (xy 94.390718 -243.974874) (xy 94.129098 -243.974874) (xy 94.082108 -244.127274)
			(xy 94.082108 -244.17147) (xy 94.437708 -244.17147)
		)
		(stroke
			(width 0)
			(type solid)
		)
		(fill yes)
		(layer "In11.Cu")
		(net "M_D_CPU1_SB_DQS_DP<4>")
	)
	(gr_poly
		(pts
			(xy 94.437708 -243.718334) (xy 94.437708 -243.674138) (xy 94.082108 -243.674138) (xy 94.082108 -243.718334)
			(xy 94.129098 -243.870734) (xy 94.390718 -243.870734)
		)
		(stroke
			(width 0)
			(type solid)
		)
		(fill yes)
		(layer "In11.Cu")
		(net "M_D_CPU1_SB_CB<0>")
	)
	(gr_poly
		(pts
			(xy 94.437708 -239.24387) (xy 94.390718 -239.09147) (xy 94.129098 -239.09147) (xy 94.082108 -239.24387)
			(xy 94.082108 -239.288066) (xy 94.437708 -239.288066)
		)
		(stroke
			(width 0)
			(type solid)
		)
		(fill yes)
		(layer "In11.Cu")
		(net "M_D_CPU1_SB_DQS_DP<5>")
	)
	(gr_poly
		(pts
			(xy 94.437708 -238.83493) (xy 94.437708 -238.790734) (xy 94.082108 -238.790734) (xy 94.082108 -238.83493)
			(xy 94.129098 -238.98733) (xy 94.390718 -238.98733)
		)
		(stroke
			(width 0)
			(type solid)
		)
		(fill yes)
		(layer "In11.Cu")
		(net "M_D_CPU1_SB_DQ<4>")
	)
	(gr_poly
		(pts
			(xy 94.437708 -229.477062) (xy 94.390718 -229.324662) (xy 94.129098 -229.324662) (xy 94.082108 -229.477062)
			(xy 94.082108 -229.521512) (xy 94.437708 -229.521512)
		)
		(stroke
			(width 0)
			(type solid)
		)
		(fill yes)
		(layer "In11.Cu")
		(net "M_D_CPU1_SB_DQ<26>")
	)
	(gr_poly
		(pts
			(xy 94.437708 -229.06863) (xy 94.437708 -229.02418) (xy 94.082108 -229.02418) (xy 94.082108 -229.06863)
			(xy 94.129098 -229.22103) (xy 94.390718 -229.22103)
		)
		(stroke
			(width 0)
			(type solid)
		)
		(fill yes)
		(layer "In11.Cu")
		(net "M_D_CPU1_SB_DQ<25>")
	)
	(gr_poly
		(pts
			(xy 94.440248 -245.346474) (xy 94.440248 -245.302278) (xy 94.084648 -245.302278) (xy 94.084648 -245.346474)
			(xy 94.131638 -245.498874) (xy 94.393258 -245.498874)
		)
		(stroke
			(width 0)
			(type solid)
		)
		(fill yes)
		(layer "In11.Cu")
		(net "M_D_CPU1_SB_DQS_DP<9>")
	)
	(gr_poly
		(pts
			(xy 94.440248 -242.499134) (xy 94.393258 -242.346734) (xy 94.131638 -242.346734) (xy 94.084648 -242.499134)
			(xy 94.084648 -242.54333) (xy 94.440248 -242.54333)
		)
		(stroke
			(width 0)
			(type solid)
		)
		(fill yes)
		(layer "In11.Cu")
		(net "M_D_CPU1_SB_CB<3>")
	)
	(gr_poly
		(pts
			(xy 94.440248 -240.46307) (xy 94.440248 -240.418874) (xy 94.084648 -240.418874) (xy 94.084648 -240.46307)
			(xy 94.131638 -240.61547) (xy 94.393258 -240.61547)
		)
		(stroke
			(width 0)
			(type solid)
		)
		(fill yes)
		(layer "In11.Cu")
		(net "M_D_CPU1_SB_DQS_DP<0>")
	)
	(gr_poly
		(pts
			(xy 94.440248 -237.61573) (xy 94.393258 -237.46333) (xy 94.131638 -237.46333) (xy 94.084648 -237.61573)
			(xy 94.084648 -237.66018) (xy 94.440248 -237.66018)
		)
		(stroke
			(width 0)
			(type solid)
		)
		(fill yes)
		(layer "In11.Cu")
		(net "M_D_CPU1_SB_DQ<7>")
	)
	(gr_poly
		(pts
			(xy 94.440248 -235.579666) (xy 94.440248 -235.53547) (xy 94.084648 -235.53547) (xy 94.084648 -235.579666)
			(xy 94.131638 -235.732066) (xy 94.393258 -235.732066)
		)
		(stroke
			(width 0)
			(type solid)
		)
		(fill yes)
		(layer "In11.Cu")
		(net "M_D_CPU1_SB_DQS_DP<1>")
	)
	(gr_poly
		(pts
			(xy 94.440248 -230.696262) (xy 94.440248 -230.652066) (xy 94.084648 -230.652066) (xy 94.084648 -230.696262)
			(xy 94.131638 -230.848662) (xy 94.393258 -230.848662)
		)
		(stroke
			(width 0)
			(type solid)
		)
		(fill yes)
		(layer "In11.Cu")
		(net "M_D_CPU1_SB_DQ<13>")
	)
	(gr_poly
		(pts
			(xy 94.440248 -227.848922) (xy 94.393258 -227.696522) (xy 94.131638 -227.696522) (xy 94.084648 -227.848922)
			(xy 94.084648 -227.893372) (xy 94.440248 -227.893372)
		)
		(stroke
			(width 0)
			(type solid)
		)
		(fill yes)
		(layer "In11.Cu")
		(net "M_D_CPU1_SB_DQS_DN<3>")
	)
	(gr_poly
		(pts
			(xy 94.440248 -227.440998) (xy 94.440248 -227.396548) (xy 94.084648 -227.396548) (xy 94.084648 -227.440998)
			(xy 94.131638 -227.593398) (xy 94.393258 -227.593398)
		)
		(stroke
			(width 0)
			(type solid)
		)
		(fill yes)
		(layer "In11.Cu")
		(net "M_D_CPU1_SB_DQS_DN<8>")
	)
	(gr_poly
		(pts
			(xy 94.440248 -226.22129) (xy 94.393258 -226.06889) (xy 94.131638 -226.06889) (xy 94.084648 -226.22129)
			(xy 94.084648 -226.26574) (xy 94.440248 -226.26574)
		)
		(stroke
			(width 0)
			(type solid)
		)
		(fill yes)
		(layer "In11.Cu")
		(net "M_D_CPU1_SB_DQ<30>")
	)
	(gr_poly
		(pts
			(xy 94.440248 -225.813366) (xy 94.440248 -225.768916) (xy 94.084648 -225.768916) (xy 94.084648 -225.813366)
			(xy 94.131638 -225.965766) (xy 94.393258 -225.965766)
		)
		(stroke
			(width 0)
			(type solid)
		)
		(fill yes)
		(layer "In11.Cu")
		(net "M_D_CPU1_SB_DQ<29>")
	)
	(gr_poly
		(pts
			(xy 94.533212 -279.759918) (xy 94.533212 -279.715722) (xy 94.177612 -279.715722) (xy 94.177612 -279.759918)
			(xy 94.224602 -279.912318) (xy 94.486222 -279.912318)
		)
		(stroke
			(width 0)
			(type solid)
		)
		(fill yes)
		(layer "In11.Cu")
		(net "M_D_CPU1_SA_DQ<8>")
	)
	(gr_poly
		(pts
			(xy 94.538292 -268.77391) (xy 94.491302 -268.62151) (xy 94.229682 -268.62151) (xy 94.182692 -268.77391)
			(xy 94.182692 -268.81836) (xy 94.538292 -268.81836)
		)
		(stroke
			(width 0)
			(type solid)
		)
		(fill yes)
		(layer "In11.Cu")
		(net "M_D_CPU1_SA_DQ<27>")
	)
	(gr_poly
		(pts
			(xy 94.538292 -262.262874) (xy 94.491302 -262.110474) (xy 94.229682 -262.110474) (xy 94.182692 -262.262874)
			(xy 94.182692 -262.307324) (xy 94.538292 -262.307324)
		)
		(stroke
			(width 0)
			(type solid)
		)
		(fill yes)
		(layer "In11.Cu")
		(net "M_D_CPU1_SA_DQS_DP<9>")
	)
	(gr_poly
		(pts
			(xy 94.541594 -260.635242) (xy 94.494604 -260.482842) (xy 94.232984 -260.482842) (xy 94.185994 -260.635242)
			(xy 94.185994 -260.679438) (xy 94.541594 -260.679438)
		)
		(stroke
			(width 0)
			(type solid)
		)
		(fill yes)
		(layer "In11.Cu")
		(net "M_D_CPU1_SA_CB<7>")
	)
	(gr_poly
		(pts
			(xy 94.541848 -278.540718) (xy 94.494858 -278.388318) (xy 94.233238 -278.388318) (xy 94.186248 -278.540718)
			(xy 94.186248 -278.585168) (xy 94.541848 -278.585168)
		)
		(stroke
			(width 0)
			(type solid)
		)
		(fill yes)
		(layer "In11.Cu")
		(net "M_D_CPU1_SA_DQ<11>")
	)
	(gr_poly
		(pts
			(xy 94.541848 -276.504146) (xy 94.541848 -276.45995) (xy 94.186248 -276.45995) (xy 94.186248 -276.504146)
			(xy 94.233238 -276.656546) (xy 94.494858 -276.656546)
		)
		(stroke
			(width 0)
			(type solid)
		)
		(fill yes)
		(layer "In11.Cu")
		(net "M_D_CPU1_SA_DQ<12>")
	)
	(gr_poly
		(pts
			(xy 94.541848 -275.284946) (xy 94.494858 -275.132546) (xy 94.233238 -275.132546) (xy 94.186248 -275.284946)
			(xy 94.186248 -275.329396) (xy 94.541848 -275.329396)
		)
		(stroke
			(width 0)
			(type solid)
		)
		(fill yes)
		(layer "In11.Cu")
		(net "M_D_CPU1_SA_DQ<15>")
	)
	(gr_poly
		(pts
			(xy 94.541848 -271.620742) (xy 94.541848 -271.576546) (xy 94.186248 -271.576546) (xy 94.186248 -271.620742)
			(xy 94.233238 -271.773142) (xy 94.494858 -271.773142)
		)
		(stroke
			(width 0)
			(type solid)
		)
		(fill yes)
		(layer "In11.Cu")
		(net "M_D_CPU1_SA_DQ<20>")
	)
	(gr_poly
		(pts
			(xy 94.541848 -270.40205) (xy 94.494858 -270.24965) (xy 94.233238 -270.24965) (xy 94.186248 -270.40205)
			(xy 94.186248 -270.446246) (xy 94.541848 -270.446246)
		)
		(stroke
			(width 0)
			(type solid)
		)
		(fill yes)
		(layer "In11.Cu")
		(net "M_D_CPU1_SA_DQ<23>")
	)
	(gr_poly
		(pts
			(xy 94.541848 -256.971038) (xy 94.541848 -256.926588) (xy 94.186248 -256.926588) (xy 94.186248 -256.971038)
			(xy 94.233238 -257.123438) (xy 94.494858 -257.123438)
		)
		(stroke
			(width 0)
			(type solid)
		)
		(fill yes)
		(layer "In11.Cu")
		(net "M_D_CPU1_SA_CA<2>")
	)
	(gr_poly
		(pts
			(xy 94.541848 -255.751838) (xy 94.494858 -255.599438) (xy 94.233238 -255.599438) (xy 94.186248 -255.751838)
			(xy 94.186248 -255.796288) (xy 94.541848 -255.796288)
		)
		(stroke
			(width 0)
			(type solid)
		)
		(fill yes)
		(layer "In11.Cu")
		(net "M_D_CPU1_SA_CA<5>")
	)
	(gr_poly
		(pts
			(xy 94.54769 -273.657314) (xy 94.5007 -273.504914) (xy 94.23908 -273.504914) (xy 94.19209 -273.657314)
			(xy 94.19209 -273.701764) (xy 94.54769 -273.701764)
		)
		(stroke
			(width 0)
			(type solid)
		)
		(fill yes)
		(layer "In11.Cu")
		(net "M_D_CPU1_SA_DQ<19>")
	)
	(gr_poly
		(pts
			(xy 94.54769 -273.248882) (xy 94.54769 -273.204432) (xy 94.19209 -273.204432) (xy 94.19209 -273.248882)
			(xy 94.23908 -273.401282) (xy 94.5007 -273.401282)
		)
		(stroke
			(width 0)
			(type solid)
		)
		(fill yes)
		(layer "In11.Cu")
		(net "M_D_CPU1_SA_DQS_DP<2>")
	)
	(gr_poly
		(pts
			(xy 94.54769 -268.365478) (xy 94.54769 -268.321028) (xy 94.19209 -268.321028) (xy 94.19209 -268.365478)
			(xy 94.23908 -268.517878) (xy 94.5007 -268.517878)
		)
		(stroke
			(width 0)
			(type solid)
		)
		(fill yes)
		(layer "In11.Cu")
		(net "M_D_CPU1_SA_DQS_DP<3>")
	)
	(gr_poly
		(pts
			(xy 94.54769 -263.891014) (xy 94.5007 -263.738614) (xy 94.23908 -263.738614) (xy 94.19209 -263.891014)
			(xy 94.19209 -263.93521) (xy 94.54769 -263.93521)
		)
		(stroke
			(width 0)
			(type solid)
		)
		(fill yes)
		(layer "In11.Cu")
		(net "M_D_CPU1_SA_CB<3>")
	)
	(gr_poly
		(pts
			(xy 94.54769 -263.482074) (xy 94.54769 -263.437878) (xy 94.19209 -263.437878) (xy 94.19209 -263.482074)
			(xy 94.23908 -263.634474) (xy 94.5007 -263.634474)
		)
		(stroke
			(width 0)
			(type solid)
		)
		(fill yes)
		(layer "In11.Cu")
		(net "M_D_CPU1_SA_DQS_DP<4>")
	)
	(gr_poly
		(pts
			(xy 94.54769 -259.00761) (xy 94.5007 -258.85521) (xy 94.23908 -258.85521) (xy 94.19209 -259.00761)
			(xy 94.19209 -259.051806) (xy 94.54769 -259.051806)
		)
		(stroke
			(width 0)
			(type solid)
		)
		(fill yes)
		(layer "In11.Cu")
		(net "M_D_CPU1_SA_CS_N<0>")
	)
	(gr_poly
		(pts
			(xy 94.54769 -258.59867) (xy 94.54769 -258.554474) (xy 94.19209 -258.554474) (xy 94.19209 -258.59867)
			(xy 94.23908 -258.75107) (xy 94.5007 -258.75107)
		)
		(stroke
			(width 0)
			(type solid)
		)
		(fill yes)
		(layer "In11.Cu")
		(net "M_D_CPU1_SA_CS_N<3>")
	)
	(gr_poly
		(pts
			(xy 94.55023 -278.132286) (xy 94.55023 -278.08809) (xy 94.19463 -278.08809) (xy 94.19463 -278.132286)
			(xy 94.24162 -278.284686) (xy 94.50324 -278.284686)
		)
		(stroke
			(width 0)
			(type solid)
		)
		(fill yes)
		(layer "In11.Cu")
		(net "M_D_CPU1_SA_DQS_DP<1>")
	)
	(gr_poly
		(pts
			(xy 94.55023 -276.912578) (xy 94.50324 -276.760178) (xy 94.24162 -276.760178) (xy 94.19463 -276.912578)
			(xy 94.19463 -276.957028) (xy 94.55023 -276.957028)
		)
		(stroke
			(width 0)
			(type solid)
		)
		(fill yes)
		(layer "In11.Cu")
		(net "M_D_CPU1_SA_DQS_DP<6>")
	)
	(gr_poly
		(pts
			(xy 94.55023 -274.876514) (xy 94.55023 -274.832318) (xy 94.19463 -274.832318) (xy 94.19463 -274.876514)
			(xy 94.24162 -275.028914) (xy 94.50324 -275.028914)
		)
		(stroke
			(width 0)
			(type solid)
		)
		(fill yes)
		(layer "In11.Cu")
		(net "M_D_CPU1_SA_DQ<16>")
	)
	(gr_poly
		(pts
			(xy 94.55023 -272.029174) (xy 94.50324 -271.876774) (xy 94.24162 -271.876774) (xy 94.19463 -272.029174)
			(xy 94.19463 -272.073624) (xy 94.55023 -272.073624)
		)
		(stroke
			(width 0)
			(type solid)
		)
		(fill yes)
		(layer "In11.Cu")
		(net "M_D_CPU1_SA_DQS_DP<7>")
	)
	(gr_poly
		(pts
			(xy 94.55023 -269.993618) (xy 94.55023 -269.949168) (xy 94.19463 -269.949168) (xy 94.19463 -269.993618)
			(xy 94.24162 -270.146018) (xy 94.50324 -270.146018)
		)
		(stroke
			(width 0)
			(type solid)
		)
		(fill yes)
		(layer "In11.Cu")
		(net "M_D_CPU1_SA_DQ<24>")
	)
	(gr_poly
		(pts
			(xy 94.55023 -267.14577) (xy 94.50324 -266.99337) (xy 94.24162 -266.99337) (xy 94.19463 -267.14577)
			(xy 94.19463 -267.19022) (xy 94.55023 -267.19022)
		)
		(stroke
			(width 0)
			(type solid)
		)
		(fill yes)
		(layer "In11.Cu")
		(net "M_D_CPU1_SA_DQS_DP<8>")
	)
	(gr_poly
		(pts
			(xy 94.55023 -266.737846) (xy 94.55023 -266.69365) (xy 94.19463 -266.69365) (xy 94.19463 -266.737846)
			(xy 94.24162 -266.890246) (xy 94.50324 -266.890246)
		)
		(stroke
			(width 0)
			(type solid)
		)
		(fill yes)
		(layer "In11.Cu")
		(net "M_D_CPU1_SA_DQ<28>")
	)
	(gr_poly
		(pts
			(xy 94.55023 -265.518138) (xy 94.50324 -265.365738) (xy 94.24162 -265.365738) (xy 94.19463 -265.518138)
			(xy 94.19463 -265.562588) (xy 94.55023 -265.562588)
		)
		(stroke
			(width 0)
			(type solid)
		)
		(fill yes)
		(layer "In11.Cu")
		(net "M_D_CPU1_SA_DQ<31>")
	)
	(gr_poly
		(pts
			(xy 94.55023 -265.110214) (xy 94.55023 -265.065764) (xy 94.19463 -265.065764) (xy 94.19463 -265.110214)
			(xy 94.24162 -265.262614) (xy 94.50324 -265.262614)
		)
		(stroke
			(width 0)
			(type solid)
		)
		(fill yes)
		(layer "In11.Cu")
		(net "M_D_CPU1_SA_CB<0>")
	)
	(gr_poly
		(pts
			(xy 94.55023 -261.854442) (xy 94.55023 -261.810246) (xy 94.19463 -261.810246) (xy 94.19463 -261.854442)
			(xy 94.24162 -262.006842) (xy 94.50324 -262.006842)
		)
		(stroke
			(width 0)
			(type solid)
		)
		(fill yes)
		(layer "In11.Cu")
		(net "M_D_CPU1_SA_CB<4>")
	)
	(gr_poly
		(pts
			(xy 94.55023 -257.37947) (xy 94.50324 -257.22707) (xy 94.24162 -257.22707) (xy 94.19463 -257.37947)
			(xy 94.19463 -257.423666) (xy 94.55023 -257.423666)
		)
		(stroke
			(width 0)
			(type solid)
		)
		(fill yes)
		(layer "In11.Cu")
		(net "M_D_CPU1_SA_CA<1>")
	)
	(gr_poly
		(pts
			(xy 94.759272 -233.809032) (xy 94.797626 -233.786934) (xy 94.619826 -233.479086) (xy 94.581472 -233.501184)
			(xy 94.473014 -233.618024) (xy 94.603824 -233.844592)
		)
		(stroke
			(width 0)
			(type solid)
		)
		(fill yes)
		(layer "In11.Cu")
		(net "M_D_CPU1_SB_DQ<12>")
	)
	(gr_poly
		(pts
			(xy 94.866968 -233.1847) (xy 94.975426 -233.06786) (xy 94.844616 -232.841292) (xy 94.689168 -232.876852)
			(xy 94.650814 -232.89895) (xy 94.828614 -233.206798)
		)
		(stroke
			(width 0)
			(type solid)
		)
		(fill yes)
		(layer "In11.Cu")
		(net "M_D_CPU1_SB_DQ<14>")
	)
	(gr_poly
		(pts
			(xy 94.89313 -244.940582) (xy 94.84614 -244.788182) (xy 94.58452 -244.788182) (xy 94.53753 -244.940582)
			(xy 94.53753 -244.985032) (xy 94.89313 -244.985032)
		)
		(stroke
			(width 0)
			(type solid)
		)
		(fill yes)
		(layer "In11.Cu")
		(net "M_D_CPU1_SB_DQS_DN<9>")
	)
	(gr_poly
		(pts
			(xy 94.89313 -242.905026) (xy 94.89313 -242.860576) (xy 94.53753 -242.860576) (xy 94.53753 -242.905026)
			(xy 94.58452 -243.057426) (xy 94.84614 -243.057426)
		)
		(stroke
			(width 0)
			(type solid)
		)
		(fill yes)
		(layer "In11.Cu")
		(net "M_D_CPU1_SB_CB<1>")
	)
	(gr_poly
		(pts
			(xy 94.89313 -240.057178) (xy 94.84614 -239.904778) (xy 94.58452 -239.904778) (xy 94.53753 -240.057178)
			(xy 94.53753 -240.101628) (xy 94.89313 -240.101628)
		)
		(stroke
			(width 0)
			(type solid)
		)
		(fill yes)
		(layer "In11.Cu")
		(net "M_D_CPU1_SB_DQS_DN<0>")
	)
	(gr_poly
		(pts
			(xy 94.89313 -238.021622) (xy 94.89313 -237.977172) (xy 94.53753 -237.977172) (xy 94.53753 -238.021622)
			(xy 94.58452 -238.174022) (xy 94.84614 -238.174022)
		)
		(stroke
			(width 0)
			(type solid)
		)
		(fill yes)
		(layer "In11.Cu")
		(net "M_D_CPU1_SB_DQ<5>")
	)
	(gr_poly
		(pts
			(xy 94.89313 -235.174282) (xy 94.84614 -235.021882) (xy 94.58452 -235.021882) (xy 94.53753 -235.174282)
			(xy 94.53753 -235.218478) (xy 94.89313 -235.218478)
		)
		(stroke
			(width 0)
			(type solid)
		)
		(fill yes)
		(layer "In11.Cu")
		(net "M_D_CPU1_SB_DQS_DN<1>")
	)
	(gr_poly
		(pts
			(xy 94.89313 -230.290878) (xy 94.84614 -230.138478) (xy 94.58452 -230.138478) (xy 94.53753 -230.290878)
			(xy 94.53753 -230.335074) (xy 94.89313 -230.335074)
		)
		(stroke
			(width 0)
			(type solid)
		)
		(fill yes)
		(layer "In11.Cu")
		(net "M_D_CPU1_SB_DQ<15>")
	)
	(gr_poly
		(pts
			(xy 94.89313 -228.254814) (xy 94.89313 -228.210618) (xy 94.53753 -228.210618) (xy 94.53753 -228.254814)
			(xy 94.58452 -228.407214) (xy 94.84614 -228.407214)
		)
		(stroke
			(width 0)
			(type solid)
		)
		(fill yes)
		(layer "In11.Cu")
		(net "M_D_CPU1_SB_DQS_DP<3>")
	)
	(gr_poly
		(pts
			(xy 94.89313 -226.627182) (xy 94.89313 -226.582732) (xy 94.53753 -226.582732) (xy 94.53753 -226.627182)
			(xy 94.58452 -226.779582) (xy 94.84614 -226.779582)
		)
		(stroke
			(width 0)
			(type solid)
		)
		(fill yes)
		(layer "In11.Cu")
		(net "M_D_CPU1_SB_DQ<28>")
	)
	(gr_poly
		(pts
			(xy 94.89313 -225.407474) (xy 94.84614 -225.255074) (xy 94.58452 -225.255074) (xy 94.53753 -225.407474)
			(xy 94.53753 -225.45167) (xy 94.89313 -225.45167)
		)
		(stroke
			(width 0)
			(type solid)
		)
		(fill yes)
		(layer "In11.Cu")
		(net "M_D_CPU1_SB_DQ<31>")
	)
	(gr_poly
		(pts
			(xy 94.89567 -246.568722) (xy 94.84868 -246.416322) (xy 94.58706 -246.416322) (xy 94.54007 -246.568722)
			(xy 94.54007 -246.613172) (xy 94.89567 -246.613172)
		)
		(stroke
			(width 0)
			(type solid)
		)
		(fill yes)
		(layer "In11.Cu")
		(net "M_D_CPU1_SB_CB<6>")
	)
	(gr_poly
		(pts
			(xy 94.89567 -246.16029) (xy 94.89567 -246.11584) (xy 94.54007 -246.11584) (xy 94.54007 -246.16029)
			(xy 94.58706 -246.31269) (xy 94.84868 -246.31269)
		)
		(stroke
			(width 0)
			(type solid)
		)
		(fill yes)
		(layer "In11.Cu")
		(net "M_D_CPU1_SB_CB<5>")
	)
	(gr_poly
		(pts
			(xy 94.89567 -241.685318) (xy 94.84868 -241.532918) (xy 94.58706 -241.532918) (xy 94.54007 -241.685318)
			(xy 94.54007 -241.729768) (xy 94.89567 -241.729768)
		)
		(stroke
			(width 0)
			(type solid)
		)
		(fill yes)
		(layer "In11.Cu")
		(net "M_D_CPU1_SB_DQ<2>")
	)
	(gr_poly
		(pts
			(xy 94.89567 -241.276886) (xy 94.89567 -241.232436) (xy 94.54007 -241.232436) (xy 94.54007 -241.276886)
			(xy 94.58706 -241.429286) (xy 94.84868 -241.429286)
		)
		(stroke
			(width 0)
			(type solid)
		)
		(fill yes)
		(layer "In11.Cu")
		(net "M_D_CPU1_SB_DQ<1>")
	)
	(gr_poly
		(pts
			(xy 94.89567 -236.801914) (xy 94.84868 -236.649514) (xy 94.58706 -236.649514) (xy 94.54007 -236.801914)
			(xy 94.54007 -236.846364) (xy 94.89567 -236.846364)
		)
		(stroke
			(width 0)
			(type solid)
		)
		(fill yes)
		(layer "In11.Cu")
		(net "M_D_CPU1_SB_DQ<10>")
	)
	(gr_poly
		(pts
			(xy 94.89567 -236.393482) (xy 94.89567 -236.349286) (xy 94.54007 -236.349286) (xy 94.54007 -236.393482)
			(xy 94.58706 -236.545882) (xy 94.84868 -236.545882)
		)
		(stroke
			(width 0)
			(type solid)
		)
		(fill yes)
		(layer "In11.Cu")
		(net "M_D_CPU1_SB_DQ<9>")
	)
	(gr_poly
		(pts
			(xy 94.901512 -249.415554) (xy 94.901512 -249.371358) (xy 94.545912 -249.371358) (xy 94.545912 -249.415554)
			(xy 94.592902 -249.567954) (xy 94.854522 -249.567954)
		)
		(stroke
			(width 0)
			(type solid)
		)
		(fill yes)
		(layer "In11.Cu")
		(net "M_D_CPU1_SB_CA<2>")
	)
	(gr_poly
		(pts
			(xy 94.901512 -244.53215) (xy 94.901512 -244.487954) (xy 94.545912 -244.487954) (xy 94.545912 -244.53215)
			(xy 94.592902 -244.68455) (xy 94.854522 -244.68455)
		)
		(stroke
			(width 0)
			(type solid)
		)
		(fill yes)
		(layer "In11.Cu")
		(net "M_D_CPU1_SB_DQS_DN<4>")
	)
	(gr_poly
		(pts
			(xy 94.901512 -243.313458) (xy 94.854522 -243.161058) (xy 94.592902 -243.161058) (xy 94.545912 -243.313458)
			(xy 94.545912 -243.357654) (xy 94.901512 -243.357654)
		)
		(stroke
			(width 0)
			(type solid)
		)
		(fill yes)
		(layer "In11.Cu")
		(net "M_D_CPU1_SB_CB<2>")
	)
	(gr_poly
		(pts
			(xy 94.901512 -239.648746) (xy 94.901512 -239.60455) (xy 94.545912 -239.60455) (xy 94.545912 -239.648746)
			(xy 94.592902 -239.801146) (xy 94.854522 -239.801146)
		)
		(stroke
			(width 0)
			(type solid)
		)
		(fill yes)
		(layer "In11.Cu")
		(net "M_D_CPU1_SB_DQS_DN<5>")
	)
	(gr_poly
		(pts
			(xy 94.901512 -238.430054) (xy 94.854522 -238.277654) (xy 94.592902 -238.277654) (xy 94.545912 -238.430054)
			(xy 94.545912 -238.47425) (xy 94.901512 -238.47425)
		)
		(stroke
			(width 0)
			(type solid)
		)
		(fill yes)
		(layer "In11.Cu")
		(net "M_D_CPU1_SB_DQ<6>")
	)
	(gr_poly
		(pts
			(xy 94.901512 -234.76585) (xy 94.901512 -234.7214) (xy 94.545912 -234.7214) (xy 94.545912 -234.76585)
			(xy 94.592902 -234.91825) (xy 94.854522 -234.91825)
		)
		(stroke
			(width 0)
			(type solid)
		)
		(fill yes)
		(layer "In11.Cu")
		(net "M_D_CPU1_SB_DQS_DN<6>")
	)
	(gr_poly
		(pts
			(xy 94.901512 -229.882446) (xy 94.901512 -229.837996) (xy 94.545912 -229.837996) (xy 94.545912 -229.882446)
			(xy 94.592902 -230.034846) (xy 94.854522 -230.034846)
		)
		(stroke
			(width 0)
			(type solid)
		)
		(fill yes)
		(layer "In11.Cu")
		(net "M_D_CPU1_SB_DQ<24>")
	)
	(gr_poly
		(pts
			(xy 94.901512 -228.663246) (xy 94.854522 -228.510846) (xy 94.592902 -228.510846) (xy 94.545912 -228.663246)
			(xy 94.545912 -228.707696) (xy 94.901512 -228.707696)
		)
		(stroke
			(width 0)
			(type solid)
		)
		(fill yes)
		(layer "In11.Cu")
		(net "M_D_CPU1_SB_DQ<27>")
	)
	(gr_poly
		(pts
			(xy 94.90202 -227.035614) (xy 94.85503 -226.883214) (xy 94.59341 -226.883214) (xy 94.54642 -227.035614)
			(xy 94.54642 -227.07981) (xy 94.90202 -227.07981)
		)
		(stroke
			(width 0)
			(type solid)
		)
		(fill yes)
		(layer "In11.Cu")
		(net "M_D_CPU1_SB_DQS_DP<8>")
	)
	(gr_poly
		(pts
			(xy 95.003112 -277.726394) (xy 94.956122 -277.573994) (xy 94.694502 -277.573994) (xy 94.647512 -277.726394)
			(xy 94.647512 -277.770844) (xy 95.003112 -277.770844)
		)
		(stroke
			(width 0)
			(type solid)
		)
		(fill yes)
		(layer "In11.Cu")
		(net "M_D_CPU1_SA_DQS_DN<1>")
	)
	(gr_poly
		(pts
			(xy 95.003112 -277.318216) (xy 95.003112 -277.27402) (xy 94.647512 -277.27402) (xy 94.647512 -277.318216)
			(xy 94.694502 -277.470616) (xy 94.956122 -277.470616)
		)
		(stroke
			(width 0)
			(type solid)
		)
		(fill yes)
		(layer "In11.Cu")
		(net "M_D_CPU1_SA_DQS_DN<6>")
	)
	(gr_poly
		(pts
			(xy 95.003112 -274.47113) (xy 94.956122 -274.31873) (xy 94.694502 -274.31873) (xy 94.647512 -274.47113)
			(xy 94.647512 -274.515326) (xy 95.003112 -274.515326)
		)
		(stroke
			(width 0)
			(type solid)
		)
		(fill yes)
		(layer "In11.Cu")
		(net "M_D_CPU1_SA_DQ<18>")
	)
	(gr_poly
		(pts
			(xy 95.003112 -272.435066) (xy 95.003112 -272.39087) (xy 94.647512 -272.39087) (xy 94.647512 -272.435066)
			(xy 94.694502 -272.587466) (xy 94.956122 -272.587466)
		)
		(stroke
			(width 0)
			(type solid)
		)
		(fill yes)
		(layer "In11.Cu")
		(net "M_D_CPU1_SA_DQS_DN<7>")
	)
	(gr_poly
		(pts
			(xy 95.003112 -269.587726) (xy 94.956122 -269.435326) (xy 94.694502 -269.435326) (xy 94.647512 -269.587726)
			(xy 94.647512 -269.631922) (xy 95.003112 -269.631922)
		)
		(stroke
			(width 0)
			(type solid)
		)
		(fill yes)
		(layer "In11.Cu")
		(net "M_D_CPU1_SA_DQ<26>")
	)
	(gr_poly
		(pts
			(xy 95.003112 -267.551662) (xy 95.003112 -267.507466) (xy 94.647512 -267.507466) (xy 94.647512 -267.551662)
			(xy 94.694502 -267.704062) (xy 94.956122 -267.704062)
		)
		(stroke
			(width 0)
			(type solid)
		)
		(fill yes)
		(layer "In11.Cu")
		(net "M_D_CPU1_SA_DQS_DN<8>")
	)
	(gr_poly
		(pts
			(xy 95.003112 -266.331954) (xy 94.956122 -266.179554) (xy 94.694502 -266.179554) (xy 94.647512 -266.331954)
			(xy 94.647512 -266.376404) (xy 95.003112 -266.376404)
		)
		(stroke
			(width 0)
			(type solid)
		)
		(fill yes)
		(layer "In11.Cu")
		(net "M_D_CPU1_SA_DQ<30>")
	)
	(gr_poly
		(pts
			(xy 95.003112 -265.92403) (xy 95.003112 -265.87958) (xy 94.647512 -265.87958) (xy 94.647512 -265.92403)
			(xy 94.694502 -266.07643) (xy 94.956122 -266.07643)
		)
		(stroke
			(width 0)
			(type solid)
		)
		(fill yes)
		(layer "In11.Cu")
		(net "M_D_CPU1_SA_DQ<29>")
	)
	(gr_poly
		(pts
			(xy 95.003112 -264.704322) (xy 94.956122 -264.551922) (xy 94.694502 -264.551922) (xy 94.647512 -264.704322)
			(xy 94.647512 -264.748772) (xy 95.003112 -264.748772)
		)
		(stroke
			(width 0)
			(type solid)
		)
		(fill yes)
		(layer "In11.Cu")
		(net "M_D_CPU1_SA_CB<2>")
	)
	(gr_poly
		(pts
			(xy 95.003112 -261.449058) (xy 94.956122 -261.296658) (xy 94.694502 -261.296658) (xy 94.647512 -261.449058)
			(xy 94.647512 -261.493254) (xy 95.003112 -261.493254)
		)
		(stroke
			(width 0)
			(type solid)
		)
		(fill yes)
		(layer "In11.Cu")
		(net "M_D_CPU1_SA_CB<6>")
	)
	(gr_poly
		(pts
			(xy 95.003112 -257.784854) (xy 95.003112 -257.740658) (xy 94.647512 -257.740658) (xy 94.647512 -257.784854)
			(xy 94.694502 -257.937254) (xy 94.956122 -257.937254)
		)
		(stroke
			(width 0)
			(type solid)
		)
		(fill yes)
		(layer "In11.Cu")
		(net "M_D_CPU1_SA_CA<0>")
	)
	(gr_poly
		(pts
			(xy 95.005652 -278.945848) (xy 95.005652 -278.901652) (xy 94.650052 -278.901652) (xy 94.650052 -278.945848)
			(xy 94.697042 -279.098248) (xy 94.958662 -279.098248)
		)
		(stroke
			(width 0)
			(type solid)
		)
		(fill yes)
		(layer "In11.Cu")
		(net "M_D_CPU1_SA_DQ<9>")
	)
	(gr_poly
		(pts
			(xy 95.005652 -276.09927) (xy 94.958662 -275.94687) (xy 94.697042 -275.94687) (xy 94.650052 -276.09927)
			(xy 94.650052 -276.143466) (xy 95.005652 -276.143466)
		)
		(stroke
			(width 0)
			(type solid)
		)
		(fill yes)
		(layer "In11.Cu")
		(net "M_D_CPU1_SA_DQ<14>")
	)
	(gr_poly
		(pts
			(xy 95.005652 -275.690584) (xy 95.005652 -275.646134) (xy 94.650052 -275.646134) (xy 94.650052 -275.690584)
			(xy 94.697042 -275.842984) (xy 94.958662 -275.842984)
		)
		(stroke
			(width 0)
			(type solid)
		)
		(fill yes)
		(layer "In11.Cu")
		(net "M_D_CPU1_SA_DQ<13>")
	)
	(gr_poly
		(pts
			(xy 95.005652 -271.215866) (xy 94.958662 -271.063466) (xy 94.697042 -271.063466) (xy 94.650052 -271.215866)
			(xy 94.650052 -271.260062) (xy 95.005652 -271.260062)
		)
		(stroke
			(width 0)
			(type solid)
		)
		(fill yes)
		(layer "In11.Cu")
		(net "M_D_CPU1_SA_DQ<22>")
	)
	(gr_poly
		(pts
			(xy 95.005652 -270.806926) (xy 95.005652 -270.76273) (xy 94.650052 -270.76273) (xy 94.650052 -270.806926)
			(xy 94.697042 -270.959326) (xy 94.958662 -270.959326)
		)
		(stroke
			(width 0)
			(type solid)
		)
		(fill yes)
		(layer "In11.Cu")
		(net "M_D_CPU1_SA_DQ<21>")
	)
	(gr_poly
		(pts
			(xy 95.005652 -256.565654) (xy 94.958662 -256.413254) (xy 94.697042 -256.413254) (xy 94.650052 -256.565654)
			(xy 94.650052 -256.610104) (xy 95.005652 -256.610104)
		)
		(stroke
			(width 0)
			(type solid)
		)
		(fill yes)
		(layer "In11.Cu")
		(net "M_D_CPU1_SA_CA<3>")
	)
	(gr_poly
		(pts
			(xy 95.005652 -256.157222) (xy 95.005652 -256.112772) (xy 94.650052 -256.112772) (xy 94.650052 -256.157222)
			(xy 94.697042 -256.309622) (xy 94.958662 -256.309622)
		)
		(stroke
			(width 0)
			(type solid)
		)
		(fill yes)
		(layer "In11.Cu")
		(net "M_D_CPU1_SA_CA<4>")
	)
	(gr_poly
		(pts
			(xy 95.011494 -274.062698) (xy 95.011494 -274.018248) (xy 94.655894 -274.018248) (xy 94.655894 -274.062698)
			(xy 94.702884 -274.215098) (xy 94.964504 -274.215098)
		)
		(stroke
			(width 0)
			(type solid)
		)
		(fill yes)
		(layer "In11.Cu")
		(net "M_D_CPU1_SA_DQ<17>")
	)
	(gr_poly
		(pts
			(xy 95.011494 -272.843498) (xy 94.964504 -272.691098) (xy 94.702884 -272.691098) (xy 94.655894 -272.843498)
			(xy 94.655894 -272.887948) (xy 95.011494 -272.887948)
		)
		(stroke
			(width 0)
			(type solid)
		)
		(fill yes)
		(layer "In11.Cu")
		(net "M_D_CPU1_SA_DQS_DN<2>")
	)
	(gr_poly
		(pts
			(xy 95.011494 -267.960094) (xy 94.964504 -267.807694) (xy 94.702884 -267.807694) (xy 94.655894 -267.960094)
			(xy 94.655894 -268.004544) (xy 95.011494 -268.004544)
		)
		(stroke
			(width 0)
			(type solid)
		)
		(fill yes)
		(layer "In11.Cu")
		(net "M_D_CPU1_SA_DQS_DN<3>")
	)
	(gr_poly
		(pts
			(xy 95.011494 -264.29589) (xy 95.011494 -264.251694) (xy 94.655894 -264.251694) (xy 94.655894 -264.29589)
			(xy 94.702884 -264.44829) (xy 94.964504 -264.44829)
		)
		(stroke
			(width 0)
			(type solid)
		)
		(fill yes)
		(layer "In11.Cu")
		(net "M_D_CPU1_SA_CB<1>")
	)
	(gr_poly
		(pts
			(xy 95.011494 -263.07669) (xy 94.964504 -262.92429) (xy 94.702884 -262.92429) (xy 94.655894 -263.07669)
			(xy 94.655894 -263.12114) (xy 95.011494 -263.12114)
		)
		(stroke
			(width 0)
			(type solid)
		)
		(fill yes)
		(layer "In11.Cu")
		(net "M_D_CPU1_SA_DQS_DN<4>")
	)
	(gr_poly
		(pts
			(xy 95.011494 -259.412486) (xy 95.011494 -259.36829) (xy 94.655894 -259.36829) (xy 94.655894 -259.412486)
			(xy 94.702884 -259.564886) (xy 94.964504 -259.564886)
		)
		(stroke
			(width 0)
			(type solid)
		)
		(fill yes)
		(layer "In11.Cu")
		(net "M_D_CPU1_SA_CS_N<2>")
	)
	(gr_poly
		(pts
			(xy 95.011494 -258.193286) (xy 94.964504 -258.040886) (xy 94.702884 -258.040886) (xy 94.655894 -258.193286)
			(xy 94.655894 -258.237736) (xy 95.011494 -258.237736)
		)
		(stroke
			(width 0)
			(type solid)
		)
		(fill yes)
		(layer "In11.Cu")
		(net "M_D_CPU1_SA_CS_N<1>")
	)
	(gr_poly
		(pts
			(xy 95.01505 -269.179294) (xy 95.01505 -269.134844) (xy 94.65945 -269.134844) (xy 94.65945 -269.179294)
			(xy 94.70644 -269.331694) (xy 94.96806 -269.331694)
		)
		(stroke
			(width 0)
			(type solid)
		)
		(fill yes)
		(layer "In11.Cu")
		(net "M_D_CPU1_SA_DQ<25>")
	)
	(gr_poly
		(pts
			(xy 95.01505 -262.668258) (xy 95.01505 -262.623808) (xy 94.65945 -262.623808) (xy 94.65945 -262.668258)
			(xy 94.70644 -262.820658) (xy 94.96806 -262.820658)
		)
		(stroke
			(width 0)
			(type solid)
		)
		(fill yes)
		(layer "In11.Cu")
		(net "M_D_CPU1_SA_DQS_DN<9>")
	)
	(gr_poly
		(pts
			(xy 95.01759 -279.354788) (xy 94.9706 -279.202388) (xy 94.70898 -279.202388) (xy 94.66199 -279.354788)
			(xy 94.66199 -279.398984) (xy 95.01759 -279.398984)
		)
		(stroke
			(width 0)
			(type solid)
		)
		(fill yes)
		(layer "In11.Cu")
		(net "M_D_CPU1_SA_DQ<10>")
	)
	(gr_poly
		(pts
			(xy 95.019876 -261.040626) (xy 95.019876 -260.99643) (xy 94.664276 -260.99643) (xy 94.664276 -261.040626)
			(xy 94.711266 -261.193026) (xy 94.972886 -261.193026)
		)
		(stroke
			(width 0)
			(type solid)
		)
		(fill yes)
		(layer "In11.Cu")
		(net "M_D_CPU1_SA_CB<5>")
	)
	(gr_poly
		(pts
			(xy 95.230188 -231.36733) (xy 95.268542 -231.345232) (xy 95.090742 -231.037384) (xy 95.052388 -231.059482)
			(xy 94.94393 -231.176322) (xy 95.07474 -231.40289)
		)
		(stroke
			(width 0)
			(type solid)
		)
		(fill yes)
		(layer "In11.Cu")
		(net "M_D_CPU1_SB_DQ<13>")
	)
	(gr_poly
		(pts
			(xy 95.342456 -230.75265) (xy 95.450914 -230.63581) (xy 95.320104 -230.409242) (xy 95.164656 -230.444802)
			(xy 95.126302 -230.4669) (xy 95.304102 -230.774748)
		)
		(stroke
			(width 0)
			(type solid)
		)
		(fill yes)
		(layer "In11.Cu")
		(net "M_D_CPU1_SB_DQ<15>")
	)
	(gr_poly
		(pts
			(xy 95.377508 -244.126766) (xy 95.330518 -243.974366) (xy 95.068898 -243.974366) (xy 95.021908 -244.126766)
			(xy 95.021908 -244.171216) (xy 95.377508 -244.171216)
		)
		(stroke
			(width 0)
			(type solid)
		)
		(fill yes)
		(layer "In11.Cu")
		(net "M_D_CPU1_SB_DQS_DP<4>")
	)
	(gr_poly
		(pts
			(xy 95.377508 -243.718842) (xy 95.377508 -243.674392) (xy 95.021908 -243.674392) (xy 95.021908 -243.718842)
			(xy 95.068898 -243.871242) (xy 95.330518 -243.871242)
		)
		(stroke
			(width 0)
			(type solid)
		)
		(fill yes)
		(layer "In11.Cu")
		(net "M_D_CPU1_SB_CB<0>")
	)
	(gr_poly
		(pts
			(xy 95.377508 -239.243362) (xy 95.330518 -239.090962) (xy 95.068898 -239.090962) (xy 95.021908 -239.243362)
			(xy 95.021908 -239.287812) (xy 95.377508 -239.287812)
		)
		(stroke
			(width 0)
			(type solid)
		)
		(fill yes)
		(layer "In11.Cu")
		(net "M_D_CPU1_SB_DQS_DP<5>")
	)
	(gr_poly
		(pts
			(xy 95.377508 -238.835438) (xy 95.377508 -238.790988) (xy 95.021908 -238.790988) (xy 95.021908 -238.835438)
			(xy 95.068898 -238.987838) (xy 95.330518 -238.987838)
		)
		(stroke
			(width 0)
			(type solid)
		)
		(fill yes)
		(layer "In11.Cu")
		(net "M_D_CPU1_SB_DQ<4>")
	)
	(gr_poly
		(pts
			(xy 95.377508 -234.360466) (xy 95.330518 -234.208066) (xy 95.068898 -234.208066) (xy 95.021908 -234.360466)
			(xy 95.021908 -234.404662) (xy 95.377508 -234.404662)
		)
		(stroke
			(width 0)
			(type solid)
		)
		(fill yes)
		(layer "In11.Cu")
		(net "M_D_CPU1_SB_DQS_DP<6>")
	)
	(gr_poly
		(pts
			(xy 95.377508 -233.952034) (xy 95.377508 -233.907838) (xy 95.021908 -233.907838) (xy 95.021908 -233.952034)
			(xy 95.068898 -234.104434) (xy 95.330518 -234.104434)
		)
		(stroke
			(width 0)
			(type solid)
		)
		(fill yes)
		(layer "In11.Cu")
		(net "M_D_CPU1_SB_DQ<12>")
	)
	(gr_poly
		(pts
			(xy 95.377508 -229.477062) (xy 95.330518 -229.324662) (xy 95.068898 -229.324662) (xy 95.021908 -229.477062)
			(xy 95.021908 -229.521258) (xy 95.377508 -229.521258)
		)
		(stroke
			(width 0)
			(type solid)
		)
		(fill yes)
		(layer "In11.Cu")
		(net "M_D_CPU1_SB_DQ<26>")
	)
	(gr_poly
		(pts
			(xy 95.377508 -229.06863) (xy 95.377508 -229.024434) (xy 95.021908 -229.024434) (xy 95.021908 -229.06863)
			(xy 95.068898 -229.22103) (xy 95.330518 -229.22103)
		)
		(stroke
			(width 0)
			(type solid)
		)
		(fill yes)
		(layer "In11.Cu")
		(net "M_D_CPU1_SB_DQ<25>")
	)
	(gr_poly
		(pts
			(xy 95.380048 -247.382538) (xy 95.333058 -247.230138) (xy 95.071438 -247.230138) (xy 95.024448 -247.382538)
			(xy 95.024448 -247.426734) (xy 95.380048 -247.426734)
		)
		(stroke
			(width 0)
			(type solid)
		)
		(fill yes)
		(layer "In11.Cu")
		(net "M_D_CPU1_SB_PAR")
	)
	(gr_poly
		(pts
			(xy 95.380048 -246.974106) (xy 95.380048 -246.92991) (xy 95.024448 -246.92991) (xy 95.024448 -246.974106)
			(xy 95.071438 -247.126506) (xy 95.333058 -247.126506)
		)
		(stroke
			(width 0)
			(type solid)
		)
		(fill yes)
		(layer "In11.Cu")
		(net "M_D_CPU1_SB_CB<4>")
	)
	(gr_poly
		(pts
			(xy 95.380048 -245.754906) (xy 95.333058 -245.602506) (xy 95.071438 -245.602506) (xy 95.024448 -245.754906)
			(xy 95.024448 -245.799102) (xy 95.380048 -245.799102)
		)
		(stroke
			(width 0)
			(type solid)
		)
		(fill yes)
		(layer "In11.Cu")
		(net "M_D_CPU1_SB_CB<7>")
	)
	(gr_poly
		(pts
			(xy 95.380048 -245.346474) (xy 95.380048 -245.302278) (xy 95.024448 -245.302278) (xy 95.024448 -245.346474)
			(xy 95.071438 -245.498874) (xy 95.333058 -245.498874)
		)
		(stroke
			(width 0)
			(type solid)
		)
		(fill yes)
		(layer "In11.Cu")
		(net "M_D_CPU1_SB_DQS_DP<9>")
	)
	(gr_poly
		(pts
			(xy 95.380048 -242.499134) (xy 95.333058 -242.346734) (xy 95.071438 -242.346734) (xy 95.024448 -242.499134)
			(xy 95.024448 -242.54333) (xy 95.380048 -242.54333)
		)
		(stroke
			(width 0)
			(type solid)
		)
		(fill yes)
		(layer "In11.Cu")
		(net "M_D_CPU1_SB_CB<3>")
	)
	(gr_poly
		(pts
			(xy 95.380048 -242.090702) (xy 95.380048 -242.046506) (xy 95.024448 -242.046506) (xy 95.024448 -242.090702)
			(xy 95.071438 -242.243102) (xy 95.333058 -242.243102)
		)
		(stroke
			(width 0)
			(type solid)
		)
		(fill yes)
		(layer "In11.Cu")
		(net "M_D_CPU1_SB_DQ<0>")
	)
	(gr_poly
		(pts
			(xy 95.380048 -240.871502) (xy 95.333058 -240.719102) (xy 95.071438 -240.719102) (xy 95.024448 -240.871502)
			(xy 95.024448 -240.915698) (xy 95.380048 -240.915698)
		)
		(stroke
			(width 0)
			(type solid)
		)
		(fill yes)
		(layer "In11.Cu")
		(net "M_D_CPU1_SB_DQ<3>")
	)
	(gr_poly
		(pts
			(xy 95.380048 -240.46307) (xy 95.380048 -240.418874) (xy 95.024448 -240.418874) (xy 95.024448 -240.46307)
			(xy 95.071438 -240.61547) (xy 95.333058 -240.61547)
		)
		(stroke
			(width 0)
			(type solid)
		)
		(fill yes)
		(layer "In11.Cu")
		(net "M_D_CPU1_SB_DQS_DP<0>")
	)
	(gr_poly
		(pts
			(xy 95.380048 -237.61573) (xy 95.333058 -237.46333) (xy 95.071438 -237.46333) (xy 95.024448 -237.61573)
			(xy 95.024448 -237.66018) (xy 95.380048 -237.66018)
		)
		(stroke
			(width 0)
			(type solid)
		)
		(fill yes)
		(layer "In11.Cu")
		(net "M_D_CPU1_SB_DQ<7>")
	)
	(gr_poly
		(pts
			(xy 95.380048 -237.207806) (xy 95.380048 -237.163356) (xy 95.024448 -237.163356) (xy 95.024448 -237.207806)
			(xy 95.071438 -237.360206) (xy 95.333058 -237.360206)
		)
		(stroke
			(width 0)
			(type solid)
		)
		(fill yes)
		(layer "In11.Cu")
		(net "M_D_CPU1_SB_DQ<8>")
	)
	(gr_poly
		(pts
			(xy 95.380048 -235.988098) (xy 95.333058 -235.835698) (xy 95.071438 -235.835698) (xy 95.024448 -235.988098)
			(xy 95.024448 -236.032294) (xy 95.380048 -236.032294)
		)
		(stroke
			(width 0)
			(type solid)
		)
		(fill yes)
		(layer "In11.Cu")
		(net "M_D_CPU1_SB_DQ<11>")
	)
	(gr_poly
		(pts
			(xy 95.380048 -235.579666) (xy 95.380048 -235.53547) (xy 95.024448 -235.53547) (xy 95.024448 -235.579666)
			(xy 95.071438 -235.732066) (xy 95.333058 -235.732066)
		)
		(stroke
			(width 0)
			(type solid)
		)
		(fill yes)
		(layer "In11.Cu")
		(net "M_D_CPU1_SB_DQS_DP<1>")
	)
	(gr_poly
		(pts
			(xy 95.380048 -227.848922) (xy 95.333058 -227.696522) (xy 95.071438 -227.696522) (xy 95.024448 -227.848922)
			(xy 95.024448 -227.893372) (xy 95.380048 -227.893372)
		)
		(stroke
			(width 0)
			(type solid)
		)
		(fill yes)
		(layer "In11.Cu")
		(net "M_D_CPU1_SB_DQS_DN<3>")
	)
	(gr_poly
		(pts
			(xy 95.380048 -227.440998) (xy 95.380048 -227.396548) (xy 95.024448 -227.396548) (xy 95.024448 -227.440998)
			(xy 95.071438 -227.593398) (xy 95.333058 -227.593398)
		)
		(stroke
			(width 0)
			(type solid)
		)
		(fill yes)
		(layer "In11.Cu")
		(net "M_D_CPU1_SB_DQS_DN<8>")
	)
	(gr_poly
		(pts
			(xy 95.380048 -226.22129) (xy 95.333058 -226.06889) (xy 95.071438 -226.06889) (xy 95.024448 -226.22129)
			(xy 95.024448 -226.26574) (xy 95.380048 -226.26574)
		)
		(stroke
			(width 0)
			(type solid)
		)
		(fill yes)
		(layer "In11.Cu")
		(net "M_D_CPU1_SB_DQ<30>")
	)
	(gr_poly
		(pts
			(xy 95.380048 -225.813366) (xy 95.380048 -225.768916) (xy 95.024448 -225.768916) (xy 95.024448 -225.813366)
			(xy 95.071438 -225.965766) (xy 95.333058 -225.965766)
		)
		(stroke
			(width 0)
			(type solid)
		)
		(fill yes)
		(layer "In11.Cu")
		(net "M_D_CPU1_SB_DQ<29>")
	)
	(gr_poly
		(pts
			(xy 95.478092 -268.77391) (xy 95.431102 -268.62151) (xy 95.169482 -268.62151) (xy 95.122492 -268.77391)
			(xy 95.122492 -268.81836) (xy 95.478092 -268.81836)
		)
		(stroke
			(width 0)
			(type solid)
		)
		(fill yes)
		(layer "In11.Cu")
		(net "M_D_CPU1_SA_DQ<27>")
	)
	(gr_poly
		(pts
			(xy 95.478092 -262.262874) (xy 95.431102 -262.110474) (xy 95.169482 -262.110474) (xy 95.122492 -262.262874)
			(xy 95.122492 -262.307324) (xy 95.478092 -262.307324)
		)
		(stroke
			(width 0)
			(type solid)
		)
		(fill yes)
		(layer "In11.Cu")
		(net "M_D_CPU1_SA_DQS_DP<9>")
	)
	(gr_poly
		(pts
			(xy 95.481394 -260.634734) (xy 95.434404 -260.482334) (xy 95.172784 -260.482334) (xy 95.125794 -260.634734)
			(xy 95.125794 -260.679184) (xy 95.481394 -260.679184)
		)
		(stroke
			(width 0)
			(type solid)
		)
		(fill yes)
		(layer "In11.Cu")
		(net "M_D_CPU1_SA_CB<7>")
	)
	(gr_poly
		(pts
			(xy 95.48749 -279.759918) (xy 95.48749 -279.715722) (xy 95.13189 -279.715722) (xy 95.13189 -279.759918)
			(xy 95.17888 -279.912318) (xy 95.4405 -279.912318)
		)
		(stroke
			(width 0)
			(type solid)
		)
		(fill yes)
		(layer "In11.Cu")
		(net "M_D_CPU1_SA_DQ<8>")
	)
	(gr_poly
		(pts
			(xy 95.48749 -273.657314) (xy 95.4405 -273.504914) (xy 95.17888 -273.504914) (xy 95.13189 -273.657314)
			(xy 95.13189 -273.70151) (xy 95.48749 -273.70151)
		)
		(stroke
			(width 0)
			(type solid)
		)
		(fill yes)
		(layer "In11.Cu")
		(net "M_D_CPU1_SA_DQ<19>")
	)
	(gr_poly
		(pts
			(xy 95.48749 -273.248882) (xy 95.48749 -273.204686) (xy 95.13189 -273.204686) (xy 95.13189 -273.248882)
			(xy 95.17888 -273.401282) (xy 95.4405 -273.401282)
		)
		(stroke
			(width 0)
			(type solid)
		)
		(fill yes)
		(layer "In11.Cu")
		(net "M_D_CPU1_SA_DQS_DP<2>")
	)
	(gr_poly
		(pts
			(xy 95.48749 -268.365478) (xy 95.48749 -268.321282) (xy 95.13189 -268.321282) (xy 95.13189 -268.365478)
			(xy 95.17888 -268.517878) (xy 95.4405 -268.517878)
		)
		(stroke
			(width 0)
			(type solid)
		)
		(fill yes)
		(layer "In11.Cu")
		(net "M_D_CPU1_SA_DQS_DP<3>")
	)
	(gr_poly
		(pts
			(xy 95.48749 -263.890506) (xy 95.4405 -263.738106) (xy 95.17888 -263.738106) (xy 95.13189 -263.890506)
			(xy 95.13189 -263.934956) (xy 95.48749 -263.934956)
		)
		(stroke
			(width 0)
			(type solid)
		)
		(fill yes)
		(layer "In11.Cu")
		(net "M_D_CPU1_SA_CB<3>")
	)
	(gr_poly
		(pts
			(xy 95.48749 -263.482582) (xy 95.48749 -263.438132) (xy 95.13189 -263.438132) (xy 95.13189 -263.482582)
			(xy 95.17888 -263.634982) (xy 95.4405 -263.634982)
		)
		(stroke
			(width 0)
			(type solid)
		)
		(fill yes)
		(layer "In11.Cu")
		(net "M_D_CPU1_SA_DQS_DP<4>")
	)
	(gr_poly
		(pts
			(xy 95.48749 -259.007102) (xy 95.4405 -258.854702) (xy 95.17888 -258.854702) (xy 95.13189 -259.007102)
			(xy 95.13189 -259.051552) (xy 95.48749 -259.051552)
		)
		(stroke
			(width 0)
			(type solid)
		)
		(fill yes)
		(layer "In11.Cu")
		(net "M_D_CPU1_SA_CS_N<0>")
	)
	(gr_poly
		(pts
			(xy 95.48749 -258.599178) (xy 95.48749 -258.554728) (xy 95.13189 -258.554728) (xy 95.13189 -258.599178)
			(xy 95.17888 -258.751578) (xy 95.4405 -258.751578)
		)
		(stroke
			(width 0)
			(type solid)
		)
		(fill yes)
		(layer "In11.Cu")
		(net "M_D_CPU1_SA_CS_N<3>")
	)
	(gr_poly
		(pts
			(xy 95.49003 -278.540718) (xy 95.44304 -278.388318) (xy 95.18142 -278.388318) (xy 95.13443 -278.540718)
			(xy 95.13443 -278.584914) (xy 95.49003 -278.584914)
		)
		(stroke
			(width 0)
			(type solid)
		)
		(fill yes)
		(layer "In11.Cu")
		(net "M_D_CPU1_SA_DQ<11>")
	)
	(gr_poly
		(pts
			(xy 95.49003 -278.132286) (xy 95.49003 -278.08809) (xy 95.13443 -278.08809) (xy 95.13443 -278.132286)
			(xy 95.18142 -278.284686) (xy 95.44304 -278.284686)
		)
		(stroke
			(width 0)
			(type solid)
		)
		(fill yes)
		(layer "In11.Cu")
		(net "M_D_CPU1_SA_DQS_DP<1>")
	)
	(gr_poly
		(pts
			(xy 95.49003 -276.912578) (xy 95.44304 -276.760178) (xy 95.18142 -276.760178) (xy 95.13443 -276.912578)
			(xy 95.13443 -276.957028) (xy 95.49003 -276.957028)
		)
		(stroke
			(width 0)
			(type solid)
		)
		(fill yes)
		(layer "In11.Cu")
		(net "M_D_CPU1_SA_DQS_DP<6>")
	)
	(gr_poly
		(pts
			(xy 95.49003 -276.5044) (xy 95.49003 -276.460204) (xy 95.13443 -276.460204) (xy 95.13443 -276.5044)
			(xy 95.18142 -276.6568) (xy 95.44304 -276.6568)
		)
		(stroke
			(width 0)
			(type solid)
		)
		(fill yes)
		(layer "In11.Cu")
		(net "M_D_CPU1_SA_DQ<12>")
	)
	(gr_poly
		(pts
			(xy 95.49003 -275.284946) (xy 95.44304 -275.132546) (xy 95.18142 -275.132546) (xy 95.13443 -275.284946)
			(xy 95.13443 -275.329142) (xy 95.49003 -275.329142)
		)
		(stroke
			(width 0)
			(type solid)
		)
		(fill yes)
		(layer "In11.Cu")
		(net "M_D_CPU1_SA_DQ<15>")
	)
	(gr_poly
		(pts
			(xy 95.49003 -274.876514) (xy 95.49003 -274.832318) (xy 95.13443 -274.832318) (xy 95.13443 -274.876514)
			(xy 95.18142 -275.028914) (xy 95.44304 -275.028914)
		)
		(stroke
			(width 0)
			(type solid)
		)
		(fill yes)
		(layer "In11.Cu")
		(net "M_D_CPU1_SA_DQ<16>")
	)
	(gr_poly
		(pts
			(xy 95.49003 -272.029174) (xy 95.44304 -271.876774) (xy 95.18142 -271.876774) (xy 95.13443 -272.029174)
			(xy 95.13443 -272.073624) (xy 95.49003 -272.073624)
		)
		(stroke
			(width 0)
			(type solid)
		)
		(fill yes)
		(layer "In11.Cu")
		(net "M_D_CPU1_SA_DQS_DP<7>")
	)
	(gr_poly
		(pts
			(xy 95.49003 -271.62125) (xy 95.49003 -271.5768) (xy 95.13443 -271.5768) (xy 95.13443 -271.62125)
			(xy 95.18142 -271.77365) (xy 95.44304 -271.77365)
		)
		(stroke
			(width 0)
			(type solid)
		)
		(fill yes)
		(layer "In11.Cu")
		(net "M_D_CPU1_SA_DQ<20>")
	)
	(gr_poly
		(pts
			(xy 95.49003 -270.401542) (xy 95.44304 -270.249142) (xy 95.18142 -270.249142) (xy 95.13443 -270.401542)
			(xy 95.13443 -270.445992) (xy 95.49003 -270.445992)
		)
		(stroke
			(width 0)
			(type solid)
		)
		(fill yes)
		(layer "In11.Cu")
		(net "M_D_CPU1_SA_DQ<23>")
	)
	(gr_poly
		(pts
			(xy 95.49003 -269.993618) (xy 95.49003 -269.949168) (xy 95.13443 -269.949168) (xy 95.13443 -269.993618)
			(xy 95.18142 -270.146018) (xy 95.44304 -270.146018)
		)
		(stroke
			(width 0)
			(type solid)
		)
		(fill yes)
		(layer "In11.Cu")
		(net "M_D_CPU1_SA_DQ<24>")
	)
	(gr_poly
		(pts
			(xy 95.49003 -267.14577) (xy 95.44304 -266.99337) (xy 95.18142 -266.99337) (xy 95.13443 -267.14577)
			(xy 95.13443 -267.19022) (xy 95.49003 -267.19022)
		)
		(stroke
			(width 0)
			(type solid)
		)
		(fill yes)
		(layer "In11.Cu")
		(net "M_D_CPU1_SA_DQS_DP<8>")
	)
	(gr_poly
		(pts
			(xy 95.49003 -266.737846) (xy 95.49003 -266.69365) (xy 95.13443 -266.69365) (xy 95.13443 -266.737846)
			(xy 95.18142 -266.890246) (xy 95.44304 -266.890246)
		)
		(stroke
			(width 0)
			(type solid)
		)
		(fill yes)
		(layer "In11.Cu")
		(net "M_D_CPU1_SA_DQ<28>")
	)
	(gr_poly
		(pts
			(xy 95.49003 -265.518138) (xy 95.44304 -265.365738) (xy 95.18142 -265.365738) (xy 95.13443 -265.518138)
			(xy 95.13443 -265.562588) (xy 95.49003 -265.562588)
		)
		(stroke
			(width 0)
			(type solid)
		)
		(fill yes)
		(layer "In11.Cu")
		(net "M_D_CPU1_SA_DQ<31>")
	)
	(gr_poly
		(pts
			(xy 95.49003 -265.110214) (xy 95.49003 -265.065764) (xy 95.13443 -265.065764) (xy 95.13443 -265.110214)
			(xy 95.18142 -265.262614) (xy 95.44304 -265.262614)
		)
		(stroke
			(width 0)
			(type solid)
		)
		(fill yes)
		(layer "In11.Cu")
		(net "M_D_CPU1_SA_CB<0>")
	)
	(gr_poly
		(pts
			(xy 95.49003 -261.854442) (xy 95.49003 -261.810246) (xy 95.13443 -261.810246) (xy 95.13443 -261.854442)
			(xy 95.18142 -262.006842) (xy 95.44304 -262.006842)
		)
		(stroke
			(width 0)
			(type solid)
		)
		(fill yes)
		(layer "In11.Cu")
		(net "M_D_CPU1_SA_CB<4>")
	)
	(gr_poly
		(pts
			(xy 95.49003 -257.37947) (xy 95.44304 -257.22707) (xy 95.18142 -257.22707) (xy 95.13443 -257.37947)
			(xy 95.13443 -257.423666) (xy 95.49003 -257.423666)
		)
		(stroke
			(width 0)
			(type solid)
		)
		(fill yes)
		(layer "In11.Cu")
		(net "M_D_CPU1_SA_CA<1>")
	)
	(gr_poly
		(pts
			(xy 95.49003 -256.971038) (xy 95.49003 -256.926842) (xy 95.13443 -256.926842) (xy 95.13443 -256.971038)
			(xy 95.18142 -257.123438) (xy 95.44304 -257.123438)
		)
		(stroke
			(width 0)
			(type solid)
		)
		(fill yes)
		(layer "In11.Cu")
		(net "M_D_CPU1_SA_CA<2>")
	)
	(gr_poly
		(pts
			(xy 95.49003 -255.751838) (xy 95.44304 -255.599438) (xy 95.18142 -255.599438) (xy 95.13443 -255.751838)
			(xy 95.13443 -255.796034) (xy 95.49003 -255.796034)
		)
		(stroke
			(width 0)
			(type solid)
		)
		(fill yes)
		(layer "In11.Cu")
		(net "M_D_CPU1_SA_CA<5>")
	)
	(gr_poly
		(pts
			(xy 95.692722 -232.170224) (xy 95.731076 -232.148126) (xy 95.553276 -231.840278) (xy 95.514922 -231.862376)
			(xy 95.406464 -231.979216) (xy 95.537274 -232.205784)
		)
		(stroke
			(width 0)
			(type solid)
		)
		(fill yes)
		(layer "In11.Cu")
		(net "M_D_CPU1_SB_DQ<13>")
	)
	(gr_poly
		(pts
			(xy 95.692722 -230.542338) (xy 95.731076 -230.52024) (xy 95.553276 -230.212392) (xy 95.514922 -230.23449)
			(xy 95.406464 -230.35133) (xy 95.537274 -230.577898)
		)
		(stroke
			(width 0)
			(type solid)
		)
		(fill yes)
		(layer "In11.Cu")
		(net "M_D_CPU1_SB_DQ<24>")
	)
	(gr_poly
		(pts
			(xy 95.80499 -231.555544) (xy 95.913448 -231.438704) (xy 95.782638 -231.212136) (xy 95.62719 -231.247696)
			(xy 95.588836 -231.269794) (xy 95.766636 -231.577642)
		)
		(stroke
			(width 0)
			(type solid)
		)
		(fill yes)
		(layer "In11.Cu")
		(net "M_D_CPU1_SB_DQ<15>")
	)
	(gr_poly
		(pts
			(xy 95.806768 -229.929182) (xy 95.915226 -229.812342) (xy 95.784416 -229.585774) (xy 95.628968 -229.621334)
			(xy 95.590614 -229.643432) (xy 95.768414 -229.95128)
		)
		(stroke
			(width 0)
			(type solid)
		)
		(fill yes)
		(layer "In11.Cu")
		(net "M_D_CPU1_SB_DQ<26>")
	)
	(gr_poly
		(pts
			(xy 95.83293 -246.568722) (xy 95.78594 -246.416322) (xy 95.52432 -246.416322) (xy 95.47733 -246.568722)
			(xy 95.47733 -246.612918) (xy 95.83293 -246.612918)
		)
		(stroke
			(width 0)
			(type solid)
		)
		(fill yes)
		(layer "In11.Cu")
		(net "M_D_CPU1_SB_CB<6>")
	)
	(gr_poly
		(pts
			(xy 95.83293 -246.16029) (xy 95.83293 -246.116094) (xy 95.47733 -246.116094) (xy 95.47733 -246.16029)
			(xy 95.52432 -246.31269) (xy 95.78594 -246.31269)
		)
		(stroke
			(width 0)
			(type solid)
		)
		(fill yes)
		(layer "In11.Cu")
		(net "M_D_CPU1_SB_CB<5>")
	)
	(gr_poly
		(pts
			(xy 95.83293 -244.940582) (xy 95.78594 -244.788182) (xy 95.52432 -244.788182) (xy 95.47733 -244.940582)
			(xy 95.47733 -244.985032) (xy 95.83293 -244.985032)
		)
		(stroke
			(width 0)
			(type solid)
		)
		(fill yes)
		(layer "In11.Cu")
		(net "M_D_CPU1_SB_DQS_DN<9>")
	)
	(gr_poly
		(pts
			(xy 95.83293 -244.532658) (xy 95.83293 -244.488208) (xy 95.47733 -244.488208) (xy 95.47733 -244.532658)
			(xy 95.52432 -244.685058) (xy 95.78594 -244.685058)
		)
		(stroke
			(width 0)
			(type solid)
		)
		(fill yes)
		(layer "In11.Cu")
		(net "M_D_CPU1_SB_DQS_DN<4>")
	)
	(gr_poly
		(pts
			(xy 95.83293 -243.31295) (xy 95.78594 -243.16055) (xy 95.52432 -243.16055) (xy 95.47733 -243.31295)
			(xy 95.47733 -243.3574) (xy 95.83293 -243.3574)
		)
		(stroke
			(width 0)
			(type solid)
		)
		(fill yes)
		(layer "In11.Cu")
		(net "M_D_CPU1_SB_CB<2>")
	)
	(gr_poly
		(pts
			(xy 95.83293 -242.905026) (xy 95.83293 -242.860576) (xy 95.47733 -242.860576) (xy 95.47733 -242.905026)
			(xy 95.52432 -243.057426) (xy 95.78594 -243.057426)
		)
		(stroke
			(width 0)
			(type solid)
		)
		(fill yes)
		(layer "In11.Cu")
		(net "M_D_CPU1_SB_CB<1>")
	)
	(gr_poly
		(pts
			(xy 95.83293 -241.685318) (xy 95.78594 -241.532918) (xy 95.52432 -241.532918) (xy 95.47733 -241.685318)
			(xy 95.47733 -241.729514) (xy 95.83293 -241.729514)
		)
		(stroke
			(width 0)
			(type solid)
		)
		(fill yes)
		(layer "In11.Cu")
		(net "M_D_CPU1_SB_DQ<2>")
	)
	(gr_poly
		(pts
			(xy 95.83293 -241.276886) (xy 95.83293 -241.23269) (xy 95.47733 -241.23269) (xy 95.47733 -241.276886)
			(xy 95.52432 -241.429286) (xy 95.78594 -241.429286)
		)
		(stroke
			(width 0)
			(type solid)
		)
		(fill yes)
		(layer "In11.Cu")
		(net "M_D_CPU1_SB_DQ<1>")
	)
	(gr_poly
		(pts
			(xy 95.83293 -240.057178) (xy 95.78594 -239.904778) (xy 95.52432 -239.904778) (xy 95.47733 -240.057178)
			(xy 95.47733 -240.101628) (xy 95.83293 -240.101628)
		)
		(stroke
			(width 0)
			(type solid)
		)
		(fill yes)
		(layer "In11.Cu")
		(net "M_D_CPU1_SB_DQS_DN<0>")
	)
	(gr_poly
		(pts
			(xy 95.83293 -239.649254) (xy 95.83293 -239.604804) (xy 95.47733 -239.604804) (xy 95.47733 -239.649254)
			(xy 95.52432 -239.801654) (xy 95.78594 -239.801654)
		)
		(stroke
			(width 0)
			(type solid)
		)
		(fill yes)
		(layer "In11.Cu")
		(net "M_D_CPU1_SB_DQS_DN<5>")
	)
	(gr_poly
		(pts
			(xy 95.83293 -238.429546) (xy 95.78594 -238.277146) (xy 95.52432 -238.277146) (xy 95.47733 -238.429546)
			(xy 95.47733 -238.473996) (xy 95.83293 -238.473996)
		)
		(stroke
			(width 0)
			(type solid)
		)
		(fill yes)
		(layer "In11.Cu")
		(net "M_D_CPU1_SB_DQ<6>")
	)
	(gr_poly
		(pts
			(xy 95.83293 -238.021622) (xy 95.83293 -237.977172) (xy 95.47733 -237.977172) (xy 95.47733 -238.021622)
			(xy 95.52432 -238.174022) (xy 95.78594 -238.174022)
		)
		(stroke
			(width 0)
			(type solid)
		)
		(fill yes)
		(layer "In11.Cu")
		(net "M_D_CPU1_SB_DQ<5>")
	)
	(gr_poly
		(pts
			(xy 95.83293 -236.801914) (xy 95.78594 -236.649514) (xy 95.52432 -236.649514) (xy 95.47733 -236.801914)
			(xy 95.47733 -236.84611) (xy 95.83293 -236.84611)
		)
		(stroke
			(width 0)
			(type solid)
		)
		(fill yes)
		(layer "In11.Cu")
		(net "M_D_CPU1_SB_DQ<10>")
	)
	(gr_poly
		(pts
			(xy 95.83293 -236.39399) (xy 95.83293 -236.34954) (xy 95.47733 -236.34954) (xy 95.47733 -236.39399)
			(xy 95.52432 -236.54639) (xy 95.78594 -236.54639)
		)
		(stroke
			(width 0)
			(type solid)
		)
		(fill yes)
		(layer "In11.Cu")
		(net "M_D_CPU1_SB_DQ<9>")
	)
	(gr_poly
		(pts
			(xy 95.83293 -235.174282) (xy 95.78594 -235.021882) (xy 95.52432 -235.021882) (xy 95.47733 -235.174282)
			(xy 95.47733 -235.218478) (xy 95.83293 -235.218478)
		)
		(stroke
			(width 0)
			(type solid)
		)
		(fill yes)
		(layer "In11.Cu")
		(net "M_D_CPU1_SB_DQS_DN<1>")
	)
	(gr_poly
		(pts
			(xy 95.83293 -234.76585) (xy 95.83293 -234.721654) (xy 95.47733 -234.721654) (xy 95.47733 -234.76585)
			(xy 95.52432 -234.91825) (xy 95.78594 -234.91825)
		)
		(stroke
			(width 0)
			(type solid)
		)
		(fill yes)
		(layer "In11.Cu")
		(net "M_D_CPU1_SB_DQS_DN<6>")
	)
	(gr_poly
		(pts
			(xy 95.83293 -233.546142) (xy 95.78594 -233.393742) (xy 95.52432 -233.393742) (xy 95.47733 -233.546142)
			(xy 95.47733 -233.590592) (xy 95.83293 -233.590592)
		)
		(stroke
			(width 0)
			(type solid)
		)
		(fill yes)
		(layer "In11.Cu")
		(net "M_D_CPU1_SB_DQ<14>")
	)
	(gr_poly
		(pts
			(xy 95.83293 -228.663246) (xy 95.78594 -228.510846) (xy 95.52432 -228.510846) (xy 95.47733 -228.663246)
			(xy 95.47733 -228.707442) (xy 95.83293 -228.707442)
		)
		(stroke
			(width 0)
			(type solid)
		)
		(fill yes)
		(layer "In11.Cu")
		(net "M_D_CPU1_SB_DQ<27>")
	)
	(gr_poly
		(pts
			(xy 95.83293 -228.254814) (xy 95.83293 -228.210618) (xy 95.47733 -228.210618) (xy 95.47733 -228.254814)
			(xy 95.52432 -228.407214) (xy 95.78594 -228.407214)
		)
		(stroke
			(width 0)
			(type solid)
		)
		(fill yes)
		(layer "In11.Cu")
		(net "M_D_CPU1_SB_DQS_DP<3>")
	)
	(gr_poly
		(pts
			(xy 95.83293 -225.407474) (xy 95.78594 -225.255074) (xy 95.52432 -225.255074) (xy 95.47733 -225.407474)
			(xy 95.47733 -225.45167) (xy 95.83293 -225.45167)
		)
		(stroke
			(width 0)
			(type solid)
		)
		(fill yes)
		(layer "In11.Cu")
		(net "M_D_CPU1_SB_DQ<31>")
	)
	(gr_poly
		(pts
			(xy 95.83547 -247.787922) (xy 95.83547 -247.743726) (xy 95.47987 -247.743726) (xy 95.47987 -247.787922)
			(xy 95.52686 -247.940322) (xy 95.78848 -247.940322)
		)
		(stroke
			(width 0)
			(type solid)
		)
		(fill yes)
		(layer "In11.Cu")
		(net "M_D_CPU1_SB_CA<5>")
	)
	(gr_poly
		(pts
			(xy 95.83547 -226.627182) (xy 95.83547 -226.582732) (xy 95.47987 -226.582732) (xy 95.47987 -226.627182)
			(xy 95.52686 -226.779582) (xy 95.78848 -226.779582)
		)
		(stroke
			(width 0)
			(type solid)
		)
		(fill yes)
		(layer "In11.Cu")
		(net "M_D_CPU1_SB_DQ<28>")
	)
	(gr_poly
		(pts
			(xy 95.841312 -227.035614) (xy 95.794322 -226.883214) (xy 95.532702 -226.883214) (xy 95.485712 -227.035614)
			(xy 95.485712 -227.07981) (xy 95.841312 -227.07981)
		)
		(stroke
			(width 0)
			(type solid)
		)
		(fill yes)
		(layer "In11.Cu")
		(net "M_D_CPU1_SB_DQS_DP<8>")
	)
	(gr_poly
		(pts
			(xy 95.942912 -279.354534) (xy 95.895922 -279.202134) (xy 95.634302 -279.202134) (xy 95.587312 -279.354534)
			(xy 95.587312 -279.39873) (xy 95.942912 -279.39873)
		)
		(stroke
			(width 0)
			(type solid)
		)
		(fill yes)
		(layer "In11.Cu")
		(net "M_D_CPU1_SA_DQ<10>")
	)
	(gr_poly
		(pts
			(xy 95.942912 -278.946102) (xy 95.942912 -278.901906) (xy 95.587312 -278.901906) (xy 95.587312 -278.946102)
			(xy 95.634302 -279.098502) (xy 95.895922 -279.098502)
		)
		(stroke
			(width 0)
			(type solid)
		)
		(fill yes)
		(layer "In11.Cu")
		(net "M_D_CPU1_SA_DQ<9>")
	)
	(gr_poly
		(pts
			(xy 95.942912 -277.726394) (xy 95.895922 -277.573994) (xy 95.634302 -277.573994) (xy 95.587312 -277.726394)
			(xy 95.587312 -277.770844) (xy 95.942912 -277.770844)
		)
		(stroke
			(width 0)
			(type solid)
		)
		(fill yes)
		(layer "In11.Cu")
		(net "M_D_CPU1_SA_DQS_DN<1>")
	)
	(gr_poly
		(pts
			(xy 95.942912 -277.318216) (xy 95.942912 -277.27402) (xy 95.587312 -277.27402) (xy 95.587312 -277.318216)
			(xy 95.634302 -277.470616) (xy 95.895922 -277.470616)
		)
		(stroke
			(width 0)
			(type solid)
		)
		(fill yes)
		(layer "In11.Cu")
		(net "M_D_CPU1_SA_DQS_DN<6>")
	)
	(gr_poly
		(pts
			(xy 95.942912 -276.098762) (xy 95.895922 -275.946362) (xy 95.634302 -275.946362) (xy 95.587312 -276.098762)
			(xy 95.587312 -276.143212) (xy 95.942912 -276.143212)
		)
		(stroke
			(width 0)
			(type solid)
		)
		(fill yes)
		(layer "In11.Cu")
		(net "M_D_CPU1_SA_DQ<14>")
	)
	(gr_poly
		(pts
			(xy 95.942912 -275.690584) (xy 95.942912 -275.646388) (xy 95.587312 -275.646388) (xy 95.587312 -275.690584)
			(xy 95.634302 -275.842984) (xy 95.895922 -275.842984)
		)
		(stroke
			(width 0)
			(type solid)
		)
		(fill yes)
		(layer "In11.Cu")
		(net "M_D_CPU1_SA_DQ<13>")
	)
	(gr_poly
		(pts
			(xy 95.942912 -274.47113) (xy 95.895922 -274.31873) (xy 95.634302 -274.31873) (xy 95.587312 -274.47113)
			(xy 95.587312 -274.515326) (xy 95.942912 -274.515326)
		)
		(stroke
			(width 0)
			(type solid)
		)
		(fill yes)
		(layer "In11.Cu")
		(net "M_D_CPU1_SA_DQ<18>")
	)
	(gr_poly
		(pts
			(xy 95.942912 -274.062698) (xy 95.942912 -274.018502) (xy 95.587312 -274.018502) (xy 95.587312 -274.062698)
			(xy 95.634302 -274.215098) (xy 95.895922 -274.215098)
		)
		(stroke
			(width 0)
			(type solid)
		)
		(fill yes)
		(layer "In11.Cu")
		(net "M_D_CPU1_SA_DQ<17>")
	)
	(gr_poly
		(pts
			(xy 95.942912 -272.843498) (xy 95.895922 -272.691098) (xy 95.634302 -272.691098) (xy 95.587312 -272.843498)
			(xy 95.587312 -272.887694) (xy 95.942912 -272.887694)
		)
		(stroke
			(width 0)
			(type solid)
		)
		(fill yes)
		(layer "In11.Cu")
		(net "M_D_CPU1_SA_DQS_DN<2>")
	)
	(gr_poly
		(pts
			(xy 95.942912 -272.435066) (xy 95.942912 -272.39087) (xy 95.587312 -272.39087) (xy 95.587312 -272.435066)
			(xy 95.634302 -272.587466) (xy 95.895922 -272.587466)
		)
		(stroke
			(width 0)
			(type solid)
		)
		(fill yes)
		(layer "In11.Cu")
		(net "M_D_CPU1_SA_DQS_DN<7>")
	)
	(gr_poly
		(pts
			(xy 95.942912 -271.215358) (xy 95.895922 -271.062958) (xy 95.634302 -271.062958) (xy 95.587312 -271.215358)
			(xy 95.587312 -271.259808) (xy 95.942912 -271.259808)
		)
		(stroke
			(width 0)
			(type solid)
		)
		(fill yes)
		(layer "In11.Cu")
		(net "M_D_CPU1_SA_DQ<22>")
	)
	(gr_poly
		(pts
			(xy 95.942912 -270.807434) (xy 95.942912 -270.762984) (xy 95.587312 -270.762984) (xy 95.587312 -270.807434)
			(xy 95.634302 -270.959834) (xy 95.895922 -270.959834)
		)
		(stroke
			(width 0)
			(type solid)
		)
		(fill yes)
		(layer "In11.Cu")
		(net "M_D_CPU1_SA_DQ<21>")
	)
	(gr_poly
		(pts
			(xy 95.942912 -269.587726) (xy 95.895922 -269.435326) (xy 95.634302 -269.435326) (xy 95.587312 -269.587726)
			(xy 95.587312 -269.631922) (xy 95.942912 -269.631922)
		)
		(stroke
			(width 0)
			(type solid)
		)
		(fill yes)
		(layer "In11.Cu")
		(net "M_D_CPU1_SA_DQ<26>")
	)
	(gr_poly
		(pts
			(xy 95.942912 -267.960094) (xy 95.895922 -267.807694) (xy 95.634302 -267.807694) (xy 95.587312 -267.960094)
			(xy 95.587312 -268.00429) (xy 95.942912 -268.00429)
		)
		(stroke
			(width 0)
			(type solid)
		)
		(fill yes)
		(layer "In11.Cu")
		(net "M_D_CPU1_SA_DQS_DN<3>")
	)
	(gr_poly
		(pts
			(xy 95.942912 -267.551662) (xy 95.942912 -267.507466) (xy 95.587312 -267.507466) (xy 95.587312 -267.551662)
			(xy 95.634302 -267.704062) (xy 95.895922 -267.704062)
		)
		(stroke
			(width 0)
			(type solid)
		)
		(fill yes)
		(layer "In11.Cu")
		(net "M_D_CPU1_SA_DQS_DN<8>")
	)
	(gr_poly
		(pts
			(xy 95.942912 -266.331954) (xy 95.895922 -266.179554) (xy 95.634302 -266.179554) (xy 95.587312 -266.331954)
			(xy 95.587312 -266.376404) (xy 95.942912 -266.376404)
		)
		(stroke
			(width 0)
			(type solid)
		)
		(fill yes)
		(layer "In11.Cu")
		(net "M_D_CPU1_SA_DQ<30>")
	)
	(gr_poly
		(pts
			(xy 95.942912 -265.92403) (xy 95.942912 -265.87958) (xy 95.587312 -265.87958) (xy 95.587312 -265.92403)
			(xy 95.634302 -266.07643) (xy 95.895922 -266.07643)
		)
		(stroke
			(width 0)
			(type solid)
		)
		(fill yes)
		(layer "In11.Cu")
		(net "M_D_CPU1_SA_DQ<29>")
	)
	(gr_poly
		(pts
			(xy 95.942912 -264.704322) (xy 95.895922 -264.551922) (xy 95.634302 -264.551922) (xy 95.587312 -264.704322)
			(xy 95.587312 -264.748772) (xy 95.942912 -264.748772)
		)
		(stroke
			(width 0)
			(type solid)
		)
		(fill yes)
		(layer "In11.Cu")
		(net "M_D_CPU1_SA_CB<2>")
	)
	(gr_poly
		(pts
			(xy 95.942912 -264.296398) (xy 95.942912 -264.251948) (xy 95.587312 -264.251948) (xy 95.587312 -264.296398)
			(xy 95.634302 -264.448798) (xy 95.895922 -264.448798)
		)
		(stroke
			(width 0)
			(type solid)
		)
		(fill yes)
		(layer "In11.Cu")
		(net "M_D_CPU1_SA_CB<1>")
	)
	(gr_poly
		(pts
			(xy 95.942912 -263.07669) (xy 95.895922 -262.92429) (xy 95.634302 -262.92429) (xy 95.587312 -263.07669)
			(xy 95.587312 -263.120886) (xy 95.942912 -263.120886)
		)
		(stroke
			(width 0)
			(type solid)
		)
		(fill yes)
		(layer "In11.Cu")
		(net "M_D_CPU1_SA_DQS_DN<4>")
	)
	(gr_poly
		(pts
			(xy 95.942912 -261.449058) (xy 95.895922 -261.296658) (xy 95.634302 -261.296658) (xy 95.587312 -261.449058)
			(xy 95.587312 -261.493254) (xy 95.942912 -261.493254)
		)
		(stroke
			(width 0)
			(type solid)
		)
		(fill yes)
		(layer "In11.Cu")
		(net "M_D_CPU1_SA_CB<6>")
	)
	(gr_poly
		(pts
			(xy 95.942912 -261.040626) (xy 95.942912 -260.99643) (xy 95.587312 -260.99643) (xy 95.587312 -261.040626)
			(xy 95.634302 -261.193026) (xy 95.895922 -261.193026)
		)
		(stroke
			(width 0)
			(type solid)
		)
		(fill yes)
		(layer "In11.Cu")
		(net "M_D_CPU1_SA_CB<5>")
	)
	(gr_poly
		(pts
			(xy 95.942912 -259.412994) (xy 95.942912 -259.368544) (xy 95.587312 -259.368544) (xy 95.587312 -259.412994)
			(xy 95.634302 -259.565394) (xy 95.895922 -259.565394)
		)
		(stroke
			(width 0)
			(type solid)
		)
		(fill yes)
		(layer "In11.Cu")
		(net "M_D_CPU1_SA_CS_N<2>")
	)
	(gr_poly
		(pts
			(xy 95.942912 -258.193286) (xy 95.895922 -258.040886) (xy 95.634302 -258.040886) (xy 95.587312 -258.193286)
			(xy 95.587312 -258.237482) (xy 95.942912 -258.237482)
		)
		(stroke
			(width 0)
			(type solid)
		)
		(fill yes)
		(layer "In11.Cu")
		(net "M_D_CPU1_SA_CS_N<1>")
	)
	(gr_poly
		(pts
			(xy 95.942912 -257.784854) (xy 95.942912 -257.740658) (xy 95.587312 -257.740658) (xy 95.587312 -257.784854)
			(xy 95.634302 -257.937254) (xy 95.895922 -257.937254)
		)
		(stroke
			(width 0)
			(type solid)
		)
		(fill yes)
		(layer "In11.Cu")
		(net "M_D_CPU1_SA_CA<0>")
	)
	(gr_poly
		(pts
			(xy 95.942912 -256.565654) (xy 95.895922 -256.413254) (xy 95.634302 -256.413254) (xy 95.587312 -256.565654)
			(xy 95.587312 -256.60985) (xy 95.942912 -256.60985)
		)
		(stroke
			(width 0)
			(type solid)
		)
		(fill yes)
		(layer "In11.Cu")
		(net "M_D_CPU1_SA_CA<3>")
	)
	(gr_poly
		(pts
			(xy 95.942912 -256.157222) (xy 95.942912 -256.113026) (xy 95.587312 -256.113026) (xy 95.587312 -256.157222)
			(xy 95.634302 -256.309622) (xy 95.895922 -256.309622)
		)
		(stroke
			(width 0)
			(type solid)
		)
		(fill yes)
		(layer "In11.Cu")
		(net "M_D_CPU1_SA_CA<4>")
	)
	(gr_poly
		(pts
			(xy 95.95485 -269.179294) (xy 95.95485 -269.134844) (xy 95.59925 -269.134844) (xy 95.59925 -269.179294)
			(xy 95.64624 -269.331694) (xy 95.90786 -269.331694)
		)
		(stroke
			(width 0)
			(type solid)
		)
		(fill yes)
		(layer "In11.Cu")
		(net "M_D_CPU1_SA_DQ<25>")
	)
	(gr_poly
		(pts
			(xy 95.95485 -262.668258) (xy 95.95485 -262.623808) (xy 95.59925 -262.623808) (xy 95.59925 -262.668258)
			(xy 95.64624 -262.820658) (xy 95.90786 -262.820658)
		)
		(stroke
			(width 0)
			(type solid)
		)
		(fill yes)
		(layer "In11.Cu")
		(net "M_D_CPU1_SA_DQS_DN<9>")
	)
	(gr_poly
		(pts
			(xy 96.16821 -232.993692) (xy 96.206564 -232.971594) (xy 96.028764 -232.663746) (xy 95.99041 -232.685844)
			(xy 95.881952 -232.802684) (xy 96.012762 -233.029252)
		)
		(stroke
			(width 0)
			(type solid)
		)
		(fill yes)
		(layer "In11.Cu")
		(net "M_D_CPU1_SB_DQ<13>")
	)
	(gr_poly
		(pts
			(xy 96.16821 -229.738174) (xy 96.206564 -229.716076) (xy 96.028764 -229.408228) (xy 95.99041 -229.430326)
			(xy 95.881952 -229.547166) (xy 96.012762 -229.773734)
		)
		(stroke
			(width 0)
			(type solid)
		)
		(fill yes)
		(layer "In11.Cu")
		(net "M_D_CPU1_SB_DQ<25>")
	)
	(gr_poly
		(pts
			(xy 96.169988 -231.36733) (xy 96.208342 -231.345232) (xy 96.030542 -231.037384) (xy 95.992188 -231.059482)
			(xy 95.88373 -231.176322) (xy 96.01454 -231.40289)
		)
		(stroke
			(width 0)
			(type solid)
		)
		(fill yes)
		(layer "In11.Cu")
		(net "M_D_CPU1_SB_DQ<24>")
	)
	(gr_poly
		(pts
			(xy 96.282256 -232.380536) (xy 96.390714 -232.263696) (xy 96.259904 -232.037128) (xy 96.104456 -232.072688)
			(xy 96.066102 -232.094786) (xy 96.243902 -232.402634)
		)
		(stroke
			(width 0)
			(type solid)
		)
		(fill yes)
		(layer "In11.Cu")
		(net "M_D_CPU1_SB_DQ<15>")
	)
	(gr_poly
		(pts
			(xy 96.282256 -230.75265) (xy 96.390714 -230.63581) (xy 96.259904 -230.409242) (xy 96.104456 -230.444802)
			(xy 96.066102 -230.4669) (xy 96.243902 -230.774748)
		)
		(stroke
			(width 0)
			(type solid)
		)
		(fill yes)
		(layer "In11.Cu")
		(net "M_D_CPU1_SB_DQ<26>")
	)
	(gr_poly
		(pts
			(xy 96.282256 -229.125018) (xy 96.390714 -229.008178) (xy 96.259904 -228.78161) (xy 96.104456 -228.81717)
			(xy 96.066102 -228.839268) (xy 96.243902 -229.147116)
		)
		(stroke
			(width 0)
			(type solid)
		)
		(fill yes)
		(layer "In11.Cu")
		(net "M_D_CPU1_SB_DQ<27>")
	)
	(gr_poly
		(pts
			(xy 96.30537 -247.382538) (xy 96.25838 -247.230138) (xy 95.99676 -247.230138) (xy 95.94977 -247.382538)
			(xy 95.94977 -247.426988) (xy 96.30537 -247.426988)
		)
		(stroke
			(width 0)
			(type solid)
		)
		(fill yes)
		(layer "In11.Cu")
		(net "M_D_CPU1_SB_PAR")
	)
	(gr_poly
		(pts
			(xy 96.311466 -227.44049) (xy 96.311466 -227.396294) (xy 95.955866 -227.396294) (xy 95.955866 -227.44049)
			(xy 96.002856 -227.59289) (xy 96.264476 -227.59289)
		)
		(stroke
			(width 0)
			(type solid)
		)
		(fill yes)
		(layer "In11.Cu")
		(net "M_D_CPU1_SB_DQS_DN<8>")
	)
	(gr_poly
		(pts
			(xy 96.311466 -226.221798) (xy 96.264476 -226.069398) (xy 96.002856 -226.069398) (xy 95.955866 -226.221798)
			(xy 95.955866 -226.265994) (xy 96.311466 -226.265994)
		)
		(stroke
			(width 0)
			(type solid)
		)
		(fill yes)
		(layer "In11.Cu")
		(net "M_D_CPU1_SB_DQ<30>")
	)
	(gr_poly
		(pts
			(xy 96.317308 -246.974106) (xy 96.317308 -246.929656) (xy 95.961708 -246.929656) (xy 95.961708 -246.974106)
			(xy 96.008698 -247.126506) (xy 96.270318 -247.126506)
		)
		(stroke
			(width 0)
			(type solid)
		)
		(fill yes)
		(layer "In11.Cu")
		(net "M_D_CPU1_SB_CB<4>")
	)
	(gr_poly
		(pts
			(xy 96.319848 -245.754906) (xy 96.272858 -245.602506) (xy 96.011238 -245.602506) (xy 95.964248 -245.754906)
			(xy 95.964248 -245.799102) (xy 96.319848 -245.799102)
		)
		(stroke
			(width 0)
			(type solid)
		)
		(fill yes)
		(layer "In11.Cu")
		(net "M_D_CPU1_SB_CB<7>")
	)
	(gr_poly
		(pts
			(xy 96.319848 -245.346474) (xy 96.319848 -245.302278) (xy 95.964248 -245.302278) (xy 95.964248 -245.346474)
			(xy 96.011238 -245.498874) (xy 96.272858 -245.498874)
		)
		(stroke
			(width 0)
			(type solid)
		)
		(fill yes)
		(layer "In11.Cu")
		(net "M_D_CPU1_SB_DQS_DP<9>")
	)
	(gr_poly
		(pts
			(xy 96.319848 -244.126766) (xy 96.272858 -243.974366) (xy 96.011238 -243.974366) (xy 95.964248 -244.126766)
			(xy 95.964248 -244.171216) (xy 96.319848 -244.171216)
		)
		(stroke
			(width 0)
			(type solid)
		)
		(fill yes)
		(layer "In11.Cu")
		(net "M_D_CPU1_SB_DQS_DP<4>")
	)
	(gr_poly
		(pts
			(xy 96.319848 -243.718842) (xy 96.319848 -243.674392) (xy 95.964248 -243.674392) (xy 95.964248 -243.718842)
			(xy 96.011238 -243.871242) (xy 96.272858 -243.871242)
		)
		(stroke
			(width 0)
			(type solid)
		)
		(fill yes)
		(layer "In11.Cu")
		(net "M_D_CPU1_SB_CB<0>")
	)
	(gr_poly
		(pts
			(xy 96.319848 -242.499134) (xy 96.272858 -242.346734) (xy 96.011238 -242.346734) (xy 95.964248 -242.499134)
			(xy 95.964248 -242.54333) (xy 96.319848 -242.54333)
		)
		(stroke
			(width 0)
			(type solid)
		)
		(fill yes)
		(layer "In11.Cu")
		(net "M_D_CPU1_SB_CB<3>")
	)
	(gr_poly
		(pts
			(xy 96.319848 -242.090702) (xy 96.319848 -242.046506) (xy 95.964248 -242.046506) (xy 95.964248 -242.090702)
			(xy 96.011238 -242.243102) (xy 96.272858 -242.243102)
		)
		(stroke
			(width 0)
			(type solid)
		)
		(fill yes)
		(layer "In11.Cu")
		(net "M_D_CPU1_SB_DQ<0>")
	)
	(gr_poly
		(pts
			(xy 96.319848 -240.871502) (xy 96.272858 -240.719102) (xy 96.011238 -240.719102) (xy 95.964248 -240.871502)
			(xy 95.964248 -240.915698) (xy 96.319848 -240.915698)
		)
		(stroke
			(width 0)
			(type solid)
		)
		(fill yes)
		(layer "In11.Cu")
		(net "M_D_CPU1_SB_DQ<3>")
	)
	(gr_poly
		(pts
			(xy 96.319848 -240.46307) (xy 96.319848 -240.418874) (xy 95.964248 -240.418874) (xy 95.964248 -240.46307)
			(xy 96.011238 -240.61547) (xy 96.272858 -240.61547)
		)
		(stroke
			(width 0)
			(type solid)
		)
		(fill yes)
		(layer "In11.Cu")
		(net "M_D_CPU1_SB_DQS_DP<0>")
	)
	(gr_poly
		(pts
			(xy 96.319848 -239.243362) (xy 96.272858 -239.090962) (xy 96.011238 -239.090962) (xy 95.964248 -239.243362)
			(xy 95.964248 -239.287812) (xy 96.319848 -239.287812)
		)
		(stroke
			(width 0)
			(type solid)
		)
		(fill yes)
		(layer "In11.Cu")
		(net "M_D_CPU1_SB_DQS_DP<5>")
	)
	(gr_poly
		(pts
			(xy 96.319848 -238.835438) (xy 96.319848 -238.790988) (xy 95.964248 -238.790988) (xy 95.964248 -238.835438)
			(xy 96.011238 -238.987838) (xy 96.272858 -238.987838)
		)
		(stroke
			(width 0)
			(type solid)
		)
		(fill yes)
		(layer "In11.Cu")
		(net "M_D_CPU1_SB_DQ<4>")
	)
	(gr_poly
		(pts
			(xy 96.319848 -237.61573) (xy 96.272858 -237.46333) (xy 96.011238 -237.46333) (xy 95.964248 -237.61573)
			(xy 95.964248 -237.66018) (xy 96.319848 -237.66018)
		)
		(stroke
			(width 0)
			(type solid)
		)
		(fill yes)
		(layer "In11.Cu")
		(net "M_D_CPU1_SB_DQ<7>")
	)
	(gr_poly
		(pts
			(xy 96.319848 -237.207806) (xy 96.319848 -237.163356) (xy 95.964248 -237.163356) (xy 95.964248 -237.207806)
			(xy 96.011238 -237.360206) (xy 96.272858 -237.360206)
		)
		(stroke
			(width 0)
			(type solid)
		)
		(fill yes)
		(layer "In11.Cu")
		(net "M_D_CPU1_SB_DQ<8>")
	)
	(gr_poly
		(pts
			(xy 96.319848 -235.988098) (xy 96.272858 -235.835698) (xy 96.011238 -235.835698) (xy 95.964248 -235.988098)
			(xy 95.964248 -236.032294) (xy 96.319848 -236.032294)
		)
		(stroke
			(width 0)
			(type solid)
		)
		(fill yes)
		(layer "In11.Cu")
		(net "M_D_CPU1_SB_DQ<11>")
	)
	(gr_poly
		(pts
			(xy 96.319848 -235.579666) (xy 96.319848 -235.53547) (xy 95.964248 -235.53547) (xy 95.964248 -235.579666)
			(xy 96.011238 -235.732066) (xy 96.272858 -235.732066)
		)
		(stroke
			(width 0)
			(type solid)
		)
		(fill yes)
		(layer "In11.Cu")
		(net "M_D_CPU1_SB_DQS_DP<1>")
	)
	(gr_poly
		(pts
			(xy 96.319848 -234.360466) (xy 96.272858 -234.208066) (xy 96.011238 -234.208066) (xy 95.964248 -234.360466)
			(xy 95.964248 -234.404662) (xy 96.319848 -234.404662)
		)
		(stroke
			(width 0)
			(type solid)
		)
		(fill yes)
		(layer "In11.Cu")
		(net "M_D_CPU1_SB_DQS_DP<6>")
	)
	(gr_poly
		(pts
			(xy 96.319848 -233.952034) (xy 96.319848 -233.907838) (xy 95.964248 -233.907838) (xy 95.964248 -233.952034)
			(xy 96.011238 -234.104434) (xy 96.272858 -234.104434)
		)
		(stroke
			(width 0)
			(type solid)
		)
		(fill yes)
		(layer "In11.Cu")
		(net "M_D_CPU1_SB_DQ<12>")
	)
	(gr_poly
		(pts
			(xy 96.319848 -227.848922) (xy 96.272858 -227.696522) (xy 96.011238 -227.696522) (xy 95.964248 -227.848922)
			(xy 95.964248 -227.893372) (xy 96.319848 -227.893372)
		)
		(stroke
			(width 0)
			(type solid)
		)
		(fill yes)
		(layer "In11.Cu")
		(net "M_D_CPU1_SB_DQS_DN<3>")
	)
	(gr_poly
		(pts
			(xy 96.319848 -225.813366) (xy 96.319848 -225.768916) (xy 95.964248 -225.768916) (xy 95.964248 -225.813366)
			(xy 96.011238 -225.965766) (xy 96.272858 -225.965766)
		)
		(stroke
			(width 0)
			(type solid)
		)
		(fill yes)
		(layer "In11.Cu")
		(net "M_D_CPU1_SB_DQ<29>")
	)
	(gr_poly
		(pts
			(xy 96.417892 -270.40205) (xy 96.370902 -270.24965) (xy 96.109282 -270.24965) (xy 96.062292 -270.40205)
			(xy 96.062292 -270.446246) (xy 96.417892 -270.446246)
		)
		(stroke
			(width 0)
			(type solid)
		)
		(fill yes)
		(layer "In11.Cu")
		(net "M_D_CPU1_SA_DQ<23>")
	)
	(gr_poly
		(pts
			(xy 96.417892 -268.77391) (xy 96.370902 -268.62151) (xy 96.109282 -268.62151) (xy 96.062292 -268.77391)
			(xy 96.062292 -268.81836) (xy 96.417892 -268.81836)
		)
		(stroke
			(width 0)
			(type solid)
		)
		(fill yes)
		(layer "In11.Cu")
		(net "M_D_CPU1_SA_DQ<27>")
	)
	(gr_poly
		(pts
			(xy 96.417892 -262.262874) (xy 96.370902 -262.110474) (xy 96.109282 -262.110474) (xy 96.062292 -262.262874)
			(xy 96.062292 -262.307324) (xy 96.417892 -262.307324)
		)
		(stroke
			(width 0)
			(type solid)
		)
		(fill yes)
		(layer "In11.Cu")
		(net "M_D_CPU1_SA_DQS_DP<9>")
	)
	(gr_poly
		(pts
			(xy 96.421194 -260.635242) (xy 96.374204 -260.482842) (xy 96.112584 -260.482842) (xy 96.065594 -260.635242)
			(xy 96.065594 -260.679438) (xy 96.421194 -260.679438)
		)
		(stroke
			(width 0)
			(type solid)
		)
		(fill yes)
		(layer "In11.Cu")
		(net "M_D_CPU1_SA_CB<7>")
	)
	(gr_poly
		(pts
			(xy 96.42983 -279.759918) (xy 96.42983 -279.715722) (xy 96.07423 -279.715722) (xy 96.07423 -279.759918)
			(xy 96.12122 -279.912318) (xy 96.38284 -279.912318)
		)
		(stroke
			(width 0)
			(type solid)
		)
		(fill yes)
		(layer "In11.Cu")
		(net "M_D_CPU1_SA_DQ<8>")
	)
	(gr_poly
		(pts
			(xy 96.42983 -278.540718) (xy 96.38284 -278.388318) (xy 96.12122 -278.388318) (xy 96.07423 -278.540718)
			(xy 96.07423 -278.584914) (xy 96.42983 -278.584914)
		)
		(stroke
			(width 0)
			(type solid)
		)
		(fill yes)
		(layer "In11.Cu")
		(net "M_D_CPU1_SA_DQ<11>")
	)
	(gr_poly
		(pts
			(xy 96.42983 -278.132286) (xy 96.42983 -278.08809) (xy 96.07423 -278.08809) (xy 96.07423 -278.132286)
			(xy 96.12122 -278.284686) (xy 96.38284 -278.284686)
		)
		(stroke
			(width 0)
			(type solid)
		)
		(fill yes)
		(layer "In11.Cu")
		(net "M_D_CPU1_SA_DQS_DP<1>")
	)
	(gr_poly
		(pts
			(xy 96.42983 -276.912578) (xy 96.38284 -276.760178) (xy 96.12122 -276.760178) (xy 96.07423 -276.912578)
			(xy 96.07423 -276.957028) (xy 96.42983 -276.957028)
		)
		(stroke
			(width 0)
			(type solid)
		)
		(fill yes)
		(layer "In11.Cu")
		(net "M_D_CPU1_SA_DQS_DP<6>")
	)
	(gr_poly
		(pts
			(xy 96.42983 -276.5044) (xy 96.42983 -276.460204) (xy 96.07423 -276.460204) (xy 96.07423 -276.5044)
			(xy 96.12122 -276.6568) (xy 96.38284 -276.6568)
		)
		(stroke
			(width 0)
			(type solid)
		)
		(fill yes)
		(layer "In11.Cu")
		(net "M_D_CPU1_SA_DQ<12>")
	)
	(gr_poly
		(pts
			(xy 96.42983 -275.284946) (xy 96.38284 -275.132546) (xy 96.12122 -275.132546) (xy 96.07423 -275.284946)
			(xy 96.07423 -275.329142) (xy 96.42983 -275.329142)
		)
		(stroke
			(width 0)
			(type solid)
		)
		(fill yes)
		(layer "In11.Cu")
		(net "M_D_CPU1_SA_DQ<15>")
	)
	(gr_poly
		(pts
			(xy 96.42983 -274.876514) (xy 96.42983 -274.832318) (xy 96.07423 -274.832318) (xy 96.07423 -274.876514)
			(xy 96.12122 -275.028914) (xy 96.38284 -275.028914)
		)
		(stroke
			(width 0)
			(type solid)
		)
		(fill yes)
		(layer "In11.Cu")
		(net "M_D_CPU1_SA_DQ<16>")
	)
	(gr_poly
		(pts
			(xy 96.42983 -273.657314) (xy 96.38284 -273.504914) (xy 96.12122 -273.504914) (xy 96.07423 -273.657314)
			(xy 96.07423 -273.70151) (xy 96.42983 -273.70151)
		)
		(stroke
			(width 0)
			(type solid)
		)
		(fill yes)
		(layer "In11.Cu")
		(net "M_D_CPU1_SA_DQ<19>")
	)
	(gr_poly
		(pts
			(xy 96.42983 -273.248882) (xy 96.42983 -273.204686) (xy 96.07423 -273.204686) (xy 96.07423 -273.248882)
			(xy 96.12122 -273.401282) (xy 96.38284 -273.401282)
		)
		(stroke
			(width 0)
			(type solid)
		)
		(fill yes)
		(layer "In11.Cu")
		(net "M_D_CPU1_SA_DQS_DP<2>")
	)
	(gr_poly
		(pts
			(xy 96.42983 -272.029174) (xy 96.38284 -271.876774) (xy 96.12122 -271.876774) (xy 96.07423 -272.029174)
			(xy 96.07423 -272.073624) (xy 96.42983 -272.073624)
		)
		(stroke
			(width 0)
			(type solid)
		)
		(fill yes)
		(layer "In11.Cu")
		(net "M_D_CPU1_SA_DQS_DP<7>")
	)
	(gr_poly
		(pts
			(xy 96.42983 -271.62125) (xy 96.42983 -271.5768) (xy 96.07423 -271.5768) (xy 96.07423 -271.62125)
			(xy 96.12122 -271.77365) (xy 96.38284 -271.77365)
		)
		(stroke
			(width 0)
			(type solid)
		)
		(fill yes)
		(layer "In11.Cu")
		(net "M_D_CPU1_SA_DQ<20>")
	)
	(gr_poly
		(pts
			(xy 96.42983 -269.993618) (xy 96.42983 -269.949168) (xy 96.07423 -269.949168) (xy 96.07423 -269.993618)
			(xy 96.12122 -270.146018) (xy 96.38284 -270.146018)
		)
		(stroke
			(width 0)
			(type solid)
		)
		(fill yes)
		(layer "In11.Cu")
		(net "M_D_CPU1_SA_DQ<24>")
	)
	(gr_poly
		(pts
			(xy 96.42983 -268.365478) (xy 96.42983 -268.321282) (xy 96.07423 -268.321282) (xy 96.07423 -268.365478)
			(xy 96.12122 -268.517878) (xy 96.38284 -268.517878)
		)
		(stroke
			(width 0)
			(type solid)
		)
		(fill yes)
		(layer "In11.Cu")
		(net "M_D_CPU1_SA_DQS_DP<3>")
	)
	(gr_poly
		(pts
			(xy 96.42983 -267.14577) (xy 96.38284 -266.99337) (xy 96.12122 -266.99337) (xy 96.07423 -267.14577)
			(xy 96.07423 -267.19022) (xy 96.42983 -267.19022)
		)
		(stroke
			(width 0)
			(type solid)
		)
		(fill yes)
		(layer "In11.Cu")
		(net "M_D_CPU1_SA_DQS_DP<8>")
	)
	(gr_poly
		(pts
			(xy 96.42983 -266.737846) (xy 96.42983 -266.69365) (xy 96.07423 -266.69365) (xy 96.07423 -266.737846)
			(xy 96.12122 -266.890246) (xy 96.38284 -266.890246)
		)
		(stroke
			(width 0)
			(type solid)
		)
		(fill yes)
		(layer "In11.Cu")
		(net "M_D_CPU1_SA_DQ<28>")
	)
	(gr_poly
		(pts
			(xy 96.42983 -265.518138) (xy 96.38284 -265.365738) (xy 96.12122 -265.365738) (xy 96.07423 -265.518138)
			(xy 96.07423 -265.562588) (xy 96.42983 -265.562588)
		)
		(stroke
			(width 0)
			(type solid)
		)
		(fill yes)
		(layer "In11.Cu")
		(net "M_D_CPU1_SA_DQ<31>")
	)
	(gr_poly
		(pts
			(xy 96.42983 -265.110214) (xy 96.42983 -265.065764) (xy 96.07423 -265.065764) (xy 96.07423 -265.110214)
			(xy 96.12122 -265.262614) (xy 96.38284 -265.262614)
		)
		(stroke
			(width 0)
			(type solid)
		)
		(fill yes)
		(layer "In11.Cu")
		(net "M_D_CPU1_SA_CB<0>")
	)
	(gr_poly
		(pts
			(xy 96.42983 -263.890506) (xy 96.38284 -263.738106) (xy 96.12122 -263.738106) (xy 96.07423 -263.890506)
			(xy 96.07423 -263.934956) (xy 96.42983 -263.934956)
		)
		(stroke
			(width 0)
			(type solid)
		)
		(fill yes)
		(layer "In11.Cu")
		(net "M_D_CPU1_SA_CB<3>")
	)
	(gr_poly
		(pts
			(xy 96.42983 -263.482582) (xy 96.42983 -263.438132) (xy 96.07423 -263.438132) (xy 96.07423 -263.482582)
			(xy 96.12122 -263.634982) (xy 96.38284 -263.634982)
		)
		(stroke
			(width 0)
			(type solid)
		)
		(fill yes)
		(layer "In11.Cu")
		(net "M_D_CPU1_SA_DQS_DP<4>")
	)
	(gr_poly
		(pts
			(xy 96.42983 -261.854442) (xy 96.42983 -261.810246) (xy 96.07423 -261.810246) (xy 96.07423 -261.854442)
			(xy 96.12122 -262.006842) (xy 96.38284 -262.006842)
		)
		(stroke
			(width 0)
			(type solid)
		)
		(fill yes)
		(layer "In11.Cu")
		(net "M_D_CPU1_SA_CB<4>")
	)
	(gr_poly
		(pts
			(xy 96.42983 -259.007102) (xy 96.38284 -258.854702) (xy 96.12122 -258.854702) (xy 96.07423 -259.007102)
			(xy 96.07423 -259.051552) (xy 96.42983 -259.051552)
		)
		(stroke
			(width 0)
			(type solid)
		)
		(fill yes)
		(layer "In11.Cu")
		(net "M_D_CPU1_SA_CS_N<0>")
	)
	(gr_poly
		(pts
			(xy 96.42983 -258.599178) (xy 96.42983 -258.554728) (xy 96.07423 -258.554728) (xy 96.07423 -258.599178)
			(xy 96.12122 -258.751578) (xy 96.38284 -258.751578)
		)
		(stroke
			(width 0)
			(type solid)
		)
		(fill yes)
		(layer "In11.Cu")
		(net "M_D_CPU1_SA_CS_N<3>")
	)
	(gr_poly
		(pts
			(xy 96.42983 -257.37947) (xy 96.38284 -257.22707) (xy 96.12122 -257.22707) (xy 96.07423 -257.37947)
			(xy 96.07423 -257.423666) (xy 96.42983 -257.423666)
		)
		(stroke
			(width 0)
			(type solid)
		)
		(fill yes)
		(layer "In11.Cu")
		(net "M_D_CPU1_SA_CA<1>")
	)
	(gr_poly
		(pts
			(xy 96.42983 -256.971038) (xy 96.42983 -256.926842) (xy 96.07423 -256.926842) (xy 96.07423 -256.971038)
			(xy 96.12122 -257.123438) (xy 96.38284 -257.123438)
		)
		(stroke
			(width 0)
			(type solid)
		)
		(fill yes)
		(layer "In11.Cu")
		(net "M_D_CPU1_SA_CA<2>")
	)
	(gr_poly
		(pts
			(xy 96.42983 -255.751838) (xy 96.38284 -255.599438) (xy 96.12122 -255.599438) (xy 96.07423 -255.751838)
			(xy 96.07423 -255.796034) (xy 96.42983 -255.796034)
		)
		(stroke
			(width 0)
			(type solid)
		)
		(fill yes)
		(layer "In11.Cu")
		(net "M_D_CPU1_SA_CA<5>")
	)
	(gr_poly
		(pts
			(xy 96.630744 -230.53929) (xy 96.669098 -230.517192) (xy 96.491298 -230.209344) (xy 96.452944 -230.231442)
			(xy 96.344486 -230.348282) (xy 96.475296 -230.57485)
		)
		(stroke
			(width 0)
			(type solid)
		)
		(fill yes)
		(layer "In11.Cu")
		(net "M_D_CPU1_SB_DQ<25>")
	)
	(gr_poly
		(pts
			(xy 96.632522 -232.170224) (xy 96.670876 -232.148126) (xy 96.493076 -231.840278) (xy 96.454722 -231.862376)
			(xy 96.346264 -231.979216) (xy 96.477074 -232.205784)
		)
		(stroke
			(width 0)
			(type solid)
		)
		(fill yes)
		(layer "In11.Cu")
		(net "M_D_CPU1_SB_DQ<24>")
	)
	(gr_poly
		(pts
			(xy 96.632522 -228.914706) (xy 96.670876 -228.892608) (xy 96.493076 -228.58476) (xy 96.454722 -228.606858)
			(xy 96.346264 -228.723698) (xy 96.477074 -228.950266)
		)
		(stroke
			(width 0)
			(type solid)
		)
		(fill yes)
		(layer "In11.Cu")
		(net "M_D_CPU1_SB_DQS_DP<3>")
	)
	(gr_poly
		(pts
			(xy 96.74479 -231.555544) (xy 96.853248 -231.438704) (xy 96.722438 -231.212136) (xy 96.56699 -231.247696)
			(xy 96.528636 -231.269794) (xy 96.706436 -231.577642)
		)
		(stroke
			(width 0)
			(type solid)
		)
		(fill yes)
		(layer "In11.Cu")
		(net "M_D_CPU1_SB_DQ<26>")
	)
	(gr_poly
		(pts
			(xy 96.74479 -228.300026) (xy 96.853248 -228.183186) (xy 96.722438 -227.956618) (xy 96.56699 -227.992178)
			(xy 96.528636 -228.014276) (xy 96.706436 -228.322124)
		)
		(stroke
			(width 0)
			(type solid)
		)
		(fill yes)
		(layer "In11.Cu")
		(net "M_D_CPU1_SB_DQS_DN<3>")
	)
	(gr_poly
		(pts
			(xy 96.752156 -229.939088) (xy 96.860614 -229.822248) (xy 96.729804 -229.59568) (xy 96.574356 -229.63124)
			(xy 96.536002 -229.653338) (xy 96.713802 -229.961186)
		)
		(stroke
			(width 0)
			(type solid)
		)
		(fill yes)
		(layer "In11.Cu")
		(net "M_D_CPU1_SB_DQ<27>")
	)
	(gr_poly
		(pts
			(xy 96.77273 -246.16029) (xy 96.77273 -246.116094) (xy 96.41713 -246.116094) (xy 96.41713 -246.16029)
			(xy 96.46412 -246.31269) (xy 96.72574 -246.31269)
		)
		(stroke
			(width 0)
			(type solid)
		)
		(fill yes)
		(layer "In11.Cu")
		(net "M_D_CPU1_SB_CB<5>")
	)
	(gr_poly
		(pts
			(xy 96.77273 -243.31295) (xy 96.72574 -243.16055) (xy 96.46412 -243.16055) (xy 96.41713 -243.31295)
			(xy 96.41713 -243.3574) (xy 96.77273 -243.3574)
		)
		(stroke
			(width 0)
			(type solid)
		)
		(fill yes)
		(layer "In11.Cu")
		(net "M_D_CPU1_SB_CB<2>")
	)
	(gr_poly
		(pts
			(xy 96.77273 -242.905026) (xy 96.77273 -242.860576) (xy 96.41713 -242.860576) (xy 96.41713 -242.905026)
			(xy 96.46412 -243.057426) (xy 96.72574 -243.057426)
		)
		(stroke
			(width 0)
			(type solid)
		)
		(fill yes)
		(layer "In11.Cu")
		(net "M_D_CPU1_SB_CB<1>")
	)
	(gr_poly
		(pts
			(xy 96.77273 -241.685318) (xy 96.72574 -241.532918) (xy 96.46412 -241.532918) (xy 96.41713 -241.685318)
			(xy 96.41713 -241.729514) (xy 96.77273 -241.729514)
		)
		(stroke
			(width 0)
			(type solid)
		)
		(fill yes)
		(layer "In11.Cu")
		(net "M_D_CPU1_SB_DQ<2>")
	)
	(gr_poly
		(pts
			(xy 96.77273 -241.276886) (xy 96.77273 -241.23269) (xy 96.41713 -241.23269) (xy 96.41713 -241.276886)
			(xy 96.46412 -241.429286) (xy 96.72574 -241.429286)
		)
		(stroke
			(width 0)
			(type solid)
		)
		(fill yes)
		(layer "In11.Cu")
		(net "M_D_CPU1_SB_DQ<1>")
	)
	(gr_poly
		(pts
			(xy 96.77273 -238.429546) (xy 96.72574 -238.277146) (xy 96.46412 -238.277146) (xy 96.41713 -238.429546)
			(xy 96.41713 -238.473996) (xy 96.77273 -238.473996)
		)
		(stroke
			(width 0)
			(type solid)
		)
		(fill yes)
		(layer "In11.Cu")
		(net "M_D_CPU1_SB_DQ<6>")
	)
	(gr_poly
		(pts
			(xy 96.77273 -238.021622) (xy 96.77273 -237.977172) (xy 96.41713 -237.977172) (xy 96.41713 -238.021622)
			(xy 96.46412 -238.174022) (xy 96.72574 -238.174022)
		)
		(stroke
			(width 0)
			(type solid)
		)
		(fill yes)
		(layer "In11.Cu")
		(net "M_D_CPU1_SB_DQ<5>")
	)
	(gr_poly
		(pts
			(xy 96.77273 -236.801914) (xy 96.72574 -236.649514) (xy 96.46412 -236.649514) (xy 96.41713 -236.801914)
			(xy 96.41713 -236.84611) (xy 96.77273 -236.84611)
		)
		(stroke
			(width 0)
			(type solid)
		)
		(fill yes)
		(layer "In11.Cu")
		(net "M_D_CPU1_SB_DQ<10>")
	)
	(gr_poly
		(pts
			(xy 96.77273 -236.39399) (xy 96.77273 -236.34954) (xy 96.41713 -236.34954) (xy 96.41713 -236.39399)
			(xy 96.46412 -236.54639) (xy 96.72574 -236.54639)
		)
		(stroke
			(width 0)
			(type solid)
		)
		(fill yes)
		(layer "In11.Cu")
		(net "M_D_CPU1_SB_DQ<9>")
	)
	(gr_poly
		(pts
			(xy 96.77273 -233.546142) (xy 96.72574 -233.393742) (xy 96.46412 -233.393742) (xy 96.41713 -233.546142)
			(xy 96.41713 -233.590592) (xy 96.77273 -233.590592)
		)
		(stroke
			(width 0)
			(type solid)
		)
		(fill yes)
		(layer "In11.Cu")
		(net "M_D_CPU1_SB_DQ<14>")
	)
	(gr_poly
		(pts
			(xy 96.77273 -233.138218) (xy 96.77273 -233.093768) (xy 96.41713 -233.093768) (xy 96.41713 -233.138218)
			(xy 96.46412 -233.290618) (xy 96.72574 -233.290618)
		)
		(stroke
			(width 0)
			(type solid)
		)
		(fill yes)
		(layer "In11.Cu")
		(net "M_D_CPU1_SB_DQ<13>")
	)
	(gr_poly
		(pts
			(xy 96.77273 -225.407474) (xy 96.72574 -225.255074) (xy 96.46412 -225.255074) (xy 96.41713 -225.407474)
			(xy 96.41713 -225.45167) (xy 96.77273 -225.45167)
		)
		(stroke
			(width 0)
			(type solid)
		)
		(fill yes)
		(layer "In11.Cu")
		(net "M_D_CPU1_SB_DQ<31>")
	)
	(gr_poly
		(pts
			(xy 96.77527 -244.940582) (xy 96.72828 -244.788182) (xy 96.46666 -244.788182) (xy 96.41967 -244.940582)
			(xy 96.41967 -244.985032) (xy 96.77527 -244.985032)
		)
		(stroke
			(width 0)
			(type solid)
		)
		(fill yes)
		(layer "In11.Cu")
		(net "M_D_CPU1_SB_DQS_DN<9>")
	)
	(gr_poly
		(pts
			(xy 96.77527 -244.532658) (xy 96.77527 -244.488208) (xy 96.41967 -244.488208) (xy 96.41967 -244.532658)
			(xy 96.46666 -244.685058) (xy 96.72828 -244.685058)
		)
		(stroke
			(width 0)
			(type solid)
		)
		(fill yes)
		(layer "In11.Cu")
		(net "M_D_CPU1_SB_DQS_DN<4>")
	)
	(gr_poly
		(pts
			(xy 96.77527 -240.057178) (xy 96.72828 -239.904778) (xy 96.46666 -239.904778) (xy 96.41967 -240.057178)
			(xy 96.41967 -240.101628) (xy 96.77527 -240.101628)
		)
		(stroke
			(width 0)
			(type solid)
		)
		(fill yes)
		(layer "In11.Cu")
		(net "M_D_CPU1_SB_DQS_DN<0>")
	)
	(gr_poly
		(pts
			(xy 96.77527 -239.649254) (xy 96.77527 -239.604804) (xy 96.41967 -239.604804) (xy 96.41967 -239.649254)
			(xy 96.46666 -239.801654) (xy 96.72828 -239.801654)
		)
		(stroke
			(width 0)
			(type solid)
		)
		(fill yes)
		(layer "In11.Cu")
		(net "M_D_CPU1_SB_DQS_DN<5>")
	)
	(gr_poly
		(pts
			(xy 96.77527 -235.174282) (xy 96.72828 -235.021882) (xy 96.46666 -235.021882) (xy 96.41967 -235.174282)
			(xy 96.41967 -235.218478) (xy 96.77527 -235.218478)
		)
		(stroke
			(width 0)
			(type solid)
		)
		(fill yes)
		(layer "In11.Cu")
		(net "M_D_CPU1_SB_DQS_DN<1>")
	)
	(gr_poly
		(pts
			(xy 96.77527 -234.76585) (xy 96.77527 -234.721654) (xy 96.41967 -234.721654) (xy 96.41967 -234.76585)
			(xy 96.46666 -234.91825) (xy 96.72828 -234.91825)
		)
		(stroke
			(width 0)
			(type solid)
		)
		(fill yes)
		(layer "In11.Cu")
		(net "M_D_CPU1_SB_DQS_DN<6>")
	)
	(gr_poly
		(pts
			(xy 96.77527 -227.035614) (xy 96.72828 -226.883214) (xy 96.46666 -226.883214) (xy 96.41967 -227.035614)
			(xy 96.41967 -227.07981) (xy 96.77527 -227.07981)
		)
		(stroke
			(width 0)
			(type solid)
		)
		(fill yes)
		(layer "In11.Cu")
		(net "M_D_CPU1_SB_DQS_DP<8>")
	)
	(gr_poly
		(pts
			(xy 96.77527 -226.626674) (xy 96.77527 -226.582478) (xy 96.41967 -226.582478) (xy 96.41967 -226.626674)
			(xy 96.46666 -226.779074) (xy 96.72828 -226.779074)
		)
		(stroke
			(width 0)
			(type solid)
		)
		(fill yes)
		(layer "In11.Cu")
		(net "M_D_CPU1_SB_DQ<28>")
	)
	(gr_poly
		(pts
			(xy 96.781112 -246.568722) (xy 96.734122 -246.416322) (xy 96.472502 -246.416322) (xy 96.425512 -246.568722)
			(xy 96.425512 -246.613172) (xy 96.781112 -246.613172)
		)
		(stroke
			(width 0)
			(type solid)
		)
		(fill yes)
		(layer "In11.Cu")
		(net "M_D_CPU1_SB_CB<6>")
	)
	(gr_poly
		(pts
			(xy 96.787208 -247.787922) (xy 96.787208 -247.743472) (xy 96.431608 -247.743472) (xy 96.431608 -247.787922)
			(xy 96.478598 -247.940322) (xy 96.740218 -247.940322)
		)
		(stroke
			(width 0)
			(type solid)
		)
		(fill yes)
		(layer "In11.Cu")
		(net "M_D_CPU1_SB_CA<5>")
	)
	(gr_poly
		(pts
			(xy 96.882712 -279.354534) (xy 96.835722 -279.202134) (xy 96.574102 -279.202134) (xy 96.527112 -279.354534)
			(xy 96.527112 -279.39873) (xy 96.882712 -279.39873)
		)
		(stroke
			(width 0)
			(type solid)
		)
		(fill yes)
		(layer "In11.Cu")
		(net "M_D_CPU1_SA_DQ<10>")
	)
	(gr_poly
		(pts
			(xy 96.882712 -278.946102) (xy 96.882712 -278.901906) (xy 96.527112 -278.901906) (xy 96.527112 -278.946102)
			(xy 96.574102 -279.098502) (xy 96.835722 -279.098502)
		)
		(stroke
			(width 0)
			(type solid)
		)
		(fill yes)
		(layer "In11.Cu")
		(net "M_D_CPU1_SA_DQ<9>")
	)
	(gr_poly
		(pts
			(xy 96.882712 -277.726394) (xy 96.835722 -277.573994) (xy 96.574102 -277.573994) (xy 96.527112 -277.726394)
			(xy 96.527112 -277.770844) (xy 96.882712 -277.770844)
		)
		(stroke
			(width 0)
			(type solid)
		)
		(fill yes)
		(layer "In11.Cu")
		(net "M_D_CPU1_SA_DQS_DN<1>")
	)
	(gr_poly
		(pts
			(xy 96.882712 -277.318216) (xy 96.882712 -277.27402) (xy 96.527112 -277.27402) (xy 96.527112 -277.318216)
			(xy 96.574102 -277.470616) (xy 96.835722 -277.470616)
		)
		(stroke
			(width 0)
			(type solid)
		)
		(fill yes)
		(layer "In11.Cu")
		(net "M_D_CPU1_SA_DQS_DN<6>")
	)
	(gr_poly
		(pts
			(xy 96.882712 -276.098762) (xy 96.835722 -275.946362) (xy 96.574102 -275.946362) (xy 96.527112 -276.098762)
			(xy 96.527112 -276.143212) (xy 96.882712 -276.143212)
		)
		(stroke
			(width 0)
			(type solid)
		)
		(fill yes)
		(layer "In11.Cu")
		(net "M_D_CPU1_SA_DQ<14>")
	)
	(gr_poly
		(pts
			(xy 96.882712 -275.690584) (xy 96.882712 -275.646388) (xy 96.527112 -275.646388) (xy 96.527112 -275.690584)
			(xy 96.574102 -275.842984) (xy 96.835722 -275.842984)
		)
		(stroke
			(width 0)
			(type solid)
		)
		(fill yes)
		(layer "In11.Cu")
		(net "M_D_CPU1_SA_DQ<13>")
	)
	(gr_poly
		(pts
			(xy 96.882712 -274.47113) (xy 96.835722 -274.31873) (xy 96.574102 -274.31873) (xy 96.527112 -274.47113)
			(xy 96.527112 -274.515326) (xy 96.882712 -274.515326)
		)
		(stroke
			(width 0)
			(type solid)
		)
		(fill yes)
		(layer "In11.Cu")
		(net "M_D_CPU1_SA_DQ<18>")
	)
	(gr_poly
		(pts
			(xy 96.882712 -274.062698) (xy 96.882712 -274.018502) (xy 96.527112 -274.018502) (xy 96.527112 -274.062698)
			(xy 96.574102 -274.215098) (xy 96.835722 -274.215098)
		)
		(stroke
			(width 0)
			(type solid)
		)
		(fill yes)
		(layer "In11.Cu")
		(net "M_D_CPU1_SA_DQ<17>")
	)
	(gr_poly
		(pts
			(xy 96.882712 -269.587726) (xy 96.835722 -269.435326) (xy 96.574102 -269.435326) (xy 96.527112 -269.587726)
			(xy 96.527112 -269.631922) (xy 96.882712 -269.631922)
		)
		(stroke
			(width 0)
			(type solid)
		)
		(fill yes)
		(layer "In11.Cu")
		(net "M_D_CPU1_SA_DQ<26>")
	)
	(gr_poly
		(pts
			(xy 96.882712 -266.331954) (xy 96.835722 -266.179554) (xy 96.574102 -266.179554) (xy 96.527112 -266.331954)
			(xy 96.527112 -266.376404) (xy 96.882712 -266.376404)
		)
		(stroke
			(width 0)
			(type solid)
		)
		(fill yes)
		(layer "In11.Cu")
		(net "M_D_CPU1_SA_DQ<30>")
	)
	(gr_poly
		(pts
			(xy 96.882712 -265.92403) (xy 96.882712 -265.87958) (xy 96.527112 -265.87958) (xy 96.527112 -265.92403)
			(xy 96.574102 -266.07643) (xy 96.835722 -266.07643)
		)
		(stroke
			(width 0)
			(type solid)
		)
		(fill yes)
		(layer "In11.Cu")
		(net "M_D_CPU1_SA_DQ<29>")
	)
	(gr_poly
		(pts
			(xy 96.882712 -264.704322) (xy 96.835722 -264.551922) (xy 96.574102 -264.551922) (xy 96.527112 -264.704322)
			(xy 96.527112 -264.748772) (xy 96.882712 -264.748772)
		)
		(stroke
			(width 0)
			(type solid)
		)
		(fill yes)
		(layer "In11.Cu")
		(net "M_D_CPU1_SA_CB<2>")
	)
	(gr_poly
		(pts
			(xy 96.882712 -264.296398) (xy 96.882712 -264.251948) (xy 96.527112 -264.251948) (xy 96.527112 -264.296398)
			(xy 96.574102 -264.448798) (xy 96.835722 -264.448798)
		)
		(stroke
			(width 0)
			(type solid)
		)
		(fill yes)
		(layer "In11.Cu")
		(net "M_D_CPU1_SA_CB<1>")
	)
	(gr_poly
		(pts
			(xy 96.882712 -261.449058) (xy 96.835722 -261.296658) (xy 96.574102 -261.296658) (xy 96.527112 -261.449058)
			(xy 96.527112 -261.493254) (xy 96.882712 -261.493254)
		)
		(stroke
			(width 0)
			(type solid)
		)
		(fill yes)
		(layer "In11.Cu")
		(net "M_D_CPU1_SA_CB<6>")
	)
	(gr_poly
		(pts
			(xy 96.882712 -259.412994) (xy 96.882712 -259.368544) (xy 96.527112 -259.368544) (xy 96.527112 -259.412994)
			(xy 96.574102 -259.565394) (xy 96.835722 -259.565394)
		)
		(stroke
			(width 0)
			(type solid)
		)
		(fill yes)
		(layer "In11.Cu")
		(net "M_D_CPU1_SA_CS_N<2>")
	)
	(gr_poly
		(pts
			(xy 96.882712 -256.565654) (xy 96.835722 -256.413254) (xy 96.574102 -256.413254) (xy 96.527112 -256.565654)
			(xy 96.527112 -256.60985) (xy 96.882712 -256.60985)
		)
		(stroke
			(width 0)
			(type solid)
		)
		(fill yes)
		(layer "In11.Cu")
		(net "M_D_CPU1_SA_CA<3>")
	)
	(gr_poly
		(pts
			(xy 96.882712 -256.157222) (xy 96.882712 -256.113026) (xy 96.527112 -256.113026) (xy 96.527112 -256.157222)
			(xy 96.574102 -256.309622) (xy 96.835722 -256.309622)
		)
		(stroke
			(width 0)
			(type solid)
		)
		(fill yes)
		(layer "In11.Cu")
		(net "M_D_CPU1_SA_CA<4>")
	)
	(gr_poly
		(pts
			(xy 96.885252 -272.843498) (xy 96.838262 -272.691098) (xy 96.576642 -272.691098) (xy 96.529652 -272.843498)
			(xy 96.529652 -272.887694) (xy 96.885252 -272.887694)
		)
		(stroke
			(width 0)
			(type solid)
		)
		(fill yes)
		(layer "In11.Cu")
		(net "M_D_CPU1_SA_DQS_DN<2>")
	)
	(gr_poly
		(pts
			(xy 96.885252 -272.435066) (xy 96.885252 -272.39087) (xy 96.529652 -272.39087) (xy 96.529652 -272.435066)
			(xy 96.576642 -272.587466) (xy 96.838262 -272.587466)
		)
		(stroke
			(width 0)
			(type solid)
		)
		(fill yes)
		(layer "In11.Cu")
		(net "M_D_CPU1_SA_DQS_DN<7>")
	)
	(gr_poly
		(pts
			(xy 96.885252 -267.960094) (xy 96.838262 -267.807694) (xy 96.576642 -267.807694) (xy 96.529652 -267.960094)
			(xy 96.529652 -268.00429) (xy 96.885252 -268.00429)
		)
		(stroke
			(width 0)
			(type solid)
		)
		(fill yes)
		(layer "In11.Cu")
		(net "M_D_CPU1_SA_DQS_DN<3>")
	)
	(gr_poly
		(pts
			(xy 96.885252 -267.551662) (xy 96.885252 -267.507466) (xy 96.529652 -267.507466) (xy 96.529652 -267.551662)
			(xy 96.576642 -267.704062) (xy 96.838262 -267.704062)
		)
		(stroke
			(width 0)
			(type solid)
		)
		(fill yes)
		(layer "In11.Cu")
		(net "M_D_CPU1_SA_DQS_DN<8>")
	)
	(gr_poly
		(pts
			(xy 96.885252 -263.07669) (xy 96.838262 -262.92429) (xy 96.576642 -262.92429) (xy 96.529652 -263.07669)
			(xy 96.529652 -263.120886) (xy 96.885252 -263.120886)
		)
		(stroke
			(width 0)
			(type solid)
		)
		(fill yes)
		(layer "In11.Cu")
		(net "M_D_CPU1_SA_DQS_DN<4>")
	)
	(gr_poly
		(pts
			(xy 96.885252 -258.193286) (xy 96.838262 -258.040886) (xy 96.576642 -258.040886) (xy 96.529652 -258.193286)
			(xy 96.529652 -258.237482) (xy 96.885252 -258.237482)
		)
		(stroke
			(width 0)
			(type solid)
		)
		(fill yes)
		(layer "In11.Cu")
		(net "M_D_CPU1_SA_CS_N<1>")
	)
	(gr_poly
		(pts
			(xy 96.885252 -257.784854) (xy 96.885252 -257.740658) (xy 96.529652 -257.740658) (xy 96.529652 -257.784854)
			(xy 96.576642 -257.937254) (xy 96.838262 -257.937254)
		)
		(stroke
			(width 0)
			(type solid)
		)
		(fill yes)
		(layer "In11.Cu")
		(net "M_D_CPU1_SA_CA<0>")
	)
	(gr_poly
		(pts
			(xy 96.891602 -271.215866) (xy 96.844612 -271.063466) (xy 96.582992 -271.063466) (xy 96.536002 -271.215866)
			(xy 96.536002 -271.260316) (xy 96.891602 -271.260316)
		)
		(stroke
			(width 0)
			(type solid)
		)
		(fill yes)
		(layer "In11.Cu")
		(net "M_D_CPU1_SA_DQ<22>")
	)
	(gr_poly
		(pts
			(xy 96.89465 -270.806926) (xy 96.89465 -270.76273) (xy 96.53905 -270.76273) (xy 96.53905 -270.806926)
			(xy 96.58604 -270.959326) (xy 96.84766 -270.959326)
		)
		(stroke
			(width 0)
			(type solid)
		)
		(fill yes)
		(layer "In11.Cu")
		(net "M_D_CPU1_SA_DQ<21>")
	)
	(gr_poly
		(pts
			(xy 96.89465 -269.179294) (xy 96.89465 -269.134844) (xy 96.53905 -269.134844) (xy 96.53905 -269.179294)
			(xy 96.58604 -269.331694) (xy 96.84766 -269.331694)
		)
		(stroke
			(width 0)
			(type solid)
		)
		(fill yes)
		(layer "In11.Cu")
		(net "M_D_CPU1_SA_DQ<25>")
	)
	(gr_poly
		(pts
			(xy 96.89465 -262.668258) (xy 96.89465 -262.623808) (xy 96.53905 -262.623808) (xy 96.53905 -262.668258)
			(xy 96.58604 -262.820658) (xy 96.84766 -262.820658)
		)
		(stroke
			(width 0)
			(type solid)
		)
		(fill yes)
		(layer "In11.Cu")
		(net "M_D_CPU1_SA_DQS_DN<9>")
	)
	(gr_poly
		(pts
			(xy 96.899476 -261.040626) (xy 96.899476 -260.99643) (xy 96.543876 -260.99643) (xy 96.543876 -261.040626)
			(xy 96.590866 -261.193026) (xy 96.852486 -261.193026)
		)
		(stroke
			(width 0)
			(type solid)
		)
		(fill yes)
		(layer "In11.Cu")
		(net "M_D_CPU1_SA_CB<5>")
	)
	(gr_poly
		(pts
			(xy 97.222056 -229.125018) (xy 97.330514 -229.008178) (xy 97.199704 -228.78161) (xy 97.044256 -228.81717)
			(xy 97.005902 -228.839268) (xy 97.183702 -229.147116)
		)
		(stroke
			(width 0)
			(type solid)
		)
		(fill yes)
		(layer "In11.Cu")
		(net "M_D_CPU1_SB_DQS_DN<3>")
	)
	(gr_poly
		(pts
			(xy 97.242884 -245.346474) (xy 97.242884 -245.302024) (xy 96.887284 -245.302024) (xy 96.887284 -245.346474)
			(xy 96.934274 -245.498874) (xy 97.195894 -245.498874)
		)
		(stroke
			(width 0)
			(type solid)
		)
		(fill yes)
		(layer "In11.Cu")
		(net "M_D_CPU1_SB_DQS_DP<9>")
	)
	(gr_poly
		(pts
			(xy 97.242884 -240.46307) (xy 97.242884 -240.41862) (xy 96.887284 -240.41862) (xy 96.887284 -240.46307)
			(xy 96.934274 -240.61547) (xy 97.195894 -240.61547)
		)
		(stroke
			(width 0)
			(type solid)
		)
		(fill yes)
		(layer "In11.Cu")
		(net "M_D_CPU1_SB_DQS_DP<0>")
	)
	(gr_poly
		(pts
			(xy 97.242884 -235.579666) (xy 97.242884 -235.53547) (xy 96.887284 -235.53547) (xy 96.887284 -235.579666)
			(xy 96.934274 -235.732066) (xy 97.195894 -235.732066)
		)
		(stroke
			(width 0)
			(type solid)
		)
		(fill yes)
		(layer "In11.Cu")
		(net "M_D_CPU1_SB_DQS_DP<1>")
	)
	(gr_poly
		(pts
			(xy 97.251266 -244.127274) (xy 97.204276 -243.974874) (xy 96.942656 -243.974874) (xy 96.895666 -244.127274)
			(xy 96.895666 -244.17147) (xy 97.251266 -244.17147)
		)
		(stroke
			(width 0)
			(type solid)
		)
		(fill yes)
		(layer "In11.Cu")
		(net "M_D_CPU1_SB_DQS_DP<4>")
	)
	(gr_poly
		(pts
			(xy 97.251266 -239.24387) (xy 97.204276 -239.09147) (xy 96.942656 -239.09147) (xy 96.895666 -239.24387)
			(xy 96.895666 -239.288066) (xy 97.251266 -239.288066)
		)
		(stroke
			(width 0)
			(type solid)
		)
		(fill yes)
		(layer "In11.Cu")
		(net "M_D_CPU1_SB_DQS_DP<5>")
	)
	(gr_poly
		(pts
			(xy 97.251266 -234.360466) (xy 97.204276 -234.208066) (xy 96.942656 -234.208066) (xy 96.895666 -234.360466)
			(xy 96.895666 -234.404916) (xy 97.251266 -234.404916)
		)
		(stroke
			(width 0)
			(type solid)
		)
		(fill yes)
		(layer "In11.Cu")
		(net "M_D_CPU1_SB_DQS_DP<6>")
	)
	(gr_poly
		(pts
			(xy 97.257108 -246.974106) (xy 97.257108 -246.92991) (xy 96.901508 -246.92991) (xy 96.901508 -246.974106)
			(xy 96.948498 -247.126506) (xy 97.210118 -247.126506)
		)
		(stroke
			(width 0)
			(type solid)
		)
		(fill yes)
		(layer "In11.Cu")
		(net "M_D_CPU1_SB_CB<4>")
	)
	(gr_poly
		(pts
			(xy 97.257108 -245.754906) (xy 97.210118 -245.602506) (xy 96.948498 -245.602506) (xy 96.901508 -245.754906)
			(xy 96.901508 -245.799356) (xy 97.257108 -245.799356)
		)
		(stroke
			(width 0)
			(type solid)
		)
		(fill yes)
		(layer "In11.Cu")
		(net "M_D_CPU1_SB_CB<7>")
	)
	(gr_poly
		(pts
			(xy 97.257108 -240.871502) (xy 97.210118 -240.719102) (xy 96.948498 -240.719102) (xy 96.901508 -240.871502)
			(xy 96.901508 -240.915952) (xy 97.257108 -240.915952)
		)
		(stroke
			(width 0)
			(type solid)
		)
		(fill yes)
		(layer "In11.Cu")
		(net "M_D_CPU1_SB_DQ<3>")
	)
	(gr_poly
		(pts
			(xy 97.257108 -235.988098) (xy 97.210118 -235.835698) (xy 96.948498 -235.835698) (xy 96.901508 -235.988098)
			(xy 96.901508 -236.032548) (xy 97.257108 -236.032548)
		)
		(stroke
			(width 0)
			(type solid)
		)
		(fill yes)
		(layer "In11.Cu")
		(net "M_D_CPU1_SB_DQ<11>")
	)
	(gr_poly
		(pts
			(xy 97.259648 -243.718842) (xy 97.259648 -243.674392) (xy 96.904048 -243.674392) (xy 96.904048 -243.718842)
			(xy 96.951038 -243.871242) (xy 97.212658 -243.871242)
		)
		(stroke
			(width 0)
			(type solid)
		)
		(fill yes)
		(layer "In11.Cu")
		(net "M_D_CPU1_SB_CB<0>")
	)
	(gr_poly
		(pts
			(xy 97.259648 -242.499134) (xy 97.212658 -242.346734) (xy 96.951038 -242.346734) (xy 96.904048 -242.499134)
			(xy 96.904048 -242.54333) (xy 97.259648 -242.54333)
		)
		(stroke
			(width 0)
			(type solid)
		)
		(fill yes)
		(layer "In11.Cu")
		(net "M_D_CPU1_SB_CB<3>")
	)
	(gr_poly
		(pts
			(xy 97.259648 -242.090702) (xy 97.259648 -242.046506) (xy 96.904048 -242.046506) (xy 96.904048 -242.090702)
			(xy 96.951038 -242.243102) (xy 97.212658 -242.243102)
		)
		(stroke
			(width 0)
			(type solid)
		)
		(fill yes)
		(layer "In11.Cu")
		(net "M_D_CPU1_SB_DQ<0>")
	)
	(gr_poly
		(pts
			(xy 97.259648 -238.835438) (xy 97.259648 -238.790988) (xy 96.904048 -238.790988) (xy 96.904048 -238.835438)
			(xy 96.951038 -238.987838) (xy 97.212658 -238.987838)
		)
		(stroke
			(width 0)
			(type solid)
		)
		(fill yes)
		(layer "In11.Cu")
		(net "M_D_CPU1_SB_DQ<4>")
	)
	(gr_poly
		(pts
			(xy 97.259648 -237.61573) (xy 97.212658 -237.46333) (xy 96.951038 -237.46333) (xy 96.904048 -237.61573)
			(xy 96.904048 -237.66018) (xy 97.259648 -237.66018)
		)
		(stroke
			(width 0)
			(type solid)
		)
		(fill yes)
		(layer "In11.Cu")
		(net "M_D_CPU1_SB_DQ<7>")
	)
	(gr_poly
		(pts
			(xy 97.259648 -237.207806) (xy 97.259648 -237.163356) (xy 96.904048 -237.163356) (xy 96.904048 -237.207806)
			(xy 96.951038 -237.360206) (xy 97.212658 -237.360206)
		)
		(stroke
			(width 0)
			(type solid)
		)
		(fill yes)
		(layer "In11.Cu")
		(net "M_D_CPU1_SB_DQ<8>")
	)
	(gr_poly
		(pts
			(xy 97.259648 -233.952034) (xy 97.259648 -233.907838) (xy 96.904048 -233.907838) (xy 96.904048 -233.952034)
			(xy 96.951038 -234.104434) (xy 97.212658 -234.104434)
		)
		(stroke
			(width 0)
			(type solid)
		)
		(fill yes)
		(layer "In11.Cu")
		(net "M_D_CPU1_SB_DQ<12>")
	)
	(gr_poly
		(pts
			(xy 97.259648 -232.732326) (xy 97.212658 -232.579926) (xy 96.951038 -232.579926) (xy 96.904048 -232.732326)
			(xy 96.904048 -232.776776) (xy 97.259648 -232.776776)
		)
		(stroke
			(width 0)
			(type solid)
		)
		(fill yes)
		(layer "In11.Cu")
		(net "M_D_CPU1_SB_DQ<15>")
	)
	(gr_poly
		(pts
			(xy 97.259648 -232.324402) (xy 97.259648 -232.279952) (xy 96.904048 -232.279952) (xy 96.904048 -232.324402)
			(xy 96.951038 -232.476802) (xy 97.212658 -232.476802)
		)
		(stroke
			(width 0)
			(type solid)
		)
		(fill yes)
		(layer "In11.Cu")
		(net "M_D_CPU1_SB_DQ<24>")
	)
	(gr_poly
		(pts
			(xy 97.259648 -227.440998) (xy 97.259648 -227.396548) (xy 96.904048 -227.396548) (xy 96.904048 -227.440998)
			(xy 96.951038 -227.593398) (xy 97.212658 -227.593398)
		)
		(stroke
			(width 0)
			(type solid)
		)
		(fill yes)
		(layer "In11.Cu")
		(net "M_D_CPU1_SB_DQS_DN<8>")
	)
	(gr_poly
		(pts
			(xy 97.259648 -226.22129) (xy 97.212658 -226.06889) (xy 96.951038 -226.06889) (xy 96.904048 -226.22129)
			(xy 96.904048 -226.26574) (xy 97.259648 -226.26574)
		)
		(stroke
			(width 0)
			(type solid)
		)
		(fill yes)
		(layer "In11.Cu")
		(net "M_D_CPU1_SB_DQ<30>")
	)
	(gr_poly
		(pts
			(xy 97.259648 -225.813366) (xy 97.259648 -225.768916) (xy 96.904048 -225.768916) (xy 96.904048 -225.813366)
			(xy 96.951038 -225.965766) (xy 97.212658 -225.965766)
		)
		(stroke
			(width 0)
			(type solid)
		)
		(fill yes)
		(layer "In11.Cu")
		(net "M_D_CPU1_SB_DQ<29>")
	)
	(gr_poly
		(pts
			(xy 97.352866 -278.132032) (xy 97.352866 -278.087836) (xy 96.997266 -278.087836) (xy 96.997266 -278.132032)
			(xy 97.044256 -278.284432) (xy 97.305876 -278.284432)
		)
		(stroke
			(width 0)
			(type solid)
		)
		(fill yes)
		(layer "In11.Cu")
		(net "M_D_CPU1_SA_DQS_DP<1>")
	)
	(gr_poly
		(pts
			(xy 97.352866 -273.248882) (xy 97.352866 -273.204686) (xy 96.997266 -273.204686) (xy 96.997266 -273.248882)
			(xy 97.044256 -273.401282) (xy 97.305876 -273.401282)
		)
		(stroke
			(width 0)
			(type solid)
		)
		(fill yes)
		(layer "In11.Cu")
		(net "M_D_CPU1_SA_DQS_DP<2>")
	)
	(gr_poly
		(pts
			(xy 97.352866 -268.365478) (xy 97.352866 -268.321282) (xy 96.997266 -268.321282) (xy 96.997266 -268.365478)
			(xy 97.044256 -268.517878) (xy 97.305876 -268.517878)
		)
		(stroke
			(width 0)
			(type solid)
		)
		(fill yes)
		(layer "In11.Cu")
		(net "M_D_CPU1_SA_DQS_DP<3>")
	)
	(gr_poly
		(pts
			(xy 97.352866 -263.482074) (xy 97.352866 -263.437878) (xy 96.997266 -263.437878) (xy 96.997266 -263.482074)
			(xy 97.044256 -263.634474) (xy 97.305876 -263.634474)
		)
		(stroke
			(width 0)
			(type solid)
		)
		(fill yes)
		(layer "In11.Cu")
		(net "M_D_CPU1_SA_DQS_DP<4>")
	)
	(gr_poly
		(pts
			(xy 97.355152 -272.029682) (xy 97.308162 -271.877282) (xy 97.046542 -271.877282) (xy 96.999552 -272.029682)
			(xy 96.999552 -272.073878) (xy 97.355152 -272.073878)
		)
		(stroke
			(width 0)
			(type solid)
		)
		(fill yes)
		(layer "In11.Cu")
		(net "M_D_CPU1_SA_DQS_DP<7>")
	)
	(gr_poly
		(pts
			(xy 97.355152 -267.146278) (xy 97.308162 -266.993878) (xy 97.046542 -266.993878) (xy 96.999552 -267.146278)
			(xy 96.999552 -267.190474) (xy 97.355152 -267.190474)
		)
		(stroke
			(width 0)
			(type solid)
		)
		(fill yes)
		(layer "In11.Cu")
		(net "M_D_CPU1_SA_DQS_DP<8>")
	)
	(gr_poly
		(pts
			(xy 97.355152 -257.37947) (xy 97.308162 -257.22707) (xy 97.046542 -257.22707) (xy 96.999552 -257.37947)
			(xy 96.999552 -257.42392) (xy 97.355152 -257.42392)
		)
		(stroke
			(width 0)
			(type solid)
		)
		(fill yes)
		(layer "In11.Cu")
		(net "M_D_CPU1_SA_CA<1>")
	)
	(gr_poly
		(pts
			(xy 97.357692 -271.620742) (xy 97.357692 -271.576546) (xy 97.002092 -271.576546) (xy 97.002092 -271.620742)
			(xy 97.049082 -271.773142) (xy 97.310702 -271.773142)
		)
		(stroke
			(width 0)
			(type solid)
		)
		(fill yes)
		(layer "In11.Cu")
		(net "M_D_CPU1_SA_DQ<20>")
	)
	(gr_poly
		(pts
			(xy 97.357692 -270.40205) (xy 97.310702 -270.24965) (xy 97.049082 -270.24965) (xy 97.002092 -270.40205)
			(xy 97.002092 -270.446246) (xy 97.357692 -270.446246)
		)
		(stroke
			(width 0)
			(type solid)
		)
		(fill yes)
		(layer "In11.Cu")
		(net "M_D_CPU1_SA_DQ<23>")
	)
	(gr_poly
		(pts
			(xy 97.357692 -268.77391) (xy 97.310702 -268.62151) (xy 97.049082 -268.62151) (xy 97.002092 -268.77391)
			(xy 97.002092 -268.81836) (xy 97.357692 -268.81836)
		)
		(stroke
			(width 0)
			(type solid)
		)
		(fill yes)
		(layer "In11.Cu")
		(net "M_D_CPU1_SA_DQ<27>")
	)
	(gr_poly
		(pts
			(xy 97.357692 -262.262874) (xy 97.310702 -262.110474) (xy 97.049082 -262.110474) (xy 97.002092 -262.262874)
			(xy 97.002092 -262.307324) (xy 97.357692 -262.307324)
		)
		(stroke
			(width 0)
			(type solid)
		)
		(fill yes)
		(layer "In11.Cu")
		(net "M_D_CPU1_SA_DQS_DP<9>")
	)
	(gr_poly
		(pts
			(xy 97.360994 -260.634734) (xy 97.314004 -260.482334) (xy 97.052384 -260.482334) (xy 97.005394 -260.634734)
			(xy 97.005394 -260.679184) (xy 97.360994 -260.679184)
		)
		(stroke
			(width 0)
			(type solid)
		)
		(fill yes)
		(layer "In11.Cu")
		(net "M_D_CPU1_SA_CB<7>")
	)
	(gr_poly
		(pts
			(xy 97.361248 -258.59867) (xy 97.361248 -258.554474) (xy 97.005648 -258.554474) (xy 97.005648 -258.59867)
			(xy 97.052638 -258.75107) (xy 97.314258 -258.75107)
		)
		(stroke
			(width 0)
			(type solid)
		)
		(fill yes)
		(layer "In11.Cu")
		(net "M_D_CPU1_SA_CS_N<3>")
	)
	(gr_poly
		(pts
			(xy 97.36709 -276.913086) (xy 97.3201 -276.760686) (xy 97.05848 -276.760686) (xy 97.01149 -276.913086)
			(xy 97.01149 -276.957282) (xy 97.36709 -276.957282)
		)
		(stroke
			(width 0)
			(type solid)
		)
		(fill yes)
		(layer "In11.Cu")
		(net "M_D_CPU1_SA_DQS_DP<6>")
	)
	(gr_poly
		(pts
			(xy 97.36709 -276.504146) (xy 97.36709 -276.45995) (xy 97.01149 -276.45995) (xy 97.01149 -276.504146)
			(xy 97.05848 -276.656546) (xy 97.3201 -276.656546)
		)
		(stroke
			(width 0)
			(type solid)
		)
		(fill yes)
		(layer "In11.Cu")
		(net "M_D_CPU1_SA_DQ<12>")
	)
	(gr_poly
		(pts
			(xy 97.36709 -266.737846) (xy 97.36709 -266.693396) (xy 97.01149 -266.693396) (xy 97.01149 -266.737846)
			(xy 97.05848 -266.890246) (xy 97.3201 -266.890246)
		)
		(stroke
			(width 0)
			(type solid)
		)
		(fill yes)
		(layer "In11.Cu")
		(net "M_D_CPU1_SA_DQ<28>")
	)
	(gr_poly
		(pts
			(xy 97.36709 -261.854442) (xy 97.36709 -261.809992) (xy 97.01149 -261.809992) (xy 97.01149 -261.854442)
			(xy 97.05848 -262.006842) (xy 97.3201 -262.006842)
		)
		(stroke
			(width 0)
			(type solid)
		)
		(fill yes)
		(layer "In11.Cu")
		(net "M_D_CPU1_SA_CB<4>")
	)
	(gr_poly
		(pts
			(xy 97.36709 -256.971038) (xy 97.36709 -256.926588) (xy 97.01149 -256.926588) (xy 97.01149 -256.971038)
			(xy 97.05848 -257.123438) (xy 97.3201 -257.123438)
		)
		(stroke
			(width 0)
			(type solid)
		)
		(fill yes)
		(layer "In11.Cu")
		(net "M_D_CPU1_SA_CA<2>")
	)
	(gr_poly
		(pts
			(xy 97.36963 -279.759918) (xy 97.36963 -279.715722) (xy 97.01403 -279.715722) (xy 97.01403 -279.759918)
			(xy 97.06102 -279.912318) (xy 97.32264 -279.912318)
		)
		(stroke
			(width 0)
			(type solid)
		)
		(fill yes)
		(layer "In11.Cu")
		(net "M_D_CPU1_SA_DQ<8>")
	)
	(gr_poly
		(pts
			(xy 97.36963 -278.540718) (xy 97.32264 -278.388318) (xy 97.06102 -278.388318) (xy 97.01403 -278.540718)
			(xy 97.01403 -278.584914) (xy 97.36963 -278.584914)
		)
		(stroke
			(width 0)
			(type solid)
		)
		(fill yes)
		(layer "In11.Cu")
		(net "M_D_CPU1_SA_DQ<11>")
	)
	(gr_poly
		(pts
			(xy 97.36963 -275.284946) (xy 97.32264 -275.132546) (xy 97.06102 -275.132546) (xy 97.01403 -275.284946)
			(xy 97.01403 -275.329142) (xy 97.36963 -275.329142)
		)
		(stroke
			(width 0)
			(type solid)
		)
		(fill yes)
		(layer "In11.Cu")
		(net "M_D_CPU1_SA_DQ<15>")
	)
	(gr_poly
		(pts
			(xy 97.36963 -274.876514) (xy 97.36963 -274.832318) (xy 97.01403 -274.832318) (xy 97.01403 -274.876514)
			(xy 97.06102 -275.028914) (xy 97.32264 -275.028914)
		)
		(stroke
			(width 0)
			(type solid)
		)
		(fill yes)
		(layer "In11.Cu")
		(net "M_D_CPU1_SA_DQ<16>")
	)
	(gr_poly
		(pts
			(xy 97.36963 -273.657314) (xy 97.32264 -273.504914) (xy 97.06102 -273.504914) (xy 97.01403 -273.657314)
			(xy 97.01403 -273.70151) (xy 97.36963 -273.70151)
		)
		(stroke
			(width 0)
			(type solid)
		)
		(fill yes)
		(layer "In11.Cu")
		(net "M_D_CPU1_SA_DQ<19>")
	)
	(gr_poly
		(pts
			(xy 97.36963 -269.993618) (xy 97.36963 -269.949168) (xy 97.01403 -269.949168) (xy 97.01403 -269.993618)
			(xy 97.06102 -270.146018) (xy 97.32264 -270.146018)
		)
		(stroke
			(width 0)
			(type solid)
		)
		(fill yes)
		(layer "In11.Cu")
		(net "M_D_CPU1_SA_DQ<24>")
	)
	(gr_poly
		(pts
			(xy 97.36963 -265.518138) (xy 97.32264 -265.365738) (xy 97.06102 -265.365738) (xy 97.01403 -265.518138)
			(xy 97.01403 -265.562588) (xy 97.36963 -265.562588)
		)
		(stroke
			(width 0)
			(type solid)
		)
		(fill yes)
		(layer "In11.Cu")
		(net "M_D_CPU1_SA_DQ<31>")
	)
	(gr_poly
		(pts
			(xy 97.36963 -265.110214) (xy 97.36963 -265.065764) (xy 97.01403 -265.065764) (xy 97.01403 -265.110214)
			(xy 97.06102 -265.262614) (xy 97.32264 -265.262614)
		)
		(stroke
			(width 0)
			(type solid)
		)
		(fill yes)
		(layer "In11.Cu")
		(net "M_D_CPU1_SA_CB<0>")
	)
	(gr_poly
		(pts
			(xy 97.36963 -263.890506) (xy 97.32264 -263.738106) (xy 97.06102 -263.738106) (xy 97.01403 -263.890506)
			(xy 97.01403 -263.934956) (xy 97.36963 -263.934956)
		)
		(stroke
			(width 0)
			(type solid)
		)
		(fill yes)
		(layer "In11.Cu")
		(net "M_D_CPU1_SA_CB<3>")
	)
	(gr_poly
		(pts
			(xy 97.36963 -259.007102) (xy 97.32264 -258.854702) (xy 97.06102 -258.854702) (xy 97.01403 -259.007102)
			(xy 97.01403 -259.051552) (xy 97.36963 -259.051552)
		)
		(stroke
			(width 0)
			(type solid)
		)
		(fill yes)
		(layer "In11.Cu")
		(net "M_D_CPU1_SA_CS_N<0>")
	)
	(gr_poly
		(pts
			(xy 97.36963 -255.751838) (xy 97.32264 -255.599438) (xy 97.06102 -255.599438) (xy 97.01403 -255.751838)
			(xy 97.01403 -255.796034) (xy 97.36963 -255.796034)
		)
		(stroke
			(width 0)
			(type solid)
		)
		(fill yes)
		(layer "In11.Cu")
		(net "M_D_CPU1_SA_CA<5>")
	)
	(gr_poly
		(pts
			(xy 97.610676 -249.186446) (xy 97.572322 -249.164348) (xy 97.416874 -249.128788) (xy 97.286064 -249.355356)
			(xy 97.394522 -249.472196) (xy 97.432876 -249.494294)
		)
		(stroke
			(width 0)
			(type solid)
		)
		(fill yes)
		(layer "In11.Cu")
		(net "M_D_CPU1_SB_CA<1>")
	)
	(gr_poly
		(pts
			(xy 97.71253 -246.568722) (xy 97.66554 -246.416322) (xy 97.40392 -246.416322) (xy 97.35693 -246.568722)
			(xy 97.35693 -246.612918) (xy 97.71253 -246.612918)
		)
		(stroke
			(width 0)
			(type solid)
		)
		(fill yes)
		(layer "In11.Cu")
		(net "M_D_CPU1_SB_CB<6>")
	)
	(gr_poly
		(pts
			(xy 97.71253 -241.685318) (xy 97.66554 -241.532918) (xy 97.40392 -241.532918) (xy 97.35693 -241.685318)
			(xy 97.35693 -241.729514) (xy 97.71253 -241.729514)
		)
		(stroke
			(width 0)
			(type solid)
		)
		(fill yes)
		(layer "In11.Cu")
		(net "M_D_CPU1_SB_DQ<2>")
	)
	(gr_poly
		(pts
			(xy 97.71253 -236.801914) (xy 97.66554 -236.649514) (xy 97.40392 -236.649514) (xy 97.35693 -236.801914)
			(xy 97.35693 -236.84611) (xy 97.71253 -236.84611)
		)
		(stroke
			(width 0)
			(type solid)
		)
		(fill yes)
		(layer "In11.Cu")
		(net "M_D_CPU1_SB_DQ<10>")
	)
	(gr_poly
		(pts
			(xy 97.71253 -227.035106) (xy 97.66554 -226.882706) (xy 97.40392 -226.882706) (xy 97.35693 -227.035106)
			(xy 97.35693 -227.079556) (xy 97.71253 -227.079556)
		)
		(stroke
			(width 0)
			(type solid)
		)
		(fill yes)
		(layer "In11.Cu")
		(net "M_D_CPU1_SB_DQS_DP<8>")
	)
	(gr_poly
		(pts
			(xy 97.71253 -225.407474) (xy 97.66554 -225.255074) (xy 97.40392 -225.255074) (xy 97.35693 -225.407474)
			(xy 97.35693 -225.45167) (xy 97.71253 -225.45167)
		)
		(stroke
			(width 0)
			(type solid)
		)
		(fill yes)
		(layer "In11.Cu")
		(net "M_D_CPU1_SB_DQ<31>")
	)
	(gr_poly
		(pts
			(xy 97.71507 -244.53215) (xy 97.71507 -244.487954) (xy 97.35947 -244.487954) (xy 97.35947 -244.53215)
			(xy 97.40646 -244.68455) (xy 97.66808 -244.68455)
		)
		(stroke
			(width 0)
			(type solid)
		)
		(fill yes)
		(layer "In11.Cu")
		(net "M_D_CPU1_SB_DQS_DN<4>")
	)
	(gr_poly
		(pts
			(xy 97.71507 -243.31295) (xy 97.66808 -243.16055) (xy 97.40646 -243.16055) (xy 97.35947 -243.31295)
			(xy 97.35947 -243.3574) (xy 97.71507 -243.3574)
		)
		(stroke
			(width 0)
			(type solid)
		)
		(fill yes)
		(layer "In11.Cu")
		(net "M_D_CPU1_SB_CB<2>")
	)
	(gr_poly
		(pts
			(xy 97.71507 -242.905026) (xy 97.71507 -242.860576) (xy 97.35947 -242.860576) (xy 97.35947 -242.905026)
			(xy 97.40646 -243.057426) (xy 97.66808 -243.057426)
		)
		(stroke
			(width 0)
			(type solid)
		)
		(fill yes)
		(layer "In11.Cu")
		(net "M_D_CPU1_SB_CB<1>")
	)
	(gr_poly
		(pts
			(xy 97.71507 -239.648746) (xy 97.71507 -239.60455) (xy 97.35947 -239.60455) (xy 97.35947 -239.648746)
			(xy 97.40646 -239.801146) (xy 97.66808 -239.801146)
		)
		(stroke
			(width 0)
			(type solid)
		)
		(fill yes)
		(layer "In11.Cu")
		(net "M_D_CPU1_SB_DQS_DN<5>")
	)
	(gr_poly
		(pts
			(xy 97.71507 -238.429546) (xy 97.66808 -238.277146) (xy 97.40646 -238.277146) (xy 97.35947 -238.429546)
			(xy 97.35947 -238.473996) (xy 97.71507 -238.473996)
		)
		(stroke
			(width 0)
			(type solid)
		)
		(fill yes)
		(layer "In11.Cu")
		(net "M_D_CPU1_SB_DQ<6>")
	)
	(gr_poly
		(pts
			(xy 97.71507 -238.021622) (xy 97.71507 -237.977172) (xy 97.35947 -237.977172) (xy 97.35947 -238.021622)
			(xy 97.40646 -238.174022) (xy 97.66808 -238.174022)
		)
		(stroke
			(width 0)
			(type solid)
		)
		(fill yes)
		(layer "In11.Cu")
		(net "M_D_CPU1_SB_DQ<5>")
	)
	(gr_poly
		(pts
			(xy 97.71507 -234.76585) (xy 97.71507 -234.7214) (xy 97.35947 -234.7214) (xy 97.35947 -234.76585)
			(xy 97.40646 -234.91825) (xy 97.66808 -234.91825)
		)
		(stroke
			(width 0)
			(type solid)
		)
		(fill yes)
		(layer "In11.Cu")
		(net "M_D_CPU1_SB_DQS_DN<6>")
	)
	(gr_poly
		(pts
			(xy 97.71507 -233.546142) (xy 97.66808 -233.393742) (xy 97.40646 -233.393742) (xy 97.35947 -233.546142)
			(xy 97.35947 -233.590592) (xy 97.71507 -233.590592)
		)
		(stroke
			(width 0)
			(type solid)
		)
		(fill yes)
		(layer "In11.Cu")
		(net "M_D_CPU1_SB_DQ<14>")
	)
	(gr_poly
		(pts
			(xy 97.71507 -233.138218) (xy 97.71507 -233.093768) (xy 97.35947 -233.093768) (xy 97.35947 -233.138218)
			(xy 97.40646 -233.290618) (xy 97.66808 -233.290618)
		)
		(stroke
			(width 0)
			(type solid)
		)
		(fill yes)
		(layer "In11.Cu")
		(net "M_D_CPU1_SB_DQ<13>")
	)
	(gr_poly
		(pts
			(xy 97.720912 -246.16029) (xy 97.720912 -246.11584) (xy 97.365312 -246.11584) (xy 97.365312 -246.16029)
			(xy 97.412302 -246.31269) (xy 97.673922 -246.31269)
		)
		(stroke
			(width 0)
			(type solid)
		)
		(fill yes)
		(layer "In11.Cu")
		(net "M_D_CPU1_SB_CB<5>")
	)
	(gr_poly
		(pts
			(xy 97.720912 -241.276886) (xy 97.720912 -241.232436) (xy 97.365312 -241.232436) (xy 97.365312 -241.276886)
			(xy 97.412302 -241.429286) (xy 97.673922 -241.429286)
		)
		(stroke
			(width 0)
			(type solid)
		)
		(fill yes)
		(layer "In11.Cu")
		(net "M_D_CPU1_SB_DQ<1>")
	)
	(gr_poly
		(pts
			(xy 97.720912 -236.393482) (xy 97.720912 -236.349286) (xy 97.365312 -236.349286) (xy 97.365312 -236.393482)
			(xy 97.412302 -236.545882) (xy 97.673922 -236.545882)
		)
		(stroke
			(width 0)
			(type solid)
		)
		(fill yes)
		(layer "In11.Cu")
		(net "M_D_CPU1_SB_DQ<9>")
	)
	(gr_poly
		(pts
			(xy 97.720912 -226.626674) (xy 97.720912 -226.582478) (xy 97.365312 -226.582478) (xy 97.365312 -226.626674)
			(xy 97.412302 -226.779074) (xy 97.673922 -226.779074)
		)
		(stroke
			(width 0)
			(type solid)
		)
		(fill yes)
		(layer "In11.Cu")
		(net "M_D_CPU1_SB_DQ<28>")
	)
	(gr_poly
		(pts
			(xy 97.822512 -275.690584) (xy 97.822512 -275.646388) (xy 97.466912 -275.646388) (xy 97.466912 -275.690584)
			(xy 97.513902 -275.842984) (xy 97.775522 -275.842984)
		)
		(stroke
			(width 0)
			(type solid)
		)
		(fill yes)
		(layer "In11.Cu")
		(net "M_D_CPU1_SA_DQ<13>")
	)
	(gr_poly
		(pts
			(xy 97.822512 -274.47113) (xy 97.775522 -274.31873) (xy 97.513902 -274.31873) (xy 97.466912 -274.47113)
			(xy 97.466912 -274.515326) (xy 97.822512 -274.515326)
		)
		(stroke
			(width 0)
			(type solid)
		)
		(fill yes)
		(layer "In11.Cu")
		(net "M_D_CPU1_SA_DQ<18>")
	)
	(gr_poly
		(pts
			(xy 97.822512 -274.062698) (xy 97.822512 -274.018502) (xy 97.466912 -274.018502) (xy 97.466912 -274.062698)
			(xy 97.513902 -274.215098) (xy 97.775522 -274.215098)
		)
		(stroke
			(width 0)
			(type solid)
		)
		(fill yes)
		(layer "In11.Cu")
		(net "M_D_CPU1_SA_DQ<17>")
	)
	(gr_poly
		(pts
			(xy 97.822512 -265.92403) (xy 97.822512 -265.87958) (xy 97.466912 -265.87958) (xy 97.466912 -265.92403)
			(xy 97.513902 -266.07643) (xy 97.775522 -266.07643)
		)
		(stroke
			(width 0)
			(type solid)
		)
		(fill yes)
		(layer "In11.Cu")
		(net "M_D_CPU1_SA_DQ<29>")
	)
	(gr_poly
		(pts
			(xy 97.822512 -261.040626) (xy 97.822512 -260.99643) (xy 97.466912 -260.99643) (xy 97.466912 -261.040626)
			(xy 97.513902 -261.193026) (xy 97.775522 -261.193026)
		)
		(stroke
			(width 0)
			(type solid)
		)
		(fill yes)
		(layer "In11.Cu")
		(net "M_D_CPU1_SA_CB<5>")
	)
	(gr_poly
		(pts
			(xy 97.822512 -256.157222) (xy 97.822512 -256.113026) (xy 97.466912 -256.113026) (xy 97.466912 -256.157222)
			(xy 97.513902 -256.309622) (xy 97.775522 -256.309622)
		)
		(stroke
			(width 0)
			(type solid)
		)
		(fill yes)
		(layer "In11.Cu")
		(net "M_D_CPU1_SA_CA<4>")
	)
	(gr_poly
		(pts
			(xy 97.825052 -279.354534) (xy 97.778062 -279.202134) (xy 97.516442 -279.202134) (xy 97.469452 -279.354534)
			(xy 97.469452 -279.39873) (xy 97.825052 -279.39873)
		)
		(stroke
			(width 0)
			(type solid)
		)
		(fill yes)
		(layer "In11.Cu")
		(net "M_D_CPU1_SA_DQ<10>")
	)
	(gr_poly
		(pts
			(xy 97.825052 -269.587726) (xy 97.778062 -269.435326) (xy 97.516442 -269.435326) (xy 97.469452 -269.587726)
			(xy 97.469452 -269.631922) (xy 97.825052 -269.631922)
		)
		(stroke
			(width 0)
			(type solid)
		)
		(fill yes)
		(layer "In11.Cu")
		(net "M_D_CPU1_SA_DQ<26>")
	)
	(gr_poly
		(pts
			(xy 97.825052 -264.704322) (xy 97.778062 -264.551922) (xy 97.516442 -264.551922) (xy 97.469452 -264.704322)
			(xy 97.469452 -264.748772) (xy 97.825052 -264.748772)
		)
		(stroke
			(width 0)
			(type solid)
		)
		(fill yes)
		(layer "In11.Cu")
		(net "M_D_CPU1_SA_CB<2>")
	)
	(gr_poly
		(pts
			(xy 97.825052 -264.296398) (xy 97.825052 -264.251948) (xy 97.469452 -264.251948) (xy 97.469452 -264.296398)
			(xy 97.516442 -264.448798) (xy 97.778062 -264.448798)
		)
		(stroke
			(width 0)
			(type solid)
		)
		(fill yes)
		(layer "In11.Cu")
		(net "M_D_CPU1_SA_CB<1>")
	)
	(gr_poly
		(pts
			(xy 97.83064 -258.193286) (xy 97.78365 -258.040886) (xy 97.52203 -258.040886) (xy 97.47504 -258.193286)
			(xy 97.47504 -258.237736) (xy 97.83064 -258.237736)
		)
		(stroke
			(width 0)
			(type solid)
		)
		(fill yes)
		(layer "In11.Cu")
		(net "M_D_CPU1_SA_CS_N<1>")
	)
	(gr_poly
		(pts
			(xy 97.830894 -278.945848) (xy 97.830894 -278.901652) (xy 97.475294 -278.901652) (xy 97.475294 -278.945848)
			(xy 97.522284 -279.098248) (xy 97.783904 -279.098248)
		)
		(stroke
			(width 0)
			(type solid)
		)
		(fill yes)
		(layer "In11.Cu")
		(net "M_D_CPU1_SA_DQ<9>")
	)
	(gr_poly
		(pts
			(xy 97.830894 -277.317962) (xy 97.830894 -277.273766) (xy 97.475294 -277.273766) (xy 97.475294 -277.317962)
			(xy 97.522284 -277.470362) (xy 97.783904 -277.470362)
		)
		(stroke
			(width 0)
			(type solid)
		)
		(fill yes)
		(layer "In11.Cu")
		(net "M_D_CPU1_SA_DQS_DN<6>")
	)
	(gr_poly
		(pts
			(xy 97.830894 -276.09927) (xy 97.783904 -275.94687) (xy 97.522284 -275.94687) (xy 97.475294 -276.09927)
			(xy 97.475294 -276.143466) (xy 97.830894 -276.143466)
		)
		(stroke
			(width 0)
			(type solid)
		)
		(fill yes)
		(layer "In11.Cu")
		(net "M_D_CPU1_SA_DQ<14>")
	)
	(gr_poly
		(pts
			(xy 97.830894 -266.332462) (xy 97.783904 -266.180062) (xy 97.522284 -266.180062) (xy 97.475294 -266.332462)
			(xy 97.475294 -266.376658) (xy 97.830894 -266.376658)
		)
		(stroke
			(width 0)
			(type solid)
		)
		(fill yes)
		(layer "In11.Cu")
		(net "M_D_CPU1_SA_DQ<30>")
	)
	(gr_poly
		(pts
			(xy 97.830894 -261.449058) (xy 97.783904 -261.296658) (xy 97.522284 -261.296658) (xy 97.475294 -261.449058)
			(xy 97.475294 -261.493508) (xy 97.830894 -261.493508)
		)
		(stroke
			(width 0)
			(type solid)
		)
		(fill yes)
		(layer "In11.Cu")
		(net "M_D_CPU1_SA_CB<6>")
	)
	(gr_poly
		(pts
			(xy 97.830894 -256.565654) (xy 97.783904 -256.413254) (xy 97.522284 -256.413254) (xy 97.475294 -256.565654)
			(xy 97.475294 -256.610104) (xy 97.830894 -256.610104)
		)
		(stroke
			(width 0)
			(type solid)
		)
		(fill yes)
		(layer "In11.Cu")
		(net "M_D_CPU1_SA_CA<3>")
	)
	(gr_poly
		(pts
			(xy 97.83445 -271.215866) (xy 97.78746 -271.063466) (xy 97.52584 -271.063466) (xy 97.47885 -271.215866)
			(xy 97.47885 -271.260062) (xy 97.83445 -271.260062)
		)
		(stroke
			(width 0)
			(type solid)
		)
		(fill yes)
		(layer "In11.Cu")
		(net "M_D_CPU1_SA_DQ<22>")
	)
	(gr_poly
		(pts
			(xy 97.83445 -270.806926) (xy 97.83445 -270.76273) (xy 97.47885 -270.76273) (xy 97.47885 -270.806926)
			(xy 97.52584 -270.959326) (xy 97.78746 -270.959326)
		)
		(stroke
			(width 0)
			(type solid)
		)
		(fill yes)
		(layer "In11.Cu")
		(net "M_D_CPU1_SA_DQ<21>")
	)
	(gr_poly
		(pts
			(xy 97.83445 -269.179294) (xy 97.83445 -269.134844) (xy 97.47885 -269.134844) (xy 97.47885 -269.179294)
			(xy 97.52584 -269.331694) (xy 97.78746 -269.331694)
		)
		(stroke
			(width 0)
			(type solid)
		)
		(fill yes)
		(layer "In11.Cu")
		(net "M_D_CPU1_SA_DQ<25>")
	)
	(gr_poly
		(pts
			(xy 97.83445 -262.668258) (xy 97.83445 -262.623808) (xy 97.47885 -262.623808) (xy 97.47885 -262.668258)
			(xy 97.52584 -262.820658) (xy 97.78746 -262.820658)
		)
		(stroke
			(width 0)
			(type solid)
		)
		(fill yes)
		(layer "In11.Cu")
		(net "M_D_CPU1_SA_DQS_DN<9>")
	)
	(gr_poly
		(pts
			(xy 97.83699 -272.435066) (xy 97.83699 -272.390616) (xy 97.48139 -272.390616) (xy 97.48139 -272.435066)
			(xy 97.52838 -272.587466) (xy 97.79 -272.587466)
		)
		(stroke
			(width 0)
			(type solid)
		)
		(fill yes)
		(layer "In11.Cu")
		(net "M_D_CPU1_SA_DQS_DN<7>")
	)
	(gr_poly
		(pts
			(xy 97.83699 -267.551662) (xy 97.83699 -267.507212) (xy 97.48139 -267.507212) (xy 97.48139 -267.551662)
			(xy 97.52838 -267.704062) (xy 97.79 -267.704062)
		)
		(stroke
			(width 0)
			(type solid)
		)
		(fill yes)
		(layer "In11.Cu")
		(net "M_D_CPU1_SA_DQS_DN<8>")
	)
	(gr_poly
		(pts
			(xy 98.08718 -248.361454) (xy 98.048826 -248.339356) (xy 97.893378 -248.303796) (xy 97.762568 -248.530364)
			(xy 97.871026 -248.647204) (xy 97.90938 -248.669302)
		)
		(stroke
			(width 0)
			(type solid)
		)
		(fill yes)
		(layer "In11.Cu")
		(net "M_D_CPU1_SB_CA<1>")
	)
	(gr_poly
		(pts
			(xy 98.161856 -227.497132) (xy 98.270314 -227.380292) (xy 98.139504 -227.153724) (xy 97.984056 -227.189284)
			(xy 97.945702 -227.211382) (xy 98.123502 -227.51923)
		)
		(stroke
			(width 0)
			(type solid)
		)
		(fill yes)
		(layer "In11.Cu")
		(net "M_D_CPU1_SB_DQS_DP<8>")
	)
	(gr_poly
		(pts
			(xy 98.18497 -237.616238) (xy 98.13798 -237.463838) (xy 97.87636 -237.463838) (xy 97.82937 -237.616238)
			(xy 97.82937 -237.660434) (xy 98.18497 -237.660434)
		)
		(stroke
			(width 0)
			(type solid)
		)
		(fill yes)
		(layer "In11.Cu")
		(net "M_D_CPU1_SB_DQ<7>")
	)
	(gr_poly
		(pts
			(xy 98.18497 -232.732834) (xy 98.13798 -232.580434) (xy 97.87636 -232.580434) (xy 97.82937 -232.732834)
			(xy 97.82937 -232.77703) (xy 98.18497 -232.77703)
		)
		(stroke
			(width 0)
			(type solid)
		)
		(fill yes)
		(layer "In11.Cu")
		(net "M_D_CPU1_SB_DQ<15>")
	)
	(gr_poly
		(pts
			(xy 98.196908 -246.974106) (xy 98.196908 -246.929656) (xy 97.841308 -246.929656) (xy 97.841308 -246.974106)
			(xy 97.888298 -247.126506) (xy 98.149918 -247.126506)
		)
		(stroke
			(width 0)
			(type solid)
		)
		(fill yes)
		(layer "In11.Cu")
		(net "M_D_CPU1_SB_CB<4>")
	)
	(gr_poly
		(pts
			(xy 98.196908 -237.207298) (xy 98.196908 -237.163102) (xy 97.841308 -237.163102) (xy 97.841308 -237.207298)
			(xy 97.888298 -237.359698) (xy 98.149918 -237.359698)
		)
		(stroke
			(width 0)
			(type solid)
		)
		(fill yes)
		(layer "In11.Cu")
		(net "M_D_CPU1_SB_DQ<8>")
	)
	(gr_poly
		(pts
			(xy 98.199448 -242.090702) (xy 98.199448 -242.046506) (xy 97.843848 -242.046506) (xy 97.843848 -242.090702)
			(xy 97.890838 -242.243102) (xy 98.152458 -242.243102)
		)
		(stroke
			(width 0)
			(type solid)
		)
		(fill yes)
		(layer "In11.Cu")
		(net "M_D_CPU1_SB_DQ<0>")
	)
	(gr_poly
		(pts
			(xy 98.199448 -239.243362) (xy 98.152458 -239.090962) (xy 97.890838 -239.090962) (xy 97.843848 -239.243362)
			(xy 97.843848 -239.287812) (xy 98.199448 -239.287812)
		)
		(stroke
			(width 0)
			(type solid)
		)
		(fill yes)
		(layer "In11.Cu")
		(net "M_D_CPU1_SB_DQS_DP<5>")
	)
	(gr_poly
		(pts
			(xy 98.199448 -234.360466) (xy 98.152458 -234.208066) (xy 97.890838 -234.208066) (xy 97.843848 -234.360466)
			(xy 97.843848 -234.404662) (xy 98.199448 -234.404662)
		)
		(stroke
			(width 0)
			(type solid)
		)
		(fill yes)
		(layer "In11.Cu")
		(net "M_D_CPU1_SB_DQS_DP<6>")
	)
	(gr_poly
		(pts
			(xy 98.199448 -226.22129) (xy 98.152458 -226.06889) (xy 97.890838 -226.06889) (xy 97.843848 -226.22129)
			(xy 97.843848 -226.26574) (xy 98.199448 -226.26574)
		)
		(stroke
			(width 0)
			(type solid)
		)
		(fill yes)
		(layer "In11.Cu")
		(net "M_D_CPU1_SB_DQ<30>")
	)
	(gr_poly
		(pts
			(xy 98.199448 -225.813366) (xy 98.199448 -225.768916) (xy 97.843848 -225.768916) (xy 97.843848 -225.813366)
			(xy 97.890838 -225.965766) (xy 98.152458 -225.965766)
		)
		(stroke
			(width 0)
			(type solid)
		)
		(fill yes)
		(layer "In11.Cu")
		(net "M_D_CPU1_SB_DQ<29>")
	)
	(gr_poly
		(pts
			(xy 98.270314 -249.070876) (xy 98.161856 -248.954036) (xy 98.123502 -248.931938) (xy 97.945702 -249.239786)
			(xy 97.984056 -249.261884) (xy 98.139504 -249.297444)
		)
		(stroke
			(width 0)
			(type solid)
		)
		(fill yes)
		(layer "In11.Cu")
		(net "M_D_CPU1_SB_CA<0>")
	)
	(gr_poly
		(pts
			(xy 98.294952 -269.99311) (xy 98.294952 -269.948914) (xy 97.939352 -269.948914) (xy 97.939352 -269.99311)
			(xy 97.986342 -270.14551) (xy 98.247962 -270.14551)
		)
		(stroke
			(width 0)
			(type solid)
		)
		(fill yes)
		(layer "In11.Cu")
		(net "M_D_CPU1_SA_DQ<24>")
	)
	(gr_poly
		(pts
			(xy 98.294952 -265.109706) (xy 98.294952 -265.06551) (xy 97.939352 -265.06551) (xy 97.939352 -265.109706)
			(xy 97.986342 -265.262106) (xy 98.247962 -265.262106)
		)
		(stroke
			(width 0)
			(type solid)
		)
		(fill yes)
		(layer "In11.Cu")
		(net "M_D_CPU1_SA_CB<0>")
	)
	(gr_poly
		(pts
			(xy 98.294952 -260.226302) (xy 98.294952 -260.182106) (xy 97.939352 -260.182106) (xy 97.939352 -260.226302)
			(xy 97.986342 -260.378702) (xy 98.247962 -260.378702)
		)
		(stroke
			(width 0)
			(type solid)
		)
		(fill yes)
		(layer "In11.Cu")
		(net "M_D_CPU1_ALERT_N")
	)
	(gr_poly
		(pts
			(xy 98.297492 -270.40205) (xy 98.250502 -270.24965) (xy 97.988882 -270.24965) (xy 97.941892 -270.40205)
			(xy 97.941892 -270.446246) (xy 98.297492 -270.446246)
		)
		(stroke
			(width 0)
			(type solid)
		)
		(fill yes)
		(layer "In11.Cu")
		(net "M_D_CPU1_SA_DQ<23>")
	)
	(gr_poly
		(pts
			(xy 98.301048 -279.759664) (xy 98.301048 -279.715468) (xy 97.945448 -279.715468) (xy 97.945448 -279.759664)
			(xy 97.992438 -279.912064) (xy 98.254058 -279.912064)
		)
		(stroke
			(width 0)
			(type solid)
		)
		(fill yes)
		(layer "In11.Cu")
		(net "M_D_CPU1_SA_DQ<8>")
	)
	(gr_poly
		(pts
			(xy 98.30689 -276.912578) (xy 98.2599 -276.760178) (xy 97.99828 -276.760178) (xy 97.95129 -276.912578)
			(xy 97.95129 -276.957028) (xy 98.30689 -276.957028)
		)
		(stroke
			(width 0)
			(type solid)
		)
		(fill yes)
		(layer "In11.Cu")
		(net "M_D_CPU1_SA_DQS_DP<6>")
	)
	(gr_poly
		(pts
			(xy 98.30689 -274.876514) (xy 98.30689 -274.832064) (xy 97.95129 -274.832064) (xy 97.95129 -274.876514)
			(xy 97.99828 -275.028914) (xy 98.2599 -275.028914)
		)
		(stroke
			(width 0)
			(type solid)
		)
		(fill yes)
		(layer "In11.Cu")
		(net "M_D_CPU1_SA_DQ<16>")
	)
	(gr_poly
		(pts
			(xy 98.30689 -267.14577) (xy 98.2599 -266.99337) (xy 97.99828 -266.99337) (xy 97.95129 -267.14577)
			(xy 97.95129 -267.19022) (xy 98.30689 -267.19022)
		)
		(stroke
			(width 0)
			(type solid)
		)
		(fill yes)
		(layer "In11.Cu")
		(net "M_D_CPU1_SA_DQS_DP<8>")
	)
	(gr_poly
		(pts
			(xy 98.30689 -265.518646) (xy 98.2599 -265.366246) (xy 97.99828 -265.366246) (xy 97.95129 -265.518646)
			(xy 97.95129 -265.562842) (xy 98.30689 -265.562842)
		)
		(stroke
			(width 0)
			(type solid)
		)
		(fill yes)
		(layer "In11.Cu")
		(net "M_D_CPU1_SA_DQ<31>")
	)
	(gr_poly
		(pts
			(xy 98.30689 -260.635242) (xy 98.2599 -260.482842) (xy 97.99828 -260.482842) (xy 97.95129 -260.635242)
			(xy 97.95129 -260.679438) (xy 98.30689 -260.679438)
		)
		(stroke
			(width 0)
			(type solid)
		)
		(fill yes)
		(layer "In11.Cu")
		(net "M_D_CPU1_SA_CB<7>")
	)
	(gr_poly
		(pts
			(xy 98.30689 -257.37947) (xy 98.2599 -257.22707) (xy 97.99828 -257.22707) (xy 97.95129 -257.37947)
			(xy 97.95129 -257.423666) (xy 98.30689 -257.423666)
		)
		(stroke
			(width 0)
			(type solid)
		)
		(fill yes)
		(layer "In11.Cu")
		(net "M_D_CPU1_SA_CA<1>")
	)
	(gr_poly
		(pts
			(xy 98.30689 -255.751838) (xy 98.2599 -255.599438) (xy 97.99828 -255.599438) (xy 97.95129 -255.751838)
			(xy 97.95129 -255.796288) (xy 98.30689 -255.796288)
		)
		(stroke
			(width 0)
			(type solid)
		)
		(fill yes)
		(layer "In11.Cu")
		(net "M_D_CPU1_SA_CA<5>")
	)
	(gr_poly
		(pts
			(xy 98.5139 -227.289614) (xy 98.552254 -227.267516) (xy 98.374454 -226.959668) (xy 98.3361 -226.981766)
			(xy 98.227642 -227.098606) (xy 98.358452 -227.325174)
		)
		(stroke
			(width 0)
			(type solid)
		)
		(fill yes)
		(layer "In11.Cu")
		(net "M_D_CPU1_SB_DQ<28>")
	)
	(gr_poly
		(pts
			(xy 98.631756 -226.68357) (xy 98.740214 -226.56673) (xy 98.609404 -226.340162) (xy 98.453956 -226.375722)
			(xy 98.415602 -226.39782) (xy 98.593402 -226.705668)
		)
		(stroke
			(width 0)
			(type solid)
		)
		(fill yes)
		(layer "In11.Cu")
		(net "M_D_CPU1_SB_DQ<30>")
	)
	(gr_poly
		(pts
			(xy 98.65233 -225.407474) (xy 98.60534 -225.255074) (xy 98.34372 -225.255074) (xy 98.29673 -225.407474)
			(xy 98.29673 -225.45167) (xy 98.65233 -225.45167)
		)
		(stroke
			(width 0)
			(type solid)
		)
		(fill yes)
		(layer "In11.Cu")
		(net "M_D_CPU1_SB_DQ<31>")
	)
	(gr_poly
		(pts
			(xy 98.65487 -233.54665) (xy 98.60788 -233.39425) (xy 98.34626 -233.39425) (xy 98.29927 -233.54665)
			(xy 98.29927 -233.590846) (xy 98.65487 -233.590846)
		)
		(stroke
			(width 0)
			(type solid)
		)
		(fill yes)
		(layer "In11.Cu")
		(net "M_D_CPU1_SB_DQ<14>")
	)
	(gr_poly
		(pts
			(xy 98.660458 -264.066782) (xy 98.622104 -264.044684) (xy 98.466656 -264.009124) (xy 98.335846 -264.235692)
			(xy 98.444304 -264.352532) (xy 98.482658 -264.37463)
		)
		(stroke
			(width 0)
			(type solid)
		)
		(fill yes)
		(layer "In11.Cu")
		(net "M_D_CPU1_SA_CB<2>")
	)
	(gr_poly
		(pts
			(xy 98.666808 -238.021114) (xy 98.666808 -237.976918) (xy 98.311208 -237.976918) (xy 98.311208 -238.021114)
			(xy 98.358198 -238.173514) (xy 98.619818 -238.173514)
		)
		(stroke
			(width 0)
			(type solid)
		)
		(fill yes)
		(layer "In11.Cu")
		(net "M_D_CPU1_SB_DQ<5>")
	)
	(gr_poly
		(pts
			(xy 98.666808 -233.13771) (xy 98.666808 -233.093514) (xy 98.311208 -233.093514) (xy 98.311208 -233.13771)
			(xy 98.358198 -233.29011) (xy 98.619818 -233.29011)
		)
		(stroke
			(width 0)
			(type solid)
		)
		(fill yes)
		(layer "In11.Cu")
		(net "M_D_CPU1_SB_DQ<13>")
	)
	(gr_poly
		(pts
			(xy 98.762312 -256.565654) (xy 98.715322 -256.413254) (xy 98.453702 -256.413254) (xy 98.406712 -256.565654)
			(xy 98.406712 -256.60985) (xy 98.762312 -256.60985)
		)
		(stroke
			(width 0)
			(type solid)
		)
		(fill yes)
		(layer "In11.Cu")
		(net "M_D_CPU1_SA_CA<3>")
	)
	(gr_poly
		(pts
			(xy 98.770694 -265.923522) (xy 98.770694 -265.879326) (xy 98.415094 -265.879326) (xy 98.415094 -265.923522)
			(xy 98.462084 -266.075922) (xy 98.723704 -266.075922)
		)
		(stroke
			(width 0)
			(type solid)
		)
		(fill yes)
		(layer "In11.Cu")
		(net "M_D_CPU1_SA_DQ<29>")
	)
	(gr_poly
		(pts
			(xy 98.770694 -261.040626) (xy 98.770694 -260.996176) (xy 98.415094 -260.996176) (xy 98.415094 -261.040626)
			(xy 98.462084 -261.193026) (xy 98.723704 -261.193026)
		)
		(stroke
			(width 0)
			(type solid)
		)
		(fill yes)
		(layer "In11.Cu")
		(net "M_D_CPU1_SA_CB<5>")
	)
	(gr_poly
		(pts
			(xy 98.77425 -271.215866) (xy 98.72726 -271.063466) (xy 98.46564 -271.063466) (xy 98.41865 -271.215866)
			(xy 98.41865 -271.260062) (xy 98.77425 -271.260062)
		)
		(stroke
			(width 0)
			(type solid)
		)
		(fill yes)
		(layer "In11.Cu")
		(net "M_D_CPU1_SA_DQ<22>")
	)
	(gr_poly
		(pts
			(xy 98.77425 -270.806926) (xy 98.77425 -270.76273) (xy 98.41865 -270.76273) (xy 98.41865 -270.806926)
			(xy 98.46564 -270.959326) (xy 98.72726 -270.959326)
		)
		(stroke
			(width 0)
			(type solid)
		)
		(fill yes)
		(layer "In11.Cu")
		(net "M_D_CPU1_SA_DQ<21>")
	)
	(gr_poly
		(pts
			(xy 98.77679 -259.821426) (xy 98.7298 -259.669026) (xy 98.46818 -259.669026) (xy 98.42119 -259.821426)
			(xy 98.42119 -259.865622) (xy 98.77679 -259.865622)
		)
		(stroke
			(width 0)
			(type solid)
		)
		(fill yes)
		(layer "In11.Cu")
		(net "M_D_CPU1_SA_CS_N<2>")
	)
	(gr_poly
		(pts
			(xy 98.986594 -226.480116) (xy 99.024948 -226.458018) (xy 98.847148 -226.15017) (xy 98.808794 -226.172268)
			(xy 98.700336 -226.289108) (xy 98.831146 -226.515676)
		)
		(stroke
			(width 0)
			(type solid)
		)
		(fill yes)
		(layer "In11.Cu")
		(net "M_D_CPU1_SB_DQ<29>")
	)
	(gr_poly
		(pts
			(xy 99.136708 -232.732326) (xy 99.089718 -232.579926) (xy 98.828098 -232.579926) (xy 98.781108 -232.732326)
			(xy 98.781108 -232.776776) (xy 99.136708 -232.776776)
		)
		(stroke
			(width 0)
			(type solid)
		)
		(fill yes)
		(layer "In11.Cu")
		(net "M_D_CPU1_SB_DQ<15>")
	)
	(gr_poly
		(pts
			(xy 99.139248 -234.360466) (xy 99.092258 -234.208066) (xy 98.830638 -234.208066) (xy 98.783648 -234.360466)
			(xy 98.783648 -234.404662) (xy 99.139248 -234.404662)
		)
		(stroke
			(width 0)
			(type solid)
		)
		(fill yes)
		(layer "In11.Cu")
		(net "M_D_CPU1_SB_DQS_DP<6>")
	)
	(gr_poly
		(pts
			(xy 99.237292 -270.40205) (xy 99.190302 -270.24965) (xy 98.928682 -270.24965) (xy 98.881692 -270.40205)
			(xy 98.881692 -270.446246) (xy 99.237292 -270.446246)
		)
		(stroke
			(width 0)
			(type solid)
		)
		(fill yes)
		(layer "In11.Cu")
		(net "M_D_CPU1_SA_DQ<23>")
	)
	(gr_poly
		(pts
			(xy 99.24669 -260.22681) (xy 99.24669 -260.18236) (xy 98.89109 -260.18236) (xy 98.89109 -260.22681)
			(xy 98.93808 -260.37921) (xy 99.1997 -260.37921)
		)
		(stroke
			(width 0)
			(type solid)
		)
		(fill yes)
		(layer "In11.Cu")
		(net "M_D_CPU1_ALERT_N")
	)
	(gr_poly
		(pts
			(xy 122.48261 -247.64365) (xy 122.520964 -247.621552) (xy 122.343164 -247.313704) (xy 122.30481 -247.335802)
			(xy 122.196352 -247.452642) (xy 122.327162 -247.67921)
		)
		(stroke
			(width 0)
			(type solid)
		)
		(fill yes)
		(layer "In11.Cu")
		(net "M_H_CPU1_SA_CA<6>")
	)
	(gr_poly
		(pts
			(xy 122.519948 -246.737632) (xy 122.481594 -246.715534) (xy 122.326146 -246.679974) (xy 122.195336 -246.906542)
			(xy 122.303794 -247.023382) (xy 122.342148 -247.04548)
		)
		(stroke
			(width 0)
			(type solid)
		)
		(fill yes)
		(layer "In11.Cu")
		(net "M_H_CPU1_SA_CA<6>")
	)
	(gr_poly
		(pts
			(xy 122.953272 -248.45899) (xy 122.991626 -248.436892) (xy 122.813826 -248.129044) (xy 122.775472 -248.151142)
			(xy 122.667014 -248.267982) (xy 122.797824 -248.49455)
		)
		(stroke
			(width 0)
			(type solid)
		)
		(fill yes)
		(layer "In11.Cu")
		(net "M_H_CPU1_SA_CA<6>")
	)
	(gr_poly
		(pts
			(xy 123.060968 -247.834658) (xy 123.169426 -247.717818) (xy 123.038616 -247.49125) (xy 122.883168 -247.52681)
			(xy 122.844814 -247.548908) (xy 123.022614 -247.856756)
		)
		(stroke
			(width 0)
			(type solid)
		)
		(fill yes)
		(layer "In11.Cu")
		(net "M_H_CPU1_SA_PAR")
	)
	(gr_poly
		(pts
			(xy 123.08967 -246.568722) (xy 123.04268 -246.416322) (xy 122.78106 -246.416322) (xy 122.73407 -246.568722)
			(xy 122.73407 -246.613172) (xy 123.08967 -246.613172)
		)
		(stroke
			(width 0)
			(type solid)
		)
		(fill yes)
		(layer "In11.Cu")
		(net "M_H_CPU1_SA_CA<6>")
	)
	(gr_poly
		(pts
			(xy 123.197112 -257.784854) (xy 123.197112 -257.740658) (xy 122.841512 -257.740658) (xy 122.841512 -257.784854)
			(xy 122.888502 -257.937254) (xy 123.150122 -257.937254)
		)
		(stroke
			(width 0)
			(type solid)
		)
		(fill yes)
		(layer "In11.Cu")
		(net "M_E_CPU1_ALERT_N")
	)
	(gr_poly
		(pts
			(xy 123.416822 -249.26163) (xy 123.455176 -249.239532) (xy 123.277376 -248.931684) (xy 123.239022 -248.953782)
			(xy 123.130564 -249.070622) (xy 123.261374 -249.29719)
		)
		(stroke
			(width 0)
			(type solid)
		)
		(fill yes)
		(layer "In11.Cu")
		(net "M_H_CPU1_SA_CA<6>")
	)
	(gr_poly
		(pts
			(xy 123.532646 -248.65203) (xy 123.641104 -248.53519) (xy 123.510294 -248.308622) (xy 123.354846 -248.344182)
			(xy 123.316492 -248.36628) (xy 123.494292 -248.674128)
		)
		(stroke
			(width 0)
			(type solid)
		)
		(fill yes)
		(layer "In11.Cu")
		(net "M_H_CPU1_SA_PAR")
	)
	(gr_poly
		(pts
			(xy 123.892056 -248.456958) (xy 123.93041 -248.43486) (xy 123.75261 -248.127012) (xy 123.714256 -248.14911)
			(xy 123.605798 -248.26595) (xy 123.736608 -248.492518)
		)
		(stroke
			(width 0)
			(type solid)
		)
		(fill yes)
		(layer "In11.Cu")
		(net "M_H_CPU1_CLK_DP<1>")
	)
	(gr_poly
		(pts
			(xy 124.000768 -249.462544) (xy 124.109226 -249.345704) (xy 123.978416 -249.119136) (xy 123.822968 -249.154696)
			(xy 123.784614 -249.176794) (xy 123.962414 -249.484642)
		)
		(stroke
			(width 0)
			(type solid)
		)
		(fill yes)
		(layer "In11.Cu")
		(net "M_H_CPU1_SA_PAR")
	)
	(gr_poly
		(pts
			(xy 124.000768 -247.834658) (xy 124.109226 -247.717818) (xy 123.978416 -247.49125) (xy 123.822968 -247.52681)
			(xy 123.784614 -247.548908) (xy 123.962414 -247.856756)
		)
		(stroke
			(width 0)
			(type solid)
		)
		(fill yes)
		(layer "In11.Cu")
		(net "M_H_CPU1_CLK_DN<1>")
	)
	(gr_poly
		(pts
			(xy 124.035058 -255.92786) (xy 123.996704 -255.905762) (xy 123.841256 -255.870202) (xy 123.710446 -256.09677)
			(xy 123.818904 -256.21361) (xy 123.857258 -256.235708)
		)
		(stroke
			(width 0)
			(type solid)
		)
		(fill yes)
		(layer "In11.Cu")
		(net "M_H_CPU1_SA_CS_N<3>")
	)
	(gr_poly
		(pts
			(xy 124.136912 -257.784854) (xy 124.136912 -257.740658) (xy 123.781312 -257.740658) (xy 123.781312 -257.784854)
			(xy 123.828302 -257.937254) (xy 124.089922 -257.937254)
		)
		(stroke
			(width 0)
			(type solid)
		)
		(fill yes)
		(layer "In11.Cu")
		(net "M_E_CPU1_ALERT_N")
	)
	(gr_poly
		(pts
			(xy 124.139452 -254.937514) (xy 124.092462 -254.785114) (xy 123.830842 -254.785114) (xy 123.783852 -254.937514)
			(xy 123.783852 -254.981964) (xy 124.139452 -254.981964)
		)
		(stroke
			(width 0)
			(type solid)
		)
		(fill yes)
		(layer "In11.Cu")
		(net "M_H_CPU1_SA_CA<2>")
	)
	(gr_poly
		(pts
			(xy 124.36221 -249.271536) (xy 124.400564 -249.249438) (xy 124.222764 -248.94159) (xy 124.18441 -248.963688)
			(xy 124.075952 -249.080528) (xy 124.206762 -249.307096)
		)
		(stroke
			(width 0)
			(type solid)
		)
		(fill yes)
		(layer "In11.Cu")
		(net "M_H_CPU1_CLK_DP<1>")
	)
	(gr_poly
		(pts
			(xy 124.470922 -248.649236) (xy 124.57938 -248.532396) (xy 124.44857 -248.305828) (xy 124.293122 -248.341388)
			(xy 124.254768 -248.363486) (xy 124.432568 -248.671334)
		)
		(stroke
			(width 0)
			(type solid)
		)
		(fill yes)
		(layer "In11.Cu")
		(net "M_H_CPU1_CLK_DN<1>")
	)
	(gr_poly
		(pts
			(xy 124.609352 -255.343406) (xy 124.609352 -255.298956) (xy 124.253752 -255.298956) (xy 124.253752 -255.343406)
			(xy 124.300742 -255.495806) (xy 124.562362 -255.495806)
		)
		(stroke
			(width 0)
			(type solid)
		)
		(fill yes)
		(layer "In11.Cu")
		(net "M_H_CPU1_SA_CA<0>")
	)
	(gr_poly
		(pts
			(xy 124.62129 -255.751838) (xy 124.5743 -255.599438) (xy 124.31268 -255.599438) (xy 124.26569 -255.751838)
			(xy 124.26569 -255.796288) (xy 124.62129 -255.796288)
		)
		(stroke
			(width 0)
			(type solid)
		)
		(fill yes)
		(layer "In11.Cu")
		(net "M_H_CPU1_SA_CS_N<3>")
	)
	(gr_poly
		(pts
			(xy 124.946156 -249.47245) (xy 125.054614 -249.35561) (xy 124.923804 -249.129042) (xy 124.768356 -249.164602)
			(xy 124.730002 -249.1867) (xy 124.907802 -249.494548)
		)
		(stroke
			(width 0)
			(type solid)
		)
		(fill yes)
		(layer "In11.Cu")
		(net "M_H_CPU1_CLK_DN<1>")
	)
	(gr_poly
		(pts
			(xy 124.96673 -242.905026) (xy 124.96673 -242.860576) (xy 124.61113 -242.860576) (xy 124.61113 -242.905026)
			(xy 124.65812 -243.057426) (xy 124.91974 -243.057426)
		)
		(stroke
			(width 0)
			(type solid)
		)
		(fill yes)
		(layer "In11.Cu")
		(net "M_H_CPU1_SB_DQS_DP<9>")
	)
	(gr_poly
		(pts
			(xy 124.96927 -244.532658) (xy 124.96927 -244.488208) (xy 124.61367 -244.488208) (xy 124.61367 -244.532658)
			(xy 124.66066 -244.685058) (xy 124.92228 -244.685058)
		)
		(stroke
			(width 0)
			(type solid)
		)
		(fill yes)
		(layer "In11.Cu")
		(net "M_H_CPU1_SB_CB<6>")
	)
	(gr_poly
		(pts
			(xy 124.978668 -233.13771) (xy 124.978668 -233.093514) (xy 124.623068 -233.093514) (xy 124.623068 -233.13771)
			(xy 124.670058 -233.29011) (xy 124.931678 -233.29011)
		)
		(stroke
			(width 0)
			(type solid)
		)
		(fill yes)
		(layer "In11.Cu")
		(net "M_H_CPU1_SB_DQS_DP<1>")
	)
	(gr_poly
		(pts
			(xy 125.076712 -261.449058) (xy 125.029722 -261.296658) (xy 124.768102 -261.296658) (xy 124.721112 -261.449058)
			(xy 124.721112 -261.493254) (xy 125.076712 -261.493254)
		)
		(stroke
			(width 0)
			(type solid)
		)
		(fill yes)
		(layer "In11.Cu")
		(net "M_H_CPU1_SA_CB<1>")
	)
	(gr_poly
		(pts
			(xy 125.079252 -257.784854) (xy 125.079252 -257.740658) (xy 124.723652 -257.740658) (xy 124.723652 -257.784854)
			(xy 124.770642 -257.937254) (xy 125.032262 -257.937254)
		)
		(stroke
			(width 0)
			(type solid)
		)
		(fill yes)
		(layer "In11.Cu")
		(net "M_E_CPU1_ALERT_N")
	)
	(gr_poly
		(pts
			(xy 125.085094 -256.157222) (xy 125.085094 -256.112772) (xy 124.729494 -256.112772) (xy 124.729494 -256.157222)
			(xy 124.776484 -256.309622) (xy 125.038104 -256.309622)
		)
		(stroke
			(width 0)
			(type solid)
		)
		(fill yes)
		(layer "In11.Cu")
		(net "M_H_CPU1_SA_CS_N<2>")
	)
	(gr_poly
		(pts
			(xy 125.08865 -270.806926) (xy 125.08865 -270.76273) (xy 124.73305 -270.76273) (xy 124.73305 -270.806926)
			(xy 124.78004 -270.959326) (xy 125.04166 -270.959326)
		)
		(stroke
			(width 0)
			(type solid)
		)
		(fill yes)
		(layer "In11.Cu")
		(net "M_H_CPU1_SA_DQS_DP<2>")
	)
	(gr_poly
		(pts
			(xy 125.09119 -254.938022) (xy 125.0442 -254.785622) (xy 124.78258 -254.785622) (xy 124.73559 -254.938022)
			(xy 124.73559 -254.982218) (xy 125.09119 -254.982218)
		)
		(stroke
			(width 0)
			(type solid)
		)
		(fill yes)
		(layer "In11.Cu")
		(net "M_H_CPU1_SA_CA<2>")
	)
	(gr_poly
		(pts
			(xy 125.406658 -280.41981) (xy 125.445012 -280.397712) (xy 125.267212 -280.089864) (xy 125.228858 -280.111962)
			(xy 125.1204 -280.228802) (xy 125.25121 -280.45537)
		)
		(stroke
			(width 0)
			(type solid)
		)
		(fill yes)
		(layer "In11.Cu")
		(net "M_H_CPU1_SA_DQ<8>")
	)
	(gr_poly
		(pts
			(xy 125.411992 -278.80183) (xy 125.450346 -278.779732) (xy 125.272546 -278.471884) (xy 125.234192 -278.493982)
			(xy 125.125734 -278.610822) (xy 125.256544 -278.83739)
		)
		(stroke
			(width 0)
			(type solid)
		)
		(fill yes)
		(layer "In11.Cu")
		(net "M_H_CPU1_SA_DQ<9>")
	)
	(gr_poly
		(pts
			(xy 125.44171 -234.360466) (xy 125.39472 -234.208066) (xy 125.1331 -234.208066) (xy 125.08611 -234.360466)
			(xy 125.08611 -234.404916) (xy 125.44171 -234.404916)
		)
		(stroke
			(width 0)
			(type solid)
		)
		(fill yes)
		(layer "In11.Cu")
		(net "M_H_CPU1_SB_DQ<10>")
	)
	(gr_poly
		(pts
			(xy 125.445266 -244.127274) (xy 125.398276 -243.974874) (xy 125.136656 -243.974874) (xy 125.089666 -244.127274)
			(xy 125.089666 -244.17147) (xy 125.445266 -244.17147)
		)
		(stroke
			(width 0)
			(type solid)
		)
		(fill yes)
		(layer "In11.Cu")
		(net "M_H_CPU1_SB_CB<4>")
	)
	(gr_poly
		(pts
			(xy 125.450854 -263.242552) (xy 125.4125 -263.220454) (xy 125.257052 -263.184894) (xy 125.126242 -263.411462)
			(xy 125.2347 -263.528302) (xy 125.273054 -263.5504)
		)
		(stroke
			(width 0)
			(type solid)
		)
		(fill yes)
		(layer "In11.Cu")
		(net "M_H_CPU1_SA_DQ<31>")
	)
	(gr_poly
		(pts
			(xy 125.453648 -233.952034) (xy 125.453648 -233.907838) (xy 125.098048 -233.907838) (xy 125.098048 -233.952034)
			(xy 125.145038 -234.104434) (xy 125.406658 -234.104434)
		)
		(stroke
			(width 0)
			(type solid)
		)
		(fill yes)
		(layer "In11.Cu")
		(net "M_H_CPU1_SB_DQ<9>")
	)
	(gr_poly
		(pts
			(xy 125.526038 -279.816306) (xy 125.634496 -279.699466) (xy 125.503686 -279.472898) (xy 125.348238 -279.508458)
			(xy 125.309884 -279.530556) (xy 125.487684 -279.838404)
		)
		(stroke
			(width 0)
			(type solid)
		)
		(fill yes)
		(layer "In11.Cu")
		(net "M_H_CPU1_SA_DQ<10>")
	)
	(gr_poly
		(pts
			(xy 125.546612 -257.37947) (xy 125.499622 -257.22707) (xy 125.238002 -257.22707) (xy 125.191012 -257.37947)
			(xy 125.191012 -257.423666) (xy 125.546612 -257.423666)
		)
		(stroke
			(width 0)
			(type solid)
		)
		(fill yes)
		(layer "In11.Cu")
		(net "M_H_CPU1_ALERT_N")
	)
	(gr_poly
		(pts
			(xy 125.549152 -272.029682) (xy 125.502162 -271.877282) (xy 125.240542 -271.877282) (xy 125.193552 -272.029682)
			(xy 125.193552 -272.073878) (xy 125.549152 -272.073878)
		)
		(stroke
			(width 0)
			(type solid)
		)
		(fill yes)
		(layer "In11.Cu")
		(net "M_H_CPU1_SA_DQ<18>")
	)
	(gr_poly
		(pts
			(xy 125.549152 -262.262874) (xy 125.502162 -262.110474) (xy 125.240542 -262.110474) (xy 125.193552 -262.262874)
			(xy 125.193552 -262.307324) (xy 125.549152 -262.307324)
		)
		(stroke
			(width 0)
			(type solid)
		)
		(fill yes)
		(layer "In11.Cu")
		(net "M_H_CPU1_SA_CB<2>")
	)
	(gr_poly
		(pts
			(xy 125.551692 -271.620742) (xy 125.551692 -271.576546) (xy 125.196092 -271.576546) (xy 125.196092 -271.620742)
			(xy 125.243082 -271.773142) (xy 125.504702 -271.773142)
		)
		(stroke
			(width 0)
			(type solid)
		)
		(fill yes)
		(layer "In11.Cu")
		(net "M_H_CPU1_SA_DQ<17>")
	)
	(gr_poly
		(pts
			(xy 125.554994 -256.971038) (xy 125.554994 -256.926588) (xy 125.199394 -256.926588) (xy 125.199394 -256.971038)
			(xy 125.246384 -257.123438) (xy 125.508004 -257.123438)
		)
		(stroke
			(width 0)
			(type solid)
		)
		(fill yes)
		(layer "In11.Cu")
		(net "M_H_CPU1_SA_CS_N<0>")
	)
	(gr_poly
		(pts
			(xy 125.56109 -267.146278) (xy 125.5141 -266.993878) (xy 125.25248 -266.993878) (xy 125.20549 -267.146278)
			(xy 125.20549 -267.190474) (xy 125.56109 -267.190474)
		)
		(stroke
			(width 0)
			(type solid)
		)
		(fill yes)
		(layer "In11.Cu")
		(net "M_H_CPU1_SA_DQ<26>")
	)
	(gr_poly
		(pts
			(xy 125.56109 -255.751838) (xy 125.5141 -255.599438) (xy 125.25248 -255.599438) (xy 125.20549 -255.751838)
			(xy 125.20549 -255.796034) (xy 125.56109 -255.796034)
		)
		(stroke
			(width 0)
			(type solid)
		)
		(fill yes)
		(layer "In11.Cu")
		(net "M_H_CPU1_SA_CS_N<3>")
	)
	(gr_poly
		(pts
			(xy 125.56109 -255.343406) (xy 125.56109 -255.29921) (xy 125.20549 -255.29921) (xy 125.20549 -255.343406)
			(xy 125.25248 -255.495806) (xy 125.5141 -255.495806)
		)
		(stroke
			(width 0)
			(type solid)
		)
		(fill yes)
		(layer "In11.Cu")
		(net "M_H_CPU1_SA_CA<0>")
	)
	(gr_poly
		(pts
			(xy 125.634496 -263.951212) (xy 125.526038 -263.834372) (xy 125.487684 -263.812274) (xy 125.309884 -264.120122)
			(xy 125.348238 -264.14222) (xy 125.503686 -264.17778)
		)
		(stroke
			(width 0)
			(type solid)
		)
		(fill yes)
		(layer "In11.Cu")
		(net "M_H_CPU1_SA_DQ<29>")
	)
	(gr_poly
		(pts
			(xy 125.770132 -248.454164) (xy 125.808486 -248.432066) (xy 125.630686 -248.124218) (xy 125.592332 -248.146316)
			(xy 125.483874 -248.263156) (xy 125.614684 -248.489724)
		)
		(stroke
			(width 0)
			(type solid)
		)
		(fill yes)
		(layer "In11.Cu")
		(net "M_H_CPU1_CLK_DP<0>")
	)
	(gr_poly
		(pts
			(xy 125.876304 -279.605994) (xy 125.914658 -279.583896) (xy 125.736858 -279.276048) (xy 125.698504 -279.298146)
			(xy 125.590046 -279.414986) (xy 125.720856 -279.641554)
		)
		(stroke
			(width 0)
			(type solid)
		)
		(fill yes)
		(layer "In11.Cu")
		(net "M_H_CPU1_SA_DQ<9>")
	)
	(gr_poly
		(pts
			(xy 125.881638 -277.987252) (xy 125.919992 -277.965154) (xy 125.742192 -277.657306) (xy 125.703838 -277.679404)
			(xy 125.59538 -277.796244) (xy 125.72619 -278.022812)
		)
		(stroke
			(width 0)
			(type solid)
		)
		(fill yes)
		(layer "In11.Cu")
		(net "M_H_CPU1_SA_DQS_DP<1>")
	)
	(gr_poly
		(pts
			(xy 125.885956 -247.844564) (xy 125.994414 -247.727724) (xy 125.863604 -247.501156) (xy 125.708156 -247.536716)
			(xy 125.669802 -247.558814) (xy 125.847602 -247.866662)
		)
		(stroke
			(width 0)
			(type solid)
		)
		(fill yes)
		(layer "In11.Cu")
		(net "M_H_CPU1_CLK_DN<0>")
	)
	(gr_poly
		(pts
			(xy 125.90653 -225.407474) (xy 125.85954 -225.255074) (xy 125.59792 -225.255074) (xy 125.55093 -225.407474)
			(xy 125.55093 -225.45167) (xy 125.90653 -225.45167)
		)
		(stroke
			(width 0)
			(type solid)
		)
		(fill yes)
		(layer "In11.Cu")
		(net "M_H_CPU1_SB_DQ<29>")
	)
	(gr_poly
		(pts
			(xy 125.90907 -244.53215) (xy 125.90907 -244.487954) (xy 125.55347 -244.487954) (xy 125.55347 -244.53215)
			(xy 125.60046 -244.68455) (xy 125.86208 -244.68455)
		)
		(stroke
			(width 0)
			(type solid)
		)
		(fill yes)
		(layer "In11.Cu")
		(net "M_H_CPU1_SB_CB<6>")
	)
	(gr_poly
		(pts
			(xy 125.90907 -242.905026) (xy 125.90907 -242.860576) (xy 125.55347 -242.860576) (xy 125.55347 -242.905026)
			(xy 125.60046 -243.057426) (xy 125.86208 -243.057426)
		)
		(stroke
			(width 0)
			(type solid)
		)
		(fill yes)
		(layer "In11.Cu")
		(net "M_H_CPU1_SB_DQS_DP<9>")
	)
	(gr_poly
		(pts
			(xy 125.90907 -230.290878) (xy 125.86208 -230.138478) (xy 125.60046 -230.138478) (xy 125.55347 -230.290878)
			(xy 125.55347 -230.335328) (xy 125.90907 -230.335328)
		)
		(stroke
			(width 0)
			(type solid)
		)
		(fill yes)
		(layer "In11.Cu")
		(net "M_H_CPU1_SB_DQ<15>")
	)
	(gr_poly
		(pts
			(xy 125.90907 -229.882446) (xy 125.90907 -229.837996) (xy 125.55347 -229.837996) (xy 125.55347 -229.882446)
			(xy 125.60046 -230.034846) (xy 125.86208 -230.034846)
		)
		(stroke
			(width 0)
			(type solid)
		)
		(fill yes)
		(layer "In11.Cu")
		(net "M_H_CPU1_SB_DQ<26>")
	)
	(gr_poly
		(pts
			(xy 125.918468 -235.174282) (xy 125.871478 -235.021882) (xy 125.609858 -235.021882) (xy 125.562868 -235.174282)
			(xy 125.562868 -235.218732) (xy 125.918468 -235.218732)
		)
		(stroke
			(width 0)
			(type solid)
		)
		(fill yes)
		(layer "In11.Cu")
		(net "M_H_CPU1_SB_DQ<7>")
	)
	(gr_poly
		(pts
			(xy 125.918468 -234.76585) (xy 125.918468 -234.7214) (xy 125.562868 -234.7214) (xy 125.562868 -234.76585)
			(xy 125.609858 -234.91825) (xy 125.871478 -234.91825)
		)
		(stroke
			(width 0)
			(type solid)
		)
		(fill yes)
		(layer "In11.Cu")
		(net "M_H_CPU1_SB_DQ<8>")
	)
	(gr_poly
		(pts
			(xy 125.918468 -233.13771) (xy 125.918468 -233.093514) (xy 125.562868 -233.093514) (xy 125.562868 -233.13771)
			(xy 125.609858 -233.29011) (xy 125.871478 -233.29011)
		)
		(stroke
			(width 0)
			(type solid)
		)
		(fill yes)
		(layer "In11.Cu")
		(net "M_H_CPU1_SB_DQS_DP<1>")
	)
	(gr_poly
		(pts
			(xy 125.918976 -277.081742) (xy 125.880622 -277.059644) (xy 125.725174 -277.024084) (xy 125.594364 -277.250652)
			(xy 125.702822 -277.367492) (xy 125.741176 -277.38959)
		)
		(stroke
			(width 0)
			(type solid)
		)
		(fill yes)
		(layer "In11.Cu")
		(net "M_H_CPU1_SA_DQS_DP<1>")
	)
	(gr_poly
		(pts
			(xy 125.99035 -278.992838) (xy 126.098808 -278.875998) (xy 125.967998 -278.64943) (xy 125.81255 -278.68499)
			(xy 125.774196 -278.707088) (xy 125.951996 -279.014936)
		)
		(stroke
			(width 0)
			(type solid)
		)
		(fill yes)
		(layer "In11.Cu")
		(net "M_H_CPU1_SA_DQ<11>")
	)
	(gr_poly
		(pts
			(xy 126.016512 -256.157222) (xy 126.016512 -256.113026) (xy 125.660912 -256.113026) (xy 125.660912 -256.157222)
			(xy 125.707902 -256.309622) (xy 125.969522 -256.309622)
		)
		(stroke
			(width 0)
			(type solid)
		)
		(fill yes)
		(layer "In11.Cu")
		(net "M_H_CPU1_SA_CS_N<2>")
	)
	(gr_poly
		(pts
			(xy 126.019052 -280.574242) (xy 126.019052 -280.529792) (xy 125.663452 -280.529792) (xy 125.663452 -280.574242)
			(xy 125.710442 -280.726642) (xy 125.972062 -280.726642)
		)
		(stroke
			(width 0)
			(type solid)
		)
		(fill yes)
		(layer "In11.Cu")
		(net "M_H_CPU1_SA_DQ<8>")
	)
	(gr_poly
		(pts
			(xy 126.019052 -272.843498) (xy 125.972062 -272.691098) (xy 125.710442 -272.691098) (xy 125.663452 -272.843498)
			(xy 125.663452 -272.887948) (xy 126.019052 -272.887948)
		)
		(stroke
			(width 0)
			(type solid)
		)
		(fill yes)
		(layer "In11.Cu")
		(net "M_H_CPU1_SA_DQ<15>")
	)
	(gr_poly
		(pts
			(xy 126.019052 -263.07669) (xy 125.972062 -262.92429) (xy 125.710442 -262.92429) (xy 125.663452 -263.07669)
			(xy 125.663452 -263.12114) (xy 126.019052 -263.12114)
		)
		(stroke
			(width 0)
			(type solid)
		)
		(fill yes)
		(layer "In11.Cu")
		(net "M_H_CPU1_SA_DQ<31>")
	)
	(gr_poly
		(pts
			(xy 126.019052 -258.193286) (xy 125.972062 -258.040886) (xy 125.710442 -258.040886) (xy 125.663452 -258.193286)
			(xy 125.663452 -258.237736) (xy 126.019052 -258.237736)
		)
		(stroke
			(width 0)
			(type solid)
		)
		(fill yes)
		(layer "In11.Cu")
		(net "M_H_CPU1_SA_CB<7>")
	)
	(gr_poly
		(pts
			(xy 126.024894 -267.551662) (xy 126.024894 -267.507212) (xy 125.669294 -267.507212) (xy 125.669294 -267.551662)
			(xy 125.716284 -267.704062) (xy 125.977904 -267.704062)
		)
		(stroke
			(width 0)
			(type solid)
		)
		(fill yes)
		(layer "In11.Cu")
		(net "M_H_CPU1_SA_DQ<24>")
	)
	(gr_poly
		(pts
			(xy 126.02845 -270.806926) (xy 126.02845 -270.76273) (xy 125.67285 -270.76273) (xy 125.67285 -270.806926)
			(xy 125.71984 -270.959326) (xy 125.98146 -270.959326)
		)
		(stroke
			(width 0)
			(type solid)
		)
		(fill yes)
		(layer "In11.Cu")
		(net "M_H_CPU1_SA_DQS_DP<2>")
	)
	(gr_poly
		(pts
			(xy 126.03099 -272.435066) (xy 126.03099 -272.390616) (xy 125.67539 -272.390616) (xy 125.67539 -272.435066)
			(xy 125.72238 -272.587466) (xy 125.984 -272.587466)
		)
		(stroke
			(width 0)
			(type solid)
		)
		(fill yes)
		(layer "In11.Cu")
		(net "M_H_CPU1_SA_DQ<16>")
	)
	(gr_poly
		(pts
			(xy 126.03099 -262.668258) (xy 126.03099 -262.623808) (xy 125.67539 -262.623808) (xy 125.67539 -262.668258)
			(xy 125.72238 -262.820658) (xy 125.984 -262.820658)
		)
		(stroke
			(width 0)
			(type solid)
		)
		(fill yes)
		(layer "In11.Cu")
		(net "M_H_CPU1_SA_CB<0>")
	)
	(gr_poly
		(pts
			(xy 126.03099 -257.784854) (xy 126.03099 -257.740404) (xy 125.67539 -257.740404) (xy 125.67539 -257.784854)
			(xy 125.72238 -257.937254) (xy 125.984 -257.937254)
		)
		(stroke
			(width 0)
			(type solid)
		)
		(fill yes)
		(layer "In11.Cu")
		(net "M_E_CPU1_ALERT_N")
	)
	(gr_poly
		(pts
			(xy 126.236222 -247.633998) (xy 126.274576 -247.6119) (xy 126.096776 -247.304052) (xy 126.058422 -247.32615)
			(xy 125.949964 -247.44299) (xy 126.080774 -247.669558)
		)
		(stroke
			(width 0)
			(type solid)
		)
		(fill yes)
		(layer "In11.Cu")
		(net "M_H_CPU1_SB_CA<0>")
	)
	(gr_poly
		(pts
			(xy 126.24181 -249.271536) (xy 126.280164 -249.249438) (xy 126.102364 -248.94159) (xy 126.06401 -248.963688)
			(xy 125.955552 -249.080528) (xy 126.086362 -249.307096)
		)
		(stroke
			(width 0)
			(type solid)
		)
		(fill yes)
		(layer "In11.Cu")
		(net "M_H_CPU1_CLK_DP<0>")
	)
	(gr_poly
		(pts
			(xy 126.349506 -248.647204) (xy 126.457964 -248.530364) (xy 126.327154 -248.303796) (xy 126.171706 -248.339356)
			(xy 126.133352 -248.361454) (xy 126.311152 -248.669302)
		)
		(stroke
			(width 0)
			(type solid)
		)
		(fill yes)
		(layer "In11.Cu")
		(net "M_H_CPU1_CLK_DN<0>")
	)
	(gr_poly
		(pts
			(xy 126.351792 -278.80183) (xy 126.390146 -278.779732) (xy 126.212346 -278.471884) (xy 126.173992 -278.493982)
			(xy 126.065534 -278.610822) (xy 126.196344 -278.83739)
		)
		(stroke
			(width 0)
			(type solid)
		)
		(fill yes)
		(layer "In11.Cu")
		(net "M_H_CPU1_SA_DQS_DP<1>")
	)
	(gr_poly
		(pts
			(xy 126.355856 -247.030494) (xy 126.464314 -246.913654) (xy 126.333504 -246.687086) (xy 126.178056 -246.722646)
			(xy 126.139702 -246.744744) (xy 126.317502 -247.052592)
		)
		(stroke
			(width 0)
			(type solid)
		)
		(fill yes)
		(layer "In11.Cu")
		(net "M_H_CPU1_SB_CA<1>")
	)
	(gr_poly
		(pts
			(xy 126.37897 -242.499642) (xy 126.33198 -242.347242) (xy 126.07036 -242.347242) (xy 126.02337 -242.499642)
			(xy 126.02337 -242.543838) (xy 126.37897 -242.543838)
		)
		(stroke
			(width 0)
			(type solid)
		)
		(fill yes)
		(layer "In11.Cu")
		(net "M_H_CPU1_SB_DQS_DN<9>")
	)
	(gr_poly
		(pts
			(xy 126.37897 -237.616238) (xy 126.33198 -237.463838) (xy 126.07036 -237.463838) (xy 126.02337 -237.616238)
			(xy 126.02337 -237.660434) (xy 126.37897 -237.660434)
		)
		(stroke
			(width 0)
			(type solid)
		)
		(fill yes)
		(layer "In11.Cu")
		(net "M_H_CPU1_SB_DQS_DN<0>")
	)
	(gr_poly
		(pts
			(xy 126.38151 -235.579666) (xy 126.38151 -235.535216) (xy 126.02591 -235.535216) (xy 126.02591 -235.579666)
			(xy 126.0729 -235.732066) (xy 126.33452 -235.732066)
		)
		(stroke
			(width 0)
			(type solid)
		)
		(fill yes)
		(layer "In11.Cu")
		(net "M_H_CPU1_SB_DQ<5>")
	)
	(gr_poly
		(pts
			(xy 126.385066 -243.718334) (xy 126.385066 -243.674138) (xy 126.029466 -243.674138) (xy 126.029466 -243.718334)
			(xy 126.076456 -243.870734) (xy 126.338076 -243.870734)
		)
		(stroke
			(width 0)
			(type solid)
		)
		(fill yes)
		(layer "In11.Cu")
		(net "M_H_CPU1_SB_CB<7>")
	)
	(gr_poly
		(pts
			(xy 126.385066 -238.83493) (xy 126.385066 -238.790734) (xy 126.029466 -238.790734) (xy 126.029466 -238.83493)
			(xy 126.076456 -238.98733) (xy 126.338076 -238.98733)
		)
		(stroke
			(width 0)
			(type solid)
		)
		(fill yes)
		(layer "In11.Cu")
		(net "M_H_CPU1_SB_DQ<1>")
	)
	(gr_poly
		(pts
			(xy 126.385066 -233.952034) (xy 126.385066 -233.907584) (xy 126.029466 -233.907584) (xy 126.029466 -233.952034)
			(xy 126.076456 -234.104434) (xy 126.338076 -234.104434)
		)
		(stroke
			(width 0)
			(type solid)
		)
		(fill yes)
		(layer "In11.Cu")
		(net "M_H_CPU1_SB_DQ<9>")
	)
	(gr_poly
		(pts
			(xy 126.385066 -229.06863) (xy 126.385066 -229.02418) (xy 126.029466 -229.02418) (xy 126.029466 -229.06863)
			(xy 126.076456 -229.22103) (xy 126.338076 -229.22103)
		)
		(stroke
			(width 0)
			(type solid)
		)
		(fill yes)
		(layer "In11.Cu")
		(net "M_H_CPU1_SB_DQ<27>")
	)
	(gr_poly
		(pts
			(xy 126.388368 -232.732834) (xy 126.341378 -232.580434) (xy 126.079758 -232.580434) (xy 126.032768 -232.732834)
			(xy 126.032768 -232.77703) (xy 126.388368 -232.77703)
		)
		(stroke
			(width 0)
			(type solid)
		)
		(fill yes)
		(layer "In11.Cu")
		(net "M_H_CPU1_SB_DQS_DN<1>")
	)
	(gr_poly
		(pts
			(xy 126.390908 -240.871502) (xy 126.343918 -240.719102) (xy 126.082298 -240.719102) (xy 126.035308 -240.871502)
			(xy 126.035308 -240.915698) (xy 126.390908 -240.915698)
		)
		(stroke
			(width 0)
			(type solid)
		)
		(fill yes)
		(layer "In11.Cu")
		(net "M_H_CPU1_SB_CB<2>")
	)
	(gr_poly
		(pts
			(xy 126.390908 -240.46307) (xy 126.390908 -240.418874) (xy 126.035308 -240.418874) (xy 126.035308 -240.46307)
			(xy 126.082298 -240.61547) (xy 126.343918 -240.61547)
		)
		(stroke
			(width 0)
			(type solid)
		)
		(fill yes)
		(layer "In11.Cu")
		(net "M_H_CPU1_SB_CB<1>")
	)
	(gr_poly
		(pts
			(xy 126.390908 -235.988098) (xy 126.343918 -235.835698) (xy 126.082298 -235.835698) (xy 126.035308 -235.988098)
			(xy 126.035308 -236.032294) (xy 126.390908 -236.032294)
		)
		(stroke
			(width 0)
			(type solid)
		)
		(fill yes)
		(layer "In11.Cu")
		(net "M_H_CPU1_SB_DQ<6>")
	)
	(gr_poly
		(pts
			(xy 126.393448 -244.126766) (xy 126.346458 -243.974366) (xy 126.084838 -243.974366) (xy 126.037848 -244.126766)
			(xy 126.037848 -244.171216) (xy 126.393448 -244.171216)
		)
		(stroke
			(width 0)
			(type solid)
		)
		(fill yes)
		(layer "In11.Cu")
		(net "M_H_CPU1_SB_CB<4>")
	)
	(gr_poly
		(pts
			(xy 126.393448 -239.243362) (xy 126.346458 -239.090962) (xy 126.084838 -239.090962) (xy 126.037848 -239.243362)
			(xy 126.037848 -239.287812) (xy 126.393448 -239.287812)
		)
		(stroke
			(width 0)
			(type solid)
		)
		(fill yes)
		(layer "In11.Cu")
		(net "M_H_CPU1_SB_DQ<2>")
	)
	(gr_poly
		(pts
			(xy 126.393448 -234.360466) (xy 126.346458 -234.208066) (xy 126.084838 -234.208066) (xy 126.037848 -234.360466)
			(xy 126.037848 -234.404662) (xy 126.393448 -234.404662)
		)
		(stroke
			(width 0)
			(type solid)
		)
		(fill yes)
		(layer "In11.Cu")
		(net "M_H_CPU1_SB_DQ<10>")
	)
	(gr_poly
		(pts
			(xy 126.393448 -231.104694) (xy 126.346458 -230.952294) (xy 126.084838 -230.952294) (xy 126.037848 -231.104694)
			(xy 126.037848 -231.14889) (xy 126.393448 -231.14889)
		)
		(stroke
			(width 0)
			(type solid)
		)
		(fill yes)
		(layer "In11.Cu")
		(net "M_H_CPU1_SB_DQ<14>")
	)
	(gr_poly
		(pts
			(xy 126.393448 -230.696262) (xy 126.393448 -230.652066) (xy 126.037848 -230.652066) (xy 126.037848 -230.696262)
			(xy 126.084838 -230.848662) (xy 126.346458 -230.848662)
		)
		(stroke
			(width 0)
			(type solid)
		)
		(fill yes)
		(layer "In11.Cu")
		(net "M_H_CPU1_SB_DQ<13>")
	)
	(gr_poly
		(pts
			(xy 126.393448 -229.477062) (xy 126.346458 -229.324662) (xy 126.084838 -229.324662) (xy 126.037848 -229.477062)
			(xy 126.037848 -229.521258) (xy 126.393448 -229.521258)
		)
		(stroke
			(width 0)
			(type solid)
		)
		(fill yes)
		(layer "In11.Cu")
		(net "M_H_CPU1_SB_DQ<24>")
	)
	(gr_poly
		(pts
			(xy 126.393448 -226.22129) (xy 126.346458 -226.06889) (xy 126.084838 -226.06889) (xy 126.037848 -226.22129)
			(xy 126.037848 -226.26574) (xy 126.393448 -226.26574)
		)
		(stroke
			(width 0)
			(type solid)
		)
		(fill yes)
		(layer "In11.Cu")
		(net "M_H_CPU1_SB_DQ<28>")
	)
	(gr_poly
		(pts
			(xy 126.393448 -225.813366) (xy 126.393448 -225.768916) (xy 126.037848 -225.768916) (xy 126.037848 -225.813366)
			(xy 126.084838 -225.965766) (xy 126.346458 -225.965766)
		)
		(stroke
			(width 0)
			(type solid)
		)
		(fill yes)
		(layer "In11.Cu")
		(net "M_H_CPU1_SB_DQ<31>")
	)
	(gr_poly
		(pts
			(xy 126.460504 -278.17953) (xy 126.568962 -278.06269) (xy 126.438152 -277.836122) (xy 126.282704 -277.871682)
			(xy 126.24435 -277.89378) (xy 126.42215 -278.201628)
		)
		(stroke
			(width 0)
			(type solid)
		)
		(fill yes)
		(layer "In11.Cu")
		(net "M_H_CPU1_SA_DQS_DN<1>")
	)
	(gr_poly
		(pts
			(xy 126.488952 -280.16835) (xy 126.441962 -280.01595) (xy 126.180342 -280.01595) (xy 126.133352 -280.16835)
			(xy 126.133352 -280.2128) (xy 126.488952 -280.2128)
		)
		(stroke
			(width 0)
			(type solid)
		)
		(fill yes)
		(layer "In11.Cu")
		(net "M_H_CPU1_SA_DQ<10>")
	)
	(gr_poly
		(pts
			(xy 126.49073 -270.40205) (xy 126.44374 -270.24965) (xy 126.18212 -270.24965) (xy 126.13513 -270.40205)
			(xy 126.13513 -270.446246) (xy 126.49073 -270.446246)
		)
		(stroke
			(width 0)
			(type solid)
		)
		(fill yes)
		(layer "In11.Cu")
		(net "M_H_CPU1_SA_DQS_DN<2>")
	)
	(gr_poly
		(pts
			(xy 126.491492 -268.77391) (xy 126.444502 -268.62151) (xy 126.182882 -268.62151) (xy 126.135892 -268.77391)
			(xy 126.135892 -268.81836) (xy 126.491492 -268.81836)
		)
		(stroke
			(width 0)
			(type solid)
		)
		(fill yes)
		(layer "In11.Cu")
		(net "M_H_CPU1_SA_DQ<22>")
	)
	(gr_poly
		(pts
			(xy 126.495048 -268.365478) (xy 126.495048 -268.321028) (xy 126.139448 -268.321028) (xy 126.139448 -268.365478)
			(xy 126.186438 -268.517878) (xy 126.448058 -268.517878)
		)
		(stroke
			(width 0)
			(type solid)
		)
		(fill yes)
		(layer "In11.Cu")
		(net "M_H_CPU1_SA_DQ<21>")
	)
	(gr_poly
		(pts
			(xy 126.495048 -263.891014) (xy 126.448058 -263.738614) (xy 126.186438 -263.738614) (xy 126.139448 -263.891014)
			(xy 126.139448 -263.93521) (xy 126.495048 -263.93521)
		)
		(stroke
			(width 0)
			(type solid)
		)
		(fill yes)
		(layer "In11.Cu")
		(net "M_H_CPU1_SA_DQ<30>")
	)
	(gr_poly
		(pts
			(xy 126.495048 -254.124206) (xy 126.448058 -253.971806) (xy 126.186438 -253.971806) (xy 126.139448 -254.124206)
			(xy 126.139448 -254.168402) (xy 126.495048 -254.168402)
		)
		(stroke
			(width 0)
			(type solid)
		)
		(fill yes)
		(layer "In11.Cu")
		(net "M_H_CPU1_SA_CA<3>")
	)
	(gr_poly
		(pts
			(xy 126.495302 -266.737846) (xy 126.495302 -266.693396) (xy 126.139702 -266.693396) (xy 126.139702 -266.737846)
			(xy 126.186692 -266.890246) (xy 126.448312 -266.890246)
		)
		(stroke
			(width 0)
			(type solid)
		)
		(fill yes)
		(layer "In11.Cu")
		(net "M_H_CPU1_SA_DQ<25>")
	)
	(gr_poly
		(pts
			(xy 126.50089 -279.759664) (xy 126.50089 -279.715468) (xy 126.14529 -279.715468) (xy 126.14529 -279.759664)
			(xy 126.19228 -279.912064) (xy 126.4539 -279.912064)
		)
		(stroke
			(width 0)
			(type solid)
		)
		(fill yes)
		(layer "In11.Cu")
		(net "M_H_CPU1_SA_DQ<9>")
	)
	(gr_poly
		(pts
			(xy 126.50089 -272.029174) (xy 126.4539 -271.876774) (xy 126.19228 -271.876774) (xy 126.14529 -272.029174)
			(xy 126.14529 -272.073624) (xy 126.50089 -272.073624)
		)
		(stroke
			(width 0)
			(type solid)
		)
		(fill yes)
		(layer "In11.Cu")
		(net "M_H_CPU1_SA_DQ<18>")
	)
	(gr_poly
		(pts
			(xy 126.50089 -271.62125) (xy 126.50089 -271.5768) (xy 126.14529 -271.5768) (xy 126.14529 -271.62125)
			(xy 126.19228 -271.77365) (xy 126.4539 -271.77365)
		)
		(stroke
			(width 0)
			(type solid)
		)
		(fill yes)
		(layer "In11.Cu")
		(net "M_H_CPU1_SA_DQ<17>")
	)
	(gr_poly
		(pts
			(xy 126.50089 -267.14577) (xy 126.4539 -266.99337) (xy 126.19228 -266.99337) (xy 126.14529 -267.14577)
			(xy 126.14529 -267.19022) (xy 126.50089 -267.19022)
		)
		(stroke
			(width 0)
			(type solid)
		)
		(fill yes)
		(layer "In11.Cu")
		(net "M_H_CPU1_SA_DQ<26>")
	)
	(gr_poly
		(pts
			(xy 126.50089 -265.518646) (xy 126.4539 -265.366246) (xy 126.19228 -265.366246) (xy 126.14529 -265.518646)
			(xy 126.14529 -265.562842) (xy 126.50089 -265.562842)
		)
		(stroke
			(width 0)
			(type solid)
		)
		(fill yes)
		(layer "In11.Cu")
		(net "M_H_CPU1_SA_DQS_DN<3>")
	)
	(gr_poly
		(pts
			(xy 126.50089 -262.262874) (xy 126.4539 -262.110474) (xy 126.19228 -262.110474) (xy 126.14529 -262.262874)
			(xy 126.14529 -262.30707) (xy 126.50089 -262.30707)
		)
		(stroke
			(width 0)
			(type solid)
		)
		(fill yes)
		(layer "In11.Cu")
		(net "M_H_CPU1_SA_CB<2>")
	)
	(gr_poly
		(pts
			(xy 126.50089 -261.854442) (xy 126.50089 -261.810246) (xy 126.14529 -261.810246) (xy 126.14529 -261.854442)
			(xy 126.19228 -262.006842) (xy 126.4539 -262.006842)
		)
		(stroke
			(width 0)
			(type solid)
		)
		(fill yes)
		(layer "In11.Cu")
		(net "M_H_CPU1_SA_CB<1>")
	)
	(gr_poly
		(pts
			(xy 126.50089 -260.635242) (xy 126.4539 -260.482842) (xy 126.19228 -260.482842) (xy 126.14529 -260.635242)
			(xy 126.14529 -260.679438) (xy 126.50089 -260.679438)
		)
		(stroke
			(width 0)
			(type solid)
		)
		(fill yes)
		(layer "In11.Cu")
		(net "M_H_CPU1_SA_DQS_DN<4>")
	)
	(gr_poly
		(pts
			(xy 126.50089 -257.37947) (xy 126.4539 -257.22707) (xy 126.19228 -257.22707) (xy 126.14529 -257.37947)
			(xy 126.14529 -257.423666) (xy 126.50089 -257.423666)
		)
		(stroke
			(width 0)
			(type solid)
		)
		(fill yes)
		(layer "In11.Cu")
		(net "M_H_CPU1_ALERT_N")
	)
	(gr_poly
		(pts
			(xy 126.50089 -256.971038) (xy 126.50089 -256.926842) (xy 126.14529 -256.926842) (xy 126.14529 -256.971038)
			(xy 126.19228 -257.123438) (xy 126.4539 -257.123438)
		)
		(stroke
			(width 0)
			(type solid)
		)
		(fill yes)
		(layer "In11.Cu")
		(net "M_H_CPU1_SA_CS_N<0>")
	)
	(gr_poly
		(pts
			(xy 126.50089 -255.751838) (xy 126.4539 -255.599438) (xy 126.19228 -255.599438) (xy 126.14529 -255.751838)
			(xy 126.14529 -255.796288) (xy 126.50089 -255.796288)
		)
		(stroke
			(width 0)
			(type solid)
		)
		(fill yes)
		(layer "In11.Cu")
		(net "M_H_CPU1_SA_CS_N<3>")
	)
	(gr_poly
		(pts
			(xy 126.50343 -273.248882) (xy 126.50343 -273.204686) (xy 126.14783 -273.204686) (xy 126.14783 -273.248882)
			(xy 126.19482 -273.401282) (xy 126.45644 -273.401282)
		)
		(stroke
			(width 0)
			(type solid)
		)
		(fill yes)
		(layer "In11.Cu")
		(net "M_H_CPU1_SA_DQ<13>")
	)
	(gr_poly
		(pts
			(xy 126.50343 -263.482582) (xy 126.50343 -263.438132) (xy 126.14783 -263.438132) (xy 126.14783 -263.482582)
			(xy 126.19482 -263.634982) (xy 126.45644 -263.634982)
		)
		(stroke
			(width 0)
			(type solid)
		)
		(fill yes)
		(layer "In11.Cu")
		(net "M_H_CPU1_SA_DQ<29>")
	)
	(gr_poly
		(pts
			(xy 126.50343 -259.007102) (xy 126.45644 -258.854702) (xy 126.19482 -258.854702) (xy 126.14783 -259.007102)
			(xy 126.14783 -259.051552) (xy 126.50343 -259.051552)
		)
		(stroke
			(width 0)
			(type solid)
		)
		(fill yes)
		(layer "In11.Cu")
		(net "M_H_CPU1_SA_CB<6>")
	)
	(gr_poly
		(pts
			(xy 126.50343 -258.599178) (xy 126.50343 -258.554728) (xy 126.14783 -258.554728) (xy 126.14783 -258.599178)
			(xy 126.19482 -258.751578) (xy 126.45644 -258.751578)
		)
		(stroke
			(width 0)
			(type solid)
		)
		(fill yes)
		(layer "In11.Cu")
		(net "M_H_CPU1_SA_CB<5>")
	)
	(gr_poly
		(pts
			(xy 126.711456 -248.456958) (xy 126.74981 -248.43486) (xy 126.57201 -248.127012) (xy 126.533656 -248.14911)
			(xy 126.425198 -248.26595) (xy 126.556008 -248.492518)
		)
		(stroke
			(width 0)
			(type solid)
		)
		(fill yes)
		(layer "In11.Cu")
		(net "M_H_CPU1_SB_CA<0>")
	)
	(gr_poly
		(pts
			(xy 126.816104 -276.350476) (xy 126.854458 -276.328378) (xy 126.676658 -276.02053) (xy 126.638304 -276.042628)
			(xy 126.529846 -276.159468) (xy 126.660656 -276.386036)
		)
		(stroke
			(width 0)
			(type solid)
		)
		(fill yes)
		(layer "In11.Cu")
		(net "M_H_CPU1_SA_DQS_DN<6>")
	)
	(gr_poly
		(pts
			(xy 126.820422 -274.729702) (xy 126.858776 -274.707604) (xy 126.680976 -274.399756) (xy 126.642622 -274.421854)
			(xy 126.534164 -274.538694) (xy 126.664974 -274.765262)
		)
		(stroke
			(width 0)
			(type solid)
		)
		(fill yes)
		(layer "In11.Cu")
		(net "M_H_CPU1_SA_DQ<12>")
	)
	(gr_poly
		(pts
			(xy 126.825756 -247.84431) (xy 126.934214 -247.72747) (xy 126.803404 -247.500902) (xy 126.647956 -247.536462)
			(xy 126.609602 -247.55856) (xy 126.787402 -247.866408)
		)
		(stroke
			(width 0)
			(type solid)
		)
		(fill yes)
		(layer "In11.Cu")
		(net "M_H_CPU1_SB_CA<1>")
	)
	(gr_poly
		(pts
			(xy 126.84633 -241.685318) (xy 126.79934 -241.532918) (xy 126.53772 -241.532918) (xy 126.49073 -241.685318)
			(xy 126.49073 -241.729514) (xy 126.84633 -241.729514)
		)
		(stroke
			(width 0)
			(type solid)
		)
		(fill yes)
		(layer "In11.Cu")
		(net "M_H_CPU1_SB_DQS_DP<4>")
	)
	(gr_poly
		(pts
			(xy 126.84633 -241.276886) (xy 126.84633 -241.23269) (xy 126.49073 -241.23269) (xy 126.49073 -241.276886)
			(xy 126.53772 -241.429286) (xy 126.79934 -241.429286)
		)
		(stroke
			(width 0)
			(type solid)
		)
		(fill yes)
		(layer "In11.Cu")
		(net "M_H_CPU1_SB_CB<0>")
	)
	(gr_poly
		(pts
			(xy 126.84633 -240.057178) (xy 126.79934 -239.904778) (xy 126.53772 -239.904778) (xy 126.49073 -240.057178)
			(xy 126.49073 -240.101628) (xy 126.84633 -240.101628)
		)
		(stroke
			(width 0)
			(type solid)
		)
		(fill yes)
		(layer "In11.Cu")
		(net "M_H_CPU1_SB_CB<3>")
	)
	(gr_poly
		(pts
			(xy 126.84633 -239.649254) (xy 126.84633 -239.604804) (xy 126.49073 -239.604804) (xy 126.49073 -239.649254)
			(xy 126.53772 -239.801654) (xy 126.79934 -239.801654)
		)
		(stroke
			(width 0)
			(type solid)
		)
		(fill yes)
		(layer "In11.Cu")
		(net "M_H_CPU1_SB_DQ<0>")
	)
	(gr_poly
		(pts
			(xy 126.84633 -236.801914) (xy 126.79934 -236.649514) (xy 126.53772 -236.649514) (xy 126.49073 -236.801914)
			(xy 126.49073 -236.84611) (xy 126.84633 -236.84611)
		)
		(stroke
			(width 0)
			(type solid)
		)
		(fill yes)
		(layer "In11.Cu")
		(net "M_H_CPU1_SB_DQS_DP<5>")
	)
	(gr_poly
		(pts
			(xy 126.84633 -236.39399) (xy 126.84633 -236.34954) (xy 126.49073 -236.34954) (xy 126.49073 -236.39399)
			(xy 126.53772 -236.54639) (xy 126.79934 -236.54639)
		)
		(stroke
			(width 0)
			(type solid)
		)
		(fill yes)
		(layer "In11.Cu")
		(net "M_H_CPU1_SB_DQ<4>")
	)
	(gr_poly
		(pts
			(xy 126.84633 -234.76585) (xy 126.84633 -234.721654) (xy 126.49073 -234.721654) (xy 126.49073 -234.76585)
			(xy 126.53772 -234.91825) (xy 126.79934 -234.91825)
		)
		(stroke
			(width 0)
			(type solid)
		)
		(fill yes)
		(layer "In11.Cu")
		(net "M_H_CPU1_SB_DQ<8>")
	)
	(gr_poly
		(pts
			(xy 126.84633 -231.510586) (xy 126.84633 -231.466136) (xy 126.49073 -231.466136) (xy 126.49073 -231.510586)
			(xy 126.53772 -231.662986) (xy 126.79934 -231.662986)
		)
		(stroke
			(width 0)
			(type solid)
		)
		(fill yes)
		(layer "In11.Cu")
		(net "M_H_CPU1_SB_DQ<12>")
	)
	(gr_poly
		(pts
			(xy 126.84633 -230.290878) (xy 126.79934 -230.138478) (xy 126.53772 -230.138478) (xy 126.49073 -230.290878)
			(xy 126.49073 -230.335074) (xy 126.84633 -230.335074)
		)
		(stroke
			(width 0)
			(type solid)
		)
		(fill yes)
		(layer "In11.Cu")
		(net "M_H_CPU1_SB_DQ<15>")
	)
	(gr_poly
		(pts
			(xy 126.84633 -229.882446) (xy 126.84633 -229.83825) (xy 126.49073 -229.83825) (xy 126.49073 -229.882446)
			(xy 126.53772 -230.034846) (xy 126.79934 -230.034846)
		)
		(stroke
			(width 0)
			(type solid)
		)
		(fill yes)
		(layer "In11.Cu")
		(net "M_H_CPU1_SB_DQ<26>")
	)
	(gr_poly
		(pts
			(xy 126.84633 -225.407474) (xy 126.79934 -225.255074) (xy 126.53772 -225.255074) (xy 126.49073 -225.407474)
			(xy 126.49073 -225.45167) (xy 126.84633 -225.45167)
		)
		(stroke
			(width 0)
			(type solid)
		)
		(fill yes)
		(layer "In11.Cu")
		(net "M_H_CPU1_SB_DQ<29>")
	)
	(gr_poly
		(pts
			(xy 126.846584 -233.546142) (xy 126.799594 -233.393742) (xy 126.537974 -233.393742) (xy 126.490984 -233.546142)
			(xy 126.490984 -233.590592) (xy 126.846584 -233.590592)
		)
		(stroke
			(width 0)
			(type solid)
		)
		(fill yes)
		(layer "In11.Cu")
		(net "M_H_CPU1_SB_DQ<11>")
	)
	(gr_poly
		(pts
			(xy 126.84887 -244.532658) (xy 126.84887 -244.488208) (xy 126.49327 -244.488208) (xy 126.49327 -244.532658)
			(xy 126.54026 -244.685058) (xy 126.80188 -244.685058)
		)
		(stroke
			(width 0)
			(type solid)
		)
		(fill yes)
		(layer "In11.Cu")
		(net "M_H_CPU1_SB_CB<6>")
	)
	(gr_poly
		(pts
			(xy 126.84887 -243.313458) (xy 126.80188 -243.161058) (xy 126.54026 -243.161058) (xy 126.49327 -243.313458)
			(xy 126.49327 -243.357654) (xy 126.84887 -243.357654)
		)
		(stroke
			(width 0)
			(type solid)
		)
		(fill yes)
		(layer "In11.Cu")
		(net "M_H_CPU1_SB_CB<5>")
	)
	(gr_poly
		(pts
			(xy 126.84887 -238.430054) (xy 126.80188 -238.277654) (xy 126.54026 -238.277654) (xy 126.49327 -238.430054)
			(xy 126.49327 -238.47425) (xy 126.84887 -238.47425)
		)
		(stroke
			(width 0)
			(type solid)
		)
		(fill yes)
		(layer "In11.Cu")
		(net "M_H_CPU1_SB_DQ<3>")
	)
	(gr_poly
		(pts
			(xy 126.84887 -238.021114) (xy 126.84887 -237.976918) (xy 126.49327 -237.976918) (xy 126.49327 -238.021114)
			(xy 126.54026 -238.173514) (xy 126.80188 -238.173514)
		)
		(stroke
			(width 0)
			(type solid)
		)
		(fill yes)
		(layer "In11.Cu")
		(net "M_H_CPU1_SB_DQS_DP<0>")
	)
	(gr_poly
		(pts
			(xy 126.84887 -228.663246) (xy 126.80188 -228.510846) (xy 126.54026 -228.510846) (xy 126.49327 -228.663246)
			(xy 126.49327 -228.707696) (xy 126.84887 -228.707696)
		)
		(stroke
			(width 0)
			(type solid)
		)
		(fill yes)
		(layer "In11.Cu")
		(net "M_H_CPU1_SB_DQ<25>")
	)
	(gr_poly
		(pts
			(xy 126.84887 -228.254814) (xy 126.84887 -228.210364) (xy 126.49327 -228.210364) (xy 126.49327 -228.254814)
			(xy 126.54026 -228.407214) (xy 126.80188 -228.407214)
		)
		(stroke
			(width 0)
			(type solid)
		)
		(fill yes)
		(layer "In11.Cu")
		(net "M_H_CPU1_SB_DQS_DN<8>")
	)
	(gr_poly
		(pts
			(xy 126.84887 -227.035106) (xy 126.80188 -226.882706) (xy 126.54026 -226.882706) (xy 126.49327 -227.035106)
			(xy 126.49327 -227.079556) (xy 126.84887 -227.079556)
		)
		(stroke
			(width 0)
			(type solid)
		)
		(fill yes)
		(layer "In11.Cu")
		(net "M_H_CPU1_SB_DQS_DN<3>")
	)
	(gr_poly
		(pts
			(xy 126.84887 -226.627182) (xy 126.84887 -226.582732) (xy 126.49327 -226.582732) (xy 126.49327 -226.627182)
			(xy 126.54026 -226.779582) (xy 126.80188 -226.779582)
		)
		(stroke
			(width 0)
			(type solid)
		)
		(fill yes)
		(layer "In11.Cu")
		(net "M_H_CPU1_SB_DQ<30>")
	)
	(gr_poly
		(pts
			(xy 126.85268 -233.13771) (xy 126.85268 -233.093514) (xy 126.49708 -233.093514) (xy 126.49708 -233.13771)
			(xy 126.54407 -233.29011) (xy 126.80569 -233.29011)
		)
		(stroke
			(width 0)
			(type solid)
		)
		(fill yes)
		(layer "In11.Cu")
		(net "M_H_CPU1_SB_DQS_DP<1>")
	)
	(gr_poly
		(pts
			(xy 126.854204 -231.919018) (xy 126.807214 -231.766618) (xy 126.545594 -231.766618) (xy 126.498604 -231.919018)
			(xy 126.498604 -231.963214) (xy 126.854204 -231.963214)
		)
		(stroke
			(width 0)
			(type solid)
		)
		(fill yes)
		(layer "In11.Cu")
		(net "M_H_CPU1_SB_DQS_DP<6>")
	)
	(gr_poly
		(pts
			(xy 126.858268 -235.174282) (xy 126.811278 -235.021882) (xy 126.549658 -235.021882) (xy 126.502668 -235.174282)
			(xy 126.502668 -235.218732) (xy 126.858268 -235.218732)
		)
		(stroke
			(width 0)
			(type solid)
		)
		(fill yes)
		(layer "In11.Cu")
		(net "M_H_CPU1_SB_DQ<7>")
	)
	(gr_poly
		(pts
			(xy 126.860808 -242.904518) (xy 126.860808 -242.860322) (xy 126.505208 -242.860322) (xy 126.505208 -242.904518)
			(xy 126.552198 -243.056918) (xy 126.813818 -243.056918)
		)
		(stroke
			(width 0)
			(type solid)
		)
		(fill yes)
		(layer "In11.Cu")
		(net "M_H_CPU1_SB_DQS_DP<9>")
	)
	(gr_poly
		(pts
			(xy 126.93142 -274.111974) (xy 127.039878 -273.995134) (xy 126.909068 -273.768566) (xy 126.75362 -273.804126)
			(xy 126.715266 -273.826224) (xy 126.893066 -274.134072)
		)
		(stroke
			(width 0)
			(type solid)
		)
		(fill yes)
		(layer "In11.Cu")
		(net "M_H_CPU1_SA_DQ<14>")
	)
	(gr_poly
		(pts
			(xy 126.956312 -278.946356) (xy 126.956312 -278.901906) (xy 126.600712 -278.901906) (xy 126.600712 -278.946356)
			(xy 126.647702 -279.098756) (xy 126.909322 -279.098756)
		)
		(stroke
			(width 0)
			(type solid)
		)
		(fill yes)
		(layer "In11.Cu")
		(net "M_H_CPU1_SA_DQS_DP<1>")
	)
	(gr_poly
		(pts
			(xy 126.956312 -272.843498) (xy 126.909322 -272.691098) (xy 126.647702 -272.691098) (xy 126.600712 -272.843498)
			(xy 126.600712 -272.887694) (xy 126.956312 -272.887694)
		)
		(stroke
			(width 0)
			(type solid)
		)
		(fill yes)
		(layer "In11.Cu")
		(net "M_H_CPU1_SA_DQ<15>")
	)
	(gr_poly
		(pts
			(xy 126.956312 -272.435066) (xy 126.956312 -272.39087) (xy 126.600712 -272.39087) (xy 126.600712 -272.435066)
			(xy 126.647702 -272.587466) (xy 126.909322 -272.587466)
		)
		(stroke
			(width 0)
			(type solid)
		)
		(fill yes)
		(layer "In11.Cu")
		(net "M_H_CPU1_SA_DQ<16>")
	)
	(gr_poly
		(pts
			(xy 126.956312 -271.215358) (xy 126.909322 -271.062958) (xy 126.647702 -271.062958) (xy 126.600712 -271.215358)
			(xy 126.600712 -271.259808) (xy 126.956312 -271.259808)
		)
		(stroke
			(width 0)
			(type solid)
		)
		(fill yes)
		(layer "In11.Cu")
		(net "M_H_CPU1_SA_DQ<19>")
	)
	(gr_poly
		(pts
			(xy 126.956312 -267.960094) (xy 126.909322 -267.807694) (xy 126.647702 -267.807694) (xy 126.600712 -267.960094)
			(xy 126.600712 -268.00429) (xy 126.956312 -268.00429)
		)
		(stroke
			(width 0)
			(type solid)
		)
		(fill yes)
		(layer "In11.Cu")
		(net "M_H_CPU1_SA_DQ<23>")
	)
	(gr_poly
		(pts
			(xy 126.956312 -267.551662) (xy 126.956312 -267.507466) (xy 126.600712 -267.507466) (xy 126.600712 -267.551662)
			(xy 126.647702 -267.704062) (xy 126.909322 -267.704062)
		)
		(stroke
			(width 0)
			(type solid)
		)
		(fill yes)
		(layer "In11.Cu")
		(net "M_H_CPU1_SA_DQ<24>")
	)
	(gr_poly
		(pts
			(xy 126.956312 -266.331954) (xy 126.909322 -266.179554) (xy 126.647702 -266.179554) (xy 126.600712 -266.331954)
			(xy 126.600712 -266.376404) (xy 126.956312 -266.376404)
		)
		(stroke
			(width 0)
			(type solid)
		)
		(fill yes)
		(layer "In11.Cu")
		(net "M_H_CPU1_SA_DQ<27>")
	)
	(gr_poly
		(pts
			(xy 126.956312 -263.07669) (xy 126.909322 -262.92429) (xy 126.647702 -262.92429) (xy 126.600712 -263.07669)
			(xy 126.600712 -263.120886) (xy 126.956312 -263.120886)
		)
		(stroke
			(width 0)
			(type solid)
		)
		(fill yes)
		(layer "In11.Cu")
		(net "M_H_CPU1_SA_DQ<31>")
	)
	(gr_poly
		(pts
			(xy 126.956312 -262.668258) (xy 126.956312 -262.624062) (xy 126.600712 -262.624062) (xy 126.600712 -262.668258)
			(xy 126.647702 -262.820658) (xy 126.909322 -262.820658)
		)
		(stroke
			(width 0)
			(type solid)
		)
		(fill yes)
		(layer "In11.Cu")
		(net "M_H_CPU1_SA_CB<0>")
	)
	(gr_poly
		(pts
			(xy 126.956312 -261.449058) (xy 126.909322 -261.296658) (xy 126.647702 -261.296658) (xy 126.600712 -261.449058)
			(xy 126.600712 -261.493254) (xy 126.956312 -261.493254)
		)
		(stroke
			(width 0)
			(type solid)
		)
		(fill yes)
		(layer "In11.Cu")
		(net "M_H_CPU1_SA_CB<3>")
	)
	(gr_poly
		(pts
			(xy 126.956312 -259.412994) (xy 126.956312 -259.368544) (xy 126.600712 -259.368544) (xy 126.600712 -259.412994)
			(xy 126.647702 -259.565394) (xy 126.909322 -259.565394)
		)
		(stroke
			(width 0)
			(type solid)
		)
		(fill yes)
		(layer "In11.Cu")
		(net "M_H_CPU1_SA_CB<4>")
	)
	(gr_poly
		(pts
			(xy 126.956312 -256.565654) (xy 126.909322 -256.413254) (xy 126.647702 -256.413254) (xy 126.600712 -256.565654)
			(xy 126.600712 -256.60985) (xy 126.956312 -256.60985)
		)
		(stroke
			(width 0)
			(type solid)
		)
		(fill yes)
		(layer "In11.Cu")
		(net "M_H_CPU1_SA_CS_N<1>")
	)
	(gr_poly
		(pts
			(xy 126.958852 -264.29589) (xy 126.958852 -264.251694) (xy 126.603252 -264.251694) (xy 126.603252 -264.29589)
			(xy 126.650242 -264.44829) (xy 126.911862 -264.44829)
		)
		(stroke
			(width 0)
			(type solid)
		)
		(fill yes)
		(layer "In11.Cu")
		(net "M_H_CPU1_SA_DQ<28>")
	)
	(gr_poly
		(pts
			(xy 126.958852 -258.193286) (xy 126.911862 -258.040886) (xy 126.650242 -258.040886) (xy 126.603252 -258.193286)
			(xy 126.603252 -258.237482) (xy 126.958852 -258.237482)
		)
		(stroke
			(width 0)
			(type solid)
		)
		(fill yes)
		(layer "In11.Cu")
		(net "M_H_CPU1_SA_CB<7>")
	)
	(gr_poly
		(pts
			(xy 126.958852 -257.784854) (xy 126.958852 -257.740658) (xy 126.603252 -257.740658) (xy 126.603252 -257.784854)
			(xy 126.650242 -257.937254) (xy 126.911862 -257.937254)
		)
		(stroke
			(width 0)
			(type solid)
		)
		(fill yes)
		(layer "In11.Cu")
		(net "M_E_CPU1_ALERT_N")
	)
	(gr_poly
		(pts
			(xy 126.958852 -254.529082) (xy 126.958852 -254.484886) (xy 126.603252 -254.484886) (xy 126.603252 -254.529082)
			(xy 126.650242 -254.681482) (xy 126.911862 -254.681482)
		)
		(stroke
			(width 0)
			(type solid)
		)
		(fill yes)
		(layer "In11.Cu")
		(net "M_H_CPU1_SA_CA<2>")
	)
	(gr_poly
		(pts
			(xy 126.96444 -269.179294) (xy 126.96444 -269.134844) (xy 126.60884 -269.134844) (xy 126.60884 -269.179294)
			(xy 126.65583 -269.331694) (xy 126.91745 -269.331694)
		)
		(stroke
			(width 0)
			(type solid)
		)
		(fill yes)
		(layer "In11.Cu")
		(net "M_H_CPU1_SA_DQ<20>")
	)
	(gr_poly
		(pts
			(xy 126.96444 -259.821426) (xy 126.91745 -259.669026) (xy 126.65583 -259.669026) (xy 126.60884 -259.821426)
			(xy 126.60884 -259.865876) (xy 126.96444 -259.865876)
		)
		(stroke
			(width 0)
			(type solid)
		)
		(fill yes)
		(layer "In11.Cu")
		(net "M_H_CPU1_SA_DQS_DP<9>")
	)
	(gr_poly
		(pts
			(xy 126.964694 -279.354788) (xy 126.917704 -279.202388) (xy 126.656084 -279.202388) (xy 126.609094 -279.354788)
			(xy 126.609094 -279.398984) (xy 126.964694 -279.398984)
		)
		(stroke
			(width 0)
			(type solid)
		)
		(fill yes)
		(layer "In11.Cu")
		(net "M_H_CPU1_SA_DQ<11>")
	)
	(gr_poly
		(pts
			(xy 126.964694 -265.92403) (xy 126.964694 -265.87958) (xy 126.609094 -265.87958) (xy 126.609094 -265.92403)
			(xy 126.656084 -266.07643) (xy 126.917704 -266.07643)
		)
		(stroke
			(width 0)
			(type solid)
		)
		(fill yes)
		(layer "In11.Cu")
		(net "M_H_CPU1_SA_DQS_DP<3>")
	)
	(gr_poly
		(pts
			(xy 126.964694 -261.040626) (xy 126.964694 -260.996176) (xy 126.609094 -260.996176) (xy 126.609094 -261.040626)
			(xy 126.656084 -261.193026) (xy 126.917704 -261.193026)
		)
		(stroke
			(width 0)
			(type solid)
		)
		(fill yes)
		(layer "In11.Cu")
		(net "M_H_CPU1_SA_DQS_DP<4>")
	)
	(gr_poly
		(pts
			(xy 126.964694 -256.157222) (xy 126.964694 -256.112772) (xy 126.609094 -256.112772) (xy 126.609094 -256.157222)
			(xy 126.656084 -256.309622) (xy 126.917704 -256.309622)
		)
		(stroke
			(width 0)
			(type solid)
		)
		(fill yes)
		(layer "In11.Cu")
		(net "M_H_CPU1_SA_CS_N<2>")
	)
	(gr_poly
		(pts
			(xy 126.964948 -269.588234) (xy 126.917958 -269.435834) (xy 126.656338 -269.435834) (xy 126.609348 -269.588234)
			(xy 126.609348 -269.632684) (xy 126.964948 -269.632684)
		)
		(stroke
			(width 0)
			(type solid)
		)
		(fill yes)
		(layer "In11.Cu")
		(net "M_H_CPU1_SA_DQS_DP<7>")
	)
	(gr_poly
		(pts
			(xy 126.96825 -270.806926) (xy 126.96825 -270.76273) (xy 126.61265 -270.76273) (xy 126.61265 -270.806926)
			(xy 126.65964 -270.959326) (xy 126.92126 -270.959326)
		)
		(stroke
			(width 0)
			(type solid)
		)
		(fill yes)
		(layer "In11.Cu")
		(net "M_H_CPU1_SA_DQS_DP<2>")
	)
	(gr_poly
		(pts
			(xy 126.969012 -264.70483) (xy 126.922022 -264.55243) (xy 126.660402 -264.55243) (xy 126.613412 -264.70483)
			(xy 126.613412 -264.749026) (xy 126.969012 -264.749026)
		)
		(stroke
			(width 0)
			(type solid)
		)
		(fill yes)
		(layer "In11.Cu")
		(net "M_H_CPU1_SA_DQS_DP<8>")
	)
	(gr_poly
		(pts
			(xy 126.97079 -280.573988) (xy 126.97079 -280.529538) (xy 126.61519 -280.529538) (xy 126.61519 -280.573988)
			(xy 126.66218 -280.726388) (xy 126.9238 -280.726388)
		)
		(stroke
			(width 0)
			(type solid)
		)
		(fill yes)
		(layer "In11.Cu")
		(net "M_H_CPU1_SA_DQ<8>")
	)
	(gr_poly
		(pts
			(xy 126.97079 -254.938022) (xy 126.9238 -254.785622) (xy 126.66218 -254.785622) (xy 126.61519 -254.938022)
			(xy 126.61519 -254.982218) (xy 126.97079 -254.982218)
		)
		(stroke
			(width 0)
			(type solid)
		)
		(fill yes)
		(layer "In11.Cu")
		(net "M_H_CPU1_SA_CA<0>")
	)
	(gr_poly
		(pts
			(xy 127.291338 -275.54555) (xy 127.329692 -275.523452) (xy 127.151892 -275.215604) (xy 127.113538 -275.237702)
			(xy 127.00508 -275.354542) (xy 127.13589 -275.58111)
		)
		(stroke
			(width 0)
			(type solid)
		)
		(fill yes)
		(layer "In11.Cu")
		(net "M_H_CPU1_SA_DQ<12>")
	)
	(gr_poly
		(pts
			(xy 127.291592 -277.173944) (xy 127.329946 -277.151846) (xy 127.152146 -276.843998) (xy 127.113792 -276.866096)
			(xy 127.005334 -276.982936) (xy 127.136144 -277.209504)
		)
		(stroke
			(width 0)
			(type solid)
		)
		(fill yes)
		(layer "In11.Cu")
		(net "M_H_CPU1_SA_DQS_DN<6>")
	)
	(gr_poly
		(pts
			(xy 127.291592 -273.918426) (xy 127.329946 -273.896328) (xy 127.152146 -273.58848) (xy 127.113792 -273.610578)
			(xy 127.005334 -273.727418) (xy 127.136144 -273.953986)
		)
		(stroke
			(width 0)
			(type solid)
		)
		(fill yes)
		(layer "In11.Cu")
		(net "M_H_CPU1_SA_DQ<13>")
	)
	(gr_poly
		(pts
			(xy 127.31877 -227.44049) (xy 127.31877 -227.396294) (xy 126.96317 -227.396294) (xy 126.96317 -227.44049)
			(xy 127.01016 -227.59289) (xy 127.27178 -227.59289)
		)
		(stroke
			(width 0)
			(type solid)
		)
		(fill yes)
		(layer "In11.Cu")
		(net "M_H_CPU1_SB_DQS_DP<3>")
	)
	(gr_poly
		(pts
			(xy 127.32131 -235.579666) (xy 127.32131 -235.535216) (xy 126.96571 -235.535216) (xy 126.96571 -235.579666)
			(xy 127.0127 -235.732066) (xy 127.27432 -235.732066)
		)
		(stroke
			(width 0)
			(type solid)
		)
		(fill yes)
		(layer "In11.Cu")
		(net "M_H_CPU1_SB_DQ<5>")
	)
	(gr_poly
		(pts
			(xy 127.324866 -244.127274) (xy 127.277876 -243.974874) (xy 127.016256 -243.974874) (xy 126.969266 -244.127274)
			(xy 126.969266 -244.17147) (xy 127.324866 -244.17147)
		)
		(stroke
			(width 0)
			(type solid)
		)
		(fill yes)
		(layer "In11.Cu")
		(net "M_H_CPU1_SB_CB<4>")
	)
	(gr_poly
		(pts
			(xy 127.324866 -226.221798) (xy 127.277876 -226.069398) (xy 127.016256 -226.069398) (xy 126.969266 -226.221798)
			(xy 126.969266 -226.265994) (xy 127.324866 -226.265994)
		)
		(stroke
			(width 0)
			(type solid)
		)
		(fill yes)
		(layer "In11.Cu")
		(net "M_H_CPU1_SB_DQ<28>")
	)
	(gr_poly
		(pts
			(xy 127.330708 -242.499134) (xy 127.283718 -242.346734) (xy 127.022098 -242.346734) (xy 126.975108 -242.499134)
			(xy 126.975108 -242.543584) (xy 127.330708 -242.543584)
		)
		(stroke
			(width 0)
			(type solid)
		)
		(fill yes)
		(layer "In11.Cu")
		(net "M_H_CPU1_SB_DQS_DN<9>")
	)
	(gr_poly
		(pts
			(xy 127.330708 -232.732326) (xy 127.283718 -232.579926) (xy 127.022098 -232.579926) (xy 126.975108 -232.732326)
			(xy 126.975108 -232.776776) (xy 127.330708 -232.776776)
		)
		(stroke
			(width 0)
			(type solid)
		)
		(fill yes)
		(layer "In11.Cu")
		(net "M_H_CPU1_SB_DQS_DN<1>")
	)
	(gr_poly
		(pts
			(xy 127.330708 -232.324402) (xy 127.330708 -232.279952) (xy 126.975108 -232.279952) (xy 126.975108 -232.324402)
			(xy 127.022098 -232.476802) (xy 127.283718 -232.476802)
		)
		(stroke
			(width 0)
			(type solid)
		)
		(fill yes)
		(layer "In11.Cu")
		(net "M_H_CPU1_SB_DQS_DN<6>")
	)
	(gr_poly
		(pts
			(xy 127.330708 -227.84943) (xy 127.283718 -227.69703) (xy 127.022098 -227.69703) (xy 126.975108 -227.84943)
			(xy 126.975108 -227.893626) (xy 127.330708 -227.893626)
		)
		(stroke
			(width 0)
			(type solid)
		)
		(fill yes)
		(layer "In11.Cu")
		(net "M_H_CPU1_SB_DQS_DP<8>")
	)
	(gr_poly
		(pts
			(xy 127.333248 -248.602246) (xy 127.333248 -248.557796) (xy 126.977648 -248.557796) (xy 126.977648 -248.602246)
			(xy 127.024638 -248.754646) (xy 127.286258 -248.754646)
		)
		(stroke
			(width 0)
			(type solid)
		)
		(fill yes)
		(layer "In11.Cu")
		(net "M_H_CPU1_SB_CA<0>")
	)
	(gr_poly
		(pts
			(xy 127.333248 -243.718842) (xy 127.333248 -243.674392) (xy 126.977648 -243.674392) (xy 126.977648 -243.718842)
			(xy 127.024638 -243.871242) (xy 127.286258 -243.871242)
		)
		(stroke
			(width 0)
			(type solid)
		)
		(fill yes)
		(layer "In11.Cu")
		(net "M_H_CPU1_SB_CB<7>")
	)
	(gr_poly
		(pts
			(xy 127.333248 -242.09121) (xy 127.333248 -242.04676) (xy 126.977648 -242.04676) (xy 126.977648 -242.09121)
			(xy 127.024638 -242.24361) (xy 127.286258 -242.24361)
		)
		(stroke
			(width 0)
			(type solid)
		)
		(fill yes)
		(layer "In11.Cu")
		(net "M_H_CPU1_SB_DQS_DN<4>")
	)
	(gr_poly
		(pts
			(xy 127.333248 -240.871502) (xy 127.286258 -240.719102) (xy 127.024638 -240.719102) (xy 126.977648 -240.871502)
			(xy 126.977648 -240.915698) (xy 127.333248 -240.915698)
		)
		(stroke
			(width 0)
			(type solid)
		)
		(fill yes)
		(layer "In11.Cu")
		(net "M_H_CPU1_SB_CB<2>")
	)
	(gr_poly
		(pts
			(xy 127.333248 -240.46307) (xy 127.333248 -240.418874) (xy 126.977648 -240.418874) (xy 126.977648 -240.46307)
			(xy 127.024638 -240.61547) (xy 127.286258 -240.61547)
		)
		(stroke
			(width 0)
			(type solid)
		)
		(fill yes)
		(layer "In11.Cu")
		(net "M_H_CPU1_SB_CB<1>")
	)
	(gr_poly
		(pts
			(xy 127.333248 -239.243362) (xy 127.286258 -239.090962) (xy 127.024638 -239.090962) (xy 126.977648 -239.243362)
			(xy 126.977648 -239.287812) (xy 127.333248 -239.287812)
		)
		(stroke
			(width 0)
			(type solid)
		)
		(fill yes)
		(layer "In11.Cu")
		(net "M_H_CPU1_SB_DQ<2>")
	)
	(gr_poly
		(pts
			(xy 127.333248 -238.835438) (xy 127.333248 -238.790988) (xy 126.977648 -238.790988) (xy 126.977648 -238.835438)
			(xy 127.024638 -238.987838) (xy 127.286258 -238.987838)
		)
		(stroke
			(width 0)
			(type solid)
		)
		(fill yes)
		(layer "In11.Cu")
		(net "M_H_CPU1_SB_DQ<1>")
	)
	(gr_poly
		(pts
			(xy 127.333248 -237.61573) (xy 127.286258 -237.46333) (xy 127.024638 -237.46333) (xy 126.977648 -237.61573)
			(xy 126.977648 -237.659926) (xy 127.333248 -237.659926)
		)
		(stroke
			(width 0)
			(type solid)
		)
		(fill yes)
		(layer "In11.Cu")
		(net "M_H_CPU1_SB_DQS_DN<0>")
	)
	(gr_poly
		(pts
			(xy 127.333248 -237.207806) (xy 127.333248 -237.163356) (xy 126.977648 -237.163356) (xy 126.977648 -237.207806)
			(xy 127.024638 -237.360206) (xy 127.286258 -237.360206)
		)
		(stroke
			(width 0)
			(type solid)
		)
		(fill yes)
		(layer "In11.Cu")
		(net "M_H_CPU1_SB_DQS_DN<5>")
	)
	(gr_poly
		(pts
			(xy 127.333248 -235.988098) (xy 127.286258 -235.835698) (xy 127.024638 -235.835698) (xy 126.977648 -235.988098)
			(xy 126.977648 -236.032294) (xy 127.333248 -236.032294)
		)
		(stroke
			(width 0)
			(type solid)
		)
		(fill yes)
		(layer "In11.Cu")
		(net "M_H_CPU1_SB_DQ<6>")
	)
	(gr_poly
		(pts
			(xy 127.333248 -234.360466) (xy 127.286258 -234.208066) (xy 127.024638 -234.208066) (xy 126.977648 -234.360466)
			(xy 126.977648 -234.404662) (xy 127.333248 -234.404662)
		)
		(stroke
			(width 0)
			(type solid)
		)
		(fill yes)
		(layer "In11.Cu")
		(net "M_H_CPU1_SB_DQ<10>")
	)
	(gr_poly
		(pts
			(xy 127.333248 -233.952034) (xy 127.333248 -233.907838) (xy 126.977648 -233.907838) (xy 126.977648 -233.952034)
			(xy 127.024638 -234.104434) (xy 127.286258 -234.104434)
		)
		(stroke
			(width 0)
			(type solid)
		)
		(fill yes)
		(layer "In11.Cu")
		(net "M_H_CPU1_SB_DQ<9>")
	)
	(gr_poly
		(pts
			(xy 127.333248 -231.104694) (xy 127.286258 -230.952294) (xy 127.024638 -230.952294) (xy 126.977648 -231.104694)
			(xy 126.977648 -231.14889) (xy 127.333248 -231.14889)
		)
		(stroke
			(width 0)
			(type solid)
		)
		(fill yes)
		(layer "In11.Cu")
		(net "M_H_CPU1_SB_DQ<14>")
	)
	(gr_poly
		(pts
			(xy 127.333248 -230.696262) (xy 127.333248 -230.652066) (xy 126.977648 -230.652066) (xy 126.977648 -230.696262)
			(xy 127.024638 -230.848662) (xy 127.286258 -230.848662)
		)
		(stroke
			(width 0)
			(type solid)
		)
		(fill yes)
		(layer "In11.Cu")
		(net "M_H_CPU1_SB_DQ<13>")
	)
	(gr_poly
		(pts
			(xy 127.333248 -229.477062) (xy 127.286258 -229.324662) (xy 127.024638 -229.324662) (xy 126.977648 -229.477062)
			(xy 126.977648 -229.521258) (xy 127.333248 -229.521258)
		)
		(stroke
			(width 0)
			(type solid)
		)
		(fill yes)
		(layer "In11.Cu")
		(net "M_H_CPU1_SB_DQ<24>")
	)
	(gr_poly
		(pts
			(xy 127.333248 -229.06863) (xy 127.333248 -229.024434) (xy 126.977648 -229.024434) (xy 126.977648 -229.06863)
			(xy 127.024638 -229.22103) (xy 127.286258 -229.22103)
		)
		(stroke
			(width 0)
			(type solid)
		)
		(fill yes)
		(layer "In11.Cu")
		(net "M_H_CPU1_SB_DQ<27>")
	)
	(gr_poly
		(pts
			(xy 127.333248 -225.813366) (xy 127.333248 -225.768916) (xy 126.977648 -225.768916) (xy 126.977648 -225.813366)
			(xy 127.024638 -225.965766) (xy 127.286258 -225.965766)
		)
		(stroke
			(width 0)
			(type solid)
		)
		(fill yes)
		(layer "In11.Cu")
		(net "M_H_CPU1_SB_DQ<31>")
	)
	(gr_poly
		(pts
			(xy 127.405638 -276.560788) (xy 127.514096 -276.443948) (xy 127.383286 -276.21738) (xy 127.227838 -276.25294)
			(xy 127.189484 -276.275038) (xy 127.367284 -276.582886)
		)
		(stroke
			(width 0)
			(type solid)
		)
		(fill yes)
		(layer "In11.Cu")
		(net "M_H_CPU1_SA_DQS_DP<6>")
	)
	(gr_poly
		(pts
			(xy 127.405638 -273.30527) (xy 127.514096 -273.18843) (xy 127.383286 -272.961862) (xy 127.227838 -272.997422)
			(xy 127.189484 -273.01952) (xy 127.367284 -273.327368)
		)
		(stroke
			(width 0)
			(type solid)
		)
		(fill yes)
		(layer "In11.Cu")
		(net "M_H_CPU1_SA_DQ<15>")
	)
	(gr_poly
		(pts
			(xy 127.407416 -274.93595) (xy 127.515874 -274.81911) (xy 127.385064 -274.592542) (xy 127.229616 -274.628102)
			(xy 127.191262 -274.6502) (xy 127.369062 -274.958048)
		)
		(stroke
			(width 0)
			(type solid)
		)
		(fill yes)
		(layer "In11.Cu")
		(net "M_H_CPU1_SA_DQ<14>")
	)
	(gr_poly
		(pts
			(xy 127.428752 -257.37947) (xy 127.381762 -257.22707) (xy 127.120142 -257.22707) (xy 127.073152 -257.37947)
			(xy 127.073152 -257.42392) (xy 127.428752 -257.42392)
		)
		(stroke
			(width 0)
			(type solid)
		)
		(fill yes)
		(layer "In11.Cu")
		(net "M_H_CPU1_ALERT_N")
	)
	(gr_poly
		(pts
			(xy 127.43053 -265.109706) (xy 127.43053 -265.06551) (xy 127.07493 -265.06551) (xy 127.07493 -265.109706)
			(xy 127.12192 -265.262106) (xy 127.38354 -265.262106)
		)
		(stroke
			(width 0)
			(type solid)
		)
		(fill yes)
		(layer "In11.Cu")
		(net "M_H_CPU1_SA_DQS_DN<8>")
	)
	(gr_poly
		(pts
			(xy 127.431546 -268.77391) (xy 127.384556 -268.62151) (xy 127.122936 -268.62151) (xy 127.075946 -268.77391)
			(xy 127.075946 -268.81836) (xy 127.431546 -268.81836)
		)
		(stroke
			(width 0)
			(type solid)
		)
		(fill yes)
		(layer "In11.Cu")
		(net "M_H_CPU1_SA_DQ<22>")
	)
	(gr_poly
		(pts
			(xy 127.434848 -258.59867) (xy 127.434848 -258.554474) (xy 127.079248 -258.554474) (xy 127.079248 -258.59867)
			(xy 127.126238 -258.75107) (xy 127.387858 -258.75107)
		)
		(stroke
			(width 0)
			(type solid)
		)
		(fill yes)
		(layer "In11.Cu")
		(net "M_H_CPU1_SA_CB<5>")
	)
	(gr_poly
		(pts
			(xy 127.44069 -280.168096) (xy 127.3937 -280.015696) (xy 127.13208 -280.015696) (xy 127.08509 -280.168096)
			(xy 127.08509 -280.212546) (xy 127.44069 -280.212546)
		)
		(stroke
			(width 0)
			(type solid)
		)
		(fill yes)
		(layer "In11.Cu")
		(net "M_H_CPU1_SA_DQ<10>")
	)
	(gr_poly
		(pts
			(xy 127.44069 -279.760172) (xy 127.44069 -279.715722) (xy 127.08509 -279.715722) (xy 127.08509 -279.760172)
			(xy 127.13208 -279.912572) (xy 127.3937 -279.912572)
		)
		(stroke
			(width 0)
			(type solid)
		)
		(fill yes)
		(layer "In11.Cu")
		(net "M_H_CPU1_SA_DQ<9>")
	)
	(gr_poly
		(pts
			(xy 127.44069 -265.518138) (xy 127.3937 -265.365738) (xy 127.13208 -265.365738) (xy 127.08509 -265.518138)
			(xy 127.08509 -265.562588) (xy 127.44069 -265.562588)
		)
		(stroke
			(width 0)
			(type solid)
		)
		(fill yes)
		(layer "In11.Cu")
		(net "M_H_CPU1_SA_DQS_DN<3>")
	)
	(gr_poly
		(pts
			(xy 127.44069 -260.634734) (xy 127.3937 -260.482334) (xy 127.13208 -260.482334) (xy 127.08509 -260.634734)
			(xy 127.08509 -260.679184) (xy 127.44069 -260.679184)
		)
		(stroke
			(width 0)
			(type solid)
		)
		(fill yes)
		(layer "In11.Cu")
		(net "M_H_CPU1_SA_DQS_DN<4>")
	)
	(gr_poly
		(pts
			(xy 127.44069 -260.22681) (xy 127.44069 -260.18236) (xy 127.08509 -260.18236) (xy 127.08509 -260.22681)
			(xy 127.13208 -260.37921) (xy 127.3937 -260.37921)
		)
		(stroke
			(width 0)
			(type solid)
		)
		(fill yes)
		(layer "In11.Cu")
		(net "M_H_CPU1_SA_DQS_DN<9>")
	)
	(gr_poly
		(pts
			(xy 127.44069 -256.971038) (xy 127.44069 -256.926588) (xy 127.08509 -256.926588) (xy 127.08509 -256.971038)
			(xy 127.13208 -257.123438) (xy 127.3937 -257.123438)
		)
		(stroke
			(width 0)
			(type solid)
		)
		(fill yes)
		(layer "In11.Cu")
		(net "M_H_CPU1_SA_CS_N<0>")
	)
	(gr_poly
		(pts
			(xy 127.44069 -255.751838) (xy 127.3937 -255.599438) (xy 127.13208 -255.599438) (xy 127.08509 -255.751838)
			(xy 127.08509 -255.796034) (xy 127.44069 -255.796034)
		)
		(stroke
			(width 0)
			(type solid)
		)
		(fill yes)
		(layer "In11.Cu")
		(net "M_H_CPU1_SA_CS_N<3>")
	)
	(gr_poly
		(pts
			(xy 127.44069 -255.343406) (xy 127.44069 -255.29921) (xy 127.08509 -255.29921) (xy 127.08509 -255.343406)
			(xy 127.13208 -255.495806) (xy 127.3937 -255.495806)
		)
		(stroke
			(width 0)
			(type solid)
		)
		(fill yes)
		(layer "In11.Cu")
		(net "M_H_CPU1_SA_CA<1>")
	)
	(gr_poly
		(pts
			(xy 127.44323 -278.540464) (xy 127.39624 -278.388064) (xy 127.13462 -278.388064) (xy 127.08763 -278.540464)
			(xy 127.08763 -278.584914) (xy 127.44323 -278.584914)
		)
		(stroke
			(width 0)
			(type solid)
		)
		(fill yes)
		(layer "In11.Cu")
		(net "M_H_CPU1_SA_DQS_DN<1>")
	)
	(gr_poly
		(pts
			(xy 127.44323 -272.029174) (xy 127.39624 -271.876774) (xy 127.13462 -271.876774) (xy 127.08763 -272.029174)
			(xy 127.08763 -272.073624) (xy 127.44323 -272.073624)
		)
		(stroke
			(width 0)
			(type solid)
		)
		(fill yes)
		(layer "In11.Cu")
		(net "M_H_CPU1_SA_DQ<18>")
	)
	(gr_poly
		(pts
			(xy 127.44323 -271.62125) (xy 127.44323 -271.5768) (xy 127.08763 -271.5768) (xy 127.08763 -271.62125)
			(xy 127.13462 -271.77365) (xy 127.39624 -271.77365)
		)
		(stroke
			(width 0)
			(type solid)
		)
		(fill yes)
		(layer "In11.Cu")
		(net "M_H_CPU1_SA_DQ<17>")
	)
	(gr_poly
		(pts
			(xy 127.44323 -270.401542) (xy 127.39624 -270.249142) (xy 127.13462 -270.249142) (xy 127.08763 -270.401542)
			(xy 127.08763 -270.445992) (xy 127.44323 -270.445992)
		)
		(stroke
			(width 0)
			(type solid)
		)
		(fill yes)
		(layer "In11.Cu")
		(net "M_H_CPU1_SA_DQS_DN<2>")
	)
	(gr_poly
		(pts
			(xy 127.44323 -269.993618) (xy 127.44323 -269.949168) (xy 127.08763 -269.949168) (xy 127.08763 -269.993618)
			(xy 127.13462 -270.146018) (xy 127.39624 -270.146018)
		)
		(stroke
			(width 0)
			(type solid)
		)
		(fill yes)
		(layer "In11.Cu")
		(net "M_H_CPU1_SA_DQS_DN<7>")
	)
	(gr_poly
		(pts
			(xy 127.44323 -268.365478) (xy 127.44323 -268.321282) (xy 127.08763 -268.321282) (xy 127.08763 -268.365478)
			(xy 127.13462 -268.517878) (xy 127.39624 -268.517878)
		)
		(stroke
			(width 0)
			(type solid)
		)
		(fill yes)
		(layer "In11.Cu")
		(net "M_H_CPU1_SA_DQ<21>")
	)
	(gr_poly
		(pts
			(xy 127.44323 -267.14577) (xy 127.39624 -266.99337) (xy 127.13462 -266.99337) (xy 127.08763 -267.14577)
			(xy 127.08763 -267.19022) (xy 127.44323 -267.19022)
		)
		(stroke
			(width 0)
			(type solid)
		)
		(fill yes)
		(layer "In11.Cu")
		(net "M_H_CPU1_SA_DQ<26>")
	)
	(gr_poly
		(pts
			(xy 127.44323 -266.737846) (xy 127.44323 -266.69365) (xy 127.08763 -266.69365) (xy 127.08763 -266.737846)
			(xy 127.13462 -266.890246) (xy 127.39624 -266.890246)
		)
		(stroke
			(width 0)
			(type solid)
		)
		(fill yes)
		(layer "In11.Cu")
		(net "M_H_CPU1_SA_DQ<25>")
	)
	(gr_poly
		(pts
			(xy 127.44323 -263.890506) (xy 127.39624 -263.738106) (xy 127.13462 -263.738106) (xy 127.08763 -263.890506)
			(xy 127.08763 -263.934956) (xy 127.44323 -263.934956)
		)
		(stroke
			(width 0)
			(type solid)
		)
		(fill yes)
		(layer "In11.Cu")
		(net "M_H_CPU1_SA_DQ<30>")
	)
	(gr_poly
		(pts
			(xy 127.44323 -263.482582) (xy 127.44323 -263.438132) (xy 127.08763 -263.438132) (xy 127.08763 -263.482582)
			(xy 127.13462 -263.634982) (xy 127.39624 -263.634982)
		)
		(stroke
			(width 0)
			(type solid)
		)
		(fill yes)
		(layer "In11.Cu")
		(net "M_H_CPU1_SA_DQ<29>")
	)
	(gr_poly
		(pts
			(xy 127.44323 -262.262874) (xy 127.39624 -262.110474) (xy 127.13462 -262.110474) (xy 127.08763 -262.262874)
			(xy 127.08763 -262.30707) (xy 127.44323 -262.30707)
		)
		(stroke
			(width 0)
			(type solid)
		)
		(fill yes)
		(layer "In11.Cu")
		(net "M_H_CPU1_SA_CB<2>")
	)
	(gr_poly
		(pts
			(xy 127.44323 -261.854442) (xy 127.44323 -261.810246) (xy 127.08763 -261.810246) (xy 127.08763 -261.854442)
			(xy 127.13462 -262.006842) (xy 127.39624 -262.006842)
		)
		(stroke
			(width 0)
			(type solid)
		)
		(fill yes)
		(layer "In11.Cu")
		(net "M_H_CPU1_SA_CB<1>")
	)
	(gr_poly
		(pts
			(xy 127.44323 -259.007102) (xy 127.39624 -258.854702) (xy 127.13462 -258.854702) (xy 127.08763 -259.007102)
			(xy 127.08763 -259.051552) (xy 127.44323 -259.051552)
		)
		(stroke
			(width 0)
			(type solid)
		)
		(fill yes)
		(layer "In11.Cu")
		(net "M_H_CPU1_SA_CB<6>")
	)
	(gr_poly
		(pts
			(xy 127.44323 -254.123698) (xy 127.39624 -253.971298) (xy 127.13462 -253.971298) (xy 127.08763 -254.123698)
			(xy 127.08763 -254.168148) (xy 127.44323 -254.168148)
		)
		(stroke
			(width 0)
			(type solid)
		)
		(fill yes)
		(layer "In11.Cu")
		(net "M_H_CPU1_SA_CA<3>")
	)
	(gr_poly
		(pts
			(xy 127.755904 -281.23388) (xy 127.794258 -281.211782) (xy 127.616458 -280.903934) (xy 127.578104 -280.926032)
			(xy 127.469646 -281.042872) (xy 127.600456 -281.26944)
		)
		(stroke
			(width 0)
			(type solid)
		)
		(fill yes)
		(layer "In11.Cu")
		(net "M_H_CPU1_SA_DQ<8>")
	)
	(gr_poly
		(pts
			(xy 127.755904 -276.350476) (xy 127.794258 -276.328378) (xy 127.616458 -276.02053) (xy 127.578104 -276.042628)
			(xy 127.469646 -276.159468) (xy 127.600456 -276.386036)
		)
		(stroke
			(width 0)
			(type solid)
		)
		(fill yes)
		(layer "In11.Cu")
		(net "M_H_CPU1_SA_DQ<12>")
	)
	(gr_poly
		(pts
			(xy 127.755904 -274.72259) (xy 127.794258 -274.700492) (xy 127.616458 -274.392644) (xy 127.578104 -274.414742)
			(xy 127.469646 -274.531582) (xy 127.600456 -274.75815)
		)
		(stroke
			(width 0)
			(type solid)
		)
		(fill yes)
		(layer "In11.Cu")
		(net "M_H_CPU1_SA_DQ<13>")
	)
	(gr_poly
		(pts
			(xy 127.755904 -273.094958) (xy 127.794258 -273.07286) (xy 127.616458 -272.765012) (xy 127.578104 -272.78711)
			(xy 127.469646 -272.90395) (xy 127.600456 -273.130518)
		)
		(stroke
			(width 0)
			(type solid)
		)
		(fill yes)
		(layer "In11.Cu")
		(net "M_H_CPU1_SA_DQ<16>")
	)
	(gr_poly
		(pts
			(xy 127.761238 -277.987252) (xy 127.799592 -277.965154) (xy 127.621792 -277.657306) (xy 127.583438 -277.679404)
			(xy 127.47498 -277.796244) (xy 127.60579 -278.022812)
		)
		(stroke
			(width 0)
			(type solid)
		)
		(fill yes)
		(layer "In11.Cu")
		(net "M_H_CPU1_SA_DQS_DN<6>")
	)
	(gr_poly
		(pts
			(xy 127.78613 -248.196354) (xy 127.73914 -248.043954) (xy 127.47752 -248.043954) (xy 127.43053 -248.196354)
			(xy 127.43053 -248.24055) (xy 127.78613 -248.24055)
		)
		(stroke
			(width 0)
			(type solid)
		)
		(fill yes)
		(layer "In11.Cu")
		(net "M_H_CPU1_SB_CA<1>")
	)
	(gr_poly
		(pts
			(xy 127.78613 -243.31295) (xy 127.73914 -243.16055) (xy 127.47752 -243.16055) (xy 127.43053 -243.31295)
			(xy 127.43053 -243.3574) (xy 127.78613 -243.3574)
		)
		(stroke
			(width 0)
			(type solid)
		)
		(fill yes)
		(layer "In11.Cu")
		(net "M_H_CPU1_SB_CB<5>")
	)
	(gr_poly
		(pts
			(xy 127.78613 -242.905026) (xy 127.78613 -242.860576) (xy 127.43053 -242.860576) (xy 127.43053 -242.905026)
			(xy 127.47752 -243.057426) (xy 127.73914 -243.057426)
		)
		(stroke
			(width 0)
			(type solid)
		)
		(fill yes)
		(layer "In11.Cu")
		(net "M_H_CPU1_SB_DQS_DP<9>")
	)
	(gr_poly
		(pts
			(xy 127.78613 -241.276886) (xy 127.78613 -241.23269) (xy 127.43053 -241.23269) (xy 127.43053 -241.276886)
			(xy 127.47752 -241.429286) (xy 127.73914 -241.429286)
		)
		(stroke
			(width 0)
			(type solid)
		)
		(fill yes)
		(layer "In11.Cu")
		(net "M_H_CPU1_SB_CB<0>")
	)
	(gr_poly
		(pts
			(xy 127.78613 -240.057178) (xy 127.73914 -239.904778) (xy 127.47752 -239.904778) (xy 127.43053 -240.057178)
			(xy 127.43053 -240.101628) (xy 127.78613 -240.101628)
		)
		(stroke
			(width 0)
			(type solid)
		)
		(fill yes)
		(layer "In11.Cu")
		(net "M_H_CPU1_SB_CB<3>")
	)
	(gr_poly
		(pts
			(xy 127.78613 -239.649254) (xy 127.78613 -239.604804) (xy 127.43053 -239.604804) (xy 127.43053 -239.649254)
			(xy 127.47752 -239.801654) (xy 127.73914 -239.801654)
		)
		(stroke
			(width 0)
			(type solid)
		)
		(fill yes)
		(layer "In11.Cu")
		(net "M_H_CPU1_SB_DQ<0>")
	)
	(gr_poly
		(pts
			(xy 127.78613 -238.429546) (xy 127.73914 -238.277146) (xy 127.47752 -238.277146) (xy 127.43053 -238.429546)
			(xy 127.43053 -238.473996) (xy 127.78613 -238.473996)
		)
		(stroke
			(width 0)
			(type solid)
		)
		(fill yes)
		(layer "In11.Cu")
		(net "M_H_CPU1_SB_DQ<3>")
	)
	(gr_poly
		(pts
			(xy 127.78613 -238.021622) (xy 127.78613 -237.977172) (xy 127.43053 -237.977172) (xy 127.43053 -238.021622)
			(xy 127.47752 -238.174022) (xy 127.73914 -238.174022)
		)
		(stroke
			(width 0)
			(type solid)
		)
		(fill yes)
		(layer "In11.Cu")
		(net "M_H_CPU1_SB_DQS_DP<0>")
	)
	(gr_poly
		(pts
			(xy 127.78613 -236.801914) (xy 127.73914 -236.649514) (xy 127.47752 -236.649514) (xy 127.43053 -236.801914)
			(xy 127.43053 -236.84611) (xy 127.78613 -236.84611)
		)
		(stroke
			(width 0)
			(type solid)
		)
		(fill yes)
		(layer "In11.Cu")
		(net "M_H_CPU1_SB_DQS_DP<5>")
	)
	(gr_poly
		(pts
			(xy 127.78613 -236.39399) (xy 127.78613 -236.34954) (xy 127.43053 -236.34954) (xy 127.43053 -236.39399)
			(xy 127.47752 -236.54639) (xy 127.73914 -236.54639)
		)
		(stroke
			(width 0)
			(type solid)
		)
		(fill yes)
		(layer "In11.Cu")
		(net "M_H_CPU1_SB_DQ<4>")
	)
	(gr_poly
		(pts
			(xy 127.78613 -234.76585) (xy 127.78613 -234.721654) (xy 127.43053 -234.721654) (xy 127.43053 -234.76585)
			(xy 127.47752 -234.91825) (xy 127.73914 -234.91825)
		)
		(stroke
			(width 0)
			(type solid)
		)
		(fill yes)
		(layer "In11.Cu")
		(net "M_H_CPU1_SB_DQ<8>")
	)
	(gr_poly
		(pts
			(xy 127.78613 -233.546142) (xy 127.73914 -233.393742) (xy 127.47752 -233.393742) (xy 127.43053 -233.546142)
			(xy 127.43053 -233.590592) (xy 127.78613 -233.590592)
		)
		(stroke
			(width 0)
			(type solid)
		)
		(fill yes)
		(layer "In11.Cu")
		(net "M_H_CPU1_SB_DQ<11>")
	)
	(gr_poly
		(pts
			(xy 127.78613 -233.138218) (xy 127.78613 -233.093768) (xy 127.43053 -233.093768) (xy 127.43053 -233.138218)
			(xy 127.47752 -233.290618) (xy 127.73914 -233.290618)
		)
		(stroke
			(width 0)
			(type solid)
		)
		(fill yes)
		(layer "In11.Cu")
		(net "M_H_CPU1_SB_DQS_DP<1>")
	)
	(gr_poly
		(pts
			(xy 127.78613 -231.91851) (xy 127.73914 -231.76611) (xy 127.47752 -231.76611) (xy 127.43053 -231.91851)
			(xy 127.43053 -231.96296) (xy 127.78613 -231.96296)
		)
		(stroke
			(width 0)
			(type solid)
		)
		(fill yes)
		(layer "In11.Cu")
		(net "M_H_CPU1_SB_DQS_DP<6>")
	)
	(gr_poly
		(pts
			(xy 127.78613 -231.510586) (xy 127.78613 -231.466136) (xy 127.43053 -231.466136) (xy 127.43053 -231.510586)
			(xy 127.47752 -231.662986) (xy 127.73914 -231.662986)
		)
		(stroke
			(width 0)
			(type solid)
		)
		(fill yes)
		(layer "In11.Cu")
		(net "M_H_CPU1_SB_DQ<12>")
	)
	(gr_poly
		(pts
			(xy 127.78613 -230.290878) (xy 127.73914 -230.138478) (xy 127.47752 -230.138478) (xy 127.43053 -230.290878)
			(xy 127.43053 -230.335074) (xy 127.78613 -230.335074)
		)
		(stroke
			(width 0)
			(type solid)
		)
		(fill yes)
		(layer "In11.Cu")
		(net "M_H_CPU1_SB_DQ<15>")
	)
	(gr_poly
		(pts
			(xy 127.78613 -229.882446) (xy 127.78613 -229.83825) (xy 127.43053 -229.83825) (xy 127.43053 -229.882446)
			(xy 127.47752 -230.034846) (xy 127.73914 -230.034846)
		)
		(stroke
			(width 0)
			(type solid)
		)
		(fill yes)
		(layer "In11.Cu")
		(net "M_H_CPU1_SB_DQ<26>")
	)
	(gr_poly
		(pts
			(xy 127.78613 -228.663246) (xy 127.73914 -228.510846) (xy 127.47752 -228.510846) (xy 127.43053 -228.663246)
			(xy 127.43053 -228.707442) (xy 127.78613 -228.707442)
		)
		(stroke
			(width 0)
			(type solid)
		)
		(fill yes)
		(layer "In11.Cu")
		(net "M_H_CPU1_SB_DQ<25>")
	)
	(gr_poly
		(pts
			(xy 127.78613 -225.407474) (xy 127.73914 -225.255074) (xy 127.47752 -225.255074) (xy 127.43053 -225.407474)
			(xy 127.43053 -225.45167) (xy 127.78613 -225.45167)
		)
		(stroke
			(width 0)
			(type solid)
		)
		(fill yes)
		(layer "In11.Cu")
		(net "M_H_CPU1_SB_DQ<29>")
	)
	(gr_poly
		(pts
			(xy 127.78867 -244.53215) (xy 127.78867 -244.487954) (xy 127.43307 -244.487954) (xy 127.43307 -244.53215)
			(xy 127.48006 -244.68455) (xy 127.74168 -244.68455)
		)
		(stroke
			(width 0)
			(type solid)
		)
		(fill yes)
		(layer "In11.Cu")
		(net "M_H_CPU1_SB_CB<6>")
	)
	(gr_poly
		(pts
			(xy 127.794512 -228.254814) (xy 127.794512 -228.210364) (xy 127.438912 -228.210364) (xy 127.438912 -228.254814)
			(xy 127.485902 -228.407214) (xy 127.747522 -228.407214)
		)
		(stroke
			(width 0)
			(type solid)
		)
		(fill yes)
		(layer "In11.Cu")
		(net "M_H_CPU1_SB_DQS_DN<8>")
	)
	(gr_poly
		(pts
			(xy 127.794766 -226.626674) (xy 127.794766 -226.582478) (xy 127.439166 -226.582478) (xy 127.439166 -226.626674)
			(xy 127.486156 -226.779074) (xy 127.747776 -226.779074)
		)
		(stroke
			(width 0)
			(type solid)
		)
		(fill yes)
		(layer "In11.Cu")
		(net "M_H_CPU1_SB_DQ<30>")
	)
	(gr_poly
		(pts
			(xy 127.79502 -241.685826) (xy 127.74803 -241.533426) (xy 127.48641 -241.533426) (xy 127.43942 -241.685826)
			(xy 127.43942 -241.730022) (xy 127.79502 -241.730022)
		)
		(stroke
			(width 0)
			(type solid)
		)
		(fill yes)
		(layer "In11.Cu")
		(net "M_H_CPU1_SB_DQS_DP<4>")
	)
	(gr_poly
		(pts
			(xy 127.798068 -235.174282) (xy 127.751078 -235.021882) (xy 127.489458 -235.021882) (xy 127.442468 -235.174282)
			(xy 127.442468 -235.218732) (xy 127.798068 -235.218732)
		)
		(stroke
			(width 0)
			(type solid)
		)
		(fill yes)
		(layer "In11.Cu")
		(net "M_H_CPU1_SB_DQ<7>")
	)
	(gr_poly
		(pts
			(xy 127.803148 -227.035106) (xy 127.756158 -226.882706) (xy 127.494538 -226.882706) (xy 127.447548 -227.035106)
			(xy 127.447548 -227.079556) (xy 127.803148 -227.079556)
		)
		(stroke
			(width 0)
			(type solid)
		)
		(fill yes)
		(layer "In11.Cu")
		(net "M_H_CPU1_SB_DQS_DN<3>")
	)
	(gr_poly
		(pts
			(xy 127.868172 -275.735796) (xy 127.97663 -275.618956) (xy 127.84582 -275.392388) (xy 127.690372 -275.427948)
			(xy 127.652018 -275.450046) (xy 127.829818 -275.757894)
		)
		(stroke
			(width 0)
			(type solid)
		)
		(fill yes)
		(layer "In11.Cu")
		(net "M_H_CPU1_SA_DQ<14>")
	)
	(gr_poly
		(pts
			(xy 127.86995 -277.364952) (xy 127.978408 -277.248112) (xy 127.847598 -277.021544) (xy 127.69215 -277.057104)
			(xy 127.653796 -277.079202) (xy 127.831596 -277.38705)
		)
		(stroke
			(width 0)
			(type solid)
		)
		(fill yes)
		(layer "In11.Cu")
		(net "M_H_CPU1_SA_DQS_DP<6>")
	)
	(gr_poly
		(pts
			(xy 127.86995 -274.109434) (xy 127.978408 -273.992594) (xy 127.847598 -273.766026) (xy 127.69215 -273.801586)
			(xy 127.653796 -273.823684) (xy 127.831596 -274.131532)
		)
		(stroke
			(width 0)
			(type solid)
		)
		(fill yes)
		(layer "In11.Cu")
		(net "M_H_CPU1_SA_DQ<15>")
	)
	(gr_poly
		(pts
			(xy 127.873506 -272.488152) (xy 127.981964 -272.371312) (xy 127.851154 -272.144744) (xy 127.695706 -272.180304)
			(xy 127.657352 -272.202402) (xy 127.835152 -272.51025)
		)
		(stroke
			(width 0)
			(type solid)
		)
		(fill yes)
		(layer "In11.Cu")
		(net "M_H_CPU1_SA_DQ<18>")
	)
	(gr_poly
		(pts
			(xy 127.875284 -280.630376) (xy 127.983742 -280.513536) (xy 127.852932 -280.286968) (xy 127.697484 -280.322528)
			(xy 127.65913 -280.344626) (xy 127.83693 -280.652474)
		)
		(stroke
			(width 0)
			(type solid)
		)
		(fill yes)
		(layer "In11.Cu")
		(net "M_H_CPU1_SA_DQ<10>")
	)
	(gr_poly
		(pts
			(xy 127.896112 -279.35428) (xy 127.849122 -279.20188) (xy 127.587502 -279.20188) (xy 127.540512 -279.35428)
			(xy 127.540512 -279.39873) (xy 127.896112 -279.39873)
		)
		(stroke
			(width 0)
			(type solid)
		)
		(fill yes)
		(layer "In11.Cu")
		(net "M_H_CPU1_SA_DQ<11>")
	)
	(gr_poly
		(pts
			(xy 127.896112 -278.946356) (xy 127.896112 -278.901906) (xy 127.540512 -278.901906) (xy 127.540512 -278.946356)
			(xy 127.587502 -279.098756) (xy 127.849122 -279.098756)
		)
		(stroke
			(width 0)
			(type solid)
		)
		(fill yes)
		(layer "In11.Cu")
		(net "M_H_CPU1_SA_DQS_DP<1>")
	)
	(gr_poly
		(pts
			(xy 127.896112 -271.215358) (xy 127.849122 -271.062958) (xy 127.587502 -271.062958) (xy 127.540512 -271.215358)
			(xy 127.540512 -271.259808) (xy 127.896112 -271.259808)
		)
		(stroke
			(width 0)
			(type solid)
		)
		(fill yes)
		(layer "In11.Cu")
		(net "M_H_CPU1_SA_DQ<19>")
	)
	(gr_poly
		(pts
			(xy 127.896112 -270.807434) (xy 127.896112 -270.762984) (xy 127.540512 -270.762984) (xy 127.540512 -270.807434)
			(xy 127.587502 -270.959834) (xy 127.849122 -270.959834)
		)
		(stroke
			(width 0)
			(type solid)
		)
		(fill yes)
		(layer "In11.Cu")
		(net "M_H_CPU1_SA_DQS_DP<2>")
	)
	(gr_poly
		(pts
			(xy 127.896112 -269.587726) (xy 127.849122 -269.435326) (xy 127.587502 -269.435326) (xy 127.540512 -269.587726)
			(xy 127.540512 -269.631922) (xy 127.896112 -269.631922)
		)
		(stroke
			(width 0)
			(type solid)
		)
		(fill yes)
		(layer "In11.Cu")
		(net "M_H_CPU1_SA_DQS_DP<7>")
	)
	(gr_poly
		(pts
			(xy 127.896112 -267.960094) (xy 127.849122 -267.807694) (xy 127.587502 -267.807694) (xy 127.540512 -267.960094)
			(xy 127.540512 -268.00429) (xy 127.896112 -268.00429)
		)
		(stroke
			(width 0)
			(type solid)
		)
		(fill yes)
		(layer "In11.Cu")
		(net "M_H_CPU1_SA_DQ<23>")
	)
	(gr_poly
		(pts
			(xy 127.896112 -267.551662) (xy 127.896112 -267.507466) (xy 127.540512 -267.507466) (xy 127.540512 -267.551662)
			(xy 127.587502 -267.704062) (xy 127.849122 -267.704062)
		)
		(stroke
			(width 0)
			(type solid)
		)
		(fill yes)
		(layer "In11.Cu")
		(net "M_H_CPU1_SA_DQ<24>")
	)
	(gr_poly
		(pts
			(xy 127.896112 -266.331954) (xy 127.849122 -266.179554) (xy 127.587502 -266.179554) (xy 127.540512 -266.331954)
			(xy 127.540512 -266.376404) (xy 127.896112 -266.376404)
		)
		(stroke
			(width 0)
			(type solid)
		)
		(fill yes)
		(layer "In11.Cu")
		(net "M_H_CPU1_SA_DQ<27>")
	)
	(gr_poly
		(pts
			(xy 127.896112 -265.92403) (xy 127.896112 -265.879834) (xy 127.540512 -265.879834) (xy 127.540512 -265.92403)
			(xy 127.587502 -266.07643) (xy 127.849122 -266.07643)
		)
		(stroke
			(width 0)
			(type solid)
		)
		(fill yes)
		(layer "In11.Cu")
		(net "M_H_CPU1_SA_DQS_DP<3>")
	)
	(gr_poly
		(pts
			(xy 127.896112 -264.296398) (xy 127.896112 -264.251948) (xy 127.540512 -264.251948) (xy 127.540512 -264.296398)
			(xy 127.587502 -264.448798) (xy 127.849122 -264.448798)
		)
		(stroke
			(width 0)
			(type solid)
		)
		(fill yes)
		(layer "In11.Cu")
		(net "M_H_CPU1_SA_DQ<28>")
	)
	(gr_poly
		(pts
			(xy 127.896112 -263.07669) (xy 127.849122 -262.92429) (xy 127.587502 -262.92429) (xy 127.540512 -263.07669)
			(xy 127.540512 -263.120886) (xy 127.896112 -263.120886)
		)
		(stroke
			(width 0)
			(type solid)
		)
		(fill yes)
		(layer "In11.Cu")
		(net "M_H_CPU1_SA_DQ<31>")
	)
	(gr_poly
		(pts
			(xy 127.896112 -262.668258) (xy 127.896112 -262.624062) (xy 127.540512 -262.624062) (xy 127.540512 -262.668258)
			(xy 127.587502 -262.820658) (xy 127.849122 -262.820658)
		)
		(stroke
			(width 0)
			(type solid)
		)
		(fill yes)
		(layer "In11.Cu")
		(net "M_H_CPU1_SA_CB<0>")
	)
	(gr_poly
		(pts
			(xy 127.896112 -261.449058) (xy 127.849122 -261.296658) (xy 127.587502 -261.296658) (xy 127.540512 -261.449058)
			(xy 127.540512 -261.493254) (xy 127.896112 -261.493254)
		)
		(stroke
			(width 0)
			(type solid)
		)
		(fill yes)
		(layer "In11.Cu")
		(net "M_H_CPU1_SA_CB<3>")
	)
	(gr_poly
		(pts
			(xy 127.896112 -261.040626) (xy 127.896112 -260.99643) (xy 127.540512 -260.99643) (xy 127.540512 -261.040626)
			(xy 127.587502 -261.193026) (xy 127.849122 -261.193026)
		)
		(stroke
			(width 0)
			(type solid)
		)
		(fill yes)
		(layer "In11.Cu")
		(net "M_H_CPU1_SA_DQS_DP<4>")
	)
	(gr_poly
		(pts
			(xy 127.896112 -259.820918) (xy 127.849122 -259.668518) (xy 127.587502 -259.668518) (xy 127.540512 -259.820918)
			(xy 127.540512 -259.865368) (xy 127.896112 -259.865368)
		)
		(stroke
			(width 0)
			(type solid)
		)
		(fill yes)
		(layer "In11.Cu")
		(net "M_H_CPU1_SA_DQS_DP<9>")
	)
	(gr_poly
		(pts
			(xy 127.896112 -259.412994) (xy 127.896112 -259.368544) (xy 127.540512 -259.368544) (xy 127.540512 -259.412994)
			(xy 127.587502 -259.565394) (xy 127.849122 -259.565394)
		)
		(stroke
			(width 0)
			(type solid)
		)
		(fill yes)
		(layer "In11.Cu")
		(net "M_H_CPU1_SA_CB<4>")
	)
	(gr_poly
		(pts
			(xy 127.896112 -256.157222) (xy 127.896112 -256.113026) (xy 127.540512 -256.113026) (xy 127.540512 -256.157222)
			(xy 127.587502 -256.309622) (xy 127.849122 -256.309622)
		)
		(stroke
			(width 0)
			(type solid)
		)
		(fill yes)
		(layer "In11.Cu")
		(net "M_H_CPU1_SA_CS_N<2>")
	)
	(gr_poly
		(pts
			(xy 127.896112 -254.937514) (xy 127.849122 -254.785114) (xy 127.587502 -254.785114) (xy 127.540512 -254.937514)
			(xy 127.540512 -254.981964) (xy 127.896112 -254.981964)
		)
		(stroke
			(width 0)
			(type solid)
		)
		(fill yes)
		(layer "In11.Cu")
		(net "M_H_CPU1_SA_CA<0>")
	)
	(gr_poly
		(pts
			(xy 127.896112 -254.52959) (xy 127.896112 -254.48514) (xy 127.540512 -254.48514) (xy 127.540512 -254.52959)
			(xy 127.587502 -254.68199) (xy 127.849122 -254.68199)
		)
		(stroke
			(width 0)
			(type solid)
		)
		(fill yes)
		(layer "In11.Cu")
		(net "M_H_CPU1_SA_CA<2>")
	)
	(gr_poly
		(pts
			(xy 127.898652 -258.193286) (xy 127.851662 -258.040886) (xy 127.590042 -258.040886) (xy 127.543052 -258.193286)
			(xy 127.543052 -258.237736) (xy 127.898652 -258.237736)
		)
		(stroke
			(width 0)
			(type solid)
		)
		(fill yes)
		(layer "In11.Cu")
		(net "M_H_CPU1_SA_CB<7>")
	)
	(gr_poly
		(pts
			(xy 127.90424 -269.179294) (xy 127.90424 -269.134844) (xy 127.54864 -269.134844) (xy 127.54864 -269.179294)
			(xy 127.59563 -269.331694) (xy 127.85725 -269.331694)
		)
		(stroke
			(width 0)
			(type solid)
		)
		(fill yes)
		(layer "In11.Cu")
		(net "M_H_CPU1_SA_DQ<20>")
	)
	(gr_poly
		(pts
			(xy 127.904494 -256.565654) (xy 127.857504 -256.413254) (xy 127.595884 -256.413254) (xy 127.548894 -256.565654)
			(xy 127.548894 -256.610104) (xy 127.904494 -256.610104)
		)
		(stroke
			(width 0)
			(type solid)
		)
		(fill yes)
		(layer "In11.Cu")
		(net "M_H_CPU1_SA_CS_N<1>")
	)
	(gr_poly
		(pts
			(xy 127.908812 -264.70483) (xy 127.861822 -264.55243) (xy 127.600202 -264.55243) (xy 127.553212 -264.70483)
			(xy 127.553212 -264.749026) (xy 127.908812 -264.749026)
		)
		(stroke
			(width 0)
			(type solid)
		)
		(fill yes)
		(layer "In11.Cu")
		(net "M_H_CPU1_SA_DQS_DP<8>")
	)
	(gr_poly
		(pts
			(xy 127.91059 -257.784854) (xy 127.91059 -257.740404) (xy 127.55499 -257.740404) (xy 127.55499 -257.784854)
			(xy 127.60198 -257.937254) (xy 127.8636 -257.937254)
		)
		(stroke
			(width 0)
			(type solid)
		)
		(fill yes)
		(layer "In11.Cu")
		(net "M_E_CPU1_ALERT_N")
	)
	(gr_poly
		(pts
			(xy 128.12141 -247.64365) (xy 128.159764 -247.621552) (xy 127.981964 -247.313704) (xy 127.94361 -247.335802)
			(xy 127.835152 -247.452642) (xy 127.965962 -247.67921)
		)
		(stroke
			(width 0)
			(type solid)
		)
		(fill yes)
		(layer "In11.Cu")
		(net "M_H_CPU1_SB_CA<2>")
	)
	(gr_poly
		(pts
			(xy 128.22555 -280.420064) (xy 128.263904 -280.397966) (xy 128.086104 -280.090118) (xy 128.04775 -280.112216)
			(xy 127.939292 -280.229056) (xy 128.070102 -280.455624)
		)
		(stroke
			(width 0)
			(type solid)
		)
		(fill yes)
		(layer "In11.Cu")
		(net "M_H_CPU1_SA_DQ<9>")
	)
	(gr_poly
		(pts
			(xy 128.231392 -277.173944) (xy 128.269746 -277.151846) (xy 128.091946 -276.843998) (xy 128.053592 -276.866096)
			(xy 127.945134 -276.982936) (xy 128.075944 -277.209504)
		)
		(stroke
			(width 0)
			(type solid)
		)
		(fill yes)
		(layer "In11.Cu")
		(net "M_H_CPU1_SA_DQ<12>")
	)
	(gr_poly
		(pts
			(xy 128.231392 -273.918426) (xy 128.269746 -273.896328) (xy 128.091946 -273.58848) (xy 128.053592 -273.610578)
			(xy 127.945134 -273.727418) (xy 128.075944 -273.953986)
		)
		(stroke
			(width 0)
			(type solid)
		)
		(fill yes)
		(layer "In11.Cu")
		(net "M_H_CPU1_SA_DQ<16>")
	)
	(gr_poly
		(pts
			(xy 128.23317 -275.547582) (xy 128.271524 -275.525484) (xy 128.093724 -275.217636) (xy 128.05537 -275.239734)
			(xy 127.946912 -275.356574) (xy 128.077722 -275.583142)
		)
		(stroke
			(width 0)
			(type solid)
		)
		(fill yes)
		(layer "In11.Cu")
		(net "M_H_CPU1_SA_DQ<13>")
	)
	(gr_poly
		(pts
			(xy 128.23317 -272.292064) (xy 128.271524 -272.269966) (xy 128.093724 -271.962118) (xy 128.05537 -271.984216)
			(xy 127.946912 -272.101056) (xy 128.077722 -272.327624)
		)
		(stroke
			(width 0)
			(type solid)
		)
		(fill yes)
		(layer "In11.Cu")
		(net "M_H_CPU1_SA_DQ<17>")
	)
	(gr_poly
		(pts
			(xy 128.235456 -247.030494) (xy 128.343914 -246.913654) (xy 128.213104 -246.687086) (xy 128.057656 -246.722646)
			(xy 128.019302 -246.744744) (xy 128.197102 -247.052592)
		)
		(stroke
			(width 0)
			(type solid)
		)
		(fill yes)
		(layer "In11.Cu")
		(net "M_H_CPU1_SB_CA<3>")
	)
	(gr_poly
		(pts
			(xy 128.25603 -227.440998) (xy 128.25603 -227.396548) (xy 127.90043 -227.396548) (xy 127.90043 -227.440998)
			(xy 127.94742 -227.593398) (xy 128.20904 -227.593398)
		)
		(stroke
			(width 0)
			(type solid)
		)
		(fill yes)
		(layer "In11.Cu")
		(net "M_H_CPU1_SB_DQS_DP<3>")
	)
	(gr_poly
		(pts
			(xy 128.264412 -227.84943) (xy 128.217422 -227.69703) (xy 127.955802 -227.69703) (xy 127.908812 -227.84943)
			(xy 127.908812 -227.893626) (xy 128.264412 -227.893626)
		)
		(stroke
			(width 0)
			(type solid)
		)
		(fill yes)
		(layer "In11.Cu")
		(net "M_H_CPU1_SB_DQS_DP<8>")
	)
	(gr_poly
		(pts
			(xy 128.264666 -226.221798) (xy 128.217676 -226.069398) (xy 127.956056 -226.069398) (xy 127.909066 -226.221798)
			(xy 127.909066 -226.265994) (xy 128.264666 -226.265994)
		)
		(stroke
			(width 0)
			(type solid)
		)
		(fill yes)
		(layer "In11.Cu")
		(net "M_H_CPU1_SB_DQ<28>")
	)
	(gr_poly
		(pts
			(xy 128.273048 -248.602246) (xy 128.273048 -248.557796) (xy 127.917448 -248.557796) (xy 127.917448 -248.602246)
			(xy 127.964438 -248.754646) (xy 128.226058 -248.754646)
		)
		(stroke
			(width 0)
			(type solid)
		)
		(fill yes)
		(layer "In11.Cu")
		(net "M_H_CPU1_SB_CA<0>")
	)
	(gr_poly
		(pts
			(xy 128.273048 -244.126766) (xy 128.226058 -243.974366) (xy 127.964438 -243.974366) (xy 127.917448 -244.126766)
			(xy 127.917448 -244.171216) (xy 128.273048 -244.171216)
		)
		(stroke
			(width 0)
			(type solid)
		)
		(fill yes)
		(layer "In11.Cu")
		(net "M_H_CPU1_SB_CB<4>")
	)
	(gr_poly
		(pts
			(xy 128.273048 -243.718842) (xy 128.273048 -243.674392) (xy 127.917448 -243.674392) (xy 127.917448 -243.718842)
			(xy 127.964438 -243.871242) (xy 128.226058 -243.871242)
		)
		(stroke
			(width 0)
			(type solid)
		)
		(fill yes)
		(layer "In11.Cu")
		(net "M_H_CPU1_SB_CB<7>")
	)
	(gr_poly
		(pts
			(xy 128.273048 -242.499134) (xy 128.226058 -242.346734) (xy 127.964438 -242.346734) (xy 127.917448 -242.499134)
			(xy 127.917448 -242.54333) (xy 128.273048 -242.54333)
		)
		(stroke
			(width 0)
			(type solid)
		)
		(fill yes)
		(layer "In11.Cu")
		(net "M_H_CPU1_SB_DQS_DN<9>")
	)
	(gr_poly
		(pts
			(xy 128.273048 -242.090702) (xy 128.273048 -242.046506) (xy 127.917448 -242.046506) (xy 127.917448 -242.090702)
			(xy 127.964438 -242.243102) (xy 128.226058 -242.243102)
		)
		(stroke
			(width 0)
			(type solid)
		)
		(fill yes)
		(layer "In11.Cu")
		(net "M_H_CPU1_SB_DQS_DN<4>")
	)
	(gr_poly
		(pts
			(xy 128.273048 -240.871502) (xy 128.226058 -240.719102) (xy 127.964438 -240.719102) (xy 127.917448 -240.871502)
			(xy 127.917448 -240.915698) (xy 128.273048 -240.915698)
		)
		(stroke
			(width 0)
			(type solid)
		)
		(fill yes)
		(layer "In11.Cu")
		(net "M_H_CPU1_SB_CB<2>")
	)
	(gr_poly
		(pts
			(xy 128.273048 -240.46307) (xy 128.273048 -240.418874) (xy 127.917448 -240.418874) (xy 127.917448 -240.46307)
			(xy 127.964438 -240.61547) (xy 128.226058 -240.61547)
		)
		(stroke
			(width 0)
			(type solid)
		)
		(fill yes)
		(layer "In11.Cu")
		(net "M_H_CPU1_SB_CB<1>")
	)
	(gr_poly
		(pts
			(xy 128.273048 -239.243362) (xy 128.226058 -239.090962) (xy 127.964438 -239.090962) (xy 127.917448 -239.243362)
			(xy 127.917448 -239.287812) (xy 128.273048 -239.287812)
		)
		(stroke
			(width 0)
			(type solid)
		)
		(fill yes)
		(layer "In11.Cu")
		(net "M_H_CPU1_SB_DQ<2>")
	)
	(gr_poly
		(pts
			(xy 128.273048 -238.835438) (xy 128.273048 -238.790988) (xy 127.917448 -238.790988) (xy 127.917448 -238.835438)
			(xy 127.964438 -238.987838) (xy 128.226058 -238.987838)
		)
		(stroke
			(width 0)
			(type solid)
		)
		(fill yes)
		(layer "In11.Cu")
		(net "M_H_CPU1_SB_DQ<1>")
	)
	(gr_poly
		(pts
			(xy 128.273048 -237.61573) (xy 128.226058 -237.46333) (xy 127.964438 -237.46333) (xy 127.917448 -237.61573)
			(xy 127.917448 -237.66018) (xy 128.273048 -237.66018)
		)
		(stroke
			(width 0)
			(type solid)
		)
		(fill yes)
		(layer "In11.Cu")
		(net "M_H_CPU1_SB_DQS_DN<0>")
	)
	(gr_poly
		(pts
			(xy 128.273048 -237.207806) (xy 128.273048 -237.163356) (xy 127.917448 -237.163356) (xy 127.917448 -237.207806)
			(xy 127.964438 -237.360206) (xy 128.226058 -237.360206)
		)
		(stroke
			(width 0)
			(type solid)
		)
		(fill yes)
		(layer "In11.Cu")
		(net "M_H_CPU1_SB_DQS_DN<5>")
	)
	(gr_poly
		(pts
			(xy 128.273048 -235.988098) (xy 128.226058 -235.835698) (xy 127.964438 -235.835698) (xy 127.917448 -235.988098)
			(xy 127.917448 -236.032294) (xy 128.273048 -236.032294)
		)
		(stroke
			(width 0)
			(type solid)
		)
		(fill yes)
		(layer "In11.Cu")
		(net "M_H_CPU1_SB_DQ<6>")
	)
	(gr_poly
		(pts
			(xy 128.273048 -235.579666) (xy 128.273048 -235.53547) (xy 127.917448 -235.53547) (xy 127.917448 -235.579666)
			(xy 127.964438 -235.732066) (xy 128.226058 -235.732066)
		)
		(stroke
			(width 0)
			(type solid)
		)
		(fill yes)
		(layer "In11.Cu")
		(net "M_H_CPU1_SB_DQ<5>")
	)
	(gr_poly
		(pts
			(xy 128.273048 -234.360466) (xy 128.226058 -234.208066) (xy 127.964438 -234.208066) (xy 127.917448 -234.360466)
			(xy 127.917448 -234.404662) (xy 128.273048 -234.404662)
		)
		(stroke
			(width 0)
			(type solid)
		)
		(fill yes)
		(layer "In11.Cu")
		(net "M_H_CPU1_SB_DQ<10>")
	)
	(gr_poly
		(pts
			(xy 128.273048 -233.952034) (xy 128.273048 -233.907838) (xy 127.917448 -233.907838) (xy 127.917448 -233.952034)
			(xy 127.964438 -234.104434) (xy 128.226058 -234.104434)
		)
		(stroke
			(width 0)
			(type solid)
		)
		(fill yes)
		(layer "In11.Cu")
		(net "M_H_CPU1_SB_DQ<9>")
	)
	(gr_poly
		(pts
			(xy 128.273048 -232.732326) (xy 128.226058 -232.579926) (xy 127.964438 -232.579926) (xy 127.917448 -232.732326)
			(xy 127.917448 -232.776776) (xy 128.273048 -232.776776)
		)
		(stroke
			(width 0)
			(type solid)
		)
		(fill yes)
		(layer "In11.Cu")
		(net "M_H_CPU1_SB_DQS_DN<1>")
	)
	(gr_poly
		(pts
			(xy 128.273048 -232.324402) (xy 128.273048 -232.279952) (xy 127.917448 -232.279952) (xy 127.917448 -232.324402)
			(xy 127.964438 -232.476802) (xy 128.226058 -232.476802)
		)
		(stroke
			(width 0)
			(type solid)
		)
		(fill yes)
		(layer "In11.Cu")
		(net "M_H_CPU1_SB_DQS_DN<6>")
	)
	(gr_poly
		(pts
			(xy 128.273048 -231.104694) (xy 128.226058 -230.952294) (xy 127.964438 -230.952294) (xy 127.917448 -231.104694)
			(xy 127.917448 -231.14889) (xy 128.273048 -231.14889)
		)
		(stroke
			(width 0)
			(type solid)
		)
		(fill yes)
		(layer "In11.Cu")
		(net "M_H_CPU1_SB_DQ<14>")
	)
	(gr_poly
		(pts
			(xy 128.273048 -230.696262) (xy 128.273048 -230.652066) (xy 127.917448 -230.652066) (xy 127.917448 -230.696262)
			(xy 127.964438 -230.848662) (xy 128.226058 -230.848662)
		)
		(stroke
			(width 0)
			(type solid)
		)
		(fill yes)
		(layer "In11.Cu")
		(net "M_H_CPU1_SB_DQ<13>")
	)
	(gr_poly
		(pts
			(xy 128.273048 -229.477062) (xy 128.226058 -229.324662) (xy 127.964438 -229.324662) (xy 127.917448 -229.477062)
			(xy 127.917448 -229.521258) (xy 128.273048 -229.521258)
		)
		(stroke
			(width 0)
			(type solid)
		)
		(fill yes)
		(layer "In11.Cu")
		(net "M_H_CPU1_SB_DQ<24>")
	)
	(gr_poly
		(pts
			(xy 128.273048 -229.06863) (xy 128.273048 -229.024434) (xy 127.917448 -229.024434) (xy 127.917448 -229.06863)
			(xy 127.964438 -229.22103) (xy 128.226058 -229.22103)
		)
		(stroke
			(width 0)
			(type solid)
		)
		(fill yes)
		(layer "In11.Cu")
		(net "M_H_CPU1_SB_DQ<27>")
	)
	(gr_poly
		(pts
			(xy 128.273048 -225.813366) (xy 128.273048 -225.768916) (xy 127.917448 -225.768916) (xy 127.917448 -225.813366)
			(xy 127.964438 -225.965766) (xy 128.226058 -225.965766)
		)
		(stroke
			(width 0)
			(type solid)
		)
		(fill yes)
		(layer "In11.Cu")
		(net "M_H_CPU1_SB_DQ<31>")
	)
	(gr_poly
		(pts
			(xy 128.345438 -279.816306) (xy 128.453896 -279.699466) (xy 128.323086 -279.472898) (xy 128.167638 -279.508458)
			(xy 128.129284 -279.530556) (xy 128.307084 -279.838404)
		)
		(stroke
			(width 0)
			(type solid)
		)
		(fill yes)
		(layer "In11.Cu")
		(net "M_H_CPU1_SA_DQ<11>")
	)
	(gr_poly
		(pts
			(xy 128.345438 -276.560788) (xy 128.453896 -276.443948) (xy 128.323086 -276.21738) (xy 128.167638 -276.25294)
			(xy 128.129284 -276.275038) (xy 128.307084 -276.582886)
		)
		(stroke
			(width 0)
			(type solid)
		)
		(fill yes)
		(layer "In11.Cu")
		(net "M_H_CPU1_SA_DQ<14>")
	)
	(gr_poly
		(pts
			(xy 128.345438 -274.932902) (xy 128.453896 -274.816062) (xy 128.323086 -274.589494) (xy 128.167638 -274.625054)
			(xy 128.129284 -274.647152) (xy 128.307084 -274.955)
		)
		(stroke
			(width 0)
			(type solid)
		)
		(fill yes)
		(layer "In11.Cu")
		(net "M_H_CPU1_SA_DQ<15>")
	)
	(gr_poly
		(pts
			(xy 128.345438 -273.30527) (xy 128.453896 -273.18843) (xy 128.323086 -272.961862) (xy 128.167638 -272.997422)
			(xy 128.129284 -273.01952) (xy 128.307084 -273.327368)
		)
		(stroke
			(width 0)
			(type solid)
		)
		(fill yes)
		(layer "In11.Cu")
		(net "M_H_CPU1_SA_DQ<18>")
	)
	(gr_poly
		(pts
			(xy 128.345438 -271.677384) (xy 128.453896 -271.560544) (xy 128.323086 -271.333976) (xy 128.167638 -271.369536)
			(xy 128.129284 -271.391634) (xy 128.307084 -271.699482)
		)
		(stroke
			(width 0)
			(type solid)
		)
		(fill yes)
		(layer "In11.Cu")
		(net "M_H_CPU1_SA_DQ<19>")
	)
	(gr_poly
		(pts
			(xy 128.37033 -265.109706) (xy 128.37033 -265.06551) (xy 128.01473 -265.06551) (xy 128.01473 -265.109706)
			(xy 128.06172 -265.262106) (xy 128.32334 -265.262106)
		)
		(stroke
			(width 0)
			(type solid)
		)
		(fill yes)
		(layer "In11.Cu")
		(net "M_H_CPU1_SA_DQS_DN<8>")
	)
	(gr_poly
		(pts
			(xy 128.371092 -268.77391) (xy 128.324102 -268.62151) (xy 128.062482 -268.62151) (xy 128.015492 -268.77391)
			(xy 128.015492 -268.81836) (xy 128.371092 -268.81836)
		)
		(stroke
			(width 0)
			(type solid)
		)
		(fill yes)
		(layer "In11.Cu")
		(net "M_H_CPU1_SA_DQ<22>")
	)
	(gr_poly
		(pts
			(xy 128.38049 -278.540718) (xy 128.3335 -278.388318) (xy 128.07188 -278.388318) (xy 128.02489 -278.540718)
			(xy 128.02489 -278.585168) (xy 128.38049 -278.585168)
		)
		(stroke
			(width 0)
			(type solid)
		)
		(fill yes)
		(layer "In11.Cu")
		(net "M_H_CPU1_SA_DQS_DN<1>")
	)
	(gr_poly
		(pts
			(xy 128.38049 -257.37947) (xy 128.3335 -257.22707) (xy 128.07188 -257.22707) (xy 128.02489 -257.37947)
			(xy 128.02489 -257.423666) (xy 128.38049 -257.423666)
		)
		(stroke
			(width 0)
			(type solid)
		)
		(fill yes)
		(layer "In11.Cu")
		(net "M_H_CPU1_ALERT_N")
	)
	(gr_poly
		(pts
			(xy 128.38049 -256.971038) (xy 128.38049 -256.926842) (xy 128.02489 -256.926842) (xy 128.02489 -256.971038)
			(xy 128.07188 -257.123438) (xy 128.3335 -257.123438)
		)
		(stroke
			(width 0)
			(type solid)
		)
		(fill yes)
		(layer "In11.Cu")
		(net "M_H_CPU1_SA_CS_N<0>")
	)
	(gr_poly
		(pts
			(xy 128.38049 -254.124206) (xy 128.3335 -253.971806) (xy 128.07188 -253.971806) (xy 128.02489 -254.124206)
			(xy 128.02489 -254.168402) (xy 128.38049 -254.168402)
		)
		(stroke
			(width 0)
			(type solid)
		)
		(fill yes)
		(layer "In11.Cu")
		(net "M_H_CPU1_SA_CA<3>")
	)
	(gr_poly
		(pts
			(xy 128.38303 -281.387804) (xy 128.38303 -281.343608) (xy 128.02743 -281.343608) (xy 128.02743 -281.387804)
			(xy 128.07442 -281.540204) (xy 128.33604 -281.540204)
		)
		(stroke
			(width 0)
			(type solid)
		)
		(fill yes)
		(layer "In11.Cu")
		(net "M_H_CPU1_SA_DQ<8>")
	)
	(gr_poly
		(pts
			(xy 128.38303 -278.132286) (xy 128.38303 -278.08809) (xy 128.02743 -278.08809) (xy 128.02743 -278.132286)
			(xy 128.07442 -278.284686) (xy 128.33604 -278.284686)
		)
		(stroke
			(width 0)
			(type solid)
		)
		(fill yes)
		(layer "In11.Cu")
		(net "M_H_CPU1_SA_DQS_DN<6>")
	)
	(gr_poly
		(pts
			(xy 128.38303 -270.401542) (xy 128.33604 -270.249142) (xy 128.07442 -270.249142) (xy 128.02743 -270.401542)
			(xy 128.02743 -270.445992) (xy 128.38303 -270.445992)
		)
		(stroke
			(width 0)
			(type solid)
		)
		(fill yes)
		(layer "In11.Cu")
		(net "M_H_CPU1_SA_DQS_DN<2>")
	)
	(gr_poly
		(pts
			(xy 128.38303 -269.993618) (xy 128.38303 -269.949168) (xy 128.02743 -269.949168) (xy 128.02743 -269.993618)
			(xy 128.07442 -270.146018) (xy 128.33604 -270.146018)
		)
		(stroke
			(width 0)
			(type solid)
		)
		(fill yes)
		(layer "In11.Cu")
		(net "M_H_CPU1_SA_DQS_DN<7>")
	)
	(gr_poly
		(pts
			(xy 128.38303 -268.365478) (xy 128.38303 -268.321282) (xy 128.02743 -268.321282) (xy 128.02743 -268.365478)
			(xy 128.07442 -268.517878) (xy 128.33604 -268.517878)
		)
		(stroke
			(width 0)
			(type solid)
		)
		(fill yes)
		(layer "In11.Cu")
		(net "M_H_CPU1_SA_DQ<21>")
	)
	(gr_poly
		(pts
			(xy 128.38303 -267.14577) (xy 128.33604 -266.99337) (xy 128.07442 -266.99337) (xy 128.02743 -267.14577)
			(xy 128.02743 -267.19022) (xy 128.38303 -267.19022)
		)
		(stroke
			(width 0)
			(type solid)
		)
		(fill yes)
		(layer "In11.Cu")
		(net "M_H_CPU1_SA_DQ<26>")
	)
	(gr_poly
		(pts
			(xy 128.38303 -266.737846) (xy 128.38303 -266.69365) (xy 128.02743 -266.69365) (xy 128.02743 -266.737846)
			(xy 128.07442 -266.890246) (xy 128.33604 -266.890246)
		)
		(stroke
			(width 0)
			(type solid)
		)
		(fill yes)
		(layer "In11.Cu")
		(net "M_H_CPU1_SA_DQ<25>")
	)
	(gr_poly
		(pts
			(xy 128.38303 -265.518138) (xy 128.33604 -265.365738) (xy 128.07442 -265.365738) (xy 128.02743 -265.518138)
			(xy 128.02743 -265.562588) (xy 128.38303 -265.562588)
		)
		(stroke
			(width 0)
			(type solid)
		)
		(fill yes)
		(layer "In11.Cu")
		(net "M_H_CPU1_SA_DQS_DN<3>")
	)
	(gr_poly
		(pts
			(xy 128.38303 -263.890506) (xy 128.33604 -263.738106) (xy 128.07442 -263.738106) (xy 128.02743 -263.890506)
			(xy 128.02743 -263.934956) (xy 128.38303 -263.934956)
		)
		(stroke
			(width 0)
			(type solid)
		)
		(fill yes)
		(layer "In11.Cu")
		(net "M_H_CPU1_SA_DQ<30>")
	)
	(gr_poly
		(pts
			(xy 128.38303 -263.482582) (xy 128.38303 -263.438132) (xy 128.02743 -263.438132) (xy 128.02743 -263.482582)
			(xy 128.07442 -263.634982) (xy 128.33604 -263.634982)
		)
		(stroke
			(width 0)
			(type solid)
		)
		(fill yes)
		(layer "In11.Cu")
		(net "M_H_CPU1_SA_DQ<29>")
	)
	(gr_poly
		(pts
			(xy 128.38303 -262.262874) (xy 128.33604 -262.110474) (xy 128.07442 -262.110474) (xy 128.02743 -262.262874)
			(xy 128.02743 -262.30707) (xy 128.38303 -262.30707)
		)
		(stroke
			(width 0)
			(type solid)
		)
		(fill yes)
		(layer "In11.Cu")
		(net "M_H_CPU1_SA_CB<2>")
	)
	(gr_poly
		(pts
			(xy 128.38303 -261.854442) (xy 128.38303 -261.810246) (xy 128.02743 -261.810246) (xy 128.02743 -261.854442)
			(xy 128.07442 -262.006842) (xy 128.33604 -262.006842)
		)
		(stroke
			(width 0)
			(type solid)
		)
		(fill yes)
		(layer "In11.Cu")
		(net "M_H_CPU1_SA_CB<1>")
	)
	(gr_poly
		(pts
			(xy 128.38303 -260.634734) (xy 128.33604 -260.482334) (xy 128.07442 -260.482334) (xy 128.02743 -260.634734)
			(xy 128.02743 -260.679184) (xy 128.38303 -260.679184)
		)
		(stroke
			(width 0)
			(type solid)
		)
		(fill yes)
		(layer "In11.Cu")
		(net "M_H_CPU1_SA_DQS_DN<4>")
	)
	(gr_poly
		(pts
			(xy 128.38303 -260.22681) (xy 128.38303 -260.18236) (xy 128.02743 -260.18236) (xy 128.02743 -260.22681)
			(xy 128.07442 -260.37921) (xy 128.33604 -260.37921)
		)
		(stroke
			(width 0)
			(type solid)
		)
		(fill yes)
		(layer "In11.Cu")
		(net "M_H_CPU1_SA_DQS_DN<9>")
	)
	(gr_poly
		(pts
			(xy 128.38303 -259.007102) (xy 128.33604 -258.854702) (xy 128.07442 -258.854702) (xy 128.02743 -259.007102)
			(xy 128.02743 -259.051552) (xy 128.38303 -259.051552)
		)
		(stroke
			(width 0)
			(type solid)
		)
		(fill yes)
		(layer "In11.Cu")
		(net "M_H_CPU1_SA_CB<6>")
	)
	(gr_poly
		(pts
			(xy 128.38303 -258.599178) (xy 128.38303 -258.554728) (xy 128.02743 -258.554728) (xy 128.02743 -258.599178)
			(xy 128.07442 -258.751578) (xy 128.33604 -258.751578)
		)
		(stroke
			(width 0)
			(type solid)
		)
		(fill yes)
		(layer "In11.Cu")
		(net "M_H_CPU1_SA_CB<5>")
	)
	(gr_poly
		(pts
			(xy 128.38303 -255.751838) (xy 128.33604 -255.599438) (xy 128.07442 -255.599438) (xy 128.02743 -255.751838)
			(xy 128.02743 -255.796034) (xy 128.38303 -255.796034)
		)
		(stroke
			(width 0)
			(type solid)
		)
		(fill yes)
		(layer "In11.Cu")
		(net "M_H_CPU1_SA_CS_N<3>")
	)
	(gr_poly
		(pts
			(xy 128.38303 -255.343406) (xy 128.38303 -255.29921) (xy 128.02743 -255.29921) (xy 128.02743 -255.343406)
			(xy 128.07442 -255.495806) (xy 128.33604 -255.495806)
		)
		(stroke
			(width 0)
			(type solid)
		)
		(fill yes)
		(layer "In11.Cu")
		(net "M_H_CPU1_SA_CA<1>")
	)
	(gr_poly
		(pts
			(xy 128.583944 -246.817134) (xy 128.622298 -246.795036) (xy 128.444498 -246.487188) (xy 128.406144 -246.509286)
			(xy 128.297686 -246.626126) (xy 128.428496 -246.852694)
		)
		(stroke
			(width 0)
			(type solid)
		)
		(fill yes)
		(layer "In11.Cu")
		(net "M_H_CPU1_SB_CA<4>")
	)
	(gr_poly
		(pts
			(xy 128.693926 -276.347428) (xy 128.73228 -276.32533) (xy 128.55448 -276.017482) (xy 128.516126 -276.03958)
			(xy 128.407668 -276.15642) (xy 128.538478 -276.382988)
		)
		(stroke
			(width 0)
			(type solid)
		)
		(fill yes)
		(layer "In11.Cu")
		(net "M_H_CPU1_SA_DQ<13>")
	)
	(gr_poly
		(pts
			(xy 128.695704 -279.605994) (xy 128.734058 -279.583896) (xy 128.556258 -279.276048) (xy 128.517904 -279.298146)
			(xy 128.409446 -279.414986) (xy 128.540256 -279.641554)
		)
		(stroke
			(width 0)
			(type solid)
		)
		(fill yes)
		(layer "In11.Cu")
		(net "M_H_CPU1_SA_DQS_DP<1>")
	)
	(gr_poly
		(pts
			(xy 128.695704 -274.72259) (xy 128.734058 -274.700492) (xy 128.556258 -274.392644) (xy 128.517904 -274.414742)
			(xy 128.409446 -274.531582) (xy 128.540256 -274.75815)
		)
		(stroke
			(width 0)
			(type solid)
		)
		(fill yes)
		(layer "In11.Cu")
		(net "M_H_CPU1_SA_DQ<16>")
	)
	(gr_poly
		(pts
			(xy 128.695704 -271.467072) (xy 128.734058 -271.444974) (xy 128.556258 -271.137126) (xy 128.517904 -271.159224)
			(xy 128.409446 -271.276064) (xy 128.540256 -271.502632)
		)
		(stroke
			(width 0)
			(type solid)
		)
		(fill yes)
		(layer "In11.Cu")
		(net "M_H_CPU1_SA_DQS_DP<2>")
	)
	(gr_poly
		(pts
			(xy 128.72593 -248.196354) (xy 128.67894 -248.043954) (xy 128.41732 -248.043954) (xy 128.37033 -248.196354)
			(xy 128.37033 -248.24055) (xy 128.72593 -248.24055)
		)
		(stroke
			(width 0)
			(type solid)
		)
		(fill yes)
		(layer "In11.Cu")
		(net "M_H_CPU1_SB_CA<1>")
	)
	(gr_poly
		(pts
			(xy 128.72593 -247.787922) (xy 128.72593 -247.743726) (xy 128.37033 -247.743726) (xy 128.37033 -247.787922)
			(xy 128.41732 -247.940322) (xy 128.67894 -247.940322)
		)
		(stroke
			(width 0)
			(type solid)
		)
		(fill yes)
		(layer "In11.Cu")
		(net "M_H_CPU1_SB_CA<2>")
	)
	(gr_poly
		(pts
			(xy 128.72593 -244.532658) (xy 128.72593 -244.488208) (xy 128.37033 -244.488208) (xy 128.37033 -244.532658)
			(xy 128.41732 -244.685058) (xy 128.67894 -244.685058)
		)
		(stroke
			(width 0)
			(type solid)
		)
		(fill yes)
		(layer "In11.Cu")
		(net "M_H_CPU1_SB_CB<6>")
	)
	(gr_poly
		(pts
			(xy 128.72593 -243.31295) (xy 128.67894 -243.16055) (xy 128.41732 -243.16055) (xy 128.37033 -243.31295)
			(xy 128.37033 -243.3574) (xy 128.72593 -243.3574)
		)
		(stroke
			(width 0)
			(type solid)
		)
		(fill yes)
		(layer "In11.Cu")
		(net "M_H_CPU1_SB_CB<5>")
	)
	(gr_poly
		(pts
			(xy 128.72593 -242.905026) (xy 128.72593 -242.860576) (xy 128.37033 -242.860576) (xy 128.37033 -242.905026)
			(xy 128.41732 -243.057426) (xy 128.67894 -243.057426)
		)
		(stroke
			(width 0)
			(type solid)
		)
		(fill yes)
		(layer "In11.Cu")
		(net "M_H_CPU1_SB_DQS_DP<9>")
	)
	(gr_poly
		(pts
			(xy 128.72593 -240.057178) (xy 128.67894 -239.904778) (xy 128.41732 -239.904778) (xy 128.37033 -240.057178)
			(xy 128.37033 -240.101628) (xy 128.72593 -240.101628)
		)
		(stroke
			(width 0)
			(type solid)
		)
		(fill yes)
		(layer "In11.Cu")
		(net "M_H_CPU1_SB_CB<3>")
	)
	(gr_poly
		(pts
			(xy 128.72593 -239.649254) (xy 128.72593 -239.604804) (xy 128.37033 -239.604804) (xy 128.37033 -239.649254)
			(xy 128.41732 -239.801654) (xy 128.67894 -239.801654)
		)
		(stroke
			(width 0)
			(type solid)
		)
		(fill yes)
		(layer "In11.Cu")
		(net "M_H_CPU1_SB_DQ<0>")
	)
	(gr_poly
		(pts
			(xy 128.72593 -238.429546) (xy 128.67894 -238.277146) (xy 128.41732 -238.277146) (xy 128.37033 -238.429546)
			(xy 128.37033 -238.473996) (xy 128.72593 -238.473996)
		)
		(stroke
			(width 0)
			(type solid)
		)
		(fill yes)
		(layer "In11.Cu")
		(net "M_H_CPU1_SB_DQ<3>")
	)
	(gr_poly
		(pts
			(xy 128.72593 -238.021622) (xy 128.72593 -237.977172) (xy 128.37033 -237.977172) (xy 128.37033 -238.021622)
			(xy 128.41732 -238.174022) (xy 128.67894 -238.174022)
		)
		(stroke
			(width 0)
			(type solid)
		)
		(fill yes)
		(layer "In11.Cu")
		(net "M_H_CPU1_SB_DQS_DP<0>")
	)
	(gr_poly
		(pts
			(xy 128.72593 -235.174282) (xy 128.67894 -235.021882) (xy 128.41732 -235.021882) (xy 128.37033 -235.174282)
			(xy 128.37033 -235.218478) (xy 128.72593 -235.218478)
		)
		(stroke
			(width 0)
			(type solid)
		)
		(fill yes)
		(layer "In11.Cu")
		(net "M_H_CPU1_SB_DQ<7>")
	)
	(gr_poly
		(pts
			(xy 128.72593 -234.76585) (xy 128.72593 -234.721654) (xy 128.37033 -234.721654) (xy 128.37033 -234.76585)
			(xy 128.41732 -234.91825) (xy 128.67894 -234.91825)
		)
		(stroke
			(width 0)
			(type solid)
		)
		(fill yes)
		(layer "In11.Cu")
		(net "M_H_CPU1_SB_DQ<8>")
	)
	(gr_poly
		(pts
			(xy 128.72593 -233.138218) (xy 128.72593 -233.093768) (xy 128.37033 -233.093768) (xy 128.37033 -233.138218)
			(xy 128.41732 -233.290618) (xy 128.67894 -233.290618)
		)
		(stroke
			(width 0)
			(type solid)
		)
		(fill yes)
		(layer "In11.Cu")
		(net "M_H_CPU1_SB_DQS_DP<1>")
	)
	(gr_poly
		(pts
			(xy 128.72593 -230.290878) (xy 128.67894 -230.138478) (xy 128.41732 -230.138478) (xy 128.37033 -230.290878)
			(xy 128.37033 -230.335074) (xy 128.72593 -230.335074)
		)
		(stroke
			(width 0)
			(type solid)
		)
		(fill yes)
		(layer "In11.Cu")
		(net "M_H_CPU1_SB_DQ<15>")
	)
	(gr_poly
		(pts
			(xy 128.72593 -229.882446) (xy 128.72593 -229.83825) (xy 128.37033 -229.83825) (xy 128.37033 -229.882446)
			(xy 128.41732 -230.034846) (xy 128.67894 -230.034846)
		)
		(stroke
			(width 0)
			(type solid)
		)
		(fill yes)
		(layer "In11.Cu")
		(net "M_H_CPU1_SB_DQ<26>")
	)
	(gr_poly
		(pts
			(xy 128.72593 -228.663246) (xy 128.67894 -228.510846) (xy 128.41732 -228.510846) (xy 128.37033 -228.663246)
			(xy 128.37033 -228.707442) (xy 128.72593 -228.707442)
		)
		(stroke
			(width 0)
			(type solid)
		)
		(fill yes)
		(layer "In11.Cu")
		(net "M_H_CPU1_SB_DQ<25>")
	)
	(gr_poly
		(pts
			(xy 128.72593 -225.407474) (xy 128.67894 -225.255074) (xy 128.41732 -225.255074) (xy 128.37033 -225.407474)
			(xy 128.37033 -225.45167) (xy 128.72593 -225.45167)
		)
		(stroke
			(width 0)
			(type solid)
		)
		(fill yes)
		(layer "In11.Cu")
		(net "M_H_CPU1_SB_DQ<29>")
	)
	(gr_poly
		(pts
			(xy 128.72847 -241.276886) (xy 128.72847 -241.23269) (xy 128.37287 -241.23269) (xy 128.37287 -241.276886)
			(xy 128.41986 -241.429286) (xy 128.68148 -241.429286)
		)
		(stroke
			(width 0)
			(type solid)
		)
		(fill yes)
		(layer "In11.Cu")
		(net "M_H_CPU1_SB_CB<0>")
	)
	(gr_poly
		(pts
			(xy 128.72847 -236.39399) (xy 128.72847 -236.34954) (xy 128.37287 -236.34954) (xy 128.37287 -236.39399)
			(xy 128.41986 -236.54639) (xy 128.68148 -236.54639)
		)
		(stroke
			(width 0)
			(type solid)
		)
		(fill yes)
		(layer "In11.Cu")
		(net "M_H_CPU1_SB_DQ<4>")
	)
	(gr_poly
		(pts
			(xy 128.72847 -231.510586) (xy 128.72847 -231.466136) (xy 128.37287 -231.466136) (xy 128.37287 -231.510586)
			(xy 128.41986 -231.662986) (xy 128.68148 -231.662986)
		)
		(stroke
			(width 0)
			(type solid)
		)
		(fill yes)
		(layer "In11.Cu")
		(net "M_H_CPU1_SB_DQ<12>")
	)
	(gr_poly
		(pts
			(xy 128.72847 -226.626674) (xy 128.72847 -226.582478) (xy 128.37287 -226.582478) (xy 128.37287 -226.626674)
			(xy 128.41986 -226.779074) (xy 128.68148 -226.779074)
		)
		(stroke
			(width 0)
			(type solid)
		)
		(fill yes)
		(layer "In11.Cu")
		(net "M_H_CPU1_SB_DQ<30>")
	)
	(gr_poly
		(pts
			(xy 128.728724 -233.54665) (xy 128.681734 -233.39425) (xy 128.420114 -233.39425) (xy 128.373124 -233.54665)
			(xy 128.373124 -233.590846) (xy 128.728724 -233.590846)
		)
		(stroke
			(width 0)
			(type solid)
		)
		(fill yes)
		(layer "In11.Cu")
		(net "M_H_CPU1_SB_DQ<11>")
	)
	(gr_poly
		(pts
			(xy 128.734312 -228.254814) (xy 128.734312 -228.210364) (xy 128.378712 -228.210364) (xy 128.378712 -228.254814)
			(xy 128.425702 -228.407214) (xy 128.687322 -228.407214)
		)
		(stroke
			(width 0)
			(type solid)
		)
		(fill yes)
		(layer "In11.Cu")
		(net "M_H_CPU1_SB_DQS_DN<8>")
	)
	(gr_poly
		(pts
			(xy 128.734566 -241.685826) (xy 128.687576 -241.533426) (xy 128.425956 -241.533426) (xy 128.378966 -241.685826)
			(xy 128.378966 -241.730022) (xy 128.734566 -241.730022)
		)
		(stroke
			(width 0)
			(type solid)
		)
		(fill yes)
		(layer "In11.Cu")
		(net "M_H_CPU1_SB_DQS_DP<4>")
	)
	(gr_poly
		(pts
			(xy 128.734566 -236.802422) (xy 128.687576 -236.650022) (xy 128.425956 -236.650022) (xy 128.378966 -236.802422)
			(xy 128.378966 -236.846872) (xy 128.734566 -236.846872)
		)
		(stroke
			(width 0)
			(type solid)
		)
		(fill yes)
		(layer "In11.Cu")
		(net "M_H_CPU1_SB_DQS_DP<5>")
	)
	(gr_poly
		(pts
			(xy 128.734566 -231.919018) (xy 128.687576 -231.766618) (xy 128.425956 -231.766618) (xy 128.378966 -231.919018)
			(xy 128.378966 -231.963468) (xy 128.734566 -231.963468)
		)
		(stroke
			(width 0)
			(type solid)
		)
		(fill yes)
		(layer "In11.Cu")
		(net "M_H_CPU1_SB_DQS_DP<6>")
	)
	(gr_poly
		(pts
			(xy 128.740408 -227.035614) (xy 128.693418 -226.883214) (xy 128.431798 -226.883214) (xy 128.384808 -227.035614)
			(xy 128.384808 -227.07981) (xy 128.740408 -227.07981)
		)
		(stroke
			(width 0)
			(type solid)
		)
		(fill yes)
		(layer "In11.Cu")
		(net "M_H_CPU1_SB_DQS_DN<3>")
	)
	(gr_poly
		(pts
			(xy 128.80975 -274.109434) (xy 128.918208 -273.992594) (xy 128.787398 -273.766026) (xy 128.63195 -273.801586)
			(xy 128.593596 -273.823684) (xy 128.771396 -274.131532)
		)
		(stroke
			(width 0)
			(type solid)
		)
		(fill yes)
		(layer "In11.Cu")
		(net "M_H_CPU1_SA_DQ<18>")
	)
	(gr_poly
		(pts
			(xy 128.80975 -270.853916) (xy 128.918208 -270.737076) (xy 128.787398 -270.510508) (xy 128.63195 -270.546068)
			(xy 128.593596 -270.568166) (xy 128.771396 -270.876014)
		)
		(stroke
			(width 0)
			(type solid)
		)
		(fill yes)
		(layer "In11.Cu")
		(net "M_H_CPU1_SA_DQS_DN<2>")
	)
	(gr_poly
		(pts
			(xy 128.810004 -275.737828) (xy 128.918462 -275.620988) (xy 128.787652 -275.39442) (xy 128.632204 -275.42998)
			(xy 128.59385 -275.452078) (xy 128.77165 -275.759926)
		)
		(stroke
			(width 0)
			(type solid)
		)
		(fill yes)
		(layer "In11.Cu")
		(net "M_H_CPU1_SA_DQ<15>")
	)
	(gr_poly
		(pts
			(xy 128.810766 -278.995378) (xy 128.919224 -278.878538) (xy 128.788414 -278.65197) (xy 128.632966 -278.68753)
			(xy 128.594612 -278.709628) (xy 128.772412 -279.017476)
		)
		(stroke
			(width 0)
			(type solid)
		)
		(fill yes)
		(layer "In11.Cu")
		(net "M_H_CPU1_SA_DQS_DN<1>")
	)
	(gr_poly
		(pts
			(xy 128.835912 -280.98242) (xy 128.788922 -280.83002) (xy 128.527302 -280.83002) (xy 128.480312 -280.98242)
			(xy 128.480312 -281.026616) (xy 128.835912 -281.026616)
		)
		(stroke
			(width 0)
			(type solid)
		)
		(fill yes)
		(layer "In11.Cu")
		(net "M_H_CPU1_SA_DQ<10>")
	)
	(gr_poly
		(pts
			(xy 128.835912 -280.574242) (xy 128.835912 -280.529792) (xy 128.480312 -280.529792) (xy 128.480312 -280.574242)
			(xy 128.527302 -280.726642) (xy 128.788922 -280.726642)
		)
		(stroke
			(width 0)
			(type solid)
		)
		(fill yes)
		(layer "In11.Cu")
		(net "M_H_CPU1_SA_DQ<9>")
	)
	(gr_poly
		(pts
			(xy 128.835912 -277.726394) (xy 128.788922 -277.573994) (xy 128.527302 -277.573994) (xy 128.480312 -277.726394)
			(xy 128.480312 -277.770844) (xy 128.835912 -277.770844)
		)
		(stroke
			(width 0)
			(type solid)
		)
		(fill yes)
		(layer "In11.Cu")
		(net "M_H_CPU1_SA_DQS_DP<6>")
	)
	(gr_poly
		(pts
			(xy 128.835912 -277.318216) (xy 128.835912 -277.27402) (xy 128.480312 -277.27402) (xy 128.480312 -277.318216)
			(xy 128.527302 -277.470616) (xy 128.788922 -277.470616)
		)
		(stroke
			(width 0)
			(type solid)
		)
		(fill yes)
		(layer "In11.Cu")
		(net "M_H_CPU1_SA_DQ<12>")
	)
	(gr_poly
		(pts
			(xy 128.835912 -272.435066) (xy 128.835912 -272.39087) (xy 128.480312 -272.39087) (xy 128.480312 -272.435066)
			(xy 128.527302 -272.587466) (xy 128.788922 -272.587466)
		)
		(stroke
			(width 0)
			(type solid)
		)
		(fill yes)
		(layer "In11.Cu")
		(net "M_H_CPU1_SA_DQ<17>")
	)
	(gr_poly
		(pts
			(xy 128.835912 -269.587726) (xy 128.788922 -269.435326) (xy 128.527302 -269.435326) (xy 128.480312 -269.587726)
			(xy 128.480312 -269.631922) (xy 128.835912 -269.631922)
		)
		(stroke
			(width 0)
			(type solid)
		)
		(fill yes)
		(layer "In11.Cu")
		(net "M_H_CPU1_SA_DQS_DP<7>")
	)
	(gr_poly
		(pts
			(xy 128.835912 -267.960094) (xy 128.788922 -267.807694) (xy 128.527302 -267.807694) (xy 128.480312 -267.960094)
			(xy 128.480312 -268.00429) (xy 128.835912 -268.00429)
		)
		(stroke
			(width 0)
			(type solid)
		)
		(fill yes)
		(layer "In11.Cu")
		(net "M_H_CPU1_SA_DQ<23>")
	)
	(gr_poly
		(pts
			(xy 128.835912 -267.551662) (xy 128.835912 -267.507466) (xy 128.480312 -267.507466) (xy 128.480312 -267.551662)
			(xy 128.527302 -267.704062) (xy 128.788922 -267.704062)
		)
		(stroke
			(width 0)
			(type solid)
		)
		(fill yes)
		(layer "In11.Cu")
		(net "M_H_CPU1_SA_DQ<24>")
	)
	(gr_poly
		(pts
			(xy 128.835912 -266.331954) (xy 128.788922 -266.179554) (xy 128.527302 -266.179554) (xy 128.480312 -266.331954)
			(xy 128.480312 -266.376404) (xy 128.835912 -266.376404)
		)
		(stroke
			(width 0)
			(type solid)
		)
		(fill yes)
		(layer "In11.Cu")
		(net "M_H_CPU1_SA_DQ<27>")
	)
	(gr_poly
		(pts
			(xy 128.835912 -265.92403) (xy 128.835912 -265.879834) (xy 128.480312 -265.879834) (xy 128.480312 -265.92403)
			(xy 128.527302 -266.07643) (xy 128.788922 -266.07643)
		)
		(stroke
			(width 0)
			(type solid)
		)
		(fill yes)
		(layer "In11.Cu")
		(net "M_H_CPU1_SA_DQS_DP<3>")
	)
	(gr_poly
		(pts
			(xy 128.835912 -264.296398) (xy 128.835912 -264.251948) (xy 128.480312 -264.251948) (xy 128.480312 -264.296398)
			(xy 128.527302 -264.448798) (xy 128.788922 -264.448798)
		)
		(stroke
			(width 0)
			(type solid)
		)
		(fill yes)
		(layer "In11.Cu")
		(net "M_H_CPU1_SA_DQ<28>")
	)
	(gr_poly
		(pts
			(xy 128.835912 -263.07669) (xy 128.788922 -262.92429) (xy 128.527302 -262.92429) (xy 128.480312 -263.07669)
			(xy 128.480312 -263.120886) (xy 128.835912 -263.120886)
		)
		(stroke
			(width 0)
			(type solid)
		)
		(fill yes)
		(layer "In11.Cu")
		(net "M_H_CPU1_SA_DQ<31>")
	)
	(gr_poly
		(pts
			(xy 128.835912 -262.668258) (xy 128.835912 -262.624062) (xy 128.480312 -262.624062) (xy 128.480312 -262.668258)
			(xy 128.527302 -262.820658) (xy 128.788922 -262.820658)
		)
		(stroke
			(width 0)
			(type solid)
		)
		(fill yes)
		(layer "In11.Cu")
		(net "M_H_CPU1_SA_CB<0>")
	)
	(gr_poly
		(pts
			(xy 128.835912 -261.449058) (xy 128.788922 -261.296658) (xy 128.527302 -261.296658) (xy 128.480312 -261.449058)
			(xy 128.480312 -261.493254) (xy 128.835912 -261.493254)
		)
		(stroke
			(width 0)
			(type solid)
		)
		(fill yes)
		(layer "In11.Cu")
		(net "M_H_CPU1_SA_CB<3>")
	)
	(gr_poly
		(pts
			(xy 128.835912 -261.040626) (xy 128.835912 -260.99643) (xy 128.480312 -260.99643) (xy 128.480312 -261.040626)
			(xy 128.527302 -261.193026) (xy 128.788922 -261.193026)
		)
		(stroke
			(width 0)
			(type solid)
		)
		(fill yes)
		(layer "In11.Cu")
		(net "M_H_CPU1_SA_DQS_DP<4>")
	)
	(gr_poly
		(pts
			(xy 128.835912 -259.820918) (xy 128.788922 -259.668518) (xy 128.527302 -259.668518) (xy 128.480312 -259.820918)
			(xy 128.480312 -259.865368) (xy 128.835912 -259.865368)
		)
		(stroke
			(width 0)
			(type solid)
		)
		(fill yes)
		(layer "In11.Cu")
		(net "M_H_CPU1_SA_DQS_DP<9>")
	)
	(gr_poly
		(pts
			(xy 128.835912 -259.412994) (xy 128.835912 -259.368544) (xy 128.480312 -259.368544) (xy 128.480312 -259.412994)
			(xy 128.527302 -259.565394) (xy 128.788922 -259.565394)
		)
		(stroke
			(width 0)
			(type solid)
		)
		(fill yes)
		(layer "In11.Cu")
		(net "M_H_CPU1_SA_CB<4>")
	)
	(gr_poly
		(pts
			(xy 128.835912 -258.193286) (xy 128.788922 -258.040886) (xy 128.527302 -258.040886) (xy 128.480312 -258.193286)
			(xy 128.480312 -258.237482) (xy 128.835912 -258.237482)
		)
		(stroke
			(width 0)
			(type solid)
		)
		(fill yes)
		(layer "In11.Cu")
		(net "M_H_CPU1_SA_CB<7>")
	)
	(gr_poly
		(pts
			(xy 128.835912 -257.784854) (xy 128.835912 -257.740658) (xy 128.480312 -257.740658) (xy 128.480312 -257.784854)
			(xy 128.527302 -257.937254) (xy 128.788922 -257.937254)
		)
		(stroke
			(width 0)
			(type solid)
		)
		(fill yes)
		(layer "In11.Cu")
		(net "M_E_CPU1_ALERT_N")
	)
	(gr_poly
		(pts
			(xy 128.835912 -254.937514) (xy 128.788922 -254.785114) (xy 128.527302 -254.785114) (xy 128.480312 -254.937514)
			(xy 128.480312 -254.981964) (xy 128.835912 -254.981964)
		)
		(stroke
			(width 0)
			(type solid)
		)
		(fill yes)
		(layer "In11.Cu")
		(net "M_H_CPU1_SA_CA<0>")
	)
	(gr_poly
		(pts
			(xy 128.835912 -254.52959) (xy 128.835912 -254.48514) (xy 128.480312 -254.48514) (xy 128.480312 -254.52959)
			(xy 128.527302 -254.68199) (xy 128.788922 -254.68199)
		)
		(stroke
			(width 0)
			(type solid)
		)
		(fill yes)
		(layer "In11.Cu")
		(net "M_H_CPU1_SA_CA<2>")
	)
	(gr_poly
		(pts
			(xy 128.838452 -256.565654) (xy 128.791462 -256.413254) (xy 128.529842 -256.413254) (xy 128.482852 -256.565654)
			(xy 128.482852 -256.60985) (xy 128.838452 -256.60985)
		)
		(stroke
			(width 0)
			(type solid)
		)
		(fill yes)
		(layer "In11.Cu")
		(net "M_H_CPU1_SA_CS_N<1>")
	)
	(gr_poly
		(pts
			(xy 128.838452 -256.157222) (xy 128.838452 -256.113026) (xy 128.482852 -256.113026) (xy 128.482852 -256.157222)
			(xy 128.529842 -256.309622) (xy 128.791462 -256.309622)
		)
		(stroke
			(width 0)
			(type solid)
		)
		(fill yes)
		(layer "In11.Cu")
		(net "M_H_CPU1_SA_CS_N<2>")
	)
	(gr_poly
		(pts
			(xy 128.84785 -269.179294) (xy 128.84785 -269.134844) (xy 128.49225 -269.134844) (xy 128.49225 -269.179294)
			(xy 128.53924 -269.331694) (xy 128.80086 -269.331694)
		)
		(stroke
			(width 0)
			(type solid)
		)
		(fill yes)
		(layer "In11.Cu")
		(net "M_H_CPU1_SA_DQ<20>")
	)
	(gr_poly
		(pts
			(xy 128.848612 -264.70483) (xy 128.801622 -264.55243) (xy 128.540002 -264.55243) (xy 128.493012 -264.70483)
			(xy 128.493012 -264.749026) (xy 128.848612 -264.749026)
		)
		(stroke
			(width 0)
			(type solid)
		)
		(fill yes)
		(layer "In11.Cu")
		(net "M_H_CPU1_SA_DQS_DP<8>")
	)
	(gr_poly
		(pts
			(xy 129.171192 -278.80183) (xy 129.209546 -278.779732) (xy 129.031746 -278.471884) (xy 128.993392 -278.493982)
			(xy 128.884934 -278.610822) (xy 129.015744 -278.83739)
		)
		(stroke
			(width 0)
			(type solid)
		)
		(fill yes)
		(layer "In11.Cu")
		(net "M_H_CPU1_SA_DQS_DN<6>")
	)
	(gr_poly
		(pts
			(xy 129.171192 -270.662908) (xy 129.209546 -270.64081) (xy 129.031746 -270.332962) (xy 128.993392 -270.35506)
			(xy 128.884934 -270.4719) (xy 129.015744 -270.698468)
		)
		(stroke
			(width 0)
			(type solid)
		)
		(fill yes)
		(layer "In11.Cu")
		(net "M_H_CPU1_SA_DQS_DN<7>")
	)
	(gr_poly
		(pts
			(xy 129.172208 -275.547836) (xy 129.210562 -275.525738) (xy 129.032762 -275.21789) (xy 128.994408 -275.239988)
			(xy 128.88595 -275.356828) (xy 129.01676 -275.583396)
		)
		(stroke
			(width 0)
			(type solid)
		)
		(fill yes)
		(layer "In11.Cu")
		(net "M_H_CPU1_SA_DQ<16>")
	)
	(gr_poly
		(pts
			(xy 129.204466 -246.974106) (xy 129.204466 -246.929656) (xy 128.848866 -246.929656) (xy 128.848866 -246.974106)
			(xy 128.895856 -247.126506) (xy 129.157476 -247.126506)
		)
		(stroke
			(width 0)
			(type solid)
		)
		(fill yes)
		(layer "In11.Cu")
		(net "M_H_CPU1_SB_CA<4>")
	)
	(gr_poly
		(pts
			(xy 129.204466 -242.090702) (xy 129.204466 -242.046252) (xy 128.848866 -242.046252) (xy 128.848866 -242.090702)
			(xy 128.895856 -242.243102) (xy 129.157476 -242.243102)
		)
		(stroke
			(width 0)
			(type solid)
		)
		(fill yes)
		(layer "In11.Cu")
		(net "M_H_CPU1_SB_DQS_DN<4>")
	)
	(gr_poly
		(pts
			(xy 129.204466 -240.871502) (xy 129.157476 -240.719102) (xy 128.895856 -240.719102) (xy 128.848866 -240.871502)
			(xy 128.848866 -240.915952) (xy 129.204466 -240.915952)
		)
		(stroke
			(width 0)
			(type solid)
		)
		(fill yes)
		(layer "In11.Cu")
		(net "M_H_CPU1_SB_CB<2>")
	)
	(gr_poly
		(pts
			(xy 129.204466 -237.207298) (xy 129.204466 -237.163102) (xy 128.848866 -237.163102) (xy 128.848866 -237.207298)
			(xy 128.895856 -237.359698) (xy 129.157476 -237.359698)
		)
		(stroke
			(width 0)
			(type solid)
		)
		(fill yes)
		(layer "In11.Cu")
		(net "M_H_CPU1_SB_DQS_DN<5>")
	)
	(gr_poly
		(pts
			(xy 129.204466 -235.988098) (xy 129.157476 -235.835698) (xy 128.895856 -235.835698) (xy 128.848866 -235.988098)
			(xy 128.848866 -236.032548) (xy 129.204466 -236.032548)
		)
		(stroke
			(width 0)
			(type solid)
		)
		(fill yes)
		(layer "In11.Cu")
		(net "M_H_CPU1_SB_DQ<6>")
	)
	(gr_poly
		(pts
			(xy 129.204466 -232.323894) (xy 129.204466 -232.279698) (xy 128.848866 -232.279698) (xy 128.848866 -232.323894)
			(xy 128.895856 -232.476294) (xy 129.157476 -232.476294)
		)
		(stroke
			(width 0)
			(type solid)
		)
		(fill yes)
		(layer "In11.Cu")
		(net "M_H_CPU1_SB_DQS_DN<6>")
	)
	(gr_poly
		(pts
			(xy 129.204466 -231.104694) (xy 129.157476 -230.952294) (xy 128.895856 -230.952294) (xy 128.848866 -231.104694)
			(xy 128.848866 -231.149144) (xy 129.204466 -231.149144)
		)
		(stroke
			(width 0)
			(type solid)
		)
		(fill yes)
		(layer "In11.Cu")
		(net "M_H_CPU1_SB_DQ<14>")
	)
	(gr_poly
		(pts
			(xy 129.210308 -248.601738) (xy 129.210308 -248.557542) (xy 128.854708 -248.557542) (xy 128.854708 -248.601738)
			(xy 128.901698 -248.754138) (xy 129.163318 -248.754138)
		)
		(stroke
			(width 0)
			(type solid)
		)
		(fill yes)
		(layer "In11.Cu")
		(net "M_H_CPU1_SB_CA<0>")
	)
	(gr_poly
		(pts
			(xy 129.210308 -244.127274) (xy 129.163318 -243.974874) (xy 128.901698 -243.974874) (xy 128.854708 -244.127274)
			(xy 128.854708 -244.17147) (xy 129.210308 -244.17147)
		)
		(stroke
			(width 0)
			(type solid)
		)
		(fill yes)
		(layer "In11.Cu")
		(net "M_H_CPU1_SB_CB<4>")
	)
	(gr_poly
		(pts
			(xy 129.210308 -243.718334) (xy 129.210308 -243.674138) (xy 128.854708 -243.674138) (xy 128.854708 -243.718334)
			(xy 128.901698 -243.870734) (xy 129.163318 -243.870734)
		)
		(stroke
			(width 0)
			(type solid)
		)
		(fill yes)
		(layer "In11.Cu")
		(net "M_H_CPU1_SB_CB<7>")
	)
	(gr_poly
		(pts
			(xy 129.210308 -239.24387) (xy 129.163318 -239.09147) (xy 128.901698 -239.09147) (xy 128.854708 -239.24387)
			(xy 128.854708 -239.288066) (xy 129.210308 -239.288066)
		)
		(stroke
			(width 0)
			(type solid)
		)
		(fill yes)
		(layer "In11.Cu")
		(net "M_H_CPU1_SB_DQ<2>")
	)
	(gr_poly
		(pts
			(xy 129.210308 -238.83493) (xy 129.210308 -238.790734) (xy 128.854708 -238.790734) (xy 128.854708 -238.83493)
			(xy 128.901698 -238.98733) (xy 129.163318 -238.98733)
		)
		(stroke
			(width 0)
			(type solid)
		)
		(fill yes)
		(layer "In11.Cu")
		(net "M_H_CPU1_SB_DQ<1>")
	)
	(gr_poly
		(pts
			(xy 129.210308 -234.360466) (xy 129.163318 -234.208066) (xy 128.901698 -234.208066) (xy 128.854708 -234.360466)
			(xy 128.854708 -234.404916) (xy 129.210308 -234.404916)
		)
		(stroke
			(width 0)
			(type solid)
		)
		(fill yes)
		(layer "In11.Cu")
		(net "M_H_CPU1_SB_DQ<10>")
	)
	(gr_poly
		(pts
			(xy 129.210308 -233.952034) (xy 129.210308 -233.907584) (xy 128.854708 -233.907584) (xy 128.854708 -233.952034)
			(xy 128.901698 -234.104434) (xy 129.163318 -234.104434)
		)
		(stroke
			(width 0)
			(type solid)
		)
		(fill yes)
		(layer "In11.Cu")
		(net "M_H_CPU1_SB_DQ<9>")
	)
	(gr_poly
		(pts
			(xy 129.210308 -229.477062) (xy 129.163318 -229.324662) (xy 128.901698 -229.324662) (xy 128.854708 -229.477062)
			(xy 128.854708 -229.521512) (xy 129.210308 -229.521512)
		)
		(stroke
			(width 0)
			(type solid)
		)
		(fill yes)
		(layer "In11.Cu")
		(net "M_H_CPU1_SB_DQ<24>")
	)
	(gr_poly
		(pts
			(xy 129.210308 -229.06863) (xy 129.210308 -229.02418) (xy 128.854708 -229.02418) (xy 128.854708 -229.06863)
			(xy 128.901698 -229.22103) (xy 129.163318 -229.22103)
		)
		(stroke
			(width 0)
			(type solid)
		)
		(fill yes)
		(layer "In11.Cu")
		(net "M_H_CPU1_SB_DQ<27>")
	)
	(gr_poly
		(pts
			(xy 129.210308 -227.848922) (xy 129.163318 -227.696522) (xy 128.901698 -227.696522) (xy 128.854708 -227.848922)
			(xy 128.854708 -227.893372) (xy 129.210308 -227.893372)
		)
		(stroke
			(width 0)
			(type solid)
		)
		(fill yes)
		(layer "In11.Cu")
		(net "M_H_CPU1_SB_DQS_DP<8>")
	)
	(gr_poly
		(pts
			(xy 129.210308 -227.440998) (xy 129.210308 -227.396548) (xy 128.854708 -227.396548) (xy 128.854708 -227.440998)
			(xy 128.901698 -227.593398) (xy 129.163318 -227.593398)
		)
		(stroke
			(width 0)
			(type solid)
		)
		(fill yes)
		(layer "In11.Cu")
		(net "M_H_CPU1_SB_DQS_DP<3>")
	)
	(gr_poly
		(pts
			(xy 129.212848 -247.382538) (xy 129.165858 -247.230138) (xy 128.904238 -247.230138) (xy 128.857248 -247.382538)
			(xy 128.857248 -247.426734) (xy 129.212848 -247.426734)
		)
		(stroke
			(width 0)
			(type solid)
		)
		(fill yes)
		(layer "In11.Cu")
		(net "M_H_CPU1_SB_CA<3>")
	)
	(gr_poly
		(pts
			(xy 129.212848 -242.499134) (xy 129.165858 -242.346734) (xy 128.904238 -242.346734) (xy 128.857248 -242.499134)
			(xy 128.857248 -242.54333) (xy 129.212848 -242.54333)
		)
		(stroke
			(width 0)
			(type solid)
		)
		(fill yes)
		(layer "In11.Cu")
		(net "M_H_CPU1_SB_DQS_DN<9>")
	)
	(gr_poly
		(pts
			(xy 129.212848 -240.46307) (xy 129.212848 -240.418874) (xy 128.857248 -240.418874) (xy 128.857248 -240.46307)
			(xy 128.904238 -240.61547) (xy 129.165858 -240.61547)
		)
		(stroke
			(width 0)
			(type solid)
		)
		(fill yes)
		(layer "In11.Cu")
		(net "M_H_CPU1_SB_CB<1>")
	)
	(gr_poly
		(pts
			(xy 129.212848 -237.61573) (xy 129.165858 -237.46333) (xy 128.904238 -237.46333) (xy 128.857248 -237.61573)
			(xy 128.857248 -237.66018) (xy 129.212848 -237.66018)
		)
		(stroke
			(width 0)
			(type solid)
		)
		(fill yes)
		(layer "In11.Cu")
		(net "M_H_CPU1_SB_DQS_DN<0>")
	)
	(gr_poly
		(pts
			(xy 129.212848 -235.579666) (xy 129.212848 -235.53547) (xy 128.857248 -235.53547) (xy 128.857248 -235.579666)
			(xy 128.904238 -235.732066) (xy 129.165858 -235.732066)
		)
		(stroke
			(width 0)
			(type solid)
		)
		(fill yes)
		(layer "In11.Cu")
		(net "M_H_CPU1_SB_DQ<5>")
	)
	(gr_poly
		(pts
			(xy 129.212848 -232.732326) (xy 129.165858 -232.579926) (xy 128.904238 -232.579926) (xy 128.857248 -232.732326)
			(xy 128.857248 -232.776776) (xy 129.212848 -232.776776)
		)
		(stroke
			(width 0)
			(type solid)
		)
		(fill yes)
		(layer "In11.Cu")
		(net "M_H_CPU1_SB_DQS_DN<1>")
	)
	(gr_poly
		(pts
			(xy 129.212848 -230.696262) (xy 129.212848 -230.652066) (xy 128.857248 -230.652066) (xy 128.857248 -230.696262)
			(xy 128.904238 -230.848662) (xy 129.165858 -230.848662)
		)
		(stroke
			(width 0)
			(type solid)
		)
		(fill yes)
		(layer "In11.Cu")
		(net "M_H_CPU1_SB_DQ<13>")
	)
	(gr_poly
		(pts
			(xy 129.212848 -226.22129) (xy 129.165858 -226.06889) (xy 128.904238 -226.06889) (xy 128.857248 -226.22129)
			(xy 128.857248 -226.26574) (xy 129.212848 -226.26574)
		)
		(stroke
			(width 0)
			(type solid)
		)
		(fill yes)
		(layer "In11.Cu")
		(net "M_H_CPU1_SB_DQ<28>")
	)
	(gr_poly
		(pts
			(xy 129.212848 -225.813366) (xy 129.212848 -225.768916) (xy 128.857248 -225.768916) (xy 128.857248 -225.813366)
			(xy 128.904238 -225.965766) (xy 129.165858 -225.965766)
		)
		(stroke
			(width 0)
			(type solid)
		)
		(fill yes)
		(layer "In11.Cu")
		(net "M_H_CPU1_SB_DQ<31>")
	)
	(gr_poly
		(pts
			(xy 129.279904 -278.17953) (xy 129.388362 -278.06269) (xy 129.257552 -277.836122) (xy 129.102104 -277.871682)
			(xy 129.06375 -277.89378) (xy 129.24155 -278.201628)
		)
		(stroke
			(width 0)
			(type solid)
		)
		(fill yes)
		(layer "In11.Cu")
		(net "M_H_CPU1_SA_DQS_DP<6>")
	)
	(gr_poly
		(pts
			(xy 129.279904 -270.040608) (xy 129.388362 -269.923768) (xy 129.257552 -269.6972) (xy 129.102104 -269.73276)
			(xy 129.06375 -269.754858) (xy 129.24155 -270.062706)
		)
		(stroke
			(width 0)
			(type solid)
		)
		(fill yes)
		(layer "In11.Cu")
		(net "M_H_CPU1_SA_DQS_DP<7>")
	)
	(gr_poly
		(pts
			(xy 129.285238 -274.932902) (xy 129.393696 -274.816062) (xy 129.262886 -274.589494) (xy 129.107438 -274.625054)
			(xy 129.069084 -274.647152) (xy 129.246884 -274.955)
		)
		(stroke
			(width 0)
			(type solid)
		)
		(fill yes)
		(layer "In11.Cu")
		(net "M_H_CPU1_SA_DQ<18>")
	)
	(gr_poly
		(pts
			(xy 129.31013 -265.109706) (xy 129.31013 -265.06551) (xy 128.95453 -265.06551) (xy 128.95453 -265.109706)
			(xy 129.00152 -265.262106) (xy 129.26314 -265.262106)
		)
		(stroke
			(width 0)
			(type solid)
		)
		(fill yes)
		(layer "In11.Cu")
		(net "M_H_CPU1_SA_DQS_DN<8>")
	)
	(gr_poly
		(pts
			(xy 129.314194 -254.124206) (xy 129.267204 -253.971806) (xy 129.005584 -253.971806) (xy 128.958594 -254.124206)
			(xy 128.958594 -254.168402) (xy 129.314194 -254.168402)
		)
		(stroke
			(width 0)
			(type solid)
		)
		(fill yes)
		(layer "In11.Cu")
		(net "M_H_CPU1_SA_CA<3>")
	)
	(gr_poly
		(pts
			(xy 129.314448 -276.504146) (xy 129.314448 -276.45995) (xy 128.958848 -276.45995) (xy 128.958848 -276.504146)
			(xy 129.005838 -276.656546) (xy 129.267458 -276.656546)
		)
		(stroke
			(width 0)
			(type solid)
		)
		(fill yes)
		(layer "In11.Cu")
		(net "M_H_CPU1_SA_DQ<13>")
	)
	(gr_poly
		(pts
			(xy 129.314448 -256.971038) (xy 129.314448 -256.926588) (xy 128.958848 -256.926588) (xy 128.958848 -256.971038)
			(xy 129.005838 -257.123438) (xy 129.267458 -257.123438)
		)
		(stroke
			(width 0)
			(type solid)
		)
		(fill yes)
		(layer "In11.Cu")
		(net "M_H_CPU1_SA_CS_N<0>")
	)
	(gr_poly
		(pts
			(xy 129.314448 -255.751838) (xy 129.267458 -255.599438) (xy 129.005838 -255.599438) (xy 128.958848 -255.751838)
			(xy 128.958848 -255.796288) (xy 129.314448 -255.796288)
		)
		(stroke
			(width 0)
			(type solid)
		)
		(fill yes)
		(layer "In11.Cu")
		(net "M_H_CPU1_SA_CS_N<3>")
	)
	(gr_poly
		(pts
			(xy 129.32029 -263.891014) (xy 129.2733 -263.738614) (xy 129.01168 -263.738614) (xy 128.96469 -263.891014)
			(xy 128.96469 -263.93521) (xy 129.32029 -263.93521)
		)
		(stroke
			(width 0)
			(type solid)
		)
		(fill yes)
		(layer "In11.Cu")
		(net "M_H_CPU1_SA_DQ<30>")
	)
	(gr_poly
		(pts
			(xy 129.32029 -263.482074) (xy 129.32029 -263.437878) (xy 128.96469 -263.437878) (xy 128.96469 -263.482074)
			(xy 129.01168 -263.634474) (xy 129.2733 -263.634474)
		)
		(stroke
			(width 0)
			(type solid)
		)
		(fill yes)
		(layer "In11.Cu")
		(net "M_H_CPU1_SA_DQ<29>")
	)
	(gr_poly
		(pts
			(xy 129.32029 -259.00761) (xy 129.2733 -258.85521) (xy 129.01168 -258.85521) (xy 128.96469 -259.00761)
			(xy 128.96469 -259.051806) (xy 129.32029 -259.051806)
		)
		(stroke
			(width 0)
			(type solid)
		)
		(fill yes)
		(layer "In11.Cu")
		(net "M_H_CPU1_SA_CB<6>")
	)
	(gr_poly
		(pts
			(xy 129.32029 -258.59867) (xy 129.32029 -258.554474) (xy 128.96469 -258.554474) (xy 128.96469 -258.59867)
			(xy 129.01168 -258.75107) (xy 129.2733 -258.75107)
		)
		(stroke
			(width 0)
			(type solid)
		)
		(fill yes)
		(layer "In11.Cu")
		(net "M_H_CPU1_SA_CB<5>")
	)
	(gr_poly
		(pts
			(xy 129.32283 -281.387804) (xy 129.32283 -281.343608) (xy 128.96723 -281.343608) (xy 128.96723 -281.387804)
			(xy 129.01422 -281.540204) (xy 129.27584 -281.540204)
		)
		(stroke
			(width 0)
			(type solid)
		)
		(fill yes)
		(layer "In11.Cu")
		(net "M_H_CPU1_SA_DQ<8>")
	)
	(gr_poly
		(pts
			(xy 129.32283 -280.168096) (xy 129.27584 -280.015696) (xy 129.01422 -280.015696) (xy 128.96723 -280.168096)
			(xy 128.96723 -280.212546) (xy 129.32283 -280.212546)
		)
		(stroke
			(width 0)
			(type solid)
		)
		(fill yes)
		(layer "In11.Cu")
		(net "M_H_CPU1_SA_DQ<11>")
	)
	(gr_poly
		(pts
			(xy 129.32283 -279.759918) (xy 129.32283 -279.715722) (xy 128.96723 -279.715722) (xy 128.96723 -279.759918)
			(xy 129.01422 -279.912318) (xy 129.27584 -279.912318)
		)
		(stroke
			(width 0)
			(type solid)
		)
		(fill yes)
		(layer "In11.Cu")
		(net "M_H_CPU1_SA_DQS_DP<1>")
	)
	(gr_poly
		(pts
			(xy 129.32283 -276.912578) (xy 129.27584 -276.760178) (xy 129.01422 -276.760178) (xy 128.96723 -276.912578)
			(xy 128.96723 -276.957028) (xy 129.32283 -276.957028)
		)
		(stroke
			(width 0)
			(type solid)
		)
		(fill yes)
		(layer "In11.Cu")
		(net "M_H_CPU1_SA_DQ<14>")
	)
	(gr_poly
		(pts
			(xy 129.32283 -272.029174) (xy 129.27584 -271.876774) (xy 129.01422 -271.876774) (xy 128.96723 -272.029174)
			(xy 128.96723 -272.073624) (xy 129.32283 -272.073624)
		)
		(stroke
			(width 0)
			(type solid)
		)
		(fill yes)
		(layer "In11.Cu")
		(net "M_H_CPU1_SA_DQ<19>")
	)
	(gr_poly
		(pts
			(xy 129.32283 -271.62125) (xy 129.32283 -271.5768) (xy 128.96723 -271.5768) (xy 128.96723 -271.62125)
			(xy 129.01422 -271.77365) (xy 129.27584 -271.77365)
		)
		(stroke
			(width 0)
			(type solid)
		)
		(fill yes)
		(layer "In11.Cu")
		(net "M_H_CPU1_SA_DQS_DP<2>")
	)
	(gr_poly
		(pts
			(xy 129.32283 -268.77391) (xy 129.27584 -268.62151) (xy 129.01422 -268.62151) (xy 128.96723 -268.77391)
			(xy 128.96723 -268.818106) (xy 129.32283 -268.818106)
		)
		(stroke
			(width 0)
			(type solid)
		)
		(fill yes)
		(layer "In11.Cu")
		(net "M_H_CPU1_SA_DQ<22>")
	)
	(gr_poly
		(pts
			(xy 129.32283 -268.365478) (xy 129.32283 -268.321282) (xy 128.96723 -268.321282) (xy 128.96723 -268.365478)
			(xy 129.01422 -268.517878) (xy 129.27584 -268.517878)
		)
		(stroke
			(width 0)
			(type solid)
		)
		(fill yes)
		(layer "In11.Cu")
		(net "M_H_CPU1_SA_DQ<21>")
	)
	(gr_poly
		(pts
			(xy 129.32283 -267.14577) (xy 129.27584 -266.99337) (xy 129.01422 -266.99337) (xy 128.96723 -267.14577)
			(xy 128.96723 -267.19022) (xy 129.32283 -267.19022)
		)
		(stroke
			(width 0)
			(type solid)
		)
		(fill yes)
		(layer "In11.Cu")
		(net "M_H_CPU1_SA_DQ<26>")
	)
	(gr_poly
		(pts
			(xy 129.32283 -266.737846) (xy 129.32283 -266.69365) (xy 128.96723 -266.69365) (xy 128.96723 -266.737846)
			(xy 129.01422 -266.890246) (xy 129.27584 -266.890246)
		)
		(stroke
			(width 0)
			(type solid)
		)
		(fill yes)
		(layer "In11.Cu")
		(net "M_H_CPU1_SA_DQ<25>")
	)
	(gr_poly
		(pts
			(xy 129.32283 -265.518138) (xy 129.27584 -265.365738) (xy 129.01422 -265.365738) (xy 128.96723 -265.518138)
			(xy 128.96723 -265.562588) (xy 129.32283 -265.562588)
		)
		(stroke
			(width 0)
			(type solid)
		)
		(fill yes)
		(layer "In11.Cu")
		(net "M_H_CPU1_SA_DQS_DN<3>")
	)
	(gr_poly
		(pts
			(xy 129.32283 -262.262874) (xy 129.27584 -262.110474) (xy 129.01422 -262.110474) (xy 128.96723 -262.262874)
			(xy 128.96723 -262.30707) (xy 129.32283 -262.30707)
		)
		(stroke
			(width 0)
			(type solid)
		)
		(fill yes)
		(layer "In11.Cu")
		(net "M_H_CPU1_SA_CB<2>")
	)
	(gr_poly
		(pts
			(xy 129.32283 -261.854442) (xy 129.32283 -261.810246) (xy 128.96723 -261.810246) (xy 128.96723 -261.854442)
			(xy 129.01422 -262.006842) (xy 129.27584 -262.006842)
		)
		(stroke
			(width 0)
			(type solid)
		)
		(fill yes)
		(layer "In11.Cu")
		(net "M_H_CPU1_SA_CB<1>")
	)
	(gr_poly
		(pts
			(xy 129.32283 -260.634734) (xy 129.27584 -260.482334) (xy 129.01422 -260.482334) (xy 128.96723 -260.634734)
			(xy 128.96723 -260.679184) (xy 129.32283 -260.679184)
		)
		(stroke
			(width 0)
			(type solid)
		)
		(fill yes)
		(layer "In11.Cu")
		(net "M_H_CPU1_SA_DQS_DN<4>")
	)
	(gr_poly
		(pts
			(xy 129.32283 -260.22681) (xy 129.32283 -260.18236) (xy 128.96723 -260.18236) (xy 128.96723 -260.22681)
			(xy 129.01422 -260.37921) (xy 129.27584 -260.37921)
		)
		(stroke
			(width 0)
			(type solid)
		)
		(fill yes)
		(layer "In11.Cu")
		(net "M_H_CPU1_SA_DQS_DN<9>")
	)
	(gr_poly
		(pts
			(xy 129.32283 -257.37947) (xy 129.27584 -257.22707) (xy 129.01422 -257.22707) (xy 128.96723 -257.37947)
			(xy 128.96723 -257.423666) (xy 129.32283 -257.423666)
		)
		(stroke
			(width 0)
			(type solid)
		)
		(fill yes)
		(layer "In11.Cu")
		(net "M_H_CPU1_ALERT_N")
	)
	(gr_poly
		(pts
			(xy 129.32283 -255.343406) (xy 129.32283 -255.29921) (xy 128.96723 -255.29921) (xy 128.96723 -255.343406)
			(xy 129.01422 -255.495806) (xy 129.27584 -255.495806)
		)
		(stroke
			(width 0)
			(type solid)
		)
		(fill yes)
		(layer "In11.Cu")
		(net "M_H_CPU1_SA_CA<1>")
	)
	(gr_poly
		(pts
			(xy 129.635504 -273.094958) (xy 129.673858 -273.07286) (xy 129.496058 -272.765012) (xy 129.457704 -272.78711)
			(xy 129.349246 -272.90395) (xy 129.480056 -273.130518)
		)
		(stroke
			(width 0)
			(type solid)
		)
		(fill yes)
		(layer "In11.Cu")
		(net "M_H_CPU1_SA_DQ<17>")
	)
	(gr_poly
		(pts
			(xy 129.639314 -277.984458) (xy 129.677668 -277.96236) (xy 129.499868 -277.654512) (xy 129.461514 -277.67661)
			(xy 129.353056 -277.79345) (xy 129.483866 -278.020018)
		)
		(stroke
			(width 0)
			(type solid)
		)
		(fill yes)
		(layer "In11.Cu")
		(net "M_H_CPU1_SA_DQ<12>")
	)
	(gr_poly
		(pts
			(xy 129.66573 -247.787922) (xy 129.66573 -247.743726) (xy 129.31013 -247.743726) (xy 129.31013 -247.787922)
			(xy 129.35712 -247.940322) (xy 129.61874 -247.940322)
		)
		(stroke
			(width 0)
			(type solid)
		)
		(fill yes)
		(layer "In11.Cu")
		(net "M_H_CPU1_SB_CA<2>")
	)
	(gr_poly
		(pts
			(xy 129.66573 -242.905026) (xy 129.66573 -242.860576) (xy 129.31013 -242.860576) (xy 129.31013 -242.905026)
			(xy 129.35712 -243.057426) (xy 129.61874 -243.057426)
		)
		(stroke
			(width 0)
			(type solid)
		)
		(fill yes)
		(layer "In11.Cu")
		(net "M_H_CPU1_SB_DQS_DP<9>")
	)
	(gr_poly
		(pts
			(xy 129.66573 -240.057178) (xy 129.61874 -239.904778) (xy 129.35712 -239.904778) (xy 129.31013 -240.057178)
			(xy 129.31013 -240.101628) (xy 129.66573 -240.101628)
		)
		(stroke
			(width 0)
			(type solid)
		)
		(fill yes)
		(layer "In11.Cu")
		(net "M_H_CPU1_SB_CB<3>")
	)
	(gr_poly
		(pts
			(xy 129.66573 -238.021622) (xy 129.66573 -237.977172) (xy 129.31013 -237.977172) (xy 129.31013 -238.021622)
			(xy 129.35712 -238.174022) (xy 129.61874 -238.174022)
		)
		(stroke
			(width 0)
			(type solid)
		)
		(fill yes)
		(layer "In11.Cu")
		(net "M_H_CPU1_SB_DQS_DP<0>")
	)
	(gr_poly
		(pts
			(xy 129.66573 -235.174282) (xy 129.61874 -235.021882) (xy 129.35712 -235.021882) (xy 129.31013 -235.174282)
			(xy 129.31013 -235.218478) (xy 129.66573 -235.218478)
		)
		(stroke
			(width 0)
			(type solid)
		)
		(fill yes)
		(layer "In11.Cu")
		(net "M_H_CPU1_SB_DQ<7>")
	)
	(gr_poly
		(pts
			(xy 129.66573 -233.138218) (xy 129.66573 -233.093768) (xy 129.31013 -233.093768) (xy 129.31013 -233.138218)
			(xy 129.35712 -233.290618) (xy 129.61874 -233.290618)
		)
		(stroke
			(width 0)
			(type solid)
		)
		(fill yes)
		(layer "In11.Cu")
		(net "M_H_CPU1_SB_DQS_DP<1>")
	)
	(gr_poly
		(pts
			(xy 129.66573 -230.290878) (xy 129.61874 -230.138478) (xy 129.35712 -230.138478) (xy 129.31013 -230.290878)
			(xy 129.31013 -230.335074) (xy 129.66573 -230.335074)
		)
		(stroke
			(width 0)
			(type solid)
		)
		(fill yes)
		(layer "In11.Cu")
		(net "M_H_CPU1_SB_DQ<15>")
	)
	(gr_poly
		(pts
			(xy 129.66573 -228.254814) (xy 129.66573 -228.210618) (xy 129.31013 -228.210618) (xy 129.31013 -228.254814)
			(xy 129.35712 -228.407214) (xy 129.61874 -228.407214)
		)
		(stroke
			(width 0)
			(type solid)
		)
		(fill yes)
		(layer "In11.Cu")
		(net "M_H_CPU1_SB_DQS_DN<8>")
	)
	(gr_poly
		(pts
			(xy 129.66573 -227.035106) (xy 129.61874 -226.882706) (xy 129.35712 -226.882706) (xy 129.31013 -227.035106)
			(xy 129.31013 -227.079556) (xy 129.66573 -227.079556)
		)
		(stroke
			(width 0)
			(type solid)
		)
		(fill yes)
		(layer "In11.Cu")
		(net "M_H_CPU1_SB_DQS_DN<3>")
	)
	(gr_poly
		(pts
			(xy 129.66573 -226.627182) (xy 129.66573 -226.582732) (xy 129.31013 -226.582732) (xy 129.31013 -226.627182)
			(xy 129.35712 -226.779582) (xy 129.61874 -226.779582)
		)
		(stroke
			(width 0)
			(type solid)
		)
		(fill yes)
		(layer "In11.Cu")
		(net "M_H_CPU1_SB_DQ<30>")
	)
	(gr_poly
		(pts
			(xy 129.66573 -225.407474) (xy 129.61874 -225.255074) (xy 129.35712 -225.255074) (xy 129.31013 -225.407474)
			(xy 129.31013 -225.45167) (xy 129.66573 -225.45167)
		)
		(stroke
			(width 0)
			(type solid)
		)
		(fill yes)
		(layer "In11.Cu")
		(net "M_H_CPU1_SB_DQ<29>")
	)
	(gr_poly
		(pts
			(xy 129.665984 -233.546142) (xy 129.618994 -233.393742) (xy 129.357374 -233.393742) (xy 129.310384 -233.546142)
			(xy 129.310384 -233.590592) (xy 129.665984 -233.590592)
		)
		(stroke
			(width 0)
			(type solid)
		)
		(fill yes)
		(layer "In11.Cu")
		(net "M_H_CPU1_SB_DQ<11>")
	)
	(gr_poly
		(pts
			(xy 129.66827 -246.568722) (xy 129.62128 -246.416322) (xy 129.35966 -246.416322) (xy 129.31267 -246.568722)
			(xy 129.31267 -246.613172) (xy 129.66827 -246.613172)
		)
		(stroke
			(width 0)
			(type solid)
		)
		(fill yes)
		(layer "In11.Cu")
		(net "M_H_CPU1_SB_CA<5>")
	)
	(gr_poly
		(pts
			(xy 129.66827 -241.276886) (xy 129.66827 -241.232436) (xy 129.31267 -241.232436) (xy 129.31267 -241.276886)
			(xy 129.35966 -241.429286) (xy 129.62128 -241.429286)
		)
		(stroke
			(width 0)
			(type solid)
		)
		(fill yes)
		(layer "In11.Cu")
		(net "M_H_CPU1_SB_CB<0>")
	)
	(gr_poly
		(pts
			(xy 129.66827 -236.393482) (xy 129.66827 -236.349286) (xy 129.31267 -236.349286) (xy 129.31267 -236.393482)
			(xy 129.35966 -236.545882) (xy 129.62128 -236.545882)
		)
		(stroke
			(width 0)
			(type solid)
		)
		(fill yes)
		(layer "In11.Cu")
		(net "M_H_CPU1_SB_DQ<4>")
	)
	(gr_poly
		(pts
			(xy 129.66827 -231.510078) (xy 129.66827 -231.465882) (xy 129.31267 -231.465882) (xy 129.31267 -231.510078)
			(xy 129.35966 -231.662478) (xy 129.62128 -231.662478)
		)
		(stroke
			(width 0)
			(type solid)
		)
		(fill yes)
		(layer "In11.Cu")
		(net "M_H_CPU1_SB_DQ<12>")
	)
	(gr_poly
		(pts
			(xy 129.674112 -248.196354) (xy 129.627122 -248.043954) (xy 129.365502 -248.043954) (xy 129.318512 -248.196354)
			(xy 129.318512 -248.240804) (xy 129.674112 -248.240804)
		)
		(stroke
			(width 0)
			(type solid)
		)
		(fill yes)
		(layer "In11.Cu")
		(net "M_H_CPU1_SB_CA<1>")
	)
	(gr_poly
		(pts
			(xy 129.674112 -244.53215) (xy 129.674112 -244.487954) (xy 129.318512 -244.487954) (xy 129.318512 -244.53215)
			(xy 129.365502 -244.68455) (xy 129.627122 -244.68455)
		)
		(stroke
			(width 0)
			(type solid)
		)
		(fill yes)
		(layer "In11.Cu")
		(net "M_H_CPU1_SB_CB<6>")
	)
	(gr_poly
		(pts
			(xy 129.674112 -243.313458) (xy 129.627122 -243.161058) (xy 129.365502 -243.161058) (xy 129.318512 -243.313458)
			(xy 129.318512 -243.357654) (xy 129.674112 -243.357654)
		)
		(stroke
			(width 0)
			(type solid)
		)
		(fill yes)
		(layer "In11.Cu")
		(net "M_H_CPU1_SB_CB<5>")
	)
	(gr_poly
		(pts
			(xy 129.674112 -239.648746) (xy 129.674112 -239.60455) (xy 129.318512 -239.60455) (xy 129.318512 -239.648746)
			(xy 129.365502 -239.801146) (xy 129.627122 -239.801146)
		)
		(stroke
			(width 0)
			(type solid)
		)
		(fill yes)
		(layer "In11.Cu")
		(net "M_H_CPU1_SB_DQ<0>")
	)
	(gr_poly
		(pts
			(xy 129.674112 -238.430054) (xy 129.627122 -238.277654) (xy 129.365502 -238.277654) (xy 129.318512 -238.430054)
			(xy 129.318512 -238.47425) (xy 129.674112 -238.47425)
		)
		(stroke
			(width 0)
			(type solid)
		)
		(fill yes)
		(layer "In11.Cu")
		(net "M_H_CPU1_SB_DQ<3>")
	)
	(gr_poly
		(pts
			(xy 129.674112 -234.76585) (xy 129.674112 -234.7214) (xy 129.318512 -234.7214) (xy 129.318512 -234.76585)
			(xy 129.365502 -234.91825) (xy 129.627122 -234.91825)
		)
		(stroke
			(width 0)
			(type solid)
		)
		(fill yes)
		(layer "In11.Cu")
		(net "M_H_CPU1_SB_DQ<8>")
	)
	(gr_poly
		(pts
			(xy 129.674112 -229.882446) (xy 129.674112 -229.837996) (xy 129.318512 -229.837996) (xy 129.318512 -229.882446)
			(xy 129.365502 -230.034846) (xy 129.627122 -230.034846)
		)
		(stroke
			(width 0)
			(type solid)
		)
		(fill yes)
		(layer "In11.Cu")
		(net "M_H_CPU1_SB_DQ<26>")
	)
	(gr_poly
		(pts
			(xy 129.674112 -228.663246) (xy 129.627122 -228.510846) (xy 129.365502 -228.510846) (xy 129.318512 -228.663246)
			(xy 129.318512 -228.707696) (xy 129.674112 -228.707696)
		)
		(stroke
			(width 0)
			(type solid)
		)
		(fill yes)
		(layer "In11.Cu")
		(net "M_H_CPU1_SB_DQ<25>")
	)
	(gr_poly
		(pts
			(xy 129.67462 -241.685826) (xy 129.62763 -241.533426) (xy 129.36601 -241.533426) (xy 129.31902 -241.685826)
			(xy 129.31902 -241.730022) (xy 129.67462 -241.730022)
		)
		(stroke
			(width 0)
			(type solid)
		)
		(fill yes)
		(layer "In11.Cu")
		(net "M_H_CPU1_SB_DQS_DP<4>")
	)
	(gr_poly
		(pts
			(xy 129.67462 -236.802422) (xy 129.62763 -236.650022) (xy 129.36601 -236.650022) (xy 129.31902 -236.802422)
			(xy 129.31902 -236.846872) (xy 129.67462 -236.846872)
		)
		(stroke
			(width 0)
			(type solid)
		)
		(fill yes)
		(layer "In11.Cu")
		(net "M_H_CPU1_SB_DQS_DP<5>")
	)
	(gr_poly
		(pts
			(xy 129.67462 -231.919018) (xy 129.62763 -231.766618) (xy 129.36601 -231.766618) (xy 129.31902 -231.919018)
			(xy 129.31902 -231.963468) (xy 129.67462 -231.963468)
		)
		(stroke
			(width 0)
			(type solid)
		)
		(fill yes)
		(layer "In11.Cu")
		(net "M_H_CPU1_SB_DQS_DP<6>")
	)
	(gr_poly
		(pts
			(xy 129.753106 -272.488152) (xy 129.861564 -272.371312) (xy 129.730754 -272.144744) (xy 129.575306 -272.180304)
			(xy 129.536952 -272.202402) (xy 129.714752 -272.51025)
		)
		(stroke
			(width 0)
			(type solid)
		)
		(fill yes)
		(layer "In11.Cu")
		(net "M_H_CPU1_SA_DQ<19>")
	)
	(gr_poly
		(pts
			(xy 129.755138 -277.374858) (xy 129.863596 -277.258018) (xy 129.732786 -277.03145) (xy 129.577338 -277.06701)
			(xy 129.538984 -277.089108) (xy 129.716784 -277.396956)
		)
		(stroke
			(width 0)
			(type solid)
		)
		(fill yes)
		(layer "In11.Cu")
		(net "M_H_CPU1_SA_DQ<14>")
	)
	(gr_poly
		(pts
			(xy 129.775712 -280.98242) (xy 129.728722 -280.83002) (xy 129.467102 -280.83002) (xy 129.420112 -280.98242)
			(xy 129.420112 -281.026616) (xy 129.775712 -281.026616)
		)
		(stroke
			(width 0)
			(type solid)
		)
		(fill yes)
		(layer "In11.Cu")
		(net "M_H_CPU1_SA_DQ<10>")
	)
	(gr_poly
		(pts
			(xy 129.775712 -280.574242) (xy 129.775712 -280.529792) (xy 129.420112 -280.529792) (xy 129.420112 -280.574242)
			(xy 129.467102 -280.726642) (xy 129.728722 -280.726642)
		)
		(stroke
			(width 0)
			(type solid)
		)
		(fill yes)
		(layer "In11.Cu")
		(net "M_H_CPU1_SA_DQ<9>")
	)
	(gr_poly
		(pts
			(xy 129.775712 -271.215358) (xy 129.728722 -271.062958) (xy 129.467102 -271.062958) (xy 129.420112 -271.215358)
			(xy 129.420112 -271.259808) (xy 129.775712 -271.259808)
		)
		(stroke
			(width 0)
			(type solid)
		)
		(fill yes)
		(layer "In11.Cu")
		(net "M_H_CPU1_SA_DQS_DN<2>")
	)
	(gr_poly
		(pts
			(xy 129.775712 -270.807434) (xy 129.775712 -270.762984) (xy 129.420112 -270.762984) (xy 129.420112 -270.807434)
			(xy 129.467102 -270.959834) (xy 129.728722 -270.959834)
		)
		(stroke
			(width 0)
			(type solid)
		)
		(fill yes)
		(layer "In11.Cu")
		(net "M_H_CPU1_SA_DQS_DN<7>")
	)
	(gr_poly
		(pts
			(xy 129.775712 -269.179294) (xy 129.775712 -269.135098) (xy 129.420112 -269.135098) (xy 129.420112 -269.179294)
			(xy 129.467102 -269.331694) (xy 129.728722 -269.331694)
		)
		(stroke
			(width 0)
			(type solid)
		)
		(fill yes)
		(layer "In11.Cu")
		(net "M_H_CPU1_SA_DQ<20>")
	)
	(gr_poly
		(pts
			(xy 129.775712 -267.551662) (xy 129.775712 -267.507466) (xy 129.420112 -267.507466) (xy 129.420112 -267.551662)
			(xy 129.467102 -267.704062) (xy 129.728722 -267.704062)
		)
		(stroke
			(width 0)
			(type solid)
		)
		(fill yes)
		(layer "In11.Cu")
		(net "M_H_CPU1_SA_DQ<24>")
	)
	(gr_poly
		(pts
			(xy 129.775712 -266.331954) (xy 129.728722 -266.179554) (xy 129.467102 -266.179554) (xy 129.420112 -266.331954)
			(xy 129.420112 -266.376404) (xy 129.775712 -266.376404)
		)
		(stroke
			(width 0)
			(type solid)
		)
		(fill yes)
		(layer "In11.Cu")
		(net "M_H_CPU1_SA_DQ<27>")
	)
	(gr_poly
		(pts
			(xy 129.775712 -265.92403) (xy 129.775712 -265.879834) (xy 129.420112 -265.879834) (xy 129.420112 -265.92403)
			(xy 129.467102 -266.07643) (xy 129.728722 -266.07643)
		)
		(stroke
			(width 0)
			(type solid)
		)
		(fill yes)
		(layer "In11.Cu")
		(net "M_H_CPU1_SA_DQS_DP<3>")
	)
	(gr_poly
		(pts
			(xy 129.775712 -262.668258) (xy 129.775712 -262.624062) (xy 129.420112 -262.624062) (xy 129.420112 -262.668258)
			(xy 129.467102 -262.820658) (xy 129.728722 -262.820658)
		)
		(stroke
			(width 0)
			(type solid)
		)
		(fill yes)
		(layer "In11.Cu")
		(net "M_H_CPU1_SA_CB<0>")
	)
	(gr_poly
		(pts
			(xy 129.775712 -261.449058) (xy 129.728722 -261.296658) (xy 129.467102 -261.296658) (xy 129.420112 -261.449058)
			(xy 129.420112 -261.493254) (xy 129.775712 -261.493254)
		)
		(stroke
			(width 0)
			(type solid)
		)
		(fill yes)
		(layer "In11.Cu")
		(net "M_H_CPU1_SA_CB<3>")
	)
	(gr_poly
		(pts
			(xy 129.775712 -261.040626) (xy 129.775712 -260.99643) (xy 129.420112 -260.99643) (xy 129.420112 -261.040626)
			(xy 129.467102 -261.193026) (xy 129.728722 -261.193026)
		)
		(stroke
			(width 0)
			(type solid)
		)
		(fill yes)
		(layer "In11.Cu")
		(net "M_H_CPU1_SA_DQS_DP<4>")
	)
	(gr_poly
		(pts
			(xy 129.775712 -259.820918) (xy 129.728722 -259.668518) (xy 129.467102 -259.668518) (xy 129.420112 -259.820918)
			(xy 129.420112 -259.865368) (xy 129.775712 -259.865368)
		)
		(stroke
			(width 0)
			(type solid)
		)
		(fill yes)
		(layer "In11.Cu")
		(net "M_H_CPU1_SA_DQS_DP<9>")
	)
	(gr_poly
		(pts
			(xy 129.775712 -257.784854) (xy 129.775712 -257.740658) (xy 129.420112 -257.740658) (xy 129.420112 -257.784854)
			(xy 129.467102 -257.937254) (xy 129.728722 -257.937254)
		)
		(stroke
			(width 0)
			(type solid)
		)
		(fill yes)
		(layer "In11.Cu")
		(net "M_E_CPU1_ALERT_N")
	)
	(gr_poly
		(pts
			(xy 129.775712 -254.937514) (xy 129.728722 -254.785114) (xy 129.467102 -254.785114) (xy 129.420112 -254.937514)
			(xy 129.420112 -254.981964) (xy 129.775712 -254.981964)
		)
		(stroke
			(width 0)
			(type solid)
		)
		(fill yes)
		(layer "In11.Cu")
		(net "M_H_CPU1_SA_CA<0>")
	)
	(gr_poly
		(pts
			(xy 129.778252 -279.354534) (xy 129.731262 -279.202134) (xy 129.469642 -279.202134) (xy 129.422652 -279.354534)
			(xy 129.422652 -279.39873) (xy 129.778252 -279.39873)
		)
		(stroke
			(width 0)
			(type solid)
		)
		(fill yes)
		(layer "In11.Cu")
		(net "M_H_CPU1_SA_DQS_DN<1>")
	)
	(gr_poly
		(pts
			(xy 129.778252 -278.946102) (xy 129.778252 -278.901906) (xy 129.422652 -278.901906) (xy 129.422652 -278.946102)
			(xy 129.469642 -279.098502) (xy 129.731262 -279.098502)
		)
		(stroke
			(width 0)
			(type solid)
		)
		(fill yes)
		(layer "In11.Cu")
		(net "M_H_CPU1_SA_DQS_DN<6>")
	)
	(gr_poly
		(pts
			(xy 129.778252 -276.09927) (xy 129.731262 -275.94687) (xy 129.469642 -275.94687) (xy 129.422652 -276.09927)
			(xy 129.422652 -276.143466) (xy 129.778252 -276.143466)
		)
		(stroke
			(width 0)
			(type solid)
		)
		(fill yes)
		(layer "In11.Cu")
		(net "M_H_CPU1_SA_DQ<15>")
	)
	(gr_poly
		(pts
			(xy 129.778252 -275.690584) (xy 129.778252 -275.646134) (xy 129.422652 -275.646134) (xy 129.422652 -275.690584)
			(xy 129.469642 -275.842984) (xy 129.731262 -275.842984)
		)
		(stroke
			(width 0)
			(type solid)
		)
		(fill yes)
		(layer "In11.Cu")
		(net "M_H_CPU1_SA_DQ<16>")
	)
	(gr_poly
		(pts
			(xy 129.778252 -256.565654) (xy 129.731262 -256.413254) (xy 129.469642 -256.413254) (xy 129.422652 -256.565654)
			(xy 129.422652 -256.610104) (xy 129.778252 -256.610104)
		)
		(stroke
			(width 0)
			(type solid)
		)
		(fill yes)
		(layer "In11.Cu")
		(net "M_H_CPU1_SA_CS_N<1>")
	)
	(gr_poly
		(pts
			(xy 129.778252 -256.157222) (xy 129.778252 -256.112772) (xy 129.422652 -256.112772) (xy 129.422652 -256.157222)
			(xy 129.469642 -256.309622) (xy 129.731262 -256.309622)
		)
		(stroke
			(width 0)
			(type solid)
		)
		(fill yes)
		(layer "In11.Cu")
		(net "M_H_CPU1_SA_CS_N<2>")
	)
	(gr_poly
		(pts
			(xy 129.78384 -267.960094) (xy 129.73685 -267.807694) (xy 129.47523 -267.807694) (xy 129.42824 -267.960094)
			(xy 129.42824 -268.004544) (xy 129.78384 -268.004544)
		)
		(stroke
			(width 0)
			(type solid)
		)
		(fill yes)
		(layer "In11.Cu")
		(net "M_H_CPU1_SA_DQ<23>")
	)
	(gr_poly
		(pts
			(xy 129.784094 -264.29589) (xy 129.784094 -264.251694) (xy 129.428494 -264.251694) (xy 129.428494 -264.29589)
			(xy 129.475484 -264.44829) (xy 129.737104 -264.44829)
		)
		(stroke
			(width 0)
			(type solid)
		)
		(fill yes)
		(layer "In11.Cu")
		(net "M_H_CPU1_SA_DQ<28>")
	)
	(gr_poly
		(pts
			(xy 129.784094 -263.07669) (xy 129.737104 -262.92429) (xy 129.475484 -262.92429) (xy 129.428494 -263.07669)
			(xy 129.428494 -263.12114) (xy 129.784094 -263.12114)
		)
		(stroke
			(width 0)
			(type solid)
		)
		(fill yes)
		(layer "In11.Cu")
		(net "M_H_CPU1_SA_DQ<31>")
	)
	(gr_poly
		(pts
			(xy 129.784094 -259.412486) (xy 129.784094 -259.36829) (xy 129.428494 -259.36829) (xy 129.428494 -259.412486)
			(xy 129.475484 -259.564886) (xy 129.737104 -259.564886)
		)
		(stroke
			(width 0)
			(type solid)
		)
		(fill yes)
		(layer "In11.Cu")
		(net "M_H_CPU1_SA_CB<4>")
	)
	(gr_poly
		(pts
			(xy 129.784094 -258.193286) (xy 129.737104 -258.040886) (xy 129.475484 -258.040886) (xy 129.428494 -258.193286)
			(xy 129.428494 -258.237736) (xy 129.784094 -258.237736)
		)
		(stroke
			(width 0)
			(type solid)
		)
		(fill yes)
		(layer "In11.Cu")
		(net "M_H_CPU1_SA_CB<7>")
	)
	(gr_poly
		(pts
			(xy 129.784094 -254.529082) (xy 129.784094 -254.484886) (xy 129.428494 -254.484886) (xy 129.428494 -254.529082)
			(xy 129.475484 -254.681482) (xy 129.737104 -254.681482)
		)
		(stroke
			(width 0)
			(type solid)
		)
		(fill yes)
		(layer "In11.Cu")
		(net "M_H_CPU1_SA_CA<2>")
	)
	(gr_poly
		(pts
			(xy 129.788412 -264.70483) (xy 129.741422 -264.55243) (xy 129.479802 -264.55243) (xy 129.432812 -264.70483)
			(xy 129.432812 -264.749026) (xy 129.788412 -264.749026)
		)
		(stroke
			(width 0)
			(type solid)
		)
		(fill yes)
		(layer "In11.Cu")
		(net "M_H_CPU1_SA_DQS_DP<8>")
	)
	(gr_poly
		(pts
			(xy 130.109976 -277.171404) (xy 130.14833 -277.149306) (xy 129.97053 -276.841458) (xy 129.932176 -276.863556)
			(xy 129.823718 -276.980396) (xy 129.954528 -277.206964)
		)
		(stroke
			(width 0)
			(type solid)
		)
		(fill yes)
		(layer "In11.Cu")
		(net "M_H_CPU1_SA_DQ<13>")
	)
	(gr_poly
		(pts
			(xy 130.110992 -273.918426) (xy 130.149346 -273.896328) (xy 129.971546 -273.58848) (xy 129.933192 -273.610578)
			(xy 129.824734 -273.727418) (xy 129.955544 -273.953986)
		)
		(stroke
			(width 0)
			(type solid)
		)
		(fill yes)
		(layer "In11.Cu")
		(net "M_H_CPU1_SA_DQ<17>")
	)
	(gr_poly
		(pts
			(xy 130.11277 -272.292064) (xy 130.151124 -272.269966) (xy 129.973324 -271.962118) (xy 129.93497 -271.984216)
			(xy 129.826512 -272.101056) (xy 129.957322 -272.327624)
		)
		(stroke
			(width 0)
			(type solid)
		)
		(fill yes)
		(layer "In11.Cu")
		(net "M_H_CPU1_SA_DQS_DP<2>")
	)
	(gr_poly
		(pts
			(xy 130.150108 -248.602246) (xy 130.150108 -248.557796) (xy 129.794508 -248.557796) (xy 129.794508 -248.602246)
			(xy 129.841498 -248.754646) (xy 130.103118 -248.754646)
		)
		(stroke
			(width 0)
			(type solid)
		)
		(fill yes)
		(layer "In11.Cu")
		(net "M_H_CPU1_SB_CA<0>")
	)
	(gr_poly
		(pts
			(xy 130.150108 -244.126766) (xy 130.103118 -243.974366) (xy 129.841498 -243.974366) (xy 129.794508 -244.126766)
			(xy 129.794508 -244.171216) (xy 130.150108 -244.171216)
		)
		(stroke
			(width 0)
			(type solid)
		)
		(fill yes)
		(layer "In11.Cu")
		(net "M_H_CPU1_SB_CB<4>")
	)
	(gr_poly
		(pts
			(xy 130.150108 -243.718842) (xy 130.150108 -243.674392) (xy 129.794508 -243.674392) (xy 129.794508 -243.718842)
			(xy 129.841498 -243.871242) (xy 130.103118 -243.871242)
		)
		(stroke
			(width 0)
			(type solid)
		)
		(fill yes)
		(layer "In11.Cu")
		(net "M_H_CPU1_SB_CB<7>")
	)
	(gr_poly
		(pts
			(xy 130.150108 -239.243362) (xy 130.103118 -239.090962) (xy 129.841498 -239.090962) (xy 129.794508 -239.243362)
			(xy 129.794508 -239.287812) (xy 130.150108 -239.287812)
		)
		(stroke
			(width 0)
			(type solid)
		)
		(fill yes)
		(layer "In11.Cu")
		(net "M_H_CPU1_SB_DQ<2>")
	)
	(gr_poly
		(pts
			(xy 130.150108 -238.835438) (xy 130.150108 -238.790988) (xy 129.794508 -238.790988) (xy 129.794508 -238.835438)
			(xy 129.841498 -238.987838) (xy 130.103118 -238.987838)
		)
		(stroke
			(width 0)
			(type solid)
		)
		(fill yes)
		(layer "In11.Cu")
		(net "M_H_CPU1_SB_DQ<1>")
	)
	(gr_poly
		(pts
			(xy 130.150108 -234.360466) (xy 130.103118 -234.208066) (xy 129.841498 -234.208066) (xy 129.794508 -234.360466)
			(xy 129.794508 -234.404662) (xy 130.150108 -234.404662)
		)
		(stroke
			(width 0)
			(type solid)
		)
		(fill yes)
		(layer "In11.Cu")
		(net "M_H_CPU1_SB_DQ<10>")
	)
	(gr_poly
		(pts
			(xy 130.150108 -233.952034) (xy 130.150108 -233.907838) (xy 129.794508 -233.907838) (xy 129.794508 -233.952034)
			(xy 129.841498 -234.104434) (xy 130.103118 -234.104434)
		)
		(stroke
			(width 0)
			(type solid)
		)
		(fill yes)
		(layer "In11.Cu")
		(net "M_H_CPU1_SB_DQ<9>")
	)
	(gr_poly
		(pts
			(xy 130.150108 -229.477062) (xy 130.103118 -229.324662) (xy 129.841498 -229.324662) (xy 129.794508 -229.477062)
			(xy 129.794508 -229.521258) (xy 130.150108 -229.521258)
		)
		(stroke
			(width 0)
			(type solid)
		)
		(fill yes)
		(layer "In11.Cu")
		(net "M_H_CPU1_SB_DQ<24>")
	)
	(gr_poly
		(pts
			(xy 130.150108 -229.06863) (xy 130.150108 -229.024434) (xy 129.794508 -229.024434) (xy 129.794508 -229.06863)
			(xy 129.841498 -229.22103) (xy 130.103118 -229.22103)
		)
		(stroke
			(width 0)
			(type solid)
		)
		(fill yes)
		(layer "In11.Cu")
		(net "M_H_CPU1_SB_DQ<27>")
	)
	(gr_poly
		(pts
			(xy 130.152648 -247.382538) (xy 130.105658 -247.230138) (xy 129.844038 -247.230138) (xy 129.797048 -247.382538)
			(xy 129.797048 -247.426734) (xy 130.152648 -247.426734)
		)
		(stroke
			(width 0)
			(type solid)
		)
		(fill yes)
		(layer "In11.Cu")
		(net "M_H_CPU1_SB_CA<3>")
	)
	(gr_poly
		(pts
			(xy 130.152648 -246.974106) (xy 130.152648 -246.92991) (xy 129.797048 -246.92991) (xy 129.797048 -246.974106)
			(xy 129.844038 -247.126506) (xy 130.105658 -247.126506)
		)
		(stroke
			(width 0)
			(type solid)
		)
		(fill yes)
		(layer "In11.Cu")
		(net "M_H_CPU1_SB_CA<4>")
	)
	(gr_poly
		(pts
			(xy 130.152648 -245.754906) (xy 130.105658 -245.602506) (xy 129.844038 -245.602506) (xy 129.797048 -245.754906)
			(xy 129.797048 -245.799102) (xy 130.152648 -245.799102)
		)
		(stroke
			(width 0)
			(type solid)
		)
		(fill yes)
		(layer "In11.Cu")
		(net "M_H_CPU1_SB_PAR")
	)
	(gr_poly
		(pts
			(xy 130.152648 -242.499134) (xy 130.105658 -242.346734) (xy 129.844038 -242.346734) (xy 129.797048 -242.499134)
			(xy 129.797048 -242.54333) (xy 130.152648 -242.54333)
		)
		(stroke
			(width 0)
			(type solid)
		)
		(fill yes)
		(layer "In11.Cu")
		(net "M_H_CPU1_SB_DQS_DN<9>")
	)
	(gr_poly
		(pts
			(xy 130.152648 -242.090702) (xy 130.152648 -242.046506) (xy 129.797048 -242.046506) (xy 129.797048 -242.090702)
			(xy 129.844038 -242.243102) (xy 130.105658 -242.243102)
		)
		(stroke
			(width 0)
			(type solid)
		)
		(fill yes)
		(layer "In11.Cu")
		(net "M_H_CPU1_SB_DQS_DN<4>")
	)
	(gr_poly
		(pts
			(xy 130.152648 -240.871502) (xy 130.105658 -240.719102) (xy 129.844038 -240.719102) (xy 129.797048 -240.871502)
			(xy 129.797048 -240.915698) (xy 130.152648 -240.915698)
		)
		(stroke
			(width 0)
			(type solid)
		)
		(fill yes)
		(layer "In11.Cu")
		(net "M_H_CPU1_SB_CB<2>")
	)
	(gr_poly
		(pts
			(xy 130.152648 -240.46307) (xy 130.152648 -240.418874) (xy 129.797048 -240.418874) (xy 129.797048 -240.46307)
			(xy 129.844038 -240.61547) (xy 130.105658 -240.61547)
		)
		(stroke
			(width 0)
			(type solid)
		)
		(fill yes)
		(layer "In11.Cu")
		(net "M_H_CPU1_SB_CB<1>")
	)
	(gr_poly
		(pts
			(xy 130.152648 -237.61573) (xy 130.105658 -237.46333) (xy 129.844038 -237.46333) (xy 129.797048 -237.61573)
			(xy 129.797048 -237.66018) (xy 130.152648 -237.66018)
		)
		(stroke
			(width 0)
			(type solid)
		)
		(fill yes)
		(layer "In11.Cu")
		(net "M_H_CPU1_SB_DQS_DN<0>")
	)
	(gr_poly
		(pts
			(xy 130.152648 -237.207806) (xy 130.152648 -237.163356) (xy 129.797048 -237.163356) (xy 129.797048 -237.207806)
			(xy 129.844038 -237.360206) (xy 130.105658 -237.360206)
		)
		(stroke
			(width 0)
			(type solid)
		)
		(fill yes)
		(layer "In11.Cu")
		(net "M_H_CPU1_SB_DQS_DN<5>")
	)
	(gr_poly
		(pts
			(xy 130.152648 -235.988098) (xy 130.105658 -235.835698) (xy 129.844038 -235.835698) (xy 129.797048 -235.988098)
			(xy 129.797048 -236.032294) (xy 130.152648 -236.032294)
		)
		(stroke
			(width 0)
			(type solid)
		)
		(fill yes)
		(layer "In11.Cu")
		(net "M_H_CPU1_SB_DQ<6>")
	)
	(gr_poly
		(pts
			(xy 130.152648 -235.579666) (xy 130.152648 -235.53547) (xy 129.797048 -235.53547) (xy 129.797048 -235.579666)
			(xy 129.844038 -235.732066) (xy 130.105658 -235.732066)
		)
		(stroke
			(width 0)
			(type solid)
		)
		(fill yes)
		(layer "In11.Cu")
		(net "M_H_CPU1_SB_DQ<5>")
	)
	(gr_poly
		(pts
			(xy 130.152648 -232.732326) (xy 130.105658 -232.579926) (xy 129.844038 -232.579926) (xy 129.797048 -232.732326)
			(xy 129.797048 -232.776776) (xy 130.152648 -232.776776)
		)
		(stroke
			(width 0)
			(type solid)
		)
		(fill yes)
		(layer "In11.Cu")
		(net "M_H_CPU1_SB_DQS_DN<1>")
	)
	(gr_poly
		(pts
			(xy 130.152648 -232.324402) (xy 130.152648 -232.279952) (xy 129.797048 -232.279952) (xy 129.797048 -232.324402)
			(xy 129.844038 -232.476802) (xy 130.105658 -232.476802)
		)
		(stroke
			(width 0)
			(type solid)
		)
		(fill yes)
		(layer "In11.Cu")
		(net "M_H_CPU1_SB_DQS_DN<6>")
	)
	(gr_poly
		(pts
			(xy 130.152648 -231.104694) (xy 130.105658 -230.952294) (xy 129.844038 -230.952294) (xy 129.797048 -231.104694)
			(xy 129.797048 -231.14889) (xy 130.152648 -231.14889)
		)
		(stroke
			(width 0)
			(type solid)
		)
		(fill yes)
		(layer "In11.Cu")
		(net "M_H_CPU1_SB_DQ<14>")
	)
	(gr_poly
		(pts
			(xy 130.152648 -230.696262) (xy 130.152648 -230.652066) (xy 129.797048 -230.652066) (xy 129.797048 -230.696262)
			(xy 129.844038 -230.848662) (xy 130.105658 -230.848662)
		)
		(stroke
			(width 0)
			(type solid)
		)
		(fill yes)
		(layer "In11.Cu")
		(net "M_H_CPU1_SB_DQ<13>")
	)
	(gr_poly
		(pts
			(xy 130.152648 -227.848922) (xy 130.105658 -227.696522) (xy 129.844038 -227.696522) (xy 129.797048 -227.848922)
			(xy 129.797048 -227.893372) (xy 130.152648 -227.893372)
		)
		(stroke
			(width 0)
			(type solid)
		)
		(fill yes)
		(layer "In11.Cu")
		(net "M_H_CPU1_SB_DQS_DP<8>")
	)
	(gr_poly
		(pts
			(xy 130.152648 -227.440998) (xy 130.152648 -227.396548) (xy 129.797048 -227.396548) (xy 129.797048 -227.440998)
			(xy 129.844038 -227.593398) (xy 130.105658 -227.593398)
		)
		(stroke
			(width 0)
			(type solid)
		)
		(fill yes)
		(layer "In11.Cu")
		(net "M_H_CPU1_SB_DQS_DP<3>")
	)
	(gr_poly
		(pts
			(xy 130.152648 -226.22129) (xy 130.105658 -226.06889) (xy 129.844038 -226.06889) (xy 129.797048 -226.22129)
			(xy 129.797048 -226.26574) (xy 130.152648 -226.26574)
		)
		(stroke
			(width 0)
			(type solid)
		)
		(fill yes)
		(layer "In11.Cu")
		(net "M_H_CPU1_SB_DQ<28>")
	)
	(gr_poly
		(pts
			(xy 130.152648 -225.813366) (xy 130.152648 -225.768916) (xy 129.797048 -225.768916) (xy 129.797048 -225.813366)
			(xy 129.844038 -225.965766) (xy 130.105658 -225.965766)
		)
		(stroke
			(width 0)
			(type solid)
		)
		(fill yes)
		(layer "In11.Cu")
		(net "M_H_CPU1_SB_DQ<31>")
	)
	(gr_poly
		(pts
			(xy 130.225038 -276.560788) (xy 130.333496 -276.443948) (xy 130.202686 -276.21738) (xy 130.047238 -276.25294)
			(xy 130.008884 -276.275038) (xy 130.186684 -276.582886)
		)
		(stroke
			(width 0)
			(type solid)
		)
		(fill yes)
		(layer "In11.Cu")
		(net "M_H_CPU1_SA_DQ<15>")
	)
	(gr_poly
		(pts
			(xy 130.225038 -273.30527) (xy 130.333496 -273.18843) (xy 130.202686 -272.961862) (xy 130.047238 -272.997422)
			(xy 130.008884 -273.01952) (xy 130.186684 -273.327368)
		)
		(stroke
			(width 0)
			(type solid)
		)
		(fill yes)
		(layer "In11.Cu")
		(net "M_H_CPU1_SA_DQ<19>")
	)
	(gr_poly
		(pts
			(xy 130.248152 -278.540718) (xy 130.201162 -278.388318) (xy 129.939542 -278.388318) (xy 129.892552 -278.540718)
			(xy 129.892552 -278.585168) (xy 130.248152 -278.585168)
		)
		(stroke
			(width 0)
			(type solid)
		)
		(fill yes)
		(layer "In11.Cu")
		(net "M_H_CPU1_SA_DQS_DP<6>")
	)
	(gr_poly
		(pts
			(xy 130.248152 -278.132032) (xy 130.248152 -278.087836) (xy 129.892552 -278.087836) (xy 129.892552 -278.132032)
			(xy 129.939542 -278.284432) (xy 130.201162 -278.284432)
		)
		(stroke
			(width 0)
			(type solid)
		)
		(fill yes)
		(layer "In11.Cu")
		(net "M_H_CPU1_SA_DQ<12>")
	)
	(gr_poly
		(pts
			(xy 130.254248 -279.759664) (xy 130.254248 -279.715468) (xy 129.898648 -279.715468) (xy 129.898648 -279.759664)
			(xy 129.945638 -279.912064) (xy 130.207258 -279.912064)
		)
		(stroke
			(width 0)
			(type solid)
		)
		(fill yes)
		(layer "In11.Cu")
		(net "M_H_CPU1_SA_DQS_DP<1>")
	)
	(gr_poly
		(pts
			(xy 130.26009 -263.890506) (xy 130.2131 -263.738106) (xy 129.95148 -263.738106) (xy 129.90449 -263.890506)
			(xy 129.90449 -263.934956) (xy 130.26009 -263.934956)
		)
		(stroke
			(width 0)
			(type solid)
		)
		(fill yes)
		(layer "In11.Cu")
		(net "M_H_CPU1_SA_DQ<30>")
	)
	(gr_poly
		(pts
			(xy 130.26009 -263.482582) (xy 130.26009 -263.438132) (xy 129.90449 -263.438132) (xy 129.90449 -263.482582)
			(xy 129.95148 -263.634982) (xy 130.2131 -263.634982)
		)
		(stroke
			(width 0)
			(type solid)
		)
		(fill yes)
		(layer "In11.Cu")
		(net "M_H_CPU1_SA_DQ<29>")
	)
	(gr_poly
		(pts
			(xy 130.26009 -259.007102) (xy 130.2131 -258.854702) (xy 129.95148 -258.854702) (xy 129.90449 -259.007102)
			(xy 129.90449 -259.051552) (xy 130.26009 -259.051552)
		)
		(stroke
			(width 0)
			(type solid)
		)
		(fill yes)
		(layer "In11.Cu")
		(net "M_H_CPU1_SA_CB<6>")
	)
	(gr_poly
		(pts
			(xy 130.26009 -258.599178) (xy 130.26009 -258.554728) (xy 129.90449 -258.554728) (xy 129.90449 -258.599178)
			(xy 129.95148 -258.751578) (xy 130.2131 -258.751578)
		)
		(stroke
			(width 0)
			(type solid)
		)
		(fill yes)
		(layer "In11.Cu")
		(net "M_H_CPU1_SA_CB<5>")
	)
	(gr_poly
		(pts
			(xy 130.26009 -254.123698) (xy 130.2131 -253.971298) (xy 129.95148 -253.971298) (xy 129.90449 -254.123698)
			(xy 129.90449 -254.168148) (xy 130.26009 -254.168148)
		)
		(stroke
			(width 0)
			(type solid)
		)
		(fill yes)
		(layer "In11.Cu")
		(net "M_H_CPU1_SA_CA<3>")
	)
	(gr_poly
		(pts
			(xy 130.26263 -281.387804) (xy 130.26263 -281.343608) (xy 129.90703 -281.343608) (xy 129.90703 -281.387804)
			(xy 129.95402 -281.540204) (xy 130.21564 -281.540204)
		)
		(stroke
			(width 0)
			(type solid)
		)
		(fill yes)
		(layer "In11.Cu")
		(net "M_H_CPU1_SA_DQ<8>")
	)
	(gr_poly
		(pts
			(xy 130.26263 -280.168096) (xy 130.21564 -280.015696) (xy 129.95402 -280.015696) (xy 129.90703 -280.168096)
			(xy 129.90703 -280.212546) (xy 130.26263 -280.212546)
		)
		(stroke
			(width 0)
			(type solid)
		)
		(fill yes)
		(layer "In11.Cu")
		(net "M_H_CPU1_SA_DQ<11>")
	)
	(gr_poly
		(pts
			(xy 130.26263 -275.284946) (xy 130.21564 -275.132546) (xy 129.95402 -275.132546) (xy 129.90703 -275.284946)
			(xy 129.90703 -275.329142) (xy 130.26263 -275.329142)
		)
		(stroke
			(width 0)
			(type solid)
		)
		(fill yes)
		(layer "In11.Cu")
		(net "M_H_CPU1_SA_DQ<18>")
	)
	(gr_poly
		(pts
			(xy 130.26263 -270.401542) (xy 130.21564 -270.249142) (xy 129.95402 -270.249142) (xy 129.90703 -270.401542)
			(xy 129.90703 -270.445992) (xy 130.26263 -270.445992)
		)
		(stroke
			(width 0)
			(type solid)
		)
		(fill yes)
		(layer "In11.Cu")
		(net "M_H_CPU1_SA_DQS_DP<7>")
	)
	(gr_poly
		(pts
			(xy 130.26263 -268.77391) (xy 130.21564 -268.62151) (xy 129.95402 -268.62151) (xy 129.90703 -268.77391)
			(xy 129.90703 -268.818106) (xy 130.26263 -268.818106)
		)
		(stroke
			(width 0)
			(type solid)
		)
		(fill yes)
		(layer "In11.Cu")
		(net "M_H_CPU1_SA_DQ<22>")
	)
	(gr_poly
		(pts
			(xy 130.26263 -268.365478) (xy 130.26263 -268.321282) (xy 129.90703 -268.321282) (xy 129.90703 -268.365478)
			(xy 129.95402 -268.517878) (xy 130.21564 -268.517878)
		)
		(stroke
			(width 0)
			(type solid)
		)
		(fill yes)
		(layer "In11.Cu")
		(net "M_H_CPU1_SA_DQ<21>")
	)
	(gr_poly
		(pts
			(xy 130.26263 -267.14577) (xy 130.21564 -266.99337) (xy 129.95402 -266.99337) (xy 129.90703 -267.14577)
			(xy 129.90703 -267.19022) (xy 130.26263 -267.19022)
		)
		(stroke
			(width 0)
			(type solid)
		)
		(fill yes)
		(layer "In11.Cu")
		(net "M_H_CPU1_SA_DQ<26>")
	)
	(gr_poly
		(pts
			(xy 130.26263 -266.737846) (xy 130.26263 -266.69365) (xy 129.90703 -266.69365) (xy 129.90703 -266.737846)
			(xy 129.95402 -266.890246) (xy 130.21564 -266.890246)
		)
		(stroke
			(width 0)
			(type solid)
		)
		(fill yes)
		(layer "In11.Cu")
		(net "M_H_CPU1_SA_DQ<25>")
	)
	(gr_poly
		(pts
			(xy 130.26263 -265.518138) (xy 130.21564 -265.365738) (xy 129.95402 -265.365738) (xy 129.90703 -265.518138)
			(xy 129.90703 -265.562588) (xy 130.26263 -265.562588)
		)
		(stroke
			(width 0)
			(type solid)
		)
		(fill yes)
		(layer "In11.Cu")
		(net "M_H_CPU1_SA_DQS_DN<3>")
	)
	(gr_poly
		(pts
			(xy 130.26263 -265.110214) (xy 130.26263 -265.065764) (xy 129.90703 -265.065764) (xy 129.90703 -265.110214)
			(xy 129.95402 -265.262614) (xy 130.21564 -265.262614)
		)
		(stroke
			(width 0)
			(type solid)
		)
		(fill yes)
		(layer "In11.Cu")
		(net "M_H_CPU1_SA_DQS_DN<8>")
	)
	(gr_poly
		(pts
			(xy 130.26263 -262.262874) (xy 130.21564 -262.110474) (xy 129.95402 -262.110474) (xy 129.90703 -262.262874)
			(xy 129.90703 -262.30707) (xy 130.26263 -262.30707)
		)
		(stroke
			(width 0)
			(type solid)
		)
		(fill yes)
		(layer "In11.Cu")
		(net "M_H_CPU1_SA_CB<2>")
	)
	(gr_poly
		(pts
			(xy 130.26263 -261.854442) (xy 130.26263 -261.810246) (xy 129.90703 -261.810246) (xy 129.90703 -261.854442)
			(xy 129.95402 -262.006842) (xy 130.21564 -262.006842)
		)
		(stroke
			(width 0)
			(type solid)
		)
		(fill yes)
		(layer "In11.Cu")
		(net "M_H_CPU1_SA_CB<1>")
	)
	(gr_poly
		(pts
			(xy 130.26263 -260.634734) (xy 130.21564 -260.482334) (xy 129.95402 -260.482334) (xy 129.90703 -260.634734)
			(xy 129.90703 -260.679184) (xy 130.26263 -260.679184)
		)
		(stroke
			(width 0)
			(type solid)
		)
		(fill yes)
		(layer "In11.Cu")
		(net "M_H_CPU1_SA_DQS_DN<4>")
	)
	(gr_poly
		(pts
			(xy 130.26263 -260.22681) (xy 130.26263 -260.18236) (xy 129.90703 -260.18236) (xy 129.90703 -260.22681)
			(xy 129.95402 -260.37921) (xy 130.21564 -260.37921)
		)
		(stroke
			(width 0)
			(type solid)
		)
		(fill yes)
		(layer "In11.Cu")
		(net "M_H_CPU1_SA_DQS_DN<9>")
	)
	(gr_poly
		(pts
			(xy 130.26263 -257.37947) (xy 130.21564 -257.22707) (xy 129.95402 -257.22707) (xy 129.90703 -257.37947)
			(xy 129.90703 -257.423666) (xy 130.26263 -257.423666)
		)
		(stroke
			(width 0)
			(type solid)
		)
		(fill yes)
		(layer "In11.Cu")
		(net "M_H_CPU1_ALERT_N")
	)
	(gr_poly
		(pts
			(xy 130.26263 -256.971038) (xy 130.26263 -256.926842) (xy 129.90703 -256.926842) (xy 129.90703 -256.971038)
			(xy 129.95402 -257.123438) (xy 130.21564 -257.123438)
		)
		(stroke
			(width 0)
			(type solid)
		)
		(fill yes)
		(layer "In11.Cu")
		(net "M_H_CPU1_SA_CS_N<0>")
	)
	(gr_poly
		(pts
			(xy 130.26263 -255.751838) (xy 130.21564 -255.599438) (xy 129.95402 -255.599438) (xy 129.90703 -255.751838)
			(xy 129.90703 -255.796034) (xy 130.26263 -255.796034)
		)
		(stroke
			(width 0)
			(type solid)
		)
		(fill yes)
		(layer "In11.Cu")
		(net "M_H_CPU1_SA_CS_N<3>")
	)
	(gr_poly
		(pts
			(xy 130.26263 -255.343406) (xy 130.26263 -255.29921) (xy 129.90703 -255.29921) (xy 129.90703 -255.343406)
			(xy 129.95402 -255.495806) (xy 130.21564 -255.495806)
		)
		(stroke
			(width 0)
			(type solid)
		)
		(fill yes)
		(layer "In11.Cu")
		(net "M_H_CPU1_SA_CA<1>")
	)
	(gr_poly
		(pts
			(xy 130.575304 -274.72259) (xy 130.613658 -274.700492) (xy 130.435858 -274.392644) (xy 130.397504 -274.414742)
			(xy 130.289046 -274.531582) (xy 130.419856 -274.75815)
		)
		(stroke
			(width 0)
			(type solid)
		)
		(fill yes)
		(layer "In11.Cu")
		(net "M_H_CPU1_SA_DQ<17>")
	)
	(gr_poly
		(pts
			(xy 130.575304 -273.094958) (xy 130.613658 -273.07286) (xy 130.435858 -272.765012) (xy 130.397504 -272.78711)
			(xy 130.289046 -272.90395) (xy 130.419856 -273.130518)
		)
		(stroke
			(width 0)
			(type solid)
		)
		(fill yes)
		(layer "In11.Cu")
		(net "M_H_CPU1_SA_DQS_DP<2>")
	)
	(gr_poly
		(pts
			(xy 130.575304 -271.467072) (xy 130.613658 -271.444974) (xy 130.435858 -271.137126) (xy 130.397504 -271.159224)
			(xy 130.289046 -271.276064) (xy 130.419856 -271.502632)
		)
		(stroke
			(width 0)
			(type solid)
		)
		(fill yes)
		(layer "In11.Cu")
		(net "M_H_CPU1_SA_DQS_DN<7>")
	)
	(gr_poly
		(pts
			(xy 130.580638 -269.84833) (xy 130.618992 -269.826232) (xy 130.441192 -269.518384) (xy 130.402838 -269.540482)
			(xy 130.29438 -269.657322) (xy 130.42519 -269.88389)
		)
		(stroke
			(width 0)
			(type solid)
		)
		(fill yes)
		(layer "In11.Cu")
		(net "M_H_CPU1_SA_DQ<20>")
	)
	(gr_poly
		(pts
			(xy 130.60553 -246.568722) (xy 130.55854 -246.416322) (xy 130.29692 -246.416322) (xy 130.24993 -246.568722)
			(xy 130.24993 -246.612918) (xy 130.60553 -246.612918)
		)
		(stroke
			(width 0)
			(type solid)
		)
		(fill yes)
		(layer "In11.Cu")
		(net "M_H_CPU1_SB_CA<5>")
	)
	(gr_poly
		(pts
			(xy 130.60553 -246.16029) (xy 130.60553 -246.116094) (xy 130.24993 -246.116094) (xy 130.24993 -246.16029)
			(xy 130.29692 -246.31269) (xy 130.55854 -246.31269)
		)
		(stroke
			(width 0)
			(type solid)
		)
		(fill yes)
		(layer "In11.Cu")
		(net "M_H_CPU1_SB_CA<6>")
	)
	(gr_poly
		(pts
			(xy 130.60553 -244.532658) (xy 130.60553 -244.488208) (xy 130.24993 -244.488208) (xy 130.24993 -244.532658)
			(xy 130.29692 -244.685058) (xy 130.55854 -244.685058)
		)
		(stroke
			(width 0)
			(type solid)
		)
		(fill yes)
		(layer "In11.Cu")
		(net "M_H_CPU1_SB_CB<6>")
	)
	(gr_poly
		(pts
			(xy 130.60553 -243.31295) (xy 130.55854 -243.16055) (xy 130.29692 -243.16055) (xy 130.24993 -243.31295)
			(xy 130.24993 -243.3574) (xy 130.60553 -243.3574)
		)
		(stroke
			(width 0)
			(type solid)
		)
		(fill yes)
		(layer "In11.Cu")
		(net "M_H_CPU1_SB_CB<5>")
	)
	(gr_poly
		(pts
			(xy 130.60553 -242.905026) (xy 130.60553 -242.860576) (xy 130.24993 -242.860576) (xy 130.24993 -242.905026)
			(xy 130.29692 -243.057426) (xy 130.55854 -243.057426)
		)
		(stroke
			(width 0)
			(type solid)
		)
		(fill yes)
		(layer "In11.Cu")
		(net "M_H_CPU1_SB_DQS_DP<9>")
	)
	(gr_poly
		(pts
			(xy 130.60553 -241.276886) (xy 130.60553 -241.23269) (xy 130.24993 -241.23269) (xy 130.24993 -241.276886)
			(xy 130.29692 -241.429286) (xy 130.55854 -241.429286)
		)
		(stroke
			(width 0)
			(type solid)
		)
		(fill yes)
		(layer "In11.Cu")
		(net "M_H_CPU1_SB_CB<0>")
	)
	(gr_poly
		(pts
			(xy 130.60553 -240.057178) (xy 130.55854 -239.904778) (xy 130.29692 -239.904778) (xy 130.24993 -240.057178)
			(xy 130.24993 -240.101628) (xy 130.60553 -240.101628)
		)
		(stroke
			(width 0)
			(type solid)
		)
		(fill yes)
		(layer "In11.Cu")
		(net "M_H_CPU1_SB_CB<3>")
	)
	(gr_poly
		(pts
			(xy 130.60553 -239.649254) (xy 130.60553 -239.604804) (xy 130.24993 -239.604804) (xy 130.24993 -239.649254)
			(xy 130.29692 -239.801654) (xy 130.55854 -239.801654)
		)
		(stroke
			(width 0)
			(type solid)
		)
		(fill yes)
		(layer "In11.Cu")
		(net "M_H_CPU1_SB_DQ<0>")
	)
	(gr_poly
		(pts
			(xy 130.60553 -238.429546) (xy 130.55854 -238.277146) (xy 130.29692 -238.277146) (xy 130.24993 -238.429546)
			(xy 130.24993 -238.473996) (xy 130.60553 -238.473996)
		)
		(stroke
			(width 0)
			(type solid)
		)
		(fill yes)
		(layer "In11.Cu")
		(net "M_H_CPU1_SB_DQ<3>")
	)
	(gr_poly
		(pts
			(xy 130.60553 -238.021622) (xy 130.60553 -237.977172) (xy 130.24993 -237.977172) (xy 130.24993 -238.021622)
			(xy 130.29692 -238.174022) (xy 130.55854 -238.174022)
		)
		(stroke
			(width 0)
			(type solid)
		)
		(fill yes)
		(layer "In11.Cu")
		(net "M_H_CPU1_SB_DQS_DP<0>")
	)
	(gr_poly
		(pts
			(xy 130.60553 -236.39399) (xy 130.60553 -236.34954) (xy 130.24993 -236.34954) (xy 130.24993 -236.39399)
			(xy 130.29692 -236.54639) (xy 130.55854 -236.54639)
		)
		(stroke
			(width 0)
			(type solid)
		)
		(fill yes)
		(layer "In11.Cu")
		(net "M_H_CPU1_SB_DQ<4>")
	)
	(gr_poly
		(pts
			(xy 130.60553 -235.174282) (xy 130.55854 -235.021882) (xy 130.29692 -235.021882) (xy 130.24993 -235.174282)
			(xy 130.24993 -235.218478) (xy 130.60553 -235.218478)
		)
		(stroke
			(width 0)
			(type solid)
		)
		(fill yes)
		(layer "In11.Cu")
		(net "M_H_CPU1_SB_DQ<7>")
	)
	(gr_poly
		(pts
			(xy 130.60553 -234.76585) (xy 130.60553 -234.721654) (xy 130.24993 -234.721654) (xy 130.24993 -234.76585)
			(xy 130.29692 -234.91825) (xy 130.55854 -234.91825)
		)
		(stroke
			(width 0)
			(type solid)
		)
		(fill yes)
		(layer "In11.Cu")
		(net "M_H_CPU1_SB_DQ<8>")
	)
	(gr_poly
		(pts
			(xy 130.60553 -233.138218) (xy 130.60553 -233.093768) (xy 130.24993 -233.093768) (xy 130.24993 -233.138218)
			(xy 130.29692 -233.290618) (xy 130.55854 -233.290618)
		)
		(stroke
			(width 0)
			(type solid)
		)
		(fill yes)
		(layer "In11.Cu")
		(net "M_H_CPU1_SB_DQS_DP<1>")
	)
	(gr_poly
		(pts
			(xy 130.60553 -231.510586) (xy 130.60553 -231.466136) (xy 130.24993 -231.466136) (xy 130.24993 -231.510586)
			(xy 130.29692 -231.662986) (xy 130.55854 -231.662986)
		)
		(stroke
			(width 0)
			(type solid)
		)
		(fill yes)
		(layer "In11.Cu")
		(net "M_H_CPU1_SB_DQ<12>")
	)
	(gr_poly
		(pts
			(xy 130.60553 -230.290878) (xy 130.55854 -230.138478) (xy 130.29692 -230.138478) (xy 130.24993 -230.290878)
			(xy 130.24993 -230.335074) (xy 130.60553 -230.335074)
		)
		(stroke
			(width 0)
			(type solid)
		)
		(fill yes)
		(layer "In11.Cu")
		(net "M_H_CPU1_SB_DQ<15>")
	)
	(gr_poly
		(pts
			(xy 130.60553 -229.882446) (xy 130.60553 -229.83825) (xy 130.24993 -229.83825) (xy 130.24993 -229.882446)
			(xy 130.29692 -230.034846) (xy 130.55854 -230.034846)
		)
		(stroke
			(width 0)
			(type solid)
		)
		(fill yes)
		(layer "In11.Cu")
		(net "M_H_CPU1_SB_DQ<26>")
	)
	(gr_poly
		(pts
			(xy 130.60553 -228.663246) (xy 130.55854 -228.510846) (xy 130.29692 -228.510846) (xy 130.24993 -228.663246)
			(xy 130.24993 -228.707442) (xy 130.60553 -228.707442)
		)
		(stroke
			(width 0)
			(type solid)
		)
		(fill yes)
		(layer "In11.Cu")
		(net "M_H_CPU1_SB_DQ<25>")
	)
	(gr_poly
		(pts
			(xy 130.60553 -228.254814) (xy 130.60553 -228.210618) (xy 130.24993 -228.210618) (xy 130.24993 -228.254814)
			(xy 130.29692 -228.407214) (xy 130.55854 -228.407214)
		)
		(stroke
			(width 0)
			(type solid)
		)
		(fill yes)
		(layer "In11.Cu")
		(net "M_H_CPU1_SB_DQS_DN<8>")
	)
	(gr_poly
		(pts
			(xy 130.60553 -225.407474) (xy 130.55854 -225.255074) (xy 130.29692 -225.255074) (xy 130.24993 -225.407474)
			(xy 130.24993 -225.45167) (xy 130.60553 -225.45167)
		)
		(stroke
			(width 0)
			(type solid)
		)
		(fill yes)
		(layer "In11.Cu")
		(net "M_H_CPU1_SB_DQ<29>")
	)
	(gr_poly
		(pts
			(xy 130.605784 -233.546142) (xy 130.558794 -233.393742) (xy 130.297174 -233.393742) (xy 130.250184 -233.546142)
			(xy 130.250184 -233.590592) (xy 130.605784 -233.590592)
		)
		(stroke
			(width 0)
			(type solid)
		)
		(fill yes)
		(layer "In11.Cu")
		(net "M_H_CPU1_SB_DQ<11>")
	)
	(gr_poly
		(pts
			(xy 130.60807 -248.196354) (xy 130.56108 -248.043954) (xy 130.29946 -248.043954) (xy 130.25247 -248.196354)
			(xy 130.25247 -248.24055) (xy 130.60807 -248.24055)
		)
		(stroke
			(width 0)
			(type solid)
		)
		(fill yes)
		(layer "In11.Cu")
		(net "M_H_CPU1_SB_CA<1>")
	)
	(gr_poly
		(pts
			(xy 130.60807 -247.787922) (xy 130.60807 -247.743726) (xy 130.25247 -247.743726) (xy 130.25247 -247.787922)
			(xy 130.29946 -247.940322) (xy 130.56108 -247.940322)
		)
		(stroke
			(width 0)
			(type solid)
		)
		(fill yes)
		(layer "In11.Cu")
		(net "M_H_CPU1_SB_CA<2>")
	)
	(gr_poly
		(pts
			(xy 130.60807 -227.035106) (xy 130.56108 -226.882706) (xy 130.29946 -226.882706) (xy 130.25247 -227.035106)
			(xy 130.25247 -227.079556) (xy 130.60807 -227.079556)
		)
		(stroke
			(width 0)
			(type solid)
		)
		(fill yes)
		(layer "In11.Cu")
		(net "M_H_CPU1_SB_DQS_DN<3>")
	)
	(gr_poly
		(pts
			(xy 130.60807 -226.627182) (xy 130.60807 -226.582732) (xy 130.25247 -226.582732) (xy 130.25247 -226.627182)
			(xy 130.29946 -226.779582) (xy 130.56108 -226.779582)
		)
		(stroke
			(width 0)
			(type solid)
		)
		(fill yes)
		(layer "In11.Cu")
		(net "M_H_CPU1_SB_DQ<30>")
	)
	(gr_poly
		(pts
			(xy 130.61442 -241.685826) (xy 130.56743 -241.533426) (xy 130.30581 -241.533426) (xy 130.25882 -241.685826)
			(xy 130.25882 -241.730022) (xy 130.61442 -241.730022)
		)
		(stroke
			(width 0)
			(type solid)
		)
		(fill yes)
		(layer "In11.Cu")
		(net "M_H_CPU1_SB_DQS_DP<4>")
	)
	(gr_poly
		(pts
			(xy 130.61442 -236.802422) (xy 130.56743 -236.650022) (xy 130.30581 -236.650022) (xy 130.25882 -236.802422)
			(xy 130.25882 -236.846872) (xy 130.61442 -236.846872)
		)
		(stroke
			(width 0)
			(type solid)
		)
		(fill yes)
		(layer "In11.Cu")
		(net "M_H_CPU1_SB_DQS_DP<5>")
	)
	(gr_poly
		(pts
			(xy 130.61442 -231.919018) (xy 130.56743 -231.766618) (xy 130.30581 -231.766618) (xy 130.25882 -231.919018)
			(xy 130.25882 -231.963468) (xy 130.61442 -231.963468)
		)
		(stroke
			(width 0)
			(type solid)
		)
		(fill yes)
		(layer "In11.Cu")
		(net "M_H_CPU1_SB_DQS_DP<6>")
	)
	(gr_poly
		(pts
			(xy 130.687572 -272.480278) (xy 130.79603 -272.363438) (xy 130.66522 -272.13687) (xy 130.509772 -272.17243)
			(xy 130.471418 -272.194528) (xy 130.649218 -272.502376)
		)
		(stroke
			(width 0)
			(type solid)
		)
		(fill yes)
		(layer "In11.Cu")
		(net "M_H_CPU1_SA_DQS_DN<2>")
	)
	(gr_poly
		(pts
			(xy 130.68935 -274.109434) (xy 130.797808 -273.992594) (xy 130.666998 -273.766026) (xy 130.51155 -273.801586)
			(xy 130.473196 -273.823684) (xy 130.650996 -274.131532)
		)
		(stroke
			(width 0)
			(type solid)
		)
		(fill yes)
		(layer "In11.Cu")
		(net "M_H_CPU1_SA_DQ<19>")
	)
	(gr_poly
		(pts
			(xy 130.68935 -270.853916) (xy 130.797808 -270.737076) (xy 130.666998 -270.510508) (xy 130.51155 -270.546068)
			(xy 130.473196 -270.568166) (xy 130.650996 -270.876014)
		)
		(stroke
			(width 0)
			(type solid)
		)
		(fill yes)
		(layer "In11.Cu")
		(net "M_H_CPU1_SA_DQS_DP<7>")
	)
	(gr_poly
		(pts
			(xy 130.68935 -269.22603) (xy 130.797808 -269.10919) (xy 130.666998 -268.882622) (xy 130.51155 -268.918182)
			(xy 130.473196 -268.94028) (xy 130.650996 -269.248128)
		)
		(stroke
			(width 0)
			(type solid)
		)
		(fill yes)
		(layer "In11.Cu")
		(net "M_H_CPU1_SA_DQ<22>")
	)
	(gr_poly
		(pts
			(xy 130.715512 -280.98242) (xy 130.668522 -280.83002) (xy 130.406902 -280.83002) (xy 130.359912 -280.98242)
			(xy 130.359912 -281.026616) (xy 130.715512 -281.026616)
		)
		(stroke
			(width 0)
			(type solid)
		)
		(fill yes)
		(layer "In11.Cu")
		(net "M_H_CPU1_SA_DQ<10>")
	)
	(gr_poly
		(pts
			(xy 130.715512 -280.574242) (xy 130.715512 -280.529792) (xy 130.359912 -280.529792) (xy 130.359912 -280.574242)
			(xy 130.406902 -280.726642) (xy 130.668522 -280.726642)
		)
		(stroke
			(width 0)
			(type solid)
		)
		(fill yes)
		(layer "In11.Cu")
		(net "M_H_CPU1_SA_DQ<9>")
	)
	(gr_poly
		(pts
			(xy 130.715512 -275.690584) (xy 130.715512 -275.646388) (xy 130.359912 -275.646388) (xy 130.359912 -275.690584)
			(xy 130.406902 -275.842984) (xy 130.668522 -275.842984)
		)
		(stroke
			(width 0)
			(type solid)
		)
		(fill yes)
		(layer "In11.Cu")
		(net "M_H_CPU1_SA_DQ<16>")
	)
	(gr_poly
		(pts
			(xy 130.715512 -267.960094) (xy 130.668522 -267.807694) (xy 130.406902 -267.807694) (xy 130.359912 -267.960094)
			(xy 130.359912 -268.00429) (xy 130.715512 -268.00429)
		)
		(stroke
			(width 0)
			(type solid)
		)
		(fill yes)
		(layer "In11.Cu")
		(net "M_H_CPU1_SA_DQ<23>")
	)
	(gr_poly
		(pts
			(xy 130.715512 -267.551662) (xy 130.715512 -267.507466) (xy 130.359912 -267.507466) (xy 130.359912 -267.551662)
			(xy 130.406902 -267.704062) (xy 130.668522 -267.704062)
		)
		(stroke
			(width 0)
			(type solid)
		)
		(fill yes)
		(layer "In11.Cu")
		(net "M_H_CPU1_SA_DQ<24>")
	)
	(gr_poly
		(pts
			(xy 130.715512 -266.331954) (xy 130.668522 -266.179554) (xy 130.406902 -266.179554) (xy 130.359912 -266.331954)
			(xy 130.359912 -266.376404) (xy 130.715512 -266.376404)
		)
		(stroke
			(width 0)
			(type solid)
		)
		(fill yes)
		(layer "In11.Cu")
		(net "M_H_CPU1_SA_DQ<27>")
	)
	(gr_poly
		(pts
			(xy 130.715512 -265.92403) (xy 130.715512 -265.879834) (xy 130.359912 -265.879834) (xy 130.359912 -265.92403)
			(xy 130.406902 -266.07643) (xy 130.668522 -266.07643)
		)
		(stroke
			(width 0)
			(type solid)
		)
		(fill yes)
		(layer "In11.Cu")
		(net "M_H_CPU1_SA_DQS_DP<3>")
	)
	(gr_poly
		(pts
			(xy 130.715512 -264.704322) (xy 130.668522 -264.551922) (xy 130.406902 -264.551922) (xy 130.359912 -264.704322)
			(xy 130.359912 -264.748772) (xy 130.715512 -264.748772)
		)
		(stroke
			(width 0)
			(type solid)
		)
		(fill yes)
		(layer "In11.Cu")
		(net "M_H_CPU1_SA_DQS_DP<8>")
	)
	(gr_poly
		(pts
			(xy 130.715512 -264.296398) (xy 130.715512 -264.251948) (xy 130.359912 -264.251948) (xy 130.359912 -264.296398)
			(xy 130.406902 -264.448798) (xy 130.668522 -264.448798)
		)
		(stroke
			(width 0)
			(type solid)
		)
		(fill yes)
		(layer "In11.Cu")
		(net "M_H_CPU1_SA_DQ<28>")
	)
	(gr_poly
		(pts
			(xy 130.715512 -263.07669) (xy 130.668522 -262.92429) (xy 130.406902 -262.92429) (xy 130.359912 -263.07669)
			(xy 130.359912 -263.120886) (xy 130.715512 -263.120886)
		)
		(stroke
			(width 0)
			(type solid)
		)
		(fill yes)
		(layer "In11.Cu")
		(net "M_H_CPU1_SA_DQ<31>")
	)
	(gr_poly
		(pts
			(xy 130.715512 -262.668258) (xy 130.715512 -262.624062) (xy 130.359912 -262.624062) (xy 130.359912 -262.668258)
			(xy 130.406902 -262.820658) (xy 130.668522 -262.820658)
		)
		(stroke
			(width 0)
			(type solid)
		)
		(fill yes)
		(layer "In11.Cu")
		(net "M_H_CPU1_SA_CB<0>")
	)
	(gr_poly
		(pts
			(xy 130.715512 -261.449058) (xy 130.668522 -261.296658) (xy 130.406902 -261.296658) (xy 130.359912 -261.449058)
			(xy 130.359912 -261.493254) (xy 130.715512 -261.493254)
		)
		(stroke
			(width 0)
			(type solid)
		)
		(fill yes)
		(layer "In11.Cu")
		(net "M_H_CPU1_SA_CB<3>")
	)
	(gr_poly
		(pts
			(xy 130.715512 -261.040626) (xy 130.715512 -260.99643) (xy 130.359912 -260.99643) (xy 130.359912 -261.040626)
			(xy 130.406902 -261.193026) (xy 130.668522 -261.193026)
		)
		(stroke
			(width 0)
			(type solid)
		)
		(fill yes)
		(layer "In11.Cu")
		(net "M_H_CPU1_SA_DQS_DP<4>")
	)
	(gr_poly
		(pts
			(xy 130.715512 -259.820918) (xy 130.668522 -259.668518) (xy 130.406902 -259.668518) (xy 130.359912 -259.820918)
			(xy 130.359912 -259.865368) (xy 130.715512 -259.865368)
		)
		(stroke
			(width 0)
			(type solid)
		)
		(fill yes)
		(layer "In11.Cu")
		(net "M_H_CPU1_SA_DQS_DP<9>")
	)
	(gr_poly
		(pts
			(xy 130.715512 -259.412994) (xy 130.715512 -259.368544) (xy 130.359912 -259.368544) (xy 130.359912 -259.412994)
			(xy 130.406902 -259.565394) (xy 130.668522 -259.565394)
		)
		(stroke
			(width 0)
			(type solid)
		)
		(fill yes)
		(layer "In11.Cu")
		(net "M_H_CPU1_SA_CB<4>")
	)
	(gr_poly
		(pts
			(xy 130.715512 -258.193286) (xy 130.668522 -258.040886) (xy 130.406902 -258.040886) (xy 130.359912 -258.193286)
			(xy 130.359912 -258.237482) (xy 130.715512 -258.237482)
		)
		(stroke
			(width 0)
			(type solid)
		)
		(fill yes)
		(layer "In11.Cu")
		(net "M_H_CPU1_SA_CB<7>")
	)
	(gr_poly
		(pts
			(xy 130.715512 -257.784854) (xy 130.715512 -257.740658) (xy 130.359912 -257.740658) (xy 130.359912 -257.784854)
			(xy 130.406902 -257.937254) (xy 130.668522 -257.937254)
		)
		(stroke
			(width 0)
			(type solid)
		)
		(fill yes)
		(layer "In11.Cu")
		(net "M_E_CPU1_ALERT_N")
	)
	(gr_poly
		(pts
			(xy 130.715512 -256.565654) (xy 130.668522 -256.413254) (xy 130.406902 -256.413254) (xy 130.359912 -256.565654)
			(xy 130.359912 -256.60985) (xy 130.715512 -256.60985)
		)
		(stroke
			(width 0)
			(type solid)
		)
		(fill yes)
		(layer "In11.Cu")
		(net "M_H_CPU1_SA_CS_N<1>")
	)
	(gr_poly
		(pts
			(xy 130.715512 -256.157222) (xy 130.715512 -256.113026) (xy 130.359912 -256.113026) (xy 130.359912 -256.157222)
			(xy 130.406902 -256.309622) (xy 130.668522 -256.309622)
		)
		(stroke
			(width 0)
			(type solid)
		)
		(fill yes)
		(layer "In11.Cu")
		(net "M_H_CPU1_SA_CS_N<2>")
	)
	(gr_poly
		(pts
			(xy 130.715512 -254.937514) (xy 130.668522 -254.785114) (xy 130.406902 -254.785114) (xy 130.359912 -254.937514)
			(xy 130.359912 -254.981964) (xy 130.715512 -254.981964)
		)
		(stroke
			(width 0)
			(type solid)
		)
		(fill yes)
		(layer "In11.Cu")
		(net "M_H_CPU1_SA_CA<0>")
	)
	(gr_poly
		(pts
			(xy 130.715512 -254.52959) (xy 130.715512 -254.48514) (xy 130.359912 -254.48514) (xy 130.359912 -254.52959)
			(xy 130.406902 -254.68199) (xy 130.668522 -254.68199)
		)
		(stroke
			(width 0)
			(type solid)
		)
		(fill yes)
		(layer "In11.Cu")
		(net "M_H_CPU1_SA_CA<2>")
	)
	(gr_poly
		(pts
			(xy 130.718052 -279.354788) (xy 130.671062 -279.202388) (xy 130.409442 -279.202388) (xy 130.362452 -279.354788)
			(xy 130.362452 -279.398984) (xy 130.718052 -279.398984)
		)
		(stroke
			(width 0)
			(type solid)
		)
		(fill yes)
		(layer "In11.Cu")
		(net "M_H_CPU1_SA_DQS_DN<1>")
	)
	(gr_poly
		(pts
			(xy 130.724148 -277.317962) (xy 130.724148 -277.273766) (xy 130.368548 -277.273766) (xy 130.368548 -277.317962)
			(xy 130.415538 -277.470362) (xy 130.677158 -277.470362)
		)
		(stroke
			(width 0)
			(type solid)
		)
		(fill yes)
		(layer "In11.Cu")
		(net "M_H_CPU1_SA_DQ<13>")
	)
	(gr_poly
		(pts
			(xy 130.72999 -278.945848) (xy 130.72999 -278.901652) (xy 130.37439 -278.901652) (xy 130.37439 -278.945848)
			(xy 130.42138 -279.098248) (xy 130.683 -279.098248)
		)
		(stroke
			(width 0)
			(type solid)
		)
		(fill yes)
		(layer "In11.Cu")
		(net "M_H_CPU1_SA_DQS_DN<6>")
	)
	(gr_poly
		(pts
			(xy 130.73253 -277.726394) (xy 130.68554 -277.573994) (xy 130.42392 -277.573994) (xy 130.37693 -277.726394)
			(xy 130.37693 -277.770844) (xy 130.73253 -277.770844)
		)
		(stroke
			(width 0)
			(type solid)
		)
		(fill yes)
		(layer "In11.Cu")
		(net "M_H_CPU1_SA_DQ<14>")
	)
	(gr_poly
		(pts
			(xy 131.050792 -273.918426) (xy 131.089146 -273.896328) (xy 130.911346 -273.58848) (xy 130.872992 -273.610578)
			(xy 130.764534 -273.727418) (xy 130.895344 -273.953986)
		)
		(stroke
			(width 0)
			(type solid)
		)
		(fill yes)
		(layer "In11.Cu")
		(net "M_H_CPU1_SA_DQS_DP<2>")
	)
	(gr_poly
		(pts
			(xy 131.050792 -270.662908) (xy 131.089146 -270.64081) (xy 130.911346 -270.332962) (xy 130.872992 -270.35506)
			(xy 130.764534 -270.4719) (xy 130.895344 -270.698468)
		)
		(stroke
			(width 0)
			(type solid)
		)
		(fill yes)
		(layer "In11.Cu")
		(net "M_H_CPU1_SA_DQ<20>")
	)
	(gr_poly
		(pts
			(xy 131.050792 -269.035022) (xy 131.089146 -269.012924) (xy 130.911346 -268.705076) (xy 130.872992 -268.727174)
			(xy 130.764534 -268.844014) (xy 130.895344 -269.070582)
		)
		(stroke
			(width 0)
			(type solid)
		)
		(fill yes)
		(layer "In11.Cu")
		(net "M_H_CPU1_SA_DQ<21>")
	)
	(gr_poly
		(pts
			(xy 131.05257 -272.292064) (xy 131.090924 -272.269966) (xy 130.913124 -271.962118) (xy 130.87477 -271.984216)
			(xy 130.766312 -272.101056) (xy 130.897122 -272.327624)
		)
		(stroke
			(width 0)
			(type solid)
		)
		(fill yes)
		(layer "In11.Cu")
		(net "M_H_CPU1_SA_DQS_DN<7>")
	)
	(gr_poly
		(pts
			(xy 131.07797 -247.382538) (xy 131.03098 -247.230138) (xy 130.76936 -247.230138) (xy 130.72237 -247.382538)
			(xy 130.72237 -247.426988) (xy 131.07797 -247.426988)
		)
		(stroke
			(width 0)
			(type solid)
		)
		(fill yes)
		(layer "In11.Cu")
		(net "M_H_CPU1_SB_CA<3>")
	)
	(gr_poly
		(pts
			(xy 131.084066 -248.601738) (xy 131.084066 -248.557542) (xy 130.728466 -248.557542) (xy 130.728466 -248.601738)
			(xy 130.775456 -248.754138) (xy 131.037076 -248.754138)
		)
		(stroke
			(width 0)
			(type solid)
		)
		(fill yes)
		(layer "In11.Cu")
		(net "M_H_CPU1_SB_CA<0>")
	)
	(gr_poly
		(pts
			(xy 131.084066 -227.44049) (xy 131.084066 -227.396294) (xy 130.728466 -227.396294) (xy 130.728466 -227.44049)
			(xy 130.775456 -227.59289) (xy 131.037076 -227.59289)
		)
		(stroke
			(width 0)
			(type solid)
		)
		(fill yes)
		(layer "In11.Cu")
		(net "M_H_CPU1_SB_DQS_DP<3>")
	)
	(gr_poly
		(pts
			(xy 131.084066 -226.221798) (xy 131.037076 -226.069398) (xy 130.775456 -226.069398) (xy 130.728466 -226.221798)
			(xy 130.728466 -226.265994) (xy 131.084066 -226.265994)
		)
		(stroke
			(width 0)
			(type solid)
		)
		(fill yes)
		(layer "In11.Cu")
		(net "M_H_CPU1_SB_DQ<28>")
	)
	(gr_poly
		(pts
			(xy 131.089908 -246.974106) (xy 131.089908 -246.929656) (xy 130.734308 -246.929656) (xy 130.734308 -246.974106)
			(xy 130.781298 -247.126506) (xy 131.042918 -247.126506)
		)
		(stroke
			(width 0)
			(type solid)
		)
		(fill yes)
		(layer "In11.Cu")
		(net "M_H_CPU1_SB_CA<4>")
	)
	(gr_poly
		(pts
			(xy 131.092448 -245.754906) (xy 131.045458 -245.602506) (xy 130.783838 -245.602506) (xy 130.736848 -245.754906)
			(xy 130.736848 -245.799102) (xy 131.092448 -245.799102)
		)
		(stroke
			(width 0)
			(type solid)
		)
		(fill yes)
		(layer "In11.Cu")
		(net "M_H_CPU1_SB_PAR")
	)
	(gr_poly
		(pts
			(xy 131.092448 -244.126766) (xy 131.045458 -243.974366) (xy 130.783838 -243.974366) (xy 130.736848 -244.126766)
			(xy 130.736848 -244.171216) (xy 131.092448 -244.171216)
		)
		(stroke
			(width 0)
			(type solid)
		)
		(fill yes)
		(layer "In11.Cu")
		(net "M_H_CPU1_SB_CB<4>")
	)
	(gr_poly
		(pts
			(xy 131.092448 -243.718842) (xy 131.092448 -243.674392) (xy 130.736848 -243.674392) (xy 130.736848 -243.718842)
			(xy 130.783838 -243.871242) (xy 131.045458 -243.871242)
		)
		(stroke
			(width 0)
			(type solid)
		)
		(fill yes)
		(layer "In11.Cu")
		(net "M_H_CPU1_SB_CB<7>")
	)
	(gr_poly
		(pts
			(xy 131.092448 -242.499134) (xy 131.045458 -242.346734) (xy 130.783838 -242.346734) (xy 130.736848 -242.499134)
			(xy 130.736848 -242.54333) (xy 131.092448 -242.54333)
		)
		(stroke
			(width 0)
			(type solid)
		)
		(fill yes)
		(layer "In11.Cu")
		(net "M_H_CPU1_SB_DQS_DN<9>")
	)
	(gr_poly
		(pts
			(xy 131.092448 -242.090702) (xy 131.092448 -242.046506) (xy 130.736848 -242.046506) (xy 130.736848 -242.090702)
			(xy 130.783838 -242.243102) (xy 131.045458 -242.243102)
		)
		(stroke
			(width 0)
			(type solid)
		)
		(fill yes)
		(layer "In11.Cu")
		(net "M_H_CPU1_SB_DQS_DN<4>")
	)
	(gr_poly
		(pts
			(xy 131.092448 -240.871502) (xy 131.045458 -240.719102) (xy 130.783838 -240.719102) (xy 130.736848 -240.871502)
			(xy 130.736848 -240.915698) (xy 131.092448 -240.915698)
		)
		(stroke
			(width 0)
			(type solid)
		)
		(fill yes)
		(layer "In11.Cu")
		(net "M_H_CPU1_SB_CB<2>")
	)
	(gr_poly
		(pts
			(xy 131.092448 -240.46307) (xy 131.092448 -240.418874) (xy 130.736848 -240.418874) (xy 130.736848 -240.46307)
			(xy 130.783838 -240.61547) (xy 131.045458 -240.61547)
		)
		(stroke
			(width 0)
			(type solid)
		)
		(fill yes)
		(layer "In11.Cu")
		(net "M_H_CPU1_SB_CB<1>")
	)
	(gr_poly
		(pts
			(xy 131.092448 -239.243362) (xy 131.045458 -239.090962) (xy 130.783838 -239.090962) (xy 130.736848 -239.243362)
			(xy 130.736848 -239.287812) (xy 131.092448 -239.287812)
		)
		(stroke
			(width 0)
			(type solid)
		)
		(fill yes)
		(layer "In11.Cu")
		(net "M_H_CPU1_SB_DQ<2>")
	)
	(gr_poly
		(pts
			(xy 131.092448 -238.835438) (xy 131.092448 -238.790988) (xy 130.736848 -238.790988) (xy 130.736848 -238.835438)
			(xy 130.783838 -238.987838) (xy 131.045458 -238.987838)
		)
		(stroke
			(width 0)
			(type solid)
		)
		(fill yes)
		(layer "In11.Cu")
		(net "M_H_CPU1_SB_DQ<1>")
	)
	(gr_poly
		(pts
			(xy 131.092448 -237.61573) (xy 131.045458 -237.46333) (xy 130.783838 -237.46333) (xy 130.736848 -237.61573)
			(xy 130.736848 -237.66018) (xy 131.092448 -237.66018)
		)
		(stroke
			(width 0)
			(type solid)
		)
		(fill yes)
		(layer "In11.Cu")
		(net "M_H_CPU1_SB_DQS_DN<0>")
	)
	(gr_poly
		(pts
			(xy 131.092448 -237.207806) (xy 131.092448 -237.163356) (xy 130.736848 -237.163356) (xy 130.736848 -237.207806)
			(xy 130.783838 -237.360206) (xy 131.045458 -237.360206)
		)
		(stroke
			(width 0)
			(type solid)
		)
		(fill yes)
		(layer "In11.Cu")
		(net "M_H_CPU1_SB_DQS_DN<5>")
	)
	(gr_poly
		(pts
			(xy 131.092448 -235.988098) (xy 131.045458 -235.835698) (xy 130.783838 -235.835698) (xy 130.736848 -235.988098)
			(xy 130.736848 -236.032294) (xy 131.092448 -236.032294)
		)
		(stroke
			(width 0)
			(type solid)
		)
		(fill yes)
		(layer "In11.Cu")
		(net "M_H_CPU1_SB_DQ<6>")
	)
	(gr_poly
		(pts
			(xy 131.092448 -235.579666) (xy 131.092448 -235.53547) (xy 130.736848 -235.53547) (xy 130.736848 -235.579666)
			(xy 130.783838 -235.732066) (xy 131.045458 -235.732066)
		)
		(stroke
			(width 0)
			(type solid)
		)
		(fill yes)
		(layer "In11.Cu")
		(net "M_H_CPU1_SB_DQ<5>")
	)
	(gr_poly
		(pts
			(xy 131.092448 -234.360466) (xy 131.045458 -234.208066) (xy 130.783838 -234.208066) (xy 130.736848 -234.360466)
			(xy 130.736848 -234.404662) (xy 131.092448 -234.404662)
		)
		(stroke
			(width 0)
			(type solid)
		)
		(fill yes)
		(layer "In11.Cu")
		(net "M_H_CPU1_SB_DQ<10>")
	)
	(gr_poly
		(pts
			(xy 131.092448 -233.952034) (xy 131.092448 -233.907838) (xy 130.736848 -233.907838) (xy 130.736848 -233.952034)
			(xy 130.783838 -234.104434) (xy 131.045458 -234.104434)
		)
		(stroke
			(width 0)
			(type solid)
		)
		(fill yes)
		(layer "In11.Cu")
		(net "M_H_CPU1_SB_DQ<9>")
	)
	(gr_poly
		(pts
			(xy 131.092448 -232.732326) (xy 131.045458 -232.579926) (xy 130.783838 -232.579926) (xy 130.736848 -232.732326)
			(xy 130.736848 -232.776776) (xy 131.092448 -232.776776)
		)
		(stroke
			(width 0)
			(type solid)
		)
		(fill yes)
		(layer "In11.Cu")
		(net "M_H_CPU1_SB_DQS_DN<1>")
	)
	(gr_poly
		(pts
			(xy 131.092448 -232.324402) (xy 131.092448 -232.279952) (xy 130.736848 -232.279952) (xy 130.736848 -232.324402)
			(xy 130.783838 -232.476802) (xy 131.045458 -232.476802)
		)
		(stroke
			(width 0)
			(type solid)
		)
		(fill yes)
		(layer "In11.Cu")
		(net "M_H_CPU1_SB_DQS_DN<6>")
	)
	(gr_poly
		(pts
			(xy 131.092448 -231.104694) (xy 131.045458 -230.952294) (xy 130.783838 -230.952294) (xy 130.736848 -231.104694)
			(xy 130.736848 -231.14889) (xy 131.092448 -231.14889)
		)
		(stroke
			(width 0)
			(type solid)
		)
		(fill yes)
		(layer "In11.Cu")
		(net "M_H_CPU1_SB_DQ<14>")
	)
	(gr_poly
		(pts
			(xy 131.092448 -230.696262) (xy 131.092448 -230.652066) (xy 130.736848 -230.652066) (xy 130.736848 -230.696262)
			(xy 130.783838 -230.848662) (xy 131.045458 -230.848662)
		)
		(stroke
			(width 0)
			(type solid)
		)
		(fill yes)
		(layer "In11.Cu")
		(net "M_H_CPU1_SB_DQ<13>")
	)
	(gr_poly
		(pts
			(xy 131.092448 -229.477062) (xy 131.045458 -229.324662) (xy 130.783838 -229.324662) (xy 130.736848 -229.477062)
			(xy 130.736848 -229.521258) (xy 131.092448 -229.521258)
		)
		(stroke
			(width 0)
			(type solid)
		)
		(fill yes)
		(layer "In11.Cu")
		(net "M_H_CPU1_SB_DQ<24>")
	)
	(gr_poly
		(pts
			(xy 131.092448 -229.06863) (xy 131.092448 -229.024434) (xy 130.736848 -229.024434) (xy 130.736848 -229.06863)
			(xy 130.783838 -229.22103) (xy 131.045458 -229.22103)
		)
		(stroke
			(width 0)
			(type solid)
		)
		(fill yes)
		(layer "In11.Cu")
		(net "M_H_CPU1_SB_DQ<27>")
	)
	(gr_poly
		(pts
			(xy 131.092448 -227.848922) (xy 131.045458 -227.696522) (xy 130.783838 -227.696522) (xy 130.736848 -227.848922)
			(xy 130.736848 -227.893372) (xy 131.092448 -227.893372)
		)
		(stroke
			(width 0)
			(type solid)
		)
		(fill yes)
		(layer "In11.Cu")
		(net "M_H_CPU1_SB_DQS_DP<8>")
	)
	(gr_poly
		(pts
			(xy 131.092448 -225.813366) (xy 131.092448 -225.768916) (xy 130.736848 -225.768916) (xy 130.736848 -225.813366)
			(xy 130.783838 -225.965766) (xy 131.045458 -225.965766)
		)
		(stroke
			(width 0)
			(type solid)
		)
		(fill yes)
		(layer "In11.Cu")
		(net "M_H_CPU1_SB_DQ<31>")
	)
	(gr_poly
		(pts
			(xy 131.159504 -270.040608) (xy 131.267962 -269.923768) (xy 131.137152 -269.6972) (xy 130.981704 -269.73276)
			(xy 130.94335 -269.754858) (xy 131.12115 -270.062706)
		)
		(stroke
			(width 0)
			(type solid)
		)
		(fill yes)
		(layer "In11.Cu")
		(net "M_H_CPU1_SA_DQ<22>")
	)
	(gr_poly
		(pts
			(xy 131.164838 -273.30527) (xy 131.273296 -273.18843) (xy 131.142486 -272.961862) (xy 130.987038 -272.997422)
			(xy 130.948684 -273.01952) (xy 131.126484 -273.327368)
		)
		(stroke
			(width 0)
			(type solid)
		)
		(fill yes)
		(layer "In11.Cu")
		(net "M_H_CPU1_SA_DQS_DN<2>")
	)
	(gr_poly
		(pts
			(xy 131.164838 -271.677384) (xy 131.273296 -271.560544) (xy 131.142486 -271.333976) (xy 130.987038 -271.369536)
			(xy 130.948684 -271.391634) (xy 131.126484 -271.699482)
		)
		(stroke
			(width 0)
			(type solid)
		)
		(fill yes)
		(layer "In11.Cu")
		(net "M_H_CPU1_SA_DQS_DP<7>")
	)
	(gr_poly
		(pts
			(xy 131.164838 -268.421866) (xy 131.273296 -268.305026) (xy 131.142486 -268.078458) (xy 130.987038 -268.114018)
			(xy 130.948684 -268.136116) (xy 131.126484 -268.443964)
		)
		(stroke
			(width 0)
			(type solid)
		)
		(fill yes)
		(layer "In11.Cu")
		(net "M_H_CPU1_SA_DQ<23>")
	)
	(gr_poly
		(pts
			(xy 131.187952 -278.132286) (xy 131.187952 -278.08809) (xy 130.832352 -278.08809) (xy 130.832352 -278.132286)
			(xy 130.879342 -278.284686) (xy 131.140962 -278.284686)
		)
		(stroke
			(width 0)
			(type solid)
		)
		(fill yes)
		(layer "In11.Cu")
		(net "M_H_CPU1_SA_DQ<12>")
	)
	(gr_poly
		(pts
			(xy 131.194048 -276.913086) (xy 131.147058 -276.760686) (xy 130.885438 -276.760686) (xy 130.838448 -276.913086)
			(xy 130.838448 -276.957282) (xy 131.194048 -276.957282)
		)
		(stroke
			(width 0)
			(type solid)
		)
		(fill yes)
		(layer "In11.Cu")
		(net "M_H_CPU1_SA_DQ<15>")
	)
	(gr_poly
		(pts
			(xy 131.19989 -278.540718) (xy 131.1529 -278.388318) (xy 130.89128 -278.388318) (xy 130.84429 -278.540718)
			(xy 130.84429 -278.584914) (xy 131.19989 -278.584914)
		)
		(stroke
			(width 0)
			(type solid)
		)
		(fill yes)
		(layer "In11.Cu")
		(net "M_H_CPU1_SA_DQS_DP<6>")
	)
	(gr_poly
		(pts
			(xy 131.19989 -254.124206) (xy 131.1529 -253.971806) (xy 130.89128 -253.971806) (xy 130.84429 -254.124206)
			(xy 130.84429 -254.168402) (xy 131.19989 -254.168402)
		)
		(stroke
			(width 0)
			(type solid)
		)
		(fill yes)
		(layer "In11.Cu")
		(net "M_H_CPU1_SA_CA<3>")
	)
	(gr_poly
		(pts
			(xy 131.20243 -281.387804) (xy 131.20243 -281.343608) (xy 130.84683 -281.343608) (xy 130.84683 -281.387804)
			(xy 130.89382 -281.540204) (xy 131.15544 -281.540204)
		)
		(stroke
			(width 0)
			(type solid)
		)
		(fill yes)
		(layer "In11.Cu")
		(net "M_H_CPU1_SA_DQ<8>")
	)
	(gr_poly
		(pts
			(xy 131.20243 -280.168096) (xy 131.15544 -280.015696) (xy 130.89382 -280.015696) (xy 130.84683 -280.168096)
			(xy 130.84683 -280.212546) (xy 131.20243 -280.212546)
		)
		(stroke
			(width 0)
			(type solid)
		)
		(fill yes)
		(layer "In11.Cu")
		(net "M_H_CPU1_SA_DQ<11>")
	)
	(gr_poly
		(pts
			(xy 131.20243 -279.759918) (xy 131.20243 -279.715722) (xy 130.84683 -279.715722) (xy 130.84683 -279.759918)
			(xy 130.89382 -279.912318) (xy 131.15544 -279.912318)
		)
		(stroke
			(width 0)
			(type solid)
		)
		(fill yes)
		(layer "In11.Cu")
		(net "M_H_CPU1_SA_DQS_DP<1>")
	)
	(gr_poly
		(pts
			(xy 131.20243 -275.284946) (xy 131.15544 -275.132546) (xy 130.89382 -275.132546) (xy 130.84683 -275.284946)
			(xy 130.84683 -275.329142) (xy 131.20243 -275.329142)
		)
		(stroke
			(width 0)
			(type solid)
		)
		(fill yes)
		(layer "In11.Cu")
		(net "M_H_CPU1_SA_DQ<18>")
	)
	(gr_poly
		(pts
			(xy 131.20243 -274.876514) (xy 131.20243 -274.832318) (xy 130.84683 -274.832318) (xy 130.84683 -274.876514)
			(xy 130.89382 -275.028914) (xy 131.15544 -275.028914)
		)
		(stroke
			(width 0)
			(type solid)
		)
		(fill yes)
		(layer "In11.Cu")
		(net "M_H_CPU1_SA_DQ<17>")
	)
	(gr_poly
		(pts
			(xy 131.20243 -267.14577) (xy 131.15544 -266.99337) (xy 130.89382 -266.99337) (xy 130.84683 -267.14577)
			(xy 130.84683 -267.19022) (xy 131.20243 -267.19022)
		)
		(stroke
			(width 0)
			(type solid)
		)
		(fill yes)
		(layer "In11.Cu")
		(net "M_H_CPU1_SA_DQ<26>")
	)
	(gr_poly
		(pts
			(xy 131.20243 -266.737846) (xy 131.20243 -266.69365) (xy 130.84683 -266.69365) (xy 130.84683 -266.737846)
			(xy 130.89382 -266.890246) (xy 131.15544 -266.890246)
		)
		(stroke
			(width 0)
			(type solid)
		)
		(fill yes)
		(layer "In11.Cu")
		(net "M_H_CPU1_SA_DQ<25>")
	)
	(gr_poly
		(pts
			(xy 131.20243 -265.518138) (xy 131.15544 -265.365738) (xy 130.89382 -265.365738) (xy 130.84683 -265.518138)
			(xy 130.84683 -265.562588) (xy 131.20243 -265.562588)
		)
		(stroke
			(width 0)
			(type solid)
		)
		(fill yes)
		(layer "In11.Cu")
		(net "M_H_CPU1_SA_DQS_DN<3>")
	)
	(gr_poly
		(pts
			(xy 131.20243 -265.110214) (xy 131.20243 -265.065764) (xy 130.84683 -265.065764) (xy 130.84683 -265.110214)
			(xy 130.89382 -265.262614) (xy 131.15544 -265.262614)
		)
		(stroke
			(width 0)
			(type solid)
		)
		(fill yes)
		(layer "In11.Cu")
		(net "M_H_CPU1_SA_DQS_DN<8>")
	)
	(gr_poly
		(pts
			(xy 131.20243 -263.890506) (xy 131.15544 -263.738106) (xy 130.89382 -263.738106) (xy 130.84683 -263.890506)
			(xy 130.84683 -263.934956) (xy 131.20243 -263.934956)
		)
		(stroke
			(width 0)
			(type solid)
		)
		(fill yes)
		(layer "In11.Cu")
		(net "M_H_CPU1_SA_DQ<30>")
	)
	(gr_poly
		(pts
			(xy 131.20243 -263.482582) (xy 131.20243 -263.438132) (xy 130.84683 -263.438132) (xy 130.84683 -263.482582)
			(xy 130.89382 -263.634982) (xy 131.15544 -263.634982)
		)
		(stroke
			(width 0)
			(type solid)
		)
		(fill yes)
		(layer "In11.Cu")
		(net "M_H_CPU1_SA_DQ<29>")
	)
	(gr_poly
		(pts
			(xy 131.20243 -262.262874) (xy 131.15544 -262.110474) (xy 130.89382 -262.110474) (xy 130.84683 -262.262874)
			(xy 130.84683 -262.30707) (xy 131.20243 -262.30707)
		)
		(stroke
			(width 0)
			(type solid)
		)
		(fill yes)
		(layer "In11.Cu")
		(net "M_H_CPU1_SA_CB<2>")
	)
	(gr_poly
		(pts
			(xy 131.20243 -261.854442) (xy 131.20243 -261.810246) (xy 130.84683 -261.810246) (xy 130.84683 -261.854442)
			(xy 130.89382 -262.006842) (xy 131.15544 -262.006842)
		)
		(stroke
			(width 0)
			(type solid)
		)
		(fill yes)
		(layer "In11.Cu")
		(net "M_H_CPU1_SA_CB<1>")
	)
	(gr_poly
		(pts
			(xy 131.20243 -260.634734) (xy 131.15544 -260.482334) (xy 130.89382 -260.482334) (xy 130.84683 -260.634734)
			(xy 130.84683 -260.679184) (xy 131.20243 -260.679184)
		)
		(stroke
			(width 0)
			(type solid)
		)
		(fill yes)
		(layer "In11.Cu")
		(net "M_H_CPU1_SA_DQS_DN<4>")
	)
	(gr_poly
		(pts
			(xy 131.20243 -260.22681) (xy 131.20243 -260.18236) (xy 130.84683 -260.18236) (xy 130.84683 -260.22681)
			(xy 130.89382 -260.37921) (xy 131.15544 -260.37921)
		)
		(stroke
			(width 0)
			(type solid)
		)
		(fill yes)
		(layer "In11.Cu")
		(net "M_H_CPU1_SA_DQS_DN<9>")
	)
	(gr_poly
		(pts
			(xy 131.20243 -259.007102) (xy 131.15544 -258.854702) (xy 130.89382 -258.854702) (xy 130.84683 -259.007102)
			(xy 130.84683 -259.051552) (xy 131.20243 -259.051552)
		)
		(stroke
			(width 0)
			(type solid)
		)
		(fill yes)
		(layer "In11.Cu")
		(net "M_H_CPU1_SA_CB<6>")
	)
	(gr_poly
		(pts
			(xy 131.20243 -258.599178) (xy 131.20243 -258.554728) (xy 130.84683 -258.554728) (xy 130.84683 -258.599178)
			(xy 130.89382 -258.751578) (xy 131.15544 -258.751578)
		)
		(stroke
			(width 0)
			(type solid)
		)
		(fill yes)
		(layer "In11.Cu")
		(net "M_H_CPU1_SA_CB<5>")
	)
	(gr_poly
		(pts
			(xy 131.20243 -257.37947) (xy 131.15544 -257.22707) (xy 130.89382 -257.22707) (xy 130.84683 -257.37947)
			(xy 130.84683 -257.423666) (xy 131.20243 -257.423666)
		)
		(stroke
			(width 0)
			(type solid)
		)
		(fill yes)
		(layer "In11.Cu")
		(net "M_H_CPU1_ALERT_N")
	)
	(gr_poly
		(pts
			(xy 131.20243 -256.971038) (xy 131.20243 -256.926842) (xy 130.84683 -256.926842) (xy 130.84683 -256.971038)
			(xy 130.89382 -257.123438) (xy 131.15544 -257.123438)
		)
		(stroke
			(width 0)
			(type solid)
		)
		(fill yes)
		(layer "In11.Cu")
		(net "M_H_CPU1_SA_CS_N<0>")
	)
	(gr_poly
		(pts
			(xy 131.20243 -255.751838) (xy 131.15544 -255.599438) (xy 130.89382 -255.599438) (xy 130.84683 -255.751838)
			(xy 130.84683 -255.796034) (xy 131.20243 -255.796034)
		)
		(stroke
			(width 0)
			(type solid)
		)
		(fill yes)
		(layer "In11.Cu")
		(net "M_H_CPU1_SA_CS_N<3>")
	)
	(gr_poly
		(pts
			(xy 131.20243 -255.343406) (xy 131.20243 -255.29921) (xy 130.84683 -255.29921) (xy 130.84683 -255.343406)
			(xy 130.89382 -255.495806) (xy 131.15544 -255.495806)
		)
		(stroke
			(width 0)
			(type solid)
		)
		(fill yes)
		(layer "In11.Cu")
		(net "M_H_CPU1_SA_CA<1>")
	)
	(gr_poly
		(pts
			(xy 131.513326 -273.09191) (xy 131.55168 -273.069812) (xy 131.37388 -272.761964) (xy 131.335526 -272.784062)
			(xy 131.227068 -272.900902) (xy 131.357878 -273.12747)
		)
		(stroke
			(width 0)
			(type solid)
		)
		(fill yes)
		(layer "In11.Cu")
		(net "M_H_CPU1_SA_DQS_DN<7>")
	)
	(gr_poly
		(pts
			(xy 131.513326 -268.208506) (xy 131.55168 -268.186408) (xy 131.37388 -267.87856) (xy 131.335526 -267.900658)
			(xy 131.227068 -268.017498) (xy 131.357878 -268.244066)
		)
		(stroke
			(width 0)
			(type solid)
		)
		(fill yes)
		(layer "In11.Cu")
		(net "M_H_CPU1_SA_DQ<24>")
	)
	(gr_poly
		(pts
			(xy 131.515104 -271.467072) (xy 131.553458 -271.444974) (xy 131.375658 -271.137126) (xy 131.337304 -271.159224)
			(xy 131.228846 -271.276064) (xy 131.359656 -271.502632)
		)
		(stroke
			(width 0)
			(type solid)
		)
		(fill yes)
		(layer "In11.Cu")
		(net "M_H_CPU1_SA_DQ<20>")
	)
	(gr_poly
		(pts
			(xy 131.520438 -269.84833) (xy 131.558792 -269.826232) (xy 131.380992 -269.518384) (xy 131.342638 -269.540482)
			(xy 131.23418 -269.657322) (xy 131.36499 -269.88389)
		)
		(stroke
			(width 0)
			(type solid)
		)
		(fill yes)
		(layer "In11.Cu")
		(net "M_H_CPU1_SA_DQ<21>")
	)
	(gr_poly
		(pts
			(xy 131.54533 -246.16029) (xy 131.54533 -246.116094) (xy 131.18973 -246.116094) (xy 131.18973 -246.16029)
			(xy 131.23672 -246.31269) (xy 131.49834 -246.31269)
		)
		(stroke
			(width 0)
			(type solid)
		)
		(fill yes)
		(layer "In11.Cu")
		(net "M_H_CPU1_SB_CA<6>")
	)
	(gr_poly
		(pts
			(xy 131.54533 -243.31295) (xy 131.49834 -243.16055) (xy 131.23672 -243.16055) (xy 131.18973 -243.31295)
			(xy 131.18973 -243.3574) (xy 131.54533 -243.3574)
		)
		(stroke
			(width 0)
			(type solid)
		)
		(fill yes)
		(layer "In11.Cu")
		(net "M_H_CPU1_SB_CB<5>")
	)
	(gr_poly
		(pts
			(xy 131.54533 -242.905026) (xy 131.54533 -242.860576) (xy 131.18973 -242.860576) (xy 131.18973 -242.905026)
			(xy 131.23672 -243.057426) (xy 131.49834 -243.057426)
		)
		(stroke
			(width 0)
			(type solid)
		)
		(fill yes)
		(layer "In11.Cu")
		(net "M_H_CPU1_SB_DQS_DP<9>")
	)
	(gr_poly
		(pts
			(xy 131.54533 -241.276886) (xy 131.54533 -241.23269) (xy 131.18973 -241.23269) (xy 131.18973 -241.276886)
			(xy 131.23672 -241.429286) (xy 131.49834 -241.429286)
		)
		(stroke
			(width 0)
			(type solid)
		)
		(fill yes)
		(layer "In11.Cu")
		(net "M_H_CPU1_SB_CB<0>")
	)
	(gr_poly
		(pts
			(xy 131.54533 -238.429546) (xy 131.49834 -238.277146) (xy 131.23672 -238.277146) (xy 131.18973 -238.429546)
			(xy 131.18973 -238.473996) (xy 131.54533 -238.473996)
		)
		(stroke
			(width 0)
			(type solid)
		)
		(fill yes)
		(layer "In11.Cu")
		(net "M_H_CPU1_SB_DQ<3>")
	)
	(gr_poly
		(pts
			(xy 131.54533 -238.021622) (xy 131.54533 -237.977172) (xy 131.18973 -237.977172) (xy 131.18973 -238.021622)
			(xy 131.23672 -238.174022) (xy 131.49834 -238.174022)
		)
		(stroke
			(width 0)
			(type solid)
		)
		(fill yes)
		(layer "In11.Cu")
		(net "M_H_CPU1_SB_DQS_DP<0>")
	)
	(gr_poly
		(pts
			(xy 131.54533 -236.39399) (xy 131.54533 -236.34954) (xy 131.18973 -236.34954) (xy 131.18973 -236.39399)
			(xy 131.23672 -236.54639) (xy 131.49834 -236.54639)
		)
		(stroke
			(width 0)
			(type solid)
		)
		(fill yes)
		(layer "In11.Cu")
		(net "M_H_CPU1_SB_DQ<4>")
	)
	(gr_poly
		(pts
			(xy 131.54533 -233.138218) (xy 131.54533 -233.093768) (xy 131.18973 -233.093768) (xy 131.18973 -233.138218)
			(xy 131.23672 -233.290618) (xy 131.49834 -233.290618)
		)
		(stroke
			(width 0)
			(type solid)
		)
		(fill yes)
		(layer "In11.Cu")
		(net "M_H_CPU1_SB_DQS_DP<1>")
	)
	(gr_poly
		(pts
			(xy 131.54533 -231.510586) (xy 131.54533 -231.466136) (xy 131.18973 -231.466136) (xy 131.18973 -231.510586)
			(xy 131.23672 -231.662986) (xy 131.49834 -231.662986)
		)
		(stroke
			(width 0)
			(type solid)
		)
		(fill yes)
		(layer "In11.Cu")
		(net "M_H_CPU1_SB_DQ<12>")
	)
	(gr_poly
		(pts
			(xy 131.54533 -228.663246) (xy 131.49834 -228.510846) (xy 131.23672 -228.510846) (xy 131.18973 -228.663246)
			(xy 131.18973 -228.707442) (xy 131.54533 -228.707442)
		)
		(stroke
			(width 0)
			(type solid)
		)
		(fill yes)
		(layer "In11.Cu")
		(net "M_H_CPU1_SB_DQ<25>")
	)
	(gr_poly
		(pts
			(xy 131.54533 -228.254814) (xy 131.54533 -228.210618) (xy 131.18973 -228.210618) (xy 131.18973 -228.254814)
			(xy 131.23672 -228.407214) (xy 131.49834 -228.407214)
		)
		(stroke
			(width 0)
			(type solid)
		)
		(fill yes)
		(layer "In11.Cu")
		(net "M_H_CPU1_SB_DQS_DN<8>")
	)
	(gr_poly
		(pts
			(xy 131.54533 -225.407474) (xy 131.49834 -225.255074) (xy 131.23672 -225.255074) (xy 131.18973 -225.407474)
			(xy 131.18973 -225.45167) (xy 131.54533 -225.45167)
		)
		(stroke
			(width 0)
			(type solid)
		)
		(fill yes)
		(layer "In11.Cu")
		(net "M_H_CPU1_SB_DQ<29>")
	)
	(gr_poly
		(pts
			(xy 131.545584 -233.546142) (xy 131.498594 -233.393742) (xy 131.236974 -233.393742) (xy 131.189984 -233.546142)
			(xy 131.189984 -233.590592) (xy 131.545584 -233.590592)
		)
		(stroke
			(width 0)
			(type solid)
		)
		(fill yes)
		(layer "In11.Cu")
		(net "M_H_CPU1_SB_DQ<11>")
	)
	(gr_poly
		(pts
			(xy 131.54787 -248.196354) (xy 131.50088 -248.043954) (xy 131.23926 -248.043954) (xy 131.19227 -248.196354)
			(xy 131.19227 -248.240804) (xy 131.54787 -248.240804)
		)
		(stroke
			(width 0)
			(type solid)
		)
		(fill yes)
		(layer "In11.Cu")
		(net "M_H_CPU1_SB_CA<1>")
	)
	(gr_poly
		(pts
			(xy 131.54787 -244.532658) (xy 131.54787 -244.488208) (xy 131.19227 -244.488208) (xy 131.19227 -244.532658)
			(xy 131.23926 -244.685058) (xy 131.50088 -244.685058)
		)
		(stroke
			(width 0)
			(type solid)
		)
		(fill yes)
		(layer "In11.Cu")
		(net "M_H_CPU1_SB_CB<6>")
	)
	(gr_poly
		(pts
			(xy 131.54787 -240.057178) (xy 131.50088 -239.904778) (xy 131.23926 -239.904778) (xy 131.19227 -240.057178)
			(xy 131.19227 -240.101628) (xy 131.54787 -240.101628)
		)
		(stroke
			(width 0)
			(type solid)
		)
		(fill yes)
		(layer "In11.Cu")
		(net "M_H_CPU1_SB_CB<3>")
	)
	(gr_poly
		(pts
			(xy 131.54787 -239.649254) (xy 131.54787 -239.604804) (xy 131.19227 -239.604804) (xy 131.19227 -239.649254)
			(xy 131.23926 -239.801654) (xy 131.50088 -239.801654)
		)
		(stroke
			(width 0)
			(type solid)
		)
		(fill yes)
		(layer "In11.Cu")
		(net "M_H_CPU1_SB_DQ<0>")
	)
	(gr_poly
		(pts
			(xy 131.54787 -235.174282) (xy 131.50088 -235.021882) (xy 131.23926 -235.021882) (xy 131.19227 -235.174282)
			(xy 131.19227 -235.218478) (xy 131.54787 -235.218478)
		)
		(stroke
			(width 0)
			(type solid)
		)
		(fill yes)
		(layer "In11.Cu")
		(net "M_H_CPU1_SB_DQ<7>")
	)
	(gr_poly
		(pts
			(xy 131.54787 -234.76585) (xy 131.54787 -234.721654) (xy 131.19227 -234.721654) (xy 131.19227 -234.76585)
			(xy 131.23926 -234.91825) (xy 131.50088 -234.91825)
		)
		(stroke
			(width 0)
			(type solid)
		)
		(fill yes)
		(layer "In11.Cu")
		(net "M_H_CPU1_SB_DQ<8>")
	)
	(gr_poly
		(pts
			(xy 131.54787 -230.290878) (xy 131.50088 -230.138478) (xy 131.23926 -230.138478) (xy 131.19227 -230.290878)
			(xy 131.19227 -230.335074) (xy 131.54787 -230.335074)
		)
		(stroke
			(width 0)
			(type solid)
		)
		(fill yes)
		(layer "In11.Cu")
		(net "M_H_CPU1_SB_DQ<15>")
	)
	(gr_poly
		(pts
			(xy 131.54787 -229.882446) (xy 131.54787 -229.83825) (xy 131.19227 -229.83825) (xy 131.19227 -229.882446)
			(xy 131.23926 -230.034846) (xy 131.50088 -230.034846)
		)
		(stroke
			(width 0)
			(type solid)
		)
		(fill yes)
		(layer "In11.Cu")
		(net "M_H_CPU1_SB_DQ<26>")
	)
	(gr_poly
		(pts
			(xy 131.54787 -227.035614) (xy 131.50088 -226.883214) (xy 131.23926 -226.883214) (xy 131.19227 -227.035614)
			(xy 131.19227 -227.07981) (xy 131.54787 -227.07981)
		)
		(stroke
			(width 0)
			(type solid)
		)
		(fill yes)
		(layer "In11.Cu")
		(net "M_H_CPU1_SB_DQS_DN<3>")
	)
	(gr_poly
		(pts
			(xy 131.54787 -226.626674) (xy 131.54787 -226.582478) (xy 131.19227 -226.582478) (xy 131.19227 -226.626674)
			(xy 131.23926 -226.779074) (xy 131.50088 -226.779074)
		)
		(stroke
			(width 0)
			(type solid)
		)
		(fill yes)
		(layer "In11.Cu")
		(net "M_H_CPU1_SB_DQ<30>")
	)
	(gr_poly
		(pts
			(xy 131.553712 -246.568722) (xy 131.506722 -246.416322) (xy 131.245102 -246.416322) (xy 131.198112 -246.568722)
			(xy 131.198112 -246.613172) (xy 131.553712 -246.613172)
		)
		(stroke
			(width 0)
			(type solid)
		)
		(fill yes)
		(layer "In11.Cu")
		(net "M_H_CPU1_SB_CA<5>")
	)
	(gr_poly
		(pts
			(xy 131.55422 -241.685826) (xy 131.50723 -241.533426) (xy 131.24561 -241.533426) (xy 131.19862 -241.685826)
			(xy 131.19862 -241.730022) (xy 131.55422 -241.730022)
		)
		(stroke
			(width 0)
			(type solid)
		)
		(fill yes)
		(layer "In11.Cu")
		(net "M_H_CPU1_SB_DQS_DP<4>")
	)
	(gr_poly
		(pts
			(xy 131.55422 -236.802422) (xy 131.50723 -236.650022) (xy 131.24561 -236.650022) (xy 131.19862 -236.802422)
			(xy 131.19862 -236.846872) (xy 131.55422 -236.846872)
		)
		(stroke
			(width 0)
			(type solid)
		)
		(fill yes)
		(layer "In11.Cu")
		(net "M_H_CPU1_SB_DQS_DP<5>")
	)
	(gr_poly
		(pts
			(xy 131.55422 -231.919018) (xy 131.50723 -231.766618) (xy 131.24561 -231.766618) (xy 131.19862 -231.919018)
			(xy 131.19862 -231.963468) (xy 131.55422 -231.963468)
		)
		(stroke
			(width 0)
			(type solid)
		)
		(fill yes)
		(layer "In11.Cu")
		(net "M_H_CPU1_SB_DQS_DP<6>")
	)
	(gr_poly
		(pts
			(xy 131.559808 -247.787922) (xy 131.559808 -247.743472) (xy 131.204208 -247.743472) (xy 131.204208 -247.787922)
			(xy 131.251198 -247.940322) (xy 131.512818 -247.940322)
		)
		(stroke
			(width 0)
			(type solid)
		)
		(fill yes)
		(layer "In11.Cu")
		(net "M_H_CPU1_SB_CA<2>")
	)
	(gr_poly
		(pts
			(xy 131.62915 -270.853916) (xy 131.737608 -270.737076) (xy 131.606798 -270.510508) (xy 131.45135 -270.546068)
			(xy 131.412996 -270.568166) (xy 131.590796 -270.876014)
		)
		(stroke
			(width 0)
			(type solid)
		)
		(fill yes)
		(layer "In11.Cu")
		(net "M_H_CPU1_SA_DQ<22>")
	)
	(gr_poly
		(pts
			(xy 131.62915 -269.22603) (xy 131.737608 -269.10919) (xy 131.606798 -268.882622) (xy 131.45135 -268.918182)
			(xy 131.412996 -268.94028) (xy 131.590796 -269.248128)
		)
		(stroke
			(width 0)
			(type solid)
		)
		(fill yes)
		(layer "In11.Cu")
		(net "M_H_CPU1_SA_DQ<23>")
	)
	(gr_poly
		(pts
			(xy 131.629404 -272.48231) (xy 131.737862 -272.36547) (xy 131.607052 -272.138902) (xy 131.451604 -272.174462)
			(xy 131.41325 -272.19656) (xy 131.59105 -272.504408)
		)
		(stroke
			(width 0)
			(type solid)
		)
		(fill yes)
		(layer "In11.Cu")
		(net "M_H_CPU1_SA_DQS_DP<7>")
	)
	(gr_poly
		(pts
			(xy 131.629404 -267.598906) (xy 131.737862 -267.482066) (xy 131.607052 -267.255498) (xy 131.451604 -267.291058)
			(xy 131.41325 -267.313156) (xy 131.59105 -267.621004)
		)
		(stroke
			(width 0)
			(type solid)
		)
		(fill yes)
		(layer "In11.Cu")
		(net "M_H_CPU1_SA_DQ<26>")
	)
	(gr_poly
		(pts
			(xy 131.655312 -280.98242) (xy 131.608322 -280.83002) (xy 131.346702 -280.83002) (xy 131.299712 -280.98242)
			(xy 131.299712 -281.026616) (xy 131.655312 -281.026616)
		)
		(stroke
			(width 0)
			(type solid)
		)
		(fill yes)
		(layer "In11.Cu")
		(net "M_H_CPU1_SA_DQ<10>")
	)
	(gr_poly
		(pts
			(xy 131.655312 -280.574242) (xy 131.655312 -280.529792) (xy 131.299712 -280.529792) (xy 131.299712 -280.574242)
			(xy 131.346702 -280.726642) (xy 131.608322 -280.726642)
		)
		(stroke
			(width 0)
			(type solid)
		)
		(fill yes)
		(layer "In11.Cu")
		(net "M_H_CPU1_SA_DQ<9>")
	)
	(gr_poly
		(pts
			(xy 131.655312 -275.690584) (xy 131.655312 -275.646388) (xy 131.299712 -275.646388) (xy 131.299712 -275.690584)
			(xy 131.346702 -275.842984) (xy 131.608322 -275.842984)
		)
		(stroke
			(width 0)
			(type solid)
		)
		(fill yes)
		(layer "In11.Cu")
		(net "M_H_CPU1_SA_DQ<16>")
	)
	(gr_poly
		(pts
			(xy 131.655312 -274.47113) (xy 131.608322 -274.31873) (xy 131.346702 -274.31873) (xy 131.299712 -274.47113)
			(xy 131.299712 -274.515326) (xy 131.655312 -274.515326)
		)
		(stroke
			(width 0)
			(type solid)
		)
		(fill yes)
		(layer "In11.Cu")
		(net "M_H_CPU1_SA_DQ<19>")
	)
	(gr_poly
		(pts
			(xy 131.655312 -274.062698) (xy 131.655312 -274.018502) (xy 131.299712 -274.018502) (xy 131.299712 -274.062698)
			(xy 131.346702 -274.215098) (xy 131.608322 -274.215098)
		)
		(stroke
			(width 0)
			(type solid)
		)
		(fill yes)
		(layer "In11.Cu")
		(net "M_H_CPU1_SA_DQS_DP<2>")
	)
	(gr_poly
		(pts
			(xy 131.655312 -266.331954) (xy 131.608322 -266.179554) (xy 131.346702 -266.179554) (xy 131.299712 -266.331954)
			(xy 131.299712 -266.376404) (xy 131.655312 -266.376404)
		)
		(stroke
			(width 0)
			(type solid)
		)
		(fill yes)
		(layer "In11.Cu")
		(net "M_H_CPU1_SA_DQ<27>")
	)
	(gr_poly
		(pts
			(xy 131.655312 -265.92403) (xy 131.655312 -265.879834) (xy 131.299712 -265.879834) (xy 131.299712 -265.92403)
			(xy 131.346702 -266.07643) (xy 131.608322 -266.07643)
		)
		(stroke
			(width 0)
			(type solid)
		)
		(fill yes)
		(layer "In11.Cu")
		(net "M_H_CPU1_SA_DQS_DP<3>")
	)
	(gr_poly
		(pts
			(xy 131.655312 -264.704322) (xy 131.608322 -264.551922) (xy 131.346702 -264.551922) (xy 131.299712 -264.704322)
			(xy 131.299712 -264.748772) (xy 131.655312 -264.748772)
		)
		(stroke
			(width 0)
			(type solid)
		)
		(fill yes)
		(layer "In11.Cu")
		(net "M_H_CPU1_SA_DQS_DP<8>")
	)
	(gr_poly
		(pts
			(xy 131.655312 -264.296398) (xy 131.655312 -264.251948) (xy 131.299712 -264.251948) (xy 131.299712 -264.296398)
			(xy 131.346702 -264.448798) (xy 131.608322 -264.448798)
		)
		(stroke
			(width 0)
			(type solid)
		)
		(fill yes)
		(layer "In11.Cu")
		(net "M_H_CPU1_SA_DQ<28>")
	)
	(gr_poly
		(pts
			(xy 131.655312 -261.449058) (xy 131.608322 -261.296658) (xy 131.346702 -261.296658) (xy 131.299712 -261.449058)
			(xy 131.299712 -261.493254) (xy 131.655312 -261.493254)
		)
		(stroke
			(width 0)
			(type solid)
		)
		(fill yes)
		(layer "In11.Cu")
		(net "M_H_CPU1_SA_CB<3>")
	)
	(gr_poly
		(pts
			(xy 131.655312 -261.040626) (xy 131.655312 -260.99643) (xy 131.299712 -260.99643) (xy 131.299712 -261.040626)
			(xy 131.346702 -261.193026) (xy 131.608322 -261.193026)
		)
		(stroke
			(width 0)
			(type solid)
		)
		(fill yes)
		(layer "In11.Cu")
		(net "M_H_CPU1_SA_DQS_DP<4>")
	)
	(gr_poly
		(pts
			(xy 131.655312 -259.820918) (xy 131.608322 -259.668518) (xy 131.346702 -259.668518) (xy 131.299712 -259.820918)
			(xy 131.299712 -259.865368) (xy 131.655312 -259.865368)
		)
		(stroke
			(width 0)
			(type solid)
		)
		(fill yes)
		(layer "In11.Cu")
		(net "M_H_CPU1_SA_DQS_DP<9>")
	)
	(gr_poly
		(pts
			(xy 131.655312 -259.412994) (xy 131.655312 -259.368544) (xy 131.299712 -259.368544) (xy 131.299712 -259.412994)
			(xy 131.346702 -259.565394) (xy 131.608322 -259.565394)
		)
		(stroke
			(width 0)
			(type solid)
		)
		(fill yes)
		(layer "In11.Cu")
		(net "M_H_CPU1_SA_CB<4>")
	)
	(gr_poly
		(pts
			(xy 131.655312 -256.565654) (xy 131.608322 -256.413254) (xy 131.346702 -256.413254) (xy 131.299712 -256.565654)
			(xy 131.299712 -256.60985) (xy 131.655312 -256.60985)
		)
		(stroke
			(width 0)
			(type solid)
		)
		(fill yes)
		(layer "In11.Cu")
		(net "M_H_CPU1_SA_CS_N<1>")
	)
	(gr_poly
		(pts
			(xy 131.655312 -256.157222) (xy 131.655312 -256.113026) (xy 131.299712 -256.113026) (xy 131.299712 -256.157222)
			(xy 131.346702 -256.309622) (xy 131.608322 -256.309622)
		)
		(stroke
			(width 0)
			(type solid)
		)
		(fill yes)
		(layer "In11.Cu")
		(net "M_H_CPU1_SA_CS_N<2>")
	)
	(gr_poly
		(pts
			(xy 131.655312 -254.937514) (xy 131.608322 -254.785114) (xy 131.346702 -254.785114) (xy 131.299712 -254.937514)
			(xy 131.299712 -254.981964) (xy 131.655312 -254.981964)
		)
		(stroke
			(width 0)
			(type solid)
		)
		(fill yes)
		(layer "In11.Cu")
		(net "M_H_CPU1_SA_CA<0>")
	)
	(gr_poly
		(pts
			(xy 131.657852 -279.354534) (xy 131.610862 -279.202134) (xy 131.349242 -279.202134) (xy 131.302252 -279.354534)
			(xy 131.302252 -279.39873) (xy 131.657852 -279.39873)
		)
		(stroke
			(width 0)
			(type solid)
		)
		(fill yes)
		(layer "In11.Cu")
		(net "M_H_CPU1_SA_DQS_DN<1>")
	)
	(gr_poly
		(pts
			(xy 131.657852 -278.946102) (xy 131.657852 -278.901906) (xy 131.302252 -278.901906) (xy 131.302252 -278.946102)
			(xy 131.349242 -279.098502) (xy 131.610862 -279.098502)
		)
		(stroke
			(width 0)
			(type solid)
		)
		(fill yes)
		(layer "In11.Cu")
		(net "M_H_CPU1_SA_DQS_DN<6>")
	)
	(gr_poly
		(pts
			(xy 131.657852 -277.726902) (xy 131.610862 -277.574502) (xy 131.349242 -277.574502) (xy 131.302252 -277.726902)
			(xy 131.302252 -277.771098) (xy 131.657852 -277.771098)
		)
		(stroke
			(width 0)
			(type solid)
		)
		(fill yes)
		(layer "In11.Cu")
		(net "M_H_CPU1_SA_DQ<14>")
	)
	(gr_poly
		(pts
			(xy 131.657852 -277.317962) (xy 131.657852 -277.273766) (xy 131.302252 -277.273766) (xy 131.302252 -277.317962)
			(xy 131.349242 -277.470362) (xy 131.610862 -277.470362)
		)
		(stroke
			(width 0)
			(type solid)
		)
		(fill yes)
		(layer "In11.Cu")
		(net "M_H_CPU1_SA_DQ<13>")
	)
	(gr_poly
		(pts
			(xy 131.657852 -263.07669) (xy 131.610862 -262.92429) (xy 131.349242 -262.92429) (xy 131.302252 -263.07669)
			(xy 131.302252 -263.120886) (xy 131.657852 -263.120886)
		)
		(stroke
			(width 0)
			(type solid)
		)
		(fill yes)
		(layer "In11.Cu")
		(net "M_H_CPU1_SA_DQ<31>")
	)
	(gr_poly
		(pts
			(xy 131.657852 -262.668258) (xy 131.657852 -262.624062) (xy 131.302252 -262.624062) (xy 131.302252 -262.668258)
			(xy 131.349242 -262.820658) (xy 131.610862 -262.820658)
		)
		(stroke
			(width 0)
			(type solid)
		)
		(fill yes)
		(layer "In11.Cu")
		(net "M_H_CPU1_SA_CB<0>")
	)
	(gr_poly
		(pts
			(xy 131.657852 -258.193286) (xy 131.610862 -258.040886) (xy 131.349242 -258.040886) (xy 131.302252 -258.193286)
			(xy 131.302252 -258.237482) (xy 131.657852 -258.237482)
		)
		(stroke
			(width 0)
			(type solid)
		)
		(fill yes)
		(layer "In11.Cu")
		(net "M_H_CPU1_SA_CB<7>")
	)
	(gr_poly
		(pts
			(xy 131.657852 -257.784854) (xy 131.657852 -257.740658) (xy 131.302252 -257.740658) (xy 131.302252 -257.784854)
			(xy 131.349242 -257.937254) (xy 131.610862 -257.937254)
		)
		(stroke
			(width 0)
			(type solid)
		)
		(fill yes)
		(layer "In11.Cu")
		(net "M_E_CPU1_ALERT_N")
	)
	(gr_poly
		(pts
			(xy 131.66979 -254.52959) (xy 131.66979 -254.48514) (xy 131.31419 -254.48514) (xy 131.31419 -254.52959)
			(xy 131.36118 -254.68199) (xy 131.6228 -254.68199)
		)
		(stroke
			(width 0)
			(type solid)
		)
		(fill yes)
		(layer "In11.Cu")
		(net "M_H_CPU1_SA_CA<2>")
	)
	(gr_poly
		(pts
			(xy 131.990338 -272.290032) (xy 132.028692 -272.267934) (xy 131.850892 -271.960086) (xy 131.812538 -271.982184)
			(xy 131.70408 -272.099024) (xy 131.83489 -272.325592)
		)
		(stroke
			(width 0)
			(type solid)
		)
		(fill yes)
		(layer "In11.Cu")
		(net "M_H_CPU1_SA_DQ<20>")
	)
	(gr_poly
		(pts
			(xy 131.990338 -267.406628) (xy 132.028692 -267.38453) (xy 131.850892 -267.076682) (xy 131.812538 -267.09878)
			(xy 131.70408 -267.21562) (xy 131.83489 -267.442188)
		)
		(stroke
			(width 0)
			(type solid)
		)
		(fill yes)
		(layer "In11.Cu")
		(net "M_H_CPU1_SA_DQ<25>")
	)
	(gr_poly
		(pts
			(xy 131.990592 -269.035022) (xy 132.028946 -269.012924) (xy 131.851146 -268.705076) (xy 131.812792 -268.727174)
			(xy 131.704334 -268.844014) (xy 131.835144 -269.070582)
		)
		(stroke
			(width 0)
			(type solid)
		)
		(fill yes)
		(layer "In11.Cu")
		(net "M_H_CPU1_SA_DQ<24>")
	)
	(gr_poly
		(pts
			(xy 132.01777 -240.46307) (xy 132.01777 -240.41862) (xy 131.66217 -240.41862) (xy 131.66217 -240.46307)
			(xy 131.70916 -240.61547) (xy 131.97078 -240.61547)
		)
		(stroke
			(width 0)
			(type solid)
		)
		(fill yes)
		(layer "In11.Cu")
		(net "M_H_CPU1_SB_CB<1>")
	)
	(gr_poly
		(pts
			(xy 132.01777 -235.579666) (xy 132.01777 -235.535216) (xy 131.66217 -235.535216) (xy 131.66217 -235.579666)
			(xy 131.70916 -235.732066) (xy 131.97078 -235.732066)
		)
		(stroke
			(width 0)
			(type solid)
		)
		(fill yes)
		(layer "In11.Cu")
		(net "M_H_CPU1_SB_DQ<5>")
	)
	(gr_poly
		(pts
			(xy 132.01777 -230.696262) (xy 132.01777 -230.651812) (xy 131.66217 -230.651812) (xy 131.66217 -230.696262)
			(xy 131.70916 -230.848662) (xy 131.97078 -230.848662)
		)
		(stroke
			(width 0)
			(type solid)
		)
		(fill yes)
		(layer "In11.Cu")
		(net "M_H_CPU1_SB_DQ<13>")
	)
	(gr_poly
		(pts
			(xy 132.023866 -244.127274) (xy 131.976876 -243.974874) (xy 131.715256 -243.974874) (xy 131.668266 -244.127274)
			(xy 131.668266 -244.17147) (xy 132.023866 -244.17147)
		)
		(stroke
			(width 0)
			(type solid)
		)
		(fill yes)
		(layer "In11.Cu")
		(net "M_H_CPU1_SB_CB<4>")
	)
	(gr_poly
		(pts
			(xy 132.023866 -239.24387) (xy 131.976876 -239.09147) (xy 131.715256 -239.09147) (xy 131.668266 -239.24387)
			(xy 131.668266 -239.288066) (xy 132.023866 -239.288066)
		)
		(stroke
			(width 0)
			(type solid)
		)
		(fill yes)
		(layer "In11.Cu")
		(net "M_H_CPU1_SB_DQ<2>")
	)
	(gr_poly
		(pts
			(xy 132.023866 -234.360466) (xy 131.976876 -234.208066) (xy 131.715256 -234.208066) (xy 131.668266 -234.360466)
			(xy 131.668266 -234.404916) (xy 132.023866 -234.404916)
		)
		(stroke
			(width 0)
			(type solid)
		)
		(fill yes)
		(layer "In11.Cu")
		(net "M_H_CPU1_SB_DQ<10>")
	)
	(gr_poly
		(pts
			(xy 132.023866 -229.477062) (xy 131.976876 -229.324662) (xy 131.715256 -229.324662) (xy 131.668266 -229.477062)
			(xy 131.668266 -229.521512) (xy 132.023866 -229.521512)
		)
		(stroke
			(width 0)
			(type solid)
		)
		(fill yes)
		(layer "In11.Cu")
		(net "M_H_CPU1_SB_DQ<24>")
	)
	(gr_poly
		(pts
			(xy 132.029708 -247.382538) (xy 131.982718 -247.230138) (xy 131.721098 -247.230138) (xy 131.674108 -247.382538)
			(xy 131.674108 -247.426734) (xy 132.029708 -247.426734)
		)
		(stroke
			(width 0)
			(type solid)
		)
		(fill yes)
		(layer "In11.Cu")
		(net "M_H_CPU1_SB_CA<3>")
	)
	(gr_poly
		(pts
			(xy 132.029708 -246.974106) (xy 132.029708 -246.92991) (xy 131.674108 -246.92991) (xy 131.674108 -246.974106)
			(xy 131.721098 -247.126506) (xy 131.982718 -247.126506)
		)
		(stroke
			(width 0)
			(type solid)
		)
		(fill yes)
		(layer "In11.Cu")
		(net "M_H_CPU1_SB_CA<4>")
	)
	(gr_poly
		(pts
			(xy 132.029708 -245.754906) (xy 131.982718 -245.602506) (xy 131.721098 -245.602506) (xy 131.674108 -245.754906)
			(xy 131.674108 -245.799356) (xy 132.029708 -245.799356)
		)
		(stroke
			(width 0)
			(type solid)
		)
		(fill yes)
		(layer "In11.Cu")
		(net "M_H_CPU1_SB_PAR")
	)
	(gr_poly
		(pts
			(xy 132.029708 -240.871502) (xy 131.982718 -240.719102) (xy 131.721098 -240.719102) (xy 131.674108 -240.871502)
			(xy 131.674108 -240.915952) (xy 132.029708 -240.915952)
		)
		(stroke
			(width 0)
			(type solid)
		)
		(fill yes)
		(layer "In11.Cu")
		(net "M_H_CPU1_SB_CB<2>")
	)
	(gr_poly
		(pts
			(xy 132.029708 -235.988098) (xy 131.982718 -235.835698) (xy 131.721098 -235.835698) (xy 131.674108 -235.988098)
			(xy 131.674108 -236.032548) (xy 132.029708 -236.032548)
		)
		(stroke
			(width 0)
			(type solid)
		)
		(fill yes)
		(layer "In11.Cu")
		(net "M_H_CPU1_SB_DQ<6>")
	)
	(gr_poly
		(pts
			(xy 132.029708 -231.104694) (xy 131.982718 -230.952294) (xy 131.721098 -230.952294) (xy 131.674108 -231.104694)
			(xy 131.674108 -231.149144) (xy 132.029708 -231.149144)
		)
		(stroke
			(width 0)
			(type solid)
		)
		(fill yes)
		(layer "In11.Cu")
		(net "M_H_CPU1_SB_DQ<14>")
	)
	(gr_poly
		(pts
			(xy 132.032248 -248.602246) (xy 132.032248 -248.557796) (xy 131.676648 -248.557796) (xy 131.676648 -248.602246)
			(xy 131.723638 -248.754646) (xy 131.985258 -248.754646)
		)
		(stroke
			(width 0)
			(type solid)
		)
		(fill yes)
		(layer "In11.Cu")
		(net "M_H_CPU1_SB_CA<0>")
	)
	(gr_poly
		(pts
			(xy 132.032248 -243.718842) (xy 132.032248 -243.674392) (xy 131.676648 -243.674392) (xy 131.676648 -243.718842)
			(xy 131.723638 -243.871242) (xy 131.985258 -243.871242)
		)
		(stroke
			(width 0)
			(type solid)
		)
		(fill yes)
		(layer "In11.Cu")
		(net "M_H_CPU1_SB_CB<7>")
	)
	(gr_poly
		(pts
			(xy 132.032248 -242.499134) (xy 131.985258 -242.346734) (xy 131.723638 -242.346734) (xy 131.676648 -242.499134)
			(xy 131.676648 -242.54333) (xy 132.032248 -242.54333)
		)
		(stroke
			(width 0)
			(type solid)
		)
		(fill yes)
		(layer "In11.Cu")
		(net "M_H_CPU1_SB_DQS_DN<9>")
	)
	(gr_poly
		(pts
			(xy 132.032248 -242.090702) (xy 132.032248 -242.046506) (xy 131.676648 -242.046506) (xy 131.676648 -242.090702)
			(xy 131.723638 -242.243102) (xy 131.985258 -242.243102)
		)
		(stroke
			(width 0)
			(type solid)
		)
		(fill yes)
		(layer "In11.Cu")
		(net "M_H_CPU1_SB_DQS_DN<4>")
	)
	(gr_poly
		(pts
			(xy 132.032248 -238.835438) (xy 132.032248 -238.790988) (xy 131.676648 -238.790988) (xy 131.676648 -238.835438)
			(xy 131.723638 -238.987838) (xy 131.985258 -238.987838)
		)
		(stroke
			(width 0)
			(type solid)
		)
		(fill yes)
		(layer "In11.Cu")
		(net "M_H_CPU1_SB_DQ<1>")
	)
	(gr_poly
		(pts
			(xy 132.032248 -237.61573) (xy 131.985258 -237.46333) (xy 131.723638 -237.46333) (xy 131.676648 -237.61573)
			(xy 131.676648 -237.66018) (xy 132.032248 -237.66018)
		)
		(stroke
			(width 0)
			(type solid)
		)
		(fill yes)
		(layer "In11.Cu")
		(net "M_H_CPU1_SB_DQS_DN<0>")
	)
	(gr_poly
		(pts
			(xy 132.032248 -237.207806) (xy 132.032248 -237.163356) (xy 131.676648 -237.163356) (xy 131.676648 -237.207806)
			(xy 131.723638 -237.360206) (xy 131.985258 -237.360206)
		)
		(stroke
			(width 0)
			(type solid)
		)
		(fill yes)
		(layer "In11.Cu")
		(net "M_H_CPU1_SB_DQS_DN<5>")
	)
	(gr_poly
		(pts
			(xy 132.032248 -233.952034) (xy 132.032248 -233.907838) (xy 131.676648 -233.907838) (xy 131.676648 -233.952034)
			(xy 131.723638 -234.104434) (xy 131.985258 -234.104434)
		)
		(stroke
			(width 0)
			(type solid)
		)
		(fill yes)
		(layer "In11.Cu")
		(net "M_H_CPU1_SB_DQ<9>")
	)
	(gr_poly
		(pts
			(xy 132.032248 -232.732326) (xy 131.985258 -232.579926) (xy 131.723638 -232.579926) (xy 131.676648 -232.732326)
			(xy 131.676648 -232.776776) (xy 132.032248 -232.776776)
		)
		(stroke
			(width 0)
			(type solid)
		)
		(fill yes)
		(layer "In11.Cu")
		(net "M_H_CPU1_SB_DQS_DN<1>")
	)
	(gr_poly
		(pts
			(xy 132.032248 -232.324402) (xy 132.032248 -232.279952) (xy 131.676648 -232.279952) (xy 131.676648 -232.324402)
			(xy 131.723638 -232.476802) (xy 131.985258 -232.476802)
		)
		(stroke
			(width 0)
			(type solid)
		)
		(fill yes)
		(layer "In11.Cu")
		(net "M_H_CPU1_SB_DQS_DN<6>")
	)
	(gr_poly
		(pts
			(xy 132.032248 -229.06863) (xy 132.032248 -229.024434) (xy 131.676648 -229.024434) (xy 131.676648 -229.06863)
			(xy 131.723638 -229.22103) (xy 131.985258 -229.22103)
		)
		(stroke
			(width 0)
			(type solid)
		)
		(fill yes)
		(layer "In11.Cu")
		(net "M_H_CPU1_SB_DQ<27>")
	)
	(gr_poly
		(pts
			(xy 132.032248 -227.848922) (xy 131.985258 -227.696522) (xy 131.723638 -227.696522) (xy 131.676648 -227.848922)
			(xy 131.676648 -227.893372) (xy 132.032248 -227.893372)
		)
		(stroke
			(width 0)
			(type solid)
		)
		(fill yes)
		(layer "In11.Cu")
		(net "M_H_CPU1_SB_DQS_DP<8>")
	)
	(gr_poly
		(pts
			(xy 132.032248 -227.440998) (xy 132.032248 -227.396548) (xy 131.676648 -227.396548) (xy 131.676648 -227.440998)
			(xy 131.723638 -227.593398) (xy 131.985258 -227.593398)
		)
		(stroke
			(width 0)
			(type solid)
		)
		(fill yes)
		(layer "In11.Cu")
		(net "M_H_CPU1_SB_DQS_DP<3>")
	)
	(gr_poly
		(pts
			(xy 132.032248 -226.22129) (xy 131.985258 -226.06889) (xy 131.723638 -226.06889) (xy 131.676648 -226.22129)
			(xy 131.676648 -226.26574) (xy 132.032248 -226.26574)
		)
		(stroke
			(width 0)
			(type solid)
		)
		(fill yes)
		(layer "In11.Cu")
		(net "M_H_CPU1_SB_DQ<28>")
	)
	(gr_poly
		(pts
			(xy 132.032248 -225.813366) (xy 132.032248 -225.768916) (xy 131.676648 -225.768916) (xy 131.676648 -225.813366)
			(xy 131.723638 -225.965766) (xy 131.985258 -225.965766)
		)
		(stroke
			(width 0)
			(type solid)
		)
		(fill yes)
		(layer "In11.Cu")
		(net "M_H_CPU1_SB_DQ<31>")
	)
	(gr_poly
		(pts
			(xy 132.10032 -268.414754) (xy 132.208778 -268.297914) (xy 132.077968 -268.071346) (xy 131.92252 -268.106906)
			(xy 131.884166 -268.129004) (xy 132.061966 -268.436852)
		)
		(stroke
			(width 0)
			(type solid)
		)
		(fill yes)
		(layer "In11.Cu")
		(net "M_H_CPU1_SA_DQ<26>")
	)
	(gr_poly
		(pts
			(xy 132.104638 -271.677384) (xy 132.213096 -271.560544) (xy 132.082286 -271.333976) (xy 131.926838 -271.369536)
			(xy 131.888484 -271.391634) (xy 132.066284 -271.699482)
		)
		(stroke
			(width 0)
			(type solid)
		)
		(fill yes)
		(layer "In11.Cu")
		(net "M_H_CPU1_SA_DQ<22>")
	)
	(gr_poly
		(pts
			(xy 132.104638 -266.79398) (xy 132.213096 -266.67714) (xy 132.082286 -266.450572) (xy 131.926838 -266.486132)
			(xy 131.888484 -266.50823) (xy 132.066284 -266.816078)
		)
		(stroke
			(width 0)
			(type solid)
		)
		(fill yes)
		(layer "In11.Cu")
		(net "M_H_CPU1_SA_DQ<27>")
	)
	(gr_poly
		(pts
			(xy 132.125466 -255.343406) (xy 132.125466 -255.29921) (xy 131.769866 -255.29921) (xy 131.769866 -255.343406)
			(xy 131.816856 -255.495806) (xy 132.078476 -255.495806)
		)
		(stroke
			(width 0)
			(type solid)
		)
		(fill yes)
		(layer "In11.Cu")
		(net "M_H_CPU1_SA_CA<1>")
	)
	(gr_poly
		(pts
			(xy 132.125466 -254.123698) (xy 132.078476 -253.971298) (xy 131.816856 -253.971298) (xy 131.769866 -254.123698)
			(xy 131.769866 -254.168148) (xy 132.125466 -254.168148)
		)
		(stroke
			(width 0)
			(type solid)
		)
		(fill yes)
		(layer "In11.Cu")
		(net "M_H_CPU1_SA_CA<3>")
	)
	(gr_poly
		(pts
			(xy 132.127752 -279.759664) (xy 132.127752 -279.715468) (xy 131.772152 -279.715468) (xy 131.772152 -279.759664)
			(xy 131.819142 -279.912064) (xy 132.080762 -279.912064)
		)
		(stroke
			(width 0)
			(type solid)
		)
		(fill yes)
		(layer "In11.Cu")
		(net "M_H_CPU1_SA_DQS_DP<1>")
	)
	(gr_poly
		(pts
			(xy 132.127752 -262.262874) (xy 132.080762 -262.110474) (xy 131.819142 -262.110474) (xy 131.772152 -262.262874)
			(xy 131.772152 -262.307324) (xy 132.127752 -262.307324)
		)
		(stroke
			(width 0)
			(type solid)
		)
		(fill yes)
		(layer "In11.Cu")
		(net "M_H_CPU1_SA_CB<2>")
	)
	(gr_poly
		(pts
			(xy 132.127752 -257.37947) (xy 132.080762 -257.22707) (xy 131.819142 -257.22707) (xy 131.772152 -257.37947)
			(xy 131.772152 -257.42392) (xy 132.127752 -257.42392)
		)
		(stroke
			(width 0)
			(type solid)
		)
		(fill yes)
		(layer "In11.Cu")
		(net "M_H_CPU1_ALERT_N")
	)
	(gr_poly
		(pts
			(xy 132.133848 -278.540718) (xy 132.086858 -278.388318) (xy 131.825238 -278.388318) (xy 131.778248 -278.540718)
			(xy 131.778248 -278.585168) (xy 132.133848 -278.585168)
		)
		(stroke
			(width 0)
			(type solid)
		)
		(fill yes)
		(layer "In11.Cu")
		(net "M_H_CPU1_SA_DQS_DP<6>")
	)
	(gr_poly
		(pts
			(xy 132.133848 -273.248882) (xy 132.133848 -273.204432) (xy 131.778248 -273.204432) (xy 131.778248 -273.248882)
			(xy 131.825238 -273.401282) (xy 132.086858 -273.401282)
		)
		(stroke
			(width 0)
			(type solid)
		)
		(fill yes)
		(layer "In11.Cu")
		(net "M_H_CPU1_SA_DQS_DN<7>")
	)
	(gr_poly
		(pts
			(xy 132.133848 -263.482074) (xy 132.133848 -263.437878) (xy 131.778248 -263.437878) (xy 131.778248 -263.482074)
			(xy 131.825238 -263.634474) (xy 132.086858 -263.634474)
		)
		(stroke
			(width 0)
			(type solid)
		)
		(fill yes)
		(layer "In11.Cu")
		(net "M_H_CPU1_SA_DQ<29>")
	)
	(gr_poly
		(pts
			(xy 132.133848 -258.59867) (xy 132.133848 -258.554474) (xy 131.778248 -258.554474) (xy 131.778248 -258.59867)
			(xy 131.825238 -258.75107) (xy 132.086858 -258.75107)
		)
		(stroke
			(width 0)
			(type solid)
		)
		(fill yes)
		(layer "In11.Cu")
		(net "M_H_CPU1_SA_CB<5>")
	)
	(gr_poly
		(pts
			(xy 132.13969 -280.16835) (xy 132.0927 -280.01595) (xy 131.83108 -280.01595) (xy 131.78409 -280.16835)
			(xy 131.78409 -280.2128) (xy 132.13969 -280.2128)
		)
		(stroke
			(width 0)
			(type solid)
		)
		(fill yes)
		(layer "In11.Cu")
		(net "M_H_CPU1_SA_DQ<11>")
	)
	(gr_poly
		(pts
			(xy 132.13969 -276.913086) (xy 132.0927 -276.760686) (xy 131.83108 -276.760686) (xy 131.78409 -276.913086)
			(xy 131.78409 -276.957282) (xy 132.13969 -276.957282)
		)
		(stroke
			(width 0)
			(type solid)
		)
		(fill yes)
		(layer "In11.Cu")
		(net "M_H_CPU1_SA_DQ<15>")
	)
	(gr_poly
		(pts
			(xy 132.13969 -261.854442) (xy 132.13969 -261.809992) (xy 131.78409 -261.809992) (xy 131.78409 -261.854442)
			(xy 131.83108 -262.006842) (xy 132.0927 -262.006842)
		)
		(stroke
			(width 0)
			(type solid)
		)
		(fill yes)
		(layer "In11.Cu")
		(net "M_H_CPU1_SA_CB<1>")
	)
	(gr_poly
		(pts
			(xy 132.13969 -256.971038) (xy 132.13969 -256.926588) (xy 131.78409 -256.926588) (xy 131.78409 -256.971038)
			(xy 131.83108 -257.123438) (xy 132.0927 -257.123438)
		)
		(stroke
			(width 0)
			(type solid)
		)
		(fill yes)
		(layer "In11.Cu")
		(net "M_H_CPU1_SA_CS_N<0>")
	)
	(gr_poly
		(pts
			(xy 132.13969 -255.751838) (xy 132.0927 -255.599438) (xy 131.83108 -255.599438) (xy 131.78409 -255.751838)
			(xy 131.78409 -255.796288) (xy 132.13969 -255.796288)
		)
		(stroke
			(width 0)
			(type solid)
		)
		(fill yes)
		(layer "In11.Cu")
		(net "M_H_CPU1_SA_CS_N<3>")
	)
	(gr_poly
		(pts
			(xy 132.14223 -281.387804) (xy 132.14223 -281.343608) (xy 131.78663 -281.343608) (xy 131.78663 -281.387804)
			(xy 131.83362 -281.540204) (xy 132.09524 -281.540204)
		)
		(stroke
			(width 0)
			(type solid)
		)
		(fill yes)
		(layer "In11.Cu")
		(net "M_H_CPU1_SA_DQ<8>")
	)
	(gr_poly
		(pts
			(xy 132.14223 -278.132286) (xy 132.14223 -278.08809) (xy 131.78663 -278.08809) (xy 131.78663 -278.132286)
			(xy 131.83362 -278.284686) (xy 132.09524 -278.284686)
		)
		(stroke
			(width 0)
			(type solid)
		)
		(fill yes)
		(layer "In11.Cu")
		(net "M_H_CPU1_SA_DQ<12>")
	)
	(gr_poly
		(pts
			(xy 132.14223 -275.284946) (xy 132.09524 -275.132546) (xy 131.83362 -275.132546) (xy 131.78663 -275.284946)
			(xy 131.78663 -275.329142) (xy 132.14223 -275.329142)
		)
		(stroke
			(width 0)
			(type solid)
		)
		(fill yes)
		(layer "In11.Cu")
		(net "M_H_CPU1_SA_DQ<18>")
	)
	(gr_poly
		(pts
			(xy 132.14223 -274.876514) (xy 132.14223 -274.832318) (xy 131.78663 -274.832318) (xy 131.78663 -274.876514)
			(xy 131.83362 -275.028914) (xy 132.09524 -275.028914)
		)
		(stroke
			(width 0)
			(type solid)
		)
		(fill yes)
		(layer "In11.Cu")
		(net "M_H_CPU1_SA_DQ<17>")
	)
	(gr_poly
		(pts
			(xy 132.14223 -273.657314) (xy 132.09524 -273.504914) (xy 131.83362 -273.504914) (xy 131.78663 -273.657314)
			(xy 131.78663 -273.70151) (xy 132.14223 -273.70151)
		)
		(stroke
			(width 0)
			(type solid)
		)
		(fill yes)
		(layer "In11.Cu")
		(net "M_H_CPU1_SA_DQS_DN<2>")
	)
	(gr_poly
		(pts
			(xy 132.14223 -269.993618) (xy 132.14223 -269.949168) (xy 131.78663 -269.949168) (xy 131.78663 -269.993618)
			(xy 131.83362 -270.146018) (xy 132.09524 -270.146018)
		)
		(stroke
			(width 0)
			(type solid)
		)
		(fill yes)
		(layer "In11.Cu")
		(net "M_H_CPU1_SA_DQ<21>")
	)
	(gr_poly
		(pts
			(xy 132.14223 -265.518138) (xy 132.09524 -265.365738) (xy 131.83362 -265.365738) (xy 131.78663 -265.518138)
			(xy 131.78663 -265.562588) (xy 132.14223 -265.562588)
		)
		(stroke
			(width 0)
			(type solid)
		)
		(fill yes)
		(layer "In11.Cu")
		(net "M_H_CPU1_SA_DQS_DN<3>")
	)
	(gr_poly
		(pts
			(xy 132.14223 -265.110214) (xy 132.14223 -265.065764) (xy 131.78663 -265.065764) (xy 131.78663 -265.110214)
			(xy 131.83362 -265.262614) (xy 132.09524 -265.262614)
		)
		(stroke
			(width 0)
			(type solid)
		)
		(fill yes)
		(layer "In11.Cu")
		(net "M_H_CPU1_SA_DQS_DN<8>")
	)
	(gr_poly
		(pts
			(xy 132.14223 -263.890506) (xy 132.09524 -263.738106) (xy 131.83362 -263.738106) (xy 131.78663 -263.890506)
			(xy 131.78663 -263.934956) (xy 132.14223 -263.934956)
		)
		(stroke
			(width 0)
			(type solid)
		)
		(fill yes)
		(layer "In11.Cu")
		(net "M_H_CPU1_SA_DQ<30>")
	)
	(gr_poly
		(pts
			(xy 132.14223 -260.634734) (xy 132.09524 -260.482334) (xy 131.83362 -260.482334) (xy 131.78663 -260.634734)
			(xy 131.78663 -260.679184) (xy 132.14223 -260.679184)
		)
		(stroke
			(width 0)
			(type solid)
		)
		(fill yes)
		(layer "In11.Cu")
		(net "M_H_CPU1_SA_DQS_DN<4>")
	)
	(gr_poly
		(pts
			(xy 132.14223 -260.22681) (xy 132.14223 -260.18236) (xy 131.78663 -260.18236) (xy 131.78663 -260.22681)
			(xy 131.83362 -260.37921) (xy 132.09524 -260.37921)
		)
		(stroke
			(width 0)
			(type solid)
		)
		(fill yes)
		(layer "In11.Cu")
		(net "M_H_CPU1_SA_DQS_DN<9>")
	)
	(gr_poly
		(pts
			(xy 132.14223 -259.007102) (xy 132.09524 -258.854702) (xy 131.83362 -258.854702) (xy 131.78663 -259.007102)
			(xy 131.78663 -259.051552) (xy 132.14223 -259.051552)
		)
		(stroke
			(width 0)
			(type solid)
		)
		(fill yes)
		(layer "In11.Cu")
		(net "M_H_CPU1_SA_CB<6>")
	)
	(gr_poly
		(pts
			(xy 132.454904 -268.211554) (xy 132.493258 -268.189456) (xy 132.315458 -267.881608) (xy 132.277104 -267.903706)
			(xy 132.168646 -268.020546) (xy 132.299456 -268.247114)
		)
		(stroke
			(width 0)
			(type solid)
		)
		(fill yes)
		(layer "In11.Cu")
		(net "M_H_CPU1_SA_DQ<25>")
	)
	(gr_poly
		(pts
			(xy 132.48513 -246.568722) (xy 132.43814 -246.416322) (xy 132.17652 -246.416322) (xy 132.12953 -246.568722)
			(xy 132.12953 -246.612918) (xy 132.48513 -246.612918)
		)
		(stroke
			(width 0)
			(type solid)
		)
		(fill yes)
		(layer "In11.Cu")
		(net "M_H_CPU1_SB_CA<5>")
	)
	(gr_poly
		(pts
			(xy 132.48513 -227.035106) (xy 132.43814 -226.882706) (xy 132.17652 -226.882706) (xy 132.12953 -227.035106)
			(xy 132.12953 -227.079556) (xy 132.48513 -227.079556)
		)
		(stroke
			(width 0)
			(type solid)
		)
		(fill yes)
		(layer "In11.Cu")
		(net "M_H_CPU1_SB_DQS_DN<3>")
	)
	(gr_poly
		(pts
			(xy 132.48513 -226.627182) (xy 132.48513 -226.582732) (xy 132.12953 -226.582732) (xy 132.12953 -226.627182)
			(xy 132.17652 -226.779582) (xy 132.43814 -226.779582)
		)
		(stroke
			(width 0)
			(type solid)
		)
		(fill yes)
		(layer "In11.Cu")
		(net "M_H_CPU1_SB_DQ<30>")
	)
	(gr_poly
		(pts
			(xy 132.48513 -225.407474) (xy 132.43814 -225.255074) (xy 132.17652 -225.255074) (xy 132.12953 -225.407474)
			(xy 132.12953 -225.45167) (xy 132.48513 -225.45167)
		)
		(stroke
			(width 0)
			(type solid)
		)
		(fill yes)
		(layer "In11.Cu")
		(net "M_H_CPU1_SB_DQ<29>")
	)
	(gr_poly
		(pts
			(xy 132.48767 -248.196354) (xy 132.44068 -248.043954) (xy 132.17906 -248.043954) (xy 132.13207 -248.196354)
			(xy 132.13207 -248.24055) (xy 132.48767 -248.24055)
		)
		(stroke
			(width 0)
			(type solid)
		)
		(fill yes)
		(layer "In11.Cu")
		(net "M_H_CPU1_SB_CA<1>")
	)
	(gr_poly
		(pts
			(xy 132.48767 -247.787922) (xy 132.48767 -247.743726) (xy 132.13207 -247.743726) (xy 132.13207 -247.787922)
			(xy 132.17906 -247.940322) (xy 132.44068 -247.940322)
		)
		(stroke
			(width 0)
			(type solid)
		)
		(fill yes)
		(layer "In11.Cu")
		(net "M_H_CPU1_SB_CA<2>")
	)
	(gr_poly
		(pts
			(xy 132.48767 -244.53215) (xy 132.48767 -244.487954) (xy 132.13207 -244.487954) (xy 132.13207 -244.53215)
			(xy 132.17906 -244.68455) (xy 132.44068 -244.68455)
		)
		(stroke
			(width 0)
			(type solid)
		)
		(fill yes)
		(layer "In11.Cu")
		(net "M_H_CPU1_SB_CB<6>")
	)
	(gr_poly
		(pts
			(xy 132.48767 -243.31295) (xy 132.44068 -243.16055) (xy 132.17906 -243.16055) (xy 132.13207 -243.31295)
			(xy 132.13207 -243.3574) (xy 132.48767 -243.3574)
		)
		(stroke
			(width 0)
			(type solid)
		)
		(fill yes)
		(layer "In11.Cu")
		(net "M_H_CPU1_SB_CB<5>")
	)
	(gr_poly
		(pts
			(xy 132.48767 -242.905026) (xy 132.48767 -242.860576) (xy 132.13207 -242.860576) (xy 132.13207 -242.905026)
			(xy 132.17906 -243.057426) (xy 132.44068 -243.057426)
		)
		(stroke
			(width 0)
			(type solid)
		)
		(fill yes)
		(layer "In11.Cu")
		(net "M_H_CPU1_SB_DQS_DP<9>")
	)
	(gr_poly
		(pts
			(xy 132.48767 -239.648746) (xy 132.48767 -239.60455) (xy 132.13207 -239.60455) (xy 132.13207 -239.648746)
			(xy 132.17906 -239.801146) (xy 132.44068 -239.801146)
		)
		(stroke
			(width 0)
			(type solid)
		)
		(fill yes)
		(layer "In11.Cu")
		(net "M_H_CPU1_SB_DQ<0>")
	)
	(gr_poly
		(pts
			(xy 132.48767 -238.429546) (xy 132.44068 -238.277146) (xy 132.17906 -238.277146) (xy 132.13207 -238.429546)
			(xy 132.13207 -238.473996) (xy 132.48767 -238.473996)
		)
		(stroke
			(width 0)
			(type solid)
		)
		(fill yes)
		(layer "In11.Cu")
		(net "M_H_CPU1_SB_DQ<3>")
	)
	(gr_poly
		(pts
			(xy 132.48767 -238.021622) (xy 132.48767 -237.977172) (xy 132.13207 -237.977172) (xy 132.13207 -238.021622)
			(xy 132.17906 -238.174022) (xy 132.44068 -238.174022)
		)
		(stroke
			(width 0)
			(type solid)
		)
		(fill yes)
		(layer "In11.Cu")
		(net "M_H_CPU1_SB_DQS_DP<0>")
	)
	(gr_poly
		(pts
			(xy 132.48767 -234.76585) (xy 132.48767 -234.7214) (xy 132.13207 -234.7214) (xy 132.13207 -234.76585)
			(xy 132.17906 -234.91825) (xy 132.44068 -234.91825)
		)
		(stroke
			(width 0)
			(type solid)
		)
		(fill yes)
		(layer "In11.Cu")
		(net "M_H_CPU1_SB_DQ<8>")
	)
	(gr_poly
		(pts
			(xy 132.48767 -233.138218) (xy 132.48767 -233.093768) (xy 132.13207 -233.093768) (xy 132.13207 -233.138218)
			(xy 132.17906 -233.290618) (xy 132.44068 -233.290618)
		)
		(stroke
			(width 0)
			(type solid)
		)
		(fill yes)
		(layer "In11.Cu")
		(net "M_H_CPU1_SB_DQS_DP<1>")
	)
	(gr_poly
		(pts
			(xy 132.48767 -229.882446) (xy 132.48767 -229.837996) (xy 132.13207 -229.837996) (xy 132.13207 -229.882446)
			(xy 132.17906 -230.034846) (xy 132.44068 -230.034846)
		)
		(stroke
			(width 0)
			(type solid)
		)
		(fill yes)
		(layer "In11.Cu")
		(net "M_H_CPU1_SB_DQ<26>")
	)
	(gr_poly
		(pts
			(xy 132.48767 -228.663246) (xy 132.44068 -228.510846) (xy 132.17906 -228.510846) (xy 132.13207 -228.663246)
			(xy 132.13207 -228.707442) (xy 132.48767 -228.707442)
		)
		(stroke
			(width 0)
			(type solid)
		)
		(fill yes)
		(layer "In11.Cu")
		(net "M_H_CPU1_SB_DQ<25>")
	)
	(gr_poly
		(pts
			(xy 132.48767 -228.254814) (xy 132.48767 -228.210618) (xy 132.13207 -228.210618) (xy 132.13207 -228.254814)
			(xy 132.17906 -228.407214) (xy 132.44068 -228.407214)
		)
		(stroke
			(width 0)
			(type solid)
		)
		(fill yes)
		(layer "In11.Cu")
		(net "M_H_CPU1_SB_DQS_DN<8>")
	)
	(gr_poly
		(pts
			(xy 132.493512 -246.16029) (xy 132.493512 -246.11584) (xy 132.137912 -246.11584) (xy 132.137912 -246.16029)
			(xy 132.184902 -246.31269) (xy 132.446522 -246.31269)
		)
		(stroke
			(width 0)
			(type solid)
		)
		(fill yes)
		(layer "In11.Cu")
		(net "M_H_CPU1_SB_CA<6>")
	)
	(gr_poly
		(pts
			(xy 132.493512 -241.276886) (xy 132.493512 -241.232436) (xy 132.137912 -241.232436) (xy 132.137912 -241.276886)
			(xy 132.184902 -241.429286) (xy 132.446522 -241.429286)
		)
		(stroke
			(width 0)
			(type solid)
		)
		(fill yes)
		(layer "In11.Cu")
		(net "M_H_CPU1_SB_CB<0>")
	)
	(gr_poly
		(pts
			(xy 132.493512 -236.393482) (xy 132.493512 -236.349286) (xy 132.137912 -236.349286) (xy 132.137912 -236.393482)
			(xy 132.184902 -236.545882) (xy 132.446522 -236.545882)
		)
		(stroke
			(width 0)
			(type solid)
		)
		(fill yes)
		(layer "In11.Cu")
		(net "M_H_CPU1_SB_DQ<4>")
	)
	(gr_poly
		(pts
			(xy 132.493512 -231.510078) (xy 132.493512 -231.465882) (xy 132.137912 -231.465882) (xy 132.137912 -231.510078)
			(xy 132.184902 -231.662478) (xy 132.446522 -231.662478)
		)
		(stroke
			(width 0)
			(type solid)
		)
		(fill yes)
		(layer "In11.Cu")
		(net "M_H_CPU1_SB_DQ<12>")
	)
	(gr_poly
		(pts
			(xy 132.49402 -241.685826) (xy 132.44703 -241.533426) (xy 132.18541 -241.533426) (xy 132.13842 -241.685826)
			(xy 132.13842 -241.730022) (xy 132.49402 -241.730022)
		)
		(stroke
			(width 0)
			(type solid)
		)
		(fill yes)
		(layer "In11.Cu")
		(net "M_H_CPU1_SB_DQS_DP<4>")
	)
	(gr_poly
		(pts
			(xy 132.49402 -236.802422) (xy 132.44703 -236.650022) (xy 132.18541 -236.650022) (xy 132.13842 -236.802422)
			(xy 132.13842 -236.846872) (xy 132.49402 -236.846872)
		)
		(stroke
			(width 0)
			(type solid)
		)
		(fill yes)
		(layer "In11.Cu")
		(net "M_H_CPU1_SB_DQS_DP<5>")
	)
	(gr_poly
		(pts
			(xy 132.49402 -231.919018) (xy 132.44703 -231.766618) (xy 132.18541 -231.766618) (xy 132.13842 -231.919018)
			(xy 132.13842 -231.963468) (xy 132.49402 -231.963468)
		)
		(stroke
			(width 0)
			(type solid)
		)
		(fill yes)
		(layer "In11.Cu")
		(net "M_H_CPU1_SB_DQS_DP<6>")
	)
	(gr_poly
		(pts
			(xy 132.499608 -240.057686) (xy 132.452618 -239.905286) (xy 132.190998 -239.905286) (xy 132.144008 -240.057686)
			(xy 132.144008 -240.101882) (xy 132.499608 -240.101882)
		)
		(stroke
			(width 0)
			(type solid)
		)
		(fill yes)
		(layer "In11.Cu")
		(net "M_H_CPU1_SB_CB<3>")
	)
	(gr_poly
		(pts
			(xy 132.499608 -235.174282) (xy 132.452618 -235.021882) (xy 132.190998 -235.021882) (xy 132.144008 -235.174282)
			(xy 132.144008 -235.218732) (xy 132.499608 -235.218732)
		)
		(stroke
			(width 0)
			(type solid)
		)
		(fill yes)
		(layer "In11.Cu")
		(net "M_H_CPU1_SB_DQ<7>")
	)
	(gr_poly
		(pts
			(xy 132.499608 -230.290878) (xy 132.452618 -230.138478) (xy 132.190998 -230.138478) (xy 132.144008 -230.290878)
			(xy 132.144008 -230.335328) (xy 132.499608 -230.335328)
		)
		(stroke
			(width 0)
			(type solid)
		)
		(fill yes)
		(layer "In11.Cu")
		(net "M_H_CPU1_SB_DQ<15>")
	)
	(gr_poly
		(pts
			(xy 132.499862 -233.546142) (xy 132.452872 -233.393742) (xy 132.191252 -233.393742) (xy 132.144262 -233.546142)
			(xy 132.144262 -233.590592) (xy 132.499862 -233.590592)
		)
		(stroke
			(width 0)
			(type solid)
		)
		(fill yes)
		(layer "In11.Cu")
		(net "M_H_CPU1_SB_DQ<11>")
	)
	(gr_poly
		(pts
			(xy 132.569204 -267.598906) (xy 132.677662 -267.482066) (xy 132.546852 -267.255498) (xy 132.391404 -267.291058)
			(xy 132.35305 -267.313156) (xy 132.53085 -267.621004)
		)
		(stroke
			(width 0)
			(type solid)
		)
		(fill yes)
		(layer "In11.Cu")
		(net "M_H_CPU1_SA_DQ<27>")
	)
	(gr_poly
		(pts
			(xy 132.595112 -280.98242) (xy 132.548122 -280.83002) (xy 132.286502 -280.83002) (xy 132.239512 -280.98242)
			(xy 132.239512 -281.026616) (xy 132.595112 -281.026616)
		)
		(stroke
			(width 0)
			(type solid)
		)
		(fill yes)
		(layer "In11.Cu")
		(net "M_H_CPU1_SA_DQ<10>")
	)
	(gr_poly
		(pts
			(xy 132.595112 -277.726394) (xy 132.548122 -277.573994) (xy 132.286502 -277.573994) (xy 132.239512 -277.726394)
			(xy 132.239512 -277.770844) (xy 132.595112 -277.770844)
		)
		(stroke
			(width 0)
			(type solid)
		)
		(fill yes)
		(layer "In11.Cu")
		(net "M_H_CPU1_SA_DQ<14>")
	)
	(gr_poly
		(pts
			(xy 132.595112 -275.690584) (xy 132.595112 -275.646388) (xy 132.239512 -275.646388) (xy 132.239512 -275.690584)
			(xy 132.286502 -275.842984) (xy 132.548122 -275.842984)
		)
		(stroke
			(width 0)
			(type solid)
		)
		(fill yes)
		(layer "In11.Cu")
		(net "M_H_CPU1_SA_DQ<16>")
	)
	(gr_poly
		(pts
			(xy 132.595112 -265.92403) (xy 132.595112 -265.879834) (xy 132.239512 -265.879834) (xy 132.239512 -265.92403)
			(xy 132.286502 -266.07643) (xy 132.548122 -266.07643)
		)
		(stroke
			(width 0)
			(type solid)
		)
		(fill yes)
		(layer "In11.Cu")
		(net "M_H_CPU1_SA_DQS_DP<3>")
	)
	(gr_poly
		(pts
			(xy 132.595112 -261.040626) (xy 132.595112 -260.99643) (xy 132.239512 -260.99643) (xy 132.239512 -261.040626)
			(xy 132.286502 -261.193026) (xy 132.548122 -261.193026)
		)
		(stroke
			(width 0)
			(type solid)
		)
		(fill yes)
		(layer "In11.Cu")
		(net "M_H_CPU1_SA_DQS_DP<4>")
	)
	(gr_poly
		(pts
			(xy 132.595112 -259.820918) (xy 132.548122 -259.668518) (xy 132.286502 -259.668518) (xy 132.239512 -259.820918)
			(xy 132.239512 -259.865368) (xy 132.595112 -259.865368)
		)
		(stroke
			(width 0)
			(type solid)
		)
		(fill yes)
		(layer "In11.Cu")
		(net "M_H_CPU1_SA_DQS_DP<9>")
	)
	(gr_poly
		(pts
			(xy 132.595112 -259.412994) (xy 132.595112 -259.368544) (xy 132.239512 -259.368544) (xy 132.239512 -259.412994)
			(xy 132.286502 -259.565394) (xy 132.548122 -259.565394)
		)
		(stroke
			(width 0)
			(type solid)
		)
		(fill yes)
		(layer "In11.Cu")
		(net "M_H_CPU1_SA_CB<4>")
	)
	(gr_poly
		(pts
			(xy 132.597652 -274.47113) (xy 132.550662 -274.31873) (xy 132.289042 -274.31873) (xy 132.242052 -274.47113)
			(xy 132.242052 -274.515326) (xy 132.597652 -274.515326)
		)
		(stroke
			(width 0)
			(type solid)
		)
		(fill yes)
		(layer "In11.Cu")
		(net "M_H_CPU1_SA_DQ<19>")
	)
	(gr_poly
		(pts
			(xy 132.597652 -274.062698) (xy 132.597652 -274.018502) (xy 132.242052 -274.018502) (xy 132.242052 -274.062698)
			(xy 132.289042 -274.215098) (xy 132.550662 -274.215098)
		)
		(stroke
			(width 0)
			(type solid)
		)
		(fill yes)
		(layer "In11.Cu")
		(net "M_H_CPU1_SA_DQS_DP<2>")
	)
	(gr_poly
		(pts
			(xy 132.597652 -272.843498) (xy 132.550662 -272.691098) (xy 132.289042 -272.691098) (xy 132.242052 -272.843498)
			(xy 132.242052 -272.887948) (xy 132.597652 -272.887948)
		)
		(stroke
			(width 0)
			(type solid)
		)
		(fill yes)
		(layer "In11.Cu")
		(net "M_H_CPU1_SA_DQS_DP<7>")
	)
	(gr_poly
		(pts
			(xy 132.597652 -269.587726) (xy 132.550662 -269.435326) (xy 132.289042 -269.435326) (xy 132.242052 -269.587726)
			(xy 132.242052 -269.631922) (xy 132.597652 -269.631922)
		)
		(stroke
			(width 0)
			(type solid)
		)
		(fill yes)
		(layer "In11.Cu")
		(net "M_H_CPU1_SA_DQ<23>")
	)
	(gr_poly
		(pts
			(xy 132.597652 -269.179294) (xy 132.597652 -269.135098) (xy 132.242052 -269.135098) (xy 132.242052 -269.179294)
			(xy 132.289042 -269.331694) (xy 132.550662 -269.331694)
		)
		(stroke
			(width 0)
			(type solid)
		)
		(fill yes)
		(layer "In11.Cu")
		(net "M_H_CPU1_SA_DQ<24>")
	)
	(gr_poly
		(pts
			(xy 132.597652 -264.704322) (xy 132.550662 -264.551922) (xy 132.289042 -264.551922) (xy 132.242052 -264.704322)
			(xy 132.242052 -264.748772) (xy 132.597652 -264.748772)
		)
		(stroke
			(width 0)
			(type solid)
		)
		(fill yes)
		(layer "In11.Cu")
		(net "M_H_CPU1_SA_DQS_DP<8>")
	)
	(gr_poly
		(pts
			(xy 132.597652 -264.296398) (xy 132.597652 -264.251948) (xy 132.242052 -264.251948) (xy 132.242052 -264.296398)
			(xy 132.289042 -264.448798) (xy 132.550662 -264.448798)
		)
		(stroke
			(width 0)
			(type solid)
		)
		(fill yes)
		(layer "In11.Cu")
		(net "M_H_CPU1_SA_DQ<28>")
	)
	(gr_poly
		(pts
			(xy 132.597652 -263.07669) (xy 132.550662 -262.92429) (xy 132.289042 -262.92429) (xy 132.242052 -263.07669)
			(xy 132.242052 -263.12114) (xy 132.597652 -263.12114)
		)
		(stroke
			(width 0)
			(type solid)
		)
		(fill yes)
		(layer "In11.Cu")
		(net "M_H_CPU1_SA_DQ<31>")
	)
	(gr_poly
		(pts
			(xy 132.597652 -258.193286) (xy 132.550662 -258.040886) (xy 132.289042 -258.040886) (xy 132.242052 -258.193286)
			(xy 132.242052 -258.237736) (xy 132.597652 -258.237736)
		)
		(stroke
			(width 0)
			(type solid)
		)
		(fill yes)
		(layer "In11.Cu")
		(net "M_H_CPU1_SA_CB<7>")
	)
	(gr_poly
		(pts
			(xy 132.603494 -280.573988) (xy 132.603494 -280.529538) (xy 132.247894 -280.529538) (xy 132.247894 -280.573988)
			(xy 132.294884 -280.726388) (xy 132.556504 -280.726388)
		)
		(stroke
			(width 0)
			(type solid)
		)
		(fill yes)
		(layer "In11.Cu")
		(net "M_H_CPU1_SA_DQ<9>")
	)
	(gr_poly
		(pts
			(xy 132.603494 -277.317962) (xy 132.603494 -277.273766) (xy 132.247894 -277.273766) (xy 132.247894 -277.317962)
			(xy 132.294884 -277.470362) (xy 132.556504 -277.470362)
		)
		(stroke
			(width 0)
			(type solid)
		)
		(fill yes)
		(layer "In11.Cu")
		(net "M_H_CPU1_SA_DQ<13>")
	)
	(gr_poly
		(pts
			(xy 132.603494 -261.449058) (xy 132.556504 -261.296658) (xy 132.294884 -261.296658) (xy 132.247894 -261.449058)
			(xy 132.247894 -261.493508) (xy 132.603494 -261.493508)
		)
		(stroke
			(width 0)
			(type solid)
		)
		(fill yes)
		(layer "In11.Cu")
		(net "M_H_CPU1_SA_CB<3>")
	)
	(gr_poly
		(pts
			(xy 132.603494 -256.565654) (xy 132.556504 -256.413254) (xy 132.294884 -256.413254) (xy 132.247894 -256.565654)
			(xy 132.247894 -256.610104) (xy 132.603494 -256.610104)
		)
		(stroke
			(width 0)
			(type solid)
		)
		(fill yes)
		(layer "In11.Cu")
		(net "M_H_CPU1_SA_CS_N<1>")
	)
	(gr_poly
		(pts
			(xy 132.603494 -256.157222) (xy 132.603494 -256.112772) (xy 132.247894 -256.112772) (xy 132.247894 -256.157222)
			(xy 132.294884 -256.309622) (xy 132.556504 -256.309622)
		)
		(stroke
			(width 0)
			(type solid)
		)
		(fill yes)
		(layer "In11.Cu")
		(net "M_H_CPU1_SA_CS_N<2>")
	)
	(gr_poly
		(pts
			(xy 132.603748 -278.945848) (xy 132.603748 -278.901652) (xy 132.248148 -278.901652) (xy 132.248148 -278.945848)
			(xy 132.295138 -279.098248) (xy 132.556758 -279.098248)
		)
		(stroke
			(width 0)
			(type solid)
		)
		(fill yes)
		(layer "In11.Cu")
		(net "M_H_CPU1_SA_DQS_DN<6>")
	)
	(gr_poly
		(pts
			(xy 132.60959 -272.435066) (xy 132.60959 -272.390616) (xy 132.25399 -272.390616) (xy 132.25399 -272.435066)
			(xy 132.30098 -272.587466) (xy 132.5626 -272.587466)
		)
		(stroke
			(width 0)
			(type solid)
		)
		(fill yes)
		(layer "In11.Cu")
		(net "M_H_CPU1_SA_DQ<20>")
	)
	(gr_poly
		(pts
			(xy 132.60959 -262.668258) (xy 132.60959 -262.623808) (xy 132.25399 -262.623808) (xy 132.25399 -262.668258)
			(xy 132.30098 -262.820658) (xy 132.5626 -262.820658)
		)
		(stroke
			(width 0)
			(type solid)
		)
		(fill yes)
		(layer "In11.Cu")
		(net "M_H_CPU1_SA_CB<0>")
	)
	(gr_poly
		(pts
			(xy 132.60959 -257.784854) (xy 132.60959 -257.740404) (xy 132.25399 -257.740404) (xy 132.25399 -257.784854)
			(xy 132.30098 -257.937254) (xy 132.5626 -257.937254)
		)
		(stroke
			(width 0)
			(type solid)
		)
		(fill yes)
		(layer "In11.Cu")
		(net "M_E_CPU1_ALERT_N")
	)
	(gr_poly
		(pts
			(xy 132.609844 -254.938022) (xy 132.562854 -254.785622) (xy 132.301234 -254.785622) (xy 132.254244 -254.938022)
			(xy 132.254244 -254.982218) (xy 132.609844 -254.982218)
		)
		(stroke
			(width 0)
			(type solid)
		)
		(fill yes)
		(layer "In11.Cu")
		(net "M_H_CPU1_SA_CA<0>")
	)
	(gr_poly
		(pts
			(xy 132.61213 -279.35428) (xy 132.56514 -279.20188) (xy 132.30352 -279.20188) (xy 132.25653 -279.35428)
			(xy 132.25653 -279.39873) (xy 132.61213 -279.39873)
		)
		(stroke
			(width 0)
			(type solid)
		)
		(fill yes)
		(layer "In11.Cu")
		(net "M_H_CPU1_SA_DQS_DN<1>")
	)
	(gr_poly
		(pts
			(xy 132.61213 -254.52959) (xy 132.61213 -254.48514) (xy 132.25653 -254.48514) (xy 132.25653 -254.52959)
			(xy 132.30352 -254.68199) (xy 132.56514 -254.68199)
		)
		(stroke
			(width 0)
			(type solid)
		)
		(fill yes)
		(layer "In11.Cu")
		(net "M_H_CPU1_SA_CA<2>")
	)
	(gr_poly
		(pts
			(xy 132.819394 -249.268996) (xy 132.857748 -249.246898) (xy 132.679948 -248.93905) (xy 132.641594 -248.961148)
			(xy 132.533136 -249.077988) (xy 132.663946 -249.304556)
		)
		(stroke
			(width 0)
			(type solid)
		)
		(fill yes)
		(layer "In11.Cu")
		(net "M_H_CPU1_SB_CA<0>")
	)
	(gr_poly
		(pts
			(xy 132.928106 -248.647204) (xy 133.036564 -248.530364) (xy 132.905754 -248.303796) (xy 132.750306 -248.339356)
			(xy 132.711952 -248.361454) (xy 132.889752 -248.669302)
		)
		(stroke
			(width 0)
			(type solid)
		)
		(fill yes)
		(layer "In11.Cu")
		(net "M_H_CPU1_SB_CA<1>")
	)
	(gr_poly
		(pts
			(xy 132.929122 -270.660368) (xy 132.967476 -270.63827) (xy 132.789676 -270.330422) (xy 132.751322 -270.35252)
			(xy 132.642864 -270.46936) (xy 132.773674 -270.695928)
		)
		(stroke
			(width 0)
			(type solid)
		)
		(fill yes)
		(layer "In11.Cu")
		(net "M_H_CPU1_SA_DQ<21>")
	)
	(gr_poly
		(pts
			(xy 132.95757 -247.382538) (xy 132.91058 -247.230138) (xy 132.64896 -247.230138) (xy 132.60197 -247.382538)
			(xy 132.60197 -247.426988) (xy 132.95757 -247.426988)
		)
		(stroke
			(width 0)
			(type solid)
		)
		(fill yes)
		(layer "In11.Cu")
		(net "M_H_CPU1_SB_CA<3>")
	)
	(gr_poly
		(pts
			(xy 132.95757 -237.616238) (xy 132.91058 -237.463838) (xy 132.64896 -237.463838) (xy 132.60197 -237.616238)
			(xy 132.60197 -237.660434) (xy 132.95757 -237.660434)
		)
		(stroke
			(width 0)
			(type solid)
		)
		(fill yes)
		(layer "In11.Cu")
		(net "M_H_CPU1_SB_DQS_DN<0>")
	)
	(gr_poly
		(pts
			(xy 132.95757 -232.732834) (xy 132.91058 -232.580434) (xy 132.64896 -232.580434) (xy 132.60197 -232.732834)
			(xy 132.60197 -232.77703) (xy 132.95757 -232.77703)
		)
		(stroke
			(width 0)
			(type solid)
		)
		(fill yes)
		(layer "In11.Cu")
		(net "M_H_CPU1_SB_DQS_DN<1>")
	)
	(gr_poly
		(pts
			(xy 132.963666 -243.718334) (xy 132.963666 -243.674138) (xy 132.608066 -243.674138) (xy 132.608066 -243.718334)
			(xy 132.655056 -243.870734) (xy 132.916676 -243.870734)
		)
		(stroke
			(width 0)
			(type solid)
		)
		(fill yes)
		(layer "In11.Cu")
		(net "M_H_CPU1_SB_CB<7>")
	)
	(gr_poly
		(pts
			(xy 132.963666 -242.499134) (xy 132.916676 -242.346734) (xy 132.655056 -242.346734) (xy 132.608066 -242.499134)
			(xy 132.608066 -242.543584) (xy 132.963666 -242.543584)
		)
		(stroke
			(width 0)
			(type solid)
		)
		(fill yes)
		(layer "In11.Cu")
		(net "M_H_CPU1_SB_DQS_DN<9>")
	)
	(gr_poly
		(pts
			(xy 132.963666 -238.83493) (xy 132.963666 -238.790734) (xy 132.608066 -238.790734) (xy 132.608066 -238.83493)
			(xy 132.655056 -238.98733) (xy 132.916676 -238.98733)
		)
		(stroke
			(width 0)
			(type solid)
		)
		(fill yes)
		(layer "In11.Cu")
		(net "M_H_CPU1_SB_DQ<1>")
	)
	(gr_poly
		(pts
			(xy 132.963666 -233.952034) (xy 132.963666 -233.907584) (xy 132.608066 -233.907584) (xy 132.608066 -233.952034)
			(xy 132.655056 -234.104434) (xy 132.916676 -234.104434)
		)
		(stroke
			(width 0)
			(type solid)
		)
		(fill yes)
		(layer "In11.Cu")
		(net "M_H_CPU1_SB_DQ<9>")
	)
	(gr_poly
		(pts
			(xy 132.963666 -229.06863) (xy 132.963666 -229.02418) (xy 132.608066 -229.02418) (xy 132.608066 -229.06863)
			(xy 132.655056 -229.22103) (xy 132.916676 -229.22103)
		)
		(stroke
			(width 0)
			(type solid)
		)
		(fill yes)
		(layer "In11.Cu")
		(net "M_H_CPU1_SB_DQ<27>")
	)
	(gr_poly
		(pts
			(xy 132.963666 -227.84943) (xy 132.916676 -227.69703) (xy 132.655056 -227.69703) (xy 132.608066 -227.84943)
			(xy 132.608066 -227.893626) (xy 132.963666 -227.893626)
		)
		(stroke
			(width 0)
			(type solid)
		)
		(fill yes)
		(layer "In11.Cu")
		(net "M_H_CPU1_SB_DQS_DP<8>")
	)
	(gr_poly
		(pts
			(xy 132.969508 -246.974106) (xy 132.969508 -246.929656) (xy 132.613908 -246.929656) (xy 132.613908 -246.974106)
			(xy 132.660898 -247.126506) (xy 132.922518 -247.126506)
		)
		(stroke
			(width 0)
			(type solid)
		)
		(fill yes)
		(layer "In11.Cu")
		(net "M_H_CPU1_SB_CA<4>")
	)
	(gr_poly
		(pts
			(xy 132.969508 -245.754906) (xy 132.922518 -245.602506) (xy 132.660898 -245.602506) (xy 132.613908 -245.754906)
			(xy 132.613908 -245.799102) (xy 132.969508 -245.799102)
		)
		(stroke
			(width 0)
			(type solid)
		)
		(fill yes)
		(layer "In11.Cu")
		(net "M_H_CPU1_SB_PAR")
	)
	(gr_poly
		(pts
			(xy 132.969508 -240.871502) (xy 132.922518 -240.719102) (xy 132.660898 -240.719102) (xy 132.613908 -240.871502)
			(xy 132.613908 -240.915698) (xy 132.969508 -240.915698)
		)
		(stroke
			(width 0)
			(type solid)
		)
		(fill yes)
		(layer "In11.Cu")
		(net "M_H_CPU1_SB_CB<2>")
	)
	(gr_poly
		(pts
			(xy 132.969508 -240.46307) (xy 132.969508 -240.418874) (xy 132.613908 -240.418874) (xy 132.613908 -240.46307)
			(xy 132.660898 -240.61547) (xy 132.922518 -240.61547)
		)
		(stroke
			(width 0)
			(type solid)
		)
		(fill yes)
		(layer "In11.Cu")
		(net "M_H_CPU1_SB_CB<1>")
	)
	(gr_poly
		(pts
			(xy 132.969508 -237.207298) (xy 132.969508 -237.163102) (xy 132.613908 -237.163102) (xy 132.613908 -237.207298)
			(xy 132.660898 -237.359698) (xy 132.922518 -237.359698)
		)
		(stroke
			(width 0)
			(type solid)
		)
		(fill yes)
		(layer "In11.Cu")
		(net "M_H_CPU1_SB_DQS_DN<5>")
	)
	(gr_poly
		(pts
			(xy 132.969508 -235.988098) (xy 132.922518 -235.835698) (xy 132.660898 -235.835698) (xy 132.613908 -235.988098)
			(xy 132.613908 -236.032294) (xy 132.969508 -236.032294)
		)
		(stroke
			(width 0)
			(type solid)
		)
		(fill yes)
		(layer "In11.Cu")
		(net "M_H_CPU1_SB_DQ<6>")
	)
	(gr_poly
		(pts
			(xy 132.969508 -235.579666) (xy 132.969508 -235.53547) (xy 132.613908 -235.53547) (xy 132.613908 -235.579666)
			(xy 132.660898 -235.732066) (xy 132.922518 -235.732066)
		)
		(stroke
			(width 0)
			(type solid)
		)
		(fill yes)
		(layer "In11.Cu")
		(net "M_H_CPU1_SB_DQ<5>")
	)
	(gr_poly
		(pts
			(xy 132.969508 -232.323894) (xy 132.969508 -232.279698) (xy 132.613908 -232.279698) (xy 132.613908 -232.323894)
			(xy 132.660898 -232.476294) (xy 132.922518 -232.476294)
		)
		(stroke
			(width 0)
			(type solid)
		)
		(fill yes)
		(layer "In11.Cu")
		(net "M_H_CPU1_SB_DQS_DN<6>")
	)
	(gr_poly
		(pts
			(xy 132.969508 -231.104694) (xy 132.922518 -230.952294) (xy 132.660898 -230.952294) (xy 132.613908 -231.104694)
			(xy 132.613908 -231.14889) (xy 132.969508 -231.14889)
		)
		(stroke
			(width 0)
			(type solid)
		)
		(fill yes)
		(layer "In11.Cu")
		(net "M_H_CPU1_SB_DQ<14>")
	)
	(gr_poly
		(pts
			(xy 132.969508 -230.696262) (xy 132.969508 -230.652066) (xy 132.613908 -230.652066) (xy 132.613908 -230.696262)
			(xy 132.660898 -230.848662) (xy 132.922518 -230.848662)
		)
		(stroke
			(width 0)
			(type solid)
		)
		(fill yes)
		(layer "In11.Cu")
		(net "M_H_CPU1_SB_DQ<13>")
	)
	(gr_poly
		(pts
			(xy 132.972048 -244.126766) (xy 132.925058 -243.974366) (xy 132.663438 -243.974366) (xy 132.616448 -244.126766)
			(xy 132.616448 -244.171216) (xy 132.972048 -244.171216)
		)
		(stroke
			(width 0)
			(type solid)
		)
		(fill yes)
		(layer "In11.Cu")
		(net "M_H_CPU1_SB_CB<4>")
	)
	(gr_poly
		(pts
			(xy 132.972048 -242.090702) (xy 132.972048 -242.046506) (xy 132.616448 -242.046506) (xy 132.616448 -242.090702)
			(xy 132.663438 -242.243102) (xy 132.925058 -242.243102)
		)
		(stroke
			(width 0)
			(type solid)
		)
		(fill yes)
		(layer "In11.Cu")
		(net "M_H_CPU1_SB_DQS_DN<4>")
	)
	(gr_poly
		(pts
			(xy 132.972048 -239.243362) (xy 132.925058 -239.090962) (xy 132.663438 -239.090962) (xy 132.616448 -239.243362)
			(xy 132.616448 -239.287812) (xy 132.972048 -239.287812)
		)
		(stroke
			(width 0)
			(type solid)
		)
		(fill yes)
		(layer "In11.Cu")
		(net "M_H_CPU1_SB_DQ<2>")
	)
	(gr_poly
		(pts
			(xy 132.972048 -234.360466) (xy 132.925058 -234.208066) (xy 132.663438 -234.208066) (xy 132.616448 -234.360466)
			(xy 132.616448 -234.404662) (xy 132.972048 -234.404662)
		)
		(stroke
			(width 0)
			(type solid)
		)
		(fill yes)
		(layer "In11.Cu")
		(net "M_H_CPU1_SB_DQ<10>")
	)
	(gr_poly
		(pts
			(xy 132.972048 -229.477062) (xy 132.925058 -229.324662) (xy 132.663438 -229.324662) (xy 132.616448 -229.477062)
			(xy 132.616448 -229.521258) (xy 132.972048 -229.521258)
		)
		(stroke
			(width 0)
			(type solid)
		)
		(fill yes)
		(layer "In11.Cu")
		(net "M_H_CPU1_SB_DQ<24>")
	)
	(gr_poly
		(pts
			(xy 132.972048 -227.440998) (xy 132.972048 -227.396548) (xy 132.616448 -227.396548) (xy 132.616448 -227.440998)
			(xy 132.663438 -227.593398) (xy 132.925058 -227.593398)
		)
		(stroke
			(width 0)
			(type solid)
		)
		(fill yes)
		(layer "In11.Cu")
		(net "M_H_CPU1_SB_DQS_DP<3>")
	)
	(gr_poly
		(pts
			(xy 132.972048 -226.22129) (xy 132.925058 -226.06889) (xy 132.663438 -226.06889) (xy 132.616448 -226.22129)
			(xy 132.616448 -226.26574) (xy 132.972048 -226.26574)
		)
		(stroke
			(width 0)
			(type solid)
		)
		(fill yes)
		(layer "In11.Cu")
		(net "M_H_CPU1_SB_DQ<28>")
	)
	(gr_poly
		(pts
			(xy 132.972048 -225.813366) (xy 132.972048 -225.768916) (xy 132.616448 -225.768916) (xy 132.616448 -225.813366)
			(xy 132.663438 -225.965766) (xy 132.925058 -225.965766)
		)
		(stroke
			(width 0)
			(type solid)
		)
		(fill yes)
		(layer "In11.Cu")
		(net "M_H_CPU1_SB_DQ<31>")
	)
	(gr_poly
		(pts
			(xy 133.038088 -270.038576) (xy 133.146546 -269.921736) (xy 133.015736 -269.695168) (xy 132.860288 -269.730728)
			(xy 132.821934 -269.752826) (xy 132.999734 -270.060674)
		)
		(stroke
			(width 0)
			(type solid)
		)
		(fill yes)
		(layer "In11.Cu")
		(net "M_H_CPU1_SA_DQ<23>")
	)
	(gr_poly
		(pts
			(xy 133.067552 -279.760172) (xy 133.067552 -279.715722) (xy 132.711952 -279.715722) (xy 132.711952 -279.760172)
			(xy 132.758942 -279.912572) (xy 133.020562 -279.912572)
		)
		(stroke
			(width 0)
			(type solid)
		)
		(fill yes)
		(layer "In11.Cu")
		(net "M_H_CPU1_SA_DQS_DP<1>")
	)
	(gr_poly
		(pts
			(xy 133.067552 -274.876514) (xy 133.067552 -274.832064) (xy 132.711952 -274.832064) (xy 132.711952 -274.876514)
			(xy 132.758942 -275.028914) (xy 133.020562 -275.028914)
		)
		(stroke
			(width 0)
			(type solid)
		)
		(fill yes)
		(layer "In11.Cu")
		(net "M_H_CPU1_SA_DQ<17>")
	)
	(gr_poly
		(pts
			(xy 133.067552 -265.109706) (xy 133.067552 -265.06551) (xy 132.711952 -265.06551) (xy 132.711952 -265.109706)
			(xy 132.758942 -265.262106) (xy 133.020562 -265.262106)
		)
		(stroke
			(width 0)
			(type solid)
		)
		(fill yes)
		(layer "In11.Cu")
		(net "M_H_CPU1_SA_DQS_DN<8>")
	)
	(gr_poly
		(pts
			(xy 133.067552 -255.343406) (xy 133.067552 -255.298956) (xy 132.711952 -255.298956) (xy 132.711952 -255.343406)
			(xy 132.758942 -255.495806) (xy 133.020562 -255.495806)
		)
		(stroke
			(width 0)
			(type solid)
		)
		(fill yes)
		(layer "In11.Cu")
		(net "M_H_CPU1_SA_CA<1>")
	)
	(gr_poly
		(pts
			(xy 133.073394 -255.751838) (xy 133.026404 -255.599438) (xy 132.764784 -255.599438) (xy 132.717794 -255.751838)
			(xy 132.717794 -255.796288) (xy 133.073394 -255.796288)
		)
		(stroke
			(width 0)
			(type solid)
		)
		(fill yes)
		(layer "In11.Cu")
		(net "M_H_CPU1_SA_CS_N<3>")
	)
	(gr_poly
		(pts
			(xy 133.073648 -278.540718) (xy 133.026658 -278.388318) (xy 132.765038 -278.388318) (xy 132.718048 -278.540718)
			(xy 132.718048 -278.585168) (xy 133.073648 -278.585168)
		)
		(stroke
			(width 0)
			(type solid)
		)
		(fill yes)
		(layer "In11.Cu")
		(net "M_H_CPU1_SA_DQS_DP<6>")
	)
	(gr_poly
		(pts
			(xy 133.073648 -273.657314) (xy 133.026658 -273.504914) (xy 132.765038 -273.504914) (xy 132.718048 -273.657314)
			(xy 132.718048 -273.701764) (xy 133.073648 -273.701764)
		)
		(stroke
			(width 0)
			(type solid)
		)
		(fill yes)
		(layer "In11.Cu")
		(net "M_H_CPU1_SA_DQS_DN<2>")
	)
	(gr_poly
		(pts
			(xy 133.073648 -268.77391) (xy 133.026658 -268.62151) (xy 132.765038 -268.62151) (xy 132.718048 -268.77391)
			(xy 132.718048 -268.81836) (xy 133.073648 -268.81836)
		)
		(stroke
			(width 0)
			(type solid)
		)
		(fill yes)
		(layer "In11.Cu")
		(net "M_H_CPU1_SA_DQ<26>")
	)
	(gr_poly
		(pts
			(xy 133.073648 -263.891014) (xy 133.026658 -263.738614) (xy 132.765038 -263.738614) (xy 132.718048 -263.891014)
			(xy 132.718048 -263.93521) (xy 133.073648 -263.93521)
		)
		(stroke
			(width 0)
			(type solid)
		)
		(fill yes)
		(layer "In11.Cu")
		(net "M_H_CPU1_SA_DQ<30>")
	)
	(gr_poly
		(pts
			(xy 133.073648 -254.124206) (xy 133.026658 -253.971806) (xy 132.765038 -253.971806) (xy 132.718048 -254.124206)
			(xy 132.718048 -254.168402) (xy 133.073648 -254.168402)
		)
		(stroke
			(width 0)
			(type solid)
		)
		(fill yes)
		(layer "In11.Cu")
		(net "M_H_CPU1_SA_CA<3>")
	)
	(gr_poly
		(pts
			(xy 133.07949 -280.168096) (xy 133.0325 -280.015696) (xy 132.77088 -280.015696) (xy 132.72389 -280.168096)
			(xy 132.72389 -280.212546) (xy 133.07949 -280.212546)
		)
		(stroke
			(width 0)
			(type solid)
		)
		(fill yes)
		(layer "In11.Cu")
		(net "M_H_CPU1_SA_DQ<11>")
	)
	(gr_poly
		(pts
			(xy 133.07949 -276.912578) (xy 133.0325 -276.760178) (xy 132.77088 -276.760178) (xy 132.72389 -276.912578)
			(xy 132.72389 -276.957028) (xy 133.07949 -276.957028)
		)
		(stroke
			(width 0)
			(type solid)
		)
		(fill yes)
		(layer "In11.Cu")
		(net "M_H_CPU1_SA_DQ<15>")
	)
	(gr_poly
		(pts
			(xy 133.07949 -275.284946) (xy 133.0325 -275.132546) (xy 132.77088 -275.132546) (xy 132.72389 -275.284946)
			(xy 132.72389 -275.329396) (xy 133.07949 -275.329396)
		)
		(stroke
			(width 0)
			(type solid)
		)
		(fill yes)
		(layer "In11.Cu")
		(net "M_H_CPU1_SA_DQ<18>")
	)
	(gr_poly
		(pts
			(xy 133.07949 -272.029174) (xy 133.0325 -271.876774) (xy 132.77088 -271.876774) (xy 132.72389 -272.029174)
			(xy 132.72389 -272.073624) (xy 133.07949 -272.073624)
		)
		(stroke
			(width 0)
			(type solid)
		)
		(fill yes)
		(layer "In11.Cu")
		(net "M_H_CPU1_SA_DQ<22>")
	)
	(gr_poly
		(pts
			(xy 133.07949 -265.518646) (xy 133.0325 -265.366246) (xy 132.77088 -265.366246) (xy 132.72389 -265.518646)
			(xy 132.72389 -265.562842) (xy 133.07949 -265.562842)
		)
		(stroke
			(width 0)
			(type solid)
		)
		(fill yes)
		(layer "In11.Cu")
		(net "M_H_CPU1_SA_DQS_DN<3>")
	)
	(gr_poly
		(pts
			(xy 133.07949 -262.262874) (xy 133.0325 -262.110474) (xy 132.77088 -262.110474) (xy 132.72389 -262.262874)
			(xy 132.72389 -262.30707) (xy 133.07949 -262.30707)
		)
		(stroke
			(width 0)
			(type solid)
		)
		(fill yes)
		(layer "In11.Cu")
		(net "M_H_CPU1_SA_CB<2>")
	)
	(gr_poly
		(pts
			(xy 133.07949 -261.854442) (xy 133.07949 -261.810246) (xy 132.72389 -261.810246) (xy 132.72389 -261.854442)
			(xy 132.77088 -262.006842) (xy 133.0325 -262.006842)
		)
		(stroke
			(width 0)
			(type solid)
		)
		(fill yes)
		(layer "In11.Cu")
		(net "M_H_CPU1_SA_CB<1>")
	)
	(gr_poly
		(pts
			(xy 133.07949 -260.635242) (xy 133.0325 -260.482842) (xy 132.77088 -260.482842) (xy 132.72389 -260.635242)
			(xy 132.72389 -260.679438) (xy 133.07949 -260.679438)
		)
		(stroke
			(width 0)
			(type solid)
		)
		(fill yes)
		(layer "In11.Cu")
		(net "M_H_CPU1_SA_DQS_DN<4>")
	)
	(gr_poly
		(pts
			(xy 133.07949 -260.226302) (xy 133.07949 -260.182106) (xy 132.72389 -260.182106) (xy 132.72389 -260.226302)
			(xy 132.77088 -260.378702) (xy 133.0325 -260.378702)
		)
		(stroke
			(width 0)
			(type solid)
		)
		(fill yes)
		(layer "In11.Cu")
		(net "M_H_CPU1_SA_DQS_DN<9>")
	)
	(gr_poly
		(pts
			(xy 133.07949 -257.37947) (xy 133.0325 -257.22707) (xy 132.77088 -257.22707) (xy 132.72389 -257.37947)
			(xy 132.72389 -257.423666) (xy 133.07949 -257.423666)
		)
		(stroke
			(width 0)
			(type solid)
		)
		(fill yes)
		(layer "In11.Cu")
		(net "M_H_CPU1_ALERT_N")
	)
	(gr_poly
		(pts
			(xy 133.07949 -256.971038) (xy 133.07949 -256.926842) (xy 132.72389 -256.926842) (xy 132.72389 -256.971038)
			(xy 132.77088 -257.123438) (xy 133.0325 -257.123438)
		)
		(stroke
			(width 0)
			(type solid)
		)
		(fill yes)
		(layer "In11.Cu")
		(net "M_H_CPU1_SA_CS_N<0>")
	)
	(gr_poly
		(pts
			(xy 133.08203 -281.387804) (xy 133.08203 -281.343608) (xy 132.72643 -281.343608) (xy 132.72643 -281.387804)
			(xy 132.77342 -281.540204) (xy 133.03504 -281.540204)
		)
		(stroke
			(width 0)
			(type solid)
		)
		(fill yes)
		(layer "In11.Cu")
		(net "M_H_CPU1_SA_DQ<8>")
	)
	(gr_poly
		(pts
			(xy 133.08203 -278.132286) (xy 133.08203 -278.08809) (xy 132.72643 -278.08809) (xy 132.72643 -278.132286)
			(xy 132.77342 -278.284686) (xy 133.03504 -278.284686)
		)
		(stroke
			(width 0)
			(type solid)
		)
		(fill yes)
		(layer "In11.Cu")
		(net "M_H_CPU1_SA_DQ<12>")
	)
	(gr_poly
		(pts
			(xy 133.08203 -273.248882) (xy 133.08203 -273.204686) (xy 132.72643 -273.204686) (xy 132.72643 -273.248882)
			(xy 132.77342 -273.401282) (xy 133.03504 -273.401282)
		)
		(stroke
			(width 0)
			(type solid)
		)
		(fill yes)
		(layer "In11.Cu")
		(net "M_H_CPU1_SA_DQS_DN<7>")
	)
	(gr_poly
		(pts
			(xy 133.08203 -268.365478) (xy 133.08203 -268.321282) (xy 132.72643 -268.321282) (xy 132.72643 -268.365478)
			(xy 132.77342 -268.517878) (xy 133.03504 -268.517878)
		)
		(stroke
			(width 0)
			(type solid)
		)
		(fill yes)
		(layer "In11.Cu")
		(net "M_H_CPU1_SA_DQ<25>")
	)
	(gr_poly
		(pts
			(xy 133.08203 -263.482582) (xy 133.08203 -263.438132) (xy 132.72643 -263.438132) (xy 132.72643 -263.482582)
			(xy 132.77342 -263.634982) (xy 133.03504 -263.634982)
		)
		(stroke
			(width 0)
			(type solid)
		)
		(fill yes)
		(layer "In11.Cu")
		(net "M_H_CPU1_SA_DQ<29>")
	)
	(gr_poly
		(pts
			(xy 133.08203 -259.007102) (xy 133.03504 -258.854702) (xy 132.77342 -258.854702) (xy 132.72643 -259.007102)
			(xy 132.72643 -259.051552) (xy 133.08203 -259.051552)
		)
		(stroke
			(width 0)
			(type solid)
		)
		(fill yes)
		(layer "In11.Cu")
		(net "M_H_CPU1_SA_CB<6>")
	)
	(gr_poly
		(pts
			(xy 133.08203 -258.599178) (xy 133.08203 -258.554728) (xy 132.72643 -258.554728) (xy 132.72643 -258.599178)
			(xy 132.77342 -258.751578) (xy 133.03504 -258.751578)
		)
		(stroke
			(width 0)
			(type solid)
		)
		(fill yes)
		(layer "In11.Cu")
		(net "M_H_CPU1_SA_CB<5>")
	)
	(gr_poly
		(pts
			(xy 133.291326 -248.45899) (xy 133.32968 -248.436892) (xy 133.15188 -248.129044) (xy 133.113526 -248.151142)
			(xy 133.005068 -248.267982) (xy 133.135878 -248.49455)
		)
		(stroke
			(width 0)
			(type solid)
		)
		(fill yes)
		(layer "In11.Cu")
		(net "M_H_CPU1_SB_CA<2>")
	)
	(gr_poly
		(pts
			(xy 133.394704 -271.467072) (xy 133.433058 -271.444974) (xy 133.255258 -271.137126) (xy 133.216904 -271.159224)
			(xy 133.108446 -271.276064) (xy 133.239256 -271.502632)
		)
		(stroke
			(width 0)
			(type solid)
		)
		(fill yes)
		(layer "In11.Cu")
		(net "M_H_CPU1_SA_DQ<21>")
	)
	(gr_poly
		(pts
			(xy 133.399022 -266.591034) (xy 133.437376 -266.568936) (xy 133.259576 -266.261088) (xy 133.221222 -266.283186)
			(xy 133.112764 -266.400026) (xy 133.243574 -266.626594)
		)
		(stroke
			(width 0)
			(type solid)
		)
		(fill yes)
		(layer "In11.Cu")
		(net "M_H_CPU1_SA_DQS_DP<3>")
	)
	(gr_poly
		(pts
			(xy 133.401054 -269.850362) (xy 133.439408 -269.828264) (xy 133.261608 -269.520416) (xy 133.223254 -269.542514)
			(xy 133.114796 -269.659354) (xy 133.245606 -269.885922)
		)
		(stroke
			(width 0)
			(type solid)
		)
		(fill yes)
		(layer "In11.Cu")
		(net "M_H_CPU1_SA_DQ<24>")
	)
	(gr_poly
		(pts
			(xy 133.42747 -246.16029) (xy 133.42747 -246.116094) (xy 133.07187 -246.116094) (xy 133.07187 -246.16029)
			(xy 133.11886 -246.31269) (xy 133.38048 -246.31269)
		)
		(stroke
			(width 0)
			(type solid)
		)
		(fill yes)
		(layer "In11.Cu")
		(net "M_H_CPU1_SB_CA<6>")
	)
	(gr_poly
		(pts
			(xy 133.42747 -244.532658) (xy 133.42747 -244.488208) (xy 133.07187 -244.488208) (xy 133.07187 -244.532658)
			(xy 133.11886 -244.685058) (xy 133.38048 -244.685058)
		)
		(stroke
			(width 0)
			(type solid)
		)
		(fill yes)
		(layer "In11.Cu")
		(net "M_H_CPU1_SB_CB<6>")
	)
	(gr_poly
		(pts
			(xy 133.42747 -241.276886) (xy 133.42747 -241.23269) (xy 133.07187 -241.23269) (xy 133.07187 -241.276886)
			(xy 133.11886 -241.429286) (xy 133.38048 -241.429286)
		)
		(stroke
			(width 0)
			(type solid)
		)
		(fill yes)
		(layer "In11.Cu")
		(net "M_H_CPU1_SB_CB<0>")
	)
	(gr_poly
		(pts
			(xy 133.42747 -240.057178) (xy 133.38048 -239.904778) (xy 133.11886 -239.904778) (xy 133.07187 -240.057178)
			(xy 133.07187 -240.101628) (xy 133.42747 -240.101628)
		)
		(stroke
			(width 0)
			(type solid)
		)
		(fill yes)
		(layer "In11.Cu")
		(net "M_H_CPU1_SB_CB<3>")
	)
	(gr_poly
		(pts
			(xy 133.42747 -239.649254) (xy 133.42747 -239.604804) (xy 133.07187 -239.604804) (xy 133.07187 -239.649254)
			(xy 133.11886 -239.801654) (xy 133.38048 -239.801654)
		)
		(stroke
			(width 0)
			(type solid)
		)
		(fill yes)
		(layer "In11.Cu")
		(net "M_H_CPU1_SB_DQ<0>")
	)
	(gr_poly
		(pts
			(xy 133.42747 -236.39399) (xy 133.42747 -236.34954) (xy 133.07187 -236.34954) (xy 133.07187 -236.39399)
			(xy 133.11886 -236.54639) (xy 133.38048 -236.54639)
		)
		(stroke
			(width 0)
			(type solid)
		)
		(fill yes)
		(layer "In11.Cu")
		(net "M_H_CPU1_SB_DQ<4>")
	)
	(gr_poly
		(pts
			(xy 133.42747 -235.174282) (xy 133.38048 -235.021882) (xy 133.11886 -235.021882) (xy 133.07187 -235.174282)
			(xy 133.07187 -235.218478) (xy 133.42747 -235.218478)
		)
		(stroke
			(width 0)
			(type solid)
		)
		(fill yes)
		(layer "In11.Cu")
		(net "M_H_CPU1_SB_DQ<7>")
	)
	(gr_poly
		(pts
			(xy 133.42747 -234.76585) (xy 133.42747 -234.721654) (xy 133.07187 -234.721654) (xy 133.07187 -234.76585)
			(xy 133.11886 -234.91825) (xy 133.38048 -234.91825)
		)
		(stroke
			(width 0)
			(type solid)
		)
		(fill yes)
		(layer "In11.Cu")
		(net "M_H_CPU1_SB_DQ<8>")
	)
	(gr_poly
		(pts
			(xy 133.42747 -231.510586) (xy 133.42747 -231.466136) (xy 133.07187 -231.466136) (xy 133.07187 -231.510586)
			(xy 133.11886 -231.662986) (xy 133.38048 -231.662986)
		)
		(stroke
			(width 0)
			(type solid)
		)
		(fill yes)
		(layer "In11.Cu")
		(net "M_H_CPU1_SB_DQ<12>")
	)
	(gr_poly
		(pts
			(xy 133.42747 -230.290878) (xy 133.38048 -230.138478) (xy 133.11886 -230.138478) (xy 133.07187 -230.290878)
			(xy 133.07187 -230.335074) (xy 133.42747 -230.335074)
		)
		(stroke
			(width 0)
			(type solid)
		)
		(fill yes)
		(layer "In11.Cu")
		(net "M_H_CPU1_SB_DQ<15>")
	)
	(gr_poly
		(pts
			(xy 133.42747 -229.882446) (xy 133.42747 -229.83825) (xy 133.07187 -229.83825) (xy 133.07187 -229.882446)
			(xy 133.11886 -230.034846) (xy 133.38048 -230.034846)
		)
		(stroke
			(width 0)
			(type solid)
		)
		(fill yes)
		(layer "In11.Cu")
		(net "M_H_CPU1_SB_DQ<26>")
	)
	(gr_poly
		(pts
			(xy 133.42747 -227.035106) (xy 133.38048 -226.882706) (xy 133.11886 -226.882706) (xy 133.07187 -227.035106)
			(xy 133.07187 -227.079556) (xy 133.42747 -227.079556)
		)
		(stroke
			(width 0)
			(type solid)
		)
		(fill yes)
		(layer "In11.Cu")
		(net "M_H_CPU1_SB_DQS_DN<3>")
	)
	(gr_poly
		(pts
			(xy 133.42747 -226.627182) (xy 133.42747 -226.582732) (xy 133.07187 -226.582732) (xy 133.07187 -226.627182)
			(xy 133.11886 -226.779582) (xy 133.38048 -226.779582)
		)
		(stroke
			(width 0)
			(type solid)
		)
		(fill yes)
		(layer "In11.Cu")
		(net "M_H_CPU1_SB_DQ<30>")
	)
	(gr_poly
		(pts
			(xy 133.42747 -225.407474) (xy 133.38048 -225.255074) (xy 133.11886 -225.255074) (xy 133.07187 -225.407474)
			(xy 133.07187 -225.45167) (xy 133.42747 -225.45167)
		)
		(stroke
			(width 0)
			(type solid)
		)
		(fill yes)
		(layer "In11.Cu")
		(net "M_H_CPU1_SB_DQ<29>")
	)
	(gr_poly
		(pts
			(xy 133.433312 -236.802422) (xy 133.386322 -236.650022) (xy 133.124702 -236.650022) (xy 133.077712 -236.802422)
			(xy 133.077712 -236.846872) (xy 133.433312 -236.846872)
		)
		(stroke
			(width 0)
			(type solid)
		)
		(fill yes)
		(layer "In11.Cu")
		(net "M_H_CPU1_SB_DQS_DP<5>")
	)
	(gr_poly
		(pts
			(xy 133.433312 -231.919018) (xy 133.386322 -231.766618) (xy 133.124702 -231.766618) (xy 133.077712 -231.919018)
			(xy 133.077712 -231.963468) (xy 133.433312 -231.963468)
		)
		(stroke
			(width 0)
			(type solid)
		)
		(fill yes)
		(layer "In11.Cu")
		(net "M_H_CPU1_SB_DQS_DP<6>")
	)
	(gr_poly
		(pts
			(xy 133.433566 -249.415554) (xy 133.433566 -249.371358) (xy 133.077966 -249.371358) (xy 133.077966 -249.415554)
			(xy 133.124956 -249.567954) (xy 133.386576 -249.567954)
		)
		(stroke
			(width 0)
			(type solid)
		)
		(fill yes)
		(layer "In11.Cu")
		(net "M_H_CPU1_SB_CA<0>")
	)
	(gr_poly
		(pts
			(xy 133.433566 -243.313458) (xy 133.386576 -243.161058) (xy 133.124956 -243.161058) (xy 133.077966 -243.313458)
			(xy 133.077966 -243.357654) (xy 133.433566 -243.357654)
		)
		(stroke
			(width 0)
			(type solid)
		)
		(fill yes)
		(layer "In11.Cu")
		(net "M_H_CPU1_SB_CB<5>")
	)
	(gr_poly
		(pts
			(xy 133.433566 -242.904518) (xy 133.433566 -242.860322) (xy 133.077966 -242.860322) (xy 133.077966 -242.904518)
			(xy 133.124956 -243.056918) (xy 133.386576 -243.056918)
		)
		(stroke
			(width 0)
			(type solid)
		)
		(fill yes)
		(layer "In11.Cu")
		(net "M_H_CPU1_SB_DQS_DP<9>")
	)
	(gr_poly
		(pts
			(xy 133.433566 -241.685826) (xy 133.386576 -241.533426) (xy 133.124956 -241.533426) (xy 133.077966 -241.685826)
			(xy 133.077966 -241.730022) (xy 133.433566 -241.730022)
		)
		(stroke
			(width 0)
			(type solid)
		)
		(fill yes)
		(layer "In11.Cu")
		(net "M_H_CPU1_SB_DQS_DP<4>")
	)
	(gr_poly
		(pts
			(xy 133.433566 -238.430054) (xy 133.386576 -238.277654) (xy 133.124956 -238.277654) (xy 133.077966 -238.430054)
			(xy 133.077966 -238.47425) (xy 133.433566 -238.47425)
		)
		(stroke
			(width 0)
			(type solid)
		)
		(fill yes)
		(layer "In11.Cu")
		(net "M_H_CPU1_SB_DQ<3>")
	)
	(gr_poly
		(pts
			(xy 133.433566 -233.54665) (xy 133.386576 -233.39425) (xy 133.124956 -233.39425) (xy 133.077966 -233.54665)
			(xy 133.077966 -233.590846) (xy 133.433566 -233.590846)
		)
		(stroke
			(width 0)
			(type solid)
		)
		(fill yes)
		(layer "In11.Cu")
		(net "M_H_CPU1_SB_DQ<11>")
	)
	(gr_poly
		(pts
			(xy 133.433566 -228.663246) (xy 133.386576 -228.510846) (xy 133.124956 -228.510846) (xy 133.077966 -228.663246)
			(xy 133.077966 -228.707696) (xy 133.433566 -228.707696)
		)
		(stroke
			(width 0)
			(type solid)
		)
		(fill yes)
		(layer "In11.Cu")
		(net "M_H_CPU1_SB_DQ<25>")
	)
	(gr_poly
		(pts
			(xy 133.433566 -228.254814) (xy 133.433566 -228.210364) (xy 133.077966 -228.210364) (xy 133.077966 -228.254814)
			(xy 133.124956 -228.407214) (xy 133.386576 -228.407214)
		)
		(stroke
			(width 0)
			(type solid)
		)
		(fill yes)
		(layer "In11.Cu")
		(net "M_H_CPU1_SB_DQS_DN<8>")
	)
	(gr_poly
		(pts
			(xy 133.439408 -246.568722) (xy 133.392418 -246.416322) (xy 133.130798 -246.416322) (xy 133.083808 -246.568722)
			(xy 133.083808 -246.612918) (xy 133.439408 -246.612918)
		)
		(stroke
			(width 0)
			(type solid)
		)
		(fill yes)
		(layer "In11.Cu")
		(net "M_H_CPU1_SB_CA<5>")
	)
	(gr_poly
		(pts
			(xy 133.441948 -238.021622) (xy 133.441948 -237.977172) (xy 133.086348 -237.977172) (xy 133.086348 -238.021622)
			(xy 133.133338 -238.174022) (xy 133.394958 -238.174022)
		)
		(stroke
			(width 0)
			(type solid)
		)
		(fill yes)
		(layer "In11.Cu")
		(net "M_H_CPU1_SB_DQS_DP<0>")
	)
	(gr_poly
		(pts
			(xy 133.441948 -233.138218) (xy 133.441948 -233.093768) (xy 133.086348 -233.093768) (xy 133.086348 -233.138218)
			(xy 133.133338 -233.290618) (xy 133.394958 -233.290618)
		)
		(stroke
			(width 0)
			(type solid)
		)
		(fill yes)
		(layer "In11.Cu")
		(net "M_H_CPU1_SB_DQS_DP<1>")
	)
	(gr_poly
		(pts
			(xy 133.507734 -265.969242) (xy 133.616192 -265.852402) (xy 133.485382 -265.625834) (xy 133.329934 -265.661394)
			(xy 133.29158 -265.683492) (xy 133.46938 -265.99134)
		)
		(stroke
			(width 0)
			(type solid)
		)
		(fill yes)
		(layer "In11.Cu")
		(net "M_H_CPU1_SA_DQS_DN<3>")
	)
	(gr_poly
		(pts
			(xy 133.509766 -270.856456) (xy 133.618224 -270.739616) (xy 133.487414 -270.513048) (xy 133.331966 -270.548608)
			(xy 133.293612 -270.570706) (xy 133.471412 -270.878554)
		)
		(stroke
			(width 0)
			(type solid)
		)
		(fill yes)
		(layer "In11.Cu")
		(net "M_H_CPU1_SA_DQ<23>")
	)
	(gr_poly
		(pts
			(xy 133.51002 -269.22857) (xy 133.618478 -269.11173) (xy 133.487668 -268.885162) (xy 133.33222 -268.920722)
			(xy 133.293866 -268.94282) (xy 133.471666 -269.250668)
		)
		(stroke
			(width 0)
			(type solid)
		)
		(fill yes)
		(layer "In11.Cu")
		(net "M_H_CPU1_SA_DQ<26>")
	)
	(gr_poly
		(pts
			(xy 133.534912 -280.98242) (xy 133.487922 -280.83002) (xy 133.226302 -280.83002) (xy 133.179312 -280.98242)
			(xy 133.179312 -281.026616) (xy 133.534912 -281.026616)
		)
		(stroke
			(width 0)
			(type solid)
		)
		(fill yes)
		(layer "In11.Cu")
		(net "M_H_CPU1_SA_DQ<10>")
	)
	(gr_poly
		(pts
			(xy 133.534912 -280.574242) (xy 133.534912 -280.529792) (xy 133.179312 -280.529792) (xy 133.179312 -280.574242)
			(xy 133.226302 -280.726642) (xy 133.487922 -280.726642)
		)
		(stroke
			(width 0)
			(type solid)
		)
		(fill yes)
		(layer "In11.Cu")
		(net "M_H_CPU1_SA_DQ<9>")
	)
	(gr_poly
		(pts
			(xy 133.534912 -277.726394) (xy 133.487922 -277.573994) (xy 133.226302 -277.573994) (xy 133.179312 -277.726394)
			(xy 133.179312 -277.770844) (xy 133.534912 -277.770844)
		)
		(stroke
			(width 0)
			(type solid)
		)
		(fill yes)
		(layer "In11.Cu")
		(net "M_H_CPU1_SA_DQ<14>")
	)
	(gr_poly
		(pts
			(xy 133.534912 -277.318216) (xy 133.534912 -277.27402) (xy 133.179312 -277.27402) (xy 133.179312 -277.318216)
			(xy 133.226302 -277.470616) (xy 133.487922 -277.470616)
		)
		(stroke
			(width 0)
			(type solid)
		)
		(fill yes)
		(layer "In11.Cu")
		(net "M_H_CPU1_SA_DQ<13>")
	)
	(gr_poly
		(pts
			(xy 133.534912 -272.843498) (xy 133.487922 -272.691098) (xy 133.226302 -272.691098) (xy 133.179312 -272.843498)
			(xy 133.179312 -272.887694) (xy 133.534912 -272.887694)
		)
		(stroke
			(width 0)
			(type solid)
		)
		(fill yes)
		(layer "In11.Cu")
		(net "M_H_CPU1_SA_DQS_DP<7>")
	)
	(gr_poly
		(pts
			(xy 133.534912 -272.435066) (xy 133.534912 -272.39087) (xy 133.179312 -272.39087) (xy 133.179312 -272.435066)
			(xy 133.226302 -272.587466) (xy 133.487922 -272.587466)
		)
		(stroke
			(width 0)
			(type solid)
		)
		(fill yes)
		(layer "In11.Cu")
		(net "M_H_CPU1_SA_DQ<20>")
	)
	(gr_poly
		(pts
			(xy 133.534912 -267.960094) (xy 133.487922 -267.807694) (xy 133.226302 -267.807694) (xy 133.179312 -267.960094)
			(xy 133.179312 -268.00429) (xy 133.534912 -268.00429)
		)
		(stroke
			(width 0)
			(type solid)
		)
		(fill yes)
		(layer "In11.Cu")
		(net "M_H_CPU1_SA_DQ<27>")
	)
	(gr_poly
		(pts
			(xy 133.534912 -263.07669) (xy 133.487922 -262.92429) (xy 133.226302 -262.92429) (xy 133.179312 -263.07669)
			(xy 133.179312 -263.120886) (xy 133.534912 -263.120886)
		)
		(stroke
			(width 0)
			(type solid)
		)
		(fill yes)
		(layer "In11.Cu")
		(net "M_H_CPU1_SA_DQ<31>")
	)
	(gr_poly
		(pts
			(xy 133.534912 -262.668258) (xy 133.534912 -262.624062) (xy 133.179312 -262.624062) (xy 133.179312 -262.668258)
			(xy 133.226302 -262.820658) (xy 133.487922 -262.820658)
		)
		(stroke
			(width 0)
			(type solid)
		)
		(fill yes)
		(layer "In11.Cu")
		(net "M_H_CPU1_SA_CB<0>")
	)
	(gr_poly
		(pts
			(xy 133.534912 -261.449058) (xy 133.487922 -261.296658) (xy 133.226302 -261.296658) (xy 133.179312 -261.449058)
			(xy 133.179312 -261.493254) (xy 133.534912 -261.493254)
		)
		(stroke
			(width 0)
			(type solid)
		)
		(fill yes)
		(layer "In11.Cu")
		(net "M_H_CPU1_SA_CB<3>")
	)
	(gr_poly
		(pts
			(xy 133.534912 -259.412994) (xy 133.534912 -259.368544) (xy 133.179312 -259.368544) (xy 133.179312 -259.412994)
			(xy 133.226302 -259.565394) (xy 133.487922 -259.565394)
		)
		(stroke
			(width 0)
			(type solid)
		)
		(fill yes)
		(layer "In11.Cu")
		(net "M_H_CPU1_SA_CB<4>")
	)
	(gr_poly
		(pts
			(xy 133.534912 -256.565654) (xy 133.487922 -256.413254) (xy 133.226302 -256.413254) (xy 133.179312 -256.565654)
			(xy 133.179312 -256.60985) (xy 133.534912 -256.60985)
		)
		(stroke
			(width 0)
			(type solid)
		)
		(fill yes)
		(layer "In11.Cu")
		(net "M_H_CPU1_SA_CS_N<1>")
	)
	(gr_poly
		(pts
			(xy 133.537452 -279.354788) (xy 133.490462 -279.202388) (xy 133.228842 -279.202388) (xy 133.181852 -279.354788)
			(xy 133.181852 -279.398984) (xy 133.537452 -279.398984)
		)
		(stroke
			(width 0)
			(type solid)
		)
		(fill yes)
		(layer "In11.Cu")
		(net "M_H_CPU1_SA_DQS_DN<1>")
	)
	(gr_poly
		(pts
			(xy 133.537452 -278.945848) (xy 133.537452 -278.901652) (xy 133.181852 -278.901652) (xy 133.181852 -278.945848)
			(xy 133.228842 -279.098248) (xy 133.490462 -279.098248)
		)
		(stroke
			(width 0)
			(type solid)
		)
		(fill yes)
		(layer "In11.Cu")
		(net "M_H_CPU1_SA_DQS_DN<6>")
	)
	(gr_poly
		(pts
			(xy 133.537452 -274.062698) (xy 133.537452 -274.018248) (xy 133.181852 -274.018248) (xy 133.181852 -274.062698)
			(xy 133.228842 -274.215098) (xy 133.490462 -274.215098)
		)
		(stroke
			(width 0)
			(type solid)
		)
		(fill yes)
		(layer "In11.Cu")
		(net "M_H_CPU1_SA_DQS_DP<2>")
	)
	(gr_poly
		(pts
			(xy 133.537452 -264.29589) (xy 133.537452 -264.251694) (xy 133.181852 -264.251694) (xy 133.181852 -264.29589)
			(xy 133.228842 -264.44829) (xy 133.490462 -264.44829)
		)
		(stroke
			(width 0)
			(type solid)
		)
		(fill yes)
		(layer "In11.Cu")
		(net "M_H_CPU1_SA_DQ<28>")
	)
	(gr_poly
		(pts
			(xy 133.537452 -258.193286) (xy 133.490462 -258.040886) (xy 133.228842 -258.040886) (xy 133.181852 -258.193286)
			(xy 133.181852 -258.237482) (xy 133.537452 -258.237482)
		)
		(stroke
			(width 0)
			(type solid)
		)
		(fill yes)
		(layer "In11.Cu")
		(net "M_H_CPU1_SA_CB<7>")
	)
	(gr_poly
		(pts
			(xy 133.537452 -257.784854) (xy 133.537452 -257.740658) (xy 133.181852 -257.740658) (xy 133.181852 -257.784854)
			(xy 133.228842 -257.937254) (xy 133.490462 -257.937254)
		)
		(stroke
			(width 0)
			(type solid)
		)
		(fill yes)
		(layer "In11.Cu")
		(net "M_E_CPU1_ALERT_N")
	)
	(gr_poly
		(pts
			(xy 133.537452 -254.529082) (xy 133.537452 -254.484886) (xy 133.181852 -254.484886) (xy 133.181852 -254.529082)
			(xy 133.228842 -254.681482) (xy 133.490462 -254.681482)
		)
		(stroke
			(width 0)
			(type solid)
		)
		(fill yes)
		(layer "In11.Cu")
		(net "M_H_CPU1_SA_CA<2>")
	)
	(gr_poly
		(pts
			(xy 133.543294 -275.690584) (xy 133.543294 -275.646134) (xy 133.187694 -275.646134) (xy 133.187694 -275.690584)
			(xy 133.234684 -275.842984) (xy 133.496304 -275.842984)
		)
		(stroke
			(width 0)
			(type solid)
		)
		(fill yes)
		(layer "In11.Cu")
		(net "M_H_CPU1_SA_DQ<16>")
	)
	(gr_poly
		(pts
			(xy 133.543294 -261.040626) (xy 133.543294 -260.996176) (xy 133.187694 -260.996176) (xy 133.187694 -261.040626)
			(xy 133.234684 -261.193026) (xy 133.496304 -261.193026)
		)
		(stroke
			(width 0)
			(type solid)
		)
		(fill yes)
		(layer "In11.Cu")
		(net "M_H_CPU1_SA_DQS_DP<4>")
	)
	(gr_poly
		(pts
			(xy 133.543294 -259.821426) (xy 133.496304 -259.669026) (xy 133.234684 -259.669026) (xy 133.187694 -259.821426)
			(xy 133.187694 -259.865622) (xy 133.543294 -259.865622)
		)
		(stroke
			(width 0)
			(type solid)
		)
		(fill yes)
		(layer "In11.Cu")
		(net "M_H_CPU1_SA_DQS_DP<9>")
	)
	(gr_poly
		(pts
			(xy 133.543294 -256.157222) (xy 133.543294 -256.112772) (xy 133.187694 -256.112772) (xy 133.187694 -256.157222)
			(xy 133.234684 -256.309622) (xy 133.496304 -256.309622)
		)
		(stroke
			(width 0)
			(type solid)
		)
		(fill yes)
		(layer "In11.Cu")
		(net "M_H_CPU1_SA_CS_N<2>")
	)
	(gr_poly
		(pts
			(xy 133.54939 -274.47113) (xy 133.5024 -274.31873) (xy 133.24078 -274.31873) (xy 133.19379 -274.47113)
			(xy 133.19379 -274.51558) (xy 133.54939 -274.51558)
		)
		(stroke
			(width 0)
			(type solid)
		)
		(fill yes)
		(layer "In11.Cu")
		(net "M_H_CPU1_SA_DQ<19>")
	)
	(gr_poly
		(pts
			(xy 133.54939 -264.70483) (xy 133.5024 -264.55243) (xy 133.24078 -264.55243) (xy 133.19379 -264.70483)
			(xy 133.19379 -264.749026) (xy 133.54939 -264.749026)
		)
		(stroke
			(width 0)
			(type solid)
		)
		(fill yes)
		(layer "In11.Cu")
		(net "M_H_CPU1_SA_DQS_DP<8>")
	)
	(gr_poly
		(pts
			(xy 133.54939 -254.938022) (xy 133.5024 -254.785622) (xy 133.24078 -254.785622) (xy 133.19379 -254.938022)
			(xy 133.19379 -254.982218) (xy 133.54939 -254.982218)
		)
		(stroke
			(width 0)
			(type solid)
		)
		(fill yes)
		(layer "In11.Cu")
		(net "M_H_CPU1_SA_CA<0>")
	)
	(gr_poly
		(pts
			(xy 133.864604 -270.653002) (xy 133.902958 -270.630904) (xy 133.725158 -270.323056) (xy 133.686804 -270.345154)
			(xy 133.578346 -270.461994) (xy 133.709156 -270.688562)
		)
		(stroke
			(width 0)
			(type solid)
		)
		(fill yes)
		(layer "In11.Cu")
		(net "M_H_CPU1_SA_DQ<24>")
	)
	(gr_poly
		(pts
			(xy 133.869938 -267.406628) (xy 133.908292 -267.38453) (xy 133.730492 -267.076682) (xy 133.692138 -267.09878)
			(xy 133.58368 -267.21562) (xy 133.71449 -267.442188)
		)
		(stroke
			(width 0)
			(type solid)
		)
		(fill yes)
		(layer "In11.Cu")
		(net "M_H_CPU1_SA_DQS_DP<3>")
	)
	(gr_poly
		(pts
			(xy 133.870192 -269.035022) (xy 133.908546 -269.012924) (xy 133.730746 -268.705076) (xy 133.692392 -268.727174)
			(xy 133.583934 -268.844014) (xy 133.714744 -269.070582)
		)
		(stroke
			(width 0)
			(type solid)
		)
		(fill yes)
		(layer "In11.Cu")
		(net "M_H_CPU1_SA_DQ<25>")
	)
	(gr_poly
		(pts
			(xy 133.89737 -246.974106) (xy 133.89737 -246.92991) (xy 133.54177 -246.92991) (xy 133.54177 -246.974106)
			(xy 133.58876 -247.126506) (xy 133.85038 -247.126506)
		)
		(stroke
			(width 0)
			(type solid)
		)
		(fill yes)
		(layer "In11.Cu")
		(net "M_H_CPU1_SB_CA<4>")
	)
	(gr_poly
		(pts
			(xy 133.89737 -237.61573) (xy 133.85038 -237.46333) (xy 133.58876 -237.46333) (xy 133.54177 -237.61573)
			(xy 133.54177 -237.66018) (xy 133.89737 -237.66018)
		)
		(stroke
			(width 0)
			(type solid)
		)
		(fill yes)
		(layer "In11.Cu")
		(net "M_H_CPU1_SB_DQS_DN<0>")
	)
	(gr_poly
		(pts
			(xy 133.89737 -237.207806) (xy 133.89737 -237.163356) (xy 133.54177 -237.163356) (xy 133.54177 -237.207806)
			(xy 133.58876 -237.360206) (xy 133.85038 -237.360206)
		)
		(stroke
			(width 0)
			(type solid)
		)
		(fill yes)
		(layer "In11.Cu")
		(net "M_H_CPU1_SB_DQS_DN<5>")
	)
	(gr_poly
		(pts
			(xy 133.89737 -232.732326) (xy 133.85038 -232.579926) (xy 133.58876 -232.579926) (xy 133.54177 -232.732326)
			(xy 133.54177 -232.776776) (xy 133.89737 -232.776776)
		)
		(stroke
			(width 0)
			(type solid)
		)
		(fill yes)
		(layer "In11.Cu")
		(net "M_H_CPU1_SB_DQS_DN<1>")
	)
	(gr_poly
		(pts
			(xy 133.89737 -232.324402) (xy 133.89737 -232.279952) (xy 133.54177 -232.279952) (xy 133.54177 -232.324402)
			(xy 133.58876 -232.476802) (xy 133.85038 -232.476802)
		)
		(stroke
			(width 0)
			(type solid)
		)
		(fill yes)
		(layer "In11.Cu")
		(net "M_H_CPU1_SB_DQS_DN<6>")
	)
	(gr_poly
		(pts
			(xy 133.903466 -249.010678) (xy 133.856476 -248.858278) (xy 133.594856 -248.858278) (xy 133.547866 -249.010678)
			(xy 133.547866 -249.054874) (xy 133.903466 -249.054874)
		)
		(stroke
			(width 0)
			(type solid)
		)
		(fill yes)
		(layer "In11.Cu")
		(net "M_H_CPU1_SB_CA<1>")
	)
	(gr_poly
		(pts
			(xy 133.903466 -248.601738) (xy 133.903466 -248.557542) (xy 133.547866 -248.557542) (xy 133.547866 -248.601738)
			(xy 133.594856 -248.754138) (xy 133.856476 -248.754138)
		)
		(stroke
			(width 0)
			(type solid)
		)
		(fill yes)
		(layer "In11.Cu")
		(net "M_H_CPU1_SB_CA<2>")
	)
	(gr_poly
		(pts
			(xy 133.903466 -245.754906) (xy 133.856476 -245.602506) (xy 133.594856 -245.602506) (xy 133.547866 -245.754906)
			(xy 133.547866 -245.799356) (xy 133.903466 -245.799356)
		)
		(stroke
			(width 0)
			(type solid)
		)
		(fill yes)
		(layer "In11.Cu")
		(net "M_H_CPU1_SB_PAR")
	)
	(gr_poly
		(pts
			(xy 133.903466 -244.127274) (xy 133.856476 -243.974874) (xy 133.594856 -243.974874) (xy 133.547866 -244.127274)
			(xy 133.547866 -244.17147) (xy 133.903466 -244.17147)
		)
		(stroke
			(width 0)
			(type solid)
		)
		(fill yes)
		(layer "In11.Cu")
		(net "M_H_CPU1_SB_CB<4>")
	)
	(gr_poly
		(pts
			(xy 133.903466 -243.718334) (xy 133.903466 -243.674138) (xy 133.547866 -243.674138) (xy 133.547866 -243.718334)
			(xy 133.594856 -243.870734) (xy 133.856476 -243.870734)
		)
		(stroke
			(width 0)
			(type solid)
		)
		(fill yes)
		(layer "In11.Cu")
		(net "M_H_CPU1_SB_CB<7>")
	)
	(gr_poly
		(pts
			(xy 133.903466 -242.499134) (xy 133.856476 -242.346734) (xy 133.594856 -242.346734) (xy 133.547866 -242.499134)
			(xy 133.547866 -242.543584) (xy 133.903466 -242.543584)
		)
		(stroke
			(width 0)
			(type solid)
		)
		(fill yes)
		(layer "In11.Cu")
		(net "M_H_CPU1_SB_DQS_DN<9>")
	)
	(gr_poly
		(pts
			(xy 133.903466 -242.090702) (xy 133.903466 -242.046252) (xy 133.547866 -242.046252) (xy 133.547866 -242.090702)
			(xy 133.594856 -242.243102) (xy 133.856476 -242.243102)
		)
		(stroke
			(width 0)
			(type solid)
		)
		(fill yes)
		(layer "In11.Cu")
		(net "M_H_CPU1_SB_DQS_DN<4>")
	)
	(gr_poly
		(pts
			(xy 133.903466 -240.871502) (xy 133.856476 -240.719102) (xy 133.594856 -240.719102) (xy 133.547866 -240.871502)
			(xy 133.547866 -240.915952) (xy 133.903466 -240.915952)
		)
		(stroke
			(width 0)
			(type solid)
		)
		(fill yes)
		(layer "In11.Cu")
		(net "M_H_CPU1_SB_CB<2>")
	)
	(gr_poly
		(pts
			(xy 133.903466 -240.46307) (xy 133.903466 -240.41862) (xy 133.547866 -240.41862) (xy 133.547866 -240.46307)
			(xy 133.594856 -240.61547) (xy 133.856476 -240.61547)
		)
		(stroke
			(width 0)
			(type solid)
		)
		(fill yes)
		(layer "In11.Cu")
		(net "M_H_CPU1_SB_CB<1>")
	)
	(gr_poly
		(pts
			(xy 133.903466 -239.24387) (xy 133.856476 -239.09147) (xy 133.594856 -239.09147) (xy 133.547866 -239.24387)
			(xy 133.547866 -239.288066) (xy 133.903466 -239.288066)
		)
		(stroke
			(width 0)
			(type solid)
		)
		(fill yes)
		(layer "In11.Cu")
		(net "M_H_CPU1_SB_DQ<2>")
	)
	(gr_poly
		(pts
			(xy 133.903466 -238.83493) (xy 133.903466 -238.790734) (xy 133.547866 -238.790734) (xy 133.547866 -238.83493)
			(xy 133.594856 -238.98733) (xy 133.856476 -238.98733)
		)
		(stroke
			(width 0)
			(type solid)
		)
		(fill yes)
		(layer "In11.Cu")
		(net "M_H_CPU1_SB_DQ<1>")
	)
	(gr_poly
		(pts
			(xy 133.903466 -235.988098) (xy 133.856476 -235.835698) (xy 133.594856 -235.835698) (xy 133.547866 -235.988098)
			(xy 133.547866 -236.032548) (xy 133.903466 -236.032548)
		)
		(stroke
			(width 0)
			(type solid)
		)
		(fill yes)
		(layer "In11.Cu")
		(net "M_H_CPU1_SB_DQ<6>")
	)
	(gr_poly
		(pts
			(xy 133.903466 -235.579666) (xy 133.903466 -235.535216) (xy 133.547866 -235.535216) (xy 133.547866 -235.579666)
			(xy 133.594856 -235.732066) (xy 133.856476 -235.732066)
		)
		(stroke
			(width 0)
			(type solid)
		)
		(fill yes)
		(layer "In11.Cu")
		(net "M_H_CPU1_SB_DQ<5>")
	)
	(gr_poly
		(pts
			(xy 133.903466 -234.360466) (xy 133.856476 -234.208066) (xy 133.594856 -234.208066) (xy 133.547866 -234.360466)
			(xy 133.547866 -234.404916) (xy 133.903466 -234.404916)
		)
		(stroke
			(width 0)
			(type solid)
		)
		(fill yes)
		(layer "In11.Cu")
		(net "M_H_CPU1_SB_DQ<10>")
	)
	(gr_poly
		(pts
			(xy 133.903466 -233.952034) (xy 133.903466 -233.907584) (xy 133.547866 -233.907584) (xy 133.547866 -233.952034)
			(xy 133.594856 -234.104434) (xy 133.856476 -234.104434)
		)
		(stroke
			(width 0)
			(type solid)
		)
		(fill yes)
		(layer "In11.Cu")
		(net "M_H_CPU1_SB_DQ<9>")
	)
	(gr_poly
		(pts
			(xy 133.903466 -231.104694) (xy 133.856476 -230.952294) (xy 133.594856 -230.952294) (xy 133.547866 -231.104694)
			(xy 133.547866 -231.149144) (xy 133.903466 -231.149144)
		)
		(stroke
			(width 0)
			(type solid)
		)
		(fill yes)
		(layer "In11.Cu")
		(net "M_H_CPU1_SB_DQ<14>")
	)
	(gr_poly
		(pts
			(xy 133.903466 -230.696262) (xy 133.903466 -230.651812) (xy 133.547866 -230.651812) (xy 133.547866 -230.696262)
			(xy 133.594856 -230.848662) (xy 133.856476 -230.848662)
		)
		(stroke
			(width 0)
			(type solid)
		)
		(fill yes)
		(layer "In11.Cu")
		(net "M_H_CPU1_SB_DQ<13>")
	)
	(gr_poly
		(pts
			(xy 133.903466 -229.477062) (xy 133.856476 -229.324662) (xy 133.594856 -229.324662) (xy 133.547866 -229.477062)
			(xy 133.547866 -229.521512) (xy 133.903466 -229.521512)
		)
		(stroke
			(width 0)
			(type solid)
		)
		(fill yes)
		(layer "In11.Cu")
		(net "M_H_CPU1_SB_DQ<24>")
	)
	(gr_poly
		(pts
			(xy 133.903466 -229.06863) (xy 133.903466 -229.02418) (xy 133.547866 -229.02418) (xy 133.547866 -229.06863)
			(xy 133.594856 -229.22103) (xy 133.856476 -229.22103)
		)
		(stroke
			(width 0)
			(type solid)
		)
		(fill yes)
		(layer "In11.Cu")
		(net "M_H_CPU1_SB_DQ<27>")
	)
	(gr_poly
		(pts
			(xy 133.903466 -227.84943) (xy 133.856476 -227.69703) (xy 133.594856 -227.69703) (xy 133.547866 -227.84943)
			(xy 133.547866 -227.893626) (xy 133.903466 -227.893626)
		)
		(stroke
			(width 0)
			(type solid)
		)
		(fill yes)
		(layer "In11.Cu")
		(net "M_H_CPU1_SB_DQS_DP<8>")
	)
	(gr_poly
		(pts
			(xy 133.903466 -227.44049) (xy 133.903466 -227.396294) (xy 133.547866 -227.396294) (xy 133.547866 -227.44049)
			(xy 133.594856 -227.59289) (xy 133.856476 -227.59289)
		)
		(stroke
			(width 0)
			(type solid)
		)
		(fill yes)
		(layer "In11.Cu")
		(net "M_H_CPU1_SB_DQS_DP<3>")
	)
	(gr_poly
		(pts
			(xy 133.903466 -226.221798) (xy 133.856476 -226.069398) (xy 133.594856 -226.069398) (xy 133.547866 -226.221798)
			(xy 133.547866 -226.265994) (xy 133.903466 -226.265994)
		)
		(stroke
			(width 0)
			(type solid)
		)
		(fill yes)
		(layer "In11.Cu")
		(net "M_H_CPU1_SB_DQ<28>")
	)
	(gr_poly
		(pts
			(xy 133.903466 -225.812858) (xy 133.903466 -225.768662) (xy 133.547866 -225.768662) (xy 133.547866 -225.812858)
			(xy 133.594856 -225.965258) (xy 133.856476 -225.965258)
		)
		(stroke
			(width 0)
			(type solid)
		)
		(fill yes)
		(layer "In11.Cu")
		(net "M_H_CPU1_SB_DQ<31>")
	)
	(gr_poly
		(pts
			(xy 133.980428 -270.043402) (xy 134.088886 -269.926562) (xy 133.958076 -269.699994) (xy 133.802628 -269.735554)
			(xy 133.764274 -269.757652) (xy 133.942074 -270.0655)
		)
		(stroke
			(width 0)
			(type solid)
		)
		(fill yes)
		(layer "In11.Cu")
		(net "M_H_CPU1_SA_DQ<26>")
	)
	(gr_poly
		(pts
			(xy 133.984238 -268.421866) (xy 134.092696 -268.305026) (xy 133.961886 -268.078458) (xy 133.806438 -268.114018)
			(xy 133.768084 -268.136116) (xy 133.945884 -268.443964)
		)
		(stroke
			(width 0)
			(type solid)
		)
		(fill yes)
		(layer "In11.Cu")
		(net "M_H_CPU1_SA_DQ<27>")
	)
	(gr_poly
		(pts
			(xy 133.986016 -266.797028) (xy 134.094474 -266.680188) (xy 133.963664 -266.45362) (xy 133.808216 -266.48918)
			(xy 133.769862 -266.511278) (xy 133.947662 -266.819126)
		)
		(stroke
			(width 0)
			(type solid)
		)
		(fill yes)
		(layer "In11.Cu")
		(net "M_H_CPU1_SA_DQS_DN<3>")
	)
	(gr_poly
		(pts
			(xy 134.007352 -257.37947) (xy 133.960362 -257.22707) (xy 133.698742 -257.22707) (xy 133.651752 -257.37947)
			(xy 133.651752 -257.42392) (xy 134.007352 -257.42392)
		)
		(stroke
			(width 0)
			(type solid)
		)
		(fill yes)
		(layer "In11.Cu")
		(net "M_H_CPU1_ALERT_N")
	)
	(gr_poly
		(pts
			(xy 134.013448 -258.59867) (xy 134.013448 -258.554474) (xy 133.657848 -258.554474) (xy 133.657848 -258.59867)
			(xy 133.704838 -258.75107) (xy 133.966458 -258.75107)
		)
		(stroke
			(width 0)
			(type solid)
		)
		(fill yes)
		(layer "In11.Cu")
		(net "M_H_CPU1_SA_CB<5>")
	)
	(gr_poly
		(pts
			(xy 134.01929 -278.540718) (xy 133.9723 -278.388318) (xy 133.71068 -278.388318) (xy 133.66369 -278.540718)
			(xy 133.66369 -278.585168) (xy 134.01929 -278.585168)
		)
		(stroke
			(width 0)
			(type solid)
		)
		(fill yes)
		(layer "In11.Cu")
		(net "M_H_CPU1_SA_DQS_DP<6>")
	)
	(gr_poly
		(pts
			(xy 134.01929 -278.132032) (xy 134.01929 -278.087836) (xy 133.66369 -278.087836) (xy 133.66369 -278.132032)
			(xy 133.71068 -278.284432) (xy 133.9723 -278.284432)
		)
		(stroke
			(width 0)
			(type solid)
		)
		(fill yes)
		(layer "In11.Cu")
		(net "M_H_CPU1_SA_DQ<12>")
	)
	(gr_poly
		(pts
			(xy 134.01929 -275.284946) (xy 133.9723 -275.132546) (xy 133.71068 -275.132546) (xy 133.66369 -275.284946)
			(xy 133.66369 -275.329142) (xy 134.01929 -275.329142)
		)
		(stroke
			(width 0)
			(type solid)
		)
		(fill yes)
		(layer "In11.Cu")
		(net "M_H_CPU1_SA_DQ<18>")
	)
	(gr_poly
		(pts
			(xy 134.01929 -274.876514) (xy 134.01929 -274.832318) (xy 133.66369 -274.832318) (xy 133.66369 -274.876514)
			(xy 133.71068 -275.028914) (xy 133.9723 -275.028914)
		)
		(stroke
			(width 0)
			(type solid)
		)
		(fill yes)
		(layer "In11.Cu")
		(net "M_H_CPU1_SA_DQ<17>")
	)
	(gr_poly
		(pts
			(xy 134.01929 -265.110214) (xy 134.01929 -265.065764) (xy 133.66369 -265.065764) (xy 133.66369 -265.110214)
			(xy 133.71068 -265.262614) (xy 133.9723 -265.262614)
		)
		(stroke
			(width 0)
			(type solid)
		)
		(fill yes)
		(layer "In11.Cu")
		(net "M_H_CPU1_SA_DQS_DN<8>")
	)
	(gr_poly
		(pts
			(xy 134.01929 -260.634734) (xy 133.9723 -260.482334) (xy 133.71068 -260.482334) (xy 133.66369 -260.634734)
			(xy 133.66369 -260.679184) (xy 134.01929 -260.679184)
		)
		(stroke
			(width 0)
			(type solid)
		)
		(fill yes)
		(layer "In11.Cu")
		(net "M_H_CPU1_SA_DQS_DN<4>")
	)
	(gr_poly
		(pts
			(xy 134.01929 -260.22681) (xy 134.01929 -260.18236) (xy 133.66369 -260.18236) (xy 133.66369 -260.22681)
			(xy 133.71068 -260.37921) (xy 133.9723 -260.37921)
		)
		(stroke
			(width 0)
			(type solid)
		)
		(fill yes)
		(layer "In11.Cu")
		(net "M_H_CPU1_SA_DQS_DN<9>")
	)
	(gr_poly
		(pts
			(xy 134.01929 -256.971038) (xy 134.01929 -256.926588) (xy 133.66369 -256.926588) (xy 133.66369 -256.971038)
			(xy 133.71068 -257.123438) (xy 133.9723 -257.123438)
		)
		(stroke
			(width 0)
			(type solid)
		)
		(fill yes)
		(layer "In11.Cu")
		(net "M_H_CPU1_SA_CS_N<0>")
	)
	(gr_poly
		(pts
			(xy 134.01929 -255.751838) (xy 133.9723 -255.599438) (xy 133.71068 -255.599438) (xy 133.66369 -255.751838)
			(xy 133.66369 -255.796034) (xy 134.01929 -255.796034)
		)
		(stroke
			(width 0)
			(type solid)
		)
		(fill yes)
		(layer "In11.Cu")
		(net "M_H_CPU1_SA_CS_N<3>")
	)
	(gr_poly
		(pts
			(xy 134.01929 -255.343406) (xy 134.01929 -255.29921) (xy 133.66369 -255.29921) (xy 133.66369 -255.343406)
			(xy 133.71068 -255.495806) (xy 133.9723 -255.495806)
		)
		(stroke
			(width 0)
			(type solid)
		)
		(fill yes)
		(layer "In11.Cu")
		(net "M_H_CPU1_SA_CA<1>")
	)
	(gr_poly
		(pts
			(xy 134.02183 -281.387804) (xy 134.02183 -281.343608) (xy 133.66623 -281.343608) (xy 133.66623 -281.387804)
			(xy 133.71322 -281.540204) (xy 133.97484 -281.540204)
		)
		(stroke
			(width 0)
			(type solid)
		)
		(fill yes)
		(layer "In11.Cu")
		(net "M_H_CPU1_SA_DQ<8>")
	)
	(gr_poly
		(pts
			(xy 134.02183 -280.168096) (xy 133.97484 -280.015696) (xy 133.71322 -280.015696) (xy 133.66623 -280.168096)
			(xy 133.66623 -280.212546) (xy 134.02183 -280.212546)
		)
		(stroke
			(width 0)
			(type solid)
		)
		(fill yes)
		(layer "In11.Cu")
		(net "M_H_CPU1_SA_DQ<11>")
	)
	(gr_poly
		(pts
			(xy 134.02183 -279.760172) (xy 134.02183 -279.715722) (xy 133.66623 -279.715722) (xy 133.66623 -279.760172)
			(xy 133.71322 -279.912572) (xy 133.97484 -279.912572)
		)
		(stroke
			(width 0)
			(type solid)
		)
		(fill yes)
		(layer "In11.Cu")
		(net "M_H_CPU1_SA_DQS_DP<1>")
	)
	(gr_poly
		(pts
			(xy 134.02183 -276.912578) (xy 133.97484 -276.760178) (xy 133.71322 -276.760178) (xy 133.66623 -276.912578)
			(xy 133.66623 -276.957028) (xy 134.02183 -276.957028)
		)
		(stroke
			(width 0)
			(type solid)
		)
		(fill yes)
		(layer "In11.Cu")
		(net "M_H_CPU1_SA_DQ<15>")
	)
	(gr_poly
		(pts
			(xy 134.02183 -273.657314) (xy 133.97484 -273.504914) (xy 133.71322 -273.504914) (xy 133.66623 -273.657314)
			(xy 133.66623 -273.70151) (xy 134.02183 -273.70151)
		)
		(stroke
			(width 0)
			(type solid)
		)
		(fill yes)
		(layer "In11.Cu")
		(net "M_H_CPU1_SA_DQS_DN<2>")
	)
	(gr_poly
		(pts
			(xy 134.02183 -273.248882) (xy 134.02183 -273.204686) (xy 133.66623 -273.204686) (xy 133.66623 -273.248882)
			(xy 133.71322 -273.401282) (xy 133.97484 -273.401282)
		)
		(stroke
			(width 0)
			(type solid)
		)
		(fill yes)
		(layer "In11.Cu")
		(net "M_H_CPU1_SA_DQS_DN<7>")
	)
	(gr_poly
		(pts
			(xy 134.02183 -272.029174) (xy 133.97484 -271.876774) (xy 133.71322 -271.876774) (xy 133.66623 -272.029174)
			(xy 133.66623 -272.073624) (xy 134.02183 -272.073624)
		)
		(stroke
			(width 0)
			(type solid)
		)
		(fill yes)
		(layer "In11.Cu")
		(net "M_H_CPU1_SA_DQ<22>")
	)
	(gr_poly
		(pts
			(xy 134.02183 -271.62125) (xy 134.02183 -271.5768) (xy 133.66623 -271.5768) (xy 133.66623 -271.62125)
			(xy 133.71322 -271.77365) (xy 133.97484 -271.77365)
		)
		(stroke
			(width 0)
			(type solid)
		)
		(fill yes)
		(layer "In11.Cu")
		(net "M_H_CPU1_SA_DQ<21>")
	)
	(gr_poly
		(pts
			(xy 134.02183 -263.890506) (xy 133.97484 -263.738106) (xy 133.71322 -263.738106) (xy 133.66623 -263.890506)
			(xy 133.66623 -263.934956) (xy 134.02183 -263.934956)
		)
		(stroke
			(width 0)
			(type solid)
		)
		(fill yes)
		(layer "In11.Cu")
		(net "M_H_CPU1_SA_DQ<30>")
	)
	(gr_poly
		(pts
			(xy 134.02183 -263.482582) (xy 134.02183 -263.438132) (xy 133.66623 -263.438132) (xy 133.66623 -263.482582)
			(xy 133.71322 -263.634982) (xy 133.97484 -263.634982)
		)
		(stroke
			(width 0)
			(type solid)
		)
		(fill yes)
		(layer "In11.Cu")
		(net "M_H_CPU1_SA_DQ<29>")
	)
	(gr_poly
		(pts
			(xy 134.02183 -262.262874) (xy 133.97484 -262.110474) (xy 133.71322 -262.110474) (xy 133.66623 -262.262874)
			(xy 133.66623 -262.30707) (xy 134.02183 -262.30707)
		)
		(stroke
			(width 0)
			(type solid)
		)
		(fill yes)
		(layer "In11.Cu")
		(net "M_H_CPU1_SA_CB<2>")
	)
	(gr_poly
		(pts
			(xy 134.02183 -261.854442) (xy 134.02183 -261.810246) (xy 133.66623 -261.810246) (xy 133.66623 -261.854442)
			(xy 133.71322 -262.006842) (xy 133.97484 -262.006842)
		)
		(stroke
			(width 0)
			(type solid)
		)
		(fill yes)
		(layer "In11.Cu")
		(net "M_H_CPU1_SA_CB<1>")
	)
	(gr_poly
		(pts
			(xy 134.02183 -259.007102) (xy 133.97484 -258.854702) (xy 133.71322 -258.854702) (xy 133.66623 -259.007102)
			(xy 133.66623 -259.051552) (xy 134.02183 -259.051552)
		)
		(stroke
			(width 0)
			(type solid)
		)
		(fill yes)
		(layer "In11.Cu")
		(net "M_H_CPU1_SA_CB<6>")
	)
	(gr_poly
		(pts
			(xy 134.02183 -254.123698) (xy 133.97484 -253.971298) (xy 133.71322 -253.971298) (xy 133.66623 -254.123698)
			(xy 133.66623 -254.168148) (xy 134.02183 -254.168148)
		)
		(stroke
			(width 0)
			(type solid)
		)
		(fill yes)
		(layer "In11.Cu")
		(net "M_H_CPU1_SA_CA<3>")
	)
	(gr_poly
		(pts
			(xy 134.334504 -268.211554) (xy 134.372858 -268.189456) (xy 134.195058 -267.881608) (xy 134.156704 -267.903706)
			(xy 134.048246 -268.020546) (xy 134.179056 -268.247114)
		)
		(stroke
			(width 0)
			(type solid)
		)
		(fill yes)
		(layer "In11.Cu")
		(net "M_H_CPU1_SA_DQS_DP<3>")
	)
	(gr_poly
		(pts
			(xy 134.339838 -269.84833) (xy 134.378192 -269.826232) (xy 134.200392 -269.518384) (xy 134.162038 -269.540482)
			(xy 134.05358 -269.657322) (xy 134.18439 -269.88389)
		)
		(stroke
			(width 0)
			(type solid)
		)
		(fill yes)
		(layer "In11.Cu")
		(net "M_H_CPU1_SA_DQ<25>")
	)
	(gr_poly
		(pts
			(xy 134.36727 -244.53215) (xy 134.36727 -244.487954) (xy 134.01167 -244.487954) (xy 134.01167 -244.53215)
			(xy 134.05866 -244.68455) (xy 134.32028 -244.68455)
		)
		(stroke
			(width 0)
			(type solid)
		)
		(fill yes)
		(layer "In11.Cu")
		(net "M_H_CPU1_SB_CB<6>")
	)
	(gr_poly
		(pts
			(xy 134.36727 -243.313458) (xy 134.32028 -243.161058) (xy 134.05866 -243.161058) (xy 134.01167 -243.313458)
			(xy 134.01167 -243.357654) (xy 134.36727 -243.357654)
		)
		(stroke
			(width 0)
			(type solid)
		)
		(fill yes)
		(layer "In11.Cu")
		(net "M_H_CPU1_SB_CB<5>")
	)
	(gr_poly
		(pts
			(xy 134.36727 -242.904518) (xy 134.36727 -242.860322) (xy 134.01167 -242.860322) (xy 134.01167 -242.904518)
			(xy 134.05866 -243.056918) (xy 134.32028 -243.056918)
		)
		(stroke
			(width 0)
			(type solid)
		)
		(fill yes)
		(layer "In11.Cu")
		(net "M_H_CPU1_SB_DQS_DP<9>")
	)
	(gr_poly
		(pts
			(xy 134.36727 -241.685318) (xy 134.32028 -241.532918) (xy 134.05866 -241.532918) (xy 134.01167 -241.685318)
			(xy 134.01167 -241.729768) (xy 134.36727 -241.729768)
		)
		(stroke
			(width 0)
			(type solid)
		)
		(fill yes)
		(layer "In11.Cu")
		(net "M_H_CPU1_SB_DQS_DP<4>")
	)
	(gr_poly
		(pts
			(xy 134.36727 -241.276886) (xy 134.36727 -241.232436) (xy 134.01167 -241.232436) (xy 134.01167 -241.276886)
			(xy 134.05866 -241.429286) (xy 134.32028 -241.429286)
		)
		(stroke
			(width 0)
			(type solid)
		)
		(fill yes)
		(layer "In11.Cu")
		(net "M_H_CPU1_SB_CB<0>")
	)
	(gr_poly
		(pts
			(xy 134.36727 -240.057686) (xy 134.32028 -239.905286) (xy 134.05866 -239.905286) (xy 134.01167 -240.057686)
			(xy 134.01167 -240.101882) (xy 134.36727 -240.101882)
		)
		(stroke
			(width 0)
			(type solid)
		)
		(fill yes)
		(layer "In11.Cu")
		(net "M_H_CPU1_SB_CB<3>")
	)
	(gr_poly
		(pts
			(xy 134.36727 -239.648746) (xy 134.36727 -239.60455) (xy 134.01167 -239.60455) (xy 134.01167 -239.648746)
			(xy 134.05866 -239.801146) (xy 134.32028 -239.801146)
		)
		(stroke
			(width 0)
			(type solid)
		)
		(fill yes)
		(layer "In11.Cu")
		(net "M_H_CPU1_SB_DQ<0>")
	)
	(gr_poly
		(pts
			(xy 134.36727 -228.663246) (xy 134.32028 -228.510846) (xy 134.05866 -228.510846) (xy 134.01167 -228.663246)
			(xy 134.01167 -228.707696) (xy 134.36727 -228.707696)
		)
		(stroke
			(width 0)
			(type solid)
		)
		(fill yes)
		(layer "In11.Cu")
		(net "M_H_CPU1_SB_DQ<25>")
	)
	(gr_poly
		(pts
			(xy 134.36727 -228.254814) (xy 134.36727 -228.210364) (xy 134.01167 -228.210364) (xy 134.01167 -228.254814)
			(xy 134.05866 -228.407214) (xy 134.32028 -228.407214)
		)
		(stroke
			(width 0)
			(type solid)
		)
		(fill yes)
		(layer "In11.Cu")
		(net "M_H_CPU1_SB_DQS_DN<8>")
	)
	(gr_poly
		(pts
			(xy 134.36727 -227.035614) (xy 134.32028 -226.883214) (xy 134.05866 -226.883214) (xy 134.01167 -227.035614)
			(xy 134.01167 -227.07981) (xy 134.36727 -227.07981)
		)
		(stroke
			(width 0)
			(type solid)
		)
		(fill yes)
		(layer "In11.Cu")
		(net "M_H_CPU1_SB_DQS_DN<3>")
	)
	(gr_poly
		(pts
			(xy 134.36727 -226.626674) (xy 134.36727 -226.582478) (xy 134.01167 -226.582478) (xy 134.01167 -226.626674)
			(xy 134.05866 -226.779074) (xy 134.32028 -226.779074)
		)
		(stroke
			(width 0)
			(type solid)
		)
		(fill yes)
		(layer "In11.Cu")
		(net "M_H_CPU1_SB_DQ<30>")
	)
	(gr_poly
		(pts
			(xy 134.372858 -231.919018) (xy 134.325868 -231.766618) (xy 134.064248 -231.766618) (xy 134.017258 -231.919018)
			(xy 134.017258 -231.963468) (xy 134.372858 -231.963468)
		)
		(stroke
			(width 0)
			(type solid)
		)
		(fill yes)
		(layer "In11.Cu")
		(net "M_H_CPU1_SB_DQS_DP<6>")
	)
	(gr_poly
		(pts
			(xy 134.373112 -236.802422) (xy 134.326122 -236.650022) (xy 134.064502 -236.650022) (xy 134.017512 -236.802422)
			(xy 134.017512 -236.846872) (xy 134.373112 -236.846872)
		)
		(stroke
			(width 0)
			(type solid)
		)
		(fill yes)
		(layer "In11.Cu")
		(net "M_H_CPU1_SB_DQS_DP<5>")
	)
	(gr_poly
		(pts
			(xy 134.373366 -249.415554) (xy 134.373366 -249.371358) (xy 134.017766 -249.371358) (xy 134.017766 -249.415554)
			(xy 134.064756 -249.567954) (xy 134.326376 -249.567954)
		)
		(stroke
			(width 0)
			(type solid)
		)
		(fill yes)
		(layer "In11.Cu")
		(net "M_H_CPU1_SB_CA<0>")
	)
	(gr_poly
		(pts
			(xy 134.373366 -248.196354) (xy 134.326376 -248.043954) (xy 134.064756 -248.043954) (xy 134.017766 -248.196354)
			(xy 134.017766 -248.240804) (xy 134.373366 -248.240804)
		)
		(stroke
			(width 0)
			(type solid)
		)
		(fill yes)
		(layer "In11.Cu")
		(net "M_H_CPU1_SB_CA<3>")
	)
	(gr_poly
		(pts
			(xy 134.373366 -246.568722) (xy 134.326376 -246.416322) (xy 134.064756 -246.416322) (xy 134.017766 -246.568722)
			(xy 134.017766 -246.613172) (xy 134.373366 -246.613172)
		)
		(stroke
			(width 0)
			(type solid)
		)
		(fill yes)
		(layer "In11.Cu")
		(net "M_H_CPU1_SB_CA<5>")
	)
	(gr_poly
		(pts
			(xy 134.373366 -246.16029) (xy 134.373366 -246.11584) (xy 134.017766 -246.11584) (xy 134.017766 -246.16029)
			(xy 134.064756 -246.31269) (xy 134.326376 -246.31269)
		)
		(stroke
			(width 0)
			(type solid)
		)
		(fill yes)
		(layer "In11.Cu")
		(net "M_H_CPU1_SB_CA<6>")
	)
	(gr_poly
		(pts
			(xy 134.373366 -238.430054) (xy 134.326376 -238.277654) (xy 134.064756 -238.277654) (xy 134.017766 -238.430054)
			(xy 134.017766 -238.47425) (xy 134.373366 -238.47425)
		)
		(stroke
			(width 0)
			(type solid)
		)
		(fill yes)
		(layer "In11.Cu")
		(net "M_H_CPU1_SB_DQ<3>")
	)
	(gr_poly
		(pts
			(xy 134.373366 -238.021114) (xy 134.373366 -237.976918) (xy 134.017766 -237.976918) (xy 134.017766 -238.021114)
			(xy 134.064756 -238.173514) (xy 134.326376 -238.173514)
		)
		(stroke
			(width 0)
			(type solid)
		)
		(fill yes)
		(layer "In11.Cu")
		(net "M_H_CPU1_SB_DQS_DP<0>")
	)
	(gr_poly
		(pts
			(xy 134.373366 -236.393482) (xy 134.373366 -236.349286) (xy 134.017766 -236.349286) (xy 134.017766 -236.393482)
			(xy 134.064756 -236.545882) (xy 134.326376 -236.545882)
		)
		(stroke
			(width 0)
			(type solid)
		)
		(fill yes)
		(layer "In11.Cu")
		(net "M_H_CPU1_SB_DQ<4>")
	)
	(gr_poly
		(pts
			(xy 134.373366 -235.174282) (xy 134.326376 -235.021882) (xy 134.064756 -235.021882) (xy 134.017766 -235.174282)
			(xy 134.017766 -235.218732) (xy 134.373366 -235.218732)
		)
		(stroke
			(width 0)
			(type solid)
		)
		(fill yes)
		(layer "In11.Cu")
		(net "M_H_CPU1_SB_DQ<7>")
	)
	(gr_poly
		(pts
			(xy 134.373366 -234.76585) (xy 134.373366 -234.7214) (xy 134.017766 -234.7214) (xy 134.017766 -234.76585)
			(xy 134.064756 -234.91825) (xy 134.326376 -234.91825)
		)
		(stroke
			(width 0)
			(type solid)
		)
		(fill yes)
		(layer "In11.Cu")
		(net "M_H_CPU1_SB_DQ<8>")
	)
	(gr_poly
		(pts
			(xy 134.373366 -233.54665) (xy 134.326376 -233.39425) (xy 134.064756 -233.39425) (xy 134.017766 -233.54665)
			(xy 134.017766 -233.590846) (xy 134.373366 -233.590846)
		)
		(stroke
			(width 0)
			(type solid)
		)
		(fill yes)
		(layer "In11.Cu")
		(net "M_H_CPU1_SB_DQ<11>")
	)
	(gr_poly
		(pts
			(xy 134.373366 -233.13771) (xy 134.373366 -233.093514) (xy 134.017766 -233.093514) (xy 134.017766 -233.13771)
			(xy 134.064756 -233.29011) (xy 134.326376 -233.29011)
		)
		(stroke
			(width 0)
			(type solid)
		)
		(fill yes)
		(layer "In11.Cu")
		(net "M_H_CPU1_SB_DQS_DP<1>")
	)
	(gr_poly
		(pts
			(xy 134.373366 -231.510078) (xy 134.373366 -231.465882) (xy 134.017766 -231.465882) (xy 134.017766 -231.510078)
			(xy 134.064756 -231.662478) (xy 134.326376 -231.662478)
		)
		(stroke
			(width 0)
			(type solid)
		)
		(fill yes)
		(layer "In11.Cu")
		(net "M_H_CPU1_SB_DQ<12>")
	)
	(gr_poly
		(pts
			(xy 134.373366 -230.290878) (xy 134.326376 -230.138478) (xy 134.064756 -230.138478) (xy 134.017766 -230.290878)
			(xy 134.017766 -230.335328) (xy 134.373366 -230.335328)
		)
		(stroke
			(width 0)
			(type solid)
		)
		(fill yes)
		(layer "In11.Cu")
		(net "M_H_CPU1_SB_DQ<15>")
	)
	(gr_poly
		(pts
			(xy 134.373366 -229.882446) (xy 134.373366 -229.837996) (xy 134.017766 -229.837996) (xy 134.017766 -229.882446)
			(xy 134.064756 -230.034846) (xy 134.326376 -230.034846)
		)
		(stroke
			(width 0)
			(type solid)
		)
		(fill yes)
		(layer "In11.Cu")
		(net "M_H_CPU1_SB_DQ<26>")
	)
	(gr_poly
		(pts
			(xy 134.373366 -225.407474) (xy 134.326376 -225.255074) (xy 134.064756 -225.255074) (xy 134.017766 -225.407474)
			(xy 134.017766 -225.451924) (xy 134.373366 -225.451924)
		)
		(stroke
			(width 0)
			(type solid)
		)
		(fill yes)
		(layer "In11.Cu")
		(net "M_H_CPU1_SB_DQ<29>")
	)
	(gr_poly
		(pts
			(xy 134.44855 -269.22603) (xy 134.557008 -269.10919) (xy 134.426198 -268.882622) (xy 134.27075 -268.918182)
			(xy 134.232396 -268.94028) (xy 134.410196 -269.248128)
		)
		(stroke
			(width 0)
			(type solid)
		)
		(fill yes)
		(layer "In11.Cu")
		(net "M_H_CPU1_SA_DQ<27>")
	)
	(gr_poly
		(pts
			(xy 134.449566 -267.600938) (xy 134.558024 -267.484098) (xy 134.427214 -267.25753) (xy 134.271766 -267.29309)
			(xy 134.233412 -267.315188) (xy 134.411212 -267.623036)
		)
		(stroke
			(width 0)
			(type solid)
		)
		(fill yes)
		(layer "In11.Cu")
		(net "M_H_CPU1_SA_DQS_DN<3>")
	)
	(gr_poly
		(pts
			(xy 134.474712 -280.98242) (xy 134.427722 -280.83002) (xy 134.166102 -280.83002) (xy 134.119112 -280.98242)
			(xy 134.119112 -281.026616) (xy 134.474712 -281.026616)
		)
		(stroke
			(width 0)
			(type solid)
		)
		(fill yes)
		(layer "In11.Cu")
		(net "M_H_CPU1_SA_DQ<10>")
	)
	(gr_poly
		(pts
			(xy 134.474712 -280.574242) (xy 134.474712 -280.529792) (xy 134.119112 -280.529792) (xy 134.119112 -280.574242)
			(xy 134.166102 -280.726642) (xy 134.427722 -280.726642)
		)
		(stroke
			(width 0)
			(type solid)
		)
		(fill yes)
		(layer "In11.Cu")
		(net "M_H_CPU1_SA_DQ<9>")
	)
	(gr_poly
		(pts
			(xy 134.474712 -279.35428) (xy 134.427722 -279.20188) (xy 134.166102 -279.20188) (xy 134.119112 -279.35428)
			(xy 134.119112 -279.39873) (xy 134.474712 -279.39873)
		)
		(stroke
			(width 0)
			(type solid)
		)
		(fill yes)
		(layer "In11.Cu")
		(net "M_H_CPU1_SA_DQS_DN<1>")
	)
	(gr_poly
		(pts
			(xy 134.474712 -277.318216) (xy 134.474712 -277.27402) (xy 134.119112 -277.27402) (xy 134.119112 -277.318216)
			(xy 134.166102 -277.470616) (xy 134.427722 -277.470616)
		)
		(stroke
			(width 0)
			(type solid)
		)
		(fill yes)
		(layer "In11.Cu")
		(net "M_H_CPU1_SA_DQ<13>")
	)
	(gr_poly
		(pts
			(xy 134.474712 -275.690584) (xy 134.474712 -275.646388) (xy 134.119112 -275.646388) (xy 134.119112 -275.690584)
			(xy 134.166102 -275.842984) (xy 134.427722 -275.842984)
		)
		(stroke
			(width 0)
			(type solid)
		)
		(fill yes)
		(layer "In11.Cu")
		(net "M_H_CPU1_SA_DQ<16>")
	)
	(gr_poly
		(pts
			(xy 134.474712 -274.47113) (xy 134.427722 -274.31873) (xy 134.166102 -274.31873) (xy 134.119112 -274.47113)
			(xy 134.119112 -274.515326) (xy 134.474712 -274.515326)
		)
		(stroke
			(width 0)
			(type solid)
		)
		(fill yes)
		(layer "In11.Cu")
		(net "M_H_CPU1_SA_DQ<19>")
	)
	(gr_poly
		(pts
			(xy 134.474712 -274.062698) (xy 134.474712 -274.018502) (xy 134.119112 -274.018502) (xy 134.119112 -274.062698)
			(xy 134.166102 -274.215098) (xy 134.427722 -274.215098)
		)
		(stroke
			(width 0)
			(type solid)
		)
		(fill yes)
		(layer "In11.Cu")
		(net "M_H_CPU1_SA_DQS_DP<2>")
	)
	(gr_poly
		(pts
			(xy 134.474712 -272.843498) (xy 134.427722 -272.691098) (xy 134.166102 -272.691098) (xy 134.119112 -272.843498)
			(xy 134.119112 -272.887694) (xy 134.474712 -272.887694)
		)
		(stroke
			(width 0)
			(type solid)
		)
		(fill yes)
		(layer "In11.Cu")
		(net "M_H_CPU1_SA_DQS_DP<7>")
	)
	(gr_poly
		(pts
			(xy 134.474712 -272.435066) (xy 134.474712 -272.39087) (xy 134.119112 -272.39087) (xy 134.119112 -272.435066)
			(xy 134.166102 -272.587466) (xy 134.427722 -272.587466)
		)
		(stroke
			(width 0)
			(type solid)
		)
		(fill yes)
		(layer "In11.Cu")
		(net "M_H_CPU1_SA_DQ<20>")
	)
	(gr_poly
		(pts
			(xy 134.474712 -271.215358) (xy 134.427722 -271.062958) (xy 134.166102 -271.062958) (xy 134.119112 -271.215358)
			(xy 134.119112 -271.259808) (xy 134.474712 -271.259808)
		)
		(stroke
			(width 0)
			(type solid)
		)
		(fill yes)
		(layer "In11.Cu")
		(net "M_H_CPU1_SA_DQ<23>")
	)
	(gr_poly
		(pts
			(xy 134.474712 -270.807434) (xy 134.474712 -270.762984) (xy 134.119112 -270.762984) (xy 134.119112 -270.807434)
			(xy 134.166102 -270.959834) (xy 134.427722 -270.959834)
		)
		(stroke
			(width 0)
			(type solid)
		)
		(fill yes)
		(layer "In11.Cu")
		(net "M_H_CPU1_SA_DQ<24>")
	)
	(gr_poly
		(pts
			(xy 134.474712 -264.704322) (xy 134.427722 -264.551922) (xy 134.166102 -264.551922) (xy 134.119112 -264.704322)
			(xy 134.119112 -264.748772) (xy 134.474712 -264.748772)
		)
		(stroke
			(width 0)
			(type solid)
		)
		(fill yes)
		(layer "In11.Cu")
		(net "M_H_CPU1_SA_DQS_DP<8>")
	)
	(gr_poly
		(pts
			(xy 134.474712 -264.296398) (xy 134.474712 -264.251948) (xy 134.119112 -264.251948) (xy 134.119112 -264.296398)
			(xy 134.166102 -264.448798) (xy 134.427722 -264.448798)
		)
		(stroke
			(width 0)
			(type solid)
		)
		(fill yes)
		(layer "In11.Cu")
		(net "M_H_CPU1_SA_DQ<28>")
	)
	(gr_poly
		(pts
			(xy 134.474712 -263.07669) (xy 134.427722 -262.92429) (xy 134.166102 -262.92429) (xy 134.119112 -263.07669)
			(xy 134.119112 -263.120886) (xy 134.474712 -263.120886)
		)
		(stroke
			(width 0)
			(type solid)
		)
		(fill yes)
		(layer "In11.Cu")
		(net "M_H_CPU1_SA_DQ<31>")
	)
	(gr_poly
		(pts
			(xy 134.474712 -262.668258) (xy 134.474712 -262.624062) (xy 134.119112 -262.624062) (xy 134.119112 -262.668258)
			(xy 134.166102 -262.820658) (xy 134.427722 -262.820658)
		)
		(stroke
			(width 0)
			(type solid)
		)
		(fill yes)
		(layer "In11.Cu")
		(net "M_H_CPU1_SA_CB<0>")
	)
	(gr_poly
		(pts
			(xy 134.474712 -261.449058) (xy 134.427722 -261.296658) (xy 134.166102 -261.296658) (xy 134.119112 -261.449058)
			(xy 134.119112 -261.493254) (xy 134.474712 -261.493254)
		)
		(stroke
			(width 0)
			(type solid)
		)
		(fill yes)
		(layer "In11.Cu")
		(net "M_H_CPU1_SA_CB<3>")
	)
	(gr_poly
		(pts
			(xy 134.474712 -261.040626) (xy 134.474712 -260.99643) (xy 134.119112 -260.99643) (xy 134.119112 -261.040626)
			(xy 134.166102 -261.193026) (xy 134.427722 -261.193026)
		)
		(stroke
			(width 0)
			(type solid)
		)
		(fill yes)
		(layer "In11.Cu")
		(net "M_H_CPU1_SA_DQS_DP<4>")
	)
	(gr_poly
		(pts
			(xy 134.474712 -259.820918) (xy 134.427722 -259.668518) (xy 134.166102 -259.668518) (xy 134.119112 -259.820918)
			(xy 134.119112 -259.865368) (xy 134.474712 -259.865368)
		)
		(stroke
			(width 0)
			(type solid)
		)
		(fill yes)
		(layer "In11.Cu")
		(net "M_H_CPU1_SA_DQS_DP<9>")
	)
	(gr_poly
		(pts
			(xy 134.474712 -259.412994) (xy 134.474712 -259.368544) (xy 134.119112 -259.368544) (xy 134.119112 -259.412994)
			(xy 134.166102 -259.565394) (xy 134.427722 -259.565394)
		)
		(stroke
			(width 0)
			(type solid)
		)
		(fill yes)
		(layer "In11.Cu")
		(net "M_H_CPU1_SA_CB<4>")
	)
	(gr_poly
		(pts
			(xy 134.474712 -256.157222) (xy 134.474712 -256.113026) (xy 134.119112 -256.113026) (xy 134.119112 -256.157222)
			(xy 134.166102 -256.309622) (xy 134.427722 -256.309622)
		)
		(stroke
			(width 0)
			(type solid)
		)
		(fill yes)
		(layer "In11.Cu")
		(net "M_H_CPU1_SA_CS_N<2>")
	)
	(gr_poly
		(pts
			(xy 134.474712 -254.937514) (xy 134.427722 -254.785114) (xy 134.166102 -254.785114) (xy 134.119112 -254.937514)
			(xy 134.119112 -254.981964) (xy 134.474712 -254.981964)
		)
		(stroke
			(width 0)
			(type solid)
		)
		(fill yes)
		(layer "In11.Cu")
		(net "M_H_CPU1_SA_CA<0>")
	)
	(gr_poly
		(pts
			(xy 134.474712 -254.52959) (xy 134.474712 -254.48514) (xy 134.119112 -254.48514) (xy 134.119112 -254.52959)
			(xy 134.166102 -254.68199) (xy 134.427722 -254.68199)
		)
		(stroke
			(width 0)
			(type solid)
		)
		(fill yes)
		(layer "In11.Cu")
		(net "M_H_CPU1_SA_CA<2>")
	)
	(gr_poly
		(pts
			(xy 134.477252 -258.193286) (xy 134.430262 -258.040886) (xy 134.168642 -258.040886) (xy 134.121652 -258.193286)
			(xy 134.121652 -258.237736) (xy 134.477252 -258.237736)
		)
		(stroke
			(width 0)
			(type solid)
		)
		(fill yes)
		(layer "In11.Cu")
		(net "M_H_CPU1_SA_CB<7>")
	)
	(gr_poly
		(pts
			(xy 134.483094 -278.945848) (xy 134.483094 -278.901652) (xy 134.127494 -278.901652) (xy 134.127494 -278.945848)
			(xy 134.174484 -279.098248) (xy 134.436104 -279.098248)
		)
		(stroke
			(width 0)
			(type solid)
		)
		(fill yes)
		(layer "In11.Cu")
		(net "M_H_CPU1_SA_DQS_DN<6>")
	)
	(gr_poly
		(pts
			(xy 134.483094 -277.726902) (xy 134.436104 -277.574502) (xy 134.174484 -277.574502) (xy 134.127494 -277.726902)
			(xy 134.127494 -277.771098) (xy 134.483094 -277.771098)
		)
		(stroke
			(width 0)
			(type solid)
		)
		(fill yes)
		(layer "In11.Cu")
		(net "M_H_CPU1_SA_DQ<14>")
	)
	(gr_poly
		(pts
			(xy 134.483094 -256.565654) (xy 134.436104 -256.413254) (xy 134.174484 -256.413254) (xy 134.127494 -256.565654)
			(xy 134.127494 -256.610104) (xy 134.483094 -256.610104)
		)
		(stroke
			(width 0)
			(type solid)
		)
		(fill yes)
		(layer "In11.Cu")
		(net "M_H_CPU1_SA_CS_N<1>")
	)
	(gr_poly
		(pts
			(xy 134.48919 -257.784854) (xy 134.48919 -257.740404) (xy 134.13359 -257.740404) (xy 134.13359 -257.784854)
			(xy 134.18058 -257.937254) (xy 134.4422 -257.937254)
		)
		(stroke
			(width 0)
			(type solid)
		)
		(fill yes)
		(layer "In11.Cu")
		(net "M_E_CPU1_ALERT_N")
	)
	(gr_poly
		(pts
			(xy 134.804404 -282.047696) (xy 134.842758 -282.025598) (xy 134.664958 -281.71775) (xy 134.626604 -281.739848)
			(xy 134.518146 -281.856688) (xy 134.648956 -282.083256)
		)
		(stroke
			(width 0)
			(type solid)
		)
		(fill yes)
		(layer "In11.Cu")
		(net "M_H_CPU1_SA_DQ<8>")
	)
	(gr_poly
		(pts
			(xy 134.809992 -269.035022) (xy 134.848346 -269.012924) (xy 134.670546 -268.705076) (xy 134.632192 -268.727174)
			(xy 134.523734 -268.844014) (xy 134.654544 -269.070582)
		)
		(stroke
			(width 0)
			(type solid)
		)
		(fill yes)
		(layer "In11.Cu")
		(net "M_H_CPU1_SA_DQS_DP<3>")
	)
	(gr_poly
		(pts
			(xy 134.81177 -265.781028) (xy 134.850124 -265.75893) (xy 134.672324 -265.451082) (xy 134.63397 -265.47318)
			(xy 134.525512 -265.59002) (xy 134.656322 -265.816588)
		)
		(stroke
			(width 0)
			(type solid)
		)
		(fill yes)
		(layer "In11.Cu")
		(net "M_H_CPU1_SA_DQS_DN<8>")
	)
	(gr_poly
		(pts
			(xy 134.843012 -232.323894) (xy 134.843012 -232.279444) (xy 134.487412 -232.279444) (xy 134.487412 -232.323894)
			(xy 134.534402 -232.476294) (xy 134.796022 -232.476294)
		)
		(stroke
			(width 0)
			(type solid)
		)
		(fill yes)
		(layer "In11.Cu")
		(net "M_H_CPU1_SB_DQS_DN<6>")
	)
	(gr_poly
		(pts
			(xy 134.843266 -249.010678) (xy 134.796276 -248.858278) (xy 134.534656 -248.858278) (xy 134.487666 -249.010678)
			(xy 134.487666 -249.054874) (xy 134.843266 -249.054874)
		)
		(stroke
			(width 0)
			(type solid)
		)
		(fill yes)
		(layer "In11.Cu")
		(net "M_H_CPU1_SB_CA<1>")
	)
	(gr_poly
		(pts
			(xy 134.843266 -248.601738) (xy 134.843266 -248.557542) (xy 134.487666 -248.557542) (xy 134.487666 -248.601738)
			(xy 134.534656 -248.754138) (xy 134.796276 -248.754138)
		)
		(stroke
			(width 0)
			(type solid)
		)
		(fill yes)
		(layer "In11.Cu")
		(net "M_H_CPU1_SB_CA<2>")
	)
	(gr_poly
		(pts
			(xy 134.843266 -246.974106) (xy 134.843266 -246.929656) (xy 134.487666 -246.929656) (xy 134.487666 -246.974106)
			(xy 134.534656 -247.126506) (xy 134.796276 -247.126506)
		)
		(stroke
			(width 0)
			(type solid)
		)
		(fill yes)
		(layer "In11.Cu")
		(net "M_H_CPU1_SB_CA<4>")
	)
	(gr_poly
		(pts
			(xy 134.843266 -245.754906) (xy 134.796276 -245.602506) (xy 134.534656 -245.602506) (xy 134.487666 -245.754906)
			(xy 134.487666 -245.799356) (xy 134.843266 -245.799356)
		)
		(stroke
			(width 0)
			(type solid)
		)
		(fill yes)
		(layer "In11.Cu")
		(net "M_H_CPU1_SB_PAR")
	)
	(gr_poly
		(pts
			(xy 134.843266 -238.83493) (xy 134.843266 -238.790734) (xy 134.487666 -238.790734) (xy 134.487666 -238.83493)
			(xy 134.534656 -238.98733) (xy 134.796276 -238.98733)
		)
		(stroke
			(width 0)
			(type solid)
		)
		(fill yes)
		(layer "In11.Cu")
		(net "M_H_CPU1_SB_DQ<1>")
	)
	(gr_poly
		(pts
			(xy 134.843266 -237.616238) (xy 134.796276 -237.463838) (xy 134.534656 -237.463838) (xy 134.487666 -237.616238)
			(xy 134.487666 -237.660434) (xy 134.843266 -237.660434)
		)
		(stroke
			(width 0)
			(type solid)
		)
		(fill yes)
		(layer "In11.Cu")
		(net "M_H_CPU1_SB_DQS_DN<0>")
	)
	(gr_poly
		(pts
			(xy 134.843266 -237.207298) (xy 134.843266 -237.163102) (xy 134.487666 -237.163102) (xy 134.487666 -237.207298)
			(xy 134.534656 -237.359698) (xy 134.796276 -237.359698)
		)
		(stroke
			(width 0)
			(type solid)
		)
		(fill yes)
		(layer "In11.Cu")
		(net "M_H_CPU1_SB_DQS_DN<5>")
	)
	(gr_poly
		(pts
			(xy 134.843266 -235.988098) (xy 134.796276 -235.835698) (xy 134.534656 -235.835698) (xy 134.487666 -235.988098)
			(xy 134.487666 -236.032548) (xy 134.843266 -236.032548)
		)
		(stroke
			(width 0)
			(type solid)
		)
		(fill yes)
		(layer "In11.Cu")
		(net "M_H_CPU1_SB_DQ<6>")
	)
	(gr_poly
		(pts
			(xy 134.843266 -235.579666) (xy 134.843266 -235.535216) (xy 134.487666 -235.535216) (xy 134.487666 -235.579666)
			(xy 134.534656 -235.732066) (xy 134.796276 -235.732066)
		)
		(stroke
			(width 0)
			(type solid)
		)
		(fill yes)
		(layer "In11.Cu")
		(net "M_H_CPU1_SB_DQ<5>")
	)
	(gr_poly
		(pts
			(xy 134.843266 -234.360466) (xy 134.796276 -234.208066) (xy 134.534656 -234.208066) (xy 134.487666 -234.360466)
			(xy 134.487666 -234.404916) (xy 134.843266 -234.404916)
		)
		(stroke
			(width 0)
			(type solid)
		)
		(fill yes)
		(layer "In11.Cu")
		(net "M_H_CPU1_SB_DQ<10>")
	)
	(gr_poly
		(pts
			(xy 134.843266 -233.952034) (xy 134.843266 -233.907584) (xy 134.487666 -233.907584) (xy 134.487666 -233.952034)
			(xy 134.534656 -234.104434) (xy 134.796276 -234.104434)
		)
		(stroke
			(width 0)
			(type solid)
		)
		(fill yes)
		(layer "In11.Cu")
		(net "M_H_CPU1_SB_DQ<9>")
	)
	(gr_poly
		(pts
			(xy 134.843266 -232.732834) (xy 134.796276 -232.580434) (xy 134.534656 -232.580434) (xy 134.487666 -232.732834)
			(xy 134.487666 -232.77703) (xy 134.843266 -232.77703)
		)
		(stroke
			(width 0)
			(type solid)
		)
		(fill yes)
		(layer "In11.Cu")
		(net "M_H_CPU1_SB_DQS_DN<1>")
	)
	(gr_poly
		(pts
			(xy 134.843266 -231.104694) (xy 134.796276 -230.952294) (xy 134.534656 -230.952294) (xy 134.487666 -231.104694)
			(xy 134.487666 -231.149144) (xy 134.843266 -231.149144)
		)
		(stroke
			(width 0)
			(type solid)
		)
		(fill yes)
		(layer "In11.Cu")
		(net "M_H_CPU1_SB_DQ<14>")
	)
	(gr_poly
		(pts
			(xy 134.843266 -230.696262) (xy 134.843266 -230.651812) (xy 134.487666 -230.651812) (xy 134.487666 -230.696262)
			(xy 134.534656 -230.848662) (xy 134.796276 -230.848662)
		)
		(stroke
			(width 0)
			(type solid)
		)
		(fill yes)
		(layer "In11.Cu")
		(net "M_H_CPU1_SB_DQ<13>")
	)
	(gr_poly
		(pts
			(xy 134.843266 -229.477062) (xy 134.796276 -229.324662) (xy 134.534656 -229.324662) (xy 134.487666 -229.477062)
			(xy 134.487666 -229.521512) (xy 134.843266 -229.521512)
		)
		(stroke
			(width 0)
			(type solid)
		)
		(fill yes)
		(layer "In11.Cu")
		(net "M_H_CPU1_SB_DQ<24>")
	)
	(gr_poly
		(pts
			(xy 134.843266 -225.812858) (xy 134.843266 -225.768662) (xy 134.487666 -225.768662) (xy 134.487666 -225.812858)
			(xy 134.534656 -225.965258) (xy 134.796276 -225.965258)
		)
		(stroke
			(width 0)
			(type solid)
		)
		(fill yes)
		(layer "In11.Cu")
		(net "M_H_CPU1_SB_DQ<31>")
	)
	(gr_poly
		(pts
			(xy 134.851648 -244.126766) (xy 134.804658 -243.974366) (xy 134.543038 -243.974366) (xy 134.496048 -244.126766)
			(xy 134.496048 -244.171216) (xy 134.851648 -244.171216)
		)
		(stroke
			(width 0)
			(type solid)
		)
		(fill yes)
		(layer "In11.Cu")
		(net "M_H_CPU1_SB_CB<4>")
	)
	(gr_poly
		(pts
			(xy 134.851648 -243.718842) (xy 134.851648 -243.674392) (xy 134.496048 -243.674392) (xy 134.496048 -243.718842)
			(xy 134.543038 -243.871242) (xy 134.804658 -243.871242)
		)
		(stroke
			(width 0)
			(type solid)
		)
		(fill yes)
		(layer "In11.Cu")
		(net "M_H_CPU1_SB_CB<7>")
	)
	(gr_poly
		(pts
			(xy 134.851648 -242.499134) (xy 134.804658 -242.346734) (xy 134.543038 -242.346734) (xy 134.496048 -242.499134)
			(xy 134.496048 -242.54333) (xy 134.851648 -242.54333)
		)
		(stroke
			(width 0)
			(type solid)
		)
		(fill yes)
		(layer "In11.Cu")
		(net "M_H_CPU1_SB_DQS_DN<9>")
	)
	(gr_poly
		(pts
			(xy 134.851648 -242.090702) (xy 134.851648 -242.046506) (xy 134.496048 -242.046506) (xy 134.496048 -242.090702)
			(xy 134.543038 -242.243102) (xy 134.804658 -242.243102)
		)
		(stroke
			(width 0)
			(type solid)
		)
		(fill yes)
		(layer "In11.Cu")
		(net "M_H_CPU1_SB_DQS_DN<4>")
	)
	(gr_poly
		(pts
			(xy 134.851648 -240.871502) (xy 134.804658 -240.719102) (xy 134.543038 -240.719102) (xy 134.496048 -240.871502)
			(xy 134.496048 -240.915698) (xy 134.851648 -240.915698)
		)
		(stroke
			(width 0)
			(type solid)
		)
		(fill yes)
		(layer "In11.Cu")
		(net "M_H_CPU1_SB_CB<2>")
	)
	(gr_poly
		(pts
			(xy 134.851648 -240.46307) (xy 134.851648 -240.418874) (xy 134.496048 -240.418874) (xy 134.496048 -240.46307)
			(xy 134.543038 -240.61547) (xy 134.804658 -240.61547)
		)
		(stroke
			(width 0)
			(type solid)
		)
		(fill yes)
		(layer "In11.Cu")
		(net "M_H_CPU1_SB_CB<1>")
	)
	(gr_poly
		(pts
			(xy 134.851648 -239.243362) (xy 134.804658 -239.090962) (xy 134.543038 -239.090962) (xy 134.496048 -239.243362)
			(xy 134.496048 -239.287812) (xy 134.851648 -239.287812)
		)
		(stroke
			(width 0)
			(type solid)
		)
		(fill yes)
		(layer "In11.Cu")
		(net "M_H_CPU1_SB_DQ<2>")
	)
	(gr_poly
		(pts
			(xy 134.851648 -229.06863) (xy 134.851648 -229.024434) (xy 134.496048 -229.024434) (xy 134.496048 -229.06863)
			(xy 134.543038 -229.22103) (xy 134.804658 -229.22103)
		)
		(stroke
			(width 0)
			(type solid)
		)
		(fill yes)
		(layer "In11.Cu")
		(net "M_H_CPU1_SB_DQ<27>")
	)
	(gr_poly
		(pts
			(xy 134.851648 -227.848922) (xy 134.804658 -227.696522) (xy 134.543038 -227.696522) (xy 134.496048 -227.848922)
			(xy 134.496048 -227.893372) (xy 134.851648 -227.893372)
		)
		(stroke
			(width 0)
			(type solid)
		)
		(fill yes)
		(layer "In11.Cu")
		(net "M_H_CPU1_SB_DQS_DP<8>")
	)
	(gr_poly
		(pts
			(xy 134.851648 -227.440998) (xy 134.851648 -227.396548) (xy 134.496048 -227.396548) (xy 134.496048 -227.440998)
			(xy 134.543038 -227.593398) (xy 134.804658 -227.593398)
		)
		(stroke
			(width 0)
			(type solid)
		)
		(fill yes)
		(layer "In11.Cu")
		(net "M_H_CPU1_SB_DQS_DP<3>")
	)
	(gr_poly
		(pts
			(xy 134.851648 -226.22129) (xy 134.804658 -226.06889) (xy 134.543038 -226.06889) (xy 134.496048 -226.22129)
			(xy 134.496048 -226.26574) (xy 134.851648 -226.26574)
		)
		(stroke
			(width 0)
			(type solid)
		)
		(fill yes)
		(layer "In11.Cu")
		(net "M_H_CPU1_SB_DQ<28>")
	)
	(gr_poly
		(pts
			(xy 134.924038 -281.444192) (xy 135.032496 -281.327352) (xy 134.901686 -281.100784) (xy 134.746238 -281.136344)
			(xy 134.707884 -281.158442) (xy 134.885684 -281.46629)
		)
		(stroke
			(width 0)
			(type solid)
		)
		(fill yes)
		(layer "In11.Cu")
		(net "M_H_CPU1_SA_DQ<10>")
	)
	(gr_poly
		(pts
			(xy 134.924038 -265.166348) (xy 135.032496 -265.049508) (xy 134.901686 -264.82294) (xy 134.746238 -264.8585)
			(xy 134.707884 -264.880598) (xy 134.885684 -265.188446)
		)
		(stroke
			(width 0)
			(type solid)
		)
		(fill yes)
		(layer "In11.Cu")
		(net "M_H_CPU1_SA_DQS_DP<8>")
	)
	(gr_poly
		(pts
			(xy 134.925054 -268.424406) (xy 135.033512 -268.307566) (xy 134.902702 -268.080998) (xy 134.747254 -268.116558)
			(xy 134.7089 -268.138656) (xy 134.8867 -268.446504)
		)
		(stroke
			(width 0)
			(type solid)
		)
		(fill yes)
		(layer "In11.Cu")
		(net "M_H_CPU1_SA_DQS_DN<3>")
	)
	(gr_poly
		(pts
			(xy 134.952994 -280.16835) (xy 134.906004 -280.01595) (xy 134.644384 -280.01595) (xy 134.597394 -280.16835)
			(xy 134.597394 -280.2128) (xy 134.952994 -280.2128)
		)
		(stroke
			(width 0)
			(type solid)
		)
		(fill yes)
		(layer "In11.Cu")
		(net "M_H_CPU1_SA_DQ<11>")
	)
	(gr_poly
		(pts
			(xy 134.952994 -279.759664) (xy 134.952994 -279.715468) (xy 134.597394 -279.715468) (xy 134.597394 -279.759664)
			(xy 134.644384 -279.912064) (xy 134.906004 -279.912064)
		)
		(stroke
			(width 0)
			(type solid)
		)
		(fill yes)
		(layer "In11.Cu")
		(net "M_H_CPU1_SA_DQS_DP<1>")
	)
	(gr_poly
		(pts
			(xy 134.952994 -278.540718) (xy 134.906004 -278.388318) (xy 134.644384 -278.388318) (xy 134.597394 -278.540718)
			(xy 134.597394 -278.585168) (xy 134.952994 -278.585168)
		)
		(stroke
			(width 0)
			(type solid)
		)
		(fill yes)
		(layer "In11.Cu")
		(net "M_H_CPU1_SA_DQS_DP<6>")
	)
	(gr_poly
		(pts
			(xy 134.952994 -278.132032) (xy 134.952994 -278.087836) (xy 134.597394 -278.087836) (xy 134.597394 -278.132032)
			(xy 134.644384 -278.284432) (xy 134.906004 -278.284432)
		)
		(stroke
			(width 0)
			(type solid)
		)
		(fill yes)
		(layer "In11.Cu")
		(net "M_H_CPU1_SA_DQ<12>")
	)
	(gr_poly
		(pts
			(xy 134.952994 -257.37947) (xy 134.906004 -257.22707) (xy 134.644384 -257.22707) (xy 134.597394 -257.37947)
			(xy 134.597394 -257.42392) (xy 134.952994 -257.42392)
		)
		(stroke
			(width 0)
			(type solid)
		)
		(fill yes)
		(layer "In11.Cu")
		(net "M_H_CPU1_ALERT_N")
	)
	(gr_poly
		(pts
			(xy 134.952994 -256.971038) (xy 134.952994 -256.926588) (xy 134.597394 -256.926588) (xy 134.597394 -256.971038)
			(xy 134.644384 -257.123438) (xy 134.906004 -257.123438)
		)
		(stroke
			(width 0)
			(type solid)
		)
		(fill yes)
		(layer "In11.Cu")
		(net "M_H_CPU1_SA_CS_N<0>")
	)
	(gr_poly
		(pts
			(xy 134.953248 -258.59867) (xy 134.953248 -258.554474) (xy 134.597648 -258.554474) (xy 134.597648 -258.59867)
			(xy 134.644638 -258.75107) (xy 134.906258 -258.75107)
		)
		(stroke
			(width 0)
			(type solid)
		)
		(fill yes)
		(layer "In11.Cu")
		(net "M_H_CPU1_SA_CB<5>")
	)
	(gr_poly
		(pts
			(xy 134.95655 -275.284946) (xy 134.90956 -275.132546) (xy 134.64794 -275.132546) (xy 134.60095 -275.284946)
			(xy 134.60095 -275.329396) (xy 134.95655 -275.329396)
		)
		(stroke
			(width 0)
			(type solid)
		)
		(fill yes)
		(layer "In11.Cu")
		(net "M_H_CPU1_SA_DQ<18>")
	)
	(gr_poly
		(pts
			(xy 134.95909 -263.891014) (xy 134.9121 -263.738614) (xy 134.65048 -263.738614) (xy 134.60349 -263.891014)
			(xy 134.60349 -263.93521) (xy 134.95909 -263.93521)
		)
		(stroke
			(width 0)
			(type solid)
		)
		(fill yes)
		(layer "In11.Cu")
		(net "M_H_CPU1_SA_DQ<30>")
	)
	(gr_poly
		(pts
			(xy 134.95909 -263.482074) (xy 134.95909 -263.437878) (xy 134.60349 -263.437878) (xy 134.60349 -263.482074)
			(xy 134.65048 -263.634474) (xy 134.9121 -263.634474)
		)
		(stroke
			(width 0)
			(type solid)
		)
		(fill yes)
		(layer "In11.Cu")
		(net "M_H_CPU1_SA_DQ<29>")
	)
	(gr_poly
		(pts
			(xy 134.95909 -262.262874) (xy 134.9121 -262.110474) (xy 134.65048 -262.110474) (xy 134.60349 -262.262874)
			(xy 134.60349 -262.307324) (xy 134.95909 -262.307324)
		)
		(stroke
			(width 0)
			(type solid)
		)
		(fill yes)
		(layer "In11.Cu")
		(net "M_H_CPU1_SA_CB<2>")
	)
	(gr_poly
		(pts
			(xy 134.95909 -261.854442) (xy 134.95909 -261.809992) (xy 134.60349 -261.809992) (xy 134.60349 -261.854442)
			(xy 134.65048 -262.006842) (xy 134.9121 -262.006842)
		)
		(stroke
			(width 0)
			(type solid)
		)
		(fill yes)
		(layer "In11.Cu")
		(net "M_H_CPU1_SA_CB<1>")
	)
	(gr_poly
		(pts
			(xy 134.95909 -260.635242) (xy 134.9121 -260.482842) (xy 134.65048 -260.482842) (xy 134.60349 -260.635242)
			(xy 134.60349 -260.679438) (xy 134.95909 -260.679438)
		)
		(stroke
			(width 0)
			(type solid)
		)
		(fill yes)
		(layer "In11.Cu")
		(net "M_H_CPU1_SA_DQS_DN<4>")
	)
	(gr_poly
		(pts
			(xy 134.95909 -260.226302) (xy 134.95909 -260.182106) (xy 134.60349 -260.182106) (xy 134.60349 -260.226302)
			(xy 134.65048 -260.378702) (xy 134.9121 -260.378702)
		)
		(stroke
			(width 0)
			(type solid)
		)
		(fill yes)
		(layer "In11.Cu")
		(net "M_H_CPU1_SA_DQS_DN<9>")
	)
	(gr_poly
		(pts
			(xy 134.95909 -259.00761) (xy 134.9121 -258.85521) (xy 134.65048 -258.85521) (xy 134.60349 -259.00761)
			(xy 134.60349 -259.051806) (xy 134.95909 -259.051806)
		)
		(stroke
			(width 0)
			(type solid)
		)
		(fill yes)
		(layer "In11.Cu")
		(net "M_H_CPU1_SA_CB<6>")
	)
	(gr_poly
		(pts
			(xy 134.95909 -255.751838) (xy 134.9121 -255.599438) (xy 134.65048 -255.599438) (xy 134.60349 -255.751838)
			(xy 134.60349 -255.796288) (xy 134.95909 -255.796288)
		)
		(stroke
			(width 0)
			(type solid)
		)
		(fill yes)
		(layer "In11.Cu")
		(net "M_H_CPU1_SA_CS_N<3>")
	)
	(gr_poly
		(pts
			(xy 134.95909 -255.343406) (xy 134.95909 -255.298956) (xy 134.60349 -255.298956) (xy 134.60349 -255.343406)
			(xy 134.65048 -255.495806) (xy 134.9121 -255.495806)
		)
		(stroke
			(width 0)
			(type solid)
		)
		(fill yes)
		(layer "In11.Cu")
		(net "M_H_CPU1_SA_CA<1>")
	)
	(gr_poly
		(pts
			(xy 134.95909 -254.124206) (xy 134.9121 -253.971806) (xy 134.65048 -253.971806) (xy 134.60349 -254.124206)
			(xy 134.60349 -254.168402) (xy 134.95909 -254.168402)
		)
		(stroke
			(width 0)
			(type solid)
		)
		(fill yes)
		(layer "In11.Cu")
		(net "M_H_CPU1_SA_CA<3>")
	)
	(gr_poly
		(pts
			(xy 134.96163 -276.912578) (xy 134.91464 -276.760178) (xy 134.65302 -276.760178) (xy 134.60603 -276.912578)
			(xy 134.60603 -276.957028) (xy 134.96163 -276.957028)
		)
		(stroke
			(width 0)
			(type solid)
		)
		(fill yes)
		(layer "In11.Cu")
		(net "M_H_CPU1_SA_DQ<15>")
	)
	(gr_poly
		(pts
			(xy 134.96163 -273.657314) (xy 134.91464 -273.504914) (xy 134.65302 -273.504914) (xy 134.60603 -273.657314)
			(xy 134.60603 -273.70151) (xy 134.96163 -273.70151)
		)
		(stroke
			(width 0)
			(type solid)
		)
		(fill yes)
		(layer "In11.Cu")
		(net "M_H_CPU1_SA_DQS_DN<2>")
	)
	(gr_poly
		(pts
			(xy 134.96163 -273.248882) (xy 134.96163 -273.204686) (xy 134.60603 -273.204686) (xy 134.60603 -273.248882)
			(xy 134.65302 -273.401282) (xy 134.91464 -273.401282)
		)
		(stroke
			(width 0)
			(type solid)
		)
		(fill yes)
		(layer "In11.Cu")
		(net "M_H_CPU1_SA_DQS_DN<7>")
	)
	(gr_poly
		(pts
			(xy 134.96163 -272.029174) (xy 134.91464 -271.876774) (xy 134.65302 -271.876774) (xy 134.60603 -272.029174)
			(xy 134.60603 -272.073624) (xy 134.96163 -272.073624)
		)
		(stroke
			(width 0)
			(type solid)
		)
		(fill yes)
		(layer "In11.Cu")
		(net "M_H_CPU1_SA_DQ<22>")
	)
	(gr_poly
		(pts
			(xy 134.96163 -271.62125) (xy 134.96163 -271.5768) (xy 134.60603 -271.5768) (xy 134.60603 -271.62125)
			(xy 134.65302 -271.77365) (xy 134.91464 -271.77365)
		)
		(stroke
			(width 0)
			(type solid)
		)
		(fill yes)
		(layer "In11.Cu")
		(net "M_H_CPU1_SA_DQ<21>")
	)
	(gr_poly
		(pts
			(xy 134.96163 -270.401542) (xy 134.91464 -270.249142) (xy 134.65302 -270.249142) (xy 134.60603 -270.401542)
			(xy 134.60603 -270.445992) (xy 134.96163 -270.445992)
		)
		(stroke
			(width 0)
			(type solid)
		)
		(fill yes)
		(layer "In11.Cu")
		(net "M_H_CPU1_SA_DQ<26>")
	)
	(gr_poly
		(pts
			(xy 134.96163 -269.993618) (xy 134.96163 -269.949168) (xy 134.60603 -269.949168) (xy 134.60603 -269.993618)
			(xy 134.65302 -270.146018) (xy 134.91464 -270.146018)
		)
		(stroke
			(width 0)
			(type solid)
		)
		(fill yes)
		(layer "In11.Cu")
		(net "M_H_CPU1_SA_DQ<25>")
	)
	(gr_poly
		(pts
			(xy 134.962646 -274.876514) (xy 134.962646 -274.832318) (xy 134.607046 -274.832318) (xy 134.607046 -274.876514)
			(xy 134.654036 -275.028914) (xy 134.915656 -275.028914)
		)
		(stroke
			(width 0)
			(type solid)
		)
		(fill yes)
		(layer "In11.Cu")
		(net "M_H_CPU1_SA_DQ<17>")
	)
	(gr_poly
		(pts
			(xy 135.208264 -224.760028) (xy 135.16991 -224.73793) (xy 135.014462 -224.70237) (xy 134.883652 -224.928938)
			(xy 134.99211 -225.045778) (xy 135.030464 -225.067876)
		)
		(stroke
			(width 0)
			(type solid)
		)
		(fill yes)
		(layer "In11.Cu")
		(net "M_H_CPU1_SB_DQ<29>")
	)
	(gr_poly
		(pts
			(xy 135.274304 -266.583922) (xy 135.312658 -266.561824) (xy 135.134858 -266.253976) (xy 135.096504 -266.276074)
			(xy 134.988046 -266.392914) (xy 135.118856 -266.619482)
		)
		(stroke
			(width 0)
			(type solid)
		)
		(fill yes)
		(layer "In11.Cu")
		(net "M_H_CPU1_SA_DQS_DN<8>")
	)
	(gr_poly
		(pts
			(xy 135.274304 -264.956036) (xy 135.312658 -264.933938) (xy 135.134858 -264.62609) (xy 135.096504 -264.648188)
			(xy 134.988046 -264.765028) (xy 135.118856 -264.991596)
		)
		(stroke
			(width 0)
			(type solid)
		)
		(fill yes)
		(layer "In11.Cu")
		(net "M_H_CPU1_SA_DQ<28>")
	)
	(gr_poly
		(pts
			(xy 135.278622 -281.240992) (xy 135.316976 -281.218894) (xy 135.139176 -280.911046) (xy 135.100822 -280.933144)
			(xy 134.992364 -281.049984) (xy 135.123174 -281.276552)
		)
		(stroke
			(width 0)
			(type solid)
		)
		(fill yes)
		(layer "In11.Cu")
		(net "M_H_CPU1_SA_DQ<9>")
	)
	(gr_poly
		(pts
			(xy 135.280654 -282.872688) (xy 135.319008 -282.85059) (xy 135.141208 -282.542742) (xy 135.102854 -282.56484)
			(xy 134.994396 -282.68168) (xy 135.125206 -282.908248)
		)
		(stroke
			(width 0)
			(type solid)
		)
		(fill yes)
		(layer "In11.Cu")
		(net "M_H_CPU1_SA_DQ<8>")
	)
	(gr_poly
		(pts
			(xy 135.30707 -244.532658) (xy 135.30707 -244.488208) (xy 134.95147 -244.488208) (xy 134.95147 -244.532658)
			(xy 134.99846 -244.685058) (xy 135.26008 -244.685058)
		)
		(stroke
			(width 0)
			(type solid)
		)
		(fill yes)
		(layer "In11.Cu")
		(net "M_H_CPU1_SB_CB<6>")
	)
	(gr_poly
		(pts
			(xy 135.30707 -243.31295) (xy 135.26008 -243.16055) (xy 134.99846 -243.16055) (xy 134.95147 -243.31295)
			(xy 134.95147 -243.3574) (xy 135.30707 -243.3574)
		)
		(stroke
			(width 0)
			(type solid)
		)
		(fill yes)
		(layer "In11.Cu")
		(net "M_H_CPU1_SB_CB<5>")
	)
	(gr_poly
		(pts
			(xy 135.30707 -242.905026) (xy 135.30707 -242.860576) (xy 134.95147 -242.860576) (xy 134.95147 -242.905026)
			(xy 134.99846 -243.057426) (xy 135.26008 -243.057426)
		)
		(stroke
			(width 0)
			(type solid)
		)
		(fill yes)
		(layer "In11.Cu")
		(net "M_H_CPU1_SB_DQS_DP<9>")
	)
	(gr_poly
		(pts
			(xy 135.30707 -241.685318) (xy 135.26008 -241.532918) (xy 134.99846 -241.532918) (xy 134.95147 -241.685318)
			(xy 134.95147 -241.729514) (xy 135.30707 -241.729514)
		)
		(stroke
			(width 0)
			(type solid)
		)
		(fill yes)
		(layer "In11.Cu")
		(net "M_H_CPU1_SB_DQS_DP<4>")
	)
	(gr_poly
		(pts
			(xy 135.30707 -241.276886) (xy 135.30707 -241.23269) (xy 134.95147 -241.23269) (xy 134.95147 -241.276886)
			(xy 134.99846 -241.429286) (xy 135.26008 -241.429286)
		)
		(stroke
			(width 0)
			(type solid)
		)
		(fill yes)
		(layer "In11.Cu")
		(net "M_H_CPU1_SB_CB<0>")
	)
	(gr_poly
		(pts
			(xy 135.30707 -240.057178) (xy 135.26008 -239.904778) (xy 134.99846 -239.904778) (xy 134.95147 -240.057178)
			(xy 134.95147 -240.101628) (xy 135.30707 -240.101628)
		)
		(stroke
			(width 0)
			(type solid)
		)
		(fill yes)
		(layer "In11.Cu")
		(net "M_H_CPU1_SB_CB<3>")
	)
	(gr_poly
		(pts
			(xy 135.30707 -239.649254) (xy 135.30707 -239.604804) (xy 134.95147 -239.604804) (xy 134.95147 -239.649254)
			(xy 134.99846 -239.801654) (xy 135.26008 -239.801654)
		)
		(stroke
			(width 0)
			(type solid)
		)
		(fill yes)
		(layer "In11.Cu")
		(net "M_H_CPU1_SB_DQ<0>")
	)
	(gr_poly
		(pts
			(xy 135.30707 -236.393482) (xy 135.30707 -236.349286) (xy 134.95147 -236.349286) (xy 134.95147 -236.393482)
			(xy 134.99846 -236.545882) (xy 135.26008 -236.545882)
		)
		(stroke
			(width 0)
			(type solid)
		)
		(fill yes)
		(layer "In11.Cu")
		(net "M_H_CPU1_SB_DQ<4>")
	)
	(gr_poly
		(pts
			(xy 135.30707 -228.663246) (xy 135.26008 -228.510846) (xy 134.99846 -228.510846) (xy 134.95147 -228.663246)
			(xy 134.95147 -228.707442) (xy 135.30707 -228.707442)
		)
		(stroke
			(width 0)
			(type solid)
		)
		(fill yes)
		(layer "In11.Cu")
		(net "M_H_CPU1_SB_DQ<25>")
	)
	(gr_poly
		(pts
			(xy 135.30707 -228.254814) (xy 135.30707 -228.210618) (xy 134.95147 -228.210618) (xy 134.95147 -228.254814)
			(xy 134.99846 -228.407214) (xy 135.26008 -228.407214)
		)
		(stroke
			(width 0)
			(type solid)
		)
		(fill yes)
		(layer "In11.Cu")
		(net "M_H_CPU1_SB_DQS_DN<8>")
	)
	(gr_poly
		(pts
			(xy 135.30707 -227.035106) (xy 135.26008 -226.882706) (xy 134.99846 -226.882706) (xy 134.95147 -227.035106)
			(xy 134.95147 -227.079556) (xy 135.30707 -227.079556)
		)
		(stroke
			(width 0)
			(type solid)
		)
		(fill yes)
		(layer "In11.Cu")
		(net "M_H_CPU1_SB_DQS_DN<3>")
	)
	(gr_poly
		(pts
			(xy 135.30707 -226.627182) (xy 135.30707 -226.582732) (xy 134.95147 -226.582732) (xy 134.95147 -226.627182)
			(xy 134.99846 -226.779582) (xy 135.26008 -226.779582)
		)
		(stroke
			(width 0)
			(type solid)
		)
		(fill yes)
		(layer "In11.Cu")
		(net "M_H_CPU1_SB_DQ<30>")
	)
	(gr_poly
		(pts
			(xy 135.313166 -248.196354) (xy 135.266176 -248.043954) (xy 135.004556 -248.043954) (xy 134.957566 -248.196354)
			(xy 134.957566 -248.240804) (xy 135.313166 -248.240804)
		)
		(stroke
			(width 0)
			(type solid)
		)
		(fill yes)
		(layer "In11.Cu")
		(net "M_H_CPU1_SB_CA<3>")
	)
	(gr_poly
		(pts
			(xy 135.313166 -246.568722) (xy 135.266176 -246.416322) (xy 135.004556 -246.416322) (xy 134.957566 -246.568722)
			(xy 134.957566 -246.613172) (xy 135.313166 -246.613172)
		)
		(stroke
			(width 0)
			(type solid)
		)
		(fill yes)
		(layer "In11.Cu")
		(net "M_H_CPU1_SB_CA<5>")
	)
	(gr_poly
		(pts
			(xy 135.313166 -246.16029) (xy 135.313166 -246.11584) (xy 134.957566 -246.11584) (xy 134.957566 -246.16029)
			(xy 135.004556 -246.31269) (xy 135.266176 -246.31269)
		)
		(stroke
			(width 0)
			(type solid)
		)
		(fill yes)
		(layer "In11.Cu")
		(net "M_H_CPU1_SB_CA<6>")
	)
	(gr_poly
		(pts
			(xy 135.313166 -238.430054) (xy 135.266176 -238.277654) (xy 135.004556 -238.277654) (xy 134.957566 -238.430054)
			(xy 134.957566 -238.47425) (xy 135.313166 -238.47425)
		)
		(stroke
			(width 0)
			(type solid)
		)
		(fill yes)
		(layer "In11.Cu")
		(net "M_H_CPU1_SB_DQ<3>")
	)
	(gr_poly
		(pts
			(xy 135.313166 -238.021114) (xy 135.313166 -237.976918) (xy 134.957566 -237.976918) (xy 134.957566 -238.021114)
			(xy 135.004556 -238.173514) (xy 135.266176 -238.173514)
		)
		(stroke
			(width 0)
			(type solid)
		)
		(fill yes)
		(layer "In11.Cu")
		(net "M_H_CPU1_SB_DQS_DP<0>")
	)
	(gr_poly
		(pts
			(xy 135.313166 -236.802422) (xy 135.266176 -236.650022) (xy 135.004556 -236.650022) (xy 134.957566 -236.802422)
			(xy 134.957566 -236.846872) (xy 135.313166 -236.846872)
		)
		(stroke
			(width 0)
			(type solid)
		)
		(fill yes)
		(layer "In11.Cu")
		(net "M_H_CPU1_SB_DQS_DP<5>")
	)
	(gr_poly
		(pts
			(xy 135.313166 -235.174282) (xy 135.266176 -235.021882) (xy 135.004556 -235.021882) (xy 134.957566 -235.174282)
			(xy 134.957566 -235.218732) (xy 135.313166 -235.218732)
		)
		(stroke
			(width 0)
			(type solid)
		)
		(fill yes)
		(layer "In11.Cu")
		(net "M_H_CPU1_SB_DQ<7>")
	)
	(gr_poly
		(pts
			(xy 135.313166 -234.76585) (xy 135.313166 -234.7214) (xy 134.957566 -234.7214) (xy 134.957566 -234.76585)
			(xy 135.004556 -234.91825) (xy 135.266176 -234.91825)
		)
		(stroke
			(width 0)
			(type solid)
		)
		(fill yes)
		(layer "In11.Cu")
		(net "M_H_CPU1_SB_DQ<8>")
	)
	(gr_poly
		(pts
			(xy 135.313166 -233.54665) (xy 135.266176 -233.39425) (xy 135.004556 -233.39425) (xy 134.957566 -233.54665)
			(xy 134.957566 -233.590846) (xy 135.313166 -233.590846)
		)
		(stroke
			(width 0)
			(type solid)
		)
		(fill yes)
		(layer "In11.Cu")
		(net "M_H_CPU1_SB_DQ<11>")
	)
	(gr_poly
		(pts
			(xy 135.313166 -233.13771) (xy 135.313166 -233.093514) (xy 134.957566 -233.093514) (xy 134.957566 -233.13771)
			(xy 135.004556 -233.29011) (xy 135.266176 -233.29011)
		)
		(stroke
			(width 0)
			(type solid)
		)
		(fill yes)
		(layer "In11.Cu")
		(net "M_H_CPU1_SB_DQS_DP<1>")
	)
	(gr_poly
		(pts
			(xy 135.313166 -231.919018) (xy 135.266176 -231.766618) (xy 135.004556 -231.766618) (xy 134.957566 -231.919018)
			(xy 134.957566 -231.963214) (xy 135.313166 -231.963214)
		)
		(stroke
			(width 0)
			(type solid)
		)
		(fill yes)
		(layer "In11.Cu")
		(net "M_H_CPU1_SB_DQS_DP<6>")
	)
	(gr_poly
		(pts
			(xy 135.313166 -231.510078) (xy 135.313166 -231.465882) (xy 134.957566 -231.465882) (xy 134.957566 -231.510078)
			(xy 135.004556 -231.662478) (xy 135.266176 -231.662478)
		)
		(stroke
			(width 0)
			(type solid)
		)
		(fill yes)
		(layer "In11.Cu")
		(net "M_H_CPU1_SB_DQ<12>")
	)
	(gr_poly
		(pts
			(xy 135.313166 -230.290878) (xy 135.266176 -230.138478) (xy 135.004556 -230.138478) (xy 134.957566 -230.290878)
			(xy 134.957566 -230.335328) (xy 135.313166 -230.335328)
		)
		(stroke
			(width 0)
			(type solid)
		)
		(fill yes)
		(layer "In11.Cu")
		(net "M_H_CPU1_SB_DQ<15>")
	)
	(gr_poly
		(pts
			(xy 135.313166 -229.882446) (xy 135.313166 -229.837996) (xy 134.957566 -229.837996) (xy 134.957566 -229.882446)
			(xy 135.004556 -230.034846) (xy 135.266176 -230.034846)
		)
		(stroke
			(width 0)
			(type solid)
		)
		(fill yes)
		(layer "In11.Cu")
		(net "M_H_CPU1_SB_DQ<26>")
	)
	(gr_poly
		(pts
			(xy 135.386064 -225.479102) (xy 135.277606 -225.362262) (xy 135.239252 -225.340164) (xy 135.061452 -225.648012)
			(xy 135.099806 -225.67011) (xy 135.255254 -225.70567)
		)
		(stroke
			(width 0)
			(type solid)
		)
		(fill yes)
		(layer "In11.Cu")
		(net "M_H_CPU1_SB_DQ<31>")
	)
	(gr_poly
		(pts
			(xy 135.386572 -265.969242) (xy 135.49503 -265.852402) (xy 135.36422 -265.625834) (xy 135.208772 -265.661394)
			(xy 135.170418 -265.683492) (xy 135.348218 -265.99134)
		)
		(stroke
			(width 0)
			(type solid)
		)
		(fill yes)
		(layer "In11.Cu")
		(net "M_H_CPU1_SA_DQS_DP<8>")
	)
	(gr_poly
		(pts
			(xy 135.38835 -280.621232) (xy 135.496808 -280.504392) (xy 135.365998 -280.277824) (xy 135.21055 -280.313384)
			(xy 135.172196 -280.335482) (xy 135.349996 -280.64333)
		)
		(stroke
			(width 0)
			(type solid)
		)
		(fill yes)
		(layer "In11.Cu")
		(net "M_H_CPU1_SA_DQ<11>")
	)
	(gr_poly
		(pts
			(xy 135.389366 -264.34542) (xy 135.497824 -264.22858) (xy 135.367014 -264.002012) (xy 135.211566 -264.037572)
			(xy 135.173212 -264.05967) (xy 135.351012 -264.367518)
		)
		(stroke
			(width 0)
			(type solid)
		)
		(fill yes)
		(layer "In11.Cu")
		(net "M_H_CPU1_SA_DQ<30>")
	)
	(gr_poly
		(pts
			(xy 135.393938 -282.258008) (xy 135.502396 -282.141168) (xy 135.371586 -281.9146) (xy 135.216138 -281.95016)
			(xy 135.177784 -281.972258) (xy 135.355584 -282.280106)
		)
		(stroke
			(width 0)
			(type solid)
		)
		(fill yes)
		(layer "In11.Cu")
		(net "M_H_CPU1_SA_DQ<10>")
	)
	(gr_poly
		(pts
			(xy 135.414512 -277.318216) (xy 135.414512 -277.27402) (xy 135.058912 -277.27402) (xy 135.058912 -277.318216)
			(xy 135.105902 -277.470616) (xy 135.367522 -277.470616)
		)
		(stroke
			(width 0)
			(type solid)
		)
		(fill yes)
		(layer "In11.Cu")
		(net "M_H_CPU1_SA_DQ<13>")
	)
	(gr_poly
		(pts
			(xy 135.414512 -275.690584) (xy 135.414512 -275.646388) (xy 135.058912 -275.646388) (xy 135.058912 -275.690584)
			(xy 135.105902 -275.842984) (xy 135.367522 -275.842984)
		)
		(stroke
			(width 0)
			(type solid)
		)
		(fill yes)
		(layer "In11.Cu")
		(net "M_H_CPU1_SA_DQ<16>")
	)
	(gr_poly
		(pts
			(xy 135.414512 -274.47113) (xy 135.367522 -274.31873) (xy 135.105902 -274.31873) (xy 135.058912 -274.47113)
			(xy 135.058912 -274.515326) (xy 135.414512 -274.515326)
		)
		(stroke
			(width 0)
			(type solid)
		)
		(fill yes)
		(layer "In11.Cu")
		(net "M_H_CPU1_SA_DQ<19>")
	)
	(gr_poly
		(pts
			(xy 135.414512 -274.062698) (xy 135.414512 -274.018502) (xy 135.058912 -274.018502) (xy 135.058912 -274.062698)
			(xy 135.105902 -274.215098) (xy 135.367522 -274.215098)
		)
		(stroke
			(width 0)
			(type solid)
		)
		(fill yes)
		(layer "In11.Cu")
		(net "M_H_CPU1_SA_DQS_DP<2>")
	)
	(gr_poly
		(pts
			(xy 135.414512 -272.843498) (xy 135.367522 -272.691098) (xy 135.105902 -272.691098) (xy 135.058912 -272.843498)
			(xy 135.058912 -272.887694) (xy 135.414512 -272.887694)
		)
		(stroke
			(width 0)
			(type solid)
		)
		(fill yes)
		(layer "In11.Cu")
		(net "M_H_CPU1_SA_DQS_DP<7>")
	)
	(gr_poly
		(pts
			(xy 135.414512 -272.435066) (xy 135.414512 -272.39087) (xy 135.058912 -272.39087) (xy 135.058912 -272.435066)
			(xy 135.105902 -272.587466) (xy 135.367522 -272.587466)
		)
		(stroke
			(width 0)
			(type solid)
		)
		(fill yes)
		(layer "In11.Cu")
		(net "M_H_CPU1_SA_DQ<20>")
	)
	(gr_poly
		(pts
			(xy 135.414512 -271.215358) (xy 135.367522 -271.062958) (xy 135.105902 -271.062958) (xy 135.058912 -271.215358)
			(xy 135.058912 -271.259808) (xy 135.414512 -271.259808)
		)
		(stroke
			(width 0)
			(type solid)
		)
		(fill yes)
		(layer "In11.Cu")
		(net "M_H_CPU1_SA_DQ<23>")
	)
	(gr_poly
		(pts
			(xy 135.414512 -270.807434) (xy 135.414512 -270.762984) (xy 135.058912 -270.762984) (xy 135.058912 -270.807434)
			(xy 135.105902 -270.959834) (xy 135.367522 -270.959834)
		)
		(stroke
			(width 0)
			(type solid)
		)
		(fill yes)
		(layer "In11.Cu")
		(net "M_H_CPU1_SA_DQ<24>")
	)
	(gr_poly
		(pts
			(xy 135.414512 -269.587726) (xy 135.367522 -269.435326) (xy 135.105902 -269.435326) (xy 135.058912 -269.587726)
			(xy 135.058912 -269.631922) (xy 135.414512 -269.631922)
		)
		(stroke
			(width 0)
			(type solid)
		)
		(fill yes)
		(layer "In11.Cu")
		(net "M_H_CPU1_SA_DQ<27>")
	)
	(gr_poly
		(pts
			(xy 135.414512 -269.179294) (xy 135.414512 -269.135098) (xy 135.058912 -269.135098) (xy 135.058912 -269.179294)
			(xy 135.105902 -269.331694) (xy 135.367522 -269.331694)
		)
		(stroke
			(width 0)
			(type solid)
		)
		(fill yes)
		(layer "In11.Cu")
		(net "M_H_CPU1_SA_DQS_DP<3>")
	)
	(gr_poly
		(pts
			(xy 135.416798 -277.726902) (xy 135.369808 -277.574502) (xy 135.108188 -277.574502) (xy 135.061198 -277.726902)
			(xy 135.061198 -277.771098) (xy 135.416798 -277.771098)
		)
		(stroke
			(width 0)
			(type solid)
		)
		(fill yes)
		(layer "In11.Cu")
		(net "M_H_CPU1_SA_DQ<14>")
	)
	(gr_poly
		(pts
			(xy 135.416798 -259.821426) (xy 135.369808 -259.669026) (xy 135.108188 -259.669026) (xy 135.061198 -259.821426)
			(xy 135.061198 -259.865622) (xy 135.416798 -259.865622)
		)
		(stroke
			(width 0)
			(type solid)
		)
		(fill yes)
		(layer "In11.Cu")
		(net "M_H_CPU1_SA_DQS_DP<9>")
	)
	(gr_poly
		(pts
			(xy 135.416798 -259.412486) (xy 135.416798 -259.36829) (xy 135.061198 -259.36829) (xy 135.061198 -259.412486)
			(xy 135.108188 -259.564886) (xy 135.369808 -259.564886)
		)
		(stroke
			(width 0)
			(type solid)
		)
		(fill yes)
		(layer "In11.Cu")
		(net "M_H_CPU1_SA_CB<4>")
	)
	(gr_poly
		(pts
			(xy 135.422894 -278.945848) (xy 135.422894 -278.901652) (xy 135.067294 -278.901652) (xy 135.067294 -278.945848)
			(xy 135.114284 -279.098248) (xy 135.375904 -279.098248)
		)
		(stroke
			(width 0)
			(type solid)
		)
		(fill yes)
		(layer "In11.Cu")
		(net "M_H_CPU1_SA_DQS_DN<6>")
	)
	(gr_poly
		(pts
			(xy 135.422894 -263.07669) (xy 135.375904 -262.92429) (xy 135.114284 -262.92429) (xy 135.067294 -263.07669)
			(xy 135.067294 -263.12114) (xy 135.422894 -263.12114)
		)
		(stroke
			(width 0)
			(type solid)
		)
		(fill yes)
		(layer "In11.Cu")
		(net "M_H_CPU1_SA_DQ<31>")
	)
	(gr_poly
		(pts
			(xy 135.422894 -262.668258) (xy 135.422894 -262.623808) (xy 135.067294 -262.623808) (xy 135.067294 -262.668258)
			(xy 135.114284 -262.820658) (xy 135.375904 -262.820658)
		)
		(stroke
			(width 0)
			(type solid)
		)
		(fill yes)
		(layer "In11.Cu")
		(net "M_H_CPU1_SA_CB<0>")
	)
	(gr_poly
		(pts
			(xy 135.422894 -261.449058) (xy 135.375904 -261.296658) (xy 135.114284 -261.296658) (xy 135.067294 -261.449058)
			(xy 135.067294 -261.493508) (xy 135.422894 -261.493508)
		)
		(stroke
			(width 0)
			(type solid)
		)
		(fill yes)
		(layer "In11.Cu")
		(net "M_H_CPU1_SA_CB<3>")
	)
	(gr_poly
		(pts
			(xy 135.422894 -261.040626) (xy 135.422894 -260.996176) (xy 135.067294 -260.996176) (xy 135.067294 -261.040626)
			(xy 135.114284 -261.193026) (xy 135.375904 -261.193026)
		)
		(stroke
			(width 0)
			(type solid)
		)
		(fill yes)
		(layer "In11.Cu")
		(net "M_H_CPU1_SA_DQS_DP<4>")
	)
	(gr_poly
		(pts
			(xy 135.422894 -258.193286) (xy 135.375904 -258.040886) (xy 135.114284 -258.040886) (xy 135.067294 -258.193286)
			(xy 135.067294 -258.237736) (xy 135.422894 -258.237736)
		)
		(stroke
			(width 0)
			(type solid)
		)
		(fill yes)
		(layer "In11.Cu")
		(net "M_H_CPU1_SA_CB<7>")
	)
	(gr_poly
		(pts
			(xy 135.422894 -257.784854) (xy 135.422894 -257.740404) (xy 135.067294 -257.740404) (xy 135.067294 -257.784854)
			(xy 135.114284 -257.937254) (xy 135.375904 -257.937254)
		)
		(stroke
			(width 0)
			(type solid)
		)
		(fill yes)
		(layer "In11.Cu")
		(net "M_E_CPU1_ALERT_N")
	)
	(gr_poly
		(pts
			(xy 135.422894 -256.565654) (xy 135.375904 -256.413254) (xy 135.114284 -256.413254) (xy 135.067294 -256.565654)
			(xy 135.067294 -256.610104) (xy 135.422894 -256.610104)
		)
		(stroke
			(width 0)
			(type solid)
		)
		(fill yes)
		(layer "In11.Cu")
		(net "M_H_CPU1_SA_CS_N<1>")
	)
	(gr_poly
		(pts
			(xy 135.422894 -256.157222) (xy 135.422894 -256.112772) (xy 135.067294 -256.112772) (xy 135.067294 -256.157222)
			(xy 135.114284 -256.309622) (xy 135.375904 -256.309622)
		)
		(stroke
			(width 0)
			(type solid)
		)
		(fill yes)
		(layer "In11.Cu")
		(net "M_H_CPU1_SA_CS_N<2>")
	)
	(gr_poly
		(pts
			(xy 135.422894 -254.938022) (xy 135.375904 -254.785622) (xy 135.114284 -254.785622) (xy 135.067294 -254.938022)
			(xy 135.067294 -254.982218) (xy 135.422894 -254.982218)
		)
		(stroke
			(width 0)
			(type solid)
		)
		(fill yes)
		(layer "In11.Cu")
		(net "M_H_CPU1_SA_CA<0>")
	)
	(gr_poly
		(pts
			(xy 135.422894 -254.529082) (xy 135.422894 -254.484886) (xy 135.067294 -254.484886) (xy 135.067294 -254.529082)
			(xy 135.114284 -254.681482) (xy 135.375904 -254.681482)
		)
		(stroke
			(width 0)
			(type solid)
		)
		(fill yes)
		(layer "In11.Cu")
		(net "M_H_CPU1_SA_CA<2>")
	)
	(gr_poly
		(pts
			(xy 135.431276 -279.35428) (xy 135.384286 -279.20188) (xy 135.122666 -279.20188) (xy 135.075676 -279.35428)
			(xy 135.075676 -279.39873) (xy 135.431276 -279.39873)
		)
		(stroke
			(width 0)
			(type solid)
		)
		(fill yes)
		(layer "In11.Cu")
		(net "M_H_CPU1_SA_DQS_DN<1>")
	)
	(gr_poly
		(pts
			(xy 135.638794 -247.64111) (xy 135.677148 -247.619012) (xy 135.499348 -247.311164) (xy 135.460994 -247.333262)
			(xy 135.352536 -247.450102) (xy 135.483346 -247.67667)
		)
		(stroke
			(width 0)
			(type solid)
		)
		(fill yes)
		(layer "In11.Cu")
		(net "M_H_CPU1_SB_CA<4>")
	)
	(gr_poly
		(pts
			(xy 135.67918 -225.572574) (xy 135.640826 -225.550476) (xy 135.485378 -225.514916) (xy 135.354568 -225.741484)
			(xy 135.463026 -225.858324) (xy 135.50138 -225.880422)
		)
		(stroke
			(width 0)
			(type solid)
		)
		(fill yes)
		(layer "In11.Cu")
		(net "M_H_CPU1_SB_DQ<28>")
	)
	(gr_poly
		(pts
			(xy 135.74776 -280.42616) (xy 135.786114 -280.404062) (xy 135.608314 -280.096214) (xy 135.56996 -280.118312)
			(xy 135.461502 -280.235152) (xy 135.592312 -280.46172)
		)
		(stroke
			(width 0)
			(type solid)
		)
		(fill yes)
		(layer "In11.Cu")
		(net "M_H_CPU1_SA_DQS_DP<1>")
	)
	(gr_poly
		(pts
			(xy 135.748522 -282.054808) (xy 135.786876 -282.03271) (xy 135.609076 -281.724862) (xy 135.570722 -281.74696)
			(xy 135.462264 -281.8638) (xy 135.593074 -282.090368)
		)
		(stroke
			(width 0)
			(type solid)
		)
		(fill yes)
		(layer "In11.Cu")
		(net "M_H_CPU1_SA_DQ<9>")
	)
	(gr_poly
		(pts
			(xy 135.748522 -264.149332) (xy 135.786876 -264.127234) (xy 135.609076 -263.819386) (xy 135.570722 -263.841484)
			(xy 135.462264 -263.958324) (xy 135.593074 -264.184892)
		)
		(stroke
			(width 0)
			(type solid)
		)
		(fill yes)
		(layer "In11.Cu")
		(net "M_H_CPU1_SA_DQ<29>")
	)
	(gr_poly
		(pts
			(xy 135.749538 -247.023382) (xy 135.857996 -246.906542) (xy 135.727186 -246.679974) (xy 135.571738 -246.715534)
			(xy 135.533384 -246.737632) (xy 135.711184 -247.04548)
		)
		(stroke
			(width 0)
			(type solid)
		)
		(fill yes)
		(layer "In11.Cu")
		(net "M_H_CPU1_SB_CA<5>")
	)
	(gr_poly
		(pts
			(xy 135.750554 -267.40866) (xy 135.788908 -267.386562) (xy 135.611108 -267.078714) (xy 135.572754 -267.100812)
			(xy 135.464296 -267.217652) (xy 135.595106 -267.44422)
		)
		(stroke
			(width 0)
			(type solid)
		)
		(fill yes)
		(layer "In11.Cu")
		(net "M_H_CPU1_SA_DQS_DN<8>")
	)
	(gr_poly
		(pts
			(xy 135.75157 -265.781028) (xy 135.789924 -265.75893) (xy 135.612124 -265.451082) (xy 135.57377 -265.47318)
			(xy 135.465312 -265.59002) (xy 135.596122 -265.816588)
		)
		(stroke
			(width 0)
			(type solid)
		)
		(fill yes)
		(layer "In11.Cu")
		(net "M_H_CPU1_SA_DQ<28>")
	)
	(gr_poly
		(pts
			(xy 135.77697 -224.593658) (xy 135.72998 -224.441258) (xy 135.46836 -224.441258) (xy 135.42137 -224.593658)
			(xy 135.42137 -224.637854) (xy 135.77697 -224.637854)
		)
		(stroke
			(width 0)
			(type solid)
		)
		(fill yes)
		(layer "In11.Cu")
		(net "M_H_CPU1_SB_DQ<29>")
	)
	(gr_poly
		(pts
			(xy 135.783066 -245.754906) (xy 135.736076 -245.602506) (xy 135.474456 -245.602506) (xy 135.427466 -245.754906)
			(xy 135.427466 -245.799356) (xy 135.783066 -245.799356)
		)
		(stroke
			(width 0)
			(type solid)
		)
		(fill yes)
		(layer "In11.Cu")
		(net "M_H_CPU1_SB_PAR")
	)
	(gr_poly
		(pts
			(xy 135.783066 -244.127274) (xy 135.736076 -243.974874) (xy 135.474456 -243.974874) (xy 135.427466 -244.127274)
			(xy 135.427466 -244.17147) (xy 135.783066 -244.17147)
		)
		(stroke
			(width 0)
			(type solid)
		)
		(fill yes)
		(layer "In11.Cu")
		(net "M_H_CPU1_SB_CB<4>")
	)
	(gr_poly
		(pts
			(xy 135.783066 -243.718334) (xy 135.783066 -243.674138) (xy 135.427466 -243.674138) (xy 135.427466 -243.718334)
			(xy 135.474456 -243.870734) (xy 135.736076 -243.870734)
		)
		(stroke
			(width 0)
			(type solid)
		)
		(fill yes)
		(layer "In11.Cu")
		(net "M_H_CPU1_SB_CB<7>")
	)
	(gr_poly
		(pts
			(xy 135.783066 -242.499134) (xy 135.736076 -242.346734) (xy 135.474456 -242.346734) (xy 135.427466 -242.499134)
			(xy 135.427466 -242.543584) (xy 135.783066 -242.543584)
		)
		(stroke
			(width 0)
			(type solid)
		)
		(fill yes)
		(layer "In11.Cu")
		(net "M_H_CPU1_SB_DQS_DN<9>")
	)
	(gr_poly
		(pts
			(xy 135.783066 -242.090702) (xy 135.783066 -242.046252) (xy 135.427466 -242.046252) (xy 135.427466 -242.090702)
			(xy 135.474456 -242.243102) (xy 135.736076 -242.243102)
		)
		(stroke
			(width 0)
			(type solid)
		)
		(fill yes)
		(layer "In11.Cu")
		(net "M_H_CPU1_SB_DQS_DN<4>")
	)
	(gr_poly
		(pts
			(xy 135.783066 -240.871502) (xy 135.736076 -240.719102) (xy 135.474456 -240.719102) (xy 135.427466 -240.871502)
			(xy 135.427466 -240.915952) (xy 135.783066 -240.915952)
		)
		(stroke
			(width 0)
			(type solid)
		)
		(fill yes)
		(layer "In11.Cu")
		(net "M_H_CPU1_SB_CB<2>")
	)
	(gr_poly
		(pts
			(xy 135.783066 -240.46307) (xy 135.783066 -240.41862) (xy 135.427466 -240.41862) (xy 135.427466 -240.46307)
			(xy 135.474456 -240.61547) (xy 135.736076 -240.61547)
		)
		(stroke
			(width 0)
			(type solid)
		)
		(fill yes)
		(layer "In11.Cu")
		(net "M_H_CPU1_SB_CB<1>")
	)
	(gr_poly
		(pts
			(xy 135.783066 -239.24387) (xy 135.736076 -239.09147) (xy 135.474456 -239.09147) (xy 135.427466 -239.24387)
			(xy 135.427466 -239.288066) (xy 135.783066 -239.288066)
		)
		(stroke
			(width 0)
			(type solid)
		)
		(fill yes)
		(layer "In11.Cu")
		(net "M_H_CPU1_SB_DQ<2>")
	)
	(gr_poly
		(pts
			(xy 135.783066 -238.83493) (xy 135.783066 -238.790734) (xy 135.427466 -238.790734) (xy 135.427466 -238.83493)
			(xy 135.474456 -238.98733) (xy 135.736076 -238.98733)
		)
		(stroke
			(width 0)
			(type solid)
		)
		(fill yes)
		(layer "In11.Cu")
		(net "M_H_CPU1_SB_DQ<1>")
	)
	(gr_poly
		(pts
			(xy 135.783066 -237.61573) (xy 135.736076 -237.46333) (xy 135.474456 -237.46333) (xy 135.427466 -237.61573)
			(xy 135.427466 -237.66018) (xy 135.783066 -237.66018)
		)
		(stroke
			(width 0)
			(type solid)
		)
		(fill yes)
		(layer "In11.Cu")
		(net "M_H_CPU1_SB_DQS_DN<0>")
	)
	(gr_poly
		(pts
			(xy 135.783066 -235.579666) (xy 135.783066 -235.535216) (xy 135.427466 -235.535216) (xy 135.427466 -235.579666)
			(xy 135.474456 -235.732066) (xy 135.736076 -235.732066)
		)
		(stroke
			(width 0)
			(type solid)
		)
		(fill yes)
		(layer "In11.Cu")
		(net "M_H_CPU1_SB_DQ<5>")
	)
	(gr_poly
		(pts
			(xy 135.783066 -234.360466) (xy 135.736076 -234.208066) (xy 135.474456 -234.208066) (xy 135.427466 -234.360466)
			(xy 135.427466 -234.404916) (xy 135.783066 -234.404916)
		)
		(stroke
			(width 0)
			(type solid)
		)
		(fill yes)
		(layer "In11.Cu")
		(net "M_H_CPU1_SB_DQ<10>")
	)
	(gr_poly
		(pts
			(xy 135.783066 -233.952034) (xy 135.783066 -233.907584) (xy 135.427466 -233.907584) (xy 135.427466 -233.952034)
			(xy 135.474456 -234.104434) (xy 135.736076 -234.104434)
		)
		(stroke
			(width 0)
			(type solid)
		)
		(fill yes)
		(layer "In11.Cu")
		(net "M_H_CPU1_SB_DQ<9>")
	)
	(gr_poly
		(pts
			(xy 135.783066 -232.732834) (xy 135.736076 -232.580434) (xy 135.474456 -232.580434) (xy 135.427466 -232.732834)
			(xy 135.427466 -232.77703) (xy 135.783066 -232.77703)
		)
		(stroke
			(width 0)
			(type solid)
		)
		(fill yes)
		(layer "In11.Cu")
		(net "M_H_CPU1_SB_DQS_DN<1>")
	)
	(gr_poly
		(pts
			(xy 135.783066 -232.323894) (xy 135.783066 -232.279698) (xy 135.427466 -232.279698) (xy 135.427466 -232.323894)
			(xy 135.474456 -232.476294) (xy 135.736076 -232.476294)
		)
		(stroke
			(width 0)
			(type solid)
		)
		(fill yes)
		(layer "In11.Cu")
		(net "M_H_CPU1_SB_DQS_DN<6>")
	)
	(gr_poly
		(pts
			(xy 135.783066 -231.104694) (xy 135.736076 -230.952294) (xy 135.474456 -230.952294) (xy 135.427466 -231.104694)
			(xy 135.427466 -231.149144) (xy 135.783066 -231.149144)
		)
		(stroke
			(width 0)
			(type solid)
		)
		(fill yes)
		(layer "In11.Cu")
		(net "M_H_CPU1_SB_DQ<14>")
	)
	(gr_poly
		(pts
			(xy 135.783066 -230.696262) (xy 135.783066 -230.651812) (xy 135.427466 -230.651812) (xy 135.427466 -230.696262)
			(xy 135.474456 -230.848662) (xy 135.736076 -230.848662)
		)
		(stroke
			(width 0)
			(type solid)
		)
		(fill yes)
		(layer "In11.Cu")
		(net "M_H_CPU1_SB_DQ<13>")
	)
	(gr_poly
		(pts
			(xy 135.783066 -229.477062) (xy 135.736076 -229.324662) (xy 135.474456 -229.324662) (xy 135.427466 -229.477062)
			(xy 135.427466 -229.521512) (xy 135.783066 -229.521512)
		)
		(stroke
			(width 0)
			(type solid)
		)
		(fill yes)
		(layer "In11.Cu")
		(net "M_H_CPU1_SB_DQ<24>")
	)
	(gr_poly
		(pts
			(xy 135.783066 -229.06863) (xy 135.783066 -229.02418) (xy 135.427466 -229.02418) (xy 135.427466 -229.06863)
			(xy 135.474456 -229.22103) (xy 135.736076 -229.22103)
		)
		(stroke
			(width 0)
			(type solid)
		)
		(fill yes)
		(layer "In11.Cu")
		(net "M_H_CPU1_SB_DQ<27>")
	)
	(gr_poly
		(pts
			(xy 135.783066 -227.84943) (xy 135.736076 -227.69703) (xy 135.474456 -227.69703) (xy 135.427466 -227.84943)
			(xy 135.427466 -227.893626) (xy 135.783066 -227.893626)
		)
		(stroke
			(width 0)
			(type solid)
		)
		(fill yes)
		(layer "In11.Cu")
		(net "M_H_CPU1_SB_DQS_DP<8>")
	)
	(gr_poly
		(pts
			(xy 135.783066 -227.44049) (xy 135.783066 -227.396294) (xy 135.427466 -227.396294) (xy 135.427466 -227.44049)
			(xy 135.474456 -227.59289) (xy 135.736076 -227.59289)
		)
		(stroke
			(width 0)
			(type solid)
		)
		(fill yes)
		(layer "In11.Cu")
		(net "M_H_CPU1_SB_DQS_DP<3>")
	)
	(gr_poly
		(pts
			(xy 135.791448 -237.207806) (xy 135.791448 -237.163356) (xy 135.435848 -237.163356) (xy 135.435848 -237.207806)
			(xy 135.482838 -237.360206) (xy 135.744458 -237.360206)
		)
		(stroke
			(width 0)
			(type solid)
		)
		(fill yes)
		(layer "In11.Cu")
		(net "M_H_CPU1_SB_DQS_DN<5>")
	)
	(gr_poly
		(pts
			(xy 135.791448 -235.988098) (xy 135.744458 -235.835698) (xy 135.482838 -235.835698) (xy 135.435848 -235.988098)
			(xy 135.435848 -236.032294) (xy 135.791448 -236.032294)
		)
		(stroke
			(width 0)
			(type solid)
		)
		(fill yes)
		(layer "In11.Cu")
		(net "M_H_CPU1_SB_DQ<6>")
	)
	(gr_poly
		(pts
			(xy 135.857234 -263.52754) (xy 135.965692 -263.4107) (xy 135.834882 -263.184132) (xy 135.679434 -263.219692)
			(xy 135.64108 -263.24179) (xy 135.81888 -263.549638)
		)
		(stroke
			(width 0)
			(type solid)
		)
		(fill yes)
		(layer "In11.Cu")
		(net "M_H_CPU1_SA_DQ<31>")
	)
	(gr_poly
		(pts
			(xy 135.857996 -226.289108) (xy 135.749538 -226.172268) (xy 135.711184 -226.15017) (xy 135.533384 -226.458018)
			(xy 135.571738 -226.480116) (xy 135.727186 -226.515676)
		)
		(stroke
			(width 0)
			(type solid)
		)
		(fill yes)
		(layer "In11.Cu")
		(net "M_H_CPU1_SB_DQ<30>")
	)
	(gr_poly
		(pts
			(xy 135.859266 -281.43708) (xy 135.967724 -281.32024) (xy 135.836914 -281.093672) (xy 135.681466 -281.129232)
			(xy 135.643112 -281.15133) (xy 135.820912 -281.459178)
		)
		(stroke
			(width 0)
			(type solid)
		)
		(fill yes)
		(layer "In11.Cu")
		(net "M_H_CPU1_SA_DQ<11>")
	)
	(gr_poly
		(pts
			(xy 135.863584 -279.81656) (xy 135.972042 -279.69972) (xy 135.841232 -279.473152) (xy 135.685784 -279.508712)
			(xy 135.64743 -279.53081) (xy 135.82523 -279.838658)
		)
		(stroke
			(width 0)
			(type solid)
		)
		(fill yes)
		(layer "In11.Cu")
		(net "M_H_CPU1_SA_DQS_DN<1>")
	)
	(gr_poly
		(pts
			(xy 135.863838 -266.79398) (xy 135.972296 -266.67714) (xy 135.841486 -266.450572) (xy 135.686038 -266.486132)
			(xy 135.647684 -266.50823) (xy 135.825484 -266.816078)
		)
		(stroke
			(width 0)
			(type solid)
		)
		(fill yes)
		(layer "In11.Cu")
		(net "M_H_CPU1_SA_DQS_DP<8>")
	)
	(gr_poly
		(pts
			(xy 135.863838 -265.166348) (xy 135.972296 -265.049508) (xy 135.841486 -264.82294) (xy 135.686038 -264.8585)
			(xy 135.647684 -264.880598) (xy 135.825484 -265.188446)
		)
		(stroke
			(width 0)
			(type solid)
		)
		(fill yes)
		(layer "In11.Cu")
		(net "M_H_CPU1_SA_DQ<30>")
	)
	(gr_poly
		(pts
			(xy 135.892794 -283.015436) (xy 135.892794 -282.97124) (xy 135.537194 -282.97124) (xy 135.537194 -283.015436)
			(xy 135.584184 -283.167836) (xy 135.845804 -283.167836)
		)
		(stroke
			(width 0)
			(type solid)
		)
		(fill yes)
		(layer "In11.Cu")
		(net "M_H_CPU1_SA_DQ<8>")
	)
	(gr_poly
		(pts
			(xy 135.892794 -278.540718) (xy 135.845804 -278.388318) (xy 135.584184 -278.388318) (xy 135.537194 -278.540718)
			(xy 135.537194 -278.585168) (xy 135.892794 -278.585168)
		)
		(stroke
			(width 0)
			(type solid)
		)
		(fill yes)
		(layer "In11.Cu")
		(net "M_H_CPU1_SA_DQS_DP<6>")
	)
	(gr_poly
		(pts
			(xy 135.892794 -262.262874) (xy 135.845804 -262.110474) (xy 135.584184 -262.110474) (xy 135.537194 -262.262874)
			(xy 135.537194 -262.307324) (xy 135.892794 -262.307324)
		)
		(stroke
			(width 0)
			(type solid)
		)
		(fill yes)
		(layer "In11.Cu")
		(net "M_H_CPU1_SA_CB<2>")
	)
	(gr_poly
		(pts
			(xy 135.892794 -261.854442) (xy 135.892794 -261.809992) (xy 135.537194 -261.809992) (xy 135.537194 -261.854442)
			(xy 135.584184 -262.006842) (xy 135.845804 -262.006842)
		)
		(stroke
			(width 0)
			(type solid)
		)
		(fill yes)
		(layer "In11.Cu")
		(net "M_H_CPU1_SA_CB<1>")
	)
	(gr_poly
		(pts
			(xy 135.892794 -260.635242) (xy 135.845804 -260.482842) (xy 135.584184 -260.482842) (xy 135.537194 -260.635242)
			(xy 135.537194 -260.679438) (xy 135.892794 -260.679438)
		)
		(stroke
			(width 0)
			(type solid)
		)
		(fill yes)
		(layer "In11.Cu")
		(net "M_H_CPU1_SA_DQS_DN<4>")
	)
	(gr_poly
		(pts
			(xy 135.892794 -258.59867) (xy 135.892794 -258.554474) (xy 135.537194 -258.554474) (xy 135.537194 -258.59867)
			(xy 135.584184 -258.75107) (xy 135.845804 -258.75107)
		)
		(stroke
			(width 0)
			(type solid)
		)
		(fill yes)
		(layer "In11.Cu")
		(net "M_H_CPU1_SA_CB<5>")
	)
	(gr_poly
		(pts
			(xy 135.892794 -257.37947) (xy 135.845804 -257.22707) (xy 135.584184 -257.22707) (xy 135.537194 -257.37947)
			(xy 135.537194 -257.42392) (xy 135.892794 -257.42392)
		)
		(stroke
			(width 0)
			(type solid)
		)
		(fill yes)
		(layer "In11.Cu")
		(net "M_H_CPU1_ALERT_N")
	)
	(gr_poly
		(pts
			(xy 135.892794 -256.971038) (xy 135.892794 -256.926588) (xy 135.537194 -256.926588) (xy 135.537194 -256.971038)
			(xy 135.584184 -257.123438) (xy 135.845804 -257.123438)
		)
		(stroke
			(width 0)
			(type solid)
		)
		(fill yes)
		(layer "In11.Cu")
		(net "M_H_CPU1_SA_CS_N<0>")
	)
	(gr_poly
		(pts
			(xy 135.892794 -255.751838) (xy 135.845804 -255.599438) (xy 135.584184 -255.599438) (xy 135.537194 -255.751838)
			(xy 135.537194 -255.796288) (xy 135.892794 -255.796288)
		)
		(stroke
			(width 0)
			(type solid)
		)
		(fill yes)
		(layer "In11.Cu")
		(net "M_H_CPU1_SA_CS_N<3>")
	)
	(gr_poly
		(pts
			(xy 135.892794 -255.343406) (xy 135.892794 -255.298956) (xy 135.537194 -255.298956) (xy 135.537194 -255.343406)
			(xy 135.584184 -255.495806) (xy 135.845804 -255.495806)
		)
		(stroke
			(width 0)
			(type solid)
		)
		(fill yes)
		(layer "In11.Cu")
		(net "M_H_CPU1_SA_CA<1>")
	)
	(gr_poly
		(pts
			(xy 135.892794 -254.124206) (xy 135.845804 -253.971806) (xy 135.584184 -253.971806) (xy 135.537194 -254.124206)
			(xy 135.537194 -254.168402) (xy 135.892794 -254.168402)
		)
		(stroke
			(width 0)
			(type solid)
		)
		(fill yes)
		(layer "In11.Cu")
		(net "M_H_CPU1_SA_CA<3>")
	)
	(gr_poly
		(pts
			(xy 135.89889 -273.657314) (xy 135.8519 -273.504914) (xy 135.59028 -273.504914) (xy 135.54329 -273.657314)
			(xy 135.54329 -273.701764) (xy 135.89889 -273.701764)
		)
		(stroke
			(width 0)
			(type solid)
		)
		(fill yes)
		(layer "In11.Cu")
		(net "M_H_CPU1_SA_DQS_DN<2>")
	)
	(gr_poly
		(pts
			(xy 135.89889 -273.248882) (xy 135.89889 -273.204432) (xy 135.54329 -273.204432) (xy 135.54329 -273.248882)
			(xy 135.59028 -273.401282) (xy 135.8519 -273.401282)
		)
		(stroke
			(width 0)
			(type solid)
		)
		(fill yes)
		(layer "In11.Cu")
		(net "M_H_CPU1_SA_DQS_DN<7>")
	)
	(gr_poly
		(pts
			(xy 135.89889 -268.77391) (xy 135.8519 -268.62151) (xy 135.59028 -268.62151) (xy 135.54329 -268.77391)
			(xy 135.54329 -268.81836) (xy 135.89889 -268.81836)
		)
		(stroke
			(width 0)
			(type solid)
		)
		(fill yes)
		(layer "In11.Cu")
		(net "M_H_CPU1_SA_DQS_DN<3>")
	)
	(gr_poly
		(pts
			(xy 135.901176 -278.132286) (xy 135.901176 -278.08809) (xy 135.545576 -278.08809) (xy 135.545576 -278.132286)
			(xy 135.592566 -278.284686) (xy 135.854186 -278.284686)
		)
		(stroke
			(width 0)
			(type solid)
		)
		(fill yes)
		(layer "In11.Cu")
		(net "M_H_CPU1_SA_DQ<12>")
	)
	(gr_poly
		(pts
			(xy 135.901176 -276.912578) (xy 135.854186 -276.760178) (xy 135.592566 -276.760178) (xy 135.545576 -276.912578)
			(xy 135.545576 -276.957028) (xy 135.901176 -276.957028)
		)
		(stroke
			(width 0)
			(type solid)
		)
		(fill yes)
		(layer "In11.Cu")
		(net "M_H_CPU1_SA_DQ<15>")
	)
	(gr_poly
		(pts
			(xy 135.901176 -260.22681) (xy 135.901176 -260.18236) (xy 135.545576 -260.18236) (xy 135.545576 -260.22681)
			(xy 135.592566 -260.37921) (xy 135.854186 -260.37921)
		)
		(stroke
			(width 0)
			(type solid)
		)
		(fill yes)
		(layer "In11.Cu")
		(net "M_H_CPU1_SA_DQS_DN<9>")
	)
	(gr_poly
		(pts
			(xy 135.901176 -259.007102) (xy 135.854186 -258.854702) (xy 135.592566 -258.854702) (xy 135.545576 -259.007102)
			(xy 135.545576 -259.051552) (xy 135.901176 -259.051552)
		)
		(stroke
			(width 0)
			(type solid)
		)
		(fill yes)
		(layer "In11.Cu")
		(net "M_H_CPU1_SA_CB<6>")
	)
	(gr_poly
		(pts
			(xy 135.90143 -274.876768) (xy 135.90143 -274.832572) (xy 135.54583 -274.832572) (xy 135.54583 -274.876768)
			(xy 135.59282 -275.029168) (xy 135.85444 -275.029168)
		)
		(stroke
			(width 0)
			(type solid)
		)
		(fill yes)
		(layer "In11.Cu")
		(net "M_H_CPU1_SA_DQ<17>")
	)
	(gr_poly
		(pts
			(xy 135.90143 -272.029174) (xy 135.85444 -271.876774) (xy 135.59282 -271.876774) (xy 135.54583 -272.029174)
			(xy 135.54583 -272.073624) (xy 135.90143 -272.073624)
		)
		(stroke
			(width 0)
			(type solid)
		)
		(fill yes)
		(layer "In11.Cu")
		(net "M_H_CPU1_SA_DQ<22>")
	)
	(gr_poly
		(pts
			(xy 135.90143 -271.62125) (xy 135.90143 -271.5768) (xy 135.54583 -271.5768) (xy 135.54583 -271.62125)
			(xy 135.59282 -271.77365) (xy 135.85444 -271.77365)
		)
		(stroke
			(width 0)
			(type solid)
		)
		(fill yes)
		(layer "In11.Cu")
		(net "M_H_CPU1_SA_DQ<21>")
	)
	(gr_poly
		(pts
			(xy 135.90143 -270.401542) (xy 135.85444 -270.249142) (xy 135.59282 -270.249142) (xy 135.54583 -270.401542)
			(xy 135.54583 -270.445992) (xy 135.90143 -270.445992)
		)
		(stroke
			(width 0)
			(type solid)
		)
		(fill yes)
		(layer "In11.Cu")
		(net "M_H_CPU1_SA_DQ<26>")
	)
	(gr_poly
		(pts
			(xy 135.90143 -269.993618) (xy 135.90143 -269.949168) (xy 135.54583 -269.949168) (xy 135.54583 -269.993618)
			(xy 135.59282 -270.146018) (xy 135.85444 -270.146018)
		)
		(stroke
			(width 0)
			(type solid)
		)
		(fill yes)
		(layer "In11.Cu")
		(net "M_H_CPU1_SA_DQ<25>")
	)
	(gr_poly
		(pts
			(xy 136.108694 -246.827294) (xy 136.147048 -246.805196) (xy 135.969248 -246.497348) (xy 135.930894 -246.519446)
			(xy 135.822436 -246.636286) (xy 135.953246 -246.862854)
		)
		(stroke
			(width 0)
			(type solid)
		)
		(fill yes)
		(layer "In11.Cu")
		(net "M_H_CPU1_SB_CA<6>")
	)
	(gr_poly
		(pts
			(xy 136.147048 -226.390454) (xy 136.108694 -226.368356) (xy 135.953246 -226.332796) (xy 135.822436 -226.559364)
			(xy 135.930894 -226.676204) (xy 135.969248 -226.698302)
		)
		(stroke
			(width 0)
			(type solid)
		)
		(fill yes)
		(layer "In11.Cu")
		(net "M_H_CPU1_SB_DQS_DN<3>")
	)
	(gr_poly
		(pts
			(xy 136.214104 -264.956036) (xy 136.252458 -264.933938) (xy 136.074658 -264.62609) (xy 136.036304 -264.648188)
			(xy 135.927846 -264.765028) (xy 136.058656 -264.991596)
		)
		(stroke
			(width 0)
			(type solid)
		)
		(fill yes)
		(layer "In11.Cu")
		(net "M_H_CPU1_SA_DQ<29>")
	)
	(gr_poly
		(pts
			(xy 136.218422 -281.240992) (xy 136.256776 -281.218894) (xy 136.078976 -280.911046) (xy 136.040622 -280.933144)
			(xy 135.932164 -281.049984) (xy 136.062974 -281.276552)
		)
		(stroke
			(width 0)
			(type solid)
		)
		(fill yes)
		(layer "In11.Cu")
		(net "M_H_CPU1_SA_DQS_DP<1>")
	)
	(gr_poly
		(pts
			(xy 136.218422 -279.613106) (xy 136.256776 -279.591008) (xy 136.078976 -279.28316) (xy 136.040622 -279.305258)
			(xy 135.932164 -279.422098) (xy 136.062974 -279.648666)
		)
		(stroke
			(width 0)
			(type solid)
		)
		(fill yes)
		(layer "In11.Cu")
		(net "M_H_CPU1_SA_DQS_DN<6>")
	)
	(gr_poly
		(pts
			(xy 136.218422 -268.218666) (xy 136.256776 -268.196568) (xy 136.078976 -267.88872) (xy 136.040622 -267.910818)
			(xy 135.932164 -268.027658) (xy 136.062974 -268.254226)
		)
		(stroke
			(width 0)
			(type solid)
		)
		(fill yes)
		(layer "In11.Cu")
		(net "M_H_CPU1_SA_DQS_DN<8>")
	)
	(gr_poly
		(pts
			(xy 136.218422 -266.591034) (xy 136.256776 -266.568936) (xy 136.078976 -266.261088) (xy 136.040622 -266.283186)
			(xy 135.932164 -266.400026) (xy 136.062974 -266.626594)
		)
		(stroke
			(width 0)
			(type solid)
		)
		(fill yes)
		(layer "In11.Cu")
		(net "M_H_CPU1_SA_DQ<28>")
	)
	(gr_poly
		(pts
			(xy 136.219438 -246.209566) (xy 136.327896 -246.092726) (xy 136.197086 -245.866158) (xy 136.041638 -245.901718)
			(xy 136.003284 -245.923816) (xy 136.181084 -246.231664)
		)
		(stroke
			(width 0)
			(type solid)
		)
		(fill yes)
		(layer "In11.Cu")
		(net "M_H_CPU1_SB_PAR")
	)
	(gr_poly
		(pts
			(xy 136.219438 -244.58168) (xy 136.327896 -244.46484) (xy 136.197086 -244.238272) (xy 136.041638 -244.273832)
			(xy 136.003284 -244.29593) (xy 136.181084 -244.603778)
		)
		(stroke
			(width 0)
			(type solid)
		)
		(fill yes)
		(layer "In11.Cu")
		(net "M_H_CPU1_SB_CB<4>")
	)
	(gr_poly
		(pts
			(xy 136.220454 -263.339326) (xy 136.258808 -263.317228) (xy 136.081008 -263.00938) (xy 136.042654 -263.031478)
			(xy 135.934196 -263.148318) (xy 136.065006 -263.374886)
		)
		(stroke
			(width 0)
			(type solid)
		)
		(fill yes)
		(layer "In11.Cu")
		(net "M_H_CPU1_SA_CB<0>")
	)
	(gr_poly
		(pts
			(xy 136.24433 -236.801914) (xy 136.19734 -236.649514) (xy 135.93572 -236.649514) (xy 135.88873 -236.801914)
			(xy 135.88873 -236.84611) (xy 136.24433 -236.84611)
		)
		(stroke
			(width 0)
			(type solid)
		)
		(fill yes)
		(layer "In11.Cu")
		(net "M_H_CPU1_SB_DQS_DP<5>")
	)
	(gr_poly
		(pts
			(xy 136.24433 -236.39399) (xy 136.24433 -236.34954) (xy 135.88873 -236.34954) (xy 135.88873 -236.39399)
			(xy 135.93572 -236.54639) (xy 136.19734 -236.54639)
		)
		(stroke
			(width 0)
			(type solid)
		)
		(fill yes)
		(layer "In11.Cu")
		(net "M_H_CPU1_SB_DQ<4>")
	)
	(gr_poly
		(pts
			(xy 136.24687 -240.057686) (xy 136.19988 -239.905286) (xy 135.93826 -239.905286) (xy 135.89127 -240.057686)
			(xy 135.89127 -240.101882) (xy 136.24687 -240.101882)
		)
		(stroke
			(width 0)
			(type solid)
		)
		(fill yes)
		(layer "In11.Cu")
		(net "M_H_CPU1_SB_CB<3>")
	)
	(gr_poly
		(pts
			(xy 136.24687 -239.648746) (xy 136.24687 -239.60455) (xy 135.89127 -239.60455) (xy 135.89127 -239.648746)
			(xy 135.93826 -239.801146) (xy 136.19988 -239.801146)
		)
		(stroke
			(width 0)
			(type solid)
		)
		(fill yes)
		(layer "In11.Cu")
		(net "M_H_CPU1_SB_DQ<0>")
	)
	(gr_poly
		(pts
			(xy 136.24687 -235.174282) (xy 136.19988 -235.021882) (xy 135.93826 -235.021882) (xy 135.89127 -235.174282)
			(xy 135.89127 -235.218732) (xy 136.24687 -235.218732)
		)
		(stroke
			(width 0)
			(type solid)
		)
		(fill yes)
		(layer "In11.Cu")
		(net "M_H_CPU1_SB_DQ<7>")
	)
	(gr_poly
		(pts
			(xy 136.24687 -234.76585) (xy 136.24687 -234.7214) (xy 135.89127 -234.7214) (xy 135.89127 -234.76585)
			(xy 135.93826 -234.91825) (xy 136.19988 -234.91825)
		)
		(stroke
			(width 0)
			(type solid)
		)
		(fill yes)
		(layer "In11.Cu")
		(net "M_H_CPU1_SB_DQ<8>")
	)
	(gr_poly
		(pts
			(xy 136.252966 -248.196354) (xy 136.205976 -248.043954) (xy 135.944356 -248.043954) (xy 135.897366 -248.196354)
			(xy 135.897366 -248.240804) (xy 136.252966 -248.240804)
		)
		(stroke
			(width 0)
			(type solid)
		)
		(fill yes)
		(layer "In11.Cu")
		(net "M_H_CPU1_SB_CA<3>")
	)
	(gr_poly
		(pts
			(xy 136.252966 -247.787922) (xy 136.252966 -247.743472) (xy 135.897366 -247.743472) (xy 135.897366 -247.787922)
			(xy 135.944356 -247.940322) (xy 136.205976 -247.940322)
		)
		(stroke
			(width 0)
			(type solid)
		)
		(fill yes)
		(layer "In11.Cu")
		(net "M_H_CPU1_SB_CA<4>")
	)
	(gr_poly
		(pts
			(xy 136.252966 -243.313458) (xy 136.205976 -243.161058) (xy 135.944356 -243.161058) (xy 135.897366 -243.313458)
			(xy 135.897366 -243.357654) (xy 136.252966 -243.357654)
		)
		(stroke
			(width 0)
			(type solid)
		)
		(fill yes)
		(layer "In11.Cu")
		(net "M_H_CPU1_SB_CB<5>")
	)
	(gr_poly
		(pts
			(xy 136.252966 -242.904518) (xy 136.252966 -242.860322) (xy 135.897366 -242.860322) (xy 135.897366 -242.904518)
			(xy 135.944356 -243.056918) (xy 136.205976 -243.056918)
		)
		(stroke
			(width 0)
			(type solid)
		)
		(fill yes)
		(layer "In11.Cu")
		(net "M_H_CPU1_SB_DQS_DP<9>")
	)
	(gr_poly
		(pts
			(xy 136.252966 -241.685318) (xy 136.205976 -241.532918) (xy 135.944356 -241.532918) (xy 135.897366 -241.685318)
			(xy 135.897366 -241.729768) (xy 136.252966 -241.729768)
		)
		(stroke
			(width 0)
			(type solid)
		)
		(fill yes)
		(layer "In11.Cu")
		(net "M_H_CPU1_SB_DQS_DP<4>")
	)
	(gr_poly
		(pts
			(xy 136.252966 -241.276886) (xy 136.252966 -241.232436) (xy 135.897366 -241.232436) (xy 135.897366 -241.276886)
			(xy 135.944356 -241.429286) (xy 136.205976 -241.429286)
		)
		(stroke
			(width 0)
			(type solid)
		)
		(fill yes)
		(layer "In11.Cu")
		(net "M_H_CPU1_SB_CB<0>")
	)
	(gr_poly
		(pts
			(xy 136.252966 -238.430054) (xy 136.205976 -238.277654) (xy 135.944356 -238.277654) (xy 135.897366 -238.430054)
			(xy 135.897366 -238.47425) (xy 136.252966 -238.47425)
		)
		(stroke
			(width 0)
			(type solid)
		)
		(fill yes)
		(layer "In11.Cu")
		(net "M_H_CPU1_SB_DQ<3>")
	)
	(gr_poly
		(pts
			(xy 136.252966 -238.021114) (xy 136.252966 -237.976918) (xy 135.897366 -237.976918) (xy 135.897366 -238.021114)
			(xy 135.944356 -238.173514) (xy 136.205976 -238.173514)
		)
		(stroke
			(width 0)
			(type solid)
		)
		(fill yes)
		(layer "In11.Cu")
		(net "M_H_CPU1_SB_DQS_DP<0>")
	)
	(gr_poly
		(pts
			(xy 136.252966 -233.54665) (xy 136.205976 -233.39425) (xy 135.944356 -233.39425) (xy 135.897366 -233.54665)
			(xy 135.897366 -233.590846) (xy 136.252966 -233.590846)
		)
		(stroke
			(width 0)
			(type solid)
		)
		(fill yes)
		(layer "In11.Cu")
		(net "M_H_CPU1_SB_DQ<11>")
	)
	(gr_poly
		(pts
			(xy 136.252966 -233.13771) (xy 136.252966 -233.093514) (xy 135.897366 -233.093514) (xy 135.897366 -233.13771)
			(xy 135.944356 -233.29011) (xy 136.205976 -233.29011)
		)
		(stroke
			(width 0)
			(type solid)
		)
		(fill yes)
		(layer "In11.Cu")
		(net "M_H_CPU1_SB_DQS_DP<1>")
	)
	(gr_poly
		(pts
			(xy 136.252966 -231.919018) (xy 136.205976 -231.766618) (xy 135.944356 -231.766618) (xy 135.897366 -231.919018)
			(xy 135.897366 -231.963214) (xy 136.252966 -231.963214)
		)
		(stroke
			(width 0)
			(type solid)
		)
		(fill yes)
		(layer "In11.Cu")
		(net "M_H_CPU1_SB_DQS_DP<6>")
	)
	(gr_poly
		(pts
			(xy 136.252966 -231.510078) (xy 136.252966 -231.465882) (xy 135.897366 -231.465882) (xy 135.897366 -231.510078)
			(xy 135.944356 -231.662478) (xy 136.205976 -231.662478)
		)
		(stroke
			(width 0)
			(type solid)
		)
		(fill yes)
		(layer "In11.Cu")
		(net "M_H_CPU1_SB_DQ<12>")
	)
	(gr_poly
		(pts
			(xy 136.252966 -230.290878) (xy 136.205976 -230.138478) (xy 135.944356 -230.138478) (xy 135.897366 -230.290878)
			(xy 135.897366 -230.335328) (xy 136.252966 -230.335328)
		)
		(stroke
			(width 0)
			(type solid)
		)
		(fill yes)
		(layer "In11.Cu")
		(net "M_H_CPU1_SB_DQ<15>")
	)
	(gr_poly
		(pts
			(xy 136.252966 -229.882446) (xy 136.252966 -229.837996) (xy 135.897366 -229.837996) (xy 135.897366 -229.882446)
			(xy 135.944356 -230.034846) (xy 136.205976 -230.034846)
		)
		(stroke
			(width 0)
			(type solid)
		)
		(fill yes)
		(layer "In11.Cu")
		(net "M_H_CPU1_SB_DQ<26>")
	)
	(gr_poly
		(pts
			(xy 136.252966 -228.663246) (xy 136.205976 -228.510846) (xy 135.944356 -228.510846) (xy 135.897366 -228.663246)
			(xy 135.897366 -228.707696) (xy 136.252966 -228.707696)
		)
		(stroke
			(width 0)
			(type solid)
		)
		(fill yes)
		(layer "In11.Cu")
		(net "M_H_CPU1_SB_DQ<25>")
	)
	(gr_poly
		(pts
			(xy 136.252966 -228.254814) (xy 136.252966 -228.210364) (xy 135.897366 -228.210364) (xy 135.897366 -228.254814)
			(xy 135.944356 -228.407214) (xy 136.205976 -228.407214)
		)
		(stroke
			(width 0)
			(type solid)
		)
		(fill yes)
		(layer "In11.Cu")
		(net "M_H_CPU1_SB_DQS_DN<8>")
	)
	(gr_poly
		(pts
			(xy 136.252966 -225.407474) (xy 136.205976 -225.255074) (xy 135.944356 -225.255074) (xy 135.897366 -225.407474)
			(xy 135.897366 -225.451924) (xy 136.252966 -225.451924)
		)
		(stroke
			(width 0)
			(type solid)
		)
		(fill yes)
		(layer "In11.Cu")
		(net "M_H_CPU1_SB_DQ<28>")
	)
	(gr_poly
		(pts
			(xy 136.252966 -224.999042) (xy 136.252966 -224.954592) (xy 135.897366 -224.954592) (xy 135.897366 -224.999042)
			(xy 135.944356 -225.151442) (xy 136.205976 -225.151442)
		)
		(stroke
			(width 0)
			(type solid)
		)
		(fill yes)
		(layer "In11.Cu")
		(net "M_H_CPU1_SB_DQ<31>")
	)
	(gr_poly
		(pts
			(xy 136.326372 -265.969242) (xy 136.43483 -265.852402) (xy 136.30402 -265.625834) (xy 136.148572 -265.661394)
			(xy 136.110218 -265.683492) (xy 136.288018 -265.99134)
		)
		(stroke
			(width 0)
			(type solid)
		)
		(fill yes)
		(layer "In11.Cu")
		(net "M_H_CPU1_SA_DQ<30>")
	)
	(gr_poly
		(pts
			(xy 136.327134 -280.6192) (xy 136.435592 -280.50236) (xy 136.304782 -280.275792) (xy 136.149334 -280.311352)
			(xy 136.11098 -280.33345) (xy 136.28878 -280.641298)
		)
		(stroke
			(width 0)
			(type solid)
		)
		(fill yes)
		(layer "In11.Cu")
		(net "M_H_CPU1_SA_DQS_DN<1>")
	)
	(gr_poly
		(pts
			(xy 136.327134 -267.596874) (xy 136.435592 -267.480034) (xy 136.304782 -267.253466) (xy 136.149334 -267.289026)
			(xy 136.11098 -267.311124) (xy 136.28878 -267.618972)
		)
		(stroke
			(width 0)
			(type solid)
		)
		(fill yes)
		(layer "In11.Cu")
		(net "M_H_CPU1_SA_DQS_DP<8>")
	)
	(gr_poly
		(pts
			(xy 136.327896 -227.102924) (xy 136.219438 -226.986084) (xy 136.181084 -226.963986) (xy 136.003284 -227.271834)
			(xy 136.041638 -227.293932) (xy 136.197086 -227.329492)
		)
		(stroke
			(width 0)
			(type solid)
		)
		(fill yes)
		(layer "In11.Cu")
		(net "M_H_CPU1_SB_DQS_DP<3>")
	)
	(gr_poly
		(pts
			(xy 136.329166 -278.995378) (xy 136.437624 -278.878538) (xy 136.306814 -278.65197) (xy 136.151366 -278.68753)
			(xy 136.113012 -278.709628) (xy 136.290812 -279.017476)
		)
		(stroke
			(width 0)
			(type solid)
		)
		(fill yes)
		(layer "In11.Cu")
		(net "M_H_CPU1_SA_DQS_DP<6>")
	)
	(gr_poly
		(pts
			(xy 136.329166 -264.34542) (xy 136.437624 -264.22858) (xy 136.306814 -264.002012) (xy 136.151366 -264.037572)
			(xy 136.113012 -264.05967) (xy 136.290812 -264.367518)
		)
		(stroke
			(width 0)
			(type solid)
		)
		(fill yes)
		(layer "In11.Cu")
		(net "M_H_CPU1_SA_DQ<31>")
	)
	(gr_poly
		(pts
			(xy 136.329166 -262.717534) (xy 136.437624 -262.600694) (xy 136.306814 -262.374126) (xy 136.151366 -262.409686)
			(xy 136.113012 -262.431784) (xy 136.290812 -262.739632)
		)
		(stroke
			(width 0)
			(type solid)
		)
		(fill yes)
		(layer "In11.Cu")
		(net "M_H_CPU1_SA_CB<2>")
	)
	(gr_poly
		(pts
			(xy 136.354058 -259.820918) (xy 136.307068 -259.668518) (xy 136.045448 -259.668518) (xy 135.998458 -259.820918)
			(xy 135.998458 -259.865368) (xy 136.354058 -259.865368)
		)
		(stroke
			(width 0)
			(type solid)
		)
		(fill yes)
		(layer "In11.Cu")
		(net "M_H_CPU1_SA_DQS_DP<9>")
	)
	(gr_poly
		(pts
			(xy 136.354058 -259.412994) (xy 136.354058 -259.368544) (xy 135.998458 -259.368544) (xy 135.998458 -259.412994)
			(xy 136.045448 -259.565394) (xy 136.307068 -259.565394)
		)
		(stroke
			(width 0)
			(type solid)
		)
		(fill yes)
		(layer "In11.Cu")
		(net "M_H_CPU1_SA_CB<4>")
	)
	(gr_poly
		(pts
			(xy 136.354312 -274.47113) (xy 136.307322 -274.31873) (xy 136.045702 -274.31873) (xy 135.998712 -274.47113)
			(xy 135.998712 -274.515326) (xy 136.354312 -274.515326)
		)
		(stroke
			(width 0)
			(type solid)
		)
		(fill yes)
		(layer "In11.Cu")
		(net "M_H_CPU1_SA_DQ<19>")
	)
	(gr_poly
		(pts
			(xy 136.354312 -272.435066) (xy 136.354312 -272.39087) (xy 135.998712 -272.39087) (xy 135.998712 -272.435066)
			(xy 136.045702 -272.587466) (xy 136.307322 -272.587466)
		)
		(stroke
			(width 0)
			(type solid)
		)
		(fill yes)
		(layer "In11.Cu")
		(net "M_H_CPU1_SA_DQ<20>")
	)
	(gr_poly
		(pts
			(xy 136.354312 -271.215358) (xy 136.307322 -271.062958) (xy 136.045702 -271.062958) (xy 135.998712 -271.215358)
			(xy 135.998712 -271.259808) (xy 136.354312 -271.259808)
		)
		(stroke
			(width 0)
			(type solid)
		)
		(fill yes)
		(layer "In11.Cu")
		(net "M_H_CPU1_SA_DQ<23>")
	)
	(gr_poly
		(pts
			(xy 136.354312 -270.807434) (xy 136.354312 -270.762984) (xy 135.998712 -270.762984) (xy 135.998712 -270.807434)
			(xy 136.045702 -270.959834) (xy 136.307322 -270.959834)
		)
		(stroke
			(width 0)
			(type solid)
		)
		(fill yes)
		(layer "In11.Cu")
		(net "M_H_CPU1_SA_DQ<24>")
	)
	(gr_poly
		(pts
			(xy 136.354312 -269.587726) (xy 136.307322 -269.435326) (xy 136.045702 -269.435326) (xy 135.998712 -269.587726)
			(xy 135.998712 -269.631922) (xy 136.354312 -269.631922)
		)
		(stroke
			(width 0)
			(type solid)
		)
		(fill yes)
		(layer "In11.Cu")
		(net "M_H_CPU1_SA_DQ<27>")
	)
	(gr_poly
		(pts
			(xy 136.356598 -277.726394) (xy 136.309608 -277.573994) (xy 136.047988 -277.573994) (xy 136.000998 -277.726394)
			(xy 136.000998 -277.770844) (xy 136.356598 -277.770844)
		)
		(stroke
			(width 0)
			(type solid)
		)
		(fill yes)
		(layer "In11.Cu")
		(net "M_H_CPU1_SA_DQ<14>")
	)
	(gr_poly
		(pts
			(xy 136.356598 -277.318216) (xy 136.356598 -277.27402) (xy 136.000998 -277.27402) (xy 136.000998 -277.318216)
			(xy 136.047988 -277.470616) (xy 136.309608 -277.470616)
		)
		(stroke
			(width 0)
			(type solid)
		)
		(fill yes)
		(layer "In11.Cu")
		(net "M_H_CPU1_SA_DQ<13>")
	)
	(gr_poly
		(pts
			(xy 136.362694 -282.610052) (xy 136.315704 -282.457652) (xy 136.054084 -282.457652) (xy 136.007094 -282.610052)
			(xy 136.007094 -282.654502) (xy 136.362694 -282.654502)
		)
		(stroke
			(width 0)
			(type solid)
		)
		(fill yes)
		(layer "In11.Cu")
		(net "M_H_CPU1_SA_DQ<10>")
	)
	(gr_poly
		(pts
			(xy 136.362694 -282.20162) (xy 136.362694 -282.15717) (xy 136.007094 -282.15717) (xy 136.007094 -282.20162)
			(xy 136.054084 -282.35402) (xy 136.315704 -282.35402)
		)
		(stroke
			(width 0)
			(type solid)
		)
		(fill yes)
		(layer "In11.Cu")
		(net "M_H_CPU1_SA_DQ<9>")
	)
	(gr_poly
		(pts
			(xy 136.362694 -274.062698) (xy 136.362694 -274.018248) (xy 136.007094 -274.018248) (xy 136.007094 -274.062698)
			(xy 136.054084 -274.215098) (xy 136.315704 -274.215098)
		)
		(stroke
			(width 0)
			(type solid)
		)
		(fill yes)
		(layer "In11.Cu")
		(net "M_H_CPU1_SA_DQS_DP<2>")
	)
	(gr_poly
		(pts
			(xy 136.362694 -272.843498) (xy 136.315704 -272.691098) (xy 136.054084 -272.691098) (xy 136.007094 -272.843498)
			(xy 136.007094 -272.887948) (xy 136.362694 -272.887948)
		)
		(stroke
			(width 0)
			(type solid)
		)
		(fill yes)
		(layer "In11.Cu")
		(net "M_H_CPU1_SA_DQS_DP<7>")
	)
	(gr_poly
		(pts
			(xy 136.362694 -269.179294) (xy 136.362694 -269.134844) (xy 136.007094 -269.134844) (xy 136.007094 -269.179294)
			(xy 136.054084 -269.331694) (xy 136.315704 -269.331694)
		)
		(stroke
			(width 0)
			(type solid)
		)
		(fill yes)
		(layer "In11.Cu")
		(net "M_H_CPU1_SA_DQS_DP<3>")
	)
	(gr_poly
		(pts
			(xy 136.362694 -261.449058) (xy 136.315704 -261.296658) (xy 136.054084 -261.296658) (xy 136.007094 -261.449058)
			(xy 136.007094 -261.493508) (xy 136.362694 -261.493508)
		)
		(stroke
			(width 0)
			(type solid)
		)
		(fill yes)
		(layer "In11.Cu")
		(net "M_H_CPU1_SA_CB<3>")
	)
	(gr_poly
		(pts
			(xy 136.362694 -261.040626) (xy 136.362694 -260.996176) (xy 136.007094 -260.996176) (xy 136.007094 -261.040626)
			(xy 136.054084 -261.193026) (xy 136.315704 -261.193026)
		)
		(stroke
			(width 0)
			(type solid)
		)
		(fill yes)
		(layer "In11.Cu")
		(net "M_H_CPU1_SA_DQS_DP<4>")
	)
	(gr_poly
		(pts
			(xy 136.362694 -256.565654) (xy 136.315704 -256.413254) (xy 136.054084 -256.413254) (xy 136.007094 -256.565654)
			(xy 136.007094 -256.610104) (xy 136.362694 -256.610104)
		)
		(stroke
			(width 0)
			(type solid)
		)
		(fill yes)
		(layer "In11.Cu")
		(net "M_H_CPU1_SA_CS_N<1>")
	)
	(gr_poly
		(pts
			(xy 136.362694 -256.157222) (xy 136.362694 -256.112772) (xy 136.007094 -256.112772) (xy 136.007094 -256.157222)
			(xy 136.054084 -256.309622) (xy 136.315704 -256.309622)
		)
		(stroke
			(width 0)
			(type solid)
		)
		(fill yes)
		(layer "In11.Cu")
		(net "M_H_CPU1_SA_CS_N<2>")
	)
	(gr_poly
		(pts
			(xy 136.362694 -254.938022) (xy 136.315704 -254.785622) (xy 136.054084 -254.785622) (xy 136.007094 -254.938022)
			(xy 136.007094 -254.982218) (xy 136.362694 -254.982218)
		)
		(stroke
			(width 0)
			(type solid)
		)
		(fill yes)
		(layer "In11.Cu")
		(net "M_H_CPU1_SA_CA<0>")
	)
	(gr_poly
		(pts
			(xy 136.362694 -254.529082) (xy 136.362694 -254.484886) (xy 136.007094 -254.484886) (xy 136.007094 -254.529082)
			(xy 136.054084 -254.681482) (xy 136.315704 -254.681482)
		)
		(stroke
			(width 0)
			(type solid)
		)
		(fill yes)
		(layer "In11.Cu")
		(net "M_H_CPU1_SA_CA<2>")
	)
	(gr_poly
		(pts
			(xy 136.36879 -258.193286) (xy 136.3218 -258.040886) (xy 136.06018 -258.040886) (xy 136.01319 -258.193286)
			(xy 136.01319 -258.237482) (xy 136.36879 -258.237482)
		)
		(stroke
			(width 0)
			(type solid)
		)
		(fill yes)
		(layer "In11.Cu")
		(net "M_H_CPU1_SA_CB<7>")
	)
	(gr_poly
		(pts
			(xy 136.36879 -257.784854) (xy 136.36879 -257.740658) (xy 136.01319 -257.740658) (xy 136.01319 -257.784854)
			(xy 136.06018 -257.937254) (xy 136.3218 -257.937254)
		)
		(stroke
			(width 0)
			(type solid)
		)
		(fill yes)
		(layer "In11.Cu")
		(net "M_E_CPU1_ALERT_N")
	)
	(gr_poly
		(pts
			(xy 136.616948 -227.20427) (xy 136.578594 -227.182172) (xy 136.423146 -227.146612) (xy 136.292336 -227.37318)
			(xy 136.400794 -227.49002) (xy 136.439148 -227.512118)
		)
		(stroke
			(width 0)
			(type solid)
		)
		(fill yes)
		(layer "In11.Cu")
		(net "M_H_CPU1_SB_DQS_DP<8>")
	)
	(gr_poly
		(pts
			(xy 136.684004 -283.675328) (xy 136.722358 -283.65323) (xy 136.544558 -283.345382) (xy 136.506204 -283.36748)
			(xy 136.397746 -283.48432) (xy 136.528556 -283.710888)
		)
		(stroke
			(width 0)
			(type solid)
		)
		(fill yes)
		(layer "In11.Cu")
		(net "M_H_CPU1_SA_DQ<8>")
	)
	(gr_poly
		(pts
			(xy 136.688322 -278.79929) (xy 136.726676 -278.777192) (xy 136.548876 -278.469344) (xy 136.510522 -278.491442)
			(xy 136.402064 -278.608282) (xy 136.532874 -278.83485)
		)
		(stroke
			(width 0)
			(type solid)
		)
		(fill yes)
		(layer "In11.Cu")
		(net "M_H_CPU1_SA_DQ<12>")
	)
	(gr_poly
		(pts
			(xy 136.688322 -262.521446) (xy 136.726676 -262.499348) (xy 136.548876 -262.1915) (xy 136.510522 -262.213598)
			(xy 136.402064 -262.330438) (xy 136.532874 -262.557006)
		)
		(stroke
			(width 0)
			(type solid)
		)
		(fill yes)
		(layer "In11.Cu")
		(net "M_H_CPU1_SA_CB<1>")
	)
	(gr_poly
		(pts
			(xy 136.690354 -280.430986) (xy 136.728708 -280.408888) (xy 136.550908 -280.10104) (xy 136.512554 -280.123138)
			(xy 136.404096 -280.239978) (xy 136.534906 -280.466546)
		)
		(stroke
			(width 0)
			(type solid)
		)
		(fill yes)
		(layer "In11.Cu")
		(net "M_H_CPU1_SA_DQS_DN<6>")
	)
	(gr_poly
		(pts
			(xy 136.690354 -264.153396) (xy 136.728708 -264.131298) (xy 136.550908 -263.82345) (xy 136.512554 -263.845548)
			(xy 136.404096 -263.962388) (xy 136.534906 -264.188956)
		)
		(stroke
			(width 0)
			(type solid)
		)
		(fill yes)
		(layer "In11.Cu")
		(net "M_H_CPU1_SA_CB<0>")
	)
	(gr_poly
		(pts
			(xy 136.69137 -265.782298) (xy 136.729724 -265.7602) (xy 136.551924 -265.452352) (xy 136.51357 -265.47445)
			(xy 136.405112 -265.59129) (xy 136.535922 -265.817858)
		)
		(stroke
			(width 0)
			(type solid)
		)
		(fill yes)
		(layer "In11.Cu")
		(net "M_H_CPU1_SA_DQ<29>")
	)
	(gr_poly
		(pts
			(xy 136.691878 -248.616724) (xy 136.695688 -248.572528) (xy 136.341612 -248.54154) (xy 136.337548 -248.585736)
			(xy 136.371076 -248.741692) (xy 136.631934 -248.764298)
		)
		(stroke
			(width 0)
			(type solid)
		)
		(fill yes)
		(layer "In11.Cu")
		(net "M_H_CPU1_SB_CA<2>")
	)
	(gr_poly
		(pts
			(xy 136.722866 -247.382538) (xy 136.675876 -247.230138) (xy 136.414256 -247.230138) (xy 136.367266 -247.382538)
			(xy 136.367266 -247.426988) (xy 136.722866 -247.426988)
		)
		(stroke
			(width 0)
			(type solid)
		)
		(fill yes)
		(layer "In11.Cu")
		(net "M_H_CPU1_SB_CA<5>")
	)
	(gr_poly
		(pts
			(xy 136.722866 -246.974106) (xy 136.722866 -246.929656) (xy 136.367266 -246.929656) (xy 136.367266 -246.974106)
			(xy 136.414256 -247.126506) (xy 136.675876 -247.126506)
		)
		(stroke
			(width 0)
			(type solid)
		)
		(fill yes)
		(layer "In11.Cu")
		(net "M_H_CPU1_SB_CA<6>")
	)
	(gr_poly
		(pts
			(xy 136.722866 -242.499134) (xy 136.675876 -242.346734) (xy 136.414256 -242.346734) (xy 136.367266 -242.499134)
			(xy 136.367266 -242.543584) (xy 136.722866 -242.543584)
		)
		(stroke
			(width 0)
			(type solid)
		)
		(fill yes)
		(layer "In11.Cu")
		(net "M_H_CPU1_SB_DQS_DN<9>")
	)
	(gr_poly
		(pts
			(xy 136.722866 -242.090702) (xy 136.722866 -242.046252) (xy 136.367266 -242.046252) (xy 136.367266 -242.090702)
			(xy 136.414256 -242.243102) (xy 136.675876 -242.243102)
		)
		(stroke
			(width 0)
			(type solid)
		)
		(fill yes)
		(layer "In11.Cu")
		(net "M_H_CPU1_SB_DQS_DN<4>")
	)
	(gr_poly
		(pts
			(xy 136.722866 -240.871502) (xy 136.675876 -240.719102) (xy 136.414256 -240.719102) (xy 136.367266 -240.871502)
			(xy 136.367266 -240.915952) (xy 136.722866 -240.915952)
		)
		(stroke
			(width 0)
			(type solid)
		)
		(fill yes)
		(layer "In11.Cu")
		(net "M_H_CPU1_SB_CB<2>")
	)
	(gr_poly
		(pts
			(xy 136.722866 -238.83493) (xy 136.722866 -238.790734) (xy 136.367266 -238.790734) (xy 136.367266 -238.83493)
			(xy 136.414256 -238.98733) (xy 136.675876 -238.98733)
		)
		(stroke
			(width 0)
			(type solid)
		)
		(fill yes)
		(layer "In11.Cu")
		(net "M_H_CPU1_SB_DQ<1>")
	)
	(gr_poly
		(pts
			(xy 136.722866 -237.61573) (xy 136.675876 -237.46333) (xy 136.414256 -237.46333) (xy 136.367266 -237.61573)
			(xy 136.367266 -237.66018) (xy 136.722866 -237.66018)
		)
		(stroke
			(width 0)
			(type solid)
		)
		(fill yes)
		(layer "In11.Cu")
		(net "M_H_CPU1_SB_DQS_DN<0>")
	)
	(gr_poly
		(pts
			(xy 136.722866 -233.952034) (xy 136.722866 -233.907584) (xy 136.367266 -233.907584) (xy 136.367266 -233.952034)
			(xy 136.414256 -234.104434) (xy 136.675876 -234.104434)
		)
		(stroke
			(width 0)
			(type solid)
		)
		(fill yes)
		(layer "In11.Cu")
		(net "M_H_CPU1_SB_DQ<9>")
	)
	(gr_poly
		(pts
			(xy 136.722866 -232.732834) (xy 136.675876 -232.580434) (xy 136.414256 -232.580434) (xy 136.367266 -232.732834)
			(xy 136.367266 -232.77703) (xy 136.722866 -232.77703)
		)
		(stroke
			(width 0)
			(type solid)
		)
		(fill yes)
		(layer "In11.Cu")
		(net "M_H_CPU1_SB_DQS_DN<1>")
	)
	(gr_poly
		(pts
			(xy 136.722866 -232.323894) (xy 136.722866 -232.279698) (xy 136.367266 -232.279698) (xy 136.367266 -232.323894)
			(xy 136.414256 -232.476294) (xy 136.675876 -232.476294)
		)
		(stroke
			(width 0)
			(type solid)
		)
		(fill yes)
		(layer "In11.Cu")
		(net "M_H_CPU1_SB_DQS_DN<6>")
	)
	(gr_poly
		(pts
			(xy 136.722866 -231.104694) (xy 136.675876 -230.952294) (xy 136.414256 -230.952294) (xy 136.367266 -231.104694)
			(xy 136.367266 -231.149144) (xy 136.722866 -231.149144)
		)
		(stroke
			(width 0)
			(type solid)
		)
		(fill yes)
		(layer "In11.Cu")
		(net "M_H_CPU1_SB_DQ<14>")
	)
	(gr_poly
		(pts
			(xy 136.722866 -230.696262) (xy 136.722866 -230.651812) (xy 136.367266 -230.651812) (xy 136.367266 -230.696262)
			(xy 136.414256 -230.848662) (xy 136.675876 -230.848662)
		)
		(stroke
			(width 0)
			(type solid)
		)
		(fill yes)
		(layer "In11.Cu")
		(net "M_H_CPU1_SB_DQ<13>")
	)
	(gr_poly
		(pts
			(xy 136.722866 -229.477062) (xy 136.675876 -229.324662) (xy 136.414256 -229.324662) (xy 136.367266 -229.477062)
			(xy 136.367266 -229.521512) (xy 136.722866 -229.521512)
		)
		(stroke
			(width 0)
			(type solid)
		)
		(fill yes)
		(layer "In11.Cu")
		(net "M_H_CPU1_SB_DQ<24>")
	)
	(gr_poly
		(pts
			(xy 136.722866 -229.06863) (xy 136.722866 -229.02418) (xy 136.367266 -229.02418) (xy 136.367266 -229.06863)
			(xy 136.414256 -229.22103) (xy 136.675876 -229.22103)
		)
		(stroke
			(width 0)
			(type solid)
		)
		(fill yes)
		(layer "In11.Cu")
		(net "M_H_CPU1_SB_DQ<27>")
	)
	(gr_poly
		(pts
			(xy 136.722866 -226.221798) (xy 136.675876 -226.069398) (xy 136.414256 -226.069398) (xy 136.367266 -226.221798)
			(xy 136.367266 -226.265994) (xy 136.722866 -226.265994)
		)
		(stroke
			(width 0)
			(type solid)
		)
		(fill yes)
		(layer "In11.Cu")
		(net "M_H_CPU1_SB_DQS_DN<3>")
	)
	(gr_poly
		(pts
			(xy 136.722866 -225.812858) (xy 136.722866 -225.768662) (xy 136.367266 -225.768662) (xy 136.367266 -225.812858)
			(xy 136.414256 -225.965258) (xy 136.675876 -225.965258)
		)
		(stroke
			(width 0)
			(type solid)
		)
		(fill yes)
		(layer "In11.Cu")
		(net "M_H_CPU1_SB_DQ<30>")
	)
	(gr_poly
		(pts
			(xy 136.722866 -224.593658) (xy 136.675876 -224.441258) (xy 136.414256 -224.441258) (xy 136.367266 -224.593658)
			(xy 136.367266 -224.638108) (xy 136.722866 -224.638108)
		)
		(stroke
			(width 0)
			(type solid)
		)
		(fill yes)
		(layer "In11.Cu")
		(net "M_H_CPU1_SB_DQ<29>")
	)
	(gr_poly
		(pts
			(xy 136.731248 -240.46307) (xy 136.731248 -240.418874) (xy 136.375648 -240.418874) (xy 136.375648 -240.46307)
			(xy 136.422638 -240.61547) (xy 136.684258 -240.61547)
		)
		(stroke
			(width 0)
			(type solid)
		)
		(fill yes)
		(layer "In11.Cu")
		(net "M_H_CPU1_SB_CB<1>")
	)
	(gr_poly
		(pts
			(xy 136.731248 -239.243362) (xy 136.684258 -239.090962) (xy 136.422638 -239.090962) (xy 136.375648 -239.243362)
			(xy 136.375648 -239.287812) (xy 136.731248 -239.287812)
		)
		(stroke
			(width 0)
			(type solid)
		)
		(fill yes)
		(layer "In11.Cu")
		(net "M_H_CPU1_SB_DQ<2>")
	)
	(gr_poly
		(pts
			(xy 136.731248 -237.207806) (xy 136.731248 -237.163356) (xy 136.375648 -237.163356) (xy 136.375648 -237.207806)
			(xy 136.422638 -237.360206) (xy 136.684258 -237.360206)
		)
		(stroke
			(width 0)
			(type solid)
		)
		(fill yes)
		(layer "In11.Cu")
		(net "M_H_CPU1_SB_DQS_DN<5>")
	)
	(gr_poly
		(pts
			(xy 136.731248 -235.988098) (xy 136.684258 -235.835698) (xy 136.422638 -235.835698) (xy 136.375648 -235.988098)
			(xy 136.375648 -236.032294) (xy 136.731248 -236.032294)
		)
		(stroke
			(width 0)
			(type solid)
		)
		(fill yes)
		(layer "In11.Cu")
		(net "M_H_CPU1_SB_DQ<6>")
	)
	(gr_poly
		(pts
			(xy 136.731248 -235.579666) (xy 136.731248 -235.53547) (xy 136.375648 -235.53547) (xy 136.375648 -235.579666)
			(xy 136.422638 -235.732066) (xy 136.684258 -235.732066)
		)
		(stroke
			(width 0)
			(type solid)
		)
		(fill yes)
		(layer "In11.Cu")
		(net "M_H_CPU1_SB_DQ<5>")
	)
	(gr_poly
		(pts
			(xy 136.731248 -234.360466) (xy 136.684258 -234.208066) (xy 136.422638 -234.208066) (xy 136.375648 -234.360466)
			(xy 136.375648 -234.404662) (xy 136.731248 -234.404662)
		)
		(stroke
			(width 0)
			(type solid)
		)
		(fill yes)
		(layer "In11.Cu")
		(net "M_H_CPU1_SB_DQ<10>")
	)
	(gr_poly
		(pts
			(xy 136.795764 -227.920804) (xy 136.687306 -227.803964) (xy 136.648952 -227.781866) (xy 136.471152 -228.089714)
			(xy 136.509506 -228.111812) (xy 136.664954 -228.147372)
		)
		(stroke
			(width 0)
			(type solid)
		)
		(fill yes)
		(layer "In11.Cu")
		(net "M_H_CPU1_SB_DQS_DN<8>")
	)
	(gr_poly
		(pts
			(xy 136.797034 -278.177498) (xy 136.905492 -278.060658) (xy 136.774682 -277.83409) (xy 136.619234 -277.86965)
			(xy 136.58088 -277.891748) (xy 136.75868 -278.199596)
		)
		(stroke
			(width 0)
			(type solid)
		)
		(fill yes)
		(layer "In11.Cu")
		(net "M_H_CPU1_SA_DQ<14>")
	)
	(gr_poly
		(pts
			(xy 136.797034 -263.52754) (xy 136.905492 -263.4107) (xy 136.774682 -263.184132) (xy 136.619234 -263.219692)
			(xy 136.58088 -263.24179) (xy 136.75868 -263.549638)
		)
		(stroke
			(width 0)
			(type solid)
		)
		(fill yes)
		(layer "In11.Cu")
		(net "M_H_CPU1_SA_CB<2>")
	)
	(gr_poly
		(pts
			(xy 136.799066 -279.809194) (xy 136.907524 -279.692354) (xy 136.776714 -279.465786) (xy 136.621266 -279.501346)
			(xy 136.582912 -279.523444) (xy 136.760712 -279.831292)
		)
		(stroke
			(width 0)
			(type solid)
		)
		(fill yes)
		(layer "In11.Cu")
		(net "M_H_CPU1_SA_DQS_DP<6>")
	)
	(gr_poly
		(pts
			(xy 136.799066 -261.903718) (xy 136.907524 -261.786878) (xy 136.776714 -261.56031) (xy 136.621266 -261.59587)
			(xy 136.582912 -261.617968) (xy 136.760712 -261.925816)
		)
		(stroke
			(width 0)
			(type solid)
		)
		(fill yes)
		(layer "In11.Cu")
		(net "M_H_CPU1_SA_CB<3>")
	)
	(gr_poly
		(pts
			(xy 136.799828 -283.065728) (xy 136.908286 -282.948888) (xy 136.777476 -282.72232) (xy 136.622028 -282.75788)
			(xy 136.583674 -282.779978) (xy 136.761474 -283.087826)
		)
		(stroke
			(width 0)
			(type solid)
		)
		(fill yes)
		(layer "In11.Cu")
		(net "M_H_CPU1_SA_DQ<10>")
	)
	(gr_poly
		(pts
			(xy 136.803638 -265.166348) (xy 136.912096 -265.049508) (xy 136.781286 -264.82294) (xy 136.625838 -264.8585)
			(xy 136.587484 -264.880598) (xy 136.765284 -265.188446)
		)
		(stroke
			(width 0)
			(type solid)
		)
		(fill yes)
		(layer "In11.Cu")
		(net "M_H_CPU1_SA_DQ<31>")
	)
	(gr_poly
		(pts
			(xy 136.824212 -258.599178) (xy 136.824212 -258.554728) (xy 136.468612 -258.554728) (xy 136.468612 -258.599178)
			(xy 136.515602 -258.751578) (xy 136.777222 -258.751578)
		)
		(stroke
			(width 0)
			(type solid)
		)
		(fill yes)
		(layer "In11.Cu")
		(net "M_H_CPU1_SA_CB<5>")
	)
	(gr_poly
		(pts
			(xy 136.824212 -257.37947) (xy 136.777222 -257.22707) (xy 136.515602 -257.22707) (xy 136.468612 -257.37947)
			(xy 136.468612 -257.423666) (xy 136.824212 -257.423666)
		)
		(stroke
			(width 0)
			(type solid)
		)
		(fill yes)
		(layer "In11.Cu")
		(net "M_H_CPU1_ALERT_N")
	)
	(gr_poly
		(pts
			(xy 136.827514 -255.343406) (xy 136.827514 -255.298956) (xy 136.471914 -255.298956) (xy 136.471914 -255.343406)
			(xy 136.518904 -255.495806) (xy 136.780524 -255.495806)
		)
		(stroke
			(width 0)
			(type solid)
		)
		(fill yes)
		(layer "In11.Cu")
		(net "M_H_CPU1_SA_CA<1>")
	)
	(gr_poly
		(pts
			(xy 136.831832 -273.657314) (xy 136.784842 -273.504914) (xy 136.523222 -273.504914) (xy 136.476232 -273.657314)
			(xy 136.476232 -273.701764) (xy 136.831832 -273.701764)
		)
		(stroke
			(width 0)
			(type solid)
		)
		(fill yes)
		(layer "In11.Cu")
		(net "M_H_CPU1_SA_DQS_DN<2>")
	)
	(gr_poly
		(pts
			(xy 136.832594 -281.796236) (xy 136.785604 -281.643836) (xy 136.523984 -281.643836) (xy 136.476994 -281.796236)
			(xy 136.476994 -281.840686) (xy 136.832594 -281.840686)
		)
		(stroke
			(width 0)
			(type solid)
		)
		(fill yes)
		(layer "In11.Cu")
		(net "M_H_CPU1_SA_DQ<11>")
	)
	(gr_poly
		(pts
			(xy 136.832594 -281.38755) (xy 136.832594 -281.343354) (xy 136.476994 -281.343354) (xy 136.476994 -281.38755)
			(xy 136.523984 -281.53995) (xy 136.785604 -281.53995)
		)
		(stroke
			(width 0)
			(type solid)
		)
		(fill yes)
		(layer "In11.Cu")
		(net "M_H_CPU1_SA_DQS_DP<1>")
	)
	(gr_poly
		(pts
			(xy 136.832594 -273.248882) (xy 136.832594 -273.204432) (xy 136.476994 -273.204432) (xy 136.476994 -273.248882)
			(xy 136.523984 -273.401282) (xy 136.785604 -273.401282)
		)
		(stroke
			(width 0)
			(type solid)
		)
		(fill yes)
		(layer "In11.Cu")
		(net "M_H_CPU1_SA_DQS_DN<7>")
	)
	(gr_poly
		(pts
			(xy 136.832594 -268.77391) (xy 136.785604 -268.62151) (xy 136.523984 -268.62151) (xy 136.476994 -268.77391)
			(xy 136.476994 -268.81836) (xy 136.832594 -268.81836)
		)
		(stroke
			(width 0)
			(type solid)
		)
		(fill yes)
		(layer "In11.Cu")
		(net "M_H_CPU1_SA_DQS_DN<3>")
	)
	(gr_poly
		(pts
			(xy 136.832594 -268.365478) (xy 136.832594 -268.321028) (xy 136.476994 -268.321028) (xy 136.476994 -268.365478)
			(xy 136.523984 -268.517878) (xy 136.785604 -268.517878)
		)
		(stroke
			(width 0)
			(type solid)
		)
		(fill yes)
		(layer "In11.Cu")
		(net "M_H_CPU1_SA_DQS_DN<8>")
	)
	(gr_poly
		(pts
			(xy 136.832594 -266.737846) (xy 136.832594 -266.693396) (xy 136.476994 -266.693396) (xy 136.476994 -266.737846)
			(xy 136.523984 -266.890246) (xy 136.785604 -266.890246)
		)
		(stroke
			(width 0)
			(type solid)
		)
		(fill yes)
		(layer "In11.Cu")
		(net "M_H_CPU1_SA_DQ<28>")
	)
	(gr_poly
		(pts
			(xy 136.832594 -260.635242) (xy 136.785604 -260.482842) (xy 136.523984 -260.482842) (xy 136.476994 -260.635242)
			(xy 136.476994 -260.679438) (xy 136.832594 -260.679438)
		)
		(stroke
			(width 0)
			(type solid)
		)
		(fill yes)
		(layer "In11.Cu")
		(net "M_H_CPU1_SA_DQS_DN<4>")
	)
	(gr_poly
		(pts
			(xy 136.832594 -256.971038) (xy 136.832594 -256.926588) (xy 136.476994 -256.926588) (xy 136.476994 -256.971038)
			(xy 136.523984 -257.123438) (xy 136.785604 -257.123438)
		)
		(stroke
			(width 0)
			(type solid)
		)
		(fill yes)
		(layer "In11.Cu")
		(net "M_H_CPU1_SA_CS_N<0>")
	)
	(gr_poly
		(pts
			(xy 136.832594 -254.124206) (xy 136.785604 -253.971806) (xy 136.523984 -253.971806) (xy 136.476994 -254.124206)
			(xy 136.476994 -254.168402) (xy 136.832594 -254.168402)
		)
		(stroke
			(width 0)
			(type solid)
		)
		(fill yes)
		(layer "In11.Cu")
		(net "M_H_CPU1_SA_CA<3>")
	)
	(gr_poly
		(pts
			(xy 136.83869 -276.912578) (xy 136.7917 -276.760178) (xy 136.53008 -276.760178) (xy 136.48309 -276.912578)
			(xy 136.48309 -276.957028) (xy 136.83869 -276.957028)
		)
		(stroke
			(width 0)
			(type solid)
		)
		(fill yes)
		(layer "In11.Cu")
		(net "M_H_CPU1_SA_DQ<15>")
	)
	(gr_poly
		(pts
			(xy 136.840976 -260.22681) (xy 136.840976 -260.18236) (xy 136.485376 -260.18236) (xy 136.485376 -260.22681)
			(xy 136.532366 -260.37921) (xy 136.793986 -260.37921)
		)
		(stroke
			(width 0)
			(type solid)
		)
		(fill yes)
		(layer "In11.Cu")
		(net "M_H_CPU1_SA_DQS_DN<9>")
	)
	(gr_poly
		(pts
			(xy 136.840976 -259.007102) (xy 136.793986 -258.854702) (xy 136.532366 -258.854702) (xy 136.485376 -259.007102)
			(xy 136.485376 -259.051552) (xy 136.840976 -259.051552)
		)
		(stroke
			(width 0)
			(type solid)
		)
		(fill yes)
		(layer "In11.Cu")
		(net "M_H_CPU1_SA_CB<6>")
	)
	(gr_poly
		(pts
			(xy 136.84123 -272.029174) (xy 136.79424 -271.876774) (xy 136.53262 -271.876774) (xy 136.48563 -272.029174)
			(xy 136.48563 -272.073624) (xy 136.84123 -272.073624)
		)
		(stroke
			(width 0)
			(type solid)
		)
		(fill yes)
		(layer "In11.Cu")
		(net "M_H_CPU1_SA_DQ<22>")
	)
	(gr_poly
		(pts
			(xy 136.84123 -271.62125) (xy 136.84123 -271.5768) (xy 136.48563 -271.5768) (xy 136.48563 -271.62125)
			(xy 136.53262 -271.77365) (xy 136.79424 -271.77365)
		)
		(stroke
			(width 0)
			(type solid)
		)
		(fill yes)
		(layer "In11.Cu")
		(net "M_H_CPU1_SA_DQ<21>")
	)
	(gr_poly
		(pts
			(xy 136.84123 -270.401542) (xy 136.79424 -270.249142) (xy 136.53262 -270.249142) (xy 136.48563 -270.401542)
			(xy 136.48563 -270.445992) (xy 136.84123 -270.445992)
		)
		(stroke
			(width 0)
			(type solid)
		)
		(fill yes)
		(layer "In11.Cu")
		(net "M_H_CPU1_SA_DQ<26>")
	)
	(gr_poly
		(pts
			(xy 136.84123 -269.993618) (xy 136.84123 -269.949168) (xy 136.48563 -269.949168) (xy 136.48563 -269.993618)
			(xy 136.53262 -270.146018) (xy 136.79424 -270.146018)
		)
		(stroke
			(width 0)
			(type solid)
		)
		(fill yes)
		(layer "In11.Cu")
		(net "M_H_CPU1_SA_DQ<25>")
	)
	(gr_poly
		(pts
			(xy 136.842754 -255.75133) (xy 136.795764 -255.59893) (xy 136.534144 -255.59893) (xy 136.487154 -255.75133)
			(xy 136.487154 -255.79578) (xy 136.842754 -255.79578)
		)
		(stroke
			(width 0)
			(type solid)
		)
		(fill yes)
		(layer "In11.Cu")
		(net "M_H_CPU1_SA_CS_N<3>")
	)
	(gr_poly
		(pts
			(xy 137.08888 -228.014276) (xy 137.050526 -227.992178) (xy 136.895078 -227.956618) (xy 136.764268 -228.183186)
			(xy 136.872726 -228.300026) (xy 136.91108 -228.322124)
		)
		(stroke
			(width 0)
			(type solid)
		)
		(fill yes)
		(layer "In11.Cu")
		(net "M_H_CPU1_SB_DQ<25>")
	)
	(gr_poly
		(pts
			(xy 137.153904 -284.489398) (xy 137.192258 -284.4673) (xy 137.014458 -284.159452) (xy 136.976104 -284.18155)
			(xy 136.867646 -284.29839) (xy 136.998456 -284.524958)
		)
		(stroke
			(width 0)
			(type solid)
		)
		(fill yes)
		(layer "In11.Cu")
		(net "M_H_CPU1_SA_DQ<8>")
	)
	(gr_poly
		(pts
			(xy 137.158222 -261.70763) (xy 137.196576 -261.685532) (xy 137.018776 -261.377684) (xy 136.980422 -261.399782)
			(xy 136.871964 -261.516622) (xy 137.002774 -261.74319)
		)
		(stroke
			(width 0)
			(type solid)
		)
		(fill yes)
		(layer "In11.Cu")
		(net "M_H_CPU1_SA_DQS_DP<4>")
	)
	(gr_poly
		(pts
			(xy 137.159238 -282.870656) (xy 137.197592 -282.848558) (xy 137.019792 -282.54071) (xy 136.981438 -282.562808)
			(xy 136.87298 -282.679648) (xy 137.00379 -282.906216)
		)
		(stroke
			(width 0)
			(type solid)
		)
		(fill yes)
		(layer "In11.Cu")
		(net "M_H_CPU1_SA_DQ<9>")
	)
	(gr_poly
		(pts
			(xy 137.160254 -277.989284) (xy 137.198608 -277.967186) (xy 137.020808 -277.659338) (xy 136.982454 -277.681436)
			(xy 136.873996 -277.798276) (xy 137.004806 -278.024844)
		)
		(stroke
			(width 0)
			(type solid)
		)
		(fill yes)
		(layer "In11.Cu")
		(net "M_H_CPU1_SA_DQ<13>")
	)
	(gr_poly
		(pts
			(xy 137.160254 -263.339326) (xy 137.198608 -263.317228) (xy 137.020808 -263.00938) (xy 136.982454 -263.031478)
			(xy 136.873996 -263.148318) (xy 137.004806 -263.374886)
		)
		(stroke
			(width 0)
			(type solid)
		)
		(fill yes)
		(layer "In11.Cu")
		(net "M_H_CPU1_SA_CB<1>")
	)
	(gr_poly
		(pts
			(xy 137.18413 -239.649254) (xy 137.18413 -239.604804) (xy 136.82853 -239.604804) (xy 136.82853 -239.649254)
			(xy 136.87552 -239.801654) (xy 137.13714 -239.801654)
		)
		(stroke
			(width 0)
			(type solid)
		)
		(fill yes)
		(layer "In11.Cu")
		(net "M_H_CPU1_SB_DQ<0>")
	)
	(gr_poly
		(pts
			(xy 137.18413 -236.801914) (xy 137.13714 -236.649514) (xy 136.87552 -236.649514) (xy 136.82853 -236.801914)
			(xy 136.82853 -236.84611) (xy 137.18413 -236.84611)
		)
		(stroke
			(width 0)
			(type solid)
		)
		(fill yes)
		(layer "In11.Cu")
		(net "M_H_CPU1_SB_DQS_DP<5>")
	)
	(gr_poly
		(pts
			(xy 137.18413 -236.39399) (xy 137.18413 -236.34954) (xy 136.82853 -236.34954) (xy 136.82853 -236.39399)
			(xy 136.87552 -236.54639) (xy 137.13714 -236.54639)
		)
		(stroke
			(width 0)
			(type solid)
		)
		(fill yes)
		(layer "In11.Cu")
		(net "M_H_CPU1_SB_DQ<4>")
	)
	(gr_poly
		(pts
			(xy 137.18413 -235.174282) (xy 137.13714 -235.021882) (xy 136.87552 -235.021882) (xy 136.82853 -235.174282)
			(xy 136.82853 -235.218478) (xy 137.18413 -235.218478)
		)
		(stroke
			(width 0)
			(type solid)
		)
		(fill yes)
		(layer "In11.Cu")
		(net "M_H_CPU1_SB_DQ<7>")
	)
	(gr_poly
		(pts
			(xy 137.18667 -240.057178) (xy 137.13968 -239.904778) (xy 136.87806 -239.904778) (xy 136.83107 -240.057178)
			(xy 136.83107 -240.101628) (xy 137.18667 -240.101628)
		)
		(stroke
			(width 0)
			(type solid)
		)
		(fill yes)
		(layer "In11.Cu")
		(net "M_H_CPU1_SB_CB<3>")
	)
	(gr_poly
		(pts
			(xy 137.18667 -234.76585) (xy 137.18667 -234.721654) (xy 136.83107 -234.721654) (xy 136.83107 -234.76585)
			(xy 136.87806 -234.91825) (xy 137.13968 -234.91825)
		)
		(stroke
			(width 0)
			(type solid)
		)
		(fill yes)
		(layer "In11.Cu")
		(net "M_H_CPU1_SB_DQ<8>")
	)
	(gr_poly
		(pts
			(xy 137.192766 -248.196354) (xy 137.145776 -248.043954) (xy 136.884156 -248.043954) (xy 136.837166 -248.196354)
			(xy 136.837166 -248.240804) (xy 137.192766 -248.240804)
		)
		(stroke
			(width 0)
			(type solid)
		)
		(fill yes)
		(layer "In11.Cu")
		(net "M_H_CPU1_SB_CA<3>")
	)
	(gr_poly
		(pts
			(xy 137.192766 -247.787922) (xy 137.192766 -247.743472) (xy 136.837166 -247.743472) (xy 136.837166 -247.787922)
			(xy 136.884156 -247.940322) (xy 137.145776 -247.940322)
		)
		(stroke
			(width 0)
			(type solid)
		)
		(fill yes)
		(layer "In11.Cu")
		(net "M_H_CPU1_SB_CA<4>")
	)
	(gr_poly
		(pts
			(xy 137.192766 -246.568722) (xy 137.145776 -246.416322) (xy 136.884156 -246.416322) (xy 136.837166 -246.568722)
			(xy 136.837166 -246.613172) (xy 137.192766 -246.613172)
		)
		(stroke
			(width 0)
			(type solid)
		)
		(fill yes)
		(layer "In11.Cu")
		(net "M_H_CPU1_SB_PAR")
	)
	(gr_poly
		(pts
			(xy 137.192766 -241.685318) (xy 137.145776 -241.532918) (xy 136.884156 -241.532918) (xy 136.837166 -241.685318)
			(xy 136.837166 -241.729768) (xy 137.192766 -241.729768)
		)
		(stroke
			(width 0)
			(type solid)
		)
		(fill yes)
		(layer "In11.Cu")
		(net "M_H_CPU1_SB_DQS_DP<4>")
	)
	(gr_poly
		(pts
			(xy 137.192766 -241.276886) (xy 137.192766 -241.232436) (xy 136.837166 -241.232436) (xy 136.837166 -241.276886)
			(xy 136.884156 -241.429286) (xy 137.145776 -241.429286)
		)
		(stroke
			(width 0)
			(type solid)
		)
		(fill yes)
		(layer "In11.Cu")
		(net "M_H_CPU1_SB_CB<0>")
	)
	(gr_poly
		(pts
			(xy 137.192766 -238.430054) (xy 137.145776 -238.277654) (xy 136.884156 -238.277654) (xy 136.837166 -238.430054)
			(xy 136.837166 -238.47425) (xy 137.192766 -238.47425)
		)
		(stroke
			(width 0)
			(type solid)
		)
		(fill yes)
		(layer "In11.Cu")
		(net "M_H_CPU1_SB_DQ<3>")
	)
	(gr_poly
		(pts
			(xy 137.192766 -238.021114) (xy 137.192766 -237.976918) (xy 136.837166 -237.976918) (xy 136.837166 -238.021114)
			(xy 136.884156 -238.173514) (xy 137.145776 -238.173514)
		)
		(stroke
			(width 0)
			(type solid)
		)
		(fill yes)
		(layer "In11.Cu")
		(net "M_H_CPU1_SB_DQS_DP<0>")
	)
	(gr_poly
		(pts
			(xy 137.192766 -233.54665) (xy 137.145776 -233.39425) (xy 136.884156 -233.39425) (xy 136.837166 -233.54665)
			(xy 136.837166 -233.590846) (xy 137.192766 -233.590846)
		)
		(stroke
			(width 0)
			(type solid)
		)
		(fill yes)
		(layer "In11.Cu")
		(net "M_H_CPU1_SB_DQ<11>")
	)
	(gr_poly
		(pts
			(xy 137.192766 -233.13771) (xy 137.192766 -233.093514) (xy 136.837166 -233.093514) (xy 136.837166 -233.13771)
			(xy 136.884156 -233.29011) (xy 137.145776 -233.29011)
		)
		(stroke
			(width 0)
			(type solid)
		)
		(fill yes)
		(layer "In11.Cu")
		(net "M_H_CPU1_SB_DQS_DP<1>")
	)
	(gr_poly
		(pts
			(xy 137.192766 -231.919018) (xy 137.145776 -231.766618) (xy 136.884156 -231.766618) (xy 136.837166 -231.919018)
			(xy 136.837166 -231.963214) (xy 137.192766 -231.963214)
		)
		(stroke
			(width 0)
			(type solid)
		)
		(fill yes)
		(layer "In11.Cu")
		(net "M_H_CPU1_SB_DQS_DP<6>")
	)
	(gr_poly
		(pts
			(xy 137.192766 -231.510078) (xy 137.192766 -231.465882) (xy 136.837166 -231.465882) (xy 136.837166 -231.510078)
			(xy 136.884156 -231.662478) (xy 137.145776 -231.662478)
		)
		(stroke
			(width 0)
			(type solid)
		)
		(fill yes)
		(layer "In11.Cu")
		(net "M_H_CPU1_SB_DQ<12>")
	)
	(gr_poly
		(pts
			(xy 137.192766 -230.290878) (xy 137.145776 -230.138478) (xy 136.884156 -230.138478) (xy 136.837166 -230.290878)
			(xy 136.837166 -230.335328) (xy 137.192766 -230.335328)
		)
		(stroke
			(width 0)
			(type solid)
		)
		(fill yes)
		(layer "In11.Cu")
		(net "M_H_CPU1_SB_DQ<15>")
	)
	(gr_poly
		(pts
			(xy 137.192766 -229.882446) (xy 137.192766 -229.837996) (xy 136.837166 -229.837996) (xy 136.837166 -229.882446)
			(xy 136.884156 -230.034846) (xy 137.145776 -230.034846)
		)
		(stroke
			(width 0)
			(type solid)
		)
		(fill yes)
		(layer "In11.Cu")
		(net "M_H_CPU1_SB_DQ<26>")
	)
	(gr_poly
		(pts
			(xy 137.192766 -227.035614) (xy 137.145776 -226.883214) (xy 136.884156 -226.883214) (xy 136.837166 -227.035614)
			(xy 136.837166 -227.07981) (xy 137.192766 -227.07981)
		)
		(stroke
			(width 0)
			(type solid)
		)
		(fill yes)
		(layer "In11.Cu")
		(net "M_H_CPU1_SB_DQS_DP<8>")
	)
	(gr_poly
		(pts
			(xy 137.192766 -226.626674) (xy 137.192766 -226.582478) (xy 136.837166 -226.582478) (xy 136.837166 -226.626674)
			(xy 136.884156 -226.779074) (xy 137.145776 -226.779074)
		)
		(stroke
			(width 0)
			(type solid)
		)
		(fill yes)
		(layer "In11.Cu")
		(net "M_H_CPU1_SB_DQS_DP<3>")
	)
	(gr_poly
		(pts
			(xy 137.192766 -225.407474) (xy 137.145776 -225.255074) (xy 136.884156 -225.255074) (xy 136.837166 -225.407474)
			(xy 136.837166 -225.451924) (xy 137.192766 -225.451924)
		)
		(stroke
			(width 0)
			(type solid)
		)
		(fill yes)
		(layer "In11.Cu")
		(net "M_H_CPU1_SB_DQ<28>")
	)
	(gr_poly
		(pts
			(xy 137.192766 -224.999042) (xy 137.192766 -224.954592) (xy 136.837166 -224.954592) (xy 136.837166 -224.999042)
			(xy 136.884156 -225.151442) (xy 137.145776 -225.151442)
		)
		(stroke
			(width 0)
			(type solid)
		)
		(fill yes)
		(layer "In11.Cu")
		(net "M_H_CPU1_SB_DQ<31>")
	)
	(gr_poly
		(pts
			(xy 137.266934 -261.085838) (xy 137.375392 -260.968998) (xy 137.244582 -260.74243) (xy 137.089134 -260.77799)
			(xy 137.05078 -260.800088) (xy 137.22858 -261.107936)
		)
		(stroke
			(width 0)
			(type solid)
		)
		(fill yes)
		(layer "In11.Cu")
		(net "M_H_CPU1_SA_DQS_DN<4>")
	)
	(gr_poly
		(pts
			(xy 137.267696 -228.73081) (xy 137.159238 -228.61397) (xy 137.120884 -228.591872) (xy 136.943084 -228.89972)
			(xy 136.981438 -228.921818) (xy 137.136886 -228.957378)
		)
		(stroke
			(width 0)
			(type solid)
		)
		(fill yes)
		(layer "In11.Cu")
		(net "M_H_CPU1_SB_DQ<27>")
	)
	(gr_poly
		(pts
			(xy 137.26795 -283.876242) (xy 137.376408 -283.759402) (xy 137.245598 -283.532834) (xy 137.09015 -283.568394)
			(xy 137.051796 -283.590492) (xy 137.229596 -283.89834)
		)
		(stroke
			(width 0)
			(type solid)
		)
		(fill yes)
		(layer "In11.Cu")
		(net "M_H_CPU1_SA_DQ<10>")
	)
	(gr_poly
		(pts
			(xy 137.268966 -282.250896) (xy 137.377424 -282.134056) (xy 137.246614 -281.907488) (xy 137.091166 -281.943048)
			(xy 137.052812 -281.965146) (xy 137.230612 -282.272994)
		)
		(stroke
			(width 0)
			(type solid)
		)
		(fill yes)
		(layer "In11.Cu")
		(net "M_H_CPU1_SA_DQ<11>")
	)
	(gr_poly
		(pts
			(xy 137.268966 -277.367492) (xy 137.377424 -277.250652) (xy 137.246614 -277.024084) (xy 137.091166 -277.059644)
			(xy 137.052812 -277.081742) (xy 137.230612 -277.38959)
		)
		(stroke
			(width 0)
			(type solid)
		)
		(fill yes)
		(layer "In11.Cu")
		(net "M_H_CPU1_SA_DQ<15>")
	)
	(gr_poly
		(pts
			(xy 137.268966 -262.717534) (xy 137.377424 -262.600694) (xy 137.246614 -262.374126) (xy 137.091166 -262.409686)
			(xy 137.052812 -262.431784) (xy 137.230612 -262.739632)
		)
		(stroke
			(width 0)
			(type solid)
		)
		(fill yes)
		(layer "In11.Cu")
		(net "M_H_CPU1_SA_CB<3>")
	)
	(gr_poly
		(pts
			(xy 137.293858 -259.820918) (xy 137.246868 -259.668518) (xy 136.985248 -259.668518) (xy 136.938258 -259.820918)
			(xy 136.938258 -259.865368) (xy 137.293858 -259.865368)
		)
		(stroke
			(width 0)
			(type solid)
		)
		(fill yes)
		(layer "In11.Cu")
		(net "M_H_CPU1_SA_DQS_DP<9>")
	)
	(gr_poly
		(pts
			(xy 137.293858 -259.412994) (xy 137.293858 -259.368544) (xy 136.938258 -259.368544) (xy 136.938258 -259.412994)
			(xy 136.985248 -259.565394) (xy 137.246868 -259.565394)
		)
		(stroke
			(width 0)
			(type solid)
		)
		(fill yes)
		(layer "In11.Cu")
		(net "M_H_CPU1_SA_CB<4>")
	)
	(gr_poly
		(pts
			(xy 137.294112 -272.435066) (xy 137.294112 -272.39087) (xy 136.938512 -272.39087) (xy 136.938512 -272.435066)
			(xy 136.985502 -272.587466) (xy 137.247122 -272.587466)
		)
		(stroke
			(width 0)
			(type solid)
		)
		(fill yes)
		(layer "In11.Cu")
		(net "M_H_CPU1_SA_DQ<20>")
	)
	(gr_poly
		(pts
			(xy 137.294112 -271.215358) (xy 137.247122 -271.062958) (xy 136.985502 -271.062958) (xy 136.938512 -271.215358)
			(xy 136.938512 -271.259808) (xy 137.294112 -271.259808)
		)
		(stroke
			(width 0)
			(type solid)
		)
		(fill yes)
		(layer "In11.Cu")
		(net "M_H_CPU1_SA_DQ<23>")
	)
	(gr_poly
		(pts
			(xy 137.294112 -270.807434) (xy 137.294112 -270.762984) (xy 136.938512 -270.762984) (xy 136.938512 -270.807434)
			(xy 136.985502 -270.959834) (xy 137.247122 -270.959834)
		)
		(stroke
			(width 0)
			(type solid)
		)
		(fill yes)
		(layer "In11.Cu")
		(net "M_H_CPU1_SA_DQ<24>")
	)
	(gr_poly
		(pts
			(xy 137.294112 -269.587726) (xy 137.247122 -269.435326) (xy 136.985502 -269.435326) (xy 136.938512 -269.587726)
			(xy 136.938512 -269.631922) (xy 137.294112 -269.631922)
		)
		(stroke
			(width 0)
			(type solid)
		)
		(fill yes)
		(layer "In11.Cu")
		(net "M_H_CPU1_SA_DQ<27>")
	)
	(gr_poly
		(pts
			(xy 137.294112 -265.92403) (xy 137.294112 -265.879834) (xy 136.938512 -265.879834) (xy 136.938512 -265.92403)
			(xy 136.985502 -266.07643) (xy 137.247122 -266.07643)
		)
		(stroke
			(width 0)
			(type solid)
		)
		(fill yes)
		(layer "In11.Cu")
		(net "M_H_CPU1_SA_DQ<29>")
	)
	(gr_poly
		(pts
			(xy 137.294112 -256.157222) (xy 137.294112 -256.113026) (xy 136.938512 -256.113026) (xy 136.938512 -256.157222)
			(xy 136.985502 -256.309622) (xy 137.247122 -256.309622)
		)
		(stroke
			(width 0)
			(type solid)
		)
		(fill yes)
		(layer "In11.Cu")
		(net "M_H_CPU1_SA_CS_N<2>")
	)
	(gr_poly
		(pts
			(xy 137.294112 -254.937514) (xy 137.247122 -254.785114) (xy 136.985502 -254.785114) (xy 136.938512 -254.937514)
			(xy 136.938512 -254.981964) (xy 137.294112 -254.981964)
		)
		(stroke
			(width 0)
			(type solid)
		)
		(fill yes)
		(layer "In11.Cu")
		(net "M_H_CPU1_SA_CA<0>")
	)
	(gr_poly
		(pts
			(xy 137.302494 -280.982674) (xy 137.255504 -280.830274) (xy 136.993884 -280.830274) (xy 136.946894 -280.982674)
			(xy 136.946894 -281.02687) (xy 137.302494 -281.02687)
		)
		(stroke
			(width 0)
			(type solid)
		)
		(fill yes)
		(layer "In11.Cu")
		(net "M_H_CPU1_SA_DQS_DN<1>")
	)
	(gr_poly
		(pts
			(xy 137.302494 -280.573734) (xy 137.302494 -280.529538) (xy 136.946894 -280.529538) (xy 136.946894 -280.573734)
			(xy 136.993884 -280.726134) (xy 137.255504 -280.726134)
		)
		(stroke
			(width 0)
			(type solid)
		)
		(fill yes)
		(layer "In11.Cu")
		(net "M_H_CPU1_SA_DQS_DN<6>")
	)
	(gr_poly
		(pts
			(xy 137.302494 -278.945848) (xy 137.302494 -278.901652) (xy 136.946894 -278.901652) (xy 136.946894 -278.945848)
			(xy 136.993884 -279.098248) (xy 137.255504 -279.098248)
		)
		(stroke
			(width 0)
			(type solid)
		)
		(fill yes)
		(layer "In11.Cu")
		(net "M_H_CPU1_SA_DQ<12>")
	)
	(gr_poly
		(pts
			(xy 137.302494 -272.843498) (xy 137.255504 -272.691098) (xy 136.993884 -272.691098) (xy 136.946894 -272.843498)
			(xy 136.946894 -272.887948) (xy 137.302494 -272.887948)
		)
		(stroke
			(width 0)
			(type solid)
		)
		(fill yes)
		(layer "In11.Cu")
		(net "M_H_CPU1_SA_DQS_DP<7>")
	)
	(gr_poly
		(pts
			(xy 137.302494 -269.179294) (xy 137.302494 -269.134844) (xy 136.946894 -269.134844) (xy 136.946894 -269.179294)
			(xy 136.993884 -269.331694) (xy 137.255504 -269.331694)
		)
		(stroke
			(width 0)
			(type solid)
		)
		(fill yes)
		(layer "In11.Cu")
		(net "M_H_CPU1_SA_DQS_DP<3>")
	)
	(gr_poly
		(pts
			(xy 137.302494 -267.960094) (xy 137.255504 -267.807694) (xy 136.993884 -267.807694) (xy 136.946894 -267.960094)
			(xy 136.946894 -268.004544) (xy 137.302494 -268.004544)
		)
		(stroke
			(width 0)
			(type solid)
		)
		(fill yes)
		(layer "In11.Cu")
		(net "M_H_CPU1_SA_DQS_DP<8>")
	)
	(gr_poly
		(pts
			(xy 137.302494 -266.332462) (xy 137.255504 -266.180062) (xy 136.993884 -266.180062) (xy 136.946894 -266.332462)
			(xy 136.946894 -266.376658) (xy 137.302494 -266.376658)
		)
		(stroke
			(width 0)
			(type solid)
		)
		(fill yes)
		(layer "In11.Cu")
		(net "M_H_CPU1_SA_DQ<30>")
	)
	(gr_poly
		(pts
			(xy 137.302494 -264.296398) (xy 137.302494 -264.251948) (xy 136.946894 -264.251948) (xy 136.946894 -264.296398)
			(xy 136.993884 -264.448798) (xy 137.255504 -264.448798)
		)
		(stroke
			(width 0)
			(type solid)
		)
		(fill yes)
		(layer "In11.Cu")
		(net "M_H_CPU1_SA_CB<0>")
	)
	(gr_poly
		(pts
			(xy 137.302494 -256.565654) (xy 137.255504 -256.413254) (xy 136.993884 -256.413254) (xy 136.946894 -256.565654)
			(xy 136.946894 -256.610104) (xy 137.302494 -256.610104)
		)
		(stroke
			(width 0)
			(type solid)
		)
		(fill yes)
		(layer "In11.Cu")
		(net "M_H_CPU1_SA_CS_N<1>")
	)
	(gr_poly
		(pts
			(xy 137.302494 -254.529082) (xy 137.302494 -254.484886) (xy 136.946894 -254.484886) (xy 136.946894 -254.529082)
			(xy 136.993884 -254.681482) (xy 137.255504 -254.681482)
		)
		(stroke
			(width 0)
			(type solid)
		)
		(fill yes)
		(layer "In11.Cu")
		(net "M_H_CPU1_SA_CA<2>")
	)
	(gr_poly
		(pts
			(xy 137.31113 -258.193286) (xy 137.26414 -258.040886) (xy 137.00252 -258.040886) (xy 136.95553 -258.193286)
			(xy 136.95553 -258.237482) (xy 137.31113 -258.237482)
		)
		(stroke
			(width 0)
			(type solid)
		)
		(fill yes)
		(layer "In11.Cu")
		(net "M_H_CPU1_SA_CB<7>")
	)
	(gr_poly
		(pts
			(xy 137.31113 -257.784854) (xy 137.31113 -257.740658) (xy 136.95553 -257.740658) (xy 136.95553 -257.784854)
			(xy 137.00252 -257.937254) (xy 137.26414 -257.937254)
		)
		(stroke
			(width 0)
			(type solid)
		)
		(fill yes)
		(layer "In11.Cu")
		(net "M_E_CPU1_ALERT_N")
	)
	(gr_poly
		(pts
			(xy 137.556748 -228.832156) (xy 137.518394 -228.810058) (xy 137.362946 -228.774498) (xy 137.232136 -229.001066)
			(xy 137.340594 -229.117906) (xy 137.378948 -229.140004)
		)
		(stroke
			(width 0)
			(type solid)
		)
		(fill yes)
		(layer "In11.Cu")
		(net "M_H_CPU1_SB_DQ<24>")
	)
	(gr_poly
		(pts
			(xy 137.556748 -223.948752) (xy 137.518394 -223.926654) (xy 137.362946 -223.891094) (xy 137.232136 -224.117662)
			(xy 137.340594 -224.234502) (xy 137.378948 -224.2566)
		)
		(stroke
			(width 0)
			(type solid)
		)
		(fill yes)
		(layer "In11.Cu")
		(net "M_H_CPU1_SB_DQ<29>")
	)
	(gr_poly
		(pts
			(xy 137.628122 -262.521446) (xy 137.666476 -262.499348) (xy 137.488676 -262.1915) (xy 137.450322 -262.213598)
			(xy 137.341864 -262.330438) (xy 137.472674 -262.557006)
		)
		(stroke
			(width 0)
			(type solid)
		)
		(fill yes)
		(layer "In11.Cu")
		(net "M_H_CPU1_SA_DQS_DP<4>")
	)
	(gr_poly
		(pts
			(xy 137.629392 -283.685234) (xy 137.667746 -283.663136) (xy 137.489946 -283.355288) (xy 137.451592 -283.377386)
			(xy 137.343134 -283.494226) (xy 137.473944 -283.720794)
		)
		(stroke
			(width 0)
			(type solid)
		)
		(fill yes)
		(layer "In11.Cu")
		(net "M_H_CPU1_SA_DQ<9>")
	)
	(gr_poly
		(pts
			(xy 137.630154 -260.897624) (xy 137.668508 -260.875526) (xy 137.490708 -260.567678) (xy 137.452354 -260.589776)
			(xy 137.343896 -260.706616) (xy 137.474706 -260.933184)
		)
		(stroke
			(width 0)
			(type solid)
		)
		(fill yes)
		(layer "In11.Cu")
		(net "M_H_CPU1_SA_DQS_DN<9>")
	)
	(gr_poly
		(pts
			(xy 137.662666 -240.871502) (xy 137.615676 -240.719102) (xy 137.354056 -240.719102) (xy 137.307066 -240.871502)
			(xy 137.307066 -240.915952) (xy 137.662666 -240.915952)
		)
		(stroke
			(width 0)
			(type solid)
		)
		(fill yes)
		(layer "In11.Cu")
		(net "M_H_CPU1_SB_CB<2>")
	)
	(gr_poly
		(pts
			(xy 137.662666 -240.46307) (xy 137.662666 -240.41862) (xy 137.307066 -240.41862) (xy 137.307066 -240.46307)
			(xy 137.354056 -240.61547) (xy 137.615676 -240.61547)
		)
		(stroke
			(width 0)
			(type solid)
		)
		(fill yes)
		(layer "In11.Cu")
		(net "M_H_CPU1_SB_CB<1>")
	)
	(gr_poly
		(pts
			(xy 137.662666 -238.83493) (xy 137.662666 -238.790734) (xy 137.307066 -238.790734) (xy 137.307066 -238.83493)
			(xy 137.354056 -238.98733) (xy 137.615676 -238.98733)
		)
		(stroke
			(width 0)
			(type solid)
		)
		(fill yes)
		(layer "In11.Cu")
		(net "M_H_CPU1_SB_DQ<1>")
	)
	(gr_poly
		(pts
			(xy 137.662666 -237.61573) (xy 137.615676 -237.46333) (xy 137.354056 -237.46333) (xy 137.307066 -237.61573)
			(xy 137.307066 -237.66018) (xy 137.662666 -237.66018)
		)
		(stroke
			(width 0)
			(type solid)
		)
		(fill yes)
		(layer "In11.Cu")
		(net "M_H_CPU1_SB_DQS_DN<0>")
	)
	(gr_poly
		(pts
			(xy 137.662666 -234.360466) (xy 137.615676 -234.208066) (xy 137.354056 -234.208066) (xy 137.307066 -234.360466)
			(xy 137.307066 -234.404916) (xy 137.662666 -234.404916)
		)
		(stroke
			(width 0)
			(type solid)
		)
		(fill yes)
		(layer "In11.Cu")
		(net "M_H_CPU1_SB_DQ<10>")
	)
	(gr_poly
		(pts
			(xy 137.662666 -233.952034) (xy 137.662666 -233.907584) (xy 137.307066 -233.907584) (xy 137.307066 -233.952034)
			(xy 137.354056 -234.104434) (xy 137.615676 -234.104434)
		)
		(stroke
			(width 0)
			(type solid)
		)
		(fill yes)
		(layer "In11.Cu")
		(net "M_H_CPU1_SB_DQ<9>")
	)
	(gr_poly
		(pts
			(xy 137.662666 -232.732834) (xy 137.615676 -232.580434) (xy 137.354056 -232.580434) (xy 137.307066 -232.732834)
			(xy 137.307066 -232.77703) (xy 137.662666 -232.77703)
		)
		(stroke
			(width 0)
			(type solid)
		)
		(fill yes)
		(layer "In11.Cu")
		(net "M_H_CPU1_SB_DQS_DN<1>")
	)
	(gr_poly
		(pts
			(xy 137.662666 -232.323894) (xy 137.662666 -232.279698) (xy 137.307066 -232.279698) (xy 137.307066 -232.323894)
			(xy 137.354056 -232.476294) (xy 137.615676 -232.476294)
		)
		(stroke
			(width 0)
			(type solid)
		)
		(fill yes)
		(layer "In11.Cu")
		(net "M_H_CPU1_SB_DQS_DN<6>")
	)
	(gr_poly
		(pts
			(xy 137.662666 -231.104694) (xy 137.615676 -230.952294) (xy 137.354056 -230.952294) (xy 137.307066 -231.104694)
			(xy 137.307066 -231.149144) (xy 137.662666 -231.149144)
		)
		(stroke
			(width 0)
			(type solid)
		)
		(fill yes)
		(layer "In11.Cu")
		(net "M_H_CPU1_SB_DQ<14>")
	)
	(gr_poly
		(pts
			(xy 137.662666 -230.696262) (xy 137.662666 -230.651812) (xy 137.307066 -230.651812) (xy 137.307066 -230.696262)
			(xy 137.354056 -230.848662) (xy 137.615676 -230.848662)
		)
		(stroke
			(width 0)
			(type solid)
		)
		(fill yes)
		(layer "In11.Cu")
		(net "M_H_CPU1_SB_DQ<13>")
	)
	(gr_poly
		(pts
			(xy 137.662666 -227.84943) (xy 137.615676 -227.69703) (xy 137.354056 -227.69703) (xy 137.307066 -227.84943)
			(xy 137.307066 -227.893626) (xy 137.662666 -227.893626)
		)
		(stroke
			(width 0)
			(type solid)
		)
		(fill yes)
		(layer "In11.Cu")
		(net "M_H_CPU1_SB_DQ<25>")
	)
	(gr_poly
		(pts
			(xy 137.662666 -227.44049) (xy 137.662666 -227.396294) (xy 137.307066 -227.396294) (xy 137.307066 -227.44049)
			(xy 137.354056 -227.59289) (xy 137.615676 -227.59289)
		)
		(stroke
			(width 0)
			(type solid)
		)
		(fill yes)
		(layer "In11.Cu")
		(net "M_H_CPU1_SB_DQS_DN<8>")
	)
	(gr_poly
		(pts
			(xy 137.662666 -226.221798) (xy 137.615676 -226.069398) (xy 137.354056 -226.069398) (xy 137.307066 -226.221798)
			(xy 137.307066 -226.265994) (xy 137.662666 -226.265994)
		)
		(stroke
			(width 0)
			(type solid)
		)
		(fill yes)
		(layer "In11.Cu")
		(net "M_H_CPU1_SB_DQS_DN<3>")
	)
	(gr_poly
		(pts
			(xy 137.662666 -225.812858) (xy 137.662666 -225.768662) (xy 137.307066 -225.768662) (xy 137.307066 -225.812858)
			(xy 137.354056 -225.965258) (xy 137.615676 -225.965258)
		)
		(stroke
			(width 0)
			(type solid)
		)
		(fill yes)
		(layer "In11.Cu")
		(net "M_H_CPU1_SB_DQ<30>")
	)
	(gr_poly
		(pts
			(xy 137.671048 -239.243362) (xy 137.624058 -239.090962) (xy 137.362438 -239.090962) (xy 137.315448 -239.243362)
			(xy 137.315448 -239.287812) (xy 137.671048 -239.287812)
		)
		(stroke
			(width 0)
			(type solid)
		)
		(fill yes)
		(layer "In11.Cu")
		(net "M_H_CPU1_SB_DQ<2>")
	)
	(gr_poly
		(pts
			(xy 137.671048 -237.207806) (xy 137.671048 -237.163356) (xy 137.315448 -237.163356) (xy 137.315448 -237.207806)
			(xy 137.362438 -237.360206) (xy 137.624058 -237.360206)
		)
		(stroke
			(width 0)
			(type solid)
		)
		(fill yes)
		(layer "In11.Cu")
		(net "M_H_CPU1_SB_DQS_DN<5>")
	)
	(gr_poly
		(pts
			(xy 137.671048 -235.988098) (xy 137.624058 -235.835698) (xy 137.362438 -235.835698) (xy 137.315448 -235.988098)
			(xy 137.315448 -236.032294) (xy 137.671048 -236.032294)
		)
		(stroke
			(width 0)
			(type solid)
		)
		(fill yes)
		(layer "In11.Cu")
		(net "M_H_CPU1_SB_DQ<6>")
	)
	(gr_poly
		(pts
			(xy 137.671048 -235.579666) (xy 137.671048 -235.53547) (xy 137.315448 -235.53547) (xy 137.315448 -235.579666)
			(xy 137.362438 -235.732066) (xy 137.624058 -235.732066)
		)
		(stroke
			(width 0)
			(type solid)
		)
		(fill yes)
		(layer "In11.Cu")
		(net "M_H_CPU1_SB_DQ<5>")
	)
	(gr_poly
		(pts
			(xy 137.737596 -229.544626) (xy 137.629138 -229.427786) (xy 137.590784 -229.405688) (xy 137.412984 -229.713536)
			(xy 137.451338 -229.735634) (xy 137.606786 -229.771194)
		)
		(stroke
			(width 0)
			(type solid)
		)
		(fill yes)
		(layer "In11.Cu")
		(net "M_H_CPU1_SB_DQ<26>")
	)
	(gr_poly
		(pts
			(xy 137.737596 -224.661222) (xy 137.629138 -224.544382) (xy 137.590784 -224.522284) (xy 137.412984 -224.830132)
			(xy 137.451338 -224.85223) (xy 137.606786 -224.88779)
		)
		(stroke
			(width 0)
			(type solid)
		)
		(fill yes)
		(layer "In11.Cu")
		(net "M_H_CPU1_SB_DQ<31>")
	)
	(gr_poly
		(pts
			(xy 137.738104 -283.062934) (xy 137.846562 -282.946094) (xy 137.715752 -282.719526) (xy 137.560304 -282.755086)
			(xy 137.52195 -282.777184) (xy 137.69975 -283.085032)
		)
		(stroke
			(width 0)
			(type solid)
		)
		(fill yes)
		(layer "In11.Cu")
		(net "M_H_CPU1_SA_DQ<11>")
	)
	(gr_poly
		(pts
			(xy 137.738866 -281.43708) (xy 137.847324 -281.32024) (xy 137.716514 -281.093672) (xy 137.561066 -281.129232)
			(xy 137.522712 -281.15133) (xy 137.700512 -281.459178)
		)
		(stroke
			(width 0)
			(type solid)
		)
		(fill yes)
		(layer "In11.Cu")
		(net "M_H_CPU1_SA_DQS_DN<1>")
	)
	(gr_poly
		(pts
			(xy 137.738866 -261.903718) (xy 137.847324 -261.786878) (xy 137.716514 -261.56031) (xy 137.561066 -261.59587)
			(xy 137.522712 -261.617968) (xy 137.700512 -261.925816)
		)
		(stroke
			(width 0)
			(type solid)
		)
		(fill yes)
		(layer "In11.Cu")
		(net "M_H_CPU1_SA_DQS_DN<4>")
	)
	(gr_poly
		(pts
			(xy 137.743184 -260.282944) (xy 137.851642 -260.166104) (xy 137.720832 -259.939536) (xy 137.565384 -259.975096)
			(xy 137.52703 -259.997194) (xy 137.70483 -260.305042)
		)
		(stroke
			(width 0)
			(type solid)
		)
		(fill yes)
		(layer "In11.Cu")
		(net "M_H_CPU1_SA_DQS_DP<9>")
	)
	(gr_poly
		(pts
			(xy 137.764012 -257.37947) (xy 137.717022 -257.22707) (xy 137.455402 -257.22707) (xy 137.408412 -257.37947)
			(xy 137.408412 -257.423666) (xy 137.764012 -257.423666)
		)
		(stroke
			(width 0)
			(type solid)
		)
		(fill yes)
		(layer "In11.Cu")
		(net "M_H_CPU1_ALERT_N")
	)
	(gr_poly
		(pts
			(xy 137.766298 -268.77391) (xy 137.719308 -268.62151) (xy 137.457688 -268.62151) (xy 137.410698 -268.77391)
			(xy 137.410698 -268.81836) (xy 137.766298 -268.81836)
		)
		(stroke
			(width 0)
			(type solid)
		)
		(fill yes)
		(layer "In11.Cu")
		(net "M_H_CPU1_SA_DQS_DN<3>")
	)
	(gr_poly
		(pts
			(xy 137.767314 -265.518646) (xy 137.720324 -265.366246) (xy 137.458704 -265.366246) (xy 137.411714 -265.518646)
			(xy 137.411714 -265.562842) (xy 137.767314 -265.562842)
		)
		(stroke
			(width 0)
			(type solid)
		)
		(fill yes)
		(layer "In11.Cu")
		(net "M_H_CPU1_SA_DQ<31>")
	)
	(gr_poly
		(pts
			(xy 137.772394 -280.168604) (xy 137.725404 -280.016204) (xy 137.463784 -280.016204) (xy 137.416794 -280.168604)
			(xy 137.416794 -280.2128) (xy 137.772394 -280.2128)
		)
		(stroke
			(width 0)
			(type solid)
		)
		(fill yes)
		(layer "In11.Cu")
		(net "M_H_CPU1_SA_DQS_DP<6>")
	)
	(gr_poly
		(pts
			(xy 137.772394 -278.540718) (xy 137.725404 -278.388318) (xy 137.463784 -278.388318) (xy 137.416794 -278.540718)
			(xy 137.416794 -278.585168) (xy 137.772394 -278.585168)
		)
		(stroke
			(width 0)
			(type solid)
		)
		(fill yes)
		(layer "In11.Cu")
		(net "M_H_CPU1_SA_DQ<14>")
	)
	(gr_poly
		(pts
			(xy 137.772394 -278.132032) (xy 137.772394 -278.087836) (xy 137.416794 -278.087836) (xy 137.416794 -278.132032)
			(xy 137.463784 -278.284432) (xy 137.725404 -278.284432)
		)
		(stroke
			(width 0)
			(type solid)
		)
		(fill yes)
		(layer "In11.Cu")
		(net "M_H_CPU1_SA_DQ<13>")
	)
	(gr_poly
		(pts
			(xy 137.772394 -268.365478) (xy 137.772394 -268.321028) (xy 137.416794 -268.321028) (xy 137.416794 -268.365478)
			(xy 137.463784 -268.517878) (xy 137.725404 -268.517878)
		)
		(stroke
			(width 0)
			(type solid)
		)
		(fill yes)
		(layer "In11.Cu")
		(net "M_H_CPU1_SA_DQS_DN<8>")
	)
	(gr_poly
		(pts
			(xy 137.772394 -266.737846) (xy 137.772394 -266.693396) (xy 137.416794 -266.693396) (xy 137.416794 -266.737846)
			(xy 137.463784 -266.890246) (xy 137.725404 -266.890246)
		)
		(stroke
			(width 0)
			(type solid)
		)
		(fill yes)
		(layer "In11.Cu")
		(net "M_H_CPU1_SA_DQ<28>")
	)
	(gr_poly
		(pts
			(xy 137.772394 -256.971038) (xy 137.772394 -256.926588) (xy 137.416794 -256.926588) (xy 137.416794 -256.971038)
			(xy 137.463784 -257.123438) (xy 137.725404 -257.123438)
		)
		(stroke
			(width 0)
			(type solid)
		)
		(fill yes)
		(layer "In11.Cu")
		(net "M_H_CPU1_SA_CS_N<0>")
	)
	(gr_poly
		(pts
			(xy 137.772394 -254.124206) (xy 137.725404 -253.971806) (xy 137.463784 -253.971806) (xy 137.416794 -254.124206)
			(xy 137.416794 -254.168402) (xy 137.772394 -254.168402)
		)
		(stroke
			(width 0)
			(type solid)
		)
		(fill yes)
		(layer "In11.Cu")
		(net "M_H_CPU1_SA_CA<3>")
	)
	(gr_poly
		(pts
			(xy 137.780776 -259.007102) (xy 137.733786 -258.854702) (xy 137.472166 -258.854702) (xy 137.425176 -259.007102)
			(xy 137.425176 -259.051552) (xy 137.780776 -259.051552)
		)
		(stroke
			(width 0)
			(type solid)
		)
		(fill yes)
		(layer "In11.Cu")
		(net "M_H_CPU1_SA_CB<6>")
	)
	(gr_poly
		(pts
			(xy 137.78103 -272.029174) (xy 137.73404 -271.876774) (xy 137.47242 -271.876774) (xy 137.42543 -272.029174)
			(xy 137.42543 -272.073624) (xy 137.78103 -272.073624)
		)
		(stroke
			(width 0)
			(type solid)
		)
		(fill yes)
		(layer "In11.Cu")
		(net "M_H_CPU1_SA_DQ<22>")
	)
	(gr_poly
		(pts
			(xy 137.78103 -271.62125) (xy 137.78103 -271.5768) (xy 137.42543 -271.5768) (xy 137.42543 -271.62125)
			(xy 137.47242 -271.77365) (xy 137.73404 -271.77365)
		)
		(stroke
			(width 0)
			(type solid)
		)
		(fill yes)
		(layer "In11.Cu")
		(net "M_H_CPU1_SA_DQ<21>")
	)
	(gr_poly
		(pts
			(xy 137.78103 -270.401542) (xy 137.73404 -270.249142) (xy 137.47242 -270.249142) (xy 137.42543 -270.401542)
			(xy 137.42543 -270.445992) (xy 137.78103 -270.445992)
		)
		(stroke
			(width 0)
			(type solid)
		)
		(fill yes)
		(layer "In11.Cu")
		(net "M_H_CPU1_SA_DQ<26>")
	)
	(gr_poly
		(pts
			(xy 137.78103 -269.993618) (xy 137.78103 -269.949168) (xy 137.42543 -269.949168) (xy 137.42543 -269.993618)
			(xy 137.47242 -270.146018) (xy 137.73404 -270.146018)
		)
		(stroke
			(width 0)
			(type solid)
		)
		(fill yes)
		(layer "In11.Cu")
		(net "M_H_CPU1_SA_DQ<25>")
	)
	(gr_poly
		(pts
			(xy 137.78103 -255.343406) (xy 137.78103 -255.298956) (xy 137.42543 -255.298956) (xy 137.42543 -255.343406)
			(xy 137.47242 -255.495806) (xy 137.73404 -255.495806)
		)
		(stroke
			(width 0)
			(type solid)
		)
		(fill yes)
		(layer "In11.Cu")
		(net "M_H_CPU1_SA_CA<1>")
	)
	(gr_poly
		(pts
			(xy 138.026648 -224.762568) (xy 137.988294 -224.74047) (xy 137.832846 -224.70491) (xy 137.702036 -224.931478)
			(xy 137.810494 -225.048318) (xy 137.848848 -225.070416)
		)
		(stroke
			(width 0)
			(type solid)
		)
		(fill yes)
		(layer "In11.Cu")
		(net "M_H_CPU1_SB_DQ<28>")
	)
	(gr_poly
		(pts
			(xy 138.09345 -260.072632) (xy 138.131804 -260.050534) (xy 137.954004 -259.742686) (xy 137.91565 -259.764784)
			(xy 137.807192 -259.881624) (xy 137.938002 -260.108192)
		)
		(stroke
			(width 0)
			(type solid)
		)
		(fill yes)
		(layer "In11.Cu")
		(net "M_H_CPU1_SA_CB<4>")
	)
	(gr_poly
		(pts
			(xy 138.093704 -284.489398) (xy 138.132058 -284.4673) (xy 137.954258 -284.159452) (xy 137.915904 -284.18155)
			(xy 137.807446 -284.29839) (xy 137.938256 -284.524958)
		)
		(stroke
			(width 0)
			(type solid)
		)
		(fill yes)
		(layer "In11.Cu")
		(net "M_H_CPU1_SA_DQ<9>")
	)
	(gr_poly
		(pts
			(xy 138.12393 -236.801914) (xy 138.07694 -236.649514) (xy 137.81532 -236.649514) (xy 137.76833 -236.801914)
			(xy 137.76833 -236.84611) (xy 138.12393 -236.84611)
		)
		(stroke
			(width 0)
			(type solid)
		)
		(fill yes)
		(layer "In11.Cu")
		(net "M_H_CPU1_SB_DQS_DP<5>")
	)
	(gr_poly
		(pts
			(xy 138.12393 -236.39399) (xy 138.12393 -236.34954) (xy 137.76833 -236.34954) (xy 137.76833 -236.39399)
			(xy 137.81532 -236.54639) (xy 138.07694 -236.54639)
		)
		(stroke
			(width 0)
			(type solid)
		)
		(fill yes)
		(layer "In11.Cu")
		(net "M_H_CPU1_SB_DQ<4>")
	)
	(gr_poly
		(pts
			(xy 138.132566 -238.021114) (xy 138.132566 -237.976918) (xy 137.776966 -237.976918) (xy 137.776966 -238.021114)
			(xy 137.823956 -238.173514) (xy 138.085576 -238.173514)
		)
		(stroke
			(width 0)
			(type solid)
		)
		(fill yes)
		(layer "In11.Cu")
		(net "M_H_CPU1_SB_DQS_DP<0>")
	)
	(gr_poly
		(pts
			(xy 138.132566 -234.76585) (xy 138.132566 -234.7214) (xy 137.776966 -234.7214) (xy 137.776966 -234.76585)
			(xy 137.823956 -234.91825) (xy 138.085576 -234.91825)
		)
		(stroke
			(width 0)
			(type solid)
		)
		(fill yes)
		(layer "In11.Cu")
		(net "M_H_CPU1_SB_DQ<8>")
	)
	(gr_poly
		(pts
			(xy 138.132566 -233.54665) (xy 138.085576 -233.39425) (xy 137.823956 -233.39425) (xy 137.776966 -233.54665)
			(xy 137.776966 -233.590846) (xy 138.132566 -233.590846)
		)
		(stroke
			(width 0)
			(type solid)
		)
		(fill yes)
		(layer "In11.Cu")
		(net "M_H_CPU1_SB_DQ<11>")
	)
	(gr_poly
		(pts
			(xy 138.132566 -231.919018) (xy 138.085576 -231.766618) (xy 137.823956 -231.766618) (xy 137.776966 -231.919018)
			(xy 137.776966 -231.963214) (xy 138.132566 -231.963214)
		)
		(stroke
			(width 0)
			(type solid)
		)
		(fill yes)
		(layer "In11.Cu")
		(net "M_H_CPU1_SB_DQS_DP<6>")
	)
	(gr_poly
		(pts
			(xy 138.132566 -231.510078) (xy 138.132566 -231.465882) (xy 137.776966 -231.465882) (xy 137.776966 -231.510078)
			(xy 137.823956 -231.662478) (xy 138.085576 -231.662478)
		)
		(stroke
			(width 0)
			(type solid)
		)
		(fill yes)
		(layer "In11.Cu")
		(net "M_H_CPU1_SB_DQ<12>")
	)
	(gr_poly
		(pts
			(xy 138.132566 -228.663246) (xy 138.085576 -228.510846) (xy 137.823956 -228.510846) (xy 137.776966 -228.663246)
			(xy 137.776966 -228.707696) (xy 138.132566 -228.707696)
		)
		(stroke
			(width 0)
			(type solid)
		)
		(fill yes)
		(layer "In11.Cu")
		(net "M_H_CPU1_SB_DQ<24>")
	)
	(gr_poly
		(pts
			(xy 138.132566 -228.254814) (xy 138.132566 -228.210364) (xy 137.776966 -228.210364) (xy 137.776966 -228.254814)
			(xy 137.823956 -228.407214) (xy 138.085576 -228.407214)
		)
		(stroke
			(width 0)
			(type solid)
		)
		(fill yes)
		(layer "In11.Cu")
		(net "M_H_CPU1_SB_DQ<27>")
	)
	(gr_poly
		(pts
			(xy 138.132566 -227.035614) (xy 138.085576 -226.883214) (xy 137.823956 -226.883214) (xy 137.776966 -227.035614)
			(xy 137.776966 -227.07981) (xy 138.132566 -227.07981)
		)
		(stroke
			(width 0)
			(type solid)
		)
		(fill yes)
		(layer "In11.Cu")
		(net "M_H_CPU1_SB_DQS_DP<8>")
	)
	(gr_poly
		(pts
			(xy 138.132566 -226.626674) (xy 138.132566 -226.582478) (xy 137.776966 -226.582478) (xy 137.776966 -226.626674)
			(xy 137.823956 -226.779074) (xy 138.085576 -226.779074)
		)
		(stroke
			(width 0)
			(type solid)
		)
		(fill yes)
		(layer "In11.Cu")
		(net "M_H_CPU1_SB_DQS_DP<3>")
	)
	(gr_poly
		(pts
			(xy 138.205464 -225.479102) (xy 138.097006 -225.362262) (xy 138.058652 -225.340164) (xy 137.880852 -225.648012)
			(xy 137.919206 -225.67011) (xy 138.074654 -225.70567)
		)
		(stroke
			(width 0)
			(type solid)
		)
		(fill yes)
		(layer "In11.Cu")
		(net "M_H_CPU1_SB_DQ<30>")
	)
	(gr_poly
		(pts
			(xy 138.206734 -261.085838) (xy 138.315192 -260.968998) (xy 138.184382 -260.74243) (xy 138.028934 -260.77799)
			(xy 137.99058 -260.800088) (xy 138.16838 -261.107936)
		)
		(stroke
			(width 0)
			(type solid)
		)
		(fill yes)
		(layer "In11.Cu")
		(net "M_H_CPU1_SA_DQS_DP<9>")
	)
	(gr_poly
		(pts
			(xy 138.207496 -259.459476) (xy 138.315954 -259.342636) (xy 138.185144 -259.116068) (xy 138.029696 -259.151628)
			(xy 137.991342 -259.173726) (xy 138.169142 -259.481574)
		)
		(stroke
			(width 0)
			(type solid)
		)
		(fill yes)
		(layer "In11.Cu")
		(net "M_H_CPU1_SA_CB<6>")
	)
	(gr_poly
		(pts
			(xy 138.207496 -230.358442) (xy 138.099038 -230.241602) (xy 138.060684 -230.219504) (xy 137.882884 -230.527352)
			(xy 137.921238 -230.54945) (xy 138.076686 -230.58501)
		)
		(stroke
			(width 0)
			(type solid)
		)
		(fill yes)
		(layer "In11.Cu")
		(net "M_H_CPU1_SB_DQ<13>")
	)
	(gr_poly
		(pts
			(xy 138.20775 -283.876242) (xy 138.316208 -283.759402) (xy 138.185398 -283.532834) (xy 138.02995 -283.568394)
			(xy 137.991596 -283.590492) (xy 138.169396 -283.89834)
		)
		(stroke
			(width 0)
			(type solid)
		)
		(fill yes)
		(layer "In11.Cu")
		(net "M_H_CPU1_SA_DQ<11>")
	)
	(gr_poly
		(pts
			(xy 138.208004 -280.621232) (xy 138.316462 -280.504392) (xy 138.185652 -280.277824) (xy 138.030204 -280.313384)
			(xy 137.99185 -280.335482) (xy 138.16965 -280.64333)
		)
		(stroke
			(width 0)
			(type solid)
		)
		(fill yes)
		(layer "In11.Cu")
		(net "M_H_CPU1_SA_DQS_DP<6>")
	)
	(gr_poly
		(pts
			(xy 138.208766 -282.250896) (xy 138.317224 -282.134056) (xy 138.186414 -281.907488) (xy 138.030966 -281.943048)
			(xy 137.992612 -281.965146) (xy 138.170412 -282.272994)
		)
		(stroke
			(width 0)
			(type solid)
		)
		(fill yes)
		(layer "In11.Cu")
		(net "M_H_CPU1_SA_DQS_DN<1>")
	)
	(gr_poly
		(pts
			(xy 138.208766 -278.995378) (xy 138.317224 -278.878538) (xy 138.186414 -278.65197) (xy 138.030966 -278.68753)
			(xy 137.992612 -278.709628) (xy 138.170412 -279.017476)
		)
		(stroke
			(width 0)
			(type solid)
		)
		(fill yes)
		(layer "In11.Cu")
		(net "M_H_CPU1_SA_DQ<14>")
	)
	(gr_poly
		(pts
			(xy 138.21156 -240.094008) (xy 138.191748 -239.935766) (xy 137.933938 -239.8903) (xy 137.861294 -240.032286)
			(xy 137.853674 -240.07572) (xy 138.203686 -240.137696)
		)
		(stroke
			(width 0)
			(type solid)
		)
		(fill yes)
		(layer "In11.Cu")
		(net "M_H_CPU1_SB_CB<3>")
	)
	(gr_poly
		(pts
			(xy 138.233912 -271.215358) (xy 138.186922 -271.062958) (xy 137.925302 -271.062958) (xy 137.878312 -271.215358)
			(xy 137.878312 -271.259808) (xy 138.233912 -271.259808)
		)
		(stroke
			(width 0)
			(type solid)
		)
		(fill yes)
		(layer "In11.Cu")
		(net "M_H_CPU1_SA_DQ<23>")
	)
	(gr_poly
		(pts
			(xy 138.233912 -270.807434) (xy 138.233912 -270.762984) (xy 137.878312 -270.762984) (xy 137.878312 -270.807434)
			(xy 137.925302 -270.959834) (xy 138.186922 -270.959834)
		)
		(stroke
			(width 0)
			(type solid)
		)
		(fill yes)
		(layer "In11.Cu")
		(net "M_H_CPU1_SA_DQ<24>")
	)
	(gr_poly
		(pts
			(xy 138.233912 -269.587726) (xy 138.186922 -269.435326) (xy 137.925302 -269.435326) (xy 137.878312 -269.587726)
			(xy 137.878312 -269.631922) (xy 138.233912 -269.631922)
		)
		(stroke
			(width 0)
			(type solid)
		)
		(fill yes)
		(layer "In11.Cu")
		(net "M_H_CPU1_SA_DQ<27>")
	)
	(gr_poly
		(pts
			(xy 138.233912 -254.937514) (xy 138.186922 -254.785114) (xy 137.925302 -254.785114) (xy 137.878312 -254.937514)
			(xy 137.878312 -254.981964) (xy 138.233912 -254.981964)
		)
		(stroke
			(width 0)
			(type solid)
		)
		(fill yes)
		(layer "In11.Cu")
		(net "M_H_CPU1_SA_CA<0>")
	)
	(gr_poly
		(pts
			(xy 138.236452 -262.668258) (xy 138.236452 -262.624062) (xy 137.880852 -262.624062) (xy 137.880852 -262.668258)
			(xy 137.927842 -262.820658) (xy 138.189462 -262.820658)
		)
		(stroke
			(width 0)
			(type solid)
		)
		(fill yes)
		(layer "In11.Cu")
		(net "M_H_CPU1_SA_DQS_DP<4>")
	)
	(gr_poly
		(pts
			(xy 138.242294 -267.960094) (xy 138.195304 -267.807694) (xy 137.933684 -267.807694) (xy 137.886694 -267.960094)
			(xy 137.886694 -268.004544) (xy 138.242294 -268.004544)
		)
		(stroke
			(width 0)
			(type solid)
		)
		(fill yes)
		(layer "In11.Cu")
		(net "M_H_CPU1_SA_DQS_DP<8>")
	)
	(gr_poly
		(pts
			(xy 138.242294 -266.332462) (xy 138.195304 -266.180062) (xy 137.933684 -266.180062) (xy 137.886694 -266.332462)
			(xy 137.886694 -266.376658) (xy 138.242294 -266.376658)
		)
		(stroke
			(width 0)
			(type solid)
		)
		(fill yes)
		(layer "In11.Cu")
		(net "M_H_CPU1_SA_DQ<30>")
	)
	(gr_poly
		(pts
			(xy 138.242294 -265.92403) (xy 138.242294 -265.879834) (xy 137.886694 -265.879834) (xy 137.886694 -265.92403)
			(xy 137.933684 -266.07643) (xy 138.195304 -266.07643)
		)
		(stroke
			(width 0)
			(type solid)
		)
		(fill yes)
		(layer "In11.Cu")
		(net "M_H_CPU1_SA_DQ<29>")
	)
	(gr_poly
		(pts
			(xy 138.242294 -256.565654) (xy 138.195304 -256.413254) (xy 137.933684 -256.413254) (xy 137.886694 -256.565654)
			(xy 137.886694 -256.610104) (xy 138.242294 -256.610104)
		)
		(stroke
			(width 0)
			(type solid)
		)
		(fill yes)
		(layer "In11.Cu")
		(net "M_H_CPU1_SA_CS_N<1>")
	)
	(gr_poly
		(pts
			(xy 138.242294 -254.529082) (xy 138.242294 -254.484886) (xy 137.886694 -254.484886) (xy 137.886694 -254.529082)
			(xy 137.933684 -254.681482) (xy 138.195304 -254.681482)
		)
		(stroke
			(width 0)
			(type solid)
		)
		(fill yes)
		(layer "In11.Cu")
		(net "M_H_CPU1_SA_CA<2>")
	)
	(gr_poly
		(pts
			(xy 138.250422 -269.179294) (xy 138.250422 -269.135098) (xy 137.894822 -269.135098) (xy 137.894822 -269.179294)
			(xy 137.941812 -269.331694) (xy 138.203432 -269.331694)
		)
		(stroke
			(width 0)
			(type solid)
		)
		(fill yes)
		(layer "In11.Cu")
		(net "M_H_CPU1_SA_DQS_DP<3>")
	)
	(gr_poly
		(pts
			(xy 138.25093 -257.784854) (xy 138.25093 -257.740658) (xy 137.89533 -257.740658) (xy 137.89533 -257.784854)
			(xy 137.94232 -257.937254) (xy 138.20394 -257.937254)
		)
		(stroke
			(width 0)
			(type solid)
		)
		(fill yes)
		(layer "In11.Cu")
		(net "M_E_CPU1_ALERT_N")
	)
	(gr_poly
		(pts
			(xy 138.496548 -230.459788) (xy 138.458194 -230.43769) (xy 138.302746 -230.40213) (xy 138.171936 -230.628698)
			(xy 138.280394 -230.745538) (xy 138.318748 -230.767636)
		)
		(stroke
			(width 0)
			(type solid)
		)
		(fill yes)
		(layer "In11.Cu")
		(net "M_H_CPU1_SB_DQ<14>")
	)
	(gr_poly
		(pts
			(xy 138.602466 -227.44049) (xy 138.602466 -227.396294) (xy 138.246866 -227.396294) (xy 138.246866 -227.44049)
			(xy 138.293856 -227.59289) (xy 138.555476 -227.59289)
		)
		(stroke
			(width 0)
			(type solid)
		)
		(fill yes)
		(layer "In11.Cu")
		(net "M_H_CPU1_SB_DQS_DN<8>")
	)
	(gr_poly
		(pts
			(xy 138.675364 -231.176322) (xy 138.566906 -231.059482) (xy 138.528552 -231.037384) (xy 138.350752 -231.345232)
			(xy 138.389106 -231.36733) (xy 138.544554 -231.40289)
		)
		(stroke
			(width 0)
			(type solid)
		)
		(fill yes)
		(layer "In11.Cu")
		(net "M_H_CPU1_SB_DQ<12>")
	)
	(gr_poly
		(pts
			(xy 138.677396 -226.289108) (xy 138.568938 -226.172268) (xy 138.530584 -226.15017) (xy 138.352784 -226.458018)
			(xy 138.391138 -226.480116) (xy 138.546586 -226.515676)
		)
		(stroke
			(width 0)
			(type solid)
		)
		(fill yes)
		(layer "In11.Cu")
		(net "M_H_CPU1_SB_DQS_DP<3>")
	)
	(gr_poly
		(pts
			(xy 138.701526 -268.77391) (xy 138.654536 -268.62151) (xy 138.392916 -268.62151) (xy 138.345926 -268.77391)
			(xy 138.345926 -268.81836) (xy 138.701526 -268.81836)
		)
		(stroke
			(width 0)
			(type solid)
		)
		(fill yes)
		(layer "In11.Cu")
		(net "M_H_CPU1_SA_DQS_DN<3>")
	)
	(gr_poly
		(pts
			(xy 138.703812 -257.37947) (xy 138.656822 -257.22707) (xy 138.395202 -257.22707) (xy 138.348212 -257.37947)
			(xy 138.348212 -257.423666) (xy 138.703812 -257.423666)
		)
		(stroke
			(width 0)
			(type solid)
		)
		(fill yes)
		(layer "In11.Cu")
		(net "M_H_CPU1_ALERT_N")
	)
	(gr_poly
		(pts
			(xy 138.712194 -256.971038) (xy 138.712194 -256.926588) (xy 138.356594 -256.926588) (xy 138.356594 -256.971038)
			(xy 138.403584 -257.123438) (xy 138.665204 -257.123438)
		)
		(stroke
			(width 0)
			(type solid)
		)
		(fill yes)
		(layer "In11.Cu")
		(net "M_H_CPU1_SA_CS_N<0>")
	)
	(gr_poly
		(pts
			(xy 138.712194 -254.124206) (xy 138.665204 -253.971806) (xy 138.403584 -253.971806) (xy 138.356594 -254.124206)
			(xy 138.356594 -254.168402) (xy 138.712194 -254.168402)
		)
		(stroke
			(width 0)
			(type solid)
		)
		(fill yes)
		(layer "In11.Cu")
		(net "M_H_CPU1_SA_CA<3>")
	)
	(gr_poly
		(pts
			(xy 138.72083 -255.343406) (xy 138.72083 -255.298956) (xy 138.36523 -255.298956) (xy 138.36523 -255.343406)
			(xy 138.41222 -255.495806) (xy 138.67384 -255.495806)
		)
		(stroke
			(width 0)
			(type solid)
		)
		(fill yes)
		(layer "In11.Cu")
		(net "M_H_CPU1_SA_CA<1>")
	)
	(gr_poly
		(pts
			(xy 139.182094 -256.565654) (xy 139.135104 -256.413254) (xy 138.873484 -256.413254) (xy 138.826494 -256.565654)
			(xy 138.826494 -256.610104) (xy 139.182094 -256.610104)
		)
		(stroke
			(width 0)
			(type solid)
		)
		(fill yes)
		(layer "In11.Cu")
		(net "M_H_CPU1_SA_CS_N<1>")
	)
	(gr_poly
		(pts
			(xy 332.613762 -264.70483) (xy 332.566772 -264.55243) (xy 332.305152 -264.55243) (xy 332.258162 -264.70483)
			(xy 332.258162 -264.749026) (xy 332.613762 -264.749026)
		)
		(stroke
			(width 0)
			(type solid)
		)
		(fill yes)
		(layer "In11.Cu")
		(net "M_D_CPU0_SA_CB<2>")
	)
	(gr_poly
		(pts
			(xy 332.613762 -264.29589) (xy 332.613762 -264.251694) (xy 332.258162 -264.251694) (xy 332.258162 -264.29589)
			(xy 332.305152 -264.44829) (xy 332.566772 -264.44829)
		)
		(stroke
			(width 0)
			(type solid)
		)
		(fill yes)
		(layer "In11.Cu")
		(net "M_D_CPU0_SA_CB<1>")
	)
	(gr_poly
		(pts
			(xy 332.613762 -263.07669) (xy 332.566772 -262.92429) (xy 332.305152 -262.92429) (xy 332.258162 -263.07669)
			(xy 332.258162 -263.12114) (xy 332.613762 -263.12114)
		)
		(stroke
			(width 0)
			(type solid)
		)
		(fill yes)
		(layer "In11.Cu")
		(net "M_D_CPU0_SA_DQS_DN<4>")
	)
	(gr_poly
		(pts
			(xy 332.613762 -262.665718) (xy 332.613762 -262.621268) (xy 332.258162 -262.621268) (xy 332.258162 -262.665718)
			(xy 332.305152 -262.818118) (xy 332.566772 -262.818118)
		)
		(stroke
			(width 0)
			(type solid)
		)
		(fill yes)
		(layer "In11.Cu")
		(net "M_D_CPU0_SA_DQS_DN<9>")
	)
	(gr_poly
		(pts
			(xy 332.613762 -261.449058) (xy 332.566772 -261.296658) (xy 332.305152 -261.296658) (xy 332.258162 -261.449058)
			(xy 332.258162 -261.493508) (xy 332.613762 -261.493508)
		)
		(stroke
			(width 0)
			(type solid)
		)
		(fill yes)
		(layer "In11.Cu")
		(net "M_D_CPU0_SA_CB<6>")
	)
	(gr_poly
		(pts
			(xy 332.613762 -261.040626) (xy 332.613762 -260.996176) (xy 332.258162 -260.996176) (xy 332.258162 -261.040626)
			(xy 332.305152 -261.193026) (xy 332.566772 -261.193026)
		)
		(stroke
			(width 0)
			(type solid)
		)
		(fill yes)
		(layer "In11.Cu")
		(net "M_D_CPU0_SA_CB<5>")
	)
	(gr_poly
		(pts
			(xy 332.613762 -259.412486) (xy 332.613762 -259.36829) (xy 332.258162 -259.36829) (xy 332.258162 -259.412486)
			(xy 332.305152 -259.564886) (xy 332.566772 -259.564886)
		)
		(stroke
			(width 0)
			(type solid)
		)
		(fill yes)
		(layer "In11.Cu")
		(net "M_D_CPU0_SA_CS_N<2>")
	)
	(gr_poly
		(pts
			(xy 332.613762 -256.565654) (xy 332.566772 -256.413254) (xy 332.305152 -256.413254) (xy 332.258162 -256.565654)
			(xy 332.258162 -256.610104) (xy 332.613762 -256.610104)
		)
		(stroke
			(width 0)
			(type solid)
		)
		(fill yes)
		(layer "In11.Cu")
		(net "M_D_CPU0_SA_CA<3>")
	)
	(gr_poly
		(pts
			(xy 332.613762 -256.157222) (xy 332.613762 -256.112772) (xy 332.258162 -256.112772) (xy 332.258162 -256.157222)
			(xy 332.305152 -256.309622) (xy 332.566772 -256.309622)
		)
		(stroke
			(width 0)
			(type solid)
		)
		(fill yes)
		(layer "In11.Cu")
		(net "M_D_CPU0_SA_CA<4>")
	)
	(gr_poly
		(pts
			(xy 332.93939 -245.393718) (xy 333.047848 -245.276878) (xy 332.917038 -245.05031) (xy 332.76159 -245.08587)
			(xy 332.723236 -245.107968) (xy 332.901036 -245.415816)
		)
		(stroke
			(width 0)
			(type solid)
		)
		(fill yes)
		(layer "In11.Cu")
		(net "M_D_CPU0_SB_CB<7>")
	)
	(gr_poly
		(pts
			(xy 332.965298 -237.61573) (xy 332.918308 -237.46333) (xy 332.656688 -237.46333) (xy 332.609698 -237.61573)
			(xy 332.609698 -237.66018) (xy 332.965298 -237.66018)
		)
		(stroke
			(width 0)
			(type solid)
		)
		(fill yes)
		(layer "In11.Cu")
		(net "M_D_CPU0_SB_DQS_DP<5>")
	)
	(gr_poly
		(pts
			(xy 332.965298 -237.207806) (xy 332.965298 -237.163356) (xy 332.609698 -237.163356) (xy 332.609698 -237.207806)
			(xy 332.656688 -237.360206) (xy 332.918308 -237.360206)
		)
		(stroke
			(width 0)
			(type solid)
		)
		(fill yes)
		(layer "In11.Cu")
		(net "M_D_CPU0_SB_DQ<4>")
	)
	(gr_poly
		(pts
			(xy 332.965298 -232.732326) (xy 332.918308 -232.579926) (xy 332.656688 -232.579926) (xy 332.609698 -232.732326)
			(xy 332.609698 -232.776776) (xy 332.965298 -232.776776)
		)
		(stroke
			(width 0)
			(type solid)
		)
		(fill yes)
		(layer "In11.Cu")
		(net "M_D_CPU0_SB_DQS_DN<1>")
	)
	(gr_poly
		(pts
			(xy 332.965298 -232.324402) (xy 332.965298 -232.279952) (xy 332.609698 -232.279952) (xy 332.609698 -232.324402)
			(xy 332.656688 -232.476802) (xy 332.918308 -232.476802)
		)
		(stroke
			(width 0)
			(type solid)
		)
		(fill yes)
		(layer "In11.Cu")
		(net "M_D_CPU0_SB_DQS_DN<6>")
	)
	(gr_poly
		(pts
			(xy 332.965298 -227.848922) (xy 332.918308 -227.696522) (xy 332.656688 -227.696522) (xy 332.609698 -227.848922)
			(xy 332.609698 -227.893372) (xy 332.965298 -227.893372)
		)
		(stroke
			(width 0)
			(type solid)
		)
		(fill yes)
		(layer "In11.Cu")
		(net "M_D_CPU0_SB_DQ<26>")
	)
	(gr_poly
		(pts
			(xy 332.97368 -227.44049) (xy 332.97368 -227.396294) (xy 332.61808 -227.396294) (xy 332.61808 -227.44049)
			(xy 332.66507 -227.59289) (xy 332.92669 -227.59289)
		)
		(stroke
			(width 0)
			(type solid)
		)
		(fill yes)
		(layer "In11.Cu")
		(net "M_D_CPU0_SB_DQ<25>")
	)
	(gr_poly
		(pts
			(xy 332.973934 -247.382538) (xy 332.926944 -247.230138) (xy 332.665324 -247.230138) (xy 332.618334 -247.382538)
			(xy 332.618334 -247.426988) (xy 332.973934 -247.426988)
		)
		(stroke
			(width 0)
			(type solid)
		)
		(fill yes)
		(layer "In11.Cu")
		(net "M_D_CPU0_SB_CA<6>")
	)
	(gr_poly
		(pts
			(xy 332.973934 -235.988098) (xy 332.926944 -235.835698) (xy 332.665324 -235.835698) (xy 332.618334 -235.988098)
			(xy 332.618334 -236.032548) (xy 332.973934 -236.032548)
		)
		(stroke
			(width 0)
			(type solid)
		)
		(fill yes)
		(layer "In11.Cu")
		(net "M_D_CPU0_SB_DQ<7>")
	)
	(gr_poly
		(pts
			(xy 332.973934 -233.952034) (xy 332.973934 -233.907584) (xy 332.618334 -233.907584) (xy 332.618334 -233.952034)
			(xy 332.665324 -234.104434) (xy 332.926944 -234.104434)
		)
		(stroke
			(width 0)
			(type solid)
		)
		(fill yes)
		(layer "In11.Cu")
		(net "M_D_CPU0_SB_DQ<9>")
	)
	(gr_poly
		(pts
			(xy 332.973934 -231.104694) (xy 332.926944 -230.952294) (xy 332.665324 -230.952294) (xy 332.618334 -231.104694)
			(xy 332.618334 -231.149144) (xy 332.973934 -231.149144)
		)
		(stroke
			(width 0)
			(type solid)
		)
		(fill yes)
		(layer "In11.Cu")
		(net "M_D_CPU0_SB_DQ<14>")
	)
	(gr_poly
		(pts
			(xy 332.974188 -238.835438) (xy 332.974188 -238.790988) (xy 332.618588 -238.790988) (xy 332.618588 -238.835438)
			(xy 332.665578 -238.987838) (xy 332.927198 -238.987838)
		)
		(stroke
			(width 0)
			(type solid)
		)
		(fill yes)
		(layer "In11.Cu")
		(net "M_D_CPU0_SB_DQS_DP<0>")
	)
	(gr_poly
		(pts
			(xy 332.982316 -240.46307) (xy 332.982316 -240.418874) (xy 332.626716 -240.418874) (xy 332.626716 -240.46307)
			(xy 332.673706 -240.61547) (xy 332.935326 -240.61547)
		)
		(stroke
			(width 0)
			(type solid)
		)
		(fill yes)
		(layer "In11.Cu")
		(net "M_D_CPU0_SB_DQ<0>")
	)
	(gr_poly
		(pts
			(xy 332.982316 -239.243362) (xy 332.935326 -239.090962) (xy 332.673706 -239.090962) (xy 332.626716 -239.243362)
			(xy 332.626716 -239.287812) (xy 332.982316 -239.287812)
		)
		(stroke
			(width 0)
			(type solid)
		)
		(fill yes)
		(layer "In11.Cu")
		(net "M_D_CPU0_SB_DQ<3>")
	)
	(gr_poly
		(pts
			(xy 332.982316 -234.360466) (xy 332.935326 -234.208066) (xy 332.673706 -234.208066) (xy 332.626716 -234.360466)
			(xy 332.626716 -234.404662) (xy 332.982316 -234.404662)
		)
		(stroke
			(width 0)
			(type solid)
		)
		(fill yes)
		(layer "In11.Cu")
		(net "M_D_CPU0_SB_DQ<10>")
	)
	(gr_poly
		(pts
			(xy 332.982316 -230.696262) (xy 332.982316 -230.652066) (xy 332.626716 -230.652066) (xy 332.626716 -230.696262)
			(xy 332.673706 -230.848662) (xy 332.935326 -230.848662)
		)
		(stroke
			(width 0)
			(type solid)
		)
		(fill yes)
		(layer "In11.Cu")
		(net "M_D_CPU0_SB_DQ<13>")
	)
	(gr_poly
		(pts
			(xy 333.083662 -268.77391) (xy 333.036672 -268.62151) (xy 332.775052 -268.62151) (xy 332.728062 -268.77391)
			(xy 332.728062 -268.81836) (xy 333.083662 -268.81836)
		)
		(stroke
			(width 0)
			(type solid)
		)
		(fill yes)
		(layer "In11.Cu")
		(net "M_D_CPU0_SA_DQ<27>")
	)
	(gr_poly
		(pts
			(xy 333.083662 -266.737846) (xy 333.083662 -266.693396) (xy 332.728062 -266.693396) (xy 332.728062 -266.737846)
			(xy 332.775052 -266.890246) (xy 333.036672 -266.890246)
		)
		(stroke
			(width 0)
			(type solid)
		)
		(fill yes)
		(layer "In11.Cu")
		(net "M_D_CPU0_SA_DQ<28>")
	)
	(gr_poly
		(pts
			(xy 333.083662 -265.518646) (xy 333.036672 -265.366246) (xy 332.775052 -265.366246) (xy 332.728062 -265.518646)
			(xy 332.728062 -265.562842) (xy 333.083662 -265.562842)
		)
		(stroke
			(width 0)
			(type solid)
		)
		(fill yes)
		(layer "In11.Cu")
		(net "M_D_CPU0_SA_DQ<31>")
	)
	(gr_poly
		(pts
			(xy 333.083662 -265.109706) (xy 333.083662 -265.06551) (xy 332.728062 -265.06551) (xy 332.728062 -265.109706)
			(xy 332.775052 -265.262106) (xy 333.036672 -265.262106)
		)
		(stroke
			(width 0)
			(type solid)
		)
		(fill yes)
		(layer "In11.Cu")
		(net "M_D_CPU0_SA_CB<0>")
	)
	(gr_poly
		(pts
			(xy 333.083662 -263.891014) (xy 333.036672 -263.738614) (xy 332.775052 -263.738614) (xy 332.728062 -263.891014)
			(xy 332.728062 -263.93521) (xy 333.083662 -263.93521)
		)
		(stroke
			(width 0)
			(type solid)
		)
		(fill yes)
		(layer "In11.Cu")
		(net "M_D_CPU0_SA_CB<3>")
	)
	(gr_poly
		(pts
			(xy 333.083662 -263.482074) (xy 333.083662 -263.437878) (xy 332.728062 -263.437878) (xy 332.728062 -263.482074)
			(xy 332.775052 -263.634474) (xy 333.036672 -263.634474)
		)
		(stroke
			(width 0)
			(type solid)
		)
		(fill yes)
		(layer "In11.Cu")
		(net "M_D_CPU0_SA_DQS_DP<4>")
	)
	(gr_poly
		(pts
			(xy 333.083662 -262.262874) (xy 333.036672 -262.110474) (xy 332.775052 -262.110474) (xy 332.728062 -262.262874)
			(xy 332.728062 -262.307324) (xy 333.083662 -262.307324)
		)
		(stroke
			(width 0)
			(type solid)
		)
		(fill yes)
		(layer "In11.Cu")
		(net "M_D_CPU0_SA_DQS_DP<9>")
	)
	(gr_poly
		(pts
			(xy 333.083662 -261.854442) (xy 333.083662 -261.809992) (xy 332.728062 -261.809992) (xy 332.728062 -261.854442)
			(xy 332.775052 -262.006842) (xy 333.036672 -262.006842)
		)
		(stroke
			(width 0)
			(type solid)
		)
		(fill yes)
		(layer "In11.Cu")
		(net "M_D_CPU0_SA_CB<4>")
	)
	(gr_poly
		(pts
			(xy 333.083662 -260.635242) (xy 333.036672 -260.482842) (xy 332.775052 -260.482842) (xy 332.728062 -260.635242)
			(xy 332.728062 -260.679438) (xy 333.083662 -260.679438)
		)
		(stroke
			(width 0)
			(type solid)
		)
		(fill yes)
		(layer "In11.Cu")
		(net "M_D_CPU0_SA_CB<7>")
	)
	(gr_poly
		(pts
			(xy 333.083662 -259.00761) (xy 333.036672 -258.85521) (xy 332.775052 -258.85521) (xy 332.728062 -259.00761)
			(xy 332.728062 -259.051806) (xy 333.083662 -259.051806)
		)
		(stroke
			(width 0)
			(type solid)
		)
		(fill yes)
		(layer "In11.Cu")
		(net "M_D_CPU0_SA_CS_N<0>")
	)
	(gr_poly
		(pts
			(xy 333.083662 -258.59867) (xy 333.083662 -258.554474) (xy 332.728062 -258.554474) (xy 332.728062 -258.59867)
			(xy 332.775052 -258.75107) (xy 333.036672 -258.75107)
		)
		(stroke
			(width 0)
			(type solid)
		)
		(fill yes)
		(layer "In11.Cu")
		(net "M_D_CPU0_SA_CS_N<3>")
	)
	(gr_poly
		(pts
			(xy 333.083662 -257.37947) (xy 333.036672 -257.22707) (xy 332.775052 -257.22707) (xy 332.728062 -257.37947)
			(xy 332.728062 -257.42392) (xy 333.083662 -257.42392)
		)
		(stroke
			(width 0)
			(type solid)
		)
		(fill yes)
		(layer "In11.Cu")
		(net "M_D_CPU0_SA_CA<1>")
	)
	(gr_poly
		(pts
			(xy 333.083662 -256.971038) (xy 333.083662 -256.926588) (xy 332.728062 -256.926588) (xy 332.728062 -256.971038)
			(xy 332.775052 -257.123438) (xy 333.036672 -257.123438)
		)
		(stroke
			(width 0)
			(type solid)
		)
		(fill yes)
		(layer "In11.Cu")
		(net "M_D_CPU0_SA_CA<2>")
	)
	(gr_poly
		(pts
			(xy 333.083662 -255.751838) (xy 333.036672 -255.599438) (xy 332.775052 -255.599438) (xy 332.728062 -255.751838)
			(xy 332.728062 -255.796288) (xy 333.083662 -255.796288)
		)
		(stroke
			(width 0)
			(type solid)
		)
		(fill yes)
		(layer "In11.Cu")
		(net "M_D_CPU0_SA_CA<5>")
	)
	(gr_poly
		(pts
			(xy 333.083916 -267.146278) (xy 333.036926 -266.993878) (xy 332.775306 -266.993878) (xy 332.728316 -267.146278)
			(xy 332.728316 -267.190474) (xy 333.083916 -267.190474)
		)
		(stroke
			(width 0)
			(type solid)
		)
		(fill yes)
		(layer "In11.Cu")
		(net "M_D_CPU0_SA_DQS_DP<8>")
	)
	(gr_poly
		(pts
			(xy 333.300324 -245.20144) (xy 333.338678 -245.179342) (xy 333.160878 -244.871494) (xy 333.122524 -244.893592)
			(xy 333.014066 -245.010432) (xy 333.144876 -245.237)
		)
		(stroke
			(width 0)
			(type solid)
		)
		(fill yes)
		(layer "In11.Cu")
		(net "M_D_CPU0_SB_DQS_DP<9>")
	)
	(gr_poly
		(pts
			(xy 333.435198 -240.057178) (xy 333.388208 -239.904778) (xy 333.126588 -239.904778) (xy 333.079598 -240.057178)
			(xy 333.079598 -240.101628) (xy 333.435198 -240.101628)
		)
		(stroke
			(width 0)
			(type solid)
		)
		(fill yes)
		(layer "In11.Cu")
		(net "M_D_CPU0_SB_DQ<2>")
	)
	(gr_poly
		(pts
			(xy 333.435198 -239.649254) (xy 333.435198 -239.604804) (xy 333.079598 -239.604804) (xy 333.079598 -239.649254)
			(xy 333.126588 -239.801654) (xy 333.388208 -239.801654)
		)
		(stroke
			(width 0)
			(type solid)
		)
		(fill yes)
		(layer "In11.Cu")
		(net "M_D_CPU0_SB_DQ<1>")
	)
	(gr_poly
		(pts
			(xy 333.435198 -234.76585) (xy 333.435198 -234.721654) (xy 333.079598 -234.721654) (xy 333.079598 -234.76585)
			(xy 333.126588 -234.91825) (xy 333.388208 -234.91825)
		)
		(stroke
			(width 0)
			(type solid)
		)
		(fill yes)
		(layer "In11.Cu")
		(net "M_D_CPU0_SB_DQ<8>")
	)
	(gr_poly
		(pts
			(xy 333.435198 -230.290878) (xy 333.388208 -230.138478) (xy 333.126588 -230.138478) (xy 333.079598 -230.290878)
			(xy 333.079598 -230.335074) (xy 333.435198 -230.335074)
		)
		(stroke
			(width 0)
			(type solid)
		)
		(fill yes)
		(layer "In11.Cu")
		(net "M_D_CPU0_SB_DQ<15>")
	)
	(gr_poly
		(pts
			(xy 333.443834 -248.196354) (xy 333.396844 -248.043954) (xy 333.135224 -248.043954) (xy 333.088234 -248.196354)
			(xy 333.088234 -248.240804) (xy 333.443834 -248.240804)
		)
		(stroke
			(width 0)
			(type solid)
		)
		(fill yes)
		(layer "In11.Cu")
		(net "M_D_CPU0_SB_CA<5>")
	)
	(gr_poly
		(pts
			(xy 333.443834 -247.787922) (xy 333.443834 -247.743472) (xy 333.088234 -247.743472) (xy 333.088234 -247.787922)
			(xy 333.135224 -247.940322) (xy 333.396844 -247.940322)
		)
		(stroke
			(width 0)
			(type solid)
		)
		(fill yes)
		(layer "In11.Cu")
		(net "M_D_CPU0_SB_PAR")
	)
	(gr_poly
		(pts
			(xy 333.443834 -246.16029) (xy 333.443834 -246.11584) (xy 333.088234 -246.11584) (xy 333.088234 -246.16029)
			(xy 333.135224 -246.31269) (xy 333.396844 -246.31269)
		)
		(stroke
			(width 0)
			(type solid)
		)
		(fill yes)
		(layer "In11.Cu")
		(net "M_D_CPU0_SB_CB<5>")
	)
	(gr_poly
		(pts
			(xy 333.443834 -238.430054) (xy 333.396844 -238.277654) (xy 333.135224 -238.277654) (xy 333.088234 -238.430054)
			(xy 333.088234 -238.47425) (xy 333.443834 -238.47425)
		)
		(stroke
			(width 0)
			(type solid)
		)
		(fill yes)
		(layer "In11.Cu")
		(net "M_D_CPU0_SB_DQS_DN<0>")
	)
	(gr_poly
		(pts
			(xy 333.443834 -236.393482) (xy 333.443834 -236.349286) (xy 333.088234 -236.349286) (xy 333.088234 -236.393482)
			(xy 333.135224 -236.545882) (xy 333.396844 -236.545882)
		)
		(stroke
			(width 0)
			(type solid)
		)
		(fill yes)
		(layer "In11.Cu")
		(net "M_D_CPU0_SB_DQ<5>")
	)
	(gr_poly
		(pts
			(xy 333.443834 -233.54665) (xy 333.396844 -233.39425) (xy 333.135224 -233.39425) (xy 333.088234 -233.54665)
			(xy 333.088234 -233.590846) (xy 333.443834 -233.590846)
		)
		(stroke
			(width 0)
			(type solid)
		)
		(fill yes)
		(layer "In11.Cu")
		(net "M_D_CPU0_SB_DQ<11>")
	)
	(gr_poly
		(pts
			(xy 333.443834 -231.510078) (xy 333.443834 -231.465882) (xy 333.088234 -231.465882) (xy 333.088234 -231.510078)
			(xy 333.135224 -231.662478) (xy 333.396844 -231.662478)
		)
		(stroke
			(width 0)
			(type solid)
		)
		(fill yes)
		(layer "In11.Cu")
		(net "M_D_CPU0_SB_DQ<12>")
	)
	(gr_poly
		(pts
			(xy 333.449676 -227.035106) (xy 333.402686 -226.882706) (xy 333.141066 -226.882706) (xy 333.094076 -227.035106)
			(xy 333.094076 -227.079556) (xy 333.449676 -227.079556)
		)
		(stroke
			(width 0)
			(type solid)
		)
		(fill yes)
		(layer "In11.Cu")
		(net "M_D_CPU0_SB_DQ<27>")
	)
	(gr_poly
		(pts
			(xy 333.449676 -226.627182) (xy 333.449676 -226.582732) (xy 333.094076 -226.582732) (xy 333.094076 -226.627182)
			(xy 333.141066 -226.779582) (xy 333.402686 -226.779582)
		)
		(stroke
			(width 0)
			(type solid)
		)
		(fill yes)
		(layer "In11.Cu")
		(net "M_D_CPU0_SB_DQS_DP<3>")
	)
	(gr_poly
		(pts
			(xy 333.452216 -243.31295) (xy 333.405226 -243.16055) (xy 333.143606 -243.16055) (xy 333.096616 -243.31295)
			(xy 333.096616 -243.3574) (xy 333.452216 -243.3574)
		)
		(stroke
			(width 0)
			(type solid)
		)
		(fill yes)
		(layer "In11.Cu")
		(net "M_D_CPU0_SB_DQS_DP<4>")
	)
	(gr_poly
		(pts
			(xy 333.452216 -242.905026) (xy 333.452216 -242.860576) (xy 333.096616 -242.860576) (xy 333.096616 -242.905026)
			(xy 333.143606 -243.057426) (xy 333.405226 -243.057426)
		)
		(stroke
			(width 0)
			(type solid)
		)
		(fill yes)
		(layer "In11.Cu")
		(net "M_D_CPU0_SB_CB<0>")
	)
	(gr_poly
		(pts
			(xy 333.452216 -241.685318) (xy 333.405226 -241.532918) (xy 333.143606 -241.532918) (xy 333.096616 -241.685318)
			(xy 333.096616 -241.729514) (xy 333.452216 -241.729514)
		)
		(stroke
			(width 0)
			(type solid)
		)
		(fill yes)
		(layer "In11.Cu")
		(net "M_D_CPU0_SB_CB<3>")
	)
	(gr_poly
		(pts
			(xy 333.452216 -238.021622) (xy 333.452216 -237.977172) (xy 333.096616 -237.977172) (xy 333.096616 -238.021622)
			(xy 333.143606 -238.174022) (xy 333.405226 -238.174022)
		)
		(stroke
			(width 0)
			(type solid)
		)
		(fill yes)
		(layer "In11.Cu")
		(net "M_D_CPU0_SB_DQS_DN<5>")
	)
	(gr_poly
		(pts
			(xy 333.452216 -236.801914) (xy 333.405226 -236.649514) (xy 333.143606 -236.649514) (xy 333.096616 -236.801914)
			(xy 333.096616 -236.846364) (xy 333.452216 -236.846364)
		)
		(stroke
			(width 0)
			(type solid)
		)
		(fill yes)
		(layer "In11.Cu")
		(net "M_D_CPU0_SB_DQ<6>")
	)
	(gr_poly
		(pts
			(xy 333.452216 -233.138218) (xy 333.452216 -233.093768) (xy 333.096616 -233.093768) (xy 333.096616 -233.138218)
			(xy 333.143606 -233.290618) (xy 333.405226 -233.290618)
		)
		(stroke
			(width 0)
			(type solid)
		)
		(fill yes)
		(layer "In11.Cu")
		(net "M_D_CPU0_SB_DQS_DP<1>")
	)
	(gr_poly
		(pts
			(xy 333.452216 -231.91851) (xy 333.405226 -231.76611) (xy 333.143606 -231.76611) (xy 333.096616 -231.91851)
			(xy 333.096616 -231.96296) (xy 333.452216 -231.96296)
		)
		(stroke
			(width 0)
			(type solid)
		)
		(fill yes)
		(layer "In11.Cu")
		(net "M_D_CPU0_SB_DQS_DP<6>")
	)
	(gr_poly
		(pts
			(xy 333.452216 -228.254814) (xy 333.452216 -228.210618) (xy 333.096616 -228.210618) (xy 333.096616 -228.254814)
			(xy 333.143606 -228.407214) (xy 333.405226 -228.407214)
		)
		(stroke
			(width 0)
			(type solid)
		)
		(fill yes)
		(layer "In11.Cu")
		(net "M_D_CPU0_SB_DQ<24>")
	)
	(gr_poly
		(pts
			(xy 333.452216 -225.407474) (xy 333.405226 -225.255074) (xy 333.143606 -225.255074) (xy 333.096616 -225.407474)
			(xy 333.096616 -225.45167) (xy 333.452216 -225.45167)
		)
		(stroke
			(width 0)
			(type solid)
		)
		(fill yes)
		(layer "In11.Cu")
		(net "M_D_CPU0_SB_DQS_DP<8>")
	)
	(gr_poly
		(pts
			(xy 333.452216 -224.999042) (xy 333.452216 -224.954846) (xy 333.096616 -224.954846) (xy 333.096616 -224.999042)
			(xy 333.143606 -225.151442) (xy 333.405226 -225.151442)
		)
		(stroke
			(width 0)
			(type solid)
		)
		(fill yes)
		(layer "In11.Cu")
		(net "M_D_CPU0_SB_DQ<28>")
	)
	(gr_poly
		(pts
			(xy 333.452216 -223.779842) (xy 333.405226 -223.627442) (xy 333.143606 -223.627442) (xy 333.096616 -223.779842)
			(xy 333.096616 -223.824038) (xy 333.452216 -223.824038)
		)
		(stroke
			(width 0)
			(type solid)
		)
		(fill yes)
		(layer "In11.Cu")
		(net "M_D_CPU0_SB_DQ<31>")
	)
	(gr_poly
		(pts
			(xy 333.54772 -272.843498) (xy 333.50073 -272.691098) (xy 333.23911 -272.691098) (xy 333.19212 -272.843498)
			(xy 333.19212 -272.887948) (xy 333.54772 -272.887948)
		)
		(stroke
			(width 0)
			(type solid)
		)
		(fill yes)
		(layer "In11.Cu")
		(net "M_D_CPU0_SA_DQS_DN<2>")
	)
	(gr_poly
		(pts
			(xy 333.553562 -271.215866) (xy 333.506572 -271.063466) (xy 333.244952 -271.063466) (xy 333.197962 -271.215866)
			(xy 333.197962 -271.260062) (xy 333.553562 -271.260062)
		)
		(stroke
			(width 0)
			(type solid)
		)
		(fill yes)
		(layer "In11.Cu")
		(net "M_D_CPU0_SA_DQ<22>")
	)
	(gr_poly
		(pts
			(xy 333.553562 -269.179294) (xy 333.553562 -269.134844) (xy 333.197962 -269.134844) (xy 333.197962 -269.179294)
			(xy 333.244952 -269.331694) (xy 333.506572 -269.331694)
		)
		(stroke
			(width 0)
			(type solid)
		)
		(fill yes)
		(layer "In11.Cu")
		(net "M_D_CPU0_SA_DQ<25>")
	)
	(gr_poly
		(pts
			(xy 333.553562 -267.960094) (xy 333.506572 -267.807694) (xy 333.244952 -267.807694) (xy 333.197962 -267.960094)
			(xy 333.197962 -268.004544) (xy 333.553562 -268.004544)
		)
		(stroke
			(width 0)
			(type solid)
		)
		(fill yes)
		(layer "In11.Cu")
		(net "M_D_CPU0_SA_DQS_DN<3>")
	)
	(gr_poly
		(pts
			(xy 333.553562 -267.551662) (xy 333.553562 -267.507212) (xy 333.197962 -267.507212) (xy 333.197962 -267.551662)
			(xy 333.244952 -267.704062) (xy 333.506572 -267.704062)
		)
		(stroke
			(width 0)
			(type solid)
		)
		(fill yes)
		(layer "In11.Cu")
		(net "M_D_CPU0_SA_DQS_DN<8>")
	)
	(gr_poly
		(pts
			(xy 333.553562 -266.332462) (xy 333.506572 -266.180062) (xy 333.244952 -266.180062) (xy 333.197962 -266.332462)
			(xy 333.197962 -266.376658) (xy 333.553562 -266.376658)
		)
		(stroke
			(width 0)
			(type solid)
		)
		(fill yes)
		(layer "In11.Cu")
		(net "M_D_CPU0_SA_DQ<30>")
	)
	(gr_poly
		(pts
			(xy 333.553562 -265.92403) (xy 333.553562 -265.87958) (xy 333.197962 -265.87958) (xy 333.197962 -265.92403)
			(xy 333.244952 -266.07643) (xy 333.506572 -266.07643)
		)
		(stroke
			(width 0)
			(type solid)
		)
		(fill yes)
		(layer "In11.Cu")
		(net "M_D_CPU0_SA_DQ<29>")
	)
	(gr_poly
		(pts
			(xy 333.553562 -264.70483) (xy 333.506572 -264.55243) (xy 333.244952 -264.55243) (xy 333.197962 -264.70483)
			(xy 333.197962 -264.749026) (xy 333.553562 -264.749026)
		)
		(stroke
			(width 0)
			(type solid)
		)
		(fill yes)
		(layer "In11.Cu")
		(net "M_D_CPU0_SA_CB<2>")
	)
	(gr_poly
		(pts
			(xy 333.553562 -264.29589) (xy 333.553562 -264.251694) (xy 333.197962 -264.251694) (xy 333.197962 -264.29589)
			(xy 333.244952 -264.44829) (xy 333.506572 -264.44829)
		)
		(stroke
			(width 0)
			(type solid)
		)
		(fill yes)
		(layer "In11.Cu")
		(net "M_D_CPU0_SA_CB<1>")
	)
	(gr_poly
		(pts
			(xy 333.553562 -263.07669) (xy 333.506572 -262.92429) (xy 333.244952 -262.92429) (xy 333.197962 -263.07669)
			(xy 333.197962 -263.12114) (xy 333.553562 -263.12114)
		)
		(stroke
			(width 0)
			(type solid)
		)
		(fill yes)
		(layer "In11.Cu")
		(net "M_D_CPU0_SA_DQS_DN<4>")
	)
	(gr_poly
		(pts
			(xy 333.553562 -262.668258) (xy 333.553562 -262.623808) (xy 333.197962 -262.623808) (xy 333.197962 -262.668258)
			(xy 333.244952 -262.820658) (xy 333.506572 -262.820658)
		)
		(stroke
			(width 0)
			(type solid)
		)
		(fill yes)
		(layer "In11.Cu")
		(net "M_D_CPU0_SA_DQS_DN<9>")
	)
	(gr_poly
		(pts
			(xy 333.553562 -261.449058) (xy 333.506572 -261.296658) (xy 333.244952 -261.296658) (xy 333.197962 -261.449058)
			(xy 333.197962 -261.493508) (xy 333.553562 -261.493508)
		)
		(stroke
			(width 0)
			(type solid)
		)
		(fill yes)
		(layer "In11.Cu")
		(net "M_D_CPU0_SA_CB<6>")
	)
	(gr_poly
		(pts
			(xy 333.553562 -261.040626) (xy 333.553562 -260.996176) (xy 333.197962 -260.996176) (xy 333.197962 -261.040626)
			(xy 333.244952 -261.193026) (xy 333.506572 -261.193026)
		)
		(stroke
			(width 0)
			(type solid)
		)
		(fill yes)
		(layer "In11.Cu")
		(net "M_D_CPU0_SA_CB<5>")
	)
	(gr_poly
		(pts
			(xy 333.553562 -259.412486) (xy 333.553562 -259.36829) (xy 333.197962 -259.36829) (xy 333.197962 -259.412486)
			(xy 333.244952 -259.564886) (xy 333.506572 -259.564886)
		)
		(stroke
			(width 0)
			(type solid)
		)
		(fill yes)
		(layer "In11.Cu")
		(net "M_D_CPU0_SA_CS_N<2>")
	)
	(gr_poly
		(pts
			(xy 333.553562 -258.193286) (xy 333.506572 -258.040886) (xy 333.244952 -258.040886) (xy 333.197962 -258.193286)
			(xy 333.197962 -258.237736) (xy 333.553562 -258.237736)
		)
		(stroke
			(width 0)
			(type solid)
		)
		(fill yes)
		(layer "In11.Cu")
		(net "M_D_CPU0_SA_CS_N<1>")
	)
	(gr_poly
		(pts
			(xy 333.553562 -257.784854) (xy 333.553562 -257.740404) (xy 333.197962 -257.740404) (xy 333.197962 -257.784854)
			(xy 333.244952 -257.937254) (xy 333.506572 -257.937254)
		)
		(stroke
			(width 0)
			(type solid)
		)
		(fill yes)
		(layer "In11.Cu")
		(net "M_D_CPU0_SA_CA<0>")
	)
	(gr_poly
		(pts
			(xy 333.553562 -256.565654) (xy 333.506572 -256.413254) (xy 333.244952 -256.413254) (xy 333.197962 -256.565654)
			(xy 333.197962 -256.610104) (xy 333.553562 -256.610104)
		)
		(stroke
			(width 0)
			(type solid)
		)
		(fill yes)
		(layer "In11.Cu")
		(net "M_D_CPU0_SA_CA<3>")
	)
	(gr_poly
		(pts
			(xy 333.553562 -256.157222) (xy 333.553562 -256.112772) (xy 333.197962 -256.112772) (xy 333.197962 -256.157222)
			(xy 333.244952 -256.309622) (xy 333.506572 -256.309622)
		)
		(stroke
			(width 0)
			(type solid)
		)
		(fill yes)
		(layer "In11.Cu")
		(net "M_D_CPU0_SA_CA<4>")
	)
	(gr_poly
		(pts
			(xy 333.559658 -272.435066) (xy 333.559658 -272.390616) (xy 333.204058 -272.390616) (xy 333.204058 -272.435066)
			(xy 333.251048 -272.587466) (xy 333.512668 -272.587466)
		)
		(stroke
			(width 0)
			(type solid)
		)
		(fill yes)
		(layer "In11.Cu")
		(net "M_D_CPU0_SA_DQS_DN<7>")
	)
	(gr_poly
		(pts
			(xy 333.769208 -244.385592) (xy 333.807562 -244.363494) (xy 333.629762 -244.055646) (xy 333.591408 -244.077744)
			(xy 333.48295 -244.194584) (xy 333.61376 -244.421152)
		)
		(stroke
			(width 0)
			(type solid)
		)
		(fill yes)
		(layer "In11.Cu")
		(net "M_D_CPU0_SB_DQS_DN<4>")
	)
	(gr_poly
		(pts
			(xy 333.769462 -241.130074) (xy 333.807816 -241.107976) (xy 333.630016 -240.800128) (xy 333.591662 -240.822226)
			(xy 333.483204 -240.939066) (xy 333.614014 -241.165634)
		)
		(stroke
			(width 0)
			(type solid)
		)
		(fill yes)
		(layer "In11.Cu")
		(net "M_D_CPU0_SB_DQ<0>")
	)
	(gr_poly
		(pts
			(xy 333.878936 -243.765324) (xy 333.987394 -243.648484) (xy 333.856584 -243.421916) (xy 333.701136 -243.457476)
			(xy 333.662782 -243.479574) (xy 333.840582 -243.787422)
		)
		(stroke
			(width 0)
			(type solid)
		)
		(fill yes)
		(layer "In11.Cu")
		(net "M_D_CPU0_SB_DQS_DP<4>")
	)
	(gr_poly
		(pts
			(xy 333.87919 -240.510314) (xy 333.987648 -240.393474) (xy 333.856838 -240.166906) (xy 333.70139 -240.202466)
			(xy 333.663036 -240.224564) (xy 333.840836 -240.532412)
		)
		(stroke
			(width 0)
			(type solid)
		)
		(fill yes)
		(layer "In11.Cu")
		(net "M_D_CPU0_SB_DQ<2>")
	)
	(gr_poly
		(pts
			(xy 333.907638 -242.499134) (xy 333.860648 -242.346734) (xy 333.599028 -242.346734) (xy 333.552038 -242.499134)
			(xy 333.552038 -242.54333) (xy 333.907638 -242.54333)
		)
		(stroke
			(width 0)
			(type solid)
		)
		(fill yes)
		(layer "In11.Cu")
		(net "M_D_CPU0_SB_CB<2>")
	)
	(gr_poly
		(pts
			(xy 333.907638 -242.090702) (xy 333.907638 -242.046506) (xy 333.552038 -242.046506) (xy 333.552038 -242.090702)
			(xy 333.599028 -242.243102) (xy 333.860648 -242.243102)
		)
		(stroke
			(width 0)
			(type solid)
		)
		(fill yes)
		(layer "In11.Cu")
		(net "M_D_CPU0_SB_CB<1>")
	)
	(gr_poly
		(pts
			(xy 333.907638 -237.61573) (xy 333.860648 -237.46333) (xy 333.599028 -237.46333) (xy 333.552038 -237.61573)
			(xy 333.552038 -237.66018) (xy 333.907638 -237.66018)
		)
		(stroke
			(width 0)
			(type solid)
		)
		(fill yes)
		(layer "In11.Cu")
		(net "M_D_CPU0_SB_DQS_DP<5>")
	)
	(gr_poly
		(pts
			(xy 333.907638 -237.207806) (xy 333.907638 -237.163356) (xy 333.552038 -237.163356) (xy 333.552038 -237.207806)
			(xy 333.599028 -237.360206) (xy 333.860648 -237.360206)
		)
		(stroke
			(width 0)
			(type solid)
		)
		(fill yes)
		(layer "In11.Cu")
		(net "M_D_CPU0_SB_DQ<4>")
	)
	(gr_poly
		(pts
			(xy 333.907638 -232.732326) (xy 333.860648 -232.579926) (xy 333.599028 -232.579926) (xy 333.552038 -232.732326)
			(xy 333.552038 -232.776776) (xy 333.907638 -232.776776)
		)
		(stroke
			(width 0)
			(type solid)
		)
		(fill yes)
		(layer "In11.Cu")
		(net "M_D_CPU0_SB_DQS_DN<1>")
	)
	(gr_poly
		(pts
			(xy 333.907638 -232.324402) (xy 333.907638 -232.279952) (xy 333.552038 -232.279952) (xy 333.552038 -232.324402)
			(xy 333.599028 -232.476802) (xy 333.860648 -232.476802)
		)
		(stroke
			(width 0)
			(type solid)
		)
		(fill yes)
		(layer "In11.Cu")
		(net "M_D_CPU0_SB_DQS_DN<6>")
	)
	(gr_poly
		(pts
			(xy 333.907638 -227.848922) (xy 333.860648 -227.696522) (xy 333.599028 -227.696522) (xy 333.552038 -227.848922)
			(xy 333.552038 -227.893372) (xy 333.907638 -227.893372)
		)
		(stroke
			(width 0)
			(type solid)
		)
		(fill yes)
		(layer "In11.Cu")
		(net "M_D_CPU0_SB_DQ<26>")
	)
	(gr_poly
		(pts
			(xy 333.907638 -227.440998) (xy 333.907638 -227.396548) (xy 333.552038 -227.396548) (xy 333.552038 -227.440998)
			(xy 333.599028 -227.593398) (xy 333.860648 -227.593398)
		)
		(stroke
			(width 0)
			(type solid)
		)
		(fill yes)
		(layer "In11.Cu")
		(net "M_D_CPU0_SB_DQ<25>")
	)
	(gr_poly
		(pts
			(xy 333.907638 -226.22129) (xy 333.860648 -226.06889) (xy 333.599028 -226.06889) (xy 333.552038 -226.22129)
			(xy 333.552038 -226.26574) (xy 333.907638 -226.26574)
		)
		(stroke
			(width 0)
			(type solid)
		)
		(fill yes)
		(layer "In11.Cu")
		(net "M_D_CPU0_SB_DQS_DN<3>")
	)
	(gr_poly
		(pts
			(xy 333.907638 -225.813366) (xy 333.907638 -225.768916) (xy 333.552038 -225.768916) (xy 333.552038 -225.813366)
			(xy 333.599028 -225.965766) (xy 333.860648 -225.965766)
		)
		(stroke
			(width 0)
			(type solid)
		)
		(fill yes)
		(layer "In11.Cu")
		(net "M_D_CPU0_SB_DQS_DN<8>")
	)
	(gr_poly
		(pts
			(xy 333.907638 -224.593658) (xy 333.860648 -224.441258) (xy 333.599028 -224.441258) (xy 333.552038 -224.593658)
			(xy 333.552038 -224.637854) (xy 333.907638 -224.637854)
		)
		(stroke
			(width 0)
			(type solid)
		)
		(fill yes)
		(layer "In11.Cu")
		(net "M_D_CPU0_SB_DQ<30>")
	)
	(gr_poly
		(pts
			(xy 333.907638 -224.185226) (xy 333.907638 -224.14103) (xy 333.552038 -224.14103) (xy 333.552038 -224.185226)
			(xy 333.599028 -224.337626) (xy 333.860648 -224.337626)
		)
		(stroke
			(width 0)
			(type solid)
		)
		(fill yes)
		(layer "In11.Cu")
		(net "M_D_CPU0_SB_DQ<29>")
	)
	(gr_poly
		(pts
			(xy 333.913734 -248.601738) (xy 333.913734 -248.557542) (xy 333.558134 -248.557542) (xy 333.558134 -248.601738)
			(xy 333.605124 -248.754138) (xy 333.866744 -248.754138)
		)
		(stroke
			(width 0)
			(type solid)
		)
		(fill yes)
		(layer "In11.Cu")
		(net "M_D_CPU0_SB_CA<4>")
	)
	(gr_poly
		(pts
			(xy 333.913734 -247.382538) (xy 333.866744 -247.230138) (xy 333.605124 -247.230138) (xy 333.558134 -247.382538)
			(xy 333.558134 -247.426988) (xy 333.913734 -247.426988)
		)
		(stroke
			(width 0)
			(type solid)
		)
		(fill yes)
		(layer "In11.Cu")
		(net "M_D_CPU0_SB_CA<6>")
	)
	(gr_poly
		(pts
			(xy 333.913734 -246.974106) (xy 333.913734 -246.929656) (xy 333.558134 -246.929656) (xy 333.558134 -246.974106)
			(xy 333.605124 -247.126506) (xy 333.866744 -247.126506)
		)
		(stroke
			(width 0)
			(type solid)
		)
		(fill yes)
		(layer "In11.Cu")
		(net "M_D_CPU0_SB_CB<4>")
	)
	(gr_poly
		(pts
			(xy 333.913734 -245.754906) (xy 333.866744 -245.602506) (xy 333.605124 -245.602506) (xy 333.558134 -245.754906)
			(xy 333.558134 -245.799356) (xy 333.913734 -245.799356)
		)
		(stroke
			(width 0)
			(type solid)
		)
		(fill yes)
		(layer "In11.Cu")
		(net "M_D_CPU0_SB_CB<7>")
	)
	(gr_poly
		(pts
			(xy 333.913734 -238.83493) (xy 333.913734 -238.790734) (xy 333.558134 -238.790734) (xy 333.558134 -238.83493)
			(xy 333.605124 -238.98733) (xy 333.866744 -238.98733)
		)
		(stroke
			(width 0)
			(type solid)
		)
		(fill yes)
		(layer "In11.Cu")
		(net "M_D_CPU0_SB_DQS_DP<0>")
	)
	(gr_poly
		(pts
			(xy 333.913734 -235.988098) (xy 333.866744 -235.835698) (xy 333.605124 -235.835698) (xy 333.558134 -235.988098)
			(xy 333.558134 -236.032548) (xy 333.913734 -236.032548)
		)
		(stroke
			(width 0)
			(type solid)
		)
		(fill yes)
		(layer "In11.Cu")
		(net "M_D_CPU0_SB_DQ<7>")
	)
	(gr_poly
		(pts
			(xy 333.913734 -233.952034) (xy 333.913734 -233.907584) (xy 333.558134 -233.907584) (xy 333.558134 -233.952034)
			(xy 333.605124 -234.104434) (xy 333.866744 -234.104434)
		)
		(stroke
			(width 0)
			(type solid)
		)
		(fill yes)
		(layer "In11.Cu")
		(net "M_D_CPU0_SB_DQ<9>")
	)
	(gr_poly
		(pts
			(xy 333.913734 -231.104694) (xy 333.866744 -230.952294) (xy 333.605124 -230.952294) (xy 333.558134 -231.104694)
			(xy 333.558134 -231.149144) (xy 333.913734 -231.149144)
		)
		(stroke
			(width 0)
			(type solid)
		)
		(fill yes)
		(layer "In11.Cu")
		(net "M_D_CPU0_SB_DQ<14>")
	)
	(gr_poly
		(pts
			(xy 333.922116 -249.01017) (xy 333.875126 -248.85777) (xy 333.613506 -248.85777) (xy 333.566516 -249.01017)
			(xy 333.566516 -249.05462) (xy 333.922116 -249.05462)
		)
		(stroke
			(width 0)
			(type solid)
		)
		(fill yes)
		(layer "In11.Cu")
		(net "M_D_CPU0_SB_CA<3>")
	)
	(gr_poly
		(pts
			(xy 333.922116 -245.346474) (xy 333.922116 -245.302278) (xy 333.566516 -245.302278) (xy 333.566516 -245.346474)
			(xy 333.613506 -245.498874) (xy 333.875126 -245.498874)
		)
		(stroke
			(width 0)
			(type solid)
		)
		(fill yes)
		(layer "In11.Cu")
		(net "M_D_CPU0_SB_DQS_DP<9>")
	)
	(gr_poly
		(pts
			(xy 333.922116 -239.243362) (xy 333.875126 -239.090962) (xy 333.613506 -239.090962) (xy 333.566516 -239.243362)
			(xy 333.566516 -239.287812) (xy 333.922116 -239.287812)
		)
		(stroke
			(width 0)
			(type solid)
		)
		(fill yes)
		(layer "In11.Cu")
		(net "M_D_CPU0_SB_DQ<3>")
	)
	(gr_poly
		(pts
			(xy 333.922116 -234.360466) (xy 333.875126 -234.208066) (xy 333.613506 -234.208066) (xy 333.566516 -234.360466)
			(xy 333.566516 -234.404662) (xy 333.922116 -234.404662)
		)
		(stroke
			(width 0)
			(type solid)
		)
		(fill yes)
		(layer "In11.Cu")
		(net "M_D_CPU0_SB_DQ<10>")
	)
	(gr_poly
		(pts
			(xy 333.922116 -230.696262) (xy 333.922116 -230.652066) (xy 333.566516 -230.652066) (xy 333.566516 -230.696262)
			(xy 333.613506 -230.848662) (xy 333.875126 -230.848662)
		)
		(stroke
			(width 0)
			(type solid)
		)
		(fill yes)
		(layer "In11.Cu")
		(net "M_D_CPU0_SB_DQ<13>")
	)
	(gr_poly
		(pts
			(xy 334.014826 -274.876514) (xy 334.014826 -274.832318) (xy 333.659226 -274.832318) (xy 333.659226 -274.876514)
			(xy 333.706216 -275.028914) (xy 333.967836 -275.028914)
		)
		(stroke
			(width 0)
			(type solid)
		)
		(fill yes)
		(layer "In11.Cu")
		(net "M_D_CPU0_SA_DQ<16>")
	)
	(gr_poly
		(pts
			(xy 334.023462 -272.029682) (xy 333.976472 -271.877282) (xy 333.714852 -271.877282) (xy 333.667862 -272.029682)
			(xy 333.667862 -272.073878) (xy 334.023462 -272.073878)
		)
		(stroke
			(width 0)
			(type solid)
		)
		(fill yes)
		(layer "In11.Cu")
		(net "M_D_CPU0_SA_DQS_DP<7>")
	)
	(gr_poly
		(pts
			(xy 334.023462 -271.620742) (xy 334.023462 -271.576546) (xy 333.667862 -271.576546) (xy 333.667862 -271.620742)
			(xy 333.714852 -271.773142) (xy 333.976472 -271.773142)
		)
		(stroke
			(width 0)
			(type solid)
		)
		(fill yes)
		(layer "In11.Cu")
		(net "M_D_CPU0_SA_DQ<20>")
	)
	(gr_poly
		(pts
			(xy 334.023462 -270.40205) (xy 333.976472 -270.24965) (xy 333.714852 -270.24965) (xy 333.667862 -270.40205)
			(xy 333.667862 -270.446246) (xy 334.023462 -270.446246)
		)
		(stroke
			(width 0)
			(type solid)
		)
		(fill yes)
		(layer "In11.Cu")
		(net "M_D_CPU0_SA_DQ<23>")
	)
	(gr_poly
		(pts
			(xy 334.023462 -268.77391) (xy 333.976472 -268.62151) (xy 333.714852 -268.62151) (xy 333.667862 -268.77391)
			(xy 333.667862 -268.81836) (xy 334.023462 -268.81836)
		)
		(stroke
			(width 0)
			(type solid)
		)
		(fill yes)
		(layer "In11.Cu")
		(net "M_D_CPU0_SA_DQ<27>")
	)
	(gr_poly
		(pts
			(xy 334.023462 -268.365478) (xy 334.023462 -268.321028) (xy 333.667862 -268.321028) (xy 333.667862 -268.365478)
			(xy 333.714852 -268.517878) (xy 333.976472 -268.517878)
		)
		(stroke
			(width 0)
			(type solid)
		)
		(fill yes)
		(layer "In11.Cu")
		(net "M_D_CPU0_SA_DQS_DP<3>")
	)
	(gr_poly
		(pts
			(xy 334.023462 -267.146278) (xy 333.976472 -266.993878) (xy 333.714852 -266.993878) (xy 333.667862 -267.146278)
			(xy 333.667862 -267.190474) (xy 334.023462 -267.190474)
		)
		(stroke
			(width 0)
			(type solid)
		)
		(fill yes)
		(layer "In11.Cu")
		(net "M_D_CPU0_SA_DQS_DP<8>")
	)
	(gr_poly
		(pts
			(xy 334.023462 -266.737846) (xy 334.023462 -266.693396) (xy 333.667862 -266.693396) (xy 333.667862 -266.737846)
			(xy 333.714852 -266.890246) (xy 333.976472 -266.890246)
		)
		(stroke
			(width 0)
			(type solid)
		)
		(fill yes)
		(layer "In11.Cu")
		(net "M_D_CPU0_SA_DQ<28>")
	)
	(gr_poly
		(pts
			(xy 334.023462 -265.518646) (xy 333.976472 -265.366246) (xy 333.714852 -265.366246) (xy 333.667862 -265.518646)
			(xy 333.667862 -265.562842) (xy 334.023462 -265.562842)
		)
		(stroke
			(width 0)
			(type solid)
		)
		(fill yes)
		(layer "In11.Cu")
		(net "M_D_CPU0_SA_DQ<31>")
	)
	(gr_poly
		(pts
			(xy 334.023462 -265.109706) (xy 334.023462 -265.06551) (xy 333.667862 -265.06551) (xy 333.667862 -265.109706)
			(xy 333.714852 -265.262106) (xy 333.976472 -265.262106)
		)
		(stroke
			(width 0)
			(type solid)
		)
		(fill yes)
		(layer "In11.Cu")
		(net "M_D_CPU0_SA_CB<0>")
	)
	(gr_poly
		(pts
			(xy 334.023462 -263.891014) (xy 333.976472 -263.738614) (xy 333.714852 -263.738614) (xy 333.667862 -263.891014)
			(xy 333.667862 -263.93521) (xy 334.023462 -263.93521)
		)
		(stroke
			(width 0)
			(type solid)
		)
		(fill yes)
		(layer "In11.Cu")
		(net "M_D_CPU0_SA_CB<3>")
	)
	(gr_poly
		(pts
			(xy 334.023462 -263.482074) (xy 334.023462 -263.437878) (xy 333.667862 -263.437878) (xy 333.667862 -263.482074)
			(xy 333.714852 -263.634474) (xy 333.976472 -263.634474)
		)
		(stroke
			(width 0)
			(type solid)
		)
		(fill yes)
		(layer "In11.Cu")
		(net "M_D_CPU0_SA_DQS_DP<4>")
	)
	(gr_poly
		(pts
			(xy 334.023462 -262.262874) (xy 333.976472 -262.110474) (xy 333.714852 -262.110474) (xy 333.667862 -262.262874)
			(xy 333.667862 -262.307324) (xy 334.023462 -262.307324)
		)
		(stroke
			(width 0)
			(type solid)
		)
		(fill yes)
		(layer "In11.Cu")
		(net "M_D_CPU0_SA_DQS_DP<9>")
	)
	(gr_poly
		(pts
			(xy 334.023462 -261.854442) (xy 334.023462 -261.809992) (xy 333.667862 -261.809992) (xy 333.667862 -261.854442)
			(xy 333.714852 -262.006842) (xy 333.976472 -262.006842)
		)
		(stroke
			(width 0)
			(type solid)
		)
		(fill yes)
		(layer "In11.Cu")
		(net "M_D_CPU0_SA_CB<4>")
	)
	(gr_poly
		(pts
			(xy 334.023462 -260.635242) (xy 333.976472 -260.482842) (xy 333.714852 -260.482842) (xy 333.667862 -260.635242)
			(xy 333.667862 -260.679438) (xy 334.023462 -260.679438)
		)
		(stroke
			(width 0)
			(type solid)
		)
		(fill yes)
		(layer "In11.Cu")
		(net "M_D_CPU0_SA_CB<7>")
	)
	(gr_poly
		(pts
			(xy 334.023462 -259.00761) (xy 333.976472 -258.85521) (xy 333.714852 -258.85521) (xy 333.667862 -259.00761)
			(xy 333.667862 -259.051806) (xy 334.023462 -259.051806)
		)
		(stroke
			(width 0)
			(type solid)
		)
		(fill yes)
		(layer "In11.Cu")
		(net "M_D_CPU0_SA_CS_N<0>")
	)
	(gr_poly
		(pts
			(xy 334.023462 -258.59867) (xy 334.023462 -258.554474) (xy 333.667862 -258.554474) (xy 333.667862 -258.59867)
			(xy 333.714852 -258.75107) (xy 333.976472 -258.75107)
		)
		(stroke
			(width 0)
			(type solid)
		)
		(fill yes)
		(layer "In11.Cu")
		(net "M_D_CPU0_SA_CS_N<3>")
	)
	(gr_poly
		(pts
			(xy 334.023462 -257.37947) (xy 333.976472 -257.22707) (xy 333.714852 -257.22707) (xy 333.667862 -257.37947)
			(xy 333.667862 -257.42392) (xy 334.023462 -257.42392)
		)
		(stroke
			(width 0)
			(type solid)
		)
		(fill yes)
		(layer "In11.Cu")
		(net "M_D_CPU0_SA_CA<1>")
	)
	(gr_poly
		(pts
			(xy 334.023462 -256.971038) (xy 334.023462 -256.926588) (xy 333.667862 -256.926588) (xy 333.667862 -256.971038)
			(xy 333.714852 -257.123438) (xy 333.976472 -257.123438)
		)
		(stroke
			(width 0)
			(type solid)
		)
		(fill yes)
		(layer "In11.Cu")
		(net "M_D_CPU0_SA_CA<2>")
	)
	(gr_poly
		(pts
			(xy 334.023462 -255.751838) (xy 333.976472 -255.599438) (xy 333.714852 -255.599438) (xy 333.667862 -255.751838)
			(xy 333.667862 -255.796288) (xy 334.023462 -255.796288)
		)
		(stroke
			(width 0)
			(type solid)
		)
		(fill yes)
		(layer "In11.Cu")
		(net "M_D_CPU0_SA_CA<5>")
	)
	(gr_poly
		(pts
			(xy 334.032098 -273.657314) (xy 333.985108 -273.504914) (xy 333.723488 -273.504914) (xy 333.676498 -273.657314)
			(xy 333.676498 -273.70151) (xy 334.032098 -273.70151)
		)
		(stroke
			(width 0)
			(type solid)
		)
		(fill yes)
		(layer "In11.Cu")
		(net "M_D_CPU0_SA_DQ<19>")
	)
	(gr_poly
		(pts
			(xy 334.032098 -273.248882) (xy 334.032098 -273.204686) (xy 333.676498 -273.204686) (xy 333.676498 -273.248882)
			(xy 333.723488 -273.401282) (xy 333.985108 -273.401282)
		)
		(stroke
			(width 0)
			(type solid)
		)
		(fill yes)
		(layer "In11.Cu")
		(net "M_D_CPU0_SA_DQS_DP<2>")
	)
	(gr_poly
		(pts
			(xy 334.239362 -228.921818) (xy 334.277716 -228.89972) (xy 334.099916 -228.591872) (xy 334.061562 -228.61397)
			(xy 333.953104 -228.73081) (xy 334.083914 -228.957378)
		)
		(stroke
			(width 0)
			(type solid)
		)
		(fill yes)
		(layer "In11.Cu")
		(net "M_D_CPU0_SB_DQ<24>")
	)
	(gr_poly
		(pts
			(xy 334.240124 -240.318036) (xy 334.278478 -240.295938) (xy 334.100678 -239.98809) (xy 334.062324 -240.010188)
			(xy 333.953866 -240.127028) (xy 334.084676 -240.353596)
		)
		(stroke
			(width 0)
			(type solid)
		)
		(fill yes)
		(layer "In11.Cu")
		(net "M_D_CPU0_SB_DQ<1>")
	)
	(gr_poly
		(pts
			(xy 334.240378 -243.574316) (xy 334.278732 -243.552218) (xy 334.100932 -243.24437) (xy 334.062578 -243.266468)
			(xy 333.95412 -243.383308) (xy 334.08493 -243.609876)
		)
		(stroke
			(width 0)
			(type solid)
		)
		(fill yes)
		(layer "In11.Cu")
		(net "M_D_CPU0_SB_CB<0>")
	)
	(gr_poly
		(pts
			(xy 334.348074 -242.949984) (xy 334.456532 -242.833144) (xy 334.325722 -242.606576) (xy 334.170274 -242.642136)
			(xy 334.13192 -242.664234) (xy 334.30972 -242.972082)
		)
		(stroke
			(width 0)
			(type solid)
		)
		(fill yes)
		(layer "In11.Cu")
		(net "M_D_CPU0_SB_CB<2>")
	)
	(gr_poly
		(pts
			(xy 334.348074 -228.300026) (xy 334.456532 -228.183186) (xy 334.325722 -227.956618) (xy 334.170274 -227.992178)
			(xy 334.13192 -228.014276) (xy 334.30972 -228.322124)
		)
		(stroke
			(width 0)
			(type solid)
		)
		(fill yes)
		(layer "In11.Cu")
		(net "M_D_CPU0_SB_DQ<26>")
	)
	(gr_poly
		(pts
			(xy 334.348836 -239.695736) (xy 334.457294 -239.578896) (xy 334.326484 -239.352328) (xy 334.171036 -239.387888)
			(xy 334.132682 -239.409986) (xy 334.310482 -239.717834)
		)
		(stroke
			(width 0)
			(type solid)
		)
		(fill yes)
		(layer "In11.Cu")
		(net "M_D_CPU0_SB_DQ<3>")
	)
	(gr_poly
		(pts
			(xy 334.374998 -249.416062) (xy 334.374998 -249.371612) (xy 334.019398 -249.371612) (xy 334.019398 -249.416062)
			(xy 334.066388 -249.568462) (xy 334.328008 -249.568462)
		)
		(stroke
			(width 0)
			(type solid)
		)
		(fill yes)
		(layer "In11.Cu")
		(net "M_D_CPU0_SB_CA<2>")
	)
	(gr_poly
		(pts
			(xy 334.374998 -244.940582) (xy 334.328008 -244.788182) (xy 334.066388 -244.788182) (xy 334.019398 -244.940582)
			(xy 334.019398 -244.985032) (xy 334.374998 -244.985032)
		)
		(stroke
			(width 0)
			(type solid)
		)
		(fill yes)
		(layer "In11.Cu")
		(net "M_D_CPU0_SB_DQS_DN<9>")
	)
	(gr_poly
		(pts
			(xy 334.374998 -234.76585) (xy 334.374998 -234.721654) (xy 334.019398 -234.721654) (xy 334.019398 -234.76585)
			(xy 334.066388 -234.91825) (xy 334.328008 -234.91825)
		)
		(stroke
			(width 0)
			(type solid)
		)
		(fill yes)
		(layer "In11.Cu")
		(net "M_D_CPU0_SB_DQ<8>")
	)
	(gr_poly
		(pts
			(xy 334.374998 -230.290878) (xy 334.328008 -230.138478) (xy 334.066388 -230.138478) (xy 334.019398 -230.290878)
			(xy 334.019398 -230.335074) (xy 334.374998 -230.335074)
		)
		(stroke
			(width 0)
			(type solid)
		)
		(fill yes)
		(layer "In11.Cu")
		(net "M_D_CPU0_SB_DQ<15>")
	)
	(gr_poly
		(pts
			(xy 334.377538 -227.035614) (xy 334.330548 -226.883214) (xy 334.068928 -226.883214) (xy 334.021938 -227.035614)
			(xy 334.021938 -227.07981) (xy 334.377538 -227.07981)
		)
		(stroke
			(width 0)
			(type solid)
		)
		(fill yes)
		(layer "In11.Cu")
		(net "M_D_CPU0_SB_DQ<27>")
	)
	(gr_poly
		(pts
			(xy 334.377538 -226.626674) (xy 334.377538 -226.582478) (xy 334.021938 -226.582478) (xy 334.021938 -226.626674)
			(xy 334.068928 -226.779074) (xy 334.330548 -226.779074)
		)
		(stroke
			(width 0)
			(type solid)
		)
		(fill yes)
		(layer "In11.Cu")
		(net "M_D_CPU0_SB_DQS_DP<3>")
	)
	(gr_poly
		(pts
			(xy 334.38338 -244.53215) (xy 334.38338 -244.487954) (xy 334.02778 -244.487954) (xy 334.02778 -244.53215)
			(xy 334.07477 -244.68455) (xy 334.33639 -244.68455)
		)
		(stroke
			(width 0)
			(type solid)
		)
		(fill yes)
		(layer "In11.Cu")
		(net "M_D_CPU0_SB_DQS_DN<4>")
	)
	(gr_poly
		(pts
			(xy 334.383634 -248.196354) (xy 334.336644 -248.043954) (xy 334.075024 -248.043954) (xy 334.028034 -248.196354)
			(xy 334.028034 -248.240804) (xy 334.383634 -248.240804)
		)
		(stroke
			(width 0)
			(type solid)
		)
		(fill yes)
		(layer "In11.Cu")
		(net "M_D_CPU0_SB_CA<5>")
	)
	(gr_poly
		(pts
			(xy 334.383634 -247.787922) (xy 334.383634 -247.743472) (xy 334.028034 -247.743472) (xy 334.028034 -247.787922)
			(xy 334.075024 -247.940322) (xy 334.336644 -247.940322)
		)
		(stroke
			(width 0)
			(type solid)
		)
		(fill yes)
		(layer "In11.Cu")
		(net "M_D_CPU0_SB_PAR")
	)
	(gr_poly
		(pts
			(xy 334.383634 -246.568722) (xy 334.336644 -246.416322) (xy 334.075024 -246.416322) (xy 334.028034 -246.568722)
			(xy 334.028034 -246.613172) (xy 334.383634 -246.613172)
		)
		(stroke
			(width 0)
			(type solid)
		)
		(fill yes)
		(layer "In11.Cu")
		(net "M_D_CPU0_SB_CB<6>")
	)
	(gr_poly
		(pts
			(xy 334.383634 -246.16029) (xy 334.383634 -246.11584) (xy 334.028034 -246.11584) (xy 334.028034 -246.16029)
			(xy 334.075024 -246.31269) (xy 334.336644 -246.31269)
		)
		(stroke
			(width 0)
			(type solid)
		)
		(fill yes)
		(layer "In11.Cu")
		(net "M_D_CPU0_SB_CB<5>")
	)
	(gr_poly
		(pts
			(xy 334.383634 -241.685318) (xy 334.336644 -241.532918) (xy 334.075024 -241.532918) (xy 334.028034 -241.685318)
			(xy 334.028034 -241.729768) (xy 334.383634 -241.729768)
		)
		(stroke
			(width 0)
			(type solid)
		)
		(fill yes)
		(layer "In11.Cu")
		(net "M_D_CPU0_SB_CB<3>")
	)
	(gr_poly
		(pts
			(xy 334.383634 -241.276886) (xy 334.383634 -241.232436) (xy 334.028034 -241.232436) (xy 334.028034 -241.276886)
			(xy 334.075024 -241.429286) (xy 334.336644 -241.429286)
		)
		(stroke
			(width 0)
			(type solid)
		)
		(fill yes)
		(layer "In11.Cu")
		(net "M_D_CPU0_SB_DQ<0>")
	)
	(gr_poly
		(pts
			(xy 334.383634 -238.430054) (xy 334.336644 -238.277654) (xy 334.075024 -238.277654) (xy 334.028034 -238.430054)
			(xy 334.028034 -238.47425) (xy 334.383634 -238.47425)
		)
		(stroke
			(width 0)
			(type solid)
		)
		(fill yes)
		(layer "In11.Cu")
		(net "M_D_CPU0_SB_DQS_DN<0>")
	)
	(gr_poly
		(pts
			(xy 334.383634 -238.021114) (xy 334.383634 -237.976918) (xy 334.028034 -237.976918) (xy 334.028034 -238.021114)
			(xy 334.075024 -238.173514) (xy 334.336644 -238.173514)
		)
		(stroke
			(width 0)
			(type solid)
		)
		(fill yes)
		(layer "In11.Cu")
		(net "M_D_CPU0_SB_DQS_DN<5>")
	)
	(gr_poly
		(pts
			(xy 334.383634 -236.802422) (xy 334.336644 -236.650022) (xy 334.075024 -236.650022) (xy 334.028034 -236.802422)
			(xy 334.028034 -236.846618) (xy 334.383634 -236.846618)
		)
		(stroke
			(width 0)
			(type solid)
		)
		(fill yes)
		(layer "In11.Cu")
		(net "M_D_CPU0_SB_DQ<6>")
	)
	(gr_poly
		(pts
			(xy 334.383634 -236.393482) (xy 334.383634 -236.349286) (xy 334.028034 -236.349286) (xy 334.028034 -236.393482)
			(xy 334.075024 -236.545882) (xy 334.336644 -236.545882)
		)
		(stroke
			(width 0)
			(type solid)
		)
		(fill yes)
		(layer "In11.Cu")
		(net "M_D_CPU0_SB_DQ<5>")
	)
	(gr_poly
		(pts
			(xy 334.383634 -233.54665) (xy 334.336644 -233.39425) (xy 334.075024 -233.39425) (xy 334.028034 -233.54665)
			(xy 334.028034 -233.590846) (xy 334.383634 -233.590846)
		)
		(stroke
			(width 0)
			(type solid)
		)
		(fill yes)
		(layer "In11.Cu")
		(net "M_D_CPU0_SB_DQ<11>")
	)
	(gr_poly
		(pts
			(xy 334.383634 -233.13771) (xy 334.383634 -233.093514) (xy 334.028034 -233.093514) (xy 334.028034 -233.13771)
			(xy 334.075024 -233.29011) (xy 334.336644 -233.29011)
		)
		(stroke
			(width 0)
			(type solid)
		)
		(fill yes)
		(layer "In11.Cu")
		(net "M_D_CPU0_SB_DQS_DP<1>")
	)
	(gr_poly
		(pts
			(xy 334.383634 -231.919018) (xy 334.336644 -231.766618) (xy 334.075024 -231.766618) (xy 334.028034 -231.919018)
			(xy 334.028034 -231.963214) (xy 334.383634 -231.963214)
		)
		(stroke
			(width 0)
			(type solid)
		)
		(fill yes)
		(layer "In11.Cu")
		(net "M_D_CPU0_SB_DQS_DP<6>")
	)
	(gr_poly
		(pts
			(xy 334.383634 -231.510078) (xy 334.383634 -231.465882) (xy 334.028034 -231.465882) (xy 334.028034 -231.510078)
			(xy 334.075024 -231.662478) (xy 334.336644 -231.662478)
		)
		(stroke
			(width 0)
			(type solid)
		)
		(fill yes)
		(layer "In11.Cu")
		(net "M_D_CPU0_SB_DQ<12>")
	)
	(gr_poly
		(pts
			(xy 334.383634 -225.407474) (xy 334.336644 -225.255074) (xy 334.075024 -225.255074) (xy 334.028034 -225.407474)
			(xy 334.028034 -225.451924) (xy 334.383634 -225.451924)
		)
		(stroke
			(width 0)
			(type solid)
		)
		(fill yes)
		(layer "In11.Cu")
		(net "M_D_CPU0_SB_DQS_DP<8>")
	)
	(gr_poly
		(pts
			(xy 334.383634 -224.999042) (xy 334.383634 -224.954592) (xy 334.028034 -224.954592) (xy 334.028034 -224.999042)
			(xy 334.075024 -225.151442) (xy 334.336644 -225.151442)
		)
		(stroke
			(width 0)
			(type solid)
		)
		(fill yes)
		(layer "In11.Cu")
		(net "M_D_CPU0_SB_DQ<28>")
	)
	(gr_poly
		(pts
			(xy 334.383634 -223.779842) (xy 334.336644 -223.627442) (xy 334.075024 -223.627442) (xy 334.028034 -223.779842)
			(xy 334.028034 -223.824292) (xy 334.383634 -223.824292)
		)
		(stroke
			(width 0)
			(type solid)
		)
		(fill yes)
		(layer "In11.Cu")
		(net "M_D_CPU0_SB_DQ<31>")
	)
	(gr_poly
		(pts
			(xy 334.48498 -274.062698) (xy 334.48498 -274.018502) (xy 334.12938 -274.018502) (xy 334.12938 -274.062698)
			(xy 334.17637 -274.215098) (xy 334.43799 -274.215098)
		)
		(stroke
			(width 0)
			(type solid)
		)
		(fill yes)
		(layer "In11.Cu")
		(net "M_D_CPU0_SA_DQ<17>")
	)
	(gr_poly
		(pts
			(xy 334.48752 -272.843498) (xy 334.44053 -272.691098) (xy 334.17891 -272.691098) (xy 334.13192 -272.843498)
			(xy 334.13192 -272.887694) (xy 334.48752 -272.887694)
		)
		(stroke
			(width 0)
			(type solid)
		)
		(fill yes)
		(layer "In11.Cu")
		(net "M_D_CPU0_SA_DQS_DN<2>")
	)
	(gr_poly
		(pts
			(xy 334.493362 -271.215866) (xy 334.446372 -271.063466) (xy 334.184752 -271.063466) (xy 334.137762 -271.215866)
			(xy 334.137762 -271.260062) (xy 334.493362 -271.260062)
		)
		(stroke
			(width 0)
			(type solid)
		)
		(fill yes)
		(layer "In11.Cu")
		(net "M_D_CPU0_SA_DQ<22>")
	)
	(gr_poly
		(pts
			(xy 334.493362 -270.806926) (xy 334.493362 -270.76273) (xy 334.137762 -270.76273) (xy 334.137762 -270.806926)
			(xy 334.184752 -270.959326) (xy 334.446372 -270.959326)
		)
		(stroke
			(width 0)
			(type solid)
		)
		(fill yes)
		(layer "In11.Cu")
		(net "M_D_CPU0_SA_DQ<21>")
	)
	(gr_poly
		(pts
			(xy 334.493362 -269.587726) (xy 334.446372 -269.435326) (xy 334.184752 -269.435326) (xy 334.137762 -269.587726)
			(xy 334.137762 -269.632176) (xy 334.493362 -269.632176)
		)
		(stroke
			(width 0)
			(type solid)
		)
		(fill yes)
		(layer "In11.Cu")
		(net "M_D_CPU0_SA_DQ<26>")
	)
	(gr_poly
		(pts
			(xy 334.493362 -269.179294) (xy 334.493362 -269.134844) (xy 334.137762 -269.134844) (xy 334.137762 -269.179294)
			(xy 334.184752 -269.331694) (xy 334.446372 -269.331694)
		)
		(stroke
			(width 0)
			(type solid)
		)
		(fill yes)
		(layer "In11.Cu")
		(net "M_D_CPU0_SA_DQ<25>")
	)
	(gr_poly
		(pts
			(xy 334.493362 -267.960094) (xy 334.446372 -267.807694) (xy 334.184752 -267.807694) (xy 334.137762 -267.960094)
			(xy 334.137762 -268.004544) (xy 334.493362 -268.004544)
		)
		(stroke
			(width 0)
			(type solid)
		)
		(fill yes)
		(layer "In11.Cu")
		(net "M_D_CPU0_SA_DQS_DN<3>")
	)
	(gr_poly
		(pts
			(xy 334.493362 -267.551662) (xy 334.493362 -267.507212) (xy 334.137762 -267.507212) (xy 334.137762 -267.551662)
			(xy 334.184752 -267.704062) (xy 334.446372 -267.704062)
		)
		(stroke
			(width 0)
			(type solid)
		)
		(fill yes)
		(layer "In11.Cu")
		(net "M_D_CPU0_SA_DQS_DN<8>")
	)
	(gr_poly
		(pts
			(xy 334.493362 -266.332462) (xy 334.446372 -266.180062) (xy 334.184752 -266.180062) (xy 334.137762 -266.332462)
			(xy 334.137762 -266.376658) (xy 334.493362 -266.376658)
		)
		(stroke
			(width 0)
			(type solid)
		)
		(fill yes)
		(layer "In11.Cu")
		(net "M_D_CPU0_SA_DQ<30>")
	)
	(gr_poly
		(pts
			(xy 334.493362 -265.92403) (xy 334.493362 -265.87958) (xy 334.137762 -265.87958) (xy 334.137762 -265.92403)
			(xy 334.184752 -266.07643) (xy 334.446372 -266.07643)
		)
		(stroke
			(width 0)
			(type solid)
		)
		(fill yes)
		(layer "In11.Cu")
		(net "M_D_CPU0_SA_DQ<29>")
	)
	(gr_poly
		(pts
			(xy 334.493362 -264.70483) (xy 334.446372 -264.55243) (xy 334.184752 -264.55243) (xy 334.137762 -264.70483)
			(xy 334.137762 -264.749026) (xy 334.493362 -264.749026)
		)
		(stroke
			(width 0)
			(type solid)
		)
		(fill yes)
		(layer "In11.Cu")
		(net "M_D_CPU0_SA_CB<2>")
	)
	(gr_poly
		(pts
			(xy 334.493362 -264.29589) (xy 334.493362 -264.251694) (xy 334.137762 -264.251694) (xy 334.137762 -264.29589)
			(xy 334.184752 -264.44829) (xy 334.446372 -264.44829)
		)
		(stroke
			(width 0)
			(type solid)
		)
		(fill yes)
		(layer "In11.Cu")
		(net "M_D_CPU0_SA_CB<1>")
	)
	(gr_poly
		(pts
			(xy 334.493362 -263.07669) (xy 334.446372 -262.92429) (xy 334.184752 -262.92429) (xy 334.137762 -263.07669)
			(xy 334.137762 -263.12114) (xy 334.493362 -263.12114)
		)
		(stroke
			(width 0)
			(type solid)
		)
		(fill yes)
		(layer "In11.Cu")
		(net "M_D_CPU0_SA_DQS_DN<4>")
	)
	(gr_poly
		(pts
			(xy 334.493362 -262.668258) (xy 334.493362 -262.623808) (xy 334.137762 -262.623808) (xy 334.137762 -262.668258)
			(xy 334.184752 -262.820658) (xy 334.446372 -262.820658)
		)
		(stroke
			(width 0)
			(type solid)
		)
		(fill yes)
		(layer "In11.Cu")
		(net "M_D_CPU0_SA_DQS_DN<9>")
	)
	(gr_poly
		(pts
			(xy 334.493362 -261.449058) (xy 334.446372 -261.296658) (xy 334.184752 -261.296658) (xy 334.137762 -261.449058)
			(xy 334.137762 -261.493508) (xy 334.493362 -261.493508)
		)
		(stroke
			(width 0)
			(type solid)
		)
		(fill yes)
		(layer "In11.Cu")
		(net "M_D_CPU0_SA_CB<6>")
	)
	(gr_poly
		(pts
			(xy 334.493362 -261.040626) (xy 334.493362 -260.996176) (xy 334.137762 -260.996176) (xy 334.137762 -261.040626)
			(xy 334.184752 -261.193026) (xy 334.446372 -261.193026)
		)
		(stroke
			(width 0)
			(type solid)
		)
		(fill yes)
		(layer "In11.Cu")
		(net "M_D_CPU0_SA_CB<5>")
	)
	(gr_poly
		(pts
			(xy 334.493362 -259.412486) (xy 334.493362 -259.36829) (xy 334.137762 -259.36829) (xy 334.137762 -259.412486)
			(xy 334.184752 -259.564886) (xy 334.446372 -259.564886)
		)
		(stroke
			(width 0)
			(type solid)
		)
		(fill yes)
		(layer "In11.Cu")
		(net "M_D_CPU0_SA_CS_N<2>")
	)
	(gr_poly
		(pts
			(xy 334.493362 -258.193286) (xy 334.446372 -258.040886) (xy 334.184752 -258.040886) (xy 334.137762 -258.193286)
			(xy 334.137762 -258.237736) (xy 334.493362 -258.237736)
		)
		(stroke
			(width 0)
			(type solid)
		)
		(fill yes)
		(layer "In11.Cu")
		(net "M_D_CPU0_SA_CS_N<1>")
	)
	(gr_poly
		(pts
			(xy 334.493362 -257.784854) (xy 334.493362 -257.740404) (xy 334.137762 -257.740404) (xy 334.137762 -257.784854)
			(xy 334.184752 -257.937254) (xy 334.446372 -257.937254)
		)
		(stroke
			(width 0)
			(type solid)
		)
		(fill yes)
		(layer "In11.Cu")
		(net "M_D_CPU0_SA_CA<0>")
	)
	(gr_poly
		(pts
			(xy 334.493362 -256.565654) (xy 334.446372 -256.413254) (xy 334.184752 -256.413254) (xy 334.137762 -256.565654)
			(xy 334.137762 -256.610104) (xy 334.493362 -256.610104)
		)
		(stroke
			(width 0)
			(type solid)
		)
		(fill yes)
		(layer "In11.Cu")
		(net "M_D_CPU0_SA_CA<3>")
	)
	(gr_poly
		(pts
			(xy 334.493362 -256.157222) (xy 334.493362 -256.112772) (xy 334.137762 -256.112772) (xy 334.137762 -256.157222)
			(xy 334.184752 -256.309622) (xy 334.446372 -256.309622)
		)
		(stroke
			(width 0)
			(type solid)
		)
		(fill yes)
		(layer "In11.Cu")
		(net "M_D_CPU0_SA_CA<4>")
	)
	(gr_poly
		(pts
			(xy 334.499458 -272.435066) (xy 334.499458 -272.39087) (xy 334.143858 -272.39087) (xy 334.143858 -272.435066)
			(xy 334.190848 -272.587466) (xy 334.452468 -272.587466)
		)
		(stroke
			(width 0)
			(type solid)
		)
		(fill yes)
		(layer "In11.Cu")
		(net "M_D_CPU0_SA_DQS_DN<7>")
	)
	(gr_poly
		(pts
			(xy 334.501744 -274.47113) (xy 334.454754 -274.31873) (xy 334.193134 -274.31873) (xy 334.146144 -274.47113)
			(xy 334.146144 -274.515326) (xy 334.501744 -274.515326)
		)
		(stroke
			(width 0)
			(type solid)
		)
		(fill yes)
		(layer "In11.Cu")
		(net "M_D_CPU0_SA_DQ<18>")
	)
	(gr_poly
		(pts
			(xy 334.709008 -229.735634) (xy 334.747362 -229.713536) (xy 334.569562 -229.405688) (xy 334.531208 -229.427786)
			(xy 334.42275 -229.544626) (xy 334.55356 -229.771194)
		)
		(stroke
			(width 0)
			(type solid)
		)
		(fill yes)
		(layer "In11.Cu")
		(net "M_D_CPU0_SB_DQ<24>")
	)
	(gr_poly
		(pts
			(xy 334.709008 -228.107748) (xy 334.747362 -228.08565) (xy 334.569562 -227.777802) (xy 334.531208 -227.7999)
			(xy 334.42275 -227.91674) (xy 334.55356 -228.143308)
		)
		(stroke
			(width 0)
			(type solid)
		)
		(fill yes)
		(layer "In11.Cu")
		(net "M_D_CPU0_SB_DQ<25>")
	)
	(gr_poly
		(pts
			(xy 334.710024 -242.759738) (xy 334.748378 -242.73764) (xy 334.570578 -242.429792) (xy 334.532224 -242.45189)
			(xy 334.423766 -242.56873) (xy 334.554576 -242.795298)
		)
		(stroke
			(width 0)
			(type solid)
		)
		(fill yes)
		(layer "In11.Cu")
		(net "M_D_CPU0_SB_CB<1>")
	)
	(gr_poly
		(pts
			(xy 334.710278 -239.504728) (xy 334.748632 -239.48263) (xy 334.570832 -239.174782) (xy 334.532478 -239.19688)
			(xy 334.42402 -239.31372) (xy 334.55483 -239.540288)
		)
		(stroke
			(width 0)
			(type solid)
		)
		(fill yes)
		(layer "In11.Cu")
		(net "M_D_CPU0_SB_DQS_DP<0>")
	)
	(gr_poly
		(pts
			(xy 334.820006 -242.139978) (xy 334.928464 -242.023138) (xy 334.797654 -241.79657) (xy 334.642206 -241.83213)
			(xy 334.603852 -241.854228) (xy 334.781652 -242.162076)
		)
		(stroke
			(width 0)
			(type solid)
		)
		(fill yes)
		(layer "In11.Cu")
		(net "M_D_CPU0_SB_CB<3>")
	)
	(gr_poly
		(pts
			(xy 334.820006 -238.88446) (xy 334.928464 -238.76762) (xy 334.797654 -238.541052) (xy 334.642206 -238.576612)
			(xy 334.603852 -238.59871) (xy 334.781652 -238.906558)
		)
		(stroke
			(width 0)
			(type solid)
		)
		(fill yes)
		(layer "In11.Cu")
		(net "M_D_CPU0_SB_DQS_DN<0>")
	)
	(gr_poly
		(pts
			(xy 334.820006 -229.117906) (xy 334.928464 -229.001066) (xy 334.797654 -228.774498) (xy 334.642206 -228.810058)
			(xy 334.603852 -228.832156) (xy 334.781652 -229.140004)
		)
		(stroke
			(width 0)
			(type solid)
		)
		(fill yes)
		(layer "In11.Cu")
		(net "M_D_CPU0_SB_DQ<26>")
	)
	(gr_poly
		(pts
			(xy 334.824324 -227.497132) (xy 334.932782 -227.380292) (xy 334.801972 -227.153724) (xy 334.646524 -227.189284)
			(xy 334.60817 -227.211382) (xy 334.78597 -227.51923)
		)
		(stroke
			(width 0)
			(type solid)
		)
		(fill yes)
		(layer "In11.Cu")
		(net "M_D_CPU0_SB_DQ<27>")
	)
	(gr_poly
		(pts
			(xy 334.844898 -243.718842) (xy 334.844898 -243.674392) (xy 334.489298 -243.674392) (xy 334.489298 -243.718842)
			(xy 334.536288 -243.871242) (xy 334.797908 -243.871242)
		)
		(stroke
			(width 0)
			(type solid)
		)
		(fill yes)
		(layer "In11.Cu")
		(net "M_D_CPU0_SB_CB<0>")
	)
	(gr_poly
		(pts
			(xy 334.847438 -237.616238) (xy 334.800448 -237.463838) (xy 334.538828 -237.463838) (xy 334.491838 -237.616238)
			(xy 334.491838 -237.660434) (xy 334.847438 -237.660434)
		)
		(stroke
			(width 0)
			(type solid)
		)
		(fill yes)
		(layer "In11.Cu")
		(net "M_D_CPU0_SB_DQS_DP<5>")
	)
	(gr_poly
		(pts
			(xy 334.847438 -237.207298) (xy 334.847438 -237.163102) (xy 334.491838 -237.163102) (xy 334.491838 -237.207298)
			(xy 334.538828 -237.359698) (xy 334.800448 -237.359698)
		)
		(stroke
			(width 0)
			(type solid)
		)
		(fill yes)
		(layer "In11.Cu")
		(net "M_D_CPU0_SB_DQ<4>")
	)
	(gr_poly
		(pts
			(xy 334.847438 -225.812858) (xy 334.847438 -225.768662) (xy 334.491838 -225.768662) (xy 334.491838 -225.812858)
			(xy 334.538828 -225.965258) (xy 334.800448 -225.965258)
		)
		(stroke
			(width 0)
			(type solid)
		)
		(fill yes)
		(layer "In11.Cu")
		(net "M_D_CPU0_SB_DQS_DN<8>")
	)
	(gr_poly
		(pts
			(xy 334.85328 -244.127274) (xy 334.80629 -243.974874) (xy 334.54467 -243.974874) (xy 334.49768 -244.127274)
			(xy 334.49768 -244.17147) (xy 334.85328 -244.17147)
		)
		(stroke
			(width 0)
			(type solid)
		)
		(fill yes)
		(layer "In11.Cu")
		(net "M_D_CPU0_SB_DQS_DP<4>")
	)
	(gr_poly
		(pts
			(xy 334.853534 -248.601738) (xy 334.853534 -248.557542) (xy 334.497934 -248.557542) (xy 334.497934 -248.601738)
			(xy 334.544924 -248.754138) (xy 334.806544 -248.754138)
		)
		(stroke
			(width 0)
			(type solid)
		)
		(fill yes)
		(layer "In11.Cu")
		(net "M_D_CPU0_SB_CA<4>")
	)
	(gr_poly
		(pts
			(xy 334.853534 -247.382538) (xy 334.806544 -247.230138) (xy 334.544924 -247.230138) (xy 334.497934 -247.382538)
			(xy 334.497934 -247.426988) (xy 334.853534 -247.426988)
		)
		(stroke
			(width 0)
			(type solid)
		)
		(fill yes)
		(layer "In11.Cu")
		(net "M_D_CPU0_SB_CA<6>")
	)
	(gr_poly
		(pts
			(xy 334.853534 -246.974106) (xy 334.853534 -246.929656) (xy 334.497934 -246.929656) (xy 334.497934 -246.974106)
			(xy 334.544924 -247.126506) (xy 334.806544 -247.126506)
		)
		(stroke
			(width 0)
			(type solid)
		)
		(fill yes)
		(layer "In11.Cu")
		(net "M_D_CPU0_SB_CB<4>")
	)
	(gr_poly
		(pts
			(xy 334.853534 -245.754906) (xy 334.806544 -245.602506) (xy 334.544924 -245.602506) (xy 334.497934 -245.754906)
			(xy 334.497934 -245.799356) (xy 334.853534 -245.799356)
		)
		(stroke
			(width 0)
			(type solid)
		)
		(fill yes)
		(layer "In11.Cu")
		(net "M_D_CPU0_SB_CB<7>")
	)
	(gr_poly
		(pts
			(xy 334.853534 -240.871502) (xy 334.806544 -240.719102) (xy 334.544924 -240.719102) (xy 334.497934 -240.871502)
			(xy 334.497934 -240.915952) (xy 334.853534 -240.915952)
		)
		(stroke
			(width 0)
			(type solid)
		)
		(fill yes)
		(layer "In11.Cu")
		(net "M_D_CPU0_SB_DQ<2>")
	)
	(gr_poly
		(pts
			(xy 334.853534 -235.988098) (xy 334.806544 -235.835698) (xy 334.544924 -235.835698) (xy 334.497934 -235.988098)
			(xy 334.497934 -236.032548) (xy 334.853534 -236.032548)
		)
		(stroke
			(width 0)
			(type solid)
		)
		(fill yes)
		(layer "In11.Cu")
		(net "M_D_CPU0_SB_DQ<7>")
	)
	(gr_poly
		(pts
			(xy 334.853534 -233.952034) (xy 334.853534 -233.907584) (xy 334.497934 -233.907584) (xy 334.497934 -233.952034)
			(xy 334.544924 -234.104434) (xy 334.806544 -234.104434)
		)
		(stroke
			(width 0)
			(type solid)
		)
		(fill yes)
		(layer "In11.Cu")
		(net "M_D_CPU0_SB_DQ<9>")
	)
	(gr_poly
		(pts
			(xy 334.853534 -232.732834) (xy 334.806544 -232.580434) (xy 334.544924 -232.580434) (xy 334.497934 -232.732834)
			(xy 334.497934 -232.77703) (xy 334.853534 -232.77703)
		)
		(stroke
			(width 0)
			(type solid)
		)
		(fill yes)
		(layer "In11.Cu")
		(net "M_D_CPU0_SB_DQS_DN<1>")
	)
	(gr_poly
		(pts
			(xy 334.853534 -232.323894) (xy 334.853534 -232.279698) (xy 334.497934 -232.279698) (xy 334.497934 -232.323894)
			(xy 334.544924 -232.476294) (xy 334.806544 -232.476294)
		)
		(stroke
			(width 0)
			(type solid)
		)
		(fill yes)
		(layer "In11.Cu")
		(net "M_D_CPU0_SB_DQS_DN<6>")
	)
	(gr_poly
		(pts
			(xy 334.853534 -231.104694) (xy 334.806544 -230.952294) (xy 334.544924 -230.952294) (xy 334.497934 -231.104694)
			(xy 334.497934 -231.149144) (xy 334.853534 -231.149144)
		)
		(stroke
			(width 0)
			(type solid)
		)
		(fill yes)
		(layer "In11.Cu")
		(net "M_D_CPU0_SB_DQ<14>")
	)
	(gr_poly
		(pts
			(xy 334.853534 -224.593658) (xy 334.806544 -224.441258) (xy 334.544924 -224.441258) (xy 334.497934 -224.593658)
			(xy 334.497934 -224.638108) (xy 334.853534 -224.638108)
		)
		(stroke
			(width 0)
			(type solid)
		)
		(fill yes)
		(layer "In11.Cu")
		(net "M_D_CPU0_SB_DQ<30>")
	)
	(gr_poly
		(pts
			(xy 334.853534 -224.185226) (xy 334.853534 -224.140776) (xy 334.497934 -224.140776) (xy 334.497934 -224.185226)
			(xy 334.544924 -224.337626) (xy 334.806544 -224.337626)
		)
		(stroke
			(width 0)
			(type solid)
		)
		(fill yes)
		(layer "In11.Cu")
		(net "M_D_CPU0_SB_DQ<29>")
	)
	(gr_poly
		(pts
			(xy 334.859376 -226.221798) (xy 334.812386 -226.069398) (xy 334.550766 -226.069398) (xy 334.503776 -226.221798)
			(xy 334.503776 -226.265994) (xy 334.859376 -226.265994)
		)
		(stroke
			(width 0)
			(type solid)
		)
		(fill yes)
		(layer "In11.Cu")
		(net "M_D_CPU0_SB_DQS_DN<3>")
	)
	(gr_poly
		(pts
			(xy 334.861916 -249.01017) (xy 334.814926 -248.85777) (xy 334.553306 -248.85777) (xy 334.506316 -249.01017)
			(xy 334.506316 -249.05462) (xy 334.861916 -249.05462)
		)
		(stroke
			(width 0)
			(type solid)
		)
		(fill yes)
		(layer "In11.Cu")
		(net "M_D_CPU0_SB_CA<3>")
	)
	(gr_poly
		(pts
			(xy 334.861916 -245.346474) (xy 334.861916 -245.302278) (xy 334.506316 -245.302278) (xy 334.506316 -245.346474)
			(xy 334.553306 -245.498874) (xy 334.814926 -245.498874)
		)
		(stroke
			(width 0)
			(type solid)
		)
		(fill yes)
		(layer "In11.Cu")
		(net "M_D_CPU0_SB_DQS_DP<9>")
	)
	(gr_poly
		(pts
			(xy 334.861916 -240.46307) (xy 334.861916 -240.418874) (xy 334.506316 -240.418874) (xy 334.506316 -240.46307)
			(xy 334.553306 -240.61547) (xy 334.814926 -240.61547)
		)
		(stroke
			(width 0)
			(type solid)
		)
		(fill yes)
		(layer "In11.Cu")
		(net "M_D_CPU0_SB_DQ<1>")
	)
	(gr_poly
		(pts
			(xy 334.861916 -234.360466) (xy 334.814926 -234.208066) (xy 334.553306 -234.208066) (xy 334.506316 -234.360466)
			(xy 334.506316 -234.404662) (xy 334.861916 -234.404662)
		)
		(stroke
			(width 0)
			(type solid)
		)
		(fill yes)
		(layer "In11.Cu")
		(net "M_D_CPU0_SB_DQ<10>")
	)
	(gr_poly
		(pts
			(xy 334.861916 -230.696262) (xy 334.861916 -230.652066) (xy 334.506316 -230.652066) (xy 334.506316 -230.696262)
			(xy 334.553306 -230.848662) (xy 334.814926 -230.848662)
		)
		(stroke
			(width 0)
			(type solid)
		)
		(fill yes)
		(layer "In11.Cu")
		(net "M_D_CPU0_SB_DQ<13>")
	)
	(gr_poly
		(pts
			(xy 334.954626 -274.876514) (xy 334.954626 -274.832318) (xy 334.599026 -274.832318) (xy 334.599026 -274.876514)
			(xy 334.646016 -275.028914) (xy 334.907636 -275.028914)
		)
		(stroke
			(width 0)
			(type solid)
		)
		(fill yes)
		(layer "In11.Cu")
		(net "M_D_CPU0_SA_DQ<16>")
	)
	(gr_poly
		(pts
			(xy 334.95488 -272.029174) (xy 334.90789 -271.876774) (xy 334.64627 -271.876774) (xy 334.59928 -272.029174)
			(xy 334.59928 -272.073624) (xy 334.95488 -272.073624)
		)
		(stroke
			(width 0)
			(type solid)
		)
		(fill yes)
		(layer "In11.Cu")
		(net "M_D_CPU0_SA_DQS_DP<7>")
	)
	(gr_poly
		(pts
			(xy 334.95742 -273.248882) (xy 334.95742 -273.204432) (xy 334.60182 -273.204432) (xy 334.60182 -273.248882)
			(xy 334.64881 -273.401282) (xy 334.91043 -273.401282)
		)
		(stroke
			(width 0)
			(type solid)
		)
		(fill yes)
		(layer "In11.Cu")
		(net "M_D_CPU0_SA_DQS_DP<2>")
	)
	(gr_poly
		(pts
			(xy 334.963262 -271.620742) (xy 334.963262 -271.576546) (xy 334.607662 -271.576546) (xy 334.607662 -271.620742)
			(xy 334.654652 -271.773142) (xy 334.916272 -271.773142)
		)
		(stroke
			(width 0)
			(type solid)
		)
		(fill yes)
		(layer "In11.Cu")
		(net "M_D_CPU0_SA_DQ<20>")
	)
	(gr_poly
		(pts
			(xy 334.963262 -270.40205) (xy 334.916272 -270.24965) (xy 334.654652 -270.24965) (xy 334.607662 -270.40205)
			(xy 334.607662 -270.446246) (xy 334.963262 -270.446246)
		)
		(stroke
			(width 0)
			(type solid)
		)
		(fill yes)
		(layer "In11.Cu")
		(net "M_D_CPU0_SA_DQ<23>")
	)
	(gr_poly
		(pts
			(xy 334.963262 -269.99311) (xy 334.963262 -269.948914) (xy 334.607662 -269.948914) (xy 334.607662 -269.99311)
			(xy 334.654652 -270.14551) (xy 334.916272 -270.14551)
		)
		(stroke
			(width 0)
			(type solid)
		)
		(fill yes)
		(layer "In11.Cu")
		(net "M_D_CPU0_SA_DQ<24>")
	)
	(gr_poly
		(pts
			(xy 334.963262 -268.77391) (xy 334.916272 -268.62151) (xy 334.654652 -268.62151) (xy 334.607662 -268.77391)
			(xy 334.607662 -268.81836) (xy 334.963262 -268.81836)
		)
		(stroke
			(width 0)
			(type solid)
		)
		(fill yes)
		(layer "In11.Cu")
		(net "M_D_CPU0_SA_DQ<27>")
	)
	(gr_poly
		(pts
			(xy 334.963262 -268.365478) (xy 334.963262 -268.321028) (xy 334.607662 -268.321028) (xy 334.607662 -268.365478)
			(xy 334.654652 -268.517878) (xy 334.916272 -268.517878)
		)
		(stroke
			(width 0)
			(type solid)
		)
		(fill yes)
		(layer "In11.Cu")
		(net "M_D_CPU0_SA_DQS_DP<3>")
	)
	(gr_poly
		(pts
			(xy 334.963262 -267.146278) (xy 334.916272 -266.993878) (xy 334.654652 -266.993878) (xy 334.607662 -267.146278)
			(xy 334.607662 -267.190474) (xy 334.963262 -267.190474)
		)
		(stroke
			(width 0)
			(type solid)
		)
		(fill yes)
		(layer "In11.Cu")
		(net "M_D_CPU0_SA_DQS_DP<8>")
	)
	(gr_poly
		(pts
			(xy 334.963262 -266.737846) (xy 334.963262 -266.693396) (xy 334.607662 -266.693396) (xy 334.607662 -266.737846)
			(xy 334.654652 -266.890246) (xy 334.916272 -266.890246)
		)
		(stroke
			(width 0)
			(type solid)
		)
		(fill yes)
		(layer "In11.Cu")
		(net "M_D_CPU0_SA_DQ<28>")
	)
	(gr_poly
		(pts
			(xy 334.963262 -265.518646) (xy 334.916272 -265.366246) (xy 334.654652 -265.366246) (xy 334.607662 -265.518646)
			(xy 334.607662 -265.562842) (xy 334.963262 -265.562842)
		)
		(stroke
			(width 0)
			(type solid)
		)
		(fill yes)
		(layer "In11.Cu")
		(net "M_D_CPU0_SA_DQ<31>")
	)
	(gr_poly
		(pts
			(xy 334.963262 -265.109706) (xy 334.963262 -265.06551) (xy 334.607662 -265.06551) (xy 334.607662 -265.109706)
			(xy 334.654652 -265.262106) (xy 334.916272 -265.262106)
		)
		(stroke
			(width 0)
			(type solid)
		)
		(fill yes)
		(layer "In11.Cu")
		(net "M_D_CPU0_SA_CB<0>")
	)
	(gr_poly
		(pts
			(xy 334.963262 -263.891014) (xy 334.916272 -263.738614) (xy 334.654652 -263.738614) (xy 334.607662 -263.891014)
			(xy 334.607662 -263.93521) (xy 334.963262 -263.93521)
		)
		(stroke
			(width 0)
			(type solid)
		)
		(fill yes)
		(layer "In11.Cu")
		(net "M_D_CPU0_SA_CB<3>")
	)
	(gr_poly
		(pts
			(xy 334.963262 -263.482074) (xy 334.963262 -263.437878) (xy 334.607662 -263.437878) (xy 334.607662 -263.482074)
			(xy 334.654652 -263.634474) (xy 334.916272 -263.634474)
		)
		(stroke
			(width 0)
			(type solid)
		)
		(fill yes)
		(layer "In11.Cu")
		(net "M_D_CPU0_SA_DQS_DP<4>")
	)
	(gr_poly
		(pts
			(xy 334.963262 -262.262874) (xy 334.916272 -262.110474) (xy 334.654652 -262.110474) (xy 334.607662 -262.262874)
			(xy 334.607662 -262.307324) (xy 334.963262 -262.307324)
		)
		(stroke
			(width 0)
			(type solid)
		)
		(fill yes)
		(layer "In11.Cu")
		(net "M_D_CPU0_SA_DQS_DP<9>")
	)
	(gr_poly
		(pts
			(xy 334.963262 -261.854442) (xy 334.963262 -261.809992) (xy 334.607662 -261.809992) (xy 334.607662 -261.854442)
			(xy 334.654652 -262.006842) (xy 334.916272 -262.006842)
		)
		(stroke
			(width 0)
			(type solid)
		)
		(fill yes)
		(layer "In11.Cu")
		(net "M_D_CPU0_SA_CB<4>")
	)
	(gr_poly
		(pts
			(xy 334.963262 -260.635242) (xy 334.916272 -260.482842) (xy 334.654652 -260.482842) (xy 334.607662 -260.635242)
			(xy 334.607662 -260.679438) (xy 334.963262 -260.679438)
		)
		(stroke
			(width 0)
			(type solid)
		)
		(fill yes)
		(layer "In11.Cu")
		(net "M_D_CPU0_SA_CB<7>")
	)
	(gr_poly
		(pts
			(xy 334.963262 -259.00761) (xy 334.916272 -258.85521) (xy 334.654652 -258.85521) (xy 334.607662 -259.00761)
			(xy 334.607662 -259.051806) (xy 334.963262 -259.051806)
		)
		(stroke
			(width 0)
			(type solid)
		)
		(fill yes)
		(layer "In11.Cu")
		(net "M_D_CPU0_SA_CS_N<0>")
	)
	(gr_poly
		(pts
			(xy 334.963262 -258.59867) (xy 334.963262 -258.554474) (xy 334.607662 -258.554474) (xy 334.607662 -258.59867)
			(xy 334.654652 -258.75107) (xy 334.916272 -258.75107)
		)
		(stroke
			(width 0)
			(type solid)
		)
		(fill yes)
		(layer "In11.Cu")
		(net "M_D_CPU0_SA_CS_N<3>")
	)
	(gr_poly
		(pts
			(xy 334.963262 -257.37947) (xy 334.916272 -257.22707) (xy 334.654652 -257.22707) (xy 334.607662 -257.37947)
			(xy 334.607662 -257.42392) (xy 334.963262 -257.42392)
		)
		(stroke
			(width 0)
			(type solid)
		)
		(fill yes)
		(layer "In11.Cu")
		(net "M_D_CPU0_SA_CA<1>")
	)
	(gr_poly
		(pts
			(xy 334.963262 -256.971038) (xy 334.963262 -256.926588) (xy 334.607662 -256.926588) (xy 334.607662 -256.971038)
			(xy 334.654652 -257.123438) (xy 334.916272 -257.123438)
		)
		(stroke
			(width 0)
			(type solid)
		)
		(fill yes)
		(layer "In11.Cu")
		(net "M_D_CPU0_SA_CA<2>")
	)
	(gr_poly
		(pts
			(xy 334.963262 -255.751838) (xy 334.916272 -255.599438) (xy 334.654652 -255.599438) (xy 334.607662 -255.751838)
			(xy 334.607662 -255.796288) (xy 334.963262 -255.796288)
		)
		(stroke
			(width 0)
			(type solid)
		)
		(fill yes)
		(layer "In11.Cu")
		(net "M_D_CPU0_SA_CA<5>")
	)
	(gr_poly
		(pts
			(xy 334.969358 -273.657314) (xy 334.922368 -273.504914) (xy 334.660748 -273.504914) (xy 334.613758 -273.657314)
			(xy 334.613758 -273.701764) (xy 334.969358 -273.701764)
		)
		(stroke
			(width 0)
			(type solid)
		)
		(fill yes)
		(layer "In11.Cu")
		(net "M_D_CPU0_SA_DQ<19>")
	)
	(gr_poly
		(pts
			(xy 335.17459 -227.286566) (xy 335.212944 -227.264468) (xy 335.035144 -226.95662) (xy 334.99679 -226.978718)
			(xy 334.888332 -227.095558) (xy 335.019142 -227.322126)
		)
		(stroke
			(width 0)
			(type solid)
		)
		(fill yes)
		(layer "In11.Cu")
		(net "M_D_CPU0_SB_DQS_DP<3>")
	)
	(gr_poly
		(pts
			(xy 335.179162 -238.688372) (xy 335.217516 -238.666274) (xy 335.039716 -238.358426) (xy 335.001362 -238.380524)
			(xy 334.892904 -238.497364) (xy 335.023714 -238.723932)
		)
		(stroke
			(width 0)
			(type solid)
		)
		(fill yes)
		(layer "In11.Cu")
		(net "M_D_CPU0_SB_DQS_DN<5>")
	)
	(gr_poly
		(pts
			(xy 335.180178 -241.94643) (xy 335.218532 -241.924332) (xy 335.040732 -241.616484) (xy 335.002378 -241.638582)
			(xy 334.89392 -241.755422) (xy 335.02473 -241.98199)
		)
		(stroke
			(width 0)
			(type solid)
		)
		(fill yes)
		(layer "In11.Cu")
		(net "M_D_CPU0_SB_DQ<0>")
	)
	(gr_poly
		(pts
			(xy 335.181194 -228.925882) (xy 335.219548 -228.903784) (xy 335.041748 -228.595936) (xy 335.003394 -228.618034)
			(xy 334.894936 -228.734874) (xy 335.025746 -228.961442)
		)
		(stroke
			(width 0)
			(type solid)
		)
		(fill yes)
		(layer "In11.Cu")
		(net "M_D_CPU0_SB_DQ<25>")
	)
	(gr_poly
		(pts
			(xy 335.289906 -241.326162) (xy 335.398364 -241.209322) (xy 335.267554 -240.982754) (xy 335.112106 -241.018314)
			(xy 335.073752 -241.040412) (xy 335.251552 -241.34826)
		)
		(stroke
			(width 0)
			(type solid)
		)
		(fill yes)
		(layer "In11.Cu")
		(net "M_D_CPU0_SB_DQ<2>")
	)
	(gr_poly
		(pts
			(xy 335.294224 -238.077756) (xy 335.402682 -237.960916) (xy 335.271872 -237.734348) (xy 335.116424 -237.769908)
			(xy 335.07807 -237.792006) (xy 335.25587 -238.099854)
		)
		(stroke
			(width 0)
			(type solid)
		)
		(fill yes)
		(layer "In11.Cu")
		(net "M_D_CPU0_SB_DQS_DP<5>")
	)
	(gr_poly
		(pts
			(xy 335.296002 -228.31425) (xy 335.40446 -228.19741) (xy 335.27365 -227.970842) (xy 335.118202 -228.006402)
			(xy 335.079848 -228.0285) (xy 335.257648 -228.336348)
		)
		(stroke
			(width 0)
			(type solid)
		)
		(fill yes)
		(layer "In11.Cu")
		(net "M_D_CPU0_SB_DQ<27>")
	)
	(gr_poly
		(pts
			(xy 335.296002 -226.686364) (xy 335.40446 -226.569524) (xy 335.27365 -226.342956) (xy 335.118202 -226.378516)
			(xy 335.079848 -226.400614) (xy 335.257648 -226.708462)
		)
		(stroke
			(width 0)
			(type solid)
		)
		(fill yes)
		(layer "In11.Cu")
		(net "M_D_CPU0_SB_DQS_DN<3>")
	)
	(gr_poly
		(pts
			(xy 335.314798 -249.416062) (xy 335.314798 -249.371612) (xy 334.959198 -249.371612) (xy 334.959198 -249.416062)
			(xy 335.006188 -249.568462) (xy 335.267808 -249.568462)
		)
		(stroke
			(width 0)
			(type solid)
		)
		(fill yes)
		(layer "In11.Cu")
		(net "M_D_CPU0_SB_CA<2>")
	)
	(gr_poly
		(pts
			(xy 335.314798 -244.940582) (xy 335.267808 -244.788182) (xy 335.006188 -244.788182) (xy 334.959198 -244.940582)
			(xy 334.959198 -244.985032) (xy 335.314798 -244.985032)
		)
		(stroke
			(width 0)
			(type solid)
		)
		(fill yes)
		(layer "In11.Cu")
		(net "M_D_CPU0_SB_DQS_DN<9>")
	)
	(gr_poly
		(pts
			(xy 335.314798 -240.057178) (xy 335.267808 -239.904778) (xy 335.006188 -239.904778) (xy 334.959198 -240.057178)
			(xy 334.959198 -240.101628) (xy 335.314798 -240.101628)
		)
		(stroke
			(width 0)
			(type solid)
		)
		(fill yes)
		(layer "In11.Cu")
		(net "M_D_CPU0_SB_DQ<3>")
	)
	(gr_poly
		(pts
			(xy 335.314798 -239.649254) (xy 335.314798 -239.604804) (xy 334.959198 -239.604804) (xy 334.959198 -239.649254)
			(xy 335.006188 -239.801654) (xy 335.267808 -239.801654)
		)
		(stroke
			(width 0)
			(type solid)
		)
		(fill yes)
		(layer "In11.Cu")
		(net "M_D_CPU0_SB_DQS_DP<0>")
	)
	(gr_poly
		(pts
			(xy 335.314798 -234.76585) (xy 335.314798 -234.721654) (xy 334.959198 -234.721654) (xy 334.959198 -234.76585)
			(xy 335.006188 -234.91825) (xy 335.267808 -234.91825)
		)
		(stroke
			(width 0)
			(type solid)
		)
		(fill yes)
		(layer "In11.Cu")
		(net "M_D_CPU0_SB_DQ<8>")
	)
	(gr_poly
		(pts
			(xy 335.314798 -230.290878) (xy 335.267808 -230.138478) (xy 335.006188 -230.138478) (xy 334.959198 -230.290878)
			(xy 334.959198 -230.335074) (xy 335.314798 -230.335074)
		)
		(stroke
			(width 0)
			(type solid)
		)
		(fill yes)
		(layer "In11.Cu")
		(net "M_D_CPU0_SB_DQ<15>")
	)
	(gr_poly
		(pts
			(xy 335.32318 -244.53215) (xy 335.32318 -244.487954) (xy 334.96758 -244.487954) (xy 334.96758 -244.53215)
			(xy 335.01457 -244.68455) (xy 335.27619 -244.68455)
		)
		(stroke
			(width 0)
			(type solid)
		)
		(fill yes)
		(layer "In11.Cu")
		(net "M_D_CPU0_SB_DQS_DN<4>")
	)
	(gr_poly
		(pts
			(xy 335.32318 -229.882446) (xy 335.32318 -229.83825) (xy 334.96758 -229.83825) (xy 334.96758 -229.882446)
			(xy 335.01457 -230.034846) (xy 335.27619 -230.034846)
		)
		(stroke
			(width 0)
			(type solid)
		)
		(fill yes)
		(layer "In11.Cu")
		(net "M_D_CPU0_SB_DQ<24>")
	)
	(gr_poly
		(pts
			(xy 335.323434 -248.196354) (xy 335.276444 -248.043954) (xy 335.014824 -248.043954) (xy 334.967834 -248.196354)
			(xy 334.967834 -248.240804) (xy 335.323434 -248.240804)
		)
		(stroke
			(width 0)
			(type solid)
		)
		(fill yes)
		(layer "In11.Cu")
		(net "M_D_CPU0_SB_CA<5>")
	)
	(gr_poly
		(pts
			(xy 335.323434 -247.787922) (xy 335.323434 -247.743472) (xy 334.967834 -247.743472) (xy 334.967834 -247.787922)
			(xy 335.014824 -247.940322) (xy 335.276444 -247.940322)
		)
		(stroke
			(width 0)
			(type solid)
		)
		(fill yes)
		(layer "In11.Cu")
		(net "M_D_CPU0_SB_PAR")
	)
	(gr_poly
		(pts
			(xy 335.323434 -246.568722) (xy 335.276444 -246.416322) (xy 335.014824 -246.416322) (xy 334.967834 -246.568722)
			(xy 334.967834 -246.613172) (xy 335.323434 -246.613172)
		)
		(stroke
			(width 0)
			(type solid)
		)
		(fill yes)
		(layer "In11.Cu")
		(net "M_D_CPU0_SB_CB<6>")
	)
	(gr_poly
		(pts
			(xy 335.323434 -246.16029) (xy 335.323434 -246.11584) (xy 334.967834 -246.11584) (xy 334.967834 -246.16029)
			(xy 335.014824 -246.31269) (xy 335.276444 -246.31269)
		)
		(stroke
			(width 0)
			(type solid)
		)
		(fill yes)
		(layer "In11.Cu")
		(net "M_D_CPU0_SB_CB<5>")
	)
	(gr_poly
		(pts
			(xy 335.323434 -236.393482) (xy 335.323434 -236.349286) (xy 334.967834 -236.349286) (xy 334.967834 -236.393482)
			(xy 335.014824 -236.545882) (xy 335.276444 -236.545882)
		)
		(stroke
			(width 0)
			(type solid)
		)
		(fill yes)
		(layer "In11.Cu")
		(net "M_D_CPU0_SB_DQ<5>")
	)
	(gr_poly
		(pts
			(xy 335.323434 -233.54665) (xy 335.276444 -233.39425) (xy 335.014824 -233.39425) (xy 334.967834 -233.54665)
			(xy 334.967834 -233.590846) (xy 335.323434 -233.590846)
		)
		(stroke
			(width 0)
			(type solid)
		)
		(fill yes)
		(layer "In11.Cu")
		(net "M_D_CPU0_SB_DQ<11>")
	)
	(gr_poly
		(pts
			(xy 335.323434 -233.13771) (xy 335.323434 -233.093514) (xy 334.967834 -233.093514) (xy 334.967834 -233.13771)
			(xy 335.014824 -233.29011) (xy 335.276444 -233.29011)
		)
		(stroke
			(width 0)
			(type solid)
		)
		(fill yes)
		(layer "In11.Cu")
		(net "M_D_CPU0_SB_DQS_DP<1>")
	)
	(gr_poly
		(pts
			(xy 335.323434 -231.919018) (xy 335.276444 -231.766618) (xy 335.014824 -231.766618) (xy 334.967834 -231.919018)
			(xy 334.967834 -231.963214) (xy 335.323434 -231.963214)
		)
		(stroke
			(width 0)
			(type solid)
		)
		(fill yes)
		(layer "In11.Cu")
		(net "M_D_CPU0_SB_DQS_DP<6>")
	)
	(gr_poly
		(pts
			(xy 335.323434 -231.510078) (xy 335.323434 -231.465882) (xy 334.967834 -231.465882) (xy 334.967834 -231.510078)
			(xy 335.014824 -231.662478) (xy 335.276444 -231.662478)
		)
		(stroke
			(width 0)
			(type solid)
		)
		(fill yes)
		(layer "In11.Cu")
		(net "M_D_CPU0_SB_DQ<12>")
	)
	(gr_poly
		(pts
			(xy 335.323434 -224.999042) (xy 335.323434 -224.954592) (xy 334.967834 -224.954592) (xy 334.967834 -224.999042)
			(xy 335.014824 -225.151442) (xy 335.276444 -225.151442)
		)
		(stroke
			(width 0)
			(type solid)
		)
		(fill yes)
		(layer "In11.Cu")
		(net "M_D_CPU0_SB_DQ<28>")
	)
	(gr_poly
		(pts
			(xy 335.323434 -223.779842) (xy 335.276444 -223.627442) (xy 335.014824 -223.627442) (xy 334.967834 -223.779842)
			(xy 334.967834 -223.824292) (xy 335.323434 -223.824292)
		)
		(stroke
			(width 0)
			(type solid)
		)
		(fill yes)
		(layer "In11.Cu")
		(net "M_D_CPU0_SB_DQ<31>")
	)
	(gr_poly
		(pts
			(xy 335.331816 -243.31295) (xy 335.284826 -243.16055) (xy 335.023206 -243.16055) (xy 334.976216 -243.31295)
			(xy 334.976216 -243.3574) (xy 335.331816 -243.3574)
		)
		(stroke
			(width 0)
			(type solid)
		)
		(fill yes)
		(layer "In11.Cu")
		(net "M_D_CPU0_SB_CB<2>")
	)
	(gr_poly
		(pts
			(xy 335.331816 -242.905026) (xy 335.331816 -242.860576) (xy 334.976216 -242.860576) (xy 334.976216 -242.905026)
			(xy 335.023206 -243.057426) (xy 335.284826 -243.057426)
		)
		(stroke
			(width 0)
			(type solid)
		)
		(fill yes)
		(layer "In11.Cu")
		(net "M_D_CPU0_SB_CB<1>")
	)
	(gr_poly
		(pts
			(xy 335.331816 -236.801914) (xy 335.284826 -236.649514) (xy 335.023206 -236.649514) (xy 334.976216 -236.801914)
			(xy 334.976216 -236.846364) (xy 335.331816 -236.846364)
		)
		(stroke
			(width 0)
			(type solid)
		)
		(fill yes)
		(layer "In11.Cu")
		(net "M_D_CPU0_SB_DQ<6>")
	)
	(gr_poly
		(pts
			(xy 335.331816 -225.407474) (xy 335.284826 -225.255074) (xy 335.023206 -225.255074) (xy 334.976216 -225.407474)
			(xy 334.976216 -225.45167) (xy 335.331816 -225.45167)
		)
		(stroke
			(width 0)
			(type solid)
		)
		(fill yes)
		(layer "In11.Cu")
		(net "M_D_CPU0_SB_DQS_DP<8>")
	)
	(gr_poly
		(pts
			(xy 335.433162 -274.062698) (xy 335.433162 -274.018248) (xy 335.077562 -274.018248) (xy 335.077562 -274.062698)
			(xy 335.124552 -274.215098) (xy 335.386172 -274.215098)
		)
		(stroke
			(width 0)
			(type solid)
		)
		(fill yes)
		(layer "In11.Cu")
		(net "M_D_CPU0_SA_DQ<17>")
	)
	(gr_poly
		(pts
			(xy 335.433162 -271.215866) (xy 335.386172 -271.063466) (xy 335.124552 -271.063466) (xy 335.077562 -271.215866)
			(xy 335.077562 -271.260062) (xy 335.433162 -271.260062)
		)
		(stroke
			(width 0)
			(type solid)
		)
		(fill yes)
		(layer "In11.Cu")
		(net "M_D_CPU0_SA_DQ<22>")
	)
	(gr_poly
		(pts
			(xy 335.433162 -270.806926) (xy 335.433162 -270.76273) (xy 335.077562 -270.76273) (xy 335.077562 -270.806926)
			(xy 335.124552 -270.959326) (xy 335.386172 -270.959326)
		)
		(stroke
			(width 0)
			(type solid)
		)
		(fill yes)
		(layer "In11.Cu")
		(net "M_D_CPU0_SA_DQ<21>")
	)
	(gr_poly
		(pts
			(xy 335.433162 -269.587726) (xy 335.386172 -269.435326) (xy 335.124552 -269.435326) (xy 335.077562 -269.587726)
			(xy 335.077562 -269.632176) (xy 335.433162 -269.632176)
		)
		(stroke
			(width 0)
			(type solid)
		)
		(fill yes)
		(layer "In11.Cu")
		(net "M_D_CPU0_SA_DQ<26>")
	)
	(gr_poly
		(pts
			(xy 335.433162 -269.179294) (xy 335.433162 -269.134844) (xy 335.077562 -269.134844) (xy 335.077562 -269.179294)
			(xy 335.124552 -269.331694) (xy 335.386172 -269.331694)
		)
		(stroke
			(width 0)
			(type solid)
		)
		(fill yes)
		(layer "In11.Cu")
		(net "M_D_CPU0_SA_DQ<25>")
	)
	(gr_poly
		(pts
			(xy 335.433162 -267.960094) (xy 335.386172 -267.807694) (xy 335.124552 -267.807694) (xy 335.077562 -267.960094)
			(xy 335.077562 -268.004544) (xy 335.433162 -268.004544)
		)
		(stroke
			(width 0)
			(type solid)
		)
		(fill yes)
		(layer "In11.Cu")
		(net "M_D_CPU0_SA_DQS_DN<3>")
	)
	(gr_poly
		(pts
			(xy 335.433162 -267.551662) (xy 335.433162 -267.507212) (xy 335.077562 -267.507212) (xy 335.077562 -267.551662)
			(xy 335.124552 -267.704062) (xy 335.386172 -267.704062)
		)
		(stroke
			(width 0)
			(type solid)
		)
		(fill yes)
		(layer "In11.Cu")
		(net "M_D_CPU0_SA_DQS_DN<8>")
	)
	(gr_poly
		(pts
			(xy 335.433162 -266.332462) (xy 335.386172 -266.180062) (xy 335.124552 -266.180062) (xy 335.077562 -266.332462)
			(xy 335.077562 -266.376658) (xy 335.433162 -266.376658)
		)
		(stroke
			(width 0)
			(type solid)
		)
		(fill yes)
		(layer "In11.Cu")
		(net "M_D_CPU0_SA_DQ<30>")
	)
	(gr_poly
		(pts
			(xy 335.433162 -265.92403) (xy 335.433162 -265.87958) (xy 335.077562 -265.87958) (xy 335.077562 -265.92403)
			(xy 335.124552 -266.07643) (xy 335.386172 -266.07643)
		)
		(stroke
			(width 0)
			(type solid)
		)
		(fill yes)
		(layer "In11.Cu")
		(net "M_D_CPU0_SA_DQ<29>")
	)
	(gr_poly
		(pts
			(xy 335.433162 -264.70483) (xy 335.386172 -264.55243) (xy 335.124552 -264.55243) (xy 335.077562 -264.70483)
			(xy 335.077562 -264.749026) (xy 335.433162 -264.749026)
		)
		(stroke
			(width 0)
			(type solid)
		)
		(fill yes)
		(layer "In11.Cu")
		(net "M_D_CPU0_SA_CB<2>")
	)
	(gr_poly
		(pts
			(xy 335.433162 -264.29589) (xy 335.433162 -264.251694) (xy 335.077562 -264.251694) (xy 335.077562 -264.29589)
			(xy 335.124552 -264.44829) (xy 335.386172 -264.44829)
		)
		(stroke
			(width 0)
			(type solid)
		)
		(fill yes)
		(layer "In11.Cu")
		(net "M_D_CPU0_SA_CB<1>")
	)
	(gr_poly
		(pts
			(xy 335.433162 -263.07669) (xy 335.386172 -262.92429) (xy 335.124552 -262.92429) (xy 335.077562 -263.07669)
			(xy 335.077562 -263.12114) (xy 335.433162 -263.12114)
		)
		(stroke
			(width 0)
			(type solid)
		)
		(fill yes)
		(layer "In11.Cu")
		(net "M_D_CPU0_SA_DQS_DN<4>")
	)
	(gr_poly
		(pts
			(xy 335.433162 -262.668258) (xy 335.433162 -262.623808) (xy 335.077562 -262.623808) (xy 335.077562 -262.668258)
			(xy 335.124552 -262.820658) (xy 335.386172 -262.820658)
		)
		(stroke
			(width 0)
			(type solid)
		)
		(fill yes)
		(layer "In11.Cu")
		(net "M_D_CPU0_SA_DQS_DN<9>")
	)
	(gr_poly
		(pts
			(xy 335.433162 -261.449058) (xy 335.386172 -261.296658) (xy 335.124552 -261.296658) (xy 335.077562 -261.449058)
			(xy 335.077562 -261.493508) (xy 335.433162 -261.493508)
		)
		(stroke
			(width 0)
			(type solid)
		)
		(fill yes)
		(layer "In11.Cu")
		(net "M_D_CPU0_SA_CB<6>")
	)
	(gr_poly
		(pts
			(xy 335.433162 -261.040626) (xy 335.433162 -260.996176) (xy 335.077562 -260.996176) (xy 335.077562 -261.040626)
			(xy 335.124552 -261.193026) (xy 335.386172 -261.193026)
		)
		(stroke
			(width 0)
			(type solid)
		)
		(fill yes)
		(layer "In11.Cu")
		(net "M_D_CPU0_SA_CB<5>")
	)
	(gr_poly
		(pts
			(xy 335.433162 -259.412486) (xy 335.433162 -259.36829) (xy 335.077562 -259.36829) (xy 335.077562 -259.412486)
			(xy 335.124552 -259.564886) (xy 335.386172 -259.564886)
		)
		(stroke
			(width 0)
			(type solid)
		)
		(fill yes)
		(layer "In11.Cu")
		(net "M_D_CPU0_SA_CS_N<2>")
	)
	(gr_poly
		(pts
			(xy 335.433162 -258.193286) (xy 335.386172 -258.040886) (xy 335.124552 -258.040886) (xy 335.077562 -258.193286)
			(xy 335.077562 -258.237736) (xy 335.433162 -258.237736)
		)
		(stroke
			(width 0)
			(type solid)
		)
		(fill yes)
		(layer "In11.Cu")
		(net "M_D_CPU0_SA_CS_N<1>")
	)
	(gr_poly
		(pts
			(xy 335.433162 -257.784854) (xy 335.433162 -257.740404) (xy 335.077562 -257.740404) (xy 335.077562 -257.784854)
			(xy 335.124552 -257.937254) (xy 335.386172 -257.937254)
		)
		(stroke
			(width 0)
			(type solid)
		)
		(fill yes)
		(layer "In11.Cu")
		(net "M_D_CPU0_SA_CA<0>")
	)
	(gr_poly
		(pts
			(xy 335.433162 -256.565654) (xy 335.386172 -256.413254) (xy 335.124552 -256.413254) (xy 335.077562 -256.565654)
			(xy 335.077562 -256.610104) (xy 335.433162 -256.610104)
		)
		(stroke
			(width 0)
			(type solid)
		)
		(fill yes)
		(layer "In11.Cu")
		(net "M_D_CPU0_SA_CA<3>")
	)
	(gr_poly
		(pts
			(xy 335.433162 -256.157222) (xy 335.433162 -256.112772) (xy 335.077562 -256.112772) (xy 335.077562 -256.157222)
			(xy 335.124552 -256.309622) (xy 335.386172 -256.309622)
		)
		(stroke
			(width 0)
			(type solid)
		)
		(fill yes)
		(layer "In11.Cu")
		(net "M_D_CPU0_SA_CA<4>")
	)
	(gr_poly
		(pts
			(xy 335.439258 -272.843498) (xy 335.392268 -272.691098) (xy 335.130648 -272.691098) (xy 335.083658 -272.843498)
			(xy 335.083658 -272.887948) (xy 335.439258 -272.887948)
		)
		(stroke
			(width 0)
			(type solid)
		)
		(fill yes)
		(layer "In11.Cu")
		(net "M_D_CPU0_SA_DQS_DN<2>")
	)
	(gr_poly
		(pts
			(xy 335.439258 -272.435066) (xy 335.439258 -272.390616) (xy 335.083658 -272.390616) (xy 335.083658 -272.435066)
			(xy 335.130648 -272.587466) (xy 335.392268 -272.587466)
		)
		(stroke
			(width 0)
			(type solid)
		)
		(fill yes)
		(layer "In11.Cu")
		(net "M_D_CPU0_SA_DQS_DN<7>")
	)
	(gr_poly
		(pts
			(xy 335.441544 -274.47113) (xy 335.394554 -274.31873) (xy 335.132934 -274.31873) (xy 335.085944 -274.47113)
			(xy 335.085944 -274.515326) (xy 335.441544 -274.515326)
		)
		(stroke
			(width 0)
			(type solid)
		)
		(fill yes)
		(layer "In11.Cu")
		(net "M_D_CPU0_SA_DQ<18>")
	)
	(gr_poly
		(pts
			(xy 335.642712 -226.469956) (xy 335.681066 -226.447858) (xy 335.503266 -226.14001) (xy 335.464912 -226.162108)
			(xy 335.356454 -226.278948) (xy 335.487264 -226.505516)
		)
		(stroke
			(width 0)
			(type solid)
		)
		(fill yes)
		(layer "In11.Cu")
		(net "M_D_CPU0_SB_DQS_DN<8>")
	)
	(gr_poly
		(pts
			(xy 335.6483 -237.87354) (xy 335.686654 -237.851442) (xy 335.508854 -237.543594) (xy 335.4705 -237.565692)
			(xy 335.362042 -237.682532) (xy 335.492852 -237.9091)
		)
		(stroke
			(width 0)
			(type solid)
		)
		(fill yes)
		(layer "In11.Cu")
		(net "M_D_CPU0_SB_DQ<4>")
	)
	(gr_poly
		(pts
			(xy 335.6483 -228.106986) (xy 335.686654 -228.084888) (xy 335.508854 -227.77704) (xy 335.4705 -227.799138)
			(xy 335.362042 -227.915978) (xy 335.492852 -228.142546)
		)
		(stroke
			(width 0)
			(type solid)
		)
		(fill yes)
		(layer "In11.Cu")
		(net "M_D_CPU0_SB_DQS_DP<3>")
	)
	(gr_poly
		(pts
			(xy 335.649062 -241.130074) (xy 335.687416 -241.107976) (xy 335.509616 -240.800128) (xy 335.471262 -240.822226)
			(xy 335.362804 -240.939066) (xy 335.493614 -241.165634)
		)
		(stroke
			(width 0)
			(type solid)
		)
		(fill yes)
		(layer "In11.Cu")
		(net "M_D_CPU0_SB_DQ<1>")
	)
	(gr_poly
		(pts
			(xy 335.75879 -240.510314) (xy 335.867248 -240.393474) (xy 335.736438 -240.166906) (xy 335.58099 -240.202466)
			(xy 335.542636 -240.224564) (xy 335.720436 -240.532412)
		)
		(stroke
			(width 0)
			(type solid)
		)
		(fill yes)
		(layer "In11.Cu")
		(net "M_D_CPU0_SB_DQ<3>")
	)
	(gr_poly
		(pts
			(xy 335.75879 -225.860356) (xy 335.867248 -225.743516) (xy 335.736438 -225.516948) (xy 335.58099 -225.552508)
			(xy 335.542636 -225.574606) (xy 335.720436 -225.882454)
		)
		(stroke
			(width 0)
			(type solid)
		)
		(fill yes)
		(layer "In11.Cu")
		(net "M_D_CPU0_SB_DQS_DP<8>")
	)
	(gr_poly
		(pts
			(xy 335.764124 -237.26394) (xy 335.872582 -237.1471) (xy 335.741772 -236.920532) (xy 335.586324 -236.956092)
			(xy 335.54797 -236.97819) (xy 335.72577 -237.286038)
		)
		(stroke
			(width 0)
			(type solid)
		)
		(fill yes)
		(layer "In11.Cu")
		(net "M_D_CPU0_SB_DQ<6>")
	)
	(gr_poly
		(pts
			(xy 335.764124 -227.497386) (xy 335.872582 -227.380546) (xy 335.741772 -227.153978) (xy 335.586324 -227.189538)
			(xy 335.54797 -227.211636) (xy 335.72577 -227.519484)
		)
		(stroke
			(width 0)
			(type solid)
		)
		(fill yes)
		(layer "In11.Cu")
		(net "M_D_CPU0_SB_DQS_DN<3>")
	)
	(gr_poly
		(pts
			(xy 335.787238 -243.718842) (xy 335.787238 -243.674392) (xy 335.431638 -243.674392) (xy 335.431638 -243.718842)
			(xy 335.478628 -243.871242) (xy 335.740248 -243.871242)
		)
		(stroke
			(width 0)
			(type solid)
		)
		(fill yes)
		(layer "In11.Cu")
		(net "M_D_CPU0_SB_CB<0>")
	)
	(gr_poly
		(pts
			(xy 335.787238 -229.477062) (xy 335.740248 -229.324662) (xy 335.478628 -229.324662) (xy 335.431638 -229.477062)
			(xy 335.431638 -229.521258) (xy 335.787238 -229.521258)
		)
		(stroke
			(width 0)
			(type solid)
		)
		(fill yes)
		(layer "In11.Cu")
		(net "M_D_CPU0_SB_DQ<26>")
	)
	(gr_poly
		(pts
			(xy 335.793334 -248.601738) (xy 335.793334 -248.557542) (xy 335.437734 -248.557542) (xy 335.437734 -248.601738)
			(xy 335.484724 -248.754138) (xy 335.746344 -248.754138)
		)
		(stroke
			(width 0)
			(type solid)
		)
		(fill yes)
		(layer "In11.Cu")
		(net "M_D_CPU0_SB_CA<4>")
	)
	(gr_poly
		(pts
			(xy 335.793334 -247.382538) (xy 335.746344 -247.230138) (xy 335.484724 -247.230138) (xy 335.437734 -247.382538)
			(xy 335.437734 -247.426988) (xy 335.793334 -247.426988)
		)
		(stroke
			(width 0)
			(type solid)
		)
		(fill yes)
		(layer "In11.Cu")
		(net "M_D_CPU0_SB_CA<6>")
	)
	(gr_poly
		(pts
			(xy 335.793334 -246.974106) (xy 335.793334 -246.929656) (xy 335.437734 -246.929656) (xy 335.437734 -246.974106)
			(xy 335.484724 -247.126506) (xy 335.746344 -247.126506)
		)
		(stroke
			(width 0)
			(type solid)
		)
		(fill yes)
		(layer "In11.Cu")
		(net "M_D_CPU0_SB_CB<4>")
	)
	(gr_poly
		(pts
			(xy 335.793334 -245.754906) (xy 335.746344 -245.602506) (xy 335.484724 -245.602506) (xy 335.437734 -245.754906)
			(xy 335.437734 -245.799356) (xy 335.793334 -245.799356)
		)
		(stroke
			(width 0)
			(type solid)
		)
		(fill yes)
		(layer "In11.Cu")
		(net "M_D_CPU0_SB_CB<7>")
	)
	(gr_poly
		(pts
			(xy 335.793334 -242.499134) (xy 335.746344 -242.346734) (xy 335.484724 -242.346734) (xy 335.437734 -242.499134)
			(xy 335.437734 -242.54333) (xy 335.793334 -242.54333)
		)
		(stroke
			(width 0)
			(type solid)
		)
		(fill yes)
		(layer "In11.Cu")
		(net "M_D_CPU0_SB_CB<3>")
	)
	(gr_poly
		(pts
			(xy 335.793334 -242.090702) (xy 335.793334 -242.046506) (xy 335.437734 -242.046506) (xy 335.437734 -242.090702)
			(xy 335.484724 -242.243102) (xy 335.746344 -242.243102)
		)
		(stroke
			(width 0)
			(type solid)
		)
		(fill yes)
		(layer "In11.Cu")
		(net "M_D_CPU0_SB_DQ<0>")
	)
	(gr_poly
		(pts
			(xy 335.793334 -238.83493) (xy 335.793334 -238.790734) (xy 335.437734 -238.790734) (xy 335.437734 -238.83493)
			(xy 335.484724 -238.98733) (xy 335.746344 -238.98733)
		)
		(stroke
			(width 0)
			(type solid)
		)
		(fill yes)
		(layer "In11.Cu")
		(net "M_D_CPU0_SB_DQS_DN<5>")
	)
	(gr_poly
		(pts
			(xy 335.793334 -235.988098) (xy 335.746344 -235.835698) (xy 335.484724 -235.835698) (xy 335.437734 -235.988098)
			(xy 335.437734 -236.032548) (xy 335.793334 -236.032548)
		)
		(stroke
			(width 0)
			(type solid)
		)
		(fill yes)
		(layer "In11.Cu")
		(net "M_D_CPU0_SB_DQ<7>")
	)
	(gr_poly
		(pts
			(xy 335.793334 -233.952034) (xy 335.793334 -233.907584) (xy 335.437734 -233.907584) (xy 335.437734 -233.952034)
			(xy 335.484724 -234.104434) (xy 335.746344 -234.104434)
		)
		(stroke
			(width 0)
			(type solid)
		)
		(fill yes)
		(layer "In11.Cu")
		(net "M_D_CPU0_SB_DQ<9>")
	)
	(gr_poly
		(pts
			(xy 335.793334 -232.732834) (xy 335.746344 -232.580434) (xy 335.484724 -232.580434) (xy 335.437734 -232.732834)
			(xy 335.437734 -232.77703) (xy 335.793334 -232.77703)
		)
		(stroke
			(width 0)
			(type solid)
		)
		(fill yes)
		(layer "In11.Cu")
		(net "M_D_CPU0_SB_DQS_DN<1>")
	)
	(gr_poly
		(pts
			(xy 335.793334 -232.323894) (xy 335.793334 -232.279698) (xy 335.437734 -232.279698) (xy 335.437734 -232.323894)
			(xy 335.484724 -232.476294) (xy 335.746344 -232.476294)
		)
		(stroke
			(width 0)
			(type solid)
		)
		(fill yes)
		(layer "In11.Cu")
		(net "M_D_CPU0_SB_DQS_DN<6>")
	)
	(gr_poly
		(pts
			(xy 335.793334 -231.104694) (xy 335.746344 -230.952294) (xy 335.484724 -230.952294) (xy 335.437734 -231.104694)
			(xy 335.437734 -231.149144) (xy 335.793334 -231.149144)
		)
		(stroke
			(width 0)
			(type solid)
		)
		(fill yes)
		(layer "In11.Cu")
		(net "M_D_CPU0_SB_DQ<14>")
	)
	(gr_poly
		(pts
			(xy 335.793334 -229.06863) (xy 335.793334 -229.02418) (xy 335.437734 -229.02418) (xy 335.437734 -229.06863)
			(xy 335.484724 -229.22103) (xy 335.746344 -229.22103)
		)
		(stroke
			(width 0)
			(type solid)
		)
		(fill yes)
		(layer "In11.Cu")
		(net "M_D_CPU0_SB_DQ<25>")
	)
	(gr_poly
		(pts
			(xy 335.793334 -224.593658) (xy 335.746344 -224.441258) (xy 335.484724 -224.441258) (xy 335.437734 -224.593658)
			(xy 335.437734 -224.638108) (xy 335.793334 -224.638108)
		)
		(stroke
			(width 0)
			(type solid)
		)
		(fill yes)
		(layer "In11.Cu")
		(net "M_D_CPU0_SB_DQ<30>")
	)
	(gr_poly
		(pts
			(xy 335.793334 -224.185226) (xy 335.793334 -224.140776) (xy 335.437734 -224.140776) (xy 335.437734 -224.185226)
			(xy 335.484724 -224.337626) (xy 335.746344 -224.337626)
		)
		(stroke
			(width 0)
			(type solid)
		)
		(fill yes)
		(layer "In11.Cu")
		(net "M_D_CPU0_SB_DQ<29>")
	)
	(gr_poly
		(pts
			(xy 335.799176 -244.126766) (xy 335.752186 -243.974366) (xy 335.490566 -243.974366) (xy 335.443576 -244.126766)
			(xy 335.443576 -244.171216) (xy 335.799176 -244.171216)
		)
		(stroke
			(width 0)
			(type solid)
		)
		(fill yes)
		(layer "In11.Cu")
		(net "M_D_CPU0_SB_DQS_DP<4>")
	)
	(gr_poly
		(pts
			(xy 335.801716 -249.01017) (xy 335.754726 -248.85777) (xy 335.493106 -248.85777) (xy 335.446116 -249.01017)
			(xy 335.446116 -249.05462) (xy 335.801716 -249.05462)
		)
		(stroke
			(width 0)
			(type solid)
		)
		(fill yes)
		(layer "In11.Cu")
		(net "M_D_CPU0_SB_CA<3>")
	)
	(gr_poly
		(pts
			(xy 335.801716 -245.346474) (xy 335.801716 -245.302278) (xy 335.446116 -245.302278) (xy 335.446116 -245.346474)
			(xy 335.493106 -245.498874) (xy 335.754726 -245.498874)
		)
		(stroke
			(width 0)
			(type solid)
		)
		(fill yes)
		(layer "In11.Cu")
		(net "M_D_CPU0_SB_DQS_DP<9>")
	)
	(gr_poly
		(pts
			(xy 335.801716 -239.243362) (xy 335.754726 -239.090962) (xy 335.493106 -239.090962) (xy 335.446116 -239.243362)
			(xy 335.446116 -239.287812) (xy 335.801716 -239.287812)
		)
		(stroke
			(width 0)
			(type solid)
		)
		(fill yes)
		(layer "In11.Cu")
		(net "M_D_CPU0_SB_DQS_DN<0>")
	)
	(gr_poly
		(pts
			(xy 335.801716 -234.360466) (xy 335.754726 -234.208066) (xy 335.493106 -234.208066) (xy 335.446116 -234.360466)
			(xy 335.446116 -234.404662) (xy 335.801716 -234.404662)
		)
		(stroke
			(width 0)
			(type solid)
		)
		(fill yes)
		(layer "In11.Cu")
		(net "M_D_CPU0_SB_DQ<10>")
	)
	(gr_poly
		(pts
			(xy 335.801716 -230.696262) (xy 335.801716 -230.652066) (xy 335.446116 -230.652066) (xy 335.446116 -230.696262)
			(xy 335.493106 -230.848662) (xy 335.754726 -230.848662)
		)
		(stroke
			(width 0)
			(type solid)
		)
		(fill yes)
		(layer "In11.Cu")
		(net "M_D_CPU0_SB_DQ<13>")
	)
	(gr_poly
		(pts
			(xy 335.896966 -274.876514) (xy 335.896966 -274.832318) (xy 335.541366 -274.832318) (xy 335.541366 -274.876514)
			(xy 335.588356 -275.028914) (xy 335.849976 -275.028914)
		)
		(stroke
			(width 0)
			(type solid)
		)
		(fill yes)
		(layer "In11.Cu")
		(net "M_D_CPU0_SA_DQ<16>")
	)
	(gr_poly
		(pts
			(xy 335.903062 -273.657314) (xy 335.856072 -273.504914) (xy 335.594452 -273.504914) (xy 335.547462 -273.657314)
			(xy 335.547462 -273.701764) (xy 335.903062 -273.701764)
		)
		(stroke
			(width 0)
			(type solid)
		)
		(fill yes)
		(layer "In11.Cu")
		(net "M_D_CPU0_SA_DQ<19>")
	)
	(gr_poly
		(pts
			(xy 335.903062 -273.248882) (xy 335.903062 -273.204432) (xy 335.547462 -273.204432) (xy 335.547462 -273.248882)
			(xy 335.594452 -273.401282) (xy 335.856072 -273.401282)
		)
		(stroke
			(width 0)
			(type solid)
		)
		(fill yes)
		(layer "In11.Cu")
		(net "M_D_CPU0_SA_DQS_DP<2>")
	)
	(gr_poly
		(pts
			(xy 335.903062 -272.029682) (xy 335.856072 -271.877282) (xy 335.594452 -271.877282) (xy 335.547462 -272.029682)
			(xy 335.547462 -272.073878) (xy 335.903062 -272.073878)
		)
		(stroke
			(width 0)
			(type solid)
		)
		(fill yes)
		(layer "In11.Cu")
		(net "M_D_CPU0_SA_DQS_DP<7>")
	)
	(gr_poly
		(pts
			(xy 335.903062 -271.620742) (xy 335.903062 -271.576546) (xy 335.547462 -271.576546) (xy 335.547462 -271.620742)
			(xy 335.594452 -271.773142) (xy 335.856072 -271.773142)
		)
		(stroke
			(width 0)
			(type solid)
		)
		(fill yes)
		(layer "In11.Cu")
		(net "M_D_CPU0_SA_DQ<20>")
	)
	(gr_poly
		(pts
			(xy 335.903062 -270.40205) (xy 335.856072 -270.24965) (xy 335.594452 -270.24965) (xy 335.547462 -270.40205)
			(xy 335.547462 -270.446246) (xy 335.903062 -270.446246)
		)
		(stroke
			(width 0)
			(type solid)
		)
		(fill yes)
		(layer "In11.Cu")
		(net "M_D_CPU0_SA_DQ<23>")
	)
	(gr_poly
		(pts
			(xy 335.903062 -269.99311) (xy 335.903062 -269.948914) (xy 335.547462 -269.948914) (xy 335.547462 -269.99311)
			(xy 335.594452 -270.14551) (xy 335.856072 -270.14551)
		)
		(stroke
			(width 0)
			(type solid)
		)
		(fill yes)
		(layer "In11.Cu")
		(net "M_D_CPU0_SA_DQ<24>")
	)
	(gr_poly
		(pts
			(xy 335.903062 -268.77391) (xy 335.856072 -268.62151) (xy 335.594452 -268.62151) (xy 335.547462 -268.77391)
			(xy 335.547462 -268.81836) (xy 335.903062 -268.81836)
		)
		(stroke
			(width 0)
			(type solid)
		)
		(fill yes)
		(layer "In11.Cu")
		(net "M_D_CPU0_SA_DQ<27>")
	)
	(gr_poly
		(pts
			(xy 335.903062 -268.365478) (xy 335.903062 -268.321028) (xy 335.547462 -268.321028) (xy 335.547462 -268.365478)
			(xy 335.594452 -268.517878) (xy 335.856072 -268.517878)
		)
		(stroke
			(width 0)
			(type solid)
		)
		(fill yes)
		(layer "In11.Cu")
		(net "M_D_CPU0_SA_DQS_DP<3>")
	)
	(gr_poly
		(pts
			(xy 335.903062 -267.146278) (xy 335.856072 -266.993878) (xy 335.594452 -266.993878) (xy 335.547462 -267.146278)
			(xy 335.547462 -267.190474) (xy 335.903062 -267.190474)
		)
		(stroke
			(width 0)
			(type solid)
		)
		(fill yes)
		(layer "In11.Cu")
		(net "M_D_CPU0_SA_DQS_DP<8>")
	)
	(gr_poly
		(pts
			(xy 335.903062 -266.737846) (xy 335.903062 -266.693396) (xy 335.547462 -266.693396) (xy 335.547462 -266.737846)
			(xy 335.594452 -266.890246) (xy 335.856072 -266.890246)
		)
		(stroke
			(width 0)
			(type solid)
		)
		(fill yes)
		(layer "In11.Cu")
		(net "M_D_CPU0_SA_DQ<28>")
	)
	(gr_poly
		(pts
			(xy 335.903062 -265.518646) (xy 335.856072 -265.366246) (xy 335.594452 -265.366246) (xy 335.547462 -265.518646)
			(xy 335.547462 -265.562842) (xy 335.903062 -265.562842)
		)
		(stroke
			(width 0)
			(type solid)
		)
		(fill yes)
		(layer "In11.Cu")
		(net "M_D_CPU0_SA_DQ<31>")
	)
	(gr_poly
		(pts
			(xy 335.903062 -265.109706) (xy 335.903062 -265.06551) (xy 335.547462 -265.06551) (xy 335.547462 -265.109706)
			(xy 335.594452 -265.262106) (xy 335.856072 -265.262106)
		)
		(stroke
			(width 0)
			(type solid)
		)
		(fill yes)
		(layer "In11.Cu")
		(net "M_D_CPU0_SA_CB<0>")
	)
	(gr_poly
		(pts
			(xy 335.903062 -263.891014) (xy 335.856072 -263.738614) (xy 335.594452 -263.738614) (xy 335.547462 -263.891014)
			(xy 335.547462 -263.93521) (xy 335.903062 -263.93521)
		)
		(stroke
			(width 0)
			(type solid)
		)
		(fill yes)
		(layer "In11.Cu")
		(net "M_D_CPU0_SA_CB<3>")
	)
	(gr_poly
		(pts
			(xy 335.903062 -263.482074) (xy 335.903062 -263.437878) (xy 335.547462 -263.437878) (xy 335.547462 -263.482074)
			(xy 335.594452 -263.634474) (xy 335.856072 -263.634474)
		)
		(stroke
			(width 0)
			(type solid)
		)
		(fill yes)
		(layer "In11.Cu")
		(net "M_D_CPU0_SA_DQS_DP<4>")
	)
	(gr_poly
		(pts
			(xy 335.903062 -262.262874) (xy 335.856072 -262.110474) (xy 335.594452 -262.110474) (xy 335.547462 -262.262874)
			(xy 335.547462 -262.307324) (xy 335.903062 -262.307324)
		)
		(stroke
			(width 0)
			(type solid)
		)
		(fill yes)
		(layer "In11.Cu")
		(net "M_D_CPU0_SA_DQS_DP<9>")
	)
	(gr_poly
		(pts
			(xy 335.903062 -261.854442) (xy 335.903062 -261.809992) (xy 335.547462 -261.809992) (xy 335.547462 -261.854442)
			(xy 335.594452 -262.006842) (xy 335.856072 -262.006842)
		)
		(stroke
			(width 0)
			(type solid)
		)
		(fill yes)
		(layer "In11.Cu")
		(net "M_D_CPU0_SA_CB<4>")
	)
	(gr_poly
		(pts
			(xy 335.903062 -260.635242) (xy 335.856072 -260.482842) (xy 335.594452 -260.482842) (xy 335.547462 -260.635242)
			(xy 335.547462 -260.679438) (xy 335.903062 -260.679438)
		)
		(stroke
			(width 0)
			(type solid)
		)
		(fill yes)
		(layer "In11.Cu")
		(net "M_D_CPU0_SA_CB<7>")
	)
	(gr_poly
		(pts
			(xy 335.903062 -259.00761) (xy 335.856072 -258.85521) (xy 335.594452 -258.85521) (xy 335.547462 -259.00761)
			(xy 335.547462 -259.051806) (xy 335.903062 -259.051806)
		)
		(stroke
			(width 0)
			(type solid)
		)
		(fill yes)
		(layer "In11.Cu")
		(net "M_D_CPU0_SA_CS_N<0>")
	)
	(gr_poly
		(pts
			(xy 335.903062 -258.59867) (xy 335.903062 -258.554474) (xy 335.547462 -258.554474) (xy 335.547462 -258.59867)
			(xy 335.594452 -258.75107) (xy 335.856072 -258.75107)
		)
		(stroke
			(width 0)
			(type solid)
		)
		(fill yes)
		(layer "In11.Cu")
		(net "M_D_CPU0_SA_CS_N<3>")
	)
	(gr_poly
		(pts
			(xy 335.903062 -257.37947) (xy 335.856072 -257.22707) (xy 335.594452 -257.22707) (xy 335.547462 -257.37947)
			(xy 335.547462 -257.42392) (xy 335.903062 -257.42392)
		)
		(stroke
			(width 0)
			(type solid)
		)
		(fill yes)
		(layer "In11.Cu")
		(net "M_D_CPU0_SA_CA<1>")
	)
	(gr_poly
		(pts
			(xy 335.903062 -256.971038) (xy 335.903062 -256.926588) (xy 335.547462 -256.926588) (xy 335.547462 -256.971038)
			(xy 335.594452 -257.123438) (xy 335.856072 -257.123438)
		)
		(stroke
			(width 0)
			(type solid)
		)
		(fill yes)
		(layer "In11.Cu")
		(net "M_D_CPU0_SA_CA<2>")
	)
	(gr_poly
		(pts
			(xy 335.903062 -255.751838) (xy 335.856072 -255.599438) (xy 335.594452 -255.599438) (xy 335.547462 -255.751838)
			(xy 335.547462 -255.796288) (xy 335.903062 -255.796288)
		)
		(stroke
			(width 0)
			(type solid)
		)
		(fill yes)
		(layer "In11.Cu")
		(net "M_D_CPU0_SA_CA<5>")
	)
	(gr_poly
		(pts
			(xy 335.908904 -275.284946) (xy 335.861914 -275.132546) (xy 335.600294 -275.132546) (xy 335.553304 -275.284946)
			(xy 335.553304 -275.329142) (xy 335.908904 -275.329142)
		)
		(stroke
			(width 0)
			(type solid)
		)
		(fill yes)
		(layer "In11.Cu")
		(net "M_D_CPU0_SA_DQ<15>")
	)
	(gr_poly
		(pts
			(xy 335.911444 -276.5044) (xy 335.911444 -276.460204) (xy 335.555844 -276.460204) (xy 335.555844 -276.5044)
			(xy 335.602834 -276.6568) (xy 335.864454 -276.6568)
		)
		(stroke
			(width 0)
			(type solid)
		)
		(fill yes)
		(layer "In11.Cu")
		(net "M_D_CPU0_SA_DQ<12>")
	)
	(gr_poly
		(pts
			(xy 335.977992 -278.608282) (xy 335.869534 -278.491442) (xy 335.83118 -278.469344) (xy 335.65338 -278.777192)
			(xy 335.691734 -278.79929) (xy 335.847182 -278.83485)
		)
		(stroke
			(width 0)
			(type solid)
		)
		(fill yes)
		(layer "In11.Cu")
		(net "M_D_CPU0_SA_DQS_DP<1>")
	)
	(gr_poly
		(pts
			(xy 336.11439 -235.425742) (xy 336.152744 -235.403644) (xy 335.974944 -235.095796) (xy 335.93659 -235.117894)
			(xy 335.828132 -235.234734) (xy 335.958942 -235.461302)
		)
		(stroke
			(width 0)
			(type solid)
		)
		(fill yes)
		(layer "In11.Cu")
		(net "M_D_CPU0_SB_DQ<8>")
	)
	(gr_poly
		(pts
			(xy 336.11439 -227.28682) (xy 336.152744 -227.264722) (xy 335.974944 -226.956874) (xy 335.93659 -226.978972)
			(xy 335.828132 -227.095812) (xy 335.958942 -227.32238)
		)
		(stroke
			(width 0)
			(type solid)
		)
		(fill yes)
		(layer "In11.Cu")
		(net "M_D_CPU0_SB_DQS_DN<8>")
	)
	(gr_poly
		(pts
			(xy 336.119724 -240.318036) (xy 336.158078 -240.295938) (xy 335.980278 -239.98809) (xy 335.941924 -240.010188)
			(xy 335.833466 -240.127028) (xy 335.964276 -240.353596)
		)
		(stroke
			(width 0)
			(type solid)
		)
		(fill yes)
		(layer "In11.Cu")
		(net "M_D_CPU0_SB_DQS_DP<0>")
	)
	(gr_poly
		(pts
			(xy 336.120994 -225.67011) (xy 336.159348 -225.648012) (xy 335.981548 -225.340164) (xy 335.943194 -225.362262)
			(xy 335.834736 -225.479102) (xy 335.965546 -225.70567)
		)
		(stroke
			(width 0)
			(type solid)
		)
		(fill yes)
		(layer "In11.Cu")
		(net "M_D_CPU0_SB_DQ<28>")
	)
	(gr_poly
		(pts
			(xy 336.228436 -239.695736) (xy 336.336894 -239.578896) (xy 336.206084 -239.352328) (xy 336.050636 -239.387888)
			(xy 336.012282 -239.409986) (xy 336.190082 -239.717834)
		)
		(stroke
			(width 0)
			(type solid)
		)
		(fill yes)
		(layer "In11.Cu")
		(net "M_D_CPU0_SB_DQS_DN<0>")
	)
	(gr_poly
		(pts
			(xy 336.228436 -234.812586) (xy 336.336894 -234.695746) (xy 336.206084 -234.469178) (xy 336.050636 -234.504738)
			(xy 336.012282 -234.526836) (xy 336.190082 -234.834684)
		)
		(stroke
			(width 0)
			(type solid)
		)
		(fill yes)
		(layer "In11.Cu")
		(net "M_D_CPU0_SB_DQ<10>")
	)
	(gr_poly
		(pts
			(xy 336.229706 -226.676204) (xy 336.338164 -226.559364) (xy 336.207354 -226.332796) (xy 336.051906 -226.368356)
			(xy 336.013552 -226.390454) (xy 336.191352 -226.698302)
		)
		(stroke
			(width 0)
			(type solid)
		)
		(fill yes)
		(layer "In11.Cu")
		(net "M_D_CPU0_SB_DQS_DP<8>")
	)
	(gr_poly
		(pts
			(xy 336.229706 -225.048318) (xy 336.338164 -224.931478) (xy 336.207354 -224.70491) (xy 336.051906 -224.74047)
			(xy 336.013552 -224.762568) (xy 336.191352 -225.070416)
		)
		(stroke
			(width 0)
			(type solid)
		)
		(fill yes)
		(layer "In11.Cu")
		(net "M_D_CPU0_SB_DQ<30>")
	)
	(gr_poly
		(pts
			(xy 336.254598 -249.416062) (xy 336.254598 -249.371612) (xy 335.898998 -249.371612) (xy 335.898998 -249.416062)
			(xy 335.945988 -249.568462) (xy 336.207608 -249.568462)
		)
		(stroke
			(width 0)
			(type solid)
		)
		(fill yes)
		(layer "In11.Cu")
		(net "M_D_CPU0_SB_CA<2>")
	)
	(gr_poly
		(pts
			(xy 336.254598 -244.940582) (xy 336.207608 -244.788182) (xy 335.945988 -244.788182) (xy 335.898998 -244.940582)
			(xy 335.898998 -244.985032) (xy 336.254598 -244.985032)
		)
		(stroke
			(width 0)
			(type solid)
		)
		(fill yes)
		(layer "In11.Cu")
		(net "M_D_CPU0_SB_DQS_DN<9>")
	)
	(gr_poly
		(pts
			(xy 336.254598 -244.532658) (xy 336.254598 -244.488208) (xy 335.898998 -244.488208) (xy 335.898998 -244.532658)
			(xy 335.945988 -244.685058) (xy 336.207608 -244.685058)
		)
		(stroke
			(width 0)
			(type solid)
		)
		(fill yes)
		(layer "In11.Cu")
		(net "M_D_CPU0_SB_DQS_DN<4>")
	)
	(gr_poly
		(pts
			(xy 336.254598 -230.290878) (xy 336.207608 -230.138478) (xy 335.945988 -230.138478) (xy 335.898998 -230.290878)
			(xy 335.898998 -230.335074) (xy 336.254598 -230.335074)
		)
		(stroke
			(width 0)
			(type solid)
		)
		(fill yes)
		(layer "In11.Cu")
		(net "M_D_CPU0_SB_DQ<15>")
	)
	(gr_poly
		(pts
			(xy 336.254598 -229.882446) (xy 336.254598 -229.83825) (xy 335.898998 -229.83825) (xy 335.898998 -229.882446)
			(xy 335.945988 -230.034846) (xy 336.207608 -230.034846)
		)
		(stroke
			(width 0)
			(type solid)
		)
		(fill yes)
		(layer "In11.Cu")
		(net "M_D_CPU0_SB_DQ<24>")
	)
	(gr_poly
		(pts
			(xy 336.254852 -242.905026) (xy 336.254852 -242.860576) (xy 335.899252 -242.860576) (xy 335.899252 -242.905026)
			(xy 335.946242 -243.057426) (xy 336.207862 -243.057426)
		)
		(stroke
			(width 0)
			(type solid)
		)
		(fill yes)
		(layer "In11.Cu")
		(net "M_D_CPU0_SB_CB<1>")
	)
	(gr_poly
		(pts
			(xy 336.254852 -241.685318) (xy 336.207862 -241.532918) (xy 335.946242 -241.532918) (xy 335.899252 -241.685318)
			(xy 335.899252 -241.729514) (xy 336.254852 -241.729514)
		)
		(stroke
			(width 0)
			(type solid)
		)
		(fill yes)
		(layer "In11.Cu")
		(net "M_D_CPU0_SB_DQ<2>")
	)
	(gr_poly
		(pts
			(xy 336.257138 -248.196354) (xy 336.210148 -248.043954) (xy 335.948528 -248.043954) (xy 335.901538 -248.196354)
			(xy 335.901538 -248.240804) (xy 336.257138 -248.240804)
		)
		(stroke
			(width 0)
			(type solid)
		)
		(fill yes)
		(layer "In11.Cu")
		(net "M_D_CPU0_SB_CA<5>")
	)
	(gr_poly
		(pts
			(xy 336.257138 -247.787922) (xy 336.257138 -247.743472) (xy 335.901538 -247.743472) (xy 335.901538 -247.787922)
			(xy 335.948528 -247.940322) (xy 336.210148 -247.940322)
		)
		(stroke
			(width 0)
			(type solid)
		)
		(fill yes)
		(layer "In11.Cu")
		(net "M_D_CPU0_SB_PAR")
	)
	(gr_poly
		(pts
			(xy 336.257138 -246.568722) (xy 336.210148 -246.416322) (xy 335.948528 -246.416322) (xy 335.901538 -246.568722)
			(xy 335.901538 -246.613172) (xy 336.257138 -246.613172)
		)
		(stroke
			(width 0)
			(type solid)
		)
		(fill yes)
		(layer "In11.Cu")
		(net "M_D_CPU0_SB_CB<6>")
	)
	(gr_poly
		(pts
			(xy 336.257138 -246.16029) (xy 336.257138 -246.11584) (xy 335.901538 -246.11584) (xy 335.901538 -246.16029)
			(xy 335.948528 -246.31269) (xy 336.210148 -246.31269)
		)
		(stroke
			(width 0)
			(type solid)
		)
		(fill yes)
		(layer "In11.Cu")
		(net "M_D_CPU0_SB_CB<5>")
	)
	(gr_poly
		(pts
			(xy 336.257138 -243.313458) (xy 336.210148 -243.161058) (xy 335.948528 -243.161058) (xy 335.901538 -243.313458)
			(xy 335.901538 -243.357654) (xy 336.257138 -243.357654)
		)
		(stroke
			(width 0)
			(type solid)
		)
		(fill yes)
		(layer "In11.Cu")
		(net "M_D_CPU0_SB_CB<2>")
	)
	(gr_poly
		(pts
			(xy 336.257138 -241.276886) (xy 336.257138 -241.232436) (xy 335.901538 -241.232436) (xy 335.901538 -241.276886)
			(xy 335.948528 -241.429286) (xy 336.210148 -241.429286)
		)
		(stroke
			(width 0)
			(type solid)
		)
		(fill yes)
		(layer "In11.Cu")
		(net "M_D_CPU0_SB_DQ<1>")
	)
	(gr_poly
		(pts
			(xy 336.257138 -238.430054) (xy 336.210148 -238.277654) (xy 335.948528 -238.277654) (xy 335.901538 -238.430054)
			(xy 335.901538 -238.47425) (xy 336.257138 -238.47425)
		)
		(stroke
			(width 0)
			(type solid)
		)
		(fill yes)
		(layer "In11.Cu")
		(net "M_D_CPU0_SB_DQS_DP<5>")
	)
	(gr_poly
		(pts
			(xy 336.257138 -238.021114) (xy 336.257138 -237.976918) (xy 335.901538 -237.976918) (xy 335.901538 -238.021114)
			(xy 335.948528 -238.173514) (xy 336.210148 -238.173514)
		)
		(stroke
			(width 0)
			(type solid)
		)
		(fill yes)
		(layer "In11.Cu")
		(net "M_D_CPU0_SB_DQ<4>")
	)
	(gr_poly
		(pts
			(xy 336.257138 -233.54665) (xy 336.210148 -233.39425) (xy 335.948528 -233.39425) (xy 335.901538 -233.54665)
			(xy 335.901538 -233.590846) (xy 336.257138 -233.590846)
		)
		(stroke
			(width 0)
			(type solid)
		)
		(fill yes)
		(layer "In11.Cu")
		(net "M_D_CPU0_SB_DQ<11>")
	)
	(gr_poly
		(pts
			(xy 336.257138 -233.13771) (xy 336.257138 -233.093514) (xy 335.901538 -233.093514) (xy 335.901538 -233.13771)
			(xy 335.948528 -233.29011) (xy 336.210148 -233.29011)
		)
		(stroke
			(width 0)
			(type solid)
		)
		(fill yes)
		(layer "In11.Cu")
		(net "M_D_CPU0_SB_DQS_DP<1>")
	)
	(gr_poly
		(pts
			(xy 336.257138 -231.919018) (xy 336.210148 -231.766618) (xy 335.948528 -231.766618) (xy 335.901538 -231.919018)
			(xy 335.901538 -231.963214) (xy 336.257138 -231.963214)
		)
		(stroke
			(width 0)
			(type solid)
		)
		(fill yes)
		(layer "In11.Cu")
		(net "M_D_CPU0_SB_DQS_DP<6>")
	)
	(gr_poly
		(pts
			(xy 336.257138 -231.510078) (xy 336.257138 -231.465882) (xy 335.901538 -231.465882) (xy 335.901538 -231.510078)
			(xy 335.948528 -231.662478) (xy 336.210148 -231.662478)
		)
		(stroke
			(width 0)
			(type solid)
		)
		(fill yes)
		(layer "In11.Cu")
		(net "M_D_CPU0_SB_DQ<12>")
	)
	(gr_poly
		(pts
			(xy 336.257138 -228.663246) (xy 336.210148 -228.510846) (xy 335.948528 -228.510846) (xy 335.901538 -228.663246)
			(xy 335.901538 -228.707696) (xy 336.257138 -228.707696)
		)
		(stroke
			(width 0)
			(type solid)
		)
		(fill yes)
		(layer "In11.Cu")
		(net "M_D_CPU0_SB_DQ<27>")
	)
	(gr_poly
		(pts
			(xy 336.257138 -228.254814) (xy 336.257138 -228.210364) (xy 335.901538 -228.210364) (xy 335.901538 -228.254814)
			(xy 335.948528 -228.407214) (xy 336.210148 -228.407214)
		)
		(stroke
			(width 0)
			(type solid)
		)
		(fill yes)
		(layer "In11.Cu")
		(net "M_D_CPU0_SB_DQS_DP<3>")
	)
	(gr_poly
		(pts
			(xy 336.257138 -223.779842) (xy 336.210148 -223.627442) (xy 335.948528 -223.627442) (xy 335.901538 -223.779842)
			(xy 335.901538 -223.824292) (xy 336.257138 -223.824292)
		)
		(stroke
			(width 0)
			(type solid)
		)
		(fill yes)
		(layer "In11.Cu")
		(net "M_D_CPU0_SB_DQ<31>")
	)
	(gr_poly
		(pts
			(xy 336.263234 -236.393482) (xy 336.263234 -236.349286) (xy 335.907634 -236.349286) (xy 335.907634 -236.393482)
			(xy 335.954624 -236.545882) (xy 336.216244 -236.545882)
		)
		(stroke
			(width 0)
			(type solid)
		)
		(fill yes)
		(layer "In11.Cu")
		(net "M_D_CPU0_SB_DQ<5>")
	)
	(gr_poly
		(pts
			(xy 336.267044 -278.709628) (xy 336.22869 -278.68753) (xy 336.073242 -278.65197) (xy 335.942432 -278.878538)
			(xy 336.05089 -278.995378) (xy 336.089244 -279.017476)
		)
		(stroke
			(width 0)
			(type solid)
		)
		(fill yes)
		(layer "In11.Cu")
		(net "M_D_CPU0_SA_DQ<11>")
	)
	(gr_poly
		(pts
			(xy 336.366866 -276.098762) (xy 336.319876 -275.946362) (xy 336.058256 -275.946362) (xy 336.011266 -276.098762)
			(xy 336.011266 -276.143212) (xy 336.366866 -276.143212)
		)
		(stroke
			(width 0)
			(type solid)
		)
		(fill yes)
		(layer "In11.Cu")
		(net "M_D_CPU0_SA_DQ<14>")
	)
	(gr_poly
		(pts
			(xy 336.366866 -275.690584) (xy 336.366866 -275.646388) (xy 336.011266 -275.646388) (xy 336.011266 -275.690584)
			(xy 336.058256 -275.842984) (xy 336.319876 -275.842984)
		)
		(stroke
			(width 0)
			(type solid)
		)
		(fill yes)
		(layer "In11.Cu")
		(net "M_D_CPU0_SA_DQ<13>")
	)
	(gr_poly
		(pts
			(xy 336.372962 -274.47113) (xy 336.325972 -274.31873) (xy 336.064352 -274.31873) (xy 336.017362 -274.47113)
			(xy 336.017362 -274.51558) (xy 336.372962 -274.51558)
		)
		(stroke
			(width 0)
			(type solid)
		)
		(fill yes)
		(layer "In11.Cu")
		(net "M_D_CPU0_SA_DQ<18>")
	)
	(gr_poly
		(pts
			(xy 336.372962 -274.062698) (xy 336.372962 -274.018248) (xy 336.017362 -274.018248) (xy 336.017362 -274.062698)
			(xy 336.064352 -274.215098) (xy 336.325972 -274.215098)
		)
		(stroke
			(width 0)
			(type solid)
		)
		(fill yes)
		(layer "In11.Cu")
		(net "M_D_CPU0_SA_DQ<17>")
	)
	(gr_poly
		(pts
			(xy 336.372962 -271.215866) (xy 336.325972 -271.063466) (xy 336.064352 -271.063466) (xy 336.017362 -271.215866)
			(xy 336.017362 -271.260062) (xy 336.372962 -271.260062)
		)
		(stroke
			(width 0)
			(type solid)
		)
		(fill yes)
		(layer "In11.Cu")
		(net "M_D_CPU0_SA_DQ<22>")
	)
	(gr_poly
		(pts
			(xy 336.372962 -270.806926) (xy 336.372962 -270.76273) (xy 336.017362 -270.76273) (xy 336.017362 -270.806926)
			(xy 336.064352 -270.959326) (xy 336.325972 -270.959326)
		)
		(stroke
			(width 0)
			(type solid)
		)
		(fill yes)
		(layer "In11.Cu")
		(net "M_D_CPU0_SA_DQ<21>")
	)
	(gr_poly
		(pts
			(xy 336.372962 -269.587726) (xy 336.325972 -269.435326) (xy 336.064352 -269.435326) (xy 336.017362 -269.587726)
			(xy 336.017362 -269.632176) (xy 336.372962 -269.632176)
		)
		(stroke
			(width 0)
			(type solid)
		)
		(fill yes)
		(layer "In11.Cu")
		(net "M_D_CPU0_SA_DQ<26>")
	)
	(gr_poly
		(pts
			(xy 336.372962 -269.179294) (xy 336.372962 -269.134844) (xy 336.017362 -269.134844) (xy 336.017362 -269.179294)
			(xy 336.064352 -269.331694) (xy 336.325972 -269.331694)
		)
		(stroke
			(width 0)
			(type solid)
		)
		(fill yes)
		(layer "In11.Cu")
		(net "M_D_CPU0_SA_DQ<25>")
	)
	(gr_poly
		(pts
			(xy 336.372962 -267.960094) (xy 336.325972 -267.807694) (xy 336.064352 -267.807694) (xy 336.017362 -267.960094)
			(xy 336.017362 -268.004544) (xy 336.372962 -268.004544)
		)
		(stroke
			(width 0)
			(type solid)
		)
		(fill yes)
		(layer "In11.Cu")
		(net "M_D_CPU0_SA_DQS_DN<3>")
	)
	(gr_poly
		(pts
			(xy 336.372962 -267.551662) (xy 336.372962 -267.507212) (xy 336.017362 -267.507212) (xy 336.017362 -267.551662)
			(xy 336.064352 -267.704062) (xy 336.325972 -267.704062)
		)
		(stroke
			(width 0)
			(type solid)
		)
		(fill yes)
		(layer "In11.Cu")
		(net "M_D_CPU0_SA_DQS_DN<8>")
	)
	(gr_poly
		(pts
			(xy 336.372962 -266.332462) (xy 336.325972 -266.180062) (xy 336.064352 -266.180062) (xy 336.017362 -266.332462)
			(xy 336.017362 -266.376658) (xy 336.372962 -266.376658)
		)
		(stroke
			(width 0)
			(type solid)
		)
		(fill yes)
		(layer "In11.Cu")
		(net "M_D_CPU0_SA_DQ<30>")
	)
	(gr_poly
		(pts
			(xy 336.372962 -265.92403) (xy 336.372962 -265.87958) (xy 336.017362 -265.87958) (xy 336.017362 -265.92403)
			(xy 336.064352 -266.07643) (xy 336.325972 -266.07643)
		)
		(stroke
			(width 0)
			(type solid)
		)
		(fill yes)
		(layer "In11.Cu")
		(net "M_D_CPU0_SA_DQ<29>")
	)
	(gr_poly
		(pts
			(xy 336.372962 -264.70483) (xy 336.325972 -264.55243) (xy 336.064352 -264.55243) (xy 336.017362 -264.70483)
			(xy 336.017362 -264.749026) (xy 336.372962 -264.749026)
		)
		(stroke
			(width 0)
			(type solid)
		)
		(fill yes)
		(layer "In11.Cu")
		(net "M_D_CPU0_SA_CB<2>")
	)
	(gr_poly
		(pts
			(xy 336.372962 -264.29589) (xy 336.372962 -264.251694) (xy 336.017362 -264.251694) (xy 336.017362 -264.29589)
			(xy 336.064352 -264.44829) (xy 336.325972 -264.44829)
		)
		(stroke
			(width 0)
			(type solid)
		)
		(fill yes)
		(layer "In11.Cu")
		(net "M_D_CPU0_SA_CB<1>")
	)
	(gr_poly
		(pts
			(xy 336.372962 -263.07669) (xy 336.325972 -262.92429) (xy 336.064352 -262.92429) (xy 336.017362 -263.07669)
			(xy 336.017362 -263.12114) (xy 336.372962 -263.12114)
		)
		(stroke
			(width 0)
			(type solid)
		)
		(fill yes)
		(layer "In11.Cu")
		(net "M_D_CPU0_SA_DQS_DN<4>")
	)
	(gr_poly
		(pts
			(xy 336.372962 -262.668258) (xy 336.372962 -262.623808) (xy 336.017362 -262.623808) (xy 336.017362 -262.668258)
			(xy 336.064352 -262.820658) (xy 336.325972 -262.820658)
		)
		(stroke
			(width 0)
			(type solid)
		)
		(fill yes)
		(layer "In11.Cu")
		(net "M_D_CPU0_SA_DQS_DN<9>")
	)
	(gr_poly
		(pts
			(xy 336.372962 -261.449058) (xy 336.325972 -261.296658) (xy 336.064352 -261.296658) (xy 336.017362 -261.449058)
			(xy 336.017362 -261.493508) (xy 336.372962 -261.493508)
		)
		(stroke
			(width 0)
			(type solid)
		)
		(fill yes)
		(layer "In11.Cu")
		(net "M_D_CPU0_SA_CB<6>")
	)
	(gr_poly
		(pts
			(xy 336.372962 -261.040626) (xy 336.372962 -260.996176) (xy 336.017362 -260.996176) (xy 336.017362 -261.040626)
			(xy 336.064352 -261.193026) (xy 336.325972 -261.193026)
		)
		(stroke
			(width 0)
			(type solid)
		)
		(fill yes)
		(layer "In11.Cu")
		(net "M_D_CPU0_SA_CB<5>")
	)
	(gr_poly
		(pts
			(xy 336.372962 -259.412486) (xy 336.372962 -259.36829) (xy 336.017362 -259.36829) (xy 336.017362 -259.412486)
			(xy 336.064352 -259.564886) (xy 336.325972 -259.564886)
		)
		(stroke
			(width 0)
			(type solid)
		)
		(fill yes)
		(layer "In11.Cu")
		(net "M_D_CPU0_SA_CS_N<2>")
	)
	(gr_poly
		(pts
			(xy 336.372962 -258.193286) (xy 336.325972 -258.040886) (xy 336.064352 -258.040886) (xy 336.017362 -258.193286)
			(xy 336.017362 -258.237736) (xy 336.372962 -258.237736)
		)
		(stroke
			(width 0)
			(type solid)
		)
		(fill yes)
		(layer "In11.Cu")
		(net "M_D_CPU0_SA_CS_N<1>")
	)
	(gr_poly
		(pts
			(xy 336.372962 -257.784854) (xy 336.372962 -257.740404) (xy 336.017362 -257.740404) (xy 336.017362 -257.784854)
			(xy 336.064352 -257.937254) (xy 336.325972 -257.937254)
		)
		(stroke
			(width 0)
			(type solid)
		)
		(fill yes)
		(layer "In11.Cu")
		(net "M_D_CPU0_SA_CA<0>")
	)
	(gr_poly
		(pts
			(xy 336.372962 -256.565654) (xy 336.325972 -256.413254) (xy 336.064352 -256.413254) (xy 336.017362 -256.565654)
			(xy 336.017362 -256.610104) (xy 336.372962 -256.610104)
		)
		(stroke
			(width 0)
			(type solid)
		)
		(fill yes)
		(layer "In11.Cu")
		(net "M_D_CPU0_SA_CA<3>")
	)
	(gr_poly
		(pts
			(xy 336.372962 -256.157222) (xy 336.372962 -256.112772) (xy 336.017362 -256.112772) (xy 336.017362 -256.157222)
			(xy 336.064352 -256.309622) (xy 336.325972 -256.309622)
		)
		(stroke
			(width 0)
			(type solid)
		)
		(fill yes)
		(layer "In11.Cu")
		(net "M_D_CPU0_SA_CA<4>")
	)
	(gr_poly
		(pts
			(xy 336.379058 -272.843498) (xy 336.332068 -272.691098) (xy 336.070448 -272.691098) (xy 336.023458 -272.843498)
			(xy 336.023458 -272.887694) (xy 336.379058 -272.887694)
		)
		(stroke
			(width 0)
			(type solid)
		)
		(fill yes)
		(layer "In11.Cu")
		(net "M_D_CPU0_SA_DQS_DN<2>")
	)
	(gr_poly
		(pts
			(xy 336.379058 -272.435066) (xy 336.379058 -272.39087) (xy 336.023458 -272.39087) (xy 336.023458 -272.435066)
			(xy 336.070448 -272.587466) (xy 336.332068 -272.587466)
		)
		(stroke
			(width 0)
			(type solid)
		)
		(fill yes)
		(layer "In11.Cu")
		(net "M_D_CPU0_SA_DQS_DN<7>")
	)
	(gr_poly
		(pts
			(xy 336.447892 -279.422098) (xy 336.339434 -279.305258) (xy 336.30108 -279.28316) (xy 336.12328 -279.591008)
			(xy 336.161634 -279.613106) (xy 336.317082 -279.648666)
		)
		(stroke
			(width 0)
			(type solid)
		)
		(fill yes)
		(layer "In11.Cu")
		(net "M_D_CPU0_SA_DQ<9>")
	)
	(gr_poly
		(pts
			(xy 336.588862 -224.85223) (xy 336.627216 -224.830132) (xy 336.449416 -224.522284) (xy 336.411062 -224.544382)
			(xy 336.302604 -224.661222) (xy 336.433414 -224.88779)
		)
		(stroke
			(width 0)
			(type solid)
		)
		(fill yes)
		(layer "In11.Cu")
		(net "M_D_CPU0_SB_DQ<29>")
	)
	(gr_poly
		(pts
			(xy 336.589878 -239.504728) (xy 336.628232 -239.48263) (xy 336.450432 -239.174782) (xy 336.412078 -239.19688)
			(xy 336.30362 -239.31372) (xy 336.43443 -239.540288)
		)
		(stroke
			(width 0)
			(type solid)
		)
		(fill yes)
		(layer "In11.Cu")
		(net "M_D_CPU0_SB_DQS_DN<5>")
	)
	(gr_poly
		(pts
			(xy 336.589878 -234.621578) (xy 336.628232 -234.59948) (xy 336.450432 -234.291632) (xy 336.412078 -234.31373)
			(xy 336.30362 -234.43057) (xy 336.43443 -234.657138)
		)
		(stroke
			(width 0)
			(type solid)
		)
		(fill yes)
		(layer "In11.Cu")
		(net "M_D_CPU0_SB_DQ<9>")
	)
	(gr_poly
		(pts
			(xy 336.589878 -226.482656) (xy 336.628232 -226.460558) (xy 336.450432 -226.15271) (xy 336.412078 -226.174808)
			(xy 336.30362 -226.291648) (xy 336.43443 -226.518216)
		)
		(stroke
			(width 0)
			(type solid)
		)
		(fill yes)
		(layer "In11.Cu")
		(net "M_D_CPU0_SB_DQ<28>")
	)
	(gr_poly
		(pts
			(xy 336.697574 -225.858324) (xy 336.806032 -225.741484) (xy 336.675222 -225.514916) (xy 336.519774 -225.550476)
			(xy 336.48142 -225.572574) (xy 336.65922 -225.880422)
		)
		(stroke
			(width 0)
			(type solid)
		)
		(fill yes)
		(layer "In11.Cu")
		(net "M_D_CPU0_SB_DQ<30>")
	)
	(gr_poly
		(pts
			(xy 336.69859 -233.999278) (xy 336.807048 -233.882438) (xy 336.676238 -233.65587) (xy 336.52079 -233.69143)
			(xy 336.482436 -233.713528) (xy 336.660236 -234.021376)
		)
		(stroke
			(width 0)
			(type solid)
		)
		(fill yes)
		(layer "In11.Cu")
		(net "M_D_CPU0_SB_DQ<11>")
	)
	(gr_poly
		(pts
			(xy 336.703924 -238.891572) (xy 336.812382 -238.774732) (xy 336.681572 -238.548164) (xy 336.526124 -238.583724)
			(xy 336.48777 -238.605822) (xy 336.66557 -238.91367)
		)
		(stroke
			(width 0)
			(type solid)
		)
		(fill yes)
		(layer "In11.Cu")
		(net "M_D_CPU0_SB_DQS_DP<5>")
	)
	(gr_poly
		(pts
			(xy 336.703924 -224.241614) (xy 336.812382 -224.124774) (xy 336.681572 -223.898206) (xy 336.526124 -223.933766)
			(xy 336.48777 -223.955864) (xy 336.66557 -224.263712)
		)
		(stroke
			(width 0)
			(type solid)
		)
		(fill yes)
		(layer "In11.Cu")
		(net "M_D_CPU0_SB_DQ<31>")
	)
	(gr_poly
		(pts
			(xy 336.733134 -235.988098) (xy 336.686144 -235.835698) (xy 336.424524 -235.835698) (xy 336.377534 -235.988098)
			(xy 336.377534 -236.032548) (xy 336.733134 -236.032548)
		)
		(stroke
			(width 0)
			(type solid)
		)
		(fill yes)
		(layer "In11.Cu")
		(net "M_D_CPU0_SB_DQ<7>")
	)
	(gr_poly
		(pts
			(xy 336.736944 -279.523444) (xy 336.69859 -279.501346) (xy 336.543142 -279.465786) (xy 336.412332 -279.692354)
			(xy 336.52079 -279.809194) (xy 336.559144 -279.831292)
		)
		(stroke
			(width 0)
			(type solid)
		)
		(fill yes)
		(layer "In11.Cu")
		(net "M_D_CPU0_SA_DQ<10>")
	)
	(gr_poly
		(pts
			(xy 336.741516 -249.01017) (xy 336.694526 -248.85777) (xy 336.432906 -248.85777) (xy 336.385916 -249.01017)
			(xy 336.385916 -249.05462) (xy 336.741516 -249.05462)
		)
		(stroke
			(width 0)
			(type solid)
		)
		(fill yes)
		(layer "In11.Cu")
		(net "M_D_CPU0_SB_CA<3>")
	)
	(gr_poly
		(pts
			(xy 336.741516 -248.602246) (xy 336.741516 -248.557796) (xy 336.385916 -248.557796) (xy 336.385916 -248.602246)
			(xy 336.432906 -248.754646) (xy 336.694526 -248.754646)
		)
		(stroke
			(width 0)
			(type solid)
		)
		(fill yes)
		(layer "In11.Cu")
		(net "M_D_CPU0_SB_CA<4>")
	)
	(gr_poly
		(pts
			(xy 336.741516 -247.382538) (xy 336.694526 -247.230138) (xy 336.432906 -247.230138) (xy 336.385916 -247.382538)
			(xy 336.385916 -247.426734) (xy 336.741516 -247.426734)
		)
		(stroke
			(width 0)
			(type solid)
		)
		(fill yes)
		(layer "In11.Cu")
		(net "M_D_CPU0_SB_CA<6>")
	)
	(gr_poly
		(pts
			(xy 336.741516 -246.974106) (xy 336.741516 -246.92991) (xy 336.385916 -246.92991) (xy 336.385916 -246.974106)
			(xy 336.432906 -247.126506) (xy 336.694526 -247.126506)
		)
		(stroke
			(width 0)
			(type solid)
		)
		(fill yes)
		(layer "In11.Cu")
		(net "M_D_CPU0_SB_CB<4>")
	)
	(gr_poly
		(pts
			(xy 336.741516 -245.754906) (xy 336.694526 -245.602506) (xy 336.432906 -245.602506) (xy 336.385916 -245.754906)
			(xy 336.385916 -245.799102) (xy 336.741516 -245.799102)
		)
		(stroke
			(width 0)
			(type solid)
		)
		(fill yes)
		(layer "In11.Cu")
		(net "M_D_CPU0_SB_CB<7>")
	)
	(gr_poly
		(pts
			(xy 336.741516 -245.346474) (xy 336.741516 -245.302278) (xy 336.385916 -245.302278) (xy 336.385916 -245.346474)
			(xy 336.432906 -245.498874) (xy 336.694526 -245.498874)
		)
		(stroke
			(width 0)
			(type solid)
		)
		(fill yes)
		(layer "In11.Cu")
		(net "M_D_CPU0_SB_DQS_DP<9>")
	)
	(gr_poly
		(pts
			(xy 336.741516 -244.126766) (xy 336.694526 -243.974366) (xy 336.432906 -243.974366) (xy 336.385916 -244.126766)
			(xy 336.385916 -244.171216) (xy 336.741516 -244.171216)
		)
		(stroke
			(width 0)
			(type solid)
		)
		(fill yes)
		(layer "In11.Cu")
		(net "M_D_CPU0_SB_DQS_DP<4>")
	)
	(gr_poly
		(pts
			(xy 336.741516 -243.718842) (xy 336.741516 -243.674392) (xy 336.385916 -243.674392) (xy 336.385916 -243.718842)
			(xy 336.432906 -243.871242) (xy 336.694526 -243.871242)
		)
		(stroke
			(width 0)
			(type solid)
		)
		(fill yes)
		(layer "In11.Cu")
		(net "M_D_CPU0_SB_CB<0>")
	)
	(gr_poly
		(pts
			(xy 336.741516 -242.499134) (xy 336.694526 -242.346734) (xy 336.432906 -242.346734) (xy 336.385916 -242.499134)
			(xy 336.385916 -242.54333) (xy 336.741516 -242.54333)
		)
		(stroke
			(width 0)
			(type solid)
		)
		(fill yes)
		(layer "In11.Cu")
		(net "M_D_CPU0_SB_CB<3>")
	)
	(gr_poly
		(pts
			(xy 336.741516 -242.090702) (xy 336.741516 -242.046506) (xy 336.385916 -242.046506) (xy 336.385916 -242.090702)
			(xy 336.432906 -242.243102) (xy 336.694526 -242.243102)
		)
		(stroke
			(width 0)
			(type solid)
		)
		(fill yes)
		(layer "In11.Cu")
		(net "M_D_CPU0_SB_DQ<0>")
	)
	(gr_poly
		(pts
			(xy 336.741516 -240.871502) (xy 336.694526 -240.719102) (xy 336.432906 -240.719102) (xy 336.385916 -240.871502)
			(xy 336.385916 -240.915698) (xy 336.741516 -240.915698)
		)
		(stroke
			(width 0)
			(type solid)
		)
		(fill yes)
		(layer "In11.Cu")
		(net "M_D_CPU0_SB_DQ<3>")
	)
	(gr_poly
		(pts
			(xy 336.741516 -240.46307) (xy 336.741516 -240.418874) (xy 336.385916 -240.418874) (xy 336.385916 -240.46307)
			(xy 336.432906 -240.61547) (xy 336.694526 -240.61547)
		)
		(stroke
			(width 0)
			(type solid)
		)
		(fill yes)
		(layer "In11.Cu")
		(net "M_D_CPU0_SB_DQS_DP<0>")
	)
	(gr_poly
		(pts
			(xy 336.741516 -237.61573) (xy 336.694526 -237.46333) (xy 336.432906 -237.46333) (xy 336.385916 -237.61573)
			(xy 336.385916 -237.659926) (xy 336.741516 -237.659926)
		)
		(stroke
			(width 0)
			(type solid)
		)
		(fill yes)
		(layer "In11.Cu")
		(net "M_D_CPU0_SB_DQ<6>")
	)
	(gr_poly
		(pts
			(xy 336.741516 -235.579666) (xy 336.741516 -235.53547) (xy 336.385916 -235.53547) (xy 336.385916 -235.579666)
			(xy 336.432906 -235.732066) (xy 336.694526 -235.732066)
		)
		(stroke
			(width 0)
			(type solid)
		)
		(fill yes)
		(layer "In11.Cu")
		(net "M_D_CPU0_SB_DQ<8>")
	)
	(gr_poly
		(pts
			(xy 336.741516 -232.732326) (xy 336.694526 -232.579926) (xy 336.432906 -232.579926) (xy 336.385916 -232.732326)
			(xy 336.385916 -232.776776) (xy 336.741516 -232.776776)
		)
		(stroke
			(width 0)
			(type solid)
		)
		(fill yes)
		(layer "In11.Cu")
		(net "M_D_CPU0_SB_DQS_DN<1>")
	)
	(gr_poly
		(pts
			(xy 336.741516 -232.324402) (xy 336.741516 -232.279952) (xy 336.385916 -232.279952) (xy 336.385916 -232.324402)
			(xy 336.432906 -232.476802) (xy 336.694526 -232.476802)
		)
		(stroke
			(width 0)
			(type solid)
		)
		(fill yes)
		(layer "In11.Cu")
		(net "M_D_CPU0_SB_DQS_DN<6>")
	)
	(gr_poly
		(pts
			(xy 336.741516 -231.104694) (xy 336.694526 -230.952294) (xy 336.432906 -230.952294) (xy 336.385916 -231.104694)
			(xy 336.385916 -231.14889) (xy 336.741516 -231.14889)
		)
		(stroke
			(width 0)
			(type solid)
		)
		(fill yes)
		(layer "In11.Cu")
		(net "M_D_CPU0_SB_DQ<14>")
	)
	(gr_poly
		(pts
			(xy 336.741516 -230.696262) (xy 336.741516 -230.652066) (xy 336.385916 -230.652066) (xy 336.385916 -230.696262)
			(xy 336.432906 -230.848662) (xy 336.694526 -230.848662)
		)
		(stroke
			(width 0)
			(type solid)
		)
		(fill yes)
		(layer "In11.Cu")
		(net "M_D_CPU0_SB_DQ<13>")
	)
	(gr_poly
		(pts
			(xy 336.741516 -229.477062) (xy 336.694526 -229.324662) (xy 336.432906 -229.324662) (xy 336.385916 -229.477062)
			(xy 336.385916 -229.521258) (xy 336.741516 -229.521258)
		)
		(stroke
			(width 0)
			(type solid)
		)
		(fill yes)
		(layer "In11.Cu")
		(net "M_D_CPU0_SB_DQ<26>")
	)
	(gr_poly
		(pts
			(xy 336.741516 -229.06863) (xy 336.741516 -229.024434) (xy 336.385916 -229.024434) (xy 336.385916 -229.06863)
			(xy 336.432906 -229.22103) (xy 336.694526 -229.22103)
		)
		(stroke
			(width 0)
			(type solid)
		)
		(fill yes)
		(layer "In11.Cu")
		(net "M_D_CPU0_SB_DQ<25>")
	)
	(gr_poly
		(pts
			(xy 336.741516 -227.848922) (xy 336.694526 -227.696522) (xy 336.432906 -227.696522) (xy 336.385916 -227.848922)
			(xy 336.385916 -227.893372) (xy 336.741516 -227.893372)
		)
		(stroke
			(width 0)
			(type solid)
		)
		(fill yes)
		(layer "In11.Cu")
		(net "M_D_CPU0_SB_DQS_DN<3>")
	)
	(gr_poly
		(pts
			(xy 336.741516 -227.440998) (xy 336.741516 -227.396548) (xy 336.385916 -227.396548) (xy 336.385916 -227.440998)
			(xy 336.432906 -227.593398) (xy 336.694526 -227.593398)
		)
		(stroke
			(width 0)
			(type solid)
		)
		(fill yes)
		(layer "In11.Cu")
		(net "M_D_CPU0_SB_DQS_DN<8>")
	)
	(gr_poly
		(pts
			(xy 336.83448 -273.248882) (xy 336.83448 -273.204686) (xy 336.47888 -273.204686) (xy 336.47888 -273.248882)
			(xy 336.52587 -273.401282) (xy 336.78749 -273.401282)
		)
		(stroke
			(width 0)
			(type solid)
		)
		(fill yes)
		(layer "In11.Cu")
		(net "M_D_CPU0_SA_DQS_DP<2>")
	)
	(gr_poly
		(pts
			(xy 336.83702 -272.029174) (xy 336.79003 -271.876774) (xy 336.52841 -271.876774) (xy 336.48142 -272.029174)
			(xy 336.48142 -272.073624) (xy 336.83702 -272.073624)
		)
		(stroke
			(width 0)
			(type solid)
		)
		(fill yes)
		(layer "In11.Cu")
		(net "M_D_CPU0_SA_DQS_DP<7>")
	)
	(gr_poly
		(pts
			(xy 336.842862 -278.540718) (xy 336.795872 -278.388318) (xy 336.534252 -278.388318) (xy 336.487262 -278.540718)
			(xy 336.487262 -278.585168) (xy 336.842862 -278.585168)
		)
		(stroke
			(width 0)
			(type solid)
		)
		(fill yes)
		(layer "In11.Cu")
		(net "M_D_CPU0_SA_DQ<11>")
	)
	(gr_poly
		(pts
			(xy 336.842862 -276.504146) (xy 336.842862 -276.45995) (xy 336.487262 -276.45995) (xy 336.487262 -276.504146)
			(xy 336.534252 -276.656546) (xy 336.795872 -276.656546)
		)
		(stroke
			(width 0)
			(type solid)
		)
		(fill yes)
		(layer "In11.Cu")
		(net "M_D_CPU0_SA_DQ<12>")
	)
	(gr_poly
		(pts
			(xy 336.842862 -275.284946) (xy 336.795872 -275.132546) (xy 336.534252 -275.132546) (xy 336.487262 -275.284946)
			(xy 336.487262 -275.329396) (xy 336.842862 -275.329396)
		)
		(stroke
			(width 0)
			(type solid)
		)
		(fill yes)
		(layer "In11.Cu")
		(net "M_D_CPU0_SA_DQ<15>")
	)
	(gr_poly
		(pts
			(xy 336.842862 -274.876514) (xy 336.842862 -274.832064) (xy 336.487262 -274.832064) (xy 336.487262 -274.876514)
			(xy 336.534252 -275.028914) (xy 336.795872 -275.028914)
		)
		(stroke
			(width 0)
			(type solid)
		)
		(fill yes)
		(layer "In11.Cu")
		(net "M_D_CPU0_SA_DQ<16>")
	)
	(gr_poly
		(pts
			(xy 336.842862 -273.657314) (xy 336.795872 -273.504914) (xy 336.534252 -273.504914) (xy 336.487262 -273.657314)
			(xy 336.487262 -273.701764) (xy 336.842862 -273.701764)
		)
		(stroke
			(width 0)
			(type solid)
		)
		(fill yes)
		(layer "In11.Cu")
		(net "M_D_CPU0_SA_DQ<19>")
	)
	(gr_poly
		(pts
			(xy 336.842862 -270.40205) (xy 336.795872 -270.24965) (xy 336.534252 -270.24965) (xy 336.487262 -270.40205)
			(xy 336.487262 -270.446246) (xy 336.842862 -270.446246)
		)
		(stroke
			(width 0)
			(type solid)
		)
		(fill yes)
		(layer "In11.Cu")
		(net "M_D_CPU0_SA_DQ<23>")
	)
	(gr_poly
		(pts
			(xy 336.842862 -269.99311) (xy 336.842862 -269.948914) (xy 336.487262 -269.948914) (xy 336.487262 -269.99311)
			(xy 336.534252 -270.14551) (xy 336.795872 -270.14551)
		)
		(stroke
			(width 0)
			(type solid)
		)
		(fill yes)
		(layer "In11.Cu")
		(net "M_D_CPU0_SA_DQ<24>")
	)
	(gr_poly
		(pts
			(xy 336.842862 -268.77391) (xy 336.795872 -268.62151) (xy 336.534252 -268.62151) (xy 336.487262 -268.77391)
			(xy 336.487262 -268.81836) (xy 336.842862 -268.81836)
		)
		(stroke
			(width 0)
			(type solid)
		)
		(fill yes)
		(layer "In11.Cu")
		(net "M_D_CPU0_SA_DQ<27>")
	)
	(gr_poly
		(pts
			(xy 336.842862 -268.365478) (xy 336.842862 -268.321028) (xy 336.487262 -268.321028) (xy 336.487262 -268.365478)
			(xy 336.534252 -268.517878) (xy 336.795872 -268.517878)
		)
		(stroke
			(width 0)
			(type solid)
		)
		(fill yes)
		(layer "In11.Cu")
		(net "M_D_CPU0_SA_DQS_DP<3>")
	)
	(gr_poly
		(pts
			(xy 336.842862 -267.146786) (xy 336.795872 -266.994386) (xy 336.534252 -266.994386) (xy 336.487262 -267.146786)
			(xy 336.487262 -267.191236) (xy 336.842862 -267.191236)
		)
		(stroke
			(width 0)
			(type solid)
		)
		(fill yes)
		(layer "In11.Cu")
		(net "M_D_CPU0_SA_DQS_DP<8>")
	)
	(gr_poly
		(pts
			(xy 336.842862 -266.737846) (xy 336.842862 -266.693396) (xy 336.487262 -266.693396) (xy 336.487262 -266.737846)
			(xy 336.534252 -266.890246) (xy 336.795872 -266.890246)
		)
		(stroke
			(width 0)
			(type solid)
		)
		(fill yes)
		(layer "In11.Cu")
		(net "M_D_CPU0_SA_DQ<28>")
	)
	(gr_poly
		(pts
			(xy 336.842862 -265.518646) (xy 336.795872 -265.366246) (xy 336.534252 -265.366246) (xy 336.487262 -265.518646)
			(xy 336.487262 -265.562842) (xy 336.842862 -265.562842)
		)
		(stroke
			(width 0)
			(type solid)
		)
		(fill yes)
		(layer "In11.Cu")
		(net "M_D_CPU0_SA_DQ<31>")
	)
	(gr_poly
		(pts
			(xy 336.842862 -265.109706) (xy 336.842862 -265.06551) (xy 336.487262 -265.06551) (xy 336.487262 -265.109706)
			(xy 336.534252 -265.262106) (xy 336.795872 -265.262106)
		)
		(stroke
			(width 0)
			(type solid)
		)
		(fill yes)
		(layer "In11.Cu")
		(net "M_D_CPU0_SA_CB<0>")
	)
	(gr_poly
		(pts
			(xy 336.842862 -263.891014) (xy 336.795872 -263.738614) (xy 336.534252 -263.738614) (xy 336.487262 -263.891014)
			(xy 336.487262 -263.93521) (xy 336.842862 -263.93521)
		)
		(stroke
			(width 0)
			(type solid)
		)
		(fill yes)
		(layer "In11.Cu")
		(net "M_D_CPU0_SA_CB<3>")
	)
	(gr_poly
		(pts
			(xy 336.842862 -263.482074) (xy 336.842862 -263.437878) (xy 336.487262 -263.437878) (xy 336.487262 -263.482074)
			(xy 336.534252 -263.634474) (xy 336.795872 -263.634474)
		)
		(stroke
			(width 0)
			(type solid)
		)
		(fill yes)
		(layer "In11.Cu")
		(net "M_D_CPU0_SA_DQS_DP<4>")
	)
	(gr_poly
		(pts
			(xy 336.842862 -259.00761) (xy 336.795872 -258.85521) (xy 336.534252 -258.85521) (xy 336.487262 -259.00761)
			(xy 336.487262 -259.051806) (xy 336.842862 -259.051806)
		)
		(stroke
			(width 0)
			(type solid)
		)
		(fill yes)
		(layer "In11.Cu")
		(net "M_D_CPU0_SA_CS_N<0>")
	)
	(gr_poly
		(pts
			(xy 336.842862 -258.59867) (xy 336.842862 -258.554474) (xy 336.487262 -258.554474) (xy 336.487262 -258.59867)
			(xy 336.534252 -258.75107) (xy 336.795872 -258.75107)
		)
		(stroke
			(width 0)
			(type solid)
		)
		(fill yes)
		(layer "In11.Cu")
		(net "M_D_CPU0_SA_CS_N<3>")
	)
	(gr_poly
		(pts
			(xy 336.842862 -257.37947) (xy 336.795872 -257.22707) (xy 336.534252 -257.22707) (xy 336.487262 -257.37947)
			(xy 336.487262 -257.42392) (xy 336.842862 -257.42392)
		)
		(stroke
			(width 0)
			(type solid)
		)
		(fill yes)
		(layer "In11.Cu")
		(net "M_D_CPU0_SA_CA<1>")
	)
	(gr_poly
		(pts
			(xy 336.842862 -256.971038) (xy 336.842862 -256.926588) (xy 336.487262 -256.926588) (xy 336.487262 -256.971038)
			(xy 336.534252 -257.123438) (xy 336.795872 -257.123438)
		)
		(stroke
			(width 0)
			(type solid)
		)
		(fill yes)
		(layer "In11.Cu")
		(net "M_D_CPU0_SA_CA<2>")
	)
	(gr_poly
		(pts
			(xy 336.848958 -271.62125) (xy 336.848958 -271.5768) (xy 336.493358 -271.5768) (xy 336.493358 -271.62125)
			(xy 336.540348 -271.77365) (xy 336.801968 -271.77365)
		)
		(stroke
			(width 0)
			(type solid)
		)
		(fill yes)
		(layer "In11.Cu")
		(net "M_D_CPU0_SA_DQ<20>")
	)
	(gr_poly
		(pts
			(xy 336.848958 -262.262874) (xy 336.801968 -262.110474) (xy 336.540348 -262.110474) (xy 336.493358 -262.262874)
			(xy 336.493358 -262.30707) (xy 336.848958 -262.30707)
		)
		(stroke
			(width 0)
			(type solid)
		)
		(fill yes)
		(layer "In11.Cu")
		(net "M_D_CPU0_SA_DQS_DP<9>")
	)
	(gr_poly
		(pts
			(xy 336.848958 -261.854442) (xy 336.848958 -261.810246) (xy 336.493358 -261.810246) (xy 336.493358 -261.854442)
			(xy 336.540348 -262.006842) (xy 336.801968 -262.006842)
		)
		(stroke
			(width 0)
			(type solid)
		)
		(fill yes)
		(layer "In11.Cu")
		(net "M_D_CPU0_SA_CB<4>")
	)
	(gr_poly
		(pts
			(xy 336.848958 -260.634734) (xy 336.801968 -260.482334) (xy 336.540348 -260.482334) (xy 336.493358 -260.634734)
			(xy 336.493358 -260.679184) (xy 336.848958 -260.679184)
		)
		(stroke
			(width 0)
			(type solid)
		)
		(fill yes)
		(layer "In11.Cu")
		(net "M_D_CPU0_SA_CB<7>")
	)
	(gr_poly
		(pts
			(xy 336.848958 -255.751838) (xy 336.801968 -255.599438) (xy 336.540348 -255.599438) (xy 336.493358 -255.751838)
			(xy 336.493358 -255.796034) (xy 336.848958 -255.796034)
		)
		(stroke
			(width 0)
			(type solid)
		)
		(fill yes)
		(layer "In11.Cu")
		(net "M_D_CPU0_SA_CA<5>")
	)
	(gr_poly
		(pts
			(xy 336.851244 -278.132286) (xy 336.851244 -278.08809) (xy 336.495644 -278.08809) (xy 336.495644 -278.132286)
			(xy 336.542634 -278.284686) (xy 336.804254 -278.284686)
		)
		(stroke
			(width 0)
			(type solid)
		)
		(fill yes)
		(layer "In11.Cu")
		(net "M_D_CPU0_SA_DQS_DP<1>")
	)
	(gr_poly
		(pts
			(xy 336.851244 -276.912578) (xy 336.804254 -276.760178) (xy 336.542634 -276.760178) (xy 336.495644 -276.912578)
			(xy 336.495644 -276.957028) (xy 336.851244 -276.957028)
		)
		(stroke
			(width 0)
			(type solid)
		)
		(fill yes)
		(layer "In11.Cu")
		(net "M_D_CPU0_SA_DQS_DP<6>")
	)
	(gr_poly
		(pts
			(xy 337.05419 -238.68126) (xy 337.092544 -238.659162) (xy 336.914744 -238.351314) (xy 336.87639 -238.373412)
			(xy 336.767932 -238.490252) (xy 336.898742 -238.71682)
		)
		(stroke
			(width 0)
			(type solid)
		)
		(fill yes)
		(layer "In11.Cu")
		(net "M_D_CPU0_SB_DQ<4>")
	)
	(gr_poly
		(pts
			(xy 337.05419 -237.053628) (xy 337.092544 -237.03153) (xy 336.914744 -236.723682) (xy 336.87639 -236.74578)
			(xy 336.767932 -236.86262) (xy 336.898742 -237.089188)
		)
		(stroke
			(width 0)
			(type solid)
		)
		(fill yes)
		(layer "In11.Cu")
		(net "M_D_CPU0_SB_DQ<5>")
	)
	(gr_poly
		(pts
			(xy 337.059524 -233.807) (xy 337.097878 -233.784902) (xy 336.920078 -233.477054) (xy 336.881724 -233.499152)
			(xy 336.773266 -233.615992) (xy 336.904076 -233.84256)
		)
		(stroke
			(width 0)
			(type solid)
		)
		(fill yes)
		(layer "In11.Cu")
		(net "M_D_CPU0_SB_DQS_DP<1>")
	)
	(gr_poly
		(pts
			(xy 337.059524 -225.668078) (xy 337.097878 -225.64598) (xy 336.920078 -225.338132) (xy 336.881724 -225.36023)
			(xy 336.773266 -225.47707) (xy 336.904076 -225.703638)
		)
		(stroke
			(width 0)
			(type solid)
		)
		(fill yes)
		(layer "In11.Cu")
		(net "M_D_CPU0_SB_DQ<29>")
	)
	(gr_poly
		(pts
			(xy 337.166458 -238.06658) (xy 337.274916 -237.94974) (xy 337.144106 -237.723172) (xy 336.988658 -237.758732)
			(xy 336.950304 -237.78083) (xy 337.128104 -238.088678)
		)
		(stroke
			(width 0)
			(type solid)
		)
		(fill yes)
		(layer "In11.Cu")
		(net "M_D_CPU0_SB_DQ<6>")
	)
	(gr_poly
		(pts
			(xy 337.167474 -236.438948) (xy 337.275932 -236.322108) (xy 337.145122 -236.09554) (xy 336.989674 -236.1311)
			(xy 336.95132 -236.153198) (xy 337.12912 -236.461046)
		)
		(stroke
			(width 0)
			(type solid)
		)
		(fill yes)
		(layer "In11.Cu")
		(net "M_D_CPU0_SB_DQ<7>")
	)
	(gr_poly
		(pts
			(xy 337.168236 -233.1847) (xy 337.276694 -233.06786) (xy 337.145884 -232.841292) (xy 336.990436 -232.876852)
			(xy 336.952082 -232.89895) (xy 337.129882 -233.206798)
		)
		(stroke
			(width 0)
			(type solid)
		)
		(fill yes)
		(layer "In11.Cu")
		(net "M_D_CPU0_SB_DQS_DN<1>")
	)
	(gr_poly
		(pts
			(xy 337.169506 -225.048318) (xy 337.277964 -224.931478) (xy 337.147154 -224.70491) (xy 336.991706 -224.74047)
			(xy 336.953352 -224.762568) (xy 337.131152 -225.070416)
		)
		(stroke
			(width 0)
			(type solid)
		)
		(fill yes)
		(layer "In11.Cu")
		(net "M_D_CPU0_SB_DQ<31>")
	)
	(gr_poly
		(pts
			(xy 337.194398 -249.416062) (xy 337.194398 -249.371612) (xy 336.838798 -249.371612) (xy 336.838798 -249.416062)
			(xy 336.885788 -249.568462) (xy 337.147408 -249.568462)
		)
		(stroke
			(width 0)
			(type solid)
		)
		(fill yes)
		(layer "In11.Cu")
		(net "M_D_CPU0_SB_CA<2>")
	)
	(gr_poly
		(pts
			(xy 337.194398 -246.568722) (xy 337.147408 -246.416322) (xy 336.885788 -246.416322) (xy 336.838798 -246.568722)
			(xy 336.838798 -246.612918) (xy 337.194398 -246.612918)
		)
		(stroke
			(width 0)
			(type solid)
		)
		(fill yes)
		(layer "In11.Cu")
		(net "M_D_CPU0_SB_CB<6>")
	)
	(gr_poly
		(pts
			(xy 337.194398 -246.16029) (xy 337.194398 -246.116094) (xy 336.838798 -246.116094) (xy 336.838798 -246.16029)
			(xy 336.885788 -246.31269) (xy 337.147408 -246.31269)
		)
		(stroke
			(width 0)
			(type solid)
		)
		(fill yes)
		(layer "In11.Cu")
		(net "M_D_CPU0_SB_CB<5>")
	)
	(gr_poly
		(pts
			(xy 337.194398 -244.940582) (xy 337.147408 -244.788182) (xy 336.885788 -244.788182) (xy 336.838798 -244.940582)
			(xy 336.838798 -244.985032) (xy 337.194398 -244.985032)
		)
		(stroke
			(width 0)
			(type solid)
		)
		(fill yes)
		(layer "In11.Cu")
		(net "M_D_CPU0_SB_DQS_DN<9>")
	)
	(gr_poly
		(pts
			(xy 337.194398 -244.532658) (xy 337.194398 -244.488208) (xy 336.838798 -244.488208) (xy 336.838798 -244.532658)
			(xy 336.885788 -244.685058) (xy 337.147408 -244.685058)
		)
		(stroke
			(width 0)
			(type solid)
		)
		(fill yes)
		(layer "In11.Cu")
		(net "M_D_CPU0_SB_DQS_DN<4>")
	)
	(gr_poly
		(pts
			(xy 337.194398 -243.31295) (xy 337.147408 -243.16055) (xy 336.885788 -243.16055) (xy 336.838798 -243.31295)
			(xy 336.838798 -243.3574) (xy 337.194398 -243.3574)
		)
		(stroke
			(width 0)
			(type solid)
		)
		(fill yes)
		(layer "In11.Cu")
		(net "M_D_CPU0_SB_CB<2>")
	)
	(gr_poly
		(pts
			(xy 337.194398 -242.905026) (xy 337.194398 -242.860576) (xy 336.838798 -242.860576) (xy 336.838798 -242.905026)
			(xy 336.885788 -243.057426) (xy 337.147408 -243.057426)
		)
		(stroke
			(width 0)
			(type solid)
		)
		(fill yes)
		(layer "In11.Cu")
		(net "M_D_CPU0_SB_CB<1>")
	)
	(gr_poly
		(pts
			(xy 337.194398 -241.685318) (xy 337.147408 -241.532918) (xy 336.885788 -241.532918) (xy 336.838798 -241.685318)
			(xy 336.838798 -241.729514) (xy 337.194398 -241.729514)
		)
		(stroke
			(width 0)
			(type solid)
		)
		(fill yes)
		(layer "In11.Cu")
		(net "M_D_CPU0_SB_DQ<2>")
	)
	(gr_poly
		(pts
			(xy 337.194398 -241.276886) (xy 337.194398 -241.23269) (xy 336.838798 -241.23269) (xy 336.838798 -241.276886)
			(xy 336.885788 -241.429286) (xy 337.147408 -241.429286)
		)
		(stroke
			(width 0)
			(type solid)
		)
		(fill yes)
		(layer "In11.Cu")
		(net "M_D_CPU0_SB_DQ<1>")
	)
	(gr_poly
		(pts
			(xy 337.194398 -240.057178) (xy 337.147408 -239.904778) (xy 336.885788 -239.904778) (xy 336.838798 -240.057178)
			(xy 336.838798 -240.101628) (xy 337.194398 -240.101628)
		)
		(stroke
			(width 0)
			(type solid)
		)
		(fill yes)
		(layer "In11.Cu")
		(net "M_D_CPU0_SB_DQS_DN<0>")
	)
	(gr_poly
		(pts
			(xy 337.194398 -239.649254) (xy 337.194398 -239.604804) (xy 336.838798 -239.604804) (xy 336.838798 -239.649254)
			(xy 336.885788 -239.801654) (xy 337.147408 -239.801654)
		)
		(stroke
			(width 0)
			(type solid)
		)
		(fill yes)
		(layer "In11.Cu")
		(net "M_D_CPU0_SB_DQS_DN<5>")
	)
	(gr_poly
		(pts
			(xy 337.194398 -235.174282) (xy 337.147408 -235.021882) (xy 336.885788 -235.021882) (xy 336.838798 -235.174282)
			(xy 336.838798 -235.218478) (xy 337.194398 -235.218478)
		)
		(stroke
			(width 0)
			(type solid)
		)
		(fill yes)
		(layer "In11.Cu")
		(net "M_D_CPU0_SB_DQ<10>")
	)
	(gr_poly
		(pts
			(xy 337.194398 -234.76585) (xy 337.194398 -234.721654) (xy 336.838798 -234.721654) (xy 336.838798 -234.76585)
			(xy 336.885788 -234.91825) (xy 337.147408 -234.91825)
		)
		(stroke
			(width 0)
			(type solid)
		)
		(fill yes)
		(layer "In11.Cu")
		(net "M_D_CPU0_SB_DQ<9>")
	)
	(gr_poly
		(pts
			(xy 337.194398 -231.510586) (xy 337.194398 -231.466136) (xy 336.838798 -231.466136) (xy 336.838798 -231.510586)
			(xy 336.885788 -231.662986) (xy 337.147408 -231.662986)
		)
		(stroke
			(width 0)
			(type solid)
		)
		(fill yes)
		(layer "In11.Cu")
		(net "M_D_CPU0_SB_DQ<12>")
	)
	(gr_poly
		(pts
			(xy 337.194398 -230.290878) (xy 337.147408 -230.138478) (xy 336.885788 -230.138478) (xy 336.838798 -230.290878)
			(xy 336.838798 -230.335074) (xy 337.194398 -230.335074)
		)
		(stroke
			(width 0)
			(type solid)
		)
		(fill yes)
		(layer "In11.Cu")
		(net "M_D_CPU0_SB_DQ<15>")
	)
	(gr_poly
		(pts
			(xy 337.194398 -229.882446) (xy 337.194398 -229.83825) (xy 336.838798 -229.83825) (xy 336.838798 -229.882446)
			(xy 336.885788 -230.034846) (xy 337.147408 -230.034846)
		)
		(stroke
			(width 0)
			(type solid)
		)
		(fill yes)
		(layer "In11.Cu")
		(net "M_D_CPU0_SB_DQ<24>")
	)
	(gr_poly
		(pts
			(xy 337.194398 -228.663246) (xy 337.147408 -228.510846) (xy 336.885788 -228.510846) (xy 336.838798 -228.663246)
			(xy 336.838798 -228.707442) (xy 337.194398 -228.707442)
		)
		(stroke
			(width 0)
			(type solid)
		)
		(fill yes)
		(layer "In11.Cu")
		(net "M_D_CPU0_SB_DQ<27>")
	)
	(gr_poly
		(pts
			(xy 337.194398 -228.254814) (xy 337.194398 -228.210618) (xy 336.838798 -228.210618) (xy 336.838798 -228.254814)
			(xy 336.885788 -228.407214) (xy 337.147408 -228.407214)
		)
		(stroke
			(width 0)
			(type solid)
		)
		(fill yes)
		(layer "In11.Cu")
		(net "M_D_CPU0_SB_DQS_DP<3>")
	)
	(gr_poly
		(pts
			(xy 337.194398 -227.035106) (xy 337.147408 -226.882706) (xy 336.885788 -226.882706) (xy 336.838798 -227.035106)
			(xy 336.838798 -227.079556) (xy 337.194398 -227.079556)
		)
		(stroke
			(width 0)
			(type solid)
		)
		(fill yes)
		(layer "In11.Cu")
		(net "M_D_CPU0_SB_DQS_DP<8>")
	)
	(gr_poly
		(pts
			(xy 337.194398 -226.627182) (xy 337.194398 -226.582732) (xy 336.838798 -226.582732) (xy 336.838798 -226.627182)
			(xy 336.885788 -226.779582) (xy 337.147408 -226.779582)
		)
		(stroke
			(width 0)
			(type solid)
		)
		(fill yes)
		(layer "In11.Cu")
		(net "M_D_CPU0_SB_DQ<28>")
	)
	(gr_poly
		(pts
			(xy 337.196938 -248.196354) (xy 337.149948 -248.043954) (xy 336.888328 -248.043954) (xy 336.841338 -248.196354)
			(xy 336.841338 -248.24055) (xy 337.196938 -248.24055)
		)
		(stroke
			(width 0)
			(type solid)
		)
		(fill yes)
		(layer "In11.Cu")
		(net "M_D_CPU0_SB_CA<5>")
	)
	(gr_poly
		(pts
			(xy 337.196938 -247.787922) (xy 337.196938 -247.743726) (xy 336.841338 -247.743726) (xy 336.841338 -247.787922)
			(xy 336.888328 -247.940322) (xy 337.149948 -247.940322)
		)
		(stroke
			(width 0)
			(type solid)
		)
		(fill yes)
		(layer "In11.Cu")
		(net "M_D_CPU0_SB_PAR")
	)
	(gr_poly
		(pts
			(xy 337.203288 -231.919018) (xy 337.156298 -231.766618) (xy 336.894678 -231.766618) (xy 336.847688 -231.919018)
			(xy 336.847688 -231.963214) (xy 337.203288 -231.963214)
		)
		(stroke
			(width 0)
			(type solid)
		)
		(fill yes)
		(layer "In11.Cu")
		(net "M_D_CPU0_SB_DQS_DP<6>")
	)
	(gr_poly
		(pts
			(xy 337.30438 -271.215358) (xy 337.25739 -271.062958) (xy 336.99577 -271.062958) (xy 336.94878 -271.215358)
			(xy 336.94878 -271.259808) (xy 337.30438 -271.259808)
		)
		(stroke
			(width 0)
			(type solid)
		)
		(fill yes)
		(layer "In11.Cu")
		(net "M_D_CPU0_SA_DQ<22>")
	)
	(gr_poly
		(pts
			(xy 337.30438 -261.44855) (xy 337.25739 -261.29615) (xy 336.99577 -261.29615) (xy 336.94878 -261.44855)
			(xy 336.94878 -261.493) (xy 337.30438 -261.493)
		)
		(stroke
			(width 0)
			(type solid)
		)
		(fill yes)
		(layer "In11.Cu")
		(net "M_D_CPU0_SA_CB<6>")
	)
	(gr_poly
		(pts
			(xy 337.30438 -261.040626) (xy 337.30438 -260.99643) (xy 336.94878 -260.99643) (xy 336.94878 -261.040626)
			(xy 336.99577 -261.193026) (xy 337.25739 -261.193026)
		)
		(stroke
			(width 0)
			(type solid)
		)
		(fill yes)
		(layer "In11.Cu")
		(net "M_D_CPU0_SA_CB<5>")
	)
	(gr_poly
		(pts
			(xy 337.30438 -256.157222) (xy 337.30438 -256.113026) (xy 336.94878 -256.113026) (xy 336.94878 -256.157222)
			(xy 336.99577 -256.309622) (xy 337.25739 -256.309622)
		)
		(stroke
			(width 0)
			(type solid)
		)
		(fill yes)
		(layer "In11.Cu")
		(net "M_D_CPU0_SA_CA<4>")
	)
	(gr_poly
		(pts
			(xy 337.30692 -272.435066) (xy 337.30692 -272.390616) (xy 336.95132 -272.390616) (xy 336.95132 -272.435066)
			(xy 336.99831 -272.587466) (xy 337.25993 -272.587466)
		)
		(stroke
			(width 0)
			(type solid)
		)
		(fill yes)
		(layer "In11.Cu")
		(net "M_D_CPU0_SA_DQS_DN<7>")
	)
	(gr_poly
		(pts
			(xy 337.312762 -279.354788) (xy 337.265772 -279.202388) (xy 337.004152 -279.202388) (xy 336.957162 -279.354788)
			(xy 336.957162 -279.398984) (xy 337.312762 -279.398984)
		)
		(stroke
			(width 0)
			(type solid)
		)
		(fill yes)
		(layer "In11.Cu")
		(net "M_D_CPU0_SA_DQ<10>")
	)
	(gr_poly
		(pts
			(xy 337.312762 -278.945848) (xy 337.312762 -278.901652) (xy 336.957162 -278.901652) (xy 336.957162 -278.945848)
			(xy 337.004152 -279.098248) (xy 337.265772 -279.098248)
		)
		(stroke
			(width 0)
			(type solid)
		)
		(fill yes)
		(layer "In11.Cu")
		(net "M_D_CPU0_SA_DQ<9>")
	)
	(gr_poly
		(pts
			(xy 337.312762 -276.09927) (xy 337.265772 -275.94687) (xy 337.004152 -275.94687) (xy 336.957162 -276.09927)
			(xy 336.957162 -276.143466) (xy 337.312762 -276.143466)
		)
		(stroke
			(width 0)
			(type solid)
		)
		(fill yes)
		(layer "In11.Cu")
		(net "M_D_CPU0_SA_DQ<14>")
	)
	(gr_poly
		(pts
			(xy 337.312762 -275.690584) (xy 337.312762 -275.646134) (xy 336.957162 -275.646134) (xy 336.957162 -275.690584)
			(xy 337.004152 -275.842984) (xy 337.265772 -275.842984)
		)
		(stroke
			(width 0)
			(type solid)
		)
		(fill yes)
		(layer "In11.Cu")
		(net "M_D_CPU0_SA_DQ<13>")
	)
	(gr_poly
		(pts
			(xy 337.312762 -274.47113) (xy 337.265772 -274.31873) (xy 337.004152 -274.31873) (xy 336.957162 -274.47113)
			(xy 336.957162 -274.51558) (xy 337.312762 -274.51558)
		)
		(stroke
			(width 0)
			(type solid)
		)
		(fill yes)
		(layer "In11.Cu")
		(net "M_D_CPU0_SA_DQ<18>")
	)
	(gr_poly
		(pts
			(xy 337.312762 -274.062698) (xy 337.312762 -274.018248) (xy 336.957162 -274.018248) (xy 336.957162 -274.062698)
			(xy 337.004152 -274.215098) (xy 337.265772 -274.215098)
		)
		(stroke
			(width 0)
			(type solid)
		)
		(fill yes)
		(layer "In11.Cu")
		(net "M_D_CPU0_SA_DQ<17>")
	)
	(gr_poly
		(pts
			(xy 337.312762 -270.806926) (xy 337.312762 -270.76273) (xy 336.957162 -270.76273) (xy 336.957162 -270.806926)
			(xy 337.004152 -270.959326) (xy 337.265772 -270.959326)
		)
		(stroke
			(width 0)
			(type solid)
		)
		(fill yes)
		(layer "In11.Cu")
		(net "M_D_CPU0_SA_DQ<21>")
	)
	(gr_poly
		(pts
			(xy 337.312762 -269.587726) (xy 337.265772 -269.435326) (xy 337.004152 -269.435326) (xy 336.957162 -269.587726)
			(xy 336.957162 -269.632176) (xy 337.312762 -269.632176)
		)
		(stroke
			(width 0)
			(type solid)
		)
		(fill yes)
		(layer "In11.Cu")
		(net "M_D_CPU0_SA_DQ<26>")
	)
	(gr_poly
		(pts
			(xy 337.312762 -269.179294) (xy 337.312762 -269.134844) (xy 336.957162 -269.134844) (xy 336.957162 -269.179294)
			(xy 337.004152 -269.331694) (xy 337.265772 -269.331694)
		)
		(stroke
			(width 0)
			(type solid)
		)
		(fill yes)
		(layer "In11.Cu")
		(net "M_D_CPU0_SA_DQ<25>")
	)
	(gr_poly
		(pts
			(xy 337.312762 -267.960094) (xy 337.265772 -267.807694) (xy 337.004152 -267.807694) (xy 336.957162 -267.960094)
			(xy 336.957162 -268.004544) (xy 337.312762 -268.004544)
		)
		(stroke
			(width 0)
			(type solid)
		)
		(fill yes)
		(layer "In11.Cu")
		(net "M_D_CPU0_SA_DQS_DN<3>")
	)
	(gr_poly
		(pts
			(xy 337.312762 -267.551662) (xy 337.312762 -267.507212) (xy 336.957162 -267.507212) (xy 336.957162 -267.551662)
			(xy 337.004152 -267.704062) (xy 337.265772 -267.704062)
		)
		(stroke
			(width 0)
			(type solid)
		)
		(fill yes)
		(layer "In11.Cu")
		(net "M_D_CPU0_SA_DQS_DN<8>")
	)
	(gr_poly
		(pts
			(xy 337.312762 -266.332462) (xy 337.265772 -266.180062) (xy 337.004152 -266.180062) (xy 336.957162 -266.332462)
			(xy 336.957162 -266.376658) (xy 337.312762 -266.376658)
		)
		(stroke
			(width 0)
			(type solid)
		)
		(fill yes)
		(layer "In11.Cu")
		(net "M_D_CPU0_SA_DQ<30>")
	)
	(gr_poly
		(pts
			(xy 337.312762 -265.923522) (xy 337.312762 -265.879326) (xy 336.957162 -265.879326) (xy 336.957162 -265.923522)
			(xy 337.004152 -266.075922) (xy 337.265772 -266.075922)
		)
		(stroke
			(width 0)
			(type solid)
		)
		(fill yes)
		(layer "In11.Cu")
		(net "M_D_CPU0_SA_DQ<29>")
	)
	(gr_poly
		(pts
			(xy 337.312762 -264.70483) (xy 337.265772 -264.55243) (xy 337.004152 -264.55243) (xy 336.957162 -264.70483)
			(xy 336.957162 -264.749026) (xy 337.312762 -264.749026)
		)
		(stroke
			(width 0)
			(type solid)
		)
		(fill yes)
		(layer "In11.Cu")
		(net "M_D_CPU0_SA_CB<2>")
	)
	(gr_poly
		(pts
			(xy 337.312762 -264.29589) (xy 337.312762 -264.251694) (xy 336.957162 -264.251694) (xy 336.957162 -264.29589)
			(xy 337.004152 -264.44829) (xy 337.265772 -264.44829)
		)
		(stroke
			(width 0)
			(type solid)
		)
		(fill yes)
		(layer "In11.Cu")
		(net "M_D_CPU0_SA_CB<1>")
	)
	(gr_poly
		(pts
			(xy 337.312762 -263.07669) (xy 337.265772 -262.92429) (xy 337.004152 -262.92429) (xy 336.957162 -263.07669)
			(xy 336.957162 -263.12114) (xy 337.312762 -263.12114)
		)
		(stroke
			(width 0)
			(type solid)
		)
		(fill yes)
		(layer "In11.Cu")
		(net "M_D_CPU0_SA_DQS_DN<4>")
	)
	(gr_poly
		(pts
			(xy 337.312762 -259.412486) (xy 337.312762 -259.36829) (xy 336.957162 -259.36829) (xy 336.957162 -259.412486)
			(xy 337.004152 -259.564886) (xy 337.265772 -259.564886)
		)
		(stroke
			(width 0)
			(type solid)
		)
		(fill yes)
		(layer "In11.Cu")
		(net "M_D_CPU0_SA_CS_N<2>")
	)
	(gr_poly
		(pts
			(xy 337.312762 -258.193286) (xy 337.265772 -258.040886) (xy 337.004152 -258.040886) (xy 336.957162 -258.193286)
			(xy 336.957162 -258.237736) (xy 337.312762 -258.237736)
		)
		(stroke
			(width 0)
			(type solid)
		)
		(fill yes)
		(layer "In11.Cu")
		(net "M_D_CPU0_SA_CS_N<1>")
	)
	(gr_poly
		(pts
			(xy 337.312762 -257.784854) (xy 337.312762 -257.740404) (xy 336.957162 -257.740404) (xy 336.957162 -257.784854)
			(xy 337.004152 -257.937254) (xy 337.265772 -257.937254)
		)
		(stroke
			(width 0)
			(type solid)
		)
		(fill yes)
		(layer "In11.Cu")
		(net "M_D_CPU0_SA_CA<0>")
	)
	(gr_poly
		(pts
			(xy 337.312762 -256.565654) (xy 337.265772 -256.413254) (xy 337.004152 -256.413254) (xy 336.957162 -256.565654)
			(xy 336.957162 -256.610104) (xy 337.312762 -256.610104)
		)
		(stroke
			(width 0)
			(type solid)
		)
		(fill yes)
		(layer "In11.Cu")
		(net "M_D_CPU0_SA_CA<3>")
	)
	(gr_poly
		(pts
			(xy 337.313016 -262.66775) (xy 337.313016 -262.623554) (xy 336.957416 -262.623554) (xy 336.957416 -262.66775)
			(xy 337.004406 -262.82015) (xy 337.266026 -262.82015)
		)
		(stroke
			(width 0)
			(type solid)
		)
		(fill yes)
		(layer "In11.Cu")
		(net "M_D_CPU0_SA_DQS_DN<9>")
	)
	(gr_poly
		(pts
			(xy 337.317842 -277.726902) (xy 337.270852 -277.574502) (xy 337.009232 -277.574502) (xy 336.962242 -277.726902)
			(xy 336.962242 -277.771098) (xy 337.317842 -277.771098)
		)
		(stroke
			(width 0)
			(type solid)
		)
		(fill yes)
		(layer "In11.Cu")
		(net "M_D_CPU0_SA_DQS_DN<1>")
	)
	(gr_poly
		(pts
			(xy 337.318858 -277.317962) (xy 337.318858 -277.273766) (xy 336.963258 -277.273766) (xy 336.963258 -277.317962)
			(xy 337.010248 -277.470362) (xy 337.271868 -277.470362)
		)
		(stroke
			(width 0)
			(type solid)
		)
		(fill yes)
		(layer "In11.Cu")
		(net "M_D_CPU0_SA_DQS_DN<6>")
	)
	(gr_poly
		(pts
			(xy 337.318858 -272.843498) (xy 337.271868 -272.691098) (xy 337.010248 -272.691098) (xy 336.963258 -272.843498)
			(xy 336.963258 -272.887948) (xy 337.318858 -272.887948)
		)
		(stroke
			(width 0)
			(type solid)
		)
		(fill yes)
		(layer "In11.Cu")
		(net "M_D_CPU0_SA_DQS_DN<2>")
	)
	(gr_poly
		(pts
			(xy 337.531456 -237.878366) (xy 337.56981 -237.856268) (xy 337.39201 -237.54842) (xy 337.353656 -237.570518)
			(xy 337.245198 -237.687358) (xy 337.376008 -237.913926)
		)
		(stroke
			(width 0)
			(type solid)
		)
		(fill yes)
		(layer "In11.Cu")
		(net "M_D_CPU0_SB_DQ<5>")
	)
	(gr_poly
		(pts
			(xy 337.531456 -236.250734) (xy 337.56981 -236.228636) (xy 337.39201 -235.920788) (xy 337.353656 -235.942886)
			(xy 337.245198 -236.059726) (xy 337.376008 -236.286294)
		)
		(stroke
			(width 0)
			(type solid)
		)
		(fill yes)
		(layer "In11.Cu")
		(net "M_D_CPU0_SB_DQ<8>")
	)
	(gr_poly
		(pts
			(xy 337.643724 -237.263686) (xy 337.752182 -237.146846) (xy 337.621372 -236.920278) (xy 337.465924 -236.955838)
			(xy 337.42757 -236.977936) (xy 337.60537 -237.285784)
		)
		(stroke
			(width 0)
			(type solid)
		)
		(fill yes)
		(layer "In11.Cu")
		(net "M_D_CPU0_SB_DQ<7>")
	)
	(gr_poly
		(pts
			(xy 337.643724 -235.636054) (xy 337.752182 -235.519214) (xy 337.621372 -235.292646) (xy 337.465924 -235.328206)
			(xy 337.42757 -235.350304) (xy 337.60537 -235.658152)
		)
		(stroke
			(width 0)
			(type solid)
		)
		(fill yes)
		(layer "In11.Cu")
		(net "M_D_CPU0_SB_DQ<10>")
	)
	(gr_poly
		(pts
			(xy 337.666838 -247.382538) (xy 337.619848 -247.230138) (xy 337.358228 -247.230138) (xy 337.311238 -247.382538)
			(xy 337.311238 -247.426988) (xy 337.666838 -247.426988)
		)
		(stroke
			(width 0)
			(type solid)
		)
		(fill yes)
		(layer "In11.Cu")
		(net "M_D_CPU0_SB_CA<6>")
	)
	(gr_poly
		(pts
			(xy 337.672934 -248.601738) (xy 337.672934 -248.557542) (xy 337.317334 -248.557542) (xy 337.317334 -248.601738)
			(xy 337.364324 -248.754138) (xy 337.625944 -248.754138)
		)
		(stroke
			(width 0)
			(type solid)
		)
		(fill yes)
		(layer "In11.Cu")
		(net "M_D_CPU0_SB_CA<4>")
	)
	(gr_poly
		(pts
			(xy 337.678776 -246.974106) (xy 337.678776 -246.929656) (xy 337.323176 -246.929656) (xy 337.323176 -246.974106)
			(xy 337.370166 -247.126506) (xy 337.631786 -247.126506)
		)
		(stroke
			(width 0)
			(type solid)
		)
		(fill yes)
		(layer "In11.Cu")
		(net "M_D_CPU0_SB_CB<4>")
	)
	(gr_poly
		(pts
			(xy 337.681316 -249.01017) (xy 337.634326 -248.85777) (xy 337.372706 -248.85777) (xy 337.325716 -249.01017)
			(xy 337.325716 -249.05462) (xy 337.681316 -249.05462)
		)
		(stroke
			(width 0)
			(type solid)
		)
		(fill yes)
		(layer "In11.Cu")
		(net "M_D_CPU0_SB_CA<3>")
	)
	(gr_poly
		(pts
			(xy 337.681316 -245.754906) (xy 337.634326 -245.602506) (xy 337.372706 -245.602506) (xy 337.325716 -245.754906)
			(xy 337.325716 -245.799102) (xy 337.681316 -245.799102)
		)
		(stroke
			(width 0)
			(type solid)
		)
		(fill yes)
		(layer "In11.Cu")
		(net "M_D_CPU0_SB_CB<7>")
	)
	(gr_poly
		(pts
			(xy 337.681316 -245.346474) (xy 337.681316 -245.302278) (xy 337.325716 -245.302278) (xy 337.325716 -245.346474)
			(xy 337.372706 -245.498874) (xy 337.634326 -245.498874)
		)
		(stroke
			(width 0)
			(type solid)
		)
		(fill yes)
		(layer "In11.Cu")
		(net "M_D_CPU0_SB_DQS_DP<9>")
	)
	(gr_poly
		(pts
			(xy 337.681316 -244.126766) (xy 337.634326 -243.974366) (xy 337.372706 -243.974366) (xy 337.325716 -244.126766)
			(xy 337.325716 -244.171216) (xy 337.681316 -244.171216)
		)
		(stroke
			(width 0)
			(type solid)
		)
		(fill yes)
		(layer "In11.Cu")
		(net "M_D_CPU0_SB_DQS_DP<4>")
	)
	(gr_poly
		(pts
			(xy 337.681316 -243.718842) (xy 337.681316 -243.674392) (xy 337.325716 -243.674392) (xy 337.325716 -243.718842)
			(xy 337.372706 -243.871242) (xy 337.634326 -243.871242)
		)
		(stroke
			(width 0)
			(type solid)
		)
		(fill yes)
		(layer "In11.Cu")
		(net "M_D_CPU0_SB_CB<0>")
	)
	(gr_poly
		(pts
			(xy 337.681316 -242.499134) (xy 337.634326 -242.346734) (xy 337.372706 -242.346734) (xy 337.325716 -242.499134)
			(xy 337.325716 -242.54333) (xy 337.681316 -242.54333)
		)
		(stroke
			(width 0)
			(type solid)
		)
		(fill yes)
		(layer "In11.Cu")
		(net "M_D_CPU0_SB_CB<3>")
	)
	(gr_poly
		(pts
			(xy 337.681316 -242.090702) (xy 337.681316 -242.046506) (xy 337.325716 -242.046506) (xy 337.325716 -242.090702)
			(xy 337.372706 -242.243102) (xy 337.634326 -242.243102)
		)
		(stroke
			(width 0)
			(type solid)
		)
		(fill yes)
		(layer "In11.Cu")
		(net "M_D_CPU0_SB_DQ<0>")
	)
	(gr_poly
		(pts
			(xy 337.681316 -240.871502) (xy 337.634326 -240.719102) (xy 337.372706 -240.719102) (xy 337.325716 -240.871502)
			(xy 337.325716 -240.915698) (xy 337.681316 -240.915698)
		)
		(stroke
			(width 0)
			(type solid)
		)
		(fill yes)
		(layer "In11.Cu")
		(net "M_D_CPU0_SB_DQ<3>")
	)
	(gr_poly
		(pts
			(xy 337.681316 -240.46307) (xy 337.681316 -240.418874) (xy 337.325716 -240.418874) (xy 337.325716 -240.46307)
			(xy 337.372706 -240.61547) (xy 337.634326 -240.61547)
		)
		(stroke
			(width 0)
			(type solid)
		)
		(fill yes)
		(layer "In11.Cu")
		(net "M_D_CPU0_SB_DQS_DP<0>")
	)
	(gr_poly
		(pts
			(xy 337.681316 -239.243362) (xy 337.634326 -239.090962) (xy 337.372706 -239.090962) (xy 337.325716 -239.243362)
			(xy 337.325716 -239.287812) (xy 337.681316 -239.287812)
		)
		(stroke
			(width 0)
			(type solid)
		)
		(fill yes)
		(layer "In11.Cu")
		(net "M_D_CPU0_SB_DQS_DP<5>")
	)
	(gr_poly
		(pts
			(xy 337.681316 -238.835438) (xy 337.681316 -238.790988) (xy 337.325716 -238.790988) (xy 337.325716 -238.835438)
			(xy 337.372706 -238.987838) (xy 337.634326 -238.987838)
		)
		(stroke
			(width 0)
			(type solid)
		)
		(fill yes)
		(layer "In11.Cu")
		(net "M_D_CPU0_SB_DQ<4>")
	)
	(gr_poly
		(pts
			(xy 337.681316 -234.360466) (xy 337.634326 -234.208066) (xy 337.372706 -234.208066) (xy 337.325716 -234.360466)
			(xy 337.325716 -234.404662) (xy 337.681316 -234.404662)
		)
		(stroke
			(width 0)
			(type solid)
		)
		(fill yes)
		(layer "In11.Cu")
		(net "M_D_CPU0_SB_DQ<11>")
	)
	(gr_poly
		(pts
			(xy 337.681316 -233.952034) (xy 337.681316 -233.907838) (xy 337.325716 -233.907838) (xy 337.325716 -233.952034)
			(xy 337.372706 -234.104434) (xy 337.634326 -234.104434)
		)
		(stroke
			(width 0)
			(type solid)
		)
		(fill yes)
		(layer "In11.Cu")
		(net "M_D_CPU0_SB_DQS_DP<1>")
	)
	(gr_poly
		(pts
			(xy 337.681316 -232.324402) (xy 337.681316 -232.279952) (xy 337.325716 -232.279952) (xy 337.325716 -232.324402)
			(xy 337.372706 -232.476802) (xy 337.634326 -232.476802)
		)
		(stroke
			(width 0)
			(type solid)
		)
		(fill yes)
		(layer "In11.Cu")
		(net "M_D_CPU0_SB_DQS_DN<6>")
	)
	(gr_poly
		(pts
			(xy 337.681316 -231.104694) (xy 337.634326 -230.952294) (xy 337.372706 -230.952294) (xy 337.325716 -231.104694)
			(xy 337.325716 -231.14889) (xy 337.681316 -231.14889)
		)
		(stroke
			(width 0)
			(type solid)
		)
		(fill yes)
		(layer "In11.Cu")
		(net "M_D_CPU0_SB_DQ<14>")
	)
	(gr_poly
		(pts
			(xy 337.681316 -230.696262) (xy 337.681316 -230.652066) (xy 337.325716 -230.652066) (xy 337.325716 -230.696262)
			(xy 337.372706 -230.848662) (xy 337.634326 -230.848662)
		)
		(stroke
			(width 0)
			(type solid)
		)
		(fill yes)
		(layer "In11.Cu")
		(net "M_D_CPU0_SB_DQ<13>")
	)
	(gr_poly
		(pts
			(xy 337.681316 -229.477062) (xy 337.634326 -229.324662) (xy 337.372706 -229.324662) (xy 337.325716 -229.477062)
			(xy 337.325716 -229.521258) (xy 337.681316 -229.521258)
		)
		(stroke
			(width 0)
			(type solid)
		)
		(fill yes)
		(layer "In11.Cu")
		(net "M_D_CPU0_SB_DQ<26>")
	)
	(gr_poly
		(pts
			(xy 337.681316 -229.06863) (xy 337.681316 -229.024434) (xy 337.325716 -229.024434) (xy 337.325716 -229.06863)
			(xy 337.372706 -229.22103) (xy 337.634326 -229.22103)
		)
		(stroke
			(width 0)
			(type solid)
		)
		(fill yes)
		(layer "In11.Cu")
		(net "M_D_CPU0_SB_DQ<25>")
	)
	(gr_poly
		(pts
			(xy 337.681316 -227.848922) (xy 337.634326 -227.696522) (xy 337.372706 -227.696522) (xy 337.325716 -227.848922)
			(xy 337.325716 -227.893372) (xy 337.681316 -227.893372)
		)
		(stroke
			(width 0)
			(type solid)
		)
		(fill yes)
		(layer "In11.Cu")
		(net "M_D_CPU0_SB_DQS_DN<3>")
	)
	(gr_poly
		(pts
			(xy 337.681316 -227.440998) (xy 337.681316 -227.396548) (xy 337.325716 -227.396548) (xy 337.325716 -227.440998)
			(xy 337.372706 -227.593398) (xy 337.634326 -227.593398)
		)
		(stroke
			(width 0)
			(type solid)
		)
		(fill yes)
		(layer "In11.Cu")
		(net "M_D_CPU0_SB_DQS_DN<8>")
	)
	(gr_poly
		(pts
			(xy 337.681316 -226.22129) (xy 337.634326 -226.06889) (xy 337.372706 -226.06889) (xy 337.325716 -226.22129)
			(xy 337.325716 -226.26574) (xy 337.681316 -226.26574)
		)
		(stroke
			(width 0)
			(type solid)
		)
		(fill yes)
		(layer "In11.Cu")
		(net "M_D_CPU0_SB_DQ<30>")
	)
	(gr_poly
		(pts
			(xy 337.681316 -225.813366) (xy 337.681316 -225.768916) (xy 337.325716 -225.768916) (xy 337.325716 -225.813366)
			(xy 337.372706 -225.965766) (xy 337.634326 -225.965766)
		)
		(stroke
			(width 0)
			(type solid)
		)
		(fill yes)
		(layer "In11.Cu")
		(net "M_D_CPU0_SB_DQ<29>")
	)
	(gr_poly
		(pts
			(xy 337.782662 -278.540718) (xy 337.735672 -278.388318) (xy 337.474052 -278.388318) (xy 337.427062 -278.540718)
			(xy 337.427062 -278.585168) (xy 337.782662 -278.585168)
		)
		(stroke
			(width 0)
			(type solid)
		)
		(fill yes)
		(layer "In11.Cu")
		(net "M_D_CPU0_SA_DQ<11>")
	)
	(gr_poly
		(pts
			(xy 337.782662 -278.132032) (xy 337.782662 -278.087836) (xy 337.427062 -278.087836) (xy 337.427062 -278.132032)
			(xy 337.474052 -278.284432) (xy 337.735672 -278.284432)
		)
		(stroke
			(width 0)
			(type solid)
		)
		(fill yes)
		(layer "In11.Cu")
		(net "M_D_CPU0_SA_DQS_DP<1>")
	)
	(gr_poly
		(pts
			(xy 337.782662 -276.913086) (xy 337.735672 -276.760686) (xy 337.474052 -276.760686) (xy 337.427062 -276.913086)
			(xy 337.427062 -276.957282) (xy 337.782662 -276.957282)
		)
		(stroke
			(width 0)
			(type solid)
		)
		(fill yes)
		(layer "In11.Cu")
		(net "M_D_CPU0_SA_DQS_DP<6>")
	)
	(gr_poly
		(pts
			(xy 337.782662 -276.504146) (xy 337.782662 -276.45995) (xy 337.427062 -276.45995) (xy 337.427062 -276.504146)
			(xy 337.474052 -276.656546) (xy 337.735672 -276.656546)
		)
		(stroke
			(width 0)
			(type solid)
		)
		(fill yes)
		(layer "In11.Cu")
		(net "M_D_CPU0_SA_DQ<12>")
	)
	(gr_poly
		(pts
			(xy 337.782662 -275.284946) (xy 337.735672 -275.132546) (xy 337.474052 -275.132546) (xy 337.427062 -275.284946)
			(xy 337.427062 -275.329396) (xy 337.782662 -275.329396)
		)
		(stroke
			(width 0)
			(type solid)
		)
		(fill yes)
		(layer "In11.Cu")
		(net "M_D_CPU0_SA_DQ<15>")
	)
	(gr_poly
		(pts
			(xy 337.782662 -274.876514) (xy 337.782662 -274.832064) (xy 337.427062 -274.832064) (xy 337.427062 -274.876514)
			(xy 337.474052 -275.028914) (xy 337.735672 -275.028914)
		)
		(stroke
			(width 0)
			(type solid)
		)
		(fill yes)
		(layer "In11.Cu")
		(net "M_D_CPU0_SA_DQ<16>")
	)
	(gr_poly
		(pts
			(xy 337.782662 -273.657314) (xy 337.735672 -273.504914) (xy 337.474052 -273.504914) (xy 337.427062 -273.657314)
			(xy 337.427062 -273.701764) (xy 337.782662 -273.701764)
		)
		(stroke
			(width 0)
			(type solid)
		)
		(fill yes)
		(layer "In11.Cu")
		(net "M_D_CPU0_SA_DQ<19>")
	)
	(gr_poly
		(pts
			(xy 337.782662 -273.248882) (xy 337.782662 -273.204432) (xy 337.427062 -273.204432) (xy 337.427062 -273.248882)
			(xy 337.474052 -273.401282) (xy 337.735672 -273.401282)
		)
		(stroke
			(width 0)
			(type solid)
		)
		(fill yes)
		(layer "In11.Cu")
		(net "M_D_CPU0_SA_DQS_DP<2>")
	)
	(gr_poly
		(pts
			(xy 337.782662 -270.40205) (xy 337.735672 -270.24965) (xy 337.474052 -270.24965) (xy 337.427062 -270.40205)
			(xy 337.427062 -270.446246) (xy 337.782662 -270.446246)
		)
		(stroke
			(width 0)
			(type solid)
		)
		(fill yes)
		(layer "In11.Cu")
		(net "M_D_CPU0_SA_DQ<23>")
	)
	(gr_poly
		(pts
			(xy 337.782662 -269.99311) (xy 337.782662 -269.948914) (xy 337.427062 -269.948914) (xy 337.427062 -269.99311)
			(xy 337.474052 -270.14551) (xy 337.735672 -270.14551)
		)
		(stroke
			(width 0)
			(type solid)
		)
		(fill yes)
		(layer "In11.Cu")
		(net "M_D_CPU0_SA_DQ<24>")
	)
	(gr_poly
		(pts
			(xy 337.782662 -268.77391) (xy 337.735672 -268.62151) (xy 337.474052 -268.62151) (xy 337.427062 -268.77391)
			(xy 337.427062 -268.81836) (xy 337.782662 -268.81836)
		)
		(stroke
			(width 0)
			(type solid)
		)
		(fill yes)
		(layer "In11.Cu")
		(net "M_D_CPU0_SA_DQ<27>")
	)
	(gr_poly
		(pts
			(xy 337.782662 -268.365478) (xy 337.782662 -268.321028) (xy 337.427062 -268.321028) (xy 337.427062 -268.365478)
			(xy 337.474052 -268.517878) (xy 337.735672 -268.517878)
		)
		(stroke
			(width 0)
			(type solid)
		)
		(fill yes)
		(layer "In11.Cu")
		(net "M_D_CPU0_SA_DQS_DP<3>")
	)
	(gr_poly
		(pts
			(xy 337.782662 -267.146278) (xy 337.735672 -266.993878) (xy 337.474052 -266.993878) (xy 337.427062 -267.146278)
			(xy 337.427062 -267.190474) (xy 337.782662 -267.190474)
		)
		(stroke
			(width 0)
			(type solid)
		)
		(fill yes)
		(layer "In11.Cu")
		(net "M_D_CPU0_SA_DQS_DP<8>")
	)
	(gr_poly
		(pts
			(xy 337.782662 -266.737846) (xy 337.782662 -266.693396) (xy 337.427062 -266.693396) (xy 337.427062 -266.737846)
			(xy 337.474052 -266.890246) (xy 337.735672 -266.890246)
		)
		(stroke
			(width 0)
			(type solid)
		)
		(fill yes)
		(layer "In11.Cu")
		(net "M_D_CPU0_SA_DQ<28>")
	)
	(gr_poly
		(pts
			(xy 337.782662 -265.518646) (xy 337.735672 -265.366246) (xy 337.474052 -265.366246) (xy 337.427062 -265.518646)
			(xy 337.427062 -265.562842) (xy 337.782662 -265.562842)
		)
		(stroke
			(width 0)
			(type solid)
		)
		(fill yes)
		(layer "In11.Cu")
		(net "M_D_CPU0_SA_DQ<31>")
	)
	(gr_poly
		(pts
			(xy 337.782662 -265.109706) (xy 337.782662 -265.06551) (xy 337.427062 -265.06551) (xy 337.427062 -265.109706)
			(xy 337.474052 -265.262106) (xy 337.735672 -265.262106)
		)
		(stroke
			(width 0)
			(type solid)
		)
		(fill yes)
		(layer "In11.Cu")
		(net "M_D_CPU0_SA_CB<0>")
	)
	(gr_poly
		(pts
			(xy 337.782662 -263.891014) (xy 337.735672 -263.738614) (xy 337.474052 -263.738614) (xy 337.427062 -263.891014)
			(xy 337.427062 -263.93521) (xy 337.782662 -263.93521)
		)
		(stroke
			(width 0)
			(type solid)
		)
		(fill yes)
		(layer "In11.Cu")
		(net "M_D_CPU0_SA_CB<3>")
	)
	(gr_poly
		(pts
			(xy 337.782662 -263.482074) (xy 337.782662 -263.437878) (xy 337.427062 -263.437878) (xy 337.427062 -263.482074)
			(xy 337.474052 -263.634474) (xy 337.735672 -263.634474)
		)
		(stroke
			(width 0)
			(type solid)
		)
		(fill yes)
		(layer "In11.Cu")
		(net "M_D_CPU0_SA_DQS_DP<4>")
	)
	(gr_poly
		(pts
			(xy 337.782662 -259.00761) (xy 337.735672 -258.85521) (xy 337.474052 -258.85521) (xy 337.427062 -259.00761)
			(xy 337.427062 -259.051806) (xy 337.782662 -259.051806)
		)
		(stroke
			(width 0)
			(type solid)
		)
		(fill yes)
		(layer "In11.Cu")
		(net "M_D_CPU0_SA_CS_N<0>")
	)
	(gr_poly
		(pts
			(xy 337.782662 -258.59867) (xy 337.782662 -258.554474) (xy 337.427062 -258.554474) (xy 337.427062 -258.59867)
			(xy 337.474052 -258.75107) (xy 337.735672 -258.75107)
		)
		(stroke
			(width 0)
			(type solid)
		)
		(fill yes)
		(layer "In11.Cu")
		(net "M_D_CPU0_SA_CS_N<3>")
	)
	(gr_poly
		(pts
			(xy 337.782662 -257.37947) (xy 337.735672 -257.22707) (xy 337.474052 -257.22707) (xy 337.427062 -257.37947)
			(xy 337.427062 -257.42392) (xy 337.782662 -257.42392)
		)
		(stroke
			(width 0)
			(type solid)
		)
		(fill yes)
		(layer "In11.Cu")
		(net "M_D_CPU0_SA_CA<1>")
	)
	(gr_poly
		(pts
			(xy 337.782662 -256.971038) (xy 337.782662 -256.926588) (xy 337.427062 -256.926588) (xy 337.427062 -256.971038)
			(xy 337.474052 -257.123438) (xy 337.735672 -257.123438)
		)
		(stroke
			(width 0)
			(type solid)
		)
		(fill yes)
		(layer "In11.Cu")
		(net "M_D_CPU0_SA_CA<2>")
	)
	(gr_poly
		(pts
			(xy 337.782916 -262.262874) (xy 337.735926 -262.110474) (xy 337.474306 -262.110474) (xy 337.427316 -262.262874)
			(xy 337.427316 -262.307324) (xy 337.782916 -262.307324)
		)
		(stroke
			(width 0)
			(type solid)
		)
		(fill yes)
		(layer "In11.Cu")
		(net "M_D_CPU0_SA_DQS_DP<9>")
	)
	(gr_poly
		(pts
			(xy 337.788758 -272.029682) (xy 337.741768 -271.877282) (xy 337.480148 -271.877282) (xy 337.433158 -272.029682)
			(xy 337.433158 -272.073878) (xy 337.788758 -272.073878)
		)
		(stroke
			(width 0)
			(type solid)
		)
		(fill yes)
		(layer "In11.Cu")
		(net "M_D_CPU0_SA_DQS_DP<7>")
	)
	(gr_poly
		(pts
			(xy 337.788758 -271.620742) (xy 337.788758 -271.576546) (xy 337.433158 -271.576546) (xy 337.433158 -271.620742)
			(xy 337.480148 -271.773142) (xy 337.741768 -271.773142)
		)
		(stroke
			(width 0)
			(type solid)
		)
		(fill yes)
		(layer "In11.Cu")
		(net "M_D_CPU0_SA_DQ<20>")
	)
	(gr_poly
		(pts
			(xy 337.788758 -261.854442) (xy 337.788758 -261.809992) (xy 337.433158 -261.809992) (xy 337.433158 -261.854442)
			(xy 337.480148 -262.006842) (xy 337.741768 -262.006842)
		)
		(stroke
			(width 0)
			(type solid)
		)
		(fill yes)
		(layer "In11.Cu")
		(net "M_D_CPU0_SA_CB<4>")
	)
	(gr_poly
		(pts
			(xy 337.788758 -260.635242) (xy 337.741768 -260.482842) (xy 337.480148 -260.482842) (xy 337.433158 -260.635242)
			(xy 337.433158 -260.679438) (xy 337.788758 -260.679438)
		)
		(stroke
			(width 0)
			(type solid)
		)
		(fill yes)
		(layer "In11.Cu")
		(net "M_D_CPU0_SA_CB<7>")
	)
	(gr_poly
		(pts
			(xy 337.788758 -255.751838) (xy 337.741768 -255.599438) (xy 337.480148 -255.599438) (xy 337.433158 -255.751838)
			(xy 337.433158 -255.796288) (xy 337.788758 -255.796288)
		)
		(stroke
			(width 0)
			(type solid)
		)
		(fill yes)
		(layer "In11.Cu")
		(net "M_D_CPU0_SA_CA<5>")
	)
	(gr_poly
		(pts
			(xy 337.992212 -235.422694) (xy 338.030566 -235.400596) (xy 337.852766 -235.092748) (xy 337.814412 -235.114846)
			(xy 337.705954 -235.231686) (xy 337.836764 -235.458254)
		)
		(stroke
			(width 0)
			(type solid)
		)
		(fill yes)
		(layer "In11.Cu")
		(net "M_D_CPU0_SB_DQ<9>")
	)
	(gr_poly
		(pts
			(xy 337.99399 -237.053628) (xy 338.032344 -237.03153) (xy 337.854544 -236.723682) (xy 337.81619 -236.74578)
			(xy 337.707732 -236.86262) (xy 337.838542 -237.089188)
		)
		(stroke
			(width 0)
			(type solid)
		)
		(fill yes)
		(layer "In11.Cu")
		(net "M_D_CPU0_SB_DQ<8>")
	)
	(gr_poly
		(pts
			(xy 338.106258 -236.438948) (xy 338.214716 -236.322108) (xy 338.083906 -236.09554) (xy 337.928458 -236.1311)
			(xy 337.890104 -236.153198) (xy 338.067904 -236.461046)
		)
		(stroke
			(width 0)
			(type solid)
		)
		(fill yes)
		(layer "In11.Cu")
		(net "M_D_CPU0_SB_DQ<10>")
	)
	(gr_poly
		(pts
			(xy 338.113624 -234.822492) (xy 338.222082 -234.705652) (xy 338.091272 -234.479084) (xy 337.935824 -234.514644)
			(xy 337.89747 -234.536742) (xy 338.07527 -234.84459)
		)
		(stroke
			(width 0)
			(type solid)
		)
		(fill yes)
		(layer "In11.Cu")
		(net "M_D_CPU0_SB_DQ<11>")
	)
	(gr_poly
		(pts
			(xy 338.134198 -246.16029) (xy 338.134198 -246.116094) (xy 337.778598 -246.116094) (xy 337.778598 -246.16029)
			(xy 337.825588 -246.31269) (xy 338.087208 -246.31269)
		)
		(stroke
			(width 0)
			(type solid)
		)
		(fill yes)
		(layer "In11.Cu")
		(net "M_D_CPU0_SB_CB<5>")
	)
	(gr_poly
		(pts
			(xy 338.134198 -243.31295) (xy 338.087208 -243.16055) (xy 337.825588 -243.16055) (xy 337.778598 -243.31295)
			(xy 337.778598 -243.3574) (xy 338.134198 -243.3574)
		)
		(stroke
			(width 0)
			(type solid)
		)
		(fill yes)
		(layer "In11.Cu")
		(net "M_D_CPU0_SB_CB<2>")
	)
	(gr_poly
		(pts
			(xy 338.134198 -242.905026) (xy 338.134198 -242.860576) (xy 337.778598 -242.860576) (xy 337.778598 -242.905026)
			(xy 337.825588 -243.057426) (xy 338.087208 -243.057426)
		)
		(stroke
			(width 0)
			(type solid)
		)
		(fill yes)
		(layer "In11.Cu")
		(net "M_D_CPU0_SB_CB<1>")
	)
	(gr_poly
		(pts
			(xy 338.134198 -241.685318) (xy 338.087208 -241.532918) (xy 337.825588 -241.532918) (xy 337.778598 -241.685318)
			(xy 337.778598 -241.729514) (xy 338.134198 -241.729514)
		)
		(stroke
			(width 0)
			(type solid)
		)
		(fill yes)
		(layer "In11.Cu")
		(net "M_D_CPU0_SB_DQ<2>")
	)
	(gr_poly
		(pts
			(xy 338.134198 -241.276886) (xy 338.134198 -241.23269) (xy 337.778598 -241.23269) (xy 337.778598 -241.276886)
			(xy 337.825588 -241.429286) (xy 338.087208 -241.429286)
		)
		(stroke
			(width 0)
			(type solid)
		)
		(fill yes)
		(layer "In11.Cu")
		(net "M_D_CPU0_SB_DQ<1>")
	)
	(gr_poly
		(pts
			(xy 338.134198 -238.429546) (xy 338.087208 -238.277146) (xy 337.825588 -238.277146) (xy 337.778598 -238.429546)
			(xy 337.778598 -238.473996) (xy 338.134198 -238.473996)
		)
		(stroke
			(width 0)
			(type solid)
		)
		(fill yes)
		(layer "In11.Cu")
		(net "M_D_CPU0_SB_DQ<6>")
	)
	(gr_poly
		(pts
			(xy 338.134198 -238.021622) (xy 338.134198 -237.977172) (xy 337.778598 -237.977172) (xy 337.778598 -238.021622)
			(xy 337.825588 -238.174022) (xy 338.087208 -238.174022)
		)
		(stroke
			(width 0)
			(type solid)
		)
		(fill yes)
		(layer "In11.Cu")
		(net "M_D_CPU0_SB_DQ<5>")
	)
	(gr_poly
		(pts
			(xy 338.134198 -233.546142) (xy 338.087208 -233.393742) (xy 337.825588 -233.393742) (xy 337.778598 -233.546142)
			(xy 337.778598 -233.590592) (xy 338.134198 -233.590592)
		)
		(stroke
			(width 0)
			(type solid)
		)
		(fill yes)
		(layer "In11.Cu")
		(net "M_D_CPU0_SB_DQS_DN<1>")
	)
	(gr_poly
		(pts
			(xy 338.134198 -231.510586) (xy 338.134198 -231.466136) (xy 337.778598 -231.466136) (xy 337.778598 -231.510586)
			(xy 337.825588 -231.662986) (xy 338.087208 -231.662986)
		)
		(stroke
			(width 0)
			(type solid)
		)
		(fill yes)
		(layer "In11.Cu")
		(net "M_D_CPU0_SB_DQ<12>")
	)
	(gr_poly
		(pts
			(xy 338.134198 -228.663246) (xy 338.087208 -228.510846) (xy 337.825588 -228.510846) (xy 337.778598 -228.663246)
			(xy 337.778598 -228.707442) (xy 338.134198 -228.707442)
		)
		(stroke
			(width 0)
			(type solid)
		)
		(fill yes)
		(layer "In11.Cu")
		(net "M_D_CPU0_SB_DQ<27>")
	)
	(gr_poly
		(pts
			(xy 338.134198 -228.254814) (xy 338.134198 -228.210618) (xy 337.778598 -228.210618) (xy 337.778598 -228.254814)
			(xy 337.825588 -228.407214) (xy 338.087208 -228.407214)
		)
		(stroke
			(width 0)
			(type solid)
		)
		(fill yes)
		(layer "In11.Cu")
		(net "M_D_CPU0_SB_DQS_DP<3>")
	)
	(gr_poly
		(pts
			(xy 338.134198 -226.627182) (xy 338.134198 -226.582732) (xy 337.778598 -226.582732) (xy 337.778598 -226.627182)
			(xy 337.825588 -226.779582) (xy 338.087208 -226.779582)
		)
		(stroke
			(width 0)
			(type solid)
		)
		(fill yes)
		(layer "In11.Cu")
		(net "M_D_CPU0_SB_DQ<28>")
	)
	(gr_poly
		(pts
			(xy 338.134198 -225.407474) (xy 338.087208 -225.255074) (xy 337.825588 -225.255074) (xy 337.778598 -225.407474)
			(xy 337.778598 -225.45167) (xy 338.134198 -225.45167)
		)
		(stroke
			(width 0)
			(type solid)
		)
		(fill yes)
		(layer "In11.Cu")
		(net "M_D_CPU0_SB_DQ<31>")
	)
	(gr_poly
		(pts
			(xy 338.136738 -249.416062) (xy 338.136738 -249.371612) (xy 337.781138 -249.371612) (xy 337.781138 -249.416062)
			(xy 337.828128 -249.568462) (xy 338.089748 -249.568462)
		)
		(stroke
			(width 0)
			(type solid)
		)
		(fill yes)
		(layer "In11.Cu")
		(net "M_D_CPU0_SB_CA<2>")
	)
	(gr_poly
		(pts
			(xy 338.136738 -248.196354) (xy 338.089748 -248.043954) (xy 337.828128 -248.043954) (xy 337.781138 -248.196354)
			(xy 337.781138 -248.240804) (xy 338.136738 -248.240804)
		)
		(stroke
			(width 0)
			(type solid)
		)
		(fill yes)
		(layer "In11.Cu")
		(net "M_D_CPU0_SB_CA<5>")
	)
	(gr_poly
		(pts
			(xy 338.136738 -244.940582) (xy 338.089748 -244.788182) (xy 337.828128 -244.788182) (xy 337.781138 -244.940582)
			(xy 337.781138 -244.985032) (xy 338.136738 -244.985032)
		)
		(stroke
			(width 0)
			(type solid)
		)
		(fill yes)
		(layer "In11.Cu")
		(net "M_D_CPU0_SB_DQS_DN<9>")
	)
	(gr_poly
		(pts
			(xy 338.136738 -244.532658) (xy 338.136738 -244.488208) (xy 337.781138 -244.488208) (xy 337.781138 -244.532658)
			(xy 337.828128 -244.685058) (xy 338.089748 -244.685058)
		)
		(stroke
			(width 0)
			(type solid)
		)
		(fill yes)
		(layer "In11.Cu")
		(net "M_D_CPU0_SB_DQS_DN<4>")
	)
	(gr_poly
		(pts
			(xy 338.136738 -240.057178) (xy 338.089748 -239.904778) (xy 337.828128 -239.904778) (xy 337.781138 -240.057178)
			(xy 337.781138 -240.101628) (xy 338.136738 -240.101628)
		)
		(stroke
			(width 0)
			(type solid)
		)
		(fill yes)
		(layer "In11.Cu")
		(net "M_D_CPU0_SB_DQS_DN<0>")
	)
	(gr_poly
		(pts
			(xy 338.136738 -239.649254) (xy 338.136738 -239.604804) (xy 337.781138 -239.604804) (xy 337.781138 -239.649254)
			(xy 337.828128 -239.801654) (xy 338.089748 -239.801654)
		)
		(stroke
			(width 0)
			(type solid)
		)
		(fill yes)
		(layer "In11.Cu")
		(net "M_D_CPU0_SB_DQS_DN<5>")
	)
	(gr_poly
		(pts
			(xy 338.136738 -230.290878) (xy 338.089748 -230.138478) (xy 337.828128 -230.138478) (xy 337.781138 -230.290878)
			(xy 337.781138 -230.335074) (xy 338.136738 -230.335074)
		)
		(stroke
			(width 0)
			(type solid)
		)
		(fill yes)
		(layer "In11.Cu")
		(net "M_D_CPU0_SB_DQ<15>")
	)
	(gr_poly
		(pts
			(xy 338.136738 -229.882446) (xy 338.136738 -229.83825) (xy 337.781138 -229.83825) (xy 337.781138 -229.882446)
			(xy 337.828128 -230.034846) (xy 338.089748 -230.034846)
		)
		(stroke
			(width 0)
			(type solid)
		)
		(fill yes)
		(layer "In11.Cu")
		(net "M_D_CPU0_SB_DQ<24>")
	)
	(gr_poly
		(pts
			(xy 338.14258 -246.568722) (xy 338.09559 -246.416322) (xy 337.83397 -246.416322) (xy 337.78698 -246.568722)
			(xy 337.78698 -246.613172) (xy 338.14258 -246.613172)
		)
		(stroke
			(width 0)
			(type solid)
		)
		(fill yes)
		(layer "In11.Cu")
		(net "M_D_CPU0_SB_CB<6>")
	)
	(gr_poly
		(pts
			(xy 338.143088 -231.919018) (xy 338.096098 -231.766618) (xy 337.834478 -231.766618) (xy 337.787488 -231.919018)
			(xy 337.787488 -231.963214) (xy 338.143088 -231.963214)
		)
		(stroke
			(width 0)
			(type solid)
		)
		(fill yes)
		(layer "In11.Cu")
		(net "M_D_CPU0_SB_DQS_DP<6>")
	)
	(gr_poly
		(pts
			(xy 338.143088 -227.035614) (xy 338.096098 -226.883214) (xy 337.834478 -226.883214) (xy 337.787488 -227.035614)
			(xy 337.787488 -227.07981) (xy 338.143088 -227.07981)
		)
		(stroke
			(width 0)
			(type solid)
		)
		(fill yes)
		(layer "In11.Cu")
		(net "M_D_CPU0_SB_DQS_DP<8>")
	)
	(gr_poly
		(pts
			(xy 338.148676 -247.787922) (xy 338.148676 -247.743472) (xy 337.793076 -247.743472) (xy 337.793076 -247.787922)
			(xy 337.840066 -247.940322) (xy 338.101686 -247.940322)
		)
		(stroke
			(width 0)
			(type solid)
		)
		(fill yes)
		(layer "In11.Cu")
		(net "M_D_CPU0_SB_PAR")
	)
	(gr_poly
		(pts
			(xy 338.252562 -279.354788) (xy 338.205572 -279.202388) (xy 337.943952 -279.202388) (xy 337.896962 -279.354788)
			(xy 337.896962 -279.398984) (xy 338.252562 -279.398984)
		)
		(stroke
			(width 0)
			(type solid)
		)
		(fill yes)
		(layer "In11.Cu")
		(net "M_D_CPU0_SA_DQ<10>")
	)
	(gr_poly
		(pts
			(xy 338.252562 -278.945848) (xy 338.252562 -278.901652) (xy 337.896962 -278.901652) (xy 337.896962 -278.945848)
			(xy 337.943952 -279.098248) (xy 338.205572 -279.098248)
		)
		(stroke
			(width 0)
			(type solid)
		)
		(fill yes)
		(layer "In11.Cu")
		(net "M_D_CPU0_SA_DQ<9>")
	)
	(gr_poly
		(pts
			(xy 338.252562 -276.09927) (xy 338.205572 -275.94687) (xy 337.943952 -275.94687) (xy 337.896962 -276.09927)
			(xy 337.896962 -276.143466) (xy 338.252562 -276.143466)
		)
		(stroke
			(width 0)
			(type solid)
		)
		(fill yes)
		(layer "In11.Cu")
		(net "M_D_CPU0_SA_DQ<14>")
	)
	(gr_poly
		(pts
			(xy 338.252562 -275.690584) (xy 338.252562 -275.646134) (xy 337.896962 -275.646134) (xy 337.896962 -275.690584)
			(xy 337.943952 -275.842984) (xy 338.205572 -275.842984)
		)
		(stroke
			(width 0)
			(type solid)
		)
		(fill yes)
		(layer "In11.Cu")
		(net "M_D_CPU0_SA_DQ<13>")
	)
	(gr_poly
		(pts
			(xy 338.252562 -274.47113) (xy 338.205572 -274.31873) (xy 337.943952 -274.31873) (xy 337.896962 -274.47113)
			(xy 337.896962 -274.51558) (xy 338.252562 -274.51558)
		)
		(stroke
			(width 0)
			(type solid)
		)
		(fill yes)
		(layer "In11.Cu")
		(net "M_D_CPU0_SA_DQ<18>")
	)
	(gr_poly
		(pts
			(xy 338.252562 -274.062698) (xy 338.252562 -274.018248) (xy 337.896962 -274.018248) (xy 337.896962 -274.062698)
			(xy 337.943952 -274.215098) (xy 338.205572 -274.215098)
		)
		(stroke
			(width 0)
			(type solid)
		)
		(fill yes)
		(layer "In11.Cu")
		(net "M_D_CPU0_SA_DQ<17>")
	)
	(gr_poly
		(pts
			(xy 338.252562 -271.215866) (xy 338.205572 -271.063466) (xy 337.943952 -271.063466) (xy 337.896962 -271.215866)
			(xy 337.896962 -271.260062) (xy 338.252562 -271.260062)
		)
		(stroke
			(width 0)
			(type solid)
		)
		(fill yes)
		(layer "In11.Cu")
		(net "M_D_CPU0_SA_DQ<22>")
	)
	(gr_poly
		(pts
			(xy 338.252562 -270.806926) (xy 338.252562 -270.76273) (xy 337.896962 -270.76273) (xy 337.896962 -270.806926)
			(xy 337.943952 -270.959326) (xy 338.205572 -270.959326)
		)
		(stroke
			(width 0)
			(type solid)
		)
		(fill yes)
		(layer "In11.Cu")
		(net "M_D_CPU0_SA_DQ<21>")
	)
	(gr_poly
		(pts
			(xy 338.252562 -269.587726) (xy 338.205572 -269.435326) (xy 337.943952 -269.435326) (xy 337.896962 -269.587726)
			(xy 337.896962 -269.632176) (xy 338.252562 -269.632176)
		)
		(stroke
			(width 0)
			(type solid)
		)
		(fill yes)
		(layer "In11.Cu")
		(net "M_D_CPU0_SA_DQ<26>")
	)
	(gr_poly
		(pts
			(xy 338.252562 -269.179294) (xy 338.252562 -269.134844) (xy 337.896962 -269.134844) (xy 337.896962 -269.179294)
			(xy 337.943952 -269.331694) (xy 338.205572 -269.331694)
		)
		(stroke
			(width 0)
			(type solid)
		)
		(fill yes)
		(layer "In11.Cu")
		(net "M_D_CPU0_SA_DQ<25>")
	)
	(gr_poly
		(pts
			(xy 338.252562 -266.332462) (xy 338.205572 -266.180062) (xy 337.943952 -266.180062) (xy 337.896962 -266.332462)
			(xy 337.896962 -266.376658) (xy 338.252562 -266.376658)
		)
		(stroke
			(width 0)
			(type solid)
		)
		(fill yes)
		(layer "In11.Cu")
		(net "M_D_CPU0_SA_DQ<30>")
	)
	(gr_poly
		(pts
			(xy 338.252562 -265.923522) (xy 338.252562 -265.879326) (xy 337.896962 -265.879326) (xy 337.896962 -265.923522)
			(xy 337.943952 -266.075922) (xy 338.205572 -266.075922)
		)
		(stroke
			(width 0)
			(type solid)
		)
		(fill yes)
		(layer "In11.Cu")
		(net "M_D_CPU0_SA_DQ<29>")
	)
	(gr_poly
		(pts
			(xy 338.252562 -264.70483) (xy 338.205572 -264.55243) (xy 337.943952 -264.55243) (xy 337.896962 -264.70483)
			(xy 337.896962 -264.749026) (xy 338.252562 -264.749026)
		)
		(stroke
			(width 0)
			(type solid)
		)
		(fill yes)
		(layer "In11.Cu")
		(net "M_D_CPU0_SA_CB<2>")
	)
	(gr_poly
		(pts
			(xy 338.252562 -264.29589) (xy 338.252562 -264.251694) (xy 337.896962 -264.251694) (xy 337.896962 -264.29589)
			(xy 337.943952 -264.44829) (xy 338.205572 -264.44829)
		)
		(stroke
			(width 0)
			(type solid)
		)
		(fill yes)
		(layer "In11.Cu")
		(net "M_D_CPU0_SA_CB<1>")
	)
	(gr_poly
		(pts
			(xy 338.252562 -261.449058) (xy 338.205572 -261.296658) (xy 337.943952 -261.296658) (xy 337.896962 -261.449058)
			(xy 337.896962 -261.493508) (xy 338.252562 -261.493508)
		)
		(stroke
			(width 0)
			(type solid)
		)
		(fill yes)
		(layer "In11.Cu")
		(net "M_D_CPU0_SA_CB<6>")
	)
	(gr_poly
		(pts
			(xy 338.252562 -261.040626) (xy 338.252562 -260.996176) (xy 337.896962 -260.996176) (xy 337.896962 -261.040626)
			(xy 337.943952 -261.193026) (xy 338.205572 -261.193026)
		)
		(stroke
			(width 0)
			(type solid)
		)
		(fill yes)
		(layer "In11.Cu")
		(net "M_D_CPU0_SA_CB<5>")
	)
	(gr_poly
		(pts
			(xy 338.252562 -259.412486) (xy 338.252562 -259.36829) (xy 337.896962 -259.36829) (xy 337.896962 -259.412486)
			(xy 337.943952 -259.564886) (xy 338.205572 -259.564886)
		)
		(stroke
			(width 0)
			(type solid)
		)
		(fill yes)
		(layer "In11.Cu")
		(net "M_D_CPU0_SA_CS_N<2>")
	)
	(gr_poly
		(pts
			(xy 338.252562 -256.565654) (xy 338.205572 -256.413254) (xy 337.943952 -256.413254) (xy 337.896962 -256.565654)
			(xy 337.896962 -256.610104) (xy 338.252562 -256.610104)
		)
		(stroke
			(width 0)
			(type solid)
		)
		(fill yes)
		(layer "In11.Cu")
		(net "M_D_CPU0_SA_CA<3>")
	)
	(gr_poly
		(pts
			(xy 338.252562 -256.157222) (xy 338.252562 -256.112772) (xy 337.896962 -256.112772) (xy 337.896962 -256.157222)
			(xy 337.943952 -256.309622) (xy 338.205572 -256.309622)
		)
		(stroke
			(width 0)
			(type solid)
		)
		(fill yes)
		(layer "In11.Cu")
		(net "M_D_CPU0_SA_CA<4>")
	)
	(gr_poly
		(pts
			(xy 338.254848 -262.668258) (xy 338.254848 -262.623808) (xy 337.899248 -262.623808) (xy 337.899248 -262.668258)
			(xy 337.946238 -262.820658) (xy 338.207858 -262.820658)
		)
		(stroke
			(width 0)
			(type solid)
		)
		(fill yes)
		(layer "In11.Cu")
		(net "M_D_CPU0_SA_DQS_DN<9>")
	)
	(gr_poly
		(pts
			(xy 338.258658 -277.726394) (xy 338.211668 -277.573994) (xy 337.950048 -277.573994) (xy 337.903058 -277.726394)
			(xy 337.903058 -277.770844) (xy 338.258658 -277.770844)
		)
		(stroke
			(width 0)
			(type solid)
		)
		(fill yes)
		(layer "In11.Cu")
		(net "M_D_CPU0_SA_DQS_DN<1>")
	)
	(gr_poly
		(pts
			(xy 338.258658 -277.318216) (xy 338.258658 -277.27402) (xy 337.903058 -277.27402) (xy 337.903058 -277.318216)
			(xy 337.950048 -277.470616) (xy 338.211668 -277.470616)
		)
		(stroke
			(width 0)
			(type solid)
		)
		(fill yes)
		(layer "In11.Cu")
		(net "M_D_CPU0_SA_DQS_DN<6>")
	)
	(gr_poly
		(pts
			(xy 338.258658 -272.843498) (xy 338.211668 -272.691098) (xy 337.950048 -272.691098) (xy 337.903058 -272.843498)
			(xy 337.903058 -272.887694) (xy 338.258658 -272.887694)
		)
		(stroke
			(width 0)
			(type solid)
		)
		(fill yes)
		(layer "In11.Cu")
		(net "M_D_CPU0_SA_DQS_DN<2>")
	)
	(gr_poly
		(pts
			(xy 338.258658 -272.435066) (xy 338.258658 -272.39087) (xy 337.903058 -272.39087) (xy 337.903058 -272.435066)
			(xy 337.950048 -272.587466) (xy 338.211668 -272.587466)
		)
		(stroke
			(width 0)
			(type solid)
		)
		(fill yes)
		(layer "In11.Cu")
		(net "M_D_CPU0_SA_DQS_DN<7>")
	)
	(gr_poly
		(pts
			(xy 338.258658 -267.960094) (xy 338.211668 -267.807694) (xy 337.950048 -267.807694) (xy 337.903058 -267.960094)
			(xy 337.903058 -268.00429) (xy 338.258658 -268.00429)
		)
		(stroke
			(width 0)
			(type solid)
		)
		(fill yes)
		(layer "In11.Cu")
		(net "M_D_CPU0_SA_DQS_DN<3>")
	)
	(gr_poly
		(pts
			(xy 338.258658 -267.551662) (xy 338.258658 -267.507466) (xy 337.903058 -267.507466) (xy 337.903058 -267.551662)
			(xy 337.950048 -267.704062) (xy 338.211668 -267.704062)
		)
		(stroke
			(width 0)
			(type solid)
		)
		(fill yes)
		(layer "In11.Cu")
		(net "M_D_CPU0_SA_DQS_DN<8>")
	)
	(gr_poly
		(pts
			(xy 338.258658 -263.07669) (xy 338.211668 -262.92429) (xy 337.950048 -262.92429) (xy 337.903058 -263.07669)
			(xy 337.903058 -263.120886) (xy 338.258658 -263.120886)
		)
		(stroke
			(width 0)
			(type solid)
		)
		(fill yes)
		(layer "In11.Cu")
		(net "M_D_CPU0_SA_DQS_DN<4>")
	)
	(gr_poly
		(pts
			(xy 338.258658 -258.193286) (xy 338.211668 -258.040886) (xy 337.950048 -258.040886) (xy 337.903058 -258.193286)
			(xy 337.903058 -258.237482) (xy 338.258658 -258.237482)
		)
		(stroke
			(width 0)
			(type solid)
		)
		(fill yes)
		(layer "In11.Cu")
		(net "M_D_CPU0_SA_CS_N<1>")
	)
	(gr_poly
		(pts
			(xy 338.258658 -257.784854) (xy 338.258658 -257.740658) (xy 337.903058 -257.740658) (xy 337.903058 -257.784854)
			(xy 337.950048 -257.937254) (xy 338.211668 -257.937254)
		)
		(stroke
			(width 0)
			(type solid)
		)
		(fill yes)
		(layer "In11.Cu")
		(net "M_D_CPU0_SA_CA<0>")
	)
	(gr_poly
		(pts
			(xy 338.47024 -236.250734) (xy 338.508594 -236.228636) (xy 338.330794 -235.920788) (xy 338.29244 -235.942886)
			(xy 338.183982 -236.059726) (xy 338.314792 -236.286294)
		)
		(stroke
			(width 0)
			(type solid)
		)
		(fill yes)
		(layer "In11.Cu")
		(net "M_D_CPU0_SB_DQ<9>")
	)
	(gr_poly
		(pts
			(xy 338.579206 -235.628942) (xy 338.687664 -235.512102) (xy 338.556854 -235.285534) (xy 338.401406 -235.321094)
			(xy 338.363052 -235.343192) (xy 338.540852 -235.65104)
		)
		(stroke
			(width 0)
			(type solid)
		)
		(fill yes)
		(layer "In11.Cu")
		(net "M_D_CPU0_SB_DQ<11>")
	)
	(gr_poly
		(pts
			(xy 338.606638 -245.346474) (xy 338.606638 -245.302024) (xy 338.251038 -245.302024) (xy 338.251038 -245.346474)
			(xy 338.298028 -245.498874) (xy 338.559648 -245.498874)
		)
		(stroke
			(width 0)
			(type solid)
		)
		(fill yes)
		(layer "In11.Cu")
		(net "M_D_CPU0_SB_DQS_DP<9>")
	)
	(gr_poly
		(pts
			(xy 338.606638 -240.46307) (xy 338.606638 -240.41862) (xy 338.251038 -240.41862) (xy 338.251038 -240.46307)
			(xy 338.298028 -240.61547) (xy 338.559648 -240.61547)
		)
		(stroke
			(width 0)
			(type solid)
		)
		(fill yes)
		(layer "In11.Cu")
		(net "M_D_CPU0_SB_DQS_DP<0>")
	)
	(gr_poly
		(pts
			(xy 338.606638 -230.696262) (xy 338.606638 -230.651812) (xy 338.251038 -230.651812) (xy 338.251038 -230.696262)
			(xy 338.298028 -230.848662) (xy 338.559648 -230.848662)
		)
		(stroke
			(width 0)
			(type solid)
		)
		(fill yes)
		(layer "In11.Cu")
		(net "M_D_CPU0_SB_DQ<13>")
	)
	(gr_poly
		(pts
			(xy 338.612734 -249.010678) (xy 338.565744 -248.858278) (xy 338.304124 -248.858278) (xy 338.257134 -249.010678)
			(xy 338.257134 -249.054874) (xy 338.612734 -249.054874)
		)
		(stroke
			(width 0)
			(type solid)
		)
		(fill yes)
		(layer "In11.Cu")
		(net "M_D_CPU0_SB_CA<3>")
	)
	(gr_poly
		(pts
			(xy 338.612734 -244.127274) (xy 338.565744 -243.974874) (xy 338.304124 -243.974874) (xy 338.257134 -244.127274)
			(xy 338.257134 -244.17147) (xy 338.612734 -244.17147)
		)
		(stroke
			(width 0)
			(type solid)
		)
		(fill yes)
		(layer "In11.Cu")
		(net "M_D_CPU0_SB_DQS_DP<4>")
	)
	(gr_poly
		(pts
			(xy 338.612734 -239.24387) (xy 338.565744 -239.09147) (xy 338.304124 -239.09147) (xy 338.257134 -239.24387)
			(xy 338.257134 -239.288066) (xy 338.612734 -239.288066)
		)
		(stroke
			(width 0)
			(type solid)
		)
		(fill yes)
		(layer "In11.Cu")
		(net "M_D_CPU0_SB_DQS_DP<5>")
	)
	(gr_poly
		(pts
			(xy 338.612734 -229.477062) (xy 338.565744 -229.324662) (xy 338.304124 -229.324662) (xy 338.257134 -229.477062)
			(xy 338.257134 -229.521512) (xy 338.612734 -229.521512)
		)
		(stroke
			(width 0)
			(type solid)
		)
		(fill yes)
		(layer "In11.Cu")
		(net "M_D_CPU0_SB_DQ<26>")
	)
	(gr_poly
		(pts
			(xy 338.618576 -247.382538) (xy 338.571586 -247.230138) (xy 338.309966 -247.230138) (xy 338.262976 -247.382538)
			(xy 338.262976 -247.426734) (xy 338.618576 -247.426734)
		)
		(stroke
			(width 0)
			(type solid)
		)
		(fill yes)
		(layer "In11.Cu")
		(net "M_D_CPU0_SB_CA<6>")
	)
	(gr_poly
		(pts
			(xy 338.618576 -246.974106) (xy 338.618576 -246.92991) (xy 338.262976 -246.92991) (xy 338.262976 -246.974106)
			(xy 338.309966 -247.126506) (xy 338.571586 -247.126506)
		)
		(stroke
			(width 0)
			(type solid)
		)
		(fill yes)
		(layer "In11.Cu")
		(net "M_D_CPU0_SB_CB<4>")
	)
	(gr_poly
		(pts
			(xy 338.618576 -245.754906) (xy 338.571586 -245.602506) (xy 338.309966 -245.602506) (xy 338.262976 -245.754906)
			(xy 338.262976 -245.799356) (xy 338.618576 -245.799356)
		)
		(stroke
			(width 0)
			(type solid)
		)
		(fill yes)
		(layer "In11.Cu")
		(net "M_D_CPU0_SB_CB<7>")
	)
	(gr_poly
		(pts
			(xy 338.618576 -240.871502) (xy 338.571586 -240.719102) (xy 338.309966 -240.719102) (xy 338.262976 -240.871502)
			(xy 338.262976 -240.915952) (xy 338.618576 -240.915952)
		)
		(stroke
			(width 0)
			(type solid)
		)
		(fill yes)
		(layer "In11.Cu")
		(net "M_D_CPU0_SB_DQ<3>")
	)
	(gr_poly
		(pts
			(xy 338.618576 -231.104694) (xy 338.571586 -230.952294) (xy 338.309966 -230.952294) (xy 338.262976 -231.104694)
			(xy 338.262976 -231.149144) (xy 338.618576 -231.149144)
		)
		(stroke
			(width 0)
			(type solid)
		)
		(fill yes)
		(layer "In11.Cu")
		(net "M_D_CPU0_SB_DQ<14>")
	)
	(gr_poly
		(pts
			(xy 338.618576 -226.221798) (xy 338.571586 -226.069398) (xy 338.309966 -226.069398) (xy 338.262976 -226.221798)
			(xy 338.262976 -226.265994) (xy 338.618576 -226.265994)
		)
		(stroke
			(width 0)
			(type solid)
		)
		(fill yes)
		(layer "In11.Cu")
		(net "M_D_CPU0_SB_DQ<30>")
	)
	(gr_poly
		(pts
			(xy 338.618576 -225.812858) (xy 338.618576 -225.768662) (xy 338.262976 -225.768662) (xy 338.262976 -225.812858)
			(xy 338.309966 -225.965258) (xy 338.571586 -225.965258)
		)
		(stroke
			(width 0)
			(type solid)
		)
		(fill yes)
		(layer "In11.Cu")
		(net "M_D_CPU0_SB_DQ<29>")
	)
	(gr_poly
		(pts
			(xy 338.621116 -248.602246) (xy 338.621116 -248.557796) (xy 338.265516 -248.557796) (xy 338.265516 -248.602246)
			(xy 338.312506 -248.754646) (xy 338.574126 -248.754646)
		)
		(stroke
			(width 0)
			(type solid)
		)
		(fill yes)
		(layer "In11.Cu")
		(net "M_D_CPU0_SB_CA<4>")
	)
	(gr_poly
		(pts
			(xy 338.621116 -243.718842) (xy 338.621116 -243.674392) (xy 338.265516 -243.674392) (xy 338.265516 -243.718842)
			(xy 338.312506 -243.871242) (xy 338.574126 -243.871242)
		)
		(stroke
			(width 0)
			(type solid)
		)
		(fill yes)
		(layer "In11.Cu")
		(net "M_D_CPU0_SB_CB<0>")
	)
	(gr_poly
		(pts
			(xy 338.621116 -242.499134) (xy 338.574126 -242.346734) (xy 338.312506 -242.346734) (xy 338.265516 -242.499134)
			(xy 338.265516 -242.54333) (xy 338.621116 -242.54333)
		)
		(stroke
			(width 0)
			(type solid)
		)
		(fill yes)
		(layer "In11.Cu")
		(net "M_D_CPU0_SB_CB<3>")
	)
	(gr_poly
		(pts
			(xy 338.621116 -242.090702) (xy 338.621116 -242.046506) (xy 338.265516 -242.046506) (xy 338.265516 -242.090702)
			(xy 338.312506 -242.243102) (xy 338.574126 -242.243102)
		)
		(stroke
			(width 0)
			(type solid)
		)
		(fill yes)
		(layer "In11.Cu")
		(net "M_D_CPU0_SB_DQ<0>")
	)
	(gr_poly
		(pts
			(xy 338.621116 -238.835438) (xy 338.621116 -238.790988) (xy 338.265516 -238.790988) (xy 338.265516 -238.835438)
			(xy 338.312506 -238.987838) (xy 338.574126 -238.987838)
		)
		(stroke
			(width 0)
			(type solid)
		)
		(fill yes)
		(layer "In11.Cu")
		(net "M_D_CPU0_SB_DQ<4>")
	)
	(gr_poly
		(pts
			(xy 338.621116 -237.61573) (xy 338.574126 -237.46333) (xy 338.312506 -237.46333) (xy 338.265516 -237.61573)
			(xy 338.265516 -237.659926) (xy 338.621116 -237.659926)
		)
		(stroke
			(width 0)
			(type solid)
		)
		(fill yes)
		(layer "In11.Cu")
		(net "M_D_CPU0_SB_DQ<7>")
	)
	(gr_poly
		(pts
			(xy 338.621116 -237.207806) (xy 338.621116 -237.163356) (xy 338.265516 -237.163356) (xy 338.265516 -237.207806)
			(xy 338.312506 -237.360206) (xy 338.574126 -237.360206)
		)
		(stroke
			(width 0)
			(type solid)
		)
		(fill yes)
		(layer "In11.Cu")
		(net "M_D_CPU0_SB_DQ<8>")
	)
	(gr_poly
		(pts
			(xy 338.621116 -233.952034) (xy 338.621116 -233.907838) (xy 338.265516 -233.907838) (xy 338.265516 -233.952034)
			(xy 338.312506 -234.104434) (xy 338.574126 -234.104434)
		)
		(stroke
			(width 0)
			(type solid)
		)
		(fill yes)
		(layer "In11.Cu")
		(net "M_D_CPU0_SB_DQS_DP<1>")
	)
	(gr_poly
		(pts
			(xy 338.621116 -232.324402) (xy 338.621116 -232.279952) (xy 338.265516 -232.279952) (xy 338.265516 -232.324402)
			(xy 338.312506 -232.476802) (xy 338.574126 -232.476802)
		)
		(stroke
			(width 0)
			(type solid)
		)
		(fill yes)
		(layer "In11.Cu")
		(net "M_D_CPU0_SB_DQS_DN<6>")
	)
	(gr_poly
		(pts
			(xy 338.621116 -229.06863) (xy 338.621116 -229.024434) (xy 338.265516 -229.024434) (xy 338.265516 -229.06863)
			(xy 338.312506 -229.22103) (xy 338.574126 -229.22103)
		)
		(stroke
			(width 0)
			(type solid)
		)
		(fill yes)
		(layer "In11.Cu")
		(net "M_D_CPU0_SB_DQ<25>")
	)
	(gr_poly
		(pts
			(xy 338.621116 -227.848922) (xy 338.574126 -227.696522) (xy 338.312506 -227.696522) (xy 338.265516 -227.848922)
			(xy 338.265516 -227.893372) (xy 338.621116 -227.893372)
		)
		(stroke
			(width 0)
			(type solid)
		)
		(fill yes)
		(layer "In11.Cu")
		(net "M_D_CPU0_SB_DQS_DN<3>")
	)
	(gr_poly
		(pts
			(xy 338.621116 -227.440998) (xy 338.621116 -227.396548) (xy 338.265516 -227.396548) (xy 338.265516 -227.440998)
			(xy 338.312506 -227.593398) (xy 338.574126 -227.593398)
		)
		(stroke
			(width 0)
			(type solid)
		)
		(fill yes)
		(layer "In11.Cu")
		(net "M_D_CPU0_SB_DQS_DN<8>")
	)
	(gr_poly
		(pts
			(xy 338.71408 -278.132286) (xy 338.71408 -278.08809) (xy 338.35848 -278.08809) (xy 338.35848 -278.132286)
			(xy 338.40547 -278.284686) (xy 338.66709 -278.284686)
		)
		(stroke
			(width 0)
			(type solid)
		)
		(fill yes)
		(layer "In11.Cu")
		(net "M_D_CPU0_SA_DQS_DP<1>")
	)
	(gr_poly
		(pts
			(xy 338.71408 -276.912578) (xy 338.66709 -276.760178) (xy 338.40547 -276.760178) (xy 338.35848 -276.912578)
			(xy 338.35848 -276.957028) (xy 338.71408 -276.957028)
		)
		(stroke
			(width 0)
			(type solid)
		)
		(fill yes)
		(layer "In11.Cu")
		(net "M_D_CPU0_SA_DQS_DP<6>")
	)
	(gr_poly
		(pts
			(xy 338.71408 -272.029174) (xy 338.66709 -271.876774) (xy 338.40547 -271.876774) (xy 338.35848 -272.029174)
			(xy 338.35848 -272.073624) (xy 338.71408 -272.073624)
		)
		(stroke
			(width 0)
			(type solid)
		)
		(fill yes)
		(layer "In11.Cu")
		(net "M_D_CPU0_SA_DQS_DP<7>")
	)
	(gr_poly
		(pts
			(xy 338.71408 -267.14577) (xy 338.66709 -266.99337) (xy 338.40547 -266.99337) (xy 338.35848 -267.14577)
			(xy 338.35848 -267.19022) (xy 338.71408 -267.19022)
		)
		(stroke
			(width 0)
			(type solid)
		)
		(fill yes)
		(layer "In11.Cu")
		(net "M_D_CPU0_SA_DQS_DP<8>")
	)
	(gr_poly
		(pts
			(xy 338.71408 -257.37947) (xy 338.66709 -257.22707) (xy 338.40547 -257.22707) (xy 338.35848 -257.37947)
			(xy 338.35848 -257.423666) (xy 338.71408 -257.423666)
		)
		(stroke
			(width 0)
			(type solid)
		)
		(fill yes)
		(layer "In11.Cu")
		(net "M_D_CPU0_SA_CA<1>")
	)
	(gr_poly
		(pts
			(xy 338.71662 -273.248882) (xy 338.71662 -273.204686) (xy 338.36102 -273.204686) (xy 338.36102 -273.248882)
			(xy 338.40801 -273.401282) (xy 338.66963 -273.401282)
		)
		(stroke
			(width 0)
			(type solid)
		)
		(fill yes)
		(layer "In11.Cu")
		(net "M_D_CPU0_SA_DQS_DP<2>")
	)
	(gr_poly
		(pts
			(xy 338.71662 -268.365478) (xy 338.71662 -268.321282) (xy 338.36102 -268.321282) (xy 338.36102 -268.365478)
			(xy 338.40801 -268.517878) (xy 338.66963 -268.517878)
		)
		(stroke
			(width 0)
			(type solid)
		)
		(fill yes)
		(layer "In11.Cu")
		(net "M_D_CPU0_SA_DQS_DP<3>")
	)
	(gr_poly
		(pts
			(xy 338.71662 -263.482582) (xy 338.71662 -263.438132) (xy 338.36102 -263.438132) (xy 338.36102 -263.482582)
			(xy 338.40801 -263.634982) (xy 338.66963 -263.634982)
		)
		(stroke
			(width 0)
			(type solid)
		)
		(fill yes)
		(layer "In11.Cu")
		(net "M_D_CPU0_SA_DQS_DP<4>")
	)
	(gr_poly
		(pts
			(xy 338.71662 -258.599178) (xy 338.71662 -258.554728) (xy 338.36102 -258.554728) (xy 338.36102 -258.599178)
			(xy 338.40801 -258.751578) (xy 338.66963 -258.751578)
		)
		(stroke
			(width 0)
			(type solid)
		)
		(fill yes)
		(layer "In11.Cu")
		(net "M_D_CPU0_SA_CS_N<3>")
	)
	(gr_poly
		(pts
			(xy 338.71916 -262.262874) (xy 338.67217 -262.110474) (xy 338.41055 -262.110474) (xy 338.36356 -262.262874)
			(xy 338.36356 -262.307324) (xy 338.71916 -262.307324)
		)
		(stroke
			(width 0)
			(type solid)
		)
		(fill yes)
		(layer "In11.Cu")
		(net "M_D_CPU0_SA_DQS_DP<9>")
	)
	(gr_poly
		(pts
			(xy 338.722462 -278.540718) (xy 338.675472 -278.388318) (xy 338.413852 -278.388318) (xy 338.366862 -278.540718)
			(xy 338.366862 -278.585168) (xy 338.722462 -278.585168)
		)
		(stroke
			(width 0)
			(type solid)
		)
		(fill yes)
		(layer "In11.Cu")
		(net "M_D_CPU0_SA_DQ<11>")
	)
	(gr_poly
		(pts
			(xy 338.722462 -276.504146) (xy 338.722462 -276.45995) (xy 338.366862 -276.45995) (xy 338.366862 -276.504146)
			(xy 338.413852 -276.656546) (xy 338.675472 -276.656546)
		)
		(stroke
			(width 0)
			(type solid)
		)
		(fill yes)
		(layer "In11.Cu")
		(net "M_D_CPU0_SA_DQ<12>")
	)
	(gr_poly
		(pts
			(xy 338.722462 -271.620742) (xy 338.722462 -271.576546) (xy 338.366862 -271.576546) (xy 338.366862 -271.620742)
			(xy 338.413852 -271.773142) (xy 338.675472 -271.773142)
		)
		(stroke
			(width 0)
			(type solid)
		)
		(fill yes)
		(layer "In11.Cu")
		(net "M_D_CPU0_SA_DQ<20>")
	)
	(gr_poly
		(pts
			(xy 338.722462 -266.737846) (xy 338.722462 -266.693396) (xy 338.366862 -266.693396) (xy 338.366862 -266.737846)
			(xy 338.413852 -266.890246) (xy 338.675472 -266.890246)
		)
		(stroke
			(width 0)
			(type solid)
		)
		(fill yes)
		(layer "In11.Cu")
		(net "M_D_CPU0_SA_DQ<28>")
	)
	(gr_poly
		(pts
			(xy 338.722462 -261.854442) (xy 338.722462 -261.809992) (xy 338.366862 -261.809992) (xy 338.366862 -261.854442)
			(xy 338.413852 -262.006842) (xy 338.675472 -262.006842)
		)
		(stroke
			(width 0)
			(type solid)
		)
		(fill yes)
		(layer "In11.Cu")
		(net "M_D_CPU0_SA_CB<4>")
	)
	(gr_poly
		(pts
			(xy 338.722462 -256.971038) (xy 338.722462 -256.926588) (xy 338.366862 -256.926588) (xy 338.366862 -256.971038)
			(xy 338.413852 -257.123438) (xy 338.675472 -257.123438)
		)
		(stroke
			(width 0)
			(type solid)
		)
		(fill yes)
		(layer "In11.Cu")
		(net "M_D_CPU0_SA_CA<2>")
	)
	(gr_poly
		(pts
			(xy 338.728558 -279.759918) (xy 338.728558 -279.715722) (xy 338.372958 -279.715722) (xy 338.372958 -279.759918)
			(xy 338.419948 -279.912318) (xy 338.681568 -279.912318)
		)
		(stroke
			(width 0)
			(type solid)
		)
		(fill yes)
		(layer "In11.Cu")
		(net "M_D_CPU0_SA_DQ<8>")
	)
	(gr_poly
		(pts
			(xy 338.728558 -275.284946) (xy 338.681568 -275.132546) (xy 338.419948 -275.132546) (xy 338.372958 -275.284946)
			(xy 338.372958 -275.329142) (xy 338.728558 -275.329142)
		)
		(stroke
			(width 0)
			(type solid)
		)
		(fill yes)
		(layer "In11.Cu")
		(net "M_D_CPU0_SA_DQ<15>")
	)
	(gr_poly
		(pts
			(xy 338.728558 -274.876514) (xy 338.728558 -274.832318) (xy 338.372958 -274.832318) (xy 338.372958 -274.876514)
			(xy 338.419948 -275.028914) (xy 338.681568 -275.028914)
		)
		(stroke
			(width 0)
			(type solid)
		)
		(fill yes)
		(layer "In11.Cu")
		(net "M_D_CPU0_SA_DQ<16>")
	)
	(gr_poly
		(pts
			(xy 338.728558 -273.657314) (xy 338.681568 -273.504914) (xy 338.419948 -273.504914) (xy 338.372958 -273.657314)
			(xy 338.372958 -273.70151) (xy 338.728558 -273.70151)
		)
		(stroke
			(width 0)
			(type solid)
		)
		(fill yes)
		(layer "In11.Cu")
		(net "M_D_CPU0_SA_DQ<19>")
	)
	(gr_poly
		(pts
			(xy 338.728558 -270.401542) (xy 338.681568 -270.249142) (xy 338.419948 -270.249142) (xy 338.372958 -270.401542)
			(xy 338.372958 -270.445992) (xy 338.728558 -270.445992)
		)
		(stroke
			(width 0)
			(type solid)
		)
		(fill yes)
		(layer "In11.Cu")
		(net "M_D_CPU0_SA_DQ<23>")
	)
	(gr_poly
		(pts
			(xy 338.728558 -269.993618) (xy 338.728558 -269.949168) (xy 338.372958 -269.949168) (xy 338.372958 -269.993618)
			(xy 338.419948 -270.146018) (xy 338.681568 -270.146018)
		)
		(stroke
			(width 0)
			(type solid)
		)
		(fill yes)
		(layer "In11.Cu")
		(net "M_D_CPU0_SA_DQ<24>")
	)
	(gr_poly
		(pts
			(xy 338.728558 -268.77391) (xy 338.681568 -268.62151) (xy 338.419948 -268.62151) (xy 338.372958 -268.77391)
			(xy 338.372958 -268.818106) (xy 338.728558 -268.818106)
		)
		(stroke
			(width 0)
			(type solid)
		)
		(fill yes)
		(layer "In11.Cu")
		(net "M_D_CPU0_SA_DQ<27>")
	)
	(gr_poly
		(pts
			(xy 338.728558 -265.518138) (xy 338.681568 -265.365738) (xy 338.419948 -265.365738) (xy 338.372958 -265.518138)
			(xy 338.372958 -265.562588) (xy 338.728558 -265.562588)
		)
		(stroke
			(width 0)
			(type solid)
		)
		(fill yes)
		(layer "In11.Cu")
		(net "M_D_CPU0_SA_DQ<31>")
	)
	(gr_poly
		(pts
			(xy 338.728558 -265.110214) (xy 338.728558 -265.065764) (xy 338.372958 -265.065764) (xy 338.372958 -265.110214)
			(xy 338.419948 -265.262614) (xy 338.681568 -265.262614)
		)
		(stroke
			(width 0)
			(type solid)
		)
		(fill yes)
		(layer "In11.Cu")
		(net "M_D_CPU0_SA_CB<0>")
	)
	(gr_poly
		(pts
			(xy 338.728558 -263.890506) (xy 338.681568 -263.738106) (xy 338.419948 -263.738106) (xy 338.372958 -263.890506)
			(xy 338.372958 -263.934956) (xy 338.728558 -263.934956)
		)
		(stroke
			(width 0)
			(type solid)
		)
		(fill yes)
		(layer "In11.Cu")
		(net "M_D_CPU0_SA_CB<3>")
	)
	(gr_poly
		(pts
			(xy 338.728558 -260.634734) (xy 338.681568 -260.482334) (xy 338.419948 -260.482334) (xy 338.372958 -260.634734)
			(xy 338.372958 -260.679184) (xy 338.728558 -260.679184)
		)
		(stroke
			(width 0)
			(type solid)
		)
		(fill yes)
		(layer "In11.Cu")
		(net "M_D_CPU0_SA_CB<7>")
	)
	(gr_poly
		(pts
			(xy 338.728558 -259.007102) (xy 338.681568 -258.854702) (xy 338.419948 -258.854702) (xy 338.372958 -259.007102)
			(xy 338.372958 -259.051552) (xy 338.728558 -259.051552)
		)
		(stroke
			(width 0)
			(type solid)
		)
		(fill yes)
		(layer "In11.Cu")
		(net "M_D_CPU0_SA_CS_N<0>")
	)
	(gr_poly
		(pts
			(xy 338.728558 -255.751838) (xy 338.681568 -255.599438) (xy 338.419948 -255.599438) (xy 338.372958 -255.751838)
			(xy 338.372958 -255.796034) (xy 338.728558 -255.796034)
		)
		(stroke
			(width 0)
			(type solid)
		)
		(fill yes)
		(layer "In11.Cu")
		(net "M_D_CPU0_SA_CA<5>")
	)
	(gr_poly
		(pts
			(xy 339.073998 -246.568722) (xy 339.027008 -246.416322) (xy 338.765388 -246.416322) (xy 338.718398 -246.568722)
			(xy 338.718398 -246.612918) (xy 339.073998 -246.612918)
		)
		(stroke
			(width 0)
			(type solid)
		)
		(fill yes)
		(layer "In11.Cu")
		(net "M_D_CPU0_SB_CB<6>")
	)
	(gr_poly
		(pts
			(xy 339.073998 -241.685318) (xy 339.027008 -241.532918) (xy 338.765388 -241.532918) (xy 338.718398 -241.685318)
			(xy 338.718398 -241.729514) (xy 339.073998 -241.729514)
		)
		(stroke
			(width 0)
			(type solid)
		)
		(fill yes)
		(layer "In11.Cu")
		(net "M_D_CPU0_SB_DQ<2>")
	)
	(gr_poly
		(pts
			(xy 339.073998 -236.801914) (xy 339.027008 -236.649514) (xy 338.765388 -236.649514) (xy 338.718398 -236.801914)
			(xy 338.718398 -236.84611) (xy 339.073998 -236.84611)
		)
		(stroke
			(width 0)
			(type solid)
		)
		(fill yes)
		(layer "In11.Cu")
		(net "M_D_CPU0_SB_DQ<10>")
	)
	(gr_poly
		(pts
			(xy 339.076538 -249.415554) (xy 339.076538 -249.371358) (xy 338.720938 -249.371358) (xy 338.720938 -249.415554)
			(xy 338.767928 -249.567954) (xy 339.029548 -249.567954)
		)
		(stroke
			(width 0)
			(type solid)
		)
		(fill yes)
		(layer "In11.Cu")
		(net "M_D_CPU0_SB_CA<2>")
	)
	(gr_poly
		(pts
			(xy 339.076538 -248.196354) (xy 339.029548 -248.043954) (xy 338.767928 -248.043954) (xy 338.720938 -248.196354)
			(xy 338.720938 -248.24055) (xy 339.076538 -248.24055)
		)
		(stroke
			(width 0)
			(type solid)
		)
		(fill yes)
		(layer "In11.Cu")
		(net "M_D_CPU0_SB_CA<5>")
	)
	(gr_poly
		(pts
			(xy 339.076538 -247.787922) (xy 339.076538 -247.743726) (xy 338.720938 -247.743726) (xy 338.720938 -247.787922)
			(xy 338.767928 -247.940322) (xy 339.029548 -247.940322)
		)
		(stroke
			(width 0)
			(type solid)
		)
		(fill yes)
		(layer "In11.Cu")
		(net "M_D_CPU0_SB_PAR")
	)
	(gr_poly
		(pts
			(xy 339.076538 -244.53215) (xy 339.076538 -244.487954) (xy 338.720938 -244.487954) (xy 338.720938 -244.53215)
			(xy 338.767928 -244.68455) (xy 339.029548 -244.68455)
		)
		(stroke
			(width 0)
			(type solid)
		)
		(fill yes)
		(layer "In11.Cu")
		(net "M_D_CPU0_SB_DQS_DN<4>")
	)
	(gr_poly
		(pts
			(xy 339.076538 -243.31295) (xy 339.029548 -243.16055) (xy 338.767928 -243.16055) (xy 338.720938 -243.31295)
			(xy 338.720938 -243.3574) (xy 339.076538 -243.3574)
		)
		(stroke
			(width 0)
			(type solid)
		)
		(fill yes)
		(layer "In11.Cu")
		(net "M_D_CPU0_SB_CB<2>")
	)
	(gr_poly
		(pts
			(xy 339.076538 -242.905026) (xy 339.076538 -242.860576) (xy 338.720938 -242.860576) (xy 338.720938 -242.905026)
			(xy 338.767928 -243.057426) (xy 339.029548 -243.057426)
		)
		(stroke
			(width 0)
			(type solid)
		)
		(fill yes)
		(layer "In11.Cu")
		(net "M_D_CPU0_SB_CB<1>")
	)
	(gr_poly
		(pts
			(xy 339.076538 -239.648746) (xy 339.076538 -239.60455) (xy 338.720938 -239.60455) (xy 338.720938 -239.648746)
			(xy 338.767928 -239.801146) (xy 339.029548 -239.801146)
		)
		(stroke
			(width 0)
			(type solid)
		)
		(fill yes)
		(layer "In11.Cu")
		(net "M_D_CPU0_SB_DQS_DN<5>")
	)
	(gr_poly
		(pts
			(xy 339.076538 -238.429546) (xy 339.029548 -238.277146) (xy 338.767928 -238.277146) (xy 338.720938 -238.429546)
			(xy 338.720938 -238.473996) (xy 339.076538 -238.473996)
		)
		(stroke
			(width 0)
			(type solid)
		)
		(fill yes)
		(layer "In11.Cu")
		(net "M_D_CPU0_SB_DQ<6>")
	)
	(gr_poly
		(pts
			(xy 339.076538 -238.021622) (xy 339.076538 -237.977172) (xy 338.720938 -237.977172) (xy 338.720938 -238.021622)
			(xy 338.767928 -238.174022) (xy 339.029548 -238.174022)
		)
		(stroke
			(width 0)
			(type solid)
		)
		(fill yes)
		(layer "In11.Cu")
		(net "M_D_CPU0_SB_DQ<5>")
	)
	(gr_poly
		(pts
			(xy 339.076538 -233.546142) (xy 339.029548 -233.393742) (xy 338.767928 -233.393742) (xy 338.720938 -233.546142)
			(xy 338.720938 -233.590592) (xy 339.076538 -233.590592)
		)
		(stroke
			(width 0)
			(type solid)
		)
		(fill yes)
		(layer "In11.Cu")
		(net "M_D_CPU0_SB_DQS_DN<1>")
	)
	(gr_poly
		(pts
			(xy 339.076538 -229.882446) (xy 339.076538 -229.837996) (xy 338.720938 -229.837996) (xy 338.720938 -229.882446)
			(xy 338.767928 -230.034846) (xy 339.029548 -230.034846)
		)
		(stroke
			(width 0)
			(type solid)
		)
		(fill yes)
		(layer "In11.Cu")
		(net "M_D_CPU0_SB_DQ<24>")
	)
	(gr_poly
		(pts
			(xy 339.076538 -228.663246) (xy 339.029548 -228.510846) (xy 338.767928 -228.510846) (xy 338.720938 -228.663246)
			(xy 338.720938 -228.707442) (xy 339.076538 -228.707442)
		)
		(stroke
			(width 0)
			(type solid)
		)
		(fill yes)
		(layer "In11.Cu")
		(net "M_D_CPU0_SB_DQ<27>")
	)
	(gr_poly
		(pts
			(xy 339.076538 -228.254814) (xy 339.076538 -228.210618) (xy 338.720938 -228.210618) (xy 338.720938 -228.254814)
			(xy 338.767928 -228.407214) (xy 339.029548 -228.407214)
		)
		(stroke
			(width 0)
			(type solid)
		)
		(fill yes)
		(layer "In11.Cu")
		(net "M_D_CPU0_SB_DQS_DP<3>")
	)
	(gr_poly
		(pts
			(xy 339.08238 -246.16029) (xy 339.08238 -246.11584) (xy 338.72678 -246.11584) (xy 338.72678 -246.16029)
			(xy 338.77377 -246.31269) (xy 339.03539 -246.31269)
		)
		(stroke
			(width 0)
			(type solid)
		)
		(fill yes)
		(layer "In11.Cu")
		(net "M_D_CPU0_SB_CB<5>")
	)
	(gr_poly
		(pts
			(xy 339.08238 -241.276886) (xy 339.08238 -241.232436) (xy 338.72678 -241.232436) (xy 338.72678 -241.276886)
			(xy 338.77377 -241.429286) (xy 339.03539 -241.429286)
		)
		(stroke
			(width 0)
			(type solid)
		)
		(fill yes)
		(layer "In11.Cu")
		(net "M_D_CPU0_SB_DQ<1>")
	)
	(gr_poly
		(pts
			(xy 339.08238 -236.393482) (xy 339.08238 -236.349286) (xy 338.72678 -236.349286) (xy 338.72678 -236.393482)
			(xy 338.77377 -236.545882) (xy 339.03539 -236.545882)
		)
		(stroke
			(width 0)
			(type solid)
		)
		(fill yes)
		(layer "In11.Cu")
		(net "M_D_CPU0_SB_DQ<9>")
	)
	(gr_poly
		(pts
			(xy 339.08238 -231.919018) (xy 339.03539 -231.766618) (xy 338.77377 -231.766618) (xy 338.72678 -231.919018)
			(xy 338.72678 -231.963214) (xy 339.08238 -231.963214)
		)
		(stroke
			(width 0)
			(type solid)
		)
		(fill yes)
		(layer "In11.Cu")
		(net "M_D_CPU0_SB_DQS_DP<6>")
	)
	(gr_poly
		(pts
			(xy 339.08238 -231.510078) (xy 339.08238 -231.465882) (xy 338.72678 -231.465882) (xy 338.72678 -231.510078)
			(xy 338.77377 -231.662478) (xy 339.03539 -231.662478)
		)
		(stroke
			(width 0)
			(type solid)
		)
		(fill yes)
		(layer "In11.Cu")
		(net "M_D_CPU0_SB_DQ<12>")
	)
	(gr_poly
		(pts
			(xy 339.08238 -227.035614) (xy 339.03539 -226.883214) (xy 338.77377 -226.883214) (xy 338.72678 -227.035614)
			(xy 338.72678 -227.07981) (xy 339.08238 -227.07981)
		)
		(stroke
			(width 0)
			(type solid)
		)
		(fill yes)
		(layer "In11.Cu")
		(net "M_D_CPU0_SB_DQS_DP<8>")
	)
	(gr_poly
		(pts
			(xy 339.08238 -225.407474) (xy 339.03539 -225.255074) (xy 338.77377 -225.255074) (xy 338.72678 -225.407474)
			(xy 338.72678 -225.451924) (xy 339.08238 -225.451924)
		)
		(stroke
			(width 0)
			(type solid)
		)
		(fill yes)
		(layer "In11.Cu")
		(net "M_D_CPU0_SB_DQ<31>")
	)
	(gr_poly
		(pts
			(xy 339.088476 -244.94109) (xy 339.041486 -244.78869) (xy 338.779866 -244.78869) (xy 338.732876 -244.94109)
			(xy 338.732876 -244.985286) (xy 339.088476 -244.985286)
		)
		(stroke
			(width 0)
			(type solid)
		)
		(fill yes)
		(layer "In11.Cu")
		(net "M_D_CPU0_SB_DQS_DN<9>")
	)
	(gr_poly
		(pts
			(xy 339.088476 -240.057686) (xy 339.041486 -239.905286) (xy 338.779866 -239.905286) (xy 338.732876 -240.057686)
			(xy 338.732876 -240.101882) (xy 339.088476 -240.101882)
		)
		(stroke
			(width 0)
			(type solid)
		)
		(fill yes)
		(layer "In11.Cu")
		(net "M_D_CPU0_SB_DQS_DN<0>")
	)
	(gr_poly
		(pts
			(xy 339.088476 -230.290878) (xy 339.041486 -230.138478) (xy 338.779866 -230.138478) (xy 338.732876 -230.290878)
			(xy 338.732876 -230.335328) (xy 339.088476 -230.335328)
		)
		(stroke
			(width 0)
			(type solid)
		)
		(fill yes)
		(layer "In11.Cu")
		(net "M_D_CPU0_SB_DQ<15>")
	)
	(gr_poly
		(pts
			(xy 339.088476 -226.627182) (xy 339.088476 -226.582732) (xy 338.732876 -226.582732) (xy 338.732876 -226.627182)
			(xy 338.779866 -226.779582) (xy 339.041486 -226.779582)
		)
		(stroke
			(width 0)
			(type solid)
		)
		(fill yes)
		(layer "In11.Cu")
		(net "M_D_CPU0_SB_DQ<28>")
	)
	(gr_poly
		(pts
			(xy 339.18398 -279.354534) (xy 339.13699 -279.202134) (xy 338.87537 -279.202134) (xy 338.82838 -279.354534)
			(xy 338.82838 -279.39873) (xy 339.18398 -279.39873)
		)
		(stroke
			(width 0)
			(type solid)
		)
		(fill yes)
		(layer "In11.Cu")
		(net "M_D_CPU0_SA_DQ<10>")
	)
	(gr_poly
		(pts
			(xy 339.18398 -275.690584) (xy 339.18398 -275.646388) (xy 338.82838 -275.646388) (xy 338.82838 -275.690584)
			(xy 338.87537 -275.842984) (xy 339.13699 -275.842984)
		)
		(stroke
			(width 0)
			(type solid)
		)
		(fill yes)
		(layer "In11.Cu")
		(net "M_D_CPU0_SA_DQ<13>")
	)
	(gr_poly
		(pts
			(xy 339.18398 -270.807434) (xy 339.18398 -270.762984) (xy 338.82838 -270.762984) (xy 338.82838 -270.807434)
			(xy 338.87537 -270.959834) (xy 339.13699 -270.959834)
		)
		(stroke
			(width 0)
			(type solid)
		)
		(fill yes)
		(layer "In11.Cu")
		(net "M_D_CPU0_SA_DQ<21>")
	)
	(gr_poly
		(pts
			(xy 339.18398 -265.92403) (xy 339.18398 -265.87958) (xy 338.82838 -265.87958) (xy 338.82838 -265.92403)
			(xy 338.87537 -266.07643) (xy 339.13699 -266.07643)
		)
		(stroke
			(width 0)
			(type solid)
		)
		(fill yes)
		(layer "In11.Cu")
		(net "M_D_CPU0_SA_DQ<29>")
	)
	(gr_poly
		(pts
			(xy 339.18398 -261.040626) (xy 339.18398 -260.99643) (xy 338.82838 -260.99643) (xy 338.82838 -261.040626)
			(xy 338.87537 -261.193026) (xy 339.13699 -261.193026)
		)
		(stroke
			(width 0)
			(type solid)
		)
		(fill yes)
		(layer "In11.Cu")
		(net "M_D_CPU0_SA_CB<5>")
	)
	(gr_poly
		(pts
			(xy 339.18398 -256.157222) (xy 339.18398 -256.113026) (xy 338.82838 -256.113026) (xy 338.82838 -256.157222)
			(xy 338.87537 -256.309622) (xy 339.13699 -256.309622)
		)
		(stroke
			(width 0)
			(type solid)
		)
		(fill yes)
		(layer "In11.Cu")
		(net "M_D_CPU0_SA_CA<4>")
	)
	(gr_poly
		(pts
			(xy 339.18652 -274.47113) (xy 339.13953 -274.31873) (xy 338.87791 -274.31873) (xy 338.83092 -274.47113)
			(xy 338.83092 -274.515326) (xy 339.18652 -274.515326)
		)
		(stroke
			(width 0)
			(type solid)
		)
		(fill yes)
		(layer "In11.Cu")
		(net "M_D_CPU0_SA_DQ<18>")
	)
	(gr_poly
		(pts
			(xy 339.18652 -274.062698) (xy 339.18652 -274.018502) (xy 338.83092 -274.018502) (xy 338.83092 -274.062698)
			(xy 338.87791 -274.215098) (xy 339.13953 -274.215098)
		)
		(stroke
			(width 0)
			(type solid)
		)
		(fill yes)
		(layer "In11.Cu")
		(net "M_D_CPU0_SA_DQ<17>")
	)
	(gr_poly
		(pts
			(xy 339.18652 -272.843498) (xy 339.13953 -272.691098) (xy 338.87791 -272.691098) (xy 338.83092 -272.843498)
			(xy 338.83092 -272.887948) (xy 339.18652 -272.887948)
		)
		(stroke
			(width 0)
			(type solid)
		)
		(fill yes)
		(layer "In11.Cu")
		(net "M_D_CPU0_SA_DQS_DN<2>")
	)
	(gr_poly
		(pts
			(xy 339.18652 -269.587726) (xy 339.13953 -269.435326) (xy 338.87791 -269.435326) (xy 338.83092 -269.587726)
			(xy 338.83092 -269.631922) (xy 339.18652 -269.631922)
		)
		(stroke
			(width 0)
			(type solid)
		)
		(fill yes)
		(layer "In11.Cu")
		(net "M_D_CPU0_SA_DQ<26>")
	)
	(gr_poly
		(pts
			(xy 339.18652 -269.179294) (xy 339.18652 -269.135098) (xy 338.83092 -269.135098) (xy 338.83092 -269.179294)
			(xy 338.87791 -269.331694) (xy 339.13953 -269.331694)
		)
		(stroke
			(width 0)
			(type solid)
		)
		(fill yes)
		(layer "In11.Cu")
		(net "M_D_CPU0_SA_DQ<25>")
	)
	(gr_poly
		(pts
			(xy 339.18652 -267.960094) (xy 339.13953 -267.807694) (xy 338.87791 -267.807694) (xy 338.83092 -267.960094)
			(xy 338.83092 -268.004544) (xy 339.18652 -268.004544)
		)
		(stroke
			(width 0)
			(type solid)
		)
		(fill yes)
		(layer "In11.Cu")
		(net "M_D_CPU0_SA_DQS_DN<3>")
	)
	(gr_poly
		(pts
			(xy 339.18652 -264.704322) (xy 339.13953 -264.551922) (xy 338.87791 -264.551922) (xy 338.83092 -264.704322)
			(xy 338.83092 -264.748772) (xy 339.18652 -264.748772)
		)
		(stroke
			(width 0)
			(type solid)
		)
		(fill yes)
		(layer "In11.Cu")
		(net "M_D_CPU0_SA_CB<2>")
	)
	(gr_poly
		(pts
			(xy 339.18652 -264.296398) (xy 339.18652 -264.251948) (xy 338.83092 -264.251948) (xy 338.83092 -264.296398)
			(xy 338.87791 -264.448798) (xy 339.13953 -264.448798)
		)
		(stroke
			(width 0)
			(type solid)
		)
		(fill yes)
		(layer "In11.Cu")
		(net "M_D_CPU0_SA_CB<1>")
	)
	(gr_poly
		(pts
			(xy 339.18652 -263.07669) (xy 339.13953 -262.92429) (xy 338.87791 -262.92429) (xy 338.83092 -263.07669)
			(xy 338.83092 -263.12114) (xy 339.18652 -263.12114)
		)
		(stroke
			(width 0)
			(type solid)
		)
		(fill yes)
		(layer "In11.Cu")
		(net "M_D_CPU0_SA_DQS_DN<4>")
	)
	(gr_poly
		(pts
			(xy 339.18652 -259.412994) (xy 339.18652 -259.368544) (xy 338.83092 -259.368544) (xy 338.83092 -259.412994)
			(xy 338.87791 -259.565394) (xy 339.13953 -259.565394)
		)
		(stroke
			(width 0)
			(type solid)
		)
		(fill yes)
		(layer "In11.Cu")
		(net "M_D_CPU0_SA_CS_N<2>")
	)
	(gr_poly
		(pts
			(xy 339.18652 -258.193286) (xy 339.13953 -258.040886) (xy 338.87791 -258.040886) (xy 338.83092 -258.193286)
			(xy 338.83092 -258.237736) (xy 339.18652 -258.237736)
		)
		(stroke
			(width 0)
			(type solid)
		)
		(fill yes)
		(layer "In11.Cu")
		(net "M_D_CPU0_SA_CS_N<1>")
	)
	(gr_poly
		(pts
			(xy 339.192362 -278.945848) (xy 339.192362 -278.901652) (xy 338.836762 -278.901652) (xy 338.836762 -278.945848)
			(xy 338.883752 -279.098248) (xy 339.145372 -279.098248)
		)
		(stroke
			(width 0)
			(type solid)
		)
		(fill yes)
		(layer "In11.Cu")
		(net "M_D_CPU0_SA_DQ<9>")
	)
	(gr_poly
		(pts
			(xy 339.192362 -276.09927) (xy 339.145372 -275.94687) (xy 338.883752 -275.94687) (xy 338.836762 -276.09927)
			(xy 338.836762 -276.143466) (xy 339.192362 -276.143466)
		)
		(stroke
			(width 0)
			(type solid)
		)
		(fill yes)
		(layer "In11.Cu")
		(net "M_D_CPU0_SA_DQ<14>")
	)
	(gr_poly
		(pts
			(xy 339.192362 -271.215866) (xy 339.145372 -271.063466) (xy 338.883752 -271.063466) (xy 338.836762 -271.215866)
			(xy 338.836762 -271.260062) (xy 339.192362 -271.260062)
		)
		(stroke
			(width 0)
			(type solid)
		)
		(fill yes)
		(layer "In11.Cu")
		(net "M_D_CPU0_SA_DQ<22>")
	)
	(gr_poly
		(pts
			(xy 339.192362 -266.332462) (xy 339.145372 -266.180062) (xy 338.883752 -266.180062) (xy 338.836762 -266.332462)
			(xy 338.836762 -266.376658) (xy 339.192362 -266.376658)
		)
		(stroke
			(width 0)
			(type solid)
		)
		(fill yes)
		(layer "In11.Cu")
		(net "M_D_CPU0_SA_DQ<30>")
	)
	(gr_poly
		(pts
			(xy 339.192362 -261.449058) (xy 339.145372 -261.296658) (xy 338.883752 -261.296658) (xy 338.836762 -261.449058)
			(xy 338.836762 -261.493508) (xy 339.192362 -261.493508)
		)
		(stroke
			(width 0)
			(type solid)
		)
		(fill yes)
		(layer "In11.Cu")
		(net "M_D_CPU0_SA_CB<6>")
	)
	(gr_poly
		(pts
			(xy 339.192362 -256.565654) (xy 339.145372 -256.413254) (xy 338.883752 -256.413254) (xy 338.836762 -256.565654)
			(xy 338.836762 -256.610104) (xy 339.192362 -256.610104)
		)
		(stroke
			(width 0)
			(type solid)
		)
		(fill yes)
		(layer "In11.Cu")
		(net "M_D_CPU0_SA_CA<3>")
	)
	(gr_poly
		(pts
			(xy 339.195918 -262.668258) (xy 339.195918 -262.623808) (xy 338.840318 -262.623808) (xy 338.840318 -262.668258)
			(xy 338.887308 -262.820658) (xy 339.148928 -262.820658)
		)
		(stroke
			(width 0)
			(type solid)
		)
		(fill yes)
		(layer "In11.Cu")
		(net "M_D_CPU0_SA_DQS_DN<9>")
	)
	(gr_poly
		(pts
			(xy 339.198458 -277.726902) (xy 339.151468 -277.574502) (xy 338.889848 -277.574502) (xy 338.842858 -277.726902)
			(xy 338.842858 -277.771098) (xy 339.198458 -277.771098)
		)
		(stroke
			(width 0)
			(type solid)
		)
		(fill yes)
		(layer "In11.Cu")
		(net "M_D_CPU0_SA_DQS_DN<1>")
	)
	(gr_poly
		(pts
			(xy 339.198458 -277.317962) (xy 339.198458 -277.273766) (xy 338.842858 -277.273766) (xy 338.842858 -277.317962)
			(xy 338.889848 -277.470362) (xy 339.151468 -277.470362)
		)
		(stroke
			(width 0)
			(type solid)
		)
		(fill yes)
		(layer "In11.Cu")
		(net "M_D_CPU0_SA_DQS_DN<6>")
	)
	(gr_poly
		(pts
			(xy 339.198458 -272.435066) (xy 339.198458 -272.390616) (xy 338.842858 -272.390616) (xy 338.842858 -272.435066)
			(xy 338.889848 -272.587466) (xy 339.151468 -272.587466)
		)
		(stroke
			(width 0)
			(type solid)
		)
		(fill yes)
		(layer "In11.Cu")
		(net "M_D_CPU0_SA_DQS_DN<7>")
	)
	(gr_poly
		(pts
			(xy 339.198458 -267.551662) (xy 339.198458 -267.507212) (xy 338.842858 -267.507212) (xy 338.842858 -267.551662)
			(xy 338.889848 -267.704062) (xy 339.151468 -267.704062)
		)
		(stroke
			(width 0)
			(type solid)
		)
		(fill yes)
		(layer "In11.Cu")
		(net "M_D_CPU0_SA_DQS_DN<8>")
	)
	(gr_poly
		(pts
			(xy 339.198458 -257.784854) (xy 339.198458 -257.740404) (xy 338.842858 -257.740404) (xy 338.842858 -257.784854)
			(xy 338.889848 -257.937254) (xy 339.151468 -257.937254)
		)
		(stroke
			(width 0)
			(type solid)
		)
		(fill yes)
		(layer "In11.Cu")
		(net "M_D_CPU0_SA_CA<0>")
	)
	(gr_poly
		(pts
			(xy 339.546438 -247.382538) (xy 339.499448 -247.230138) (xy 339.237828 -247.230138) (xy 339.190838 -247.382538)
			(xy 339.190838 -247.426988) (xy 339.546438 -247.426988)
		)
		(stroke
			(width 0)
			(type solid)
		)
		(fill yes)
		(layer "In11.Cu")
		(net "M_D_CPU0_SB_CA<6>")
	)
	(gr_poly
		(pts
			(xy 339.546438 -237.61573) (xy 339.499448 -237.46333) (xy 339.237828 -237.46333) (xy 339.190838 -237.61573)
			(xy 339.190838 -237.66018) (xy 339.546438 -237.66018)
		)
		(stroke
			(width 0)
			(type solid)
		)
		(fill yes)
		(layer "In11.Cu")
		(net "M_D_CPU0_SB_DQ<7>")
	)
	(gr_poly
		(pts
			(xy 339.546438 -227.84943) (xy 339.499448 -227.69703) (xy 339.237828 -227.69703) (xy 339.190838 -227.84943)
			(xy 339.190838 -227.893626) (xy 339.546438 -227.893626)
		)
		(stroke
			(width 0)
			(type solid)
		)
		(fill yes)
		(layer "In11.Cu")
		(net "M_D_CPU0_SB_DQS_DN<3>")
	)
	(gr_poly
		(pts
			(xy 339.546438 -227.44049) (xy 339.546438 -227.396294) (xy 339.190838 -227.396294) (xy 339.190838 -227.44049)
			(xy 339.237828 -227.59289) (xy 339.499448 -227.59289)
		)
		(stroke
			(width 0)
			(type solid)
		)
		(fill yes)
		(layer "In11.Cu")
		(net "M_D_CPU0_SB_DQS_DN<8>")
	)
	(gr_poly
		(pts
			(xy 339.546438 -226.22129) (xy 339.499448 -226.06889) (xy 339.237828 -226.06889) (xy 339.190838 -226.22129)
			(xy 339.190838 -226.26574) (xy 339.546438 -226.26574)
		)
		(stroke
			(width 0)
			(type solid)
		)
		(fill yes)
		(layer "In11.Cu")
		(net "M_D_CPU0_SB_DQ<30>")
	)
	(gr_poly
		(pts
			(xy 339.552534 -248.601738) (xy 339.552534 -248.557542) (xy 339.196934 -248.557542) (xy 339.196934 -248.601738)
			(xy 339.243924 -248.754138) (xy 339.505544 -248.754138)
		)
		(stroke
			(width 0)
			(type solid)
		)
		(fill yes)
		(layer "In11.Cu")
		(net "M_D_CPU0_SB_CA<4>")
	)
	(gr_poly
		(pts
			(xy 339.552534 -243.718334) (xy 339.552534 -243.674138) (xy 339.196934 -243.674138) (xy 339.196934 -243.718334)
			(xy 339.243924 -243.870734) (xy 339.505544 -243.870734)
		)
		(stroke
			(width 0)
			(type solid)
		)
		(fill yes)
		(layer "In11.Cu")
		(net "M_D_CPU0_SB_CB<0>")
	)
	(gr_poly
		(pts
			(xy 339.552534 -242.499134) (xy 339.505544 -242.346734) (xy 339.243924 -242.346734) (xy 339.196934 -242.499134)
			(xy 339.196934 -242.543584) (xy 339.552534 -242.543584)
		)
		(stroke
			(width 0)
			(type solid)
		)
		(fill yes)
		(layer "In11.Cu")
		(net "M_D_CPU0_SB_CB<3>")
	)
	(gr_poly
		(pts
			(xy 339.552534 -238.83493) (xy 339.552534 -238.790734) (xy 339.196934 -238.790734) (xy 339.196934 -238.83493)
			(xy 339.243924 -238.98733) (xy 339.505544 -238.98733)
		)
		(stroke
			(width 0)
			(type solid)
		)
		(fill yes)
		(layer "In11.Cu")
		(net "M_D_CPU0_SB_DQ<4>")
	)
	(gr_poly
		(pts
			(xy 339.552534 -233.952034) (xy 339.552534 -233.907584) (xy 339.196934 -233.907584) (xy 339.196934 -233.952034)
			(xy 339.243924 -234.104434) (xy 339.505544 -234.104434)
		)
		(stroke
			(width 0)
			(type solid)
		)
		(fill yes)
		(layer "In11.Cu")
		(net "M_D_CPU0_SB_DQS_DP<1>")
	)
	(gr_poly
		(pts
			(xy 339.552534 -229.06863) (xy 339.552534 -229.02418) (xy 339.196934 -229.02418) (xy 339.196934 -229.06863)
			(xy 339.243924 -229.22103) (xy 339.505544 -229.22103)
		)
		(stroke
			(width 0)
			(type solid)
		)
		(fill yes)
		(layer "In11.Cu")
		(net "M_D_CPU0_SB_DQ<25>")
	)
	(gr_poly
		(pts
			(xy 339.558376 -246.974106) (xy 339.558376 -246.929656) (xy 339.202776 -246.929656) (xy 339.202776 -246.974106)
			(xy 339.249766 -247.126506) (xy 339.511386 -247.126506)
		)
		(stroke
			(width 0)
			(type solid)
		)
		(fill yes)
		(layer "In11.Cu")
		(net "M_D_CPU0_SB_CB<4>")
	)
	(gr_poly
		(pts
			(xy 339.558376 -245.754906) (xy 339.511386 -245.602506) (xy 339.249766 -245.602506) (xy 339.202776 -245.754906)
			(xy 339.202776 -245.799102) (xy 339.558376 -245.799102)
		)
		(stroke
			(width 0)
			(type solid)
		)
		(fill yes)
		(layer "In11.Cu")
		(net "M_D_CPU0_SB_CB<7>")
	)
	(gr_poly
		(pts
			(xy 339.558376 -245.346474) (xy 339.558376 -245.302278) (xy 339.202776 -245.302278) (xy 339.202776 -245.346474)
			(xy 339.249766 -245.498874) (xy 339.511386 -245.498874)
		)
		(stroke
			(width 0)
			(type solid)
		)
		(fill yes)
		(layer "In11.Cu")
		(net "M_D_CPU0_SB_DQS_DP<9>")
	)
	(gr_poly
		(pts
			(xy 339.558376 -240.871502) (xy 339.511386 -240.719102) (xy 339.249766 -240.719102) (xy 339.202776 -240.871502)
			(xy 339.202776 -240.915698) (xy 339.558376 -240.915698)
		)
		(stroke
			(width 0)
			(type solid)
		)
		(fill yes)
		(layer "In11.Cu")
		(net "M_D_CPU0_SB_DQ<3>")
	)
	(gr_poly
		(pts
			(xy 339.558376 -240.46307) (xy 339.558376 -240.418874) (xy 339.202776 -240.418874) (xy 339.202776 -240.46307)
			(xy 339.249766 -240.61547) (xy 339.511386 -240.61547)
		)
		(stroke
			(width 0)
			(type solid)
		)
		(fill yes)
		(layer "In11.Cu")
		(net "M_D_CPU0_SB_DQS_DP<0>")
	)
	(gr_poly
		(pts
			(xy 339.558376 -237.207298) (xy 339.558376 -237.163102) (xy 339.202776 -237.163102) (xy 339.202776 -237.207298)
			(xy 339.249766 -237.359698) (xy 339.511386 -237.359698)
		)
		(stroke
			(width 0)
			(type solid)
		)
		(fill yes)
		(layer "In11.Cu")
		(net "M_D_CPU0_SB_DQ<8>")
	)
	(gr_poly
		(pts
			(xy 339.558376 -235.988098) (xy 339.511386 -235.835698) (xy 339.249766 -235.835698) (xy 339.202776 -235.988098)
			(xy 339.202776 -236.032294) (xy 339.558376 -236.032294)
		)
		(stroke
			(width 0)
			(type solid)
		)
		(fill yes)
		(layer "In11.Cu")
		(net "M_D_CPU0_SB_DQ<11>")
	)
	(gr_poly
		(pts
			(xy 339.558376 -232.323894) (xy 339.558376 -232.279698) (xy 339.202776 -232.279698) (xy 339.202776 -232.323894)
			(xy 339.249766 -232.476294) (xy 339.511386 -232.476294)
		)
		(stroke
			(width 0)
			(type solid)
		)
		(fill yes)
		(layer "In11.Cu")
		(net "M_D_CPU0_SB_DQS_DN<6>")
	)
	(gr_poly
		(pts
			(xy 339.558376 -231.104694) (xy 339.511386 -230.952294) (xy 339.249766 -230.952294) (xy 339.202776 -231.104694)
			(xy 339.202776 -231.14889) (xy 339.558376 -231.14889)
		)
		(stroke
			(width 0)
			(type solid)
		)
		(fill yes)
		(layer "In11.Cu")
		(net "M_D_CPU0_SB_DQ<14>")
	)
	(gr_poly
		(pts
			(xy 339.558376 -230.696262) (xy 339.558376 -230.652066) (xy 339.202776 -230.652066) (xy 339.202776 -230.696262)
			(xy 339.249766 -230.848662) (xy 339.511386 -230.848662)
		)
		(stroke
			(width 0)
			(type solid)
		)
		(fill yes)
		(layer "In11.Cu")
		(net "M_D_CPU0_SB_DQ<13>")
	)
	(gr_poly
		(pts
			(xy 339.558376 -225.813366) (xy 339.558376 -225.768916) (xy 339.202776 -225.768916) (xy 339.202776 -225.813366)
			(xy 339.249766 -225.965766) (xy 339.511386 -225.965766)
		)
		(stroke
			(width 0)
			(type solid)
		)
		(fill yes)
		(layer "In11.Cu")
		(net "M_D_CPU0_SB_DQ<29>")
	)
	(gr_poly
		(pts
			(xy 339.560916 -249.01017) (xy 339.513926 -248.85777) (xy 339.252306 -248.85777) (xy 339.205316 -249.01017)
			(xy 339.205316 -249.05462) (xy 339.560916 -249.05462)
		)
		(stroke
			(width 0)
			(type solid)
		)
		(fill yes)
		(layer "In11.Cu")
		(net "M_D_CPU0_SB_CA<3>")
	)
	(gr_poly
		(pts
			(xy 339.560916 -244.126766) (xy 339.513926 -243.974366) (xy 339.252306 -243.974366) (xy 339.205316 -244.126766)
			(xy 339.205316 -244.171216) (xy 339.560916 -244.171216)
		)
		(stroke
			(width 0)
			(type solid)
		)
		(fill yes)
		(layer "In11.Cu")
		(net "M_D_CPU0_SB_DQS_DP<4>")
	)
	(gr_poly
		(pts
			(xy 339.560916 -242.090702) (xy 339.560916 -242.046506) (xy 339.205316 -242.046506) (xy 339.205316 -242.090702)
			(xy 339.252306 -242.243102) (xy 339.513926 -242.243102)
		)
		(stroke
			(width 0)
			(type solid)
		)
		(fill yes)
		(layer "In11.Cu")
		(net "M_D_CPU0_SB_DQ<0>")
	)
	(gr_poly
		(pts
			(xy 339.560916 -239.243362) (xy 339.513926 -239.090962) (xy 339.252306 -239.090962) (xy 339.205316 -239.243362)
			(xy 339.205316 -239.287812) (xy 339.560916 -239.287812)
		)
		(stroke
			(width 0)
			(type solid)
		)
		(fill yes)
		(layer "In11.Cu")
		(net "M_D_CPU0_SB_DQS_DP<5>")
	)
	(gr_poly
		(pts
			(xy 339.560916 -229.477062) (xy 339.513926 -229.324662) (xy 339.252306 -229.324662) (xy 339.205316 -229.477062)
			(xy 339.205316 -229.521258) (xy 339.560916 -229.521258)
		)
		(stroke
			(width 0)
			(type solid)
		)
		(fill yes)
		(layer "In11.Cu")
		(net "M_D_CPU0_SB_DQ<26>")
	)
	(gr_poly
		(pts
			(xy 339.65642 -274.876514) (xy 339.65642 -274.832064) (xy 339.30082 -274.832064) (xy 339.30082 -274.876514)
			(xy 339.34781 -275.028914) (xy 339.60943 -275.028914)
		)
		(stroke
			(width 0)
			(type solid)
		)
		(fill yes)
		(layer "In11.Cu")
		(net "M_D_CPU0_SA_DQ<16>")
	)
	(gr_poly
		(pts
			(xy 339.65642 -269.99311) (xy 339.65642 -269.948914) (xy 339.30082 -269.948914) (xy 339.30082 -269.99311)
			(xy 339.34781 -270.14551) (xy 339.60943 -270.14551)
		)
		(stroke
			(width 0)
			(type solid)
		)
		(fill yes)
		(layer "In11.Cu")
		(net "M_D_CPU0_SA_DQ<24>")
	)
	(gr_poly
		(pts
			(xy 339.65642 -265.109706) (xy 339.65642 -265.06551) (xy 339.30082 -265.06551) (xy 339.30082 -265.109706)
			(xy 339.34781 -265.262106) (xy 339.60943 -265.262106)
		)
		(stroke
			(width 0)
			(type solid)
		)
		(fill yes)
		(layer "In11.Cu")
		(net "M_D_CPU0_SA_CB<0>")
	)
	(gr_poly
		(pts
			(xy 339.65896 -262.262874) (xy 339.61197 -262.110474) (xy 339.35035 -262.110474) (xy 339.30336 -262.262874)
			(xy 339.30336 -262.307324) (xy 339.65896 -262.307324)
		)
		(stroke
			(width 0)
			(type solid)
		)
		(fill yes)
		(layer "In11.Cu")
		(net "M_D_CPU0_SA_DQS_DP<9>")
	)
	(gr_poly
		(pts
			(xy 339.662516 -273.657314) (xy 339.615526 -273.504914) (xy 339.353906 -273.504914) (xy 339.306916 -273.657314)
			(xy 339.306916 -273.701764) (xy 339.662516 -273.701764)
		)
		(stroke
			(width 0)
			(type solid)
		)
		(fill yes)
		(layer "In11.Cu")
		(net "M_D_CPU0_SA_DQ<19>")
	)
	(gr_poly
		(pts
			(xy 339.662516 -268.77391) (xy 339.615526 -268.62151) (xy 339.353906 -268.62151) (xy 339.306916 -268.77391)
			(xy 339.306916 -268.81836) (xy 339.662516 -268.81836)
		)
		(stroke
			(width 0)
			(type solid)
		)
		(fill yes)
		(layer "In11.Cu")
		(net "M_D_CPU0_SA_DQ<27>")
	)
	(gr_poly
		(pts
			(xy 339.662516 -263.891014) (xy 339.615526 -263.738614) (xy 339.353906 -263.738614) (xy 339.306916 -263.891014)
			(xy 339.306916 -263.93521) (xy 339.662516 -263.93521)
		)
		(stroke
			(width 0)
			(type solid)
		)
		(fill yes)
		(layer "In11.Cu")
		(net "M_D_CPU0_SA_CB<3>")
	)
	(gr_poly
		(pts
			(xy 339.662516 -259.00761) (xy 339.615526 -258.85521) (xy 339.353906 -258.85521) (xy 339.306916 -259.00761)
			(xy 339.306916 -259.051806) (xy 339.662516 -259.051806)
		)
		(stroke
			(width 0)
			(type solid)
		)
		(fill yes)
		(layer "In11.Cu")
		(net "M_D_CPU0_SA_CS_N<0>")
	)
	(gr_poly
		(pts
			(xy 339.668358 -278.540718) (xy 339.621368 -278.388318) (xy 339.359748 -278.388318) (xy 339.312758 -278.540718)
			(xy 339.312758 -278.584914) (xy 339.668358 -278.584914)
		)
		(stroke
			(width 0)
			(type solid)
		)
		(fill yes)
		(layer "In11.Cu")
		(net "M_D_CPU0_SA_DQ<11>")
	)
	(gr_poly
		(pts
			(xy 339.668358 -278.132286) (xy 339.668358 -278.08809) (xy 339.312758 -278.08809) (xy 339.312758 -278.132286)
			(xy 339.359748 -278.284686) (xy 339.621368 -278.284686)
		)
		(stroke
			(width 0)
			(type solid)
		)
		(fill yes)
		(layer "In11.Cu")
		(net "M_D_CPU0_SA_DQS_DP<1>")
	)
	(gr_poly
		(pts
			(xy 339.668358 -276.912578) (xy 339.621368 -276.760178) (xy 339.359748 -276.760178) (xy 339.312758 -276.912578)
			(xy 339.312758 -276.957028) (xy 339.668358 -276.957028)
		)
		(stroke
			(width 0)
			(type solid)
		)
		(fill yes)
		(layer "In11.Cu")
		(net "M_D_CPU0_SA_DQS_DP<6>")
	)
	(gr_poly
		(pts
			(xy 339.668358 -276.5044) (xy 339.668358 -276.460204) (xy 339.312758 -276.460204) (xy 339.312758 -276.5044)
			(xy 339.359748 -276.6568) (xy 339.621368 -276.6568)
		)
		(stroke
			(width 0)
			(type solid)
		)
		(fill yes)
		(layer "In11.Cu")
		(net "M_D_CPU0_SA_DQ<12>")
	)
	(gr_poly
		(pts
			(xy 339.668358 -275.284946) (xy 339.621368 -275.132546) (xy 339.359748 -275.132546) (xy 339.312758 -275.284946)
			(xy 339.312758 -275.329396) (xy 339.668358 -275.329396)
		)
		(stroke
			(width 0)
			(type solid)
		)
		(fill yes)
		(layer "In11.Cu")
		(net "M_D_CPU0_SA_DQ<15>")
	)
	(gr_poly
		(pts
			(xy 339.668358 -272.029174) (xy 339.621368 -271.876774) (xy 339.359748 -271.876774) (xy 339.312758 -272.029174)
			(xy 339.312758 -272.073624) (xy 339.668358 -272.073624)
		)
		(stroke
			(width 0)
			(type solid)
		)
		(fill yes)
		(layer "In11.Cu")
		(net "M_D_CPU0_SA_DQS_DP<7>")
	)
	(gr_poly
		(pts
			(xy 339.668358 -271.62125) (xy 339.668358 -271.5768) (xy 339.312758 -271.5768) (xy 339.312758 -271.62125)
			(xy 339.359748 -271.77365) (xy 339.621368 -271.77365)
		)
		(stroke
			(width 0)
			(type solid)
		)
		(fill yes)
		(layer "In11.Cu")
		(net "M_D_CPU0_SA_DQ<20>")
	)
	(gr_poly
		(pts
			(xy 339.668358 -270.40205) (xy 339.621368 -270.24965) (xy 339.359748 -270.24965) (xy 339.312758 -270.40205)
			(xy 339.312758 -270.446246) (xy 339.668358 -270.446246)
		)
		(stroke
			(width 0)
			(type solid)
		)
		(fill yes)
		(layer "In11.Cu")
		(net "M_D_CPU0_SA_DQ<23>")
	)
	(gr_poly
		(pts
			(xy 339.668358 -267.14577) (xy 339.621368 -266.99337) (xy 339.359748 -266.99337) (xy 339.312758 -267.14577)
			(xy 339.312758 -267.19022) (xy 339.668358 -267.19022)
		)
		(stroke
			(width 0)
			(type solid)
		)
		(fill yes)
		(layer "In11.Cu")
		(net "M_D_CPU0_SA_DQS_DP<8>")
	)
	(gr_poly
		(pts
			(xy 339.668358 -266.737846) (xy 339.668358 -266.69365) (xy 339.312758 -266.69365) (xy 339.312758 -266.737846)
			(xy 339.359748 -266.890246) (xy 339.621368 -266.890246)
		)
		(stroke
			(width 0)
			(type solid)
		)
		(fill yes)
		(layer "In11.Cu")
		(net "M_D_CPU0_SA_DQ<28>")
	)
	(gr_poly
		(pts
			(xy 339.668358 -265.518646) (xy 339.621368 -265.366246) (xy 339.359748 -265.366246) (xy 339.312758 -265.518646)
			(xy 339.312758 -265.562842) (xy 339.668358 -265.562842)
		)
		(stroke
			(width 0)
			(type solid)
		)
		(fill yes)
		(layer "In11.Cu")
		(net "M_D_CPU0_SA_DQ<31>")
	)
	(gr_poly
		(pts
			(xy 339.668358 -261.854442) (xy 339.668358 -261.810246) (xy 339.312758 -261.810246) (xy 339.312758 -261.854442)
			(xy 339.359748 -262.006842) (xy 339.621368 -262.006842)
		)
		(stroke
			(width 0)
			(type solid)
		)
		(fill yes)
		(layer "In11.Cu")
		(net "M_D_CPU0_SA_CB<4>")
	)
	(gr_poly
		(pts
			(xy 339.668358 -260.635242) (xy 339.621368 -260.482842) (xy 339.359748 -260.482842) (xy 339.312758 -260.635242)
			(xy 339.312758 -260.679438) (xy 339.668358 -260.679438)
		)
		(stroke
			(width 0)
			(type solid)
		)
		(fill yes)
		(layer "In11.Cu")
		(net "M_D_CPU0_SA_CB<7>")
	)
	(gr_poly
		(pts
			(xy 339.668358 -257.37947) (xy 339.621368 -257.22707) (xy 339.359748 -257.22707) (xy 339.312758 -257.37947)
			(xy 339.312758 -257.423666) (xy 339.668358 -257.423666)
		)
		(stroke
			(width 0)
			(type solid)
		)
		(fill yes)
		(layer "In11.Cu")
		(net "M_D_CPU0_SA_CA<1>")
	)
	(gr_poly
		(pts
			(xy 339.668358 -256.971038) (xy 339.668358 -256.926842) (xy 339.312758 -256.926842) (xy 339.312758 -256.971038)
			(xy 339.359748 -257.123438) (xy 339.621368 -257.123438)
		)
		(stroke
			(width 0)
			(type solid)
		)
		(fill yes)
		(layer "In11.Cu")
		(net "M_D_CPU0_SA_CA<2>")
	)
	(gr_poly
		(pts
			(xy 339.668358 -255.751838) (xy 339.621368 -255.599438) (xy 339.359748 -255.599438) (xy 339.312758 -255.751838)
			(xy 339.312758 -255.796288) (xy 339.668358 -255.796288)
		)
		(stroke
			(width 0)
			(type solid)
		)
		(fill yes)
		(layer "In11.Cu")
		(net "M_D_CPU0_SA_CA<5>")
	)
	(gr_poly
		(pts
			(xy 339.670898 -279.759918) (xy 339.670898 -279.715722) (xy 339.315298 -279.715722) (xy 339.315298 -279.759918)
			(xy 339.362288 -279.912318) (xy 339.623908 -279.912318)
		)
		(stroke
			(width 0)
			(type solid)
		)
		(fill yes)
		(layer "In11.Cu")
		(net "M_D_CPU0_SA_DQ<8>")
	)
	(gr_poly
		(pts
			(xy 339.670898 -273.248882) (xy 339.670898 -273.204686) (xy 339.315298 -273.204686) (xy 339.315298 -273.248882)
			(xy 339.362288 -273.401282) (xy 339.623908 -273.401282)
		)
		(stroke
			(width 0)
			(type solid)
		)
		(fill yes)
		(layer "In11.Cu")
		(net "M_D_CPU0_SA_DQS_DP<2>")
	)
	(gr_poly
		(pts
			(xy 339.670898 -268.365478) (xy 339.670898 -268.321282) (xy 339.315298 -268.321282) (xy 339.315298 -268.365478)
			(xy 339.362288 -268.517878) (xy 339.623908 -268.517878)
		)
		(stroke
			(width 0)
			(type solid)
		)
		(fill yes)
		(layer "In11.Cu")
		(net "M_D_CPU0_SA_DQS_DP<3>")
	)
	(gr_poly
		(pts
			(xy 339.670898 -263.482582) (xy 339.670898 -263.438132) (xy 339.315298 -263.438132) (xy 339.315298 -263.482582)
			(xy 339.362288 -263.634982) (xy 339.623908 -263.634982)
		)
		(stroke
			(width 0)
			(type solid)
		)
		(fill yes)
		(layer "In11.Cu")
		(net "M_D_CPU0_SA_DQS_DP<4>")
	)
	(gr_poly
		(pts
			(xy 339.670898 -258.599178) (xy 339.670898 -258.554728) (xy 339.315298 -258.554728) (xy 339.315298 -258.599178)
			(xy 339.362288 -258.751578) (xy 339.623908 -258.751578)
		)
		(stroke
			(width 0)
			(type solid)
		)
		(fill yes)
		(layer "In11.Cu")
		(net "M_D_CPU0_SA_CS_N<3>")
	)
	(gr_poly
		(pts
			(xy 340.013798 -249.416062) (xy 340.013798 -249.371612) (xy 339.658198 -249.371612) (xy 339.658198 -249.416062)
			(xy 339.705188 -249.568462) (xy 339.966808 -249.568462)
		)
		(stroke
			(width 0)
			(type solid)
		)
		(fill yes)
		(layer "In11.Cu")
		(net "M_D_CPU0_SB_CA<2>")
	)
	(gr_poly
		(pts
			(xy 340.013798 -246.16029) (xy 340.013798 -246.116094) (xy 339.658198 -246.116094) (xy 339.658198 -246.16029)
			(xy 339.705188 -246.31269) (xy 339.966808 -246.31269)
		)
		(stroke
			(width 0)
			(type solid)
		)
		(fill yes)
		(layer "In11.Cu")
		(net "M_D_CPU0_SB_CB<5>")
	)
	(gr_poly
		(pts
			(xy 340.013798 -241.685318) (xy 339.966808 -241.532918) (xy 339.705188 -241.532918) (xy 339.658198 -241.685318)
			(xy 339.658198 -241.729514) (xy 340.013798 -241.729514)
		)
		(stroke
			(width 0)
			(type solid)
		)
		(fill yes)
		(layer "In11.Cu")
		(net "M_D_CPU0_SB_DQ<2>")
	)
	(gr_poly
		(pts
			(xy 340.013798 -241.276886) (xy 340.013798 -241.23269) (xy 339.658198 -241.23269) (xy 339.658198 -241.276886)
			(xy 339.705188 -241.429286) (xy 339.966808 -241.429286)
		)
		(stroke
			(width 0)
			(type solid)
		)
		(fill yes)
		(layer "In11.Cu")
		(net "M_D_CPU0_SB_DQ<1>")
	)
	(gr_poly
		(pts
			(xy 340.013798 -240.057178) (xy 339.966808 -239.904778) (xy 339.705188 -239.904778) (xy 339.658198 -240.057178)
			(xy 339.658198 -240.101628) (xy 340.013798 -240.101628)
		)
		(stroke
			(width 0)
			(type solid)
		)
		(fill yes)
		(layer "In11.Cu")
		(net "M_D_CPU0_SB_DQS_DN<0>")
	)
	(gr_poly
		(pts
			(xy 340.013798 -239.649254) (xy 340.013798 -239.604804) (xy 339.658198 -239.604804) (xy 339.658198 -239.649254)
			(xy 339.705188 -239.801654) (xy 339.966808 -239.801654)
		)
		(stroke
			(width 0)
			(type solid)
		)
		(fill yes)
		(layer "In11.Cu")
		(net "M_D_CPU0_SB_DQS_DN<5>")
	)
	(gr_poly
		(pts
			(xy 340.013798 -236.39399) (xy 340.013798 -236.34954) (xy 339.658198 -236.34954) (xy 339.658198 -236.39399)
			(xy 339.705188 -236.54639) (xy 339.966808 -236.54639)
		)
		(stroke
			(width 0)
			(type solid)
		)
		(fill yes)
		(layer "In11.Cu")
		(net "M_D_CPU0_SB_DQ<9>")
	)
	(gr_poly
		(pts
			(xy 340.013798 -231.510586) (xy 340.013798 -231.466136) (xy 339.658198 -231.466136) (xy 339.658198 -231.510586)
			(xy 339.705188 -231.662986) (xy 339.966808 -231.662986)
		)
		(stroke
			(width 0)
			(type solid)
		)
		(fill yes)
		(layer "In11.Cu")
		(net "M_D_CPU0_SB_DQ<12>")
	)
	(gr_poly
		(pts
			(xy 340.013798 -230.290878) (xy 339.966808 -230.138478) (xy 339.705188 -230.138478) (xy 339.658198 -230.290878)
			(xy 339.658198 -230.335074) (xy 340.013798 -230.335074)
		)
		(stroke
			(width 0)
			(type solid)
		)
		(fill yes)
		(layer "In11.Cu")
		(net "M_D_CPU0_SB_DQ<15>")
	)
	(gr_poly
		(pts
			(xy 340.013798 -229.882446) (xy 340.013798 -229.83825) (xy 339.658198 -229.83825) (xy 339.658198 -229.882446)
			(xy 339.705188 -230.034846) (xy 339.966808 -230.034846)
		)
		(stroke
			(width 0)
			(type solid)
		)
		(fill yes)
		(layer "In11.Cu")
		(net "M_D_CPU0_SB_DQ<24>")
	)
	(gr_poly
		(pts
			(xy 340.013798 -225.407474) (xy 339.966808 -225.255074) (xy 339.705188 -225.255074) (xy 339.658198 -225.407474)
			(xy 339.658198 -225.45167) (xy 340.013798 -225.45167)
		)
		(stroke
			(width 0)
			(type solid)
		)
		(fill yes)
		(layer "In11.Cu")
		(net "M_D_CPU0_SB_DQ<31>")
	)
	(gr_poly
		(pts
			(xy 340.016338 -248.196354) (xy 339.969348 -248.043954) (xy 339.707728 -248.043954) (xy 339.660738 -248.196354)
			(xy 339.660738 -248.240804) (xy 340.016338 -248.240804)
		)
		(stroke
			(width 0)
			(type solid)
		)
		(fill yes)
		(layer "In11.Cu")
		(net "M_D_CPU0_SB_CA<5>")
	)
	(gr_poly
		(pts
			(xy 340.016338 -244.940582) (xy 339.969348 -244.788182) (xy 339.707728 -244.788182) (xy 339.660738 -244.940582)
			(xy 339.660738 -244.985032) (xy 340.016338 -244.985032)
		)
		(stroke
			(width 0)
			(type solid)
		)
		(fill yes)
		(layer "In11.Cu")
		(net "M_D_CPU0_SB_DQS_DN<9>")
	)
	(gr_poly
		(pts
			(xy 340.016338 -244.532658) (xy 340.016338 -244.488208) (xy 339.660738 -244.488208) (xy 339.660738 -244.532658)
			(xy 339.707728 -244.685058) (xy 339.969348 -244.685058)
		)
		(stroke
			(width 0)
			(type solid)
		)
		(fill yes)
		(layer "In11.Cu")
		(net "M_D_CPU0_SB_DQS_DN<4>")
	)
	(gr_poly
		(pts
			(xy 340.016338 -243.313458) (xy 339.969348 -243.161058) (xy 339.707728 -243.161058) (xy 339.660738 -243.313458)
			(xy 339.660738 -243.357654) (xy 340.016338 -243.357654)
		)
		(stroke
			(width 0)
			(type solid)
		)
		(fill yes)
		(layer "In11.Cu")
		(net "M_D_CPU0_SB_CB<2>")
	)
	(gr_poly
		(pts
			(xy 340.016338 -242.904518) (xy 340.016338 -242.860322) (xy 339.660738 -242.860322) (xy 339.660738 -242.904518)
			(xy 339.707728 -243.056918) (xy 339.969348 -243.056918)
		)
		(stroke
			(width 0)
			(type solid)
		)
		(fill yes)
		(layer "In11.Cu")
		(net "M_D_CPU0_SB_CB<1>")
	)
	(gr_poly
		(pts
			(xy 340.016338 -238.430054) (xy 339.969348 -238.277654) (xy 339.707728 -238.277654) (xy 339.660738 -238.430054)
			(xy 339.660738 -238.47425) (xy 340.016338 -238.47425)
		)
		(stroke
			(width 0)
			(type solid)
		)
		(fill yes)
		(layer "In11.Cu")
		(net "M_D_CPU0_SB_DQ<6>")
	)
	(gr_poly
		(pts
			(xy 340.016338 -233.54665) (xy 339.969348 -233.39425) (xy 339.707728 -233.39425) (xy 339.660738 -233.54665)
			(xy 339.660738 -233.590846) (xy 340.016338 -233.590846)
		)
		(stroke
			(width 0)
			(type solid)
		)
		(fill yes)
		(layer "In11.Cu")
		(net "M_D_CPU0_SB_DQS_DN<1>")
	)
	(gr_poly
		(pts
			(xy 340.016338 -228.663246) (xy 339.969348 -228.510846) (xy 339.707728 -228.510846) (xy 339.660738 -228.663246)
			(xy 339.660738 -228.707696) (xy 340.016338 -228.707696)
		)
		(stroke
			(width 0)
			(type solid)
		)
		(fill yes)
		(layer "In11.Cu")
		(net "M_D_CPU0_SB_DQ<27>")
	)
	(gr_poly
		(pts
			(xy 340.016338 -226.626674) (xy 340.016338 -226.582478) (xy 339.660738 -226.582478) (xy 339.660738 -226.626674)
			(xy 339.707728 -226.779074) (xy 339.969348 -226.779074)
		)
		(stroke
			(width 0)
			(type solid)
		)
		(fill yes)
		(layer "In11.Cu")
		(net "M_D_CPU0_SB_DQ<28>")
	)
	(gr_poly
		(pts
			(xy 340.02218 -246.568722) (xy 339.97519 -246.416322) (xy 339.71357 -246.416322) (xy 339.66658 -246.568722)
			(xy 339.66658 -246.613172) (xy 340.02218 -246.613172)
		)
		(stroke
			(width 0)
			(type solid)
		)
		(fill yes)
		(layer "In11.Cu")
		(net "M_D_CPU0_SB_CB<6>")
	)
	(gr_poly
		(pts
			(xy 340.02218 -236.801914) (xy 339.97519 -236.649514) (xy 339.71357 -236.649514) (xy 339.66658 -236.801914)
			(xy 339.66658 -236.846364) (xy 340.02218 -236.846364)
		)
		(stroke
			(width 0)
			(type solid)
		)
		(fill yes)
		(layer "In11.Cu")
		(net "M_D_CPU0_SB_DQ<10>")
	)
	(gr_poly
		(pts
			(xy 340.02218 -231.919018) (xy 339.97519 -231.766618) (xy 339.71357 -231.766618) (xy 339.66658 -231.919018)
			(xy 339.66658 -231.963214) (xy 340.02218 -231.963214)
		)
		(stroke
			(width 0)
			(type solid)
		)
		(fill yes)
		(layer "In11.Cu")
		(net "M_D_CPU0_SB_DQS_DP<6>")
	)
	(gr_poly
		(pts
			(xy 340.02218 -227.035614) (xy 339.97519 -226.883214) (xy 339.71357 -226.883214) (xy 339.66658 -227.035614)
			(xy 339.66658 -227.07981) (xy 340.02218 -227.07981)
		)
		(stroke
			(width 0)
			(type solid)
		)
		(fill yes)
		(layer "In11.Cu")
		(net "M_D_CPU0_SB_DQS_DP<8>")
	)
	(gr_poly
		(pts
			(xy 340.028276 -247.787922) (xy 340.028276 -247.743472) (xy 339.672676 -247.743472) (xy 339.672676 -247.787922)
			(xy 339.719666 -247.940322) (xy 339.981286 -247.940322)
		)
		(stroke
			(width 0)
			(type solid)
		)
		(fill yes)
		(layer "In11.Cu")
		(net "M_D_CPU0_SB_PAR")
	)
	(gr_poly
		(pts
			(xy 340.028276 -238.021114) (xy 340.028276 -237.976918) (xy 339.672676 -237.976918) (xy 339.672676 -238.021114)
			(xy 339.719666 -238.173514) (xy 339.981286 -238.173514)
		)
		(stroke
			(width 0)
			(type solid)
		)
		(fill yes)
		(layer "In11.Cu")
		(net "M_D_CPU0_SB_DQ<5>")
	)
	(gr_poly
		(pts
			(xy 340.028276 -228.254814) (xy 340.028276 -228.210364) (xy 339.672676 -228.210364) (xy 339.672676 -228.254814)
			(xy 339.719666 -228.407214) (xy 339.981286 -228.407214)
		)
		(stroke
			(width 0)
			(type solid)
		)
		(fill yes)
		(layer "In11.Cu")
		(net "M_D_CPU0_SB_DQS_DP<3>")
	)
	(gr_poly
		(pts
			(xy 340.12378 -279.354534) (xy 340.07679 -279.202134) (xy 339.81517 -279.202134) (xy 339.76818 -279.354534)
			(xy 339.76818 -279.39873) (xy 340.12378 -279.39873)
		)
		(stroke
			(width 0)
			(type solid)
		)
		(fill yes)
		(layer "In11.Cu")
		(net "M_D_CPU0_SA_DQ<10>")
	)
	(gr_poly
		(pts
			(xy 340.12378 -278.946102) (xy 340.12378 -278.901906) (xy 339.76818 -278.901906) (xy 339.76818 -278.946102)
			(xy 339.81517 -279.098502) (xy 340.07679 -279.098502)
		)
		(stroke
			(width 0)
			(type solid)
		)
		(fill yes)
		(layer "In11.Cu")
		(net "M_D_CPU0_SA_DQ<9>")
	)
	(gr_poly
		(pts
			(xy 340.12378 -277.726394) (xy 340.07679 -277.573994) (xy 339.81517 -277.573994) (xy 339.76818 -277.726394)
			(xy 339.76818 -277.770844) (xy 340.12378 -277.770844)
		)
		(stroke
			(width 0)
			(type solid)
		)
		(fill yes)
		(layer "In11.Cu")
		(net "M_D_CPU0_SA_DQS_DN<1>")
	)
	(gr_poly
		(pts
			(xy 340.12378 -277.318216) (xy 340.12378 -277.27402) (xy 339.76818 -277.27402) (xy 339.76818 -277.318216)
			(xy 339.81517 -277.470616) (xy 340.07679 -277.470616)
		)
		(stroke
			(width 0)
			(type solid)
		)
		(fill yes)
		(layer "In11.Cu")
		(net "M_D_CPU0_SA_DQS_DN<6>")
	)
	(gr_poly
		(pts
			(xy 340.12378 -276.098762) (xy 340.07679 -275.946362) (xy 339.81517 -275.946362) (xy 339.76818 -276.098762)
			(xy 339.76818 -276.143212) (xy 340.12378 -276.143212)
		)
		(stroke
			(width 0)
			(type solid)
		)
		(fill yes)
		(layer "In11.Cu")
		(net "M_D_CPU0_SA_DQ<14>")
	)
	(gr_poly
		(pts
			(xy 340.12378 -272.843498) (xy 340.07679 -272.691098) (xy 339.81517 -272.691098) (xy 339.76818 -272.843498)
			(xy 339.76818 -272.887694) (xy 340.12378 -272.887694)
		)
		(stroke
			(width 0)
			(type solid)
		)
		(fill yes)
		(layer "In11.Cu")
		(net "M_D_CPU0_SA_DQS_DN<2>")
	)
	(gr_poly
		(pts
			(xy 340.12378 -272.435066) (xy 340.12378 -272.39087) (xy 339.76818 -272.39087) (xy 339.76818 -272.435066)
			(xy 339.81517 -272.587466) (xy 340.07679 -272.587466)
		)
		(stroke
			(width 0)
			(type solid)
		)
		(fill yes)
		(layer "In11.Cu")
		(net "M_D_CPU0_SA_DQS_DN<7>")
	)
	(gr_poly
		(pts
			(xy 340.12378 -271.215358) (xy 340.07679 -271.062958) (xy 339.81517 -271.062958) (xy 339.76818 -271.215358)
			(xy 339.76818 -271.259808) (xy 340.12378 -271.259808)
		)
		(stroke
			(width 0)
			(type solid)
		)
		(fill yes)
		(layer "In11.Cu")
		(net "M_D_CPU0_SA_DQ<22>")
	)
	(gr_poly
		(pts
			(xy 340.12378 -267.960094) (xy 340.07679 -267.807694) (xy 339.81517 -267.807694) (xy 339.76818 -267.960094)
			(xy 339.76818 -268.00429) (xy 340.12378 -268.00429)
		)
		(stroke
			(width 0)
			(type solid)
		)
		(fill yes)
		(layer "In11.Cu")
		(net "M_D_CPU0_SA_DQS_DN<3>")
	)
	(gr_poly
		(pts
			(xy 340.12378 -267.551662) (xy 340.12378 -267.507466) (xy 339.76818 -267.507466) (xy 339.76818 -267.551662)
			(xy 339.81517 -267.704062) (xy 340.07679 -267.704062)
		)
		(stroke
			(width 0)
			(type solid)
		)
		(fill yes)
		(layer "In11.Cu")
		(net "M_D_CPU0_SA_DQS_DN<8>")
	)
	(gr_poly
		(pts
			(xy 340.12378 -266.331954) (xy 340.07679 -266.179554) (xy 339.81517 -266.179554) (xy 339.76818 -266.331954)
			(xy 339.76818 -266.376404) (xy 340.12378 -266.376404)
		)
		(stroke
			(width 0)
			(type solid)
		)
		(fill yes)
		(layer "In11.Cu")
		(net "M_D_CPU0_SA_DQ<30>")
	)
	(gr_poly
		(pts
			(xy 340.12378 -263.07669) (xy 340.07679 -262.92429) (xy 339.81517 -262.92429) (xy 339.76818 -263.07669)
			(xy 339.76818 -263.120886) (xy 340.12378 -263.120886)
		)
		(stroke
			(width 0)
			(type solid)
		)
		(fill yes)
		(layer "In11.Cu")
		(net "M_D_CPU0_SA_DQS_DN<4>")
	)
	(gr_poly
		(pts
			(xy 340.12378 -261.449058) (xy 340.07679 -261.296658) (xy 339.81517 -261.296658) (xy 339.76818 -261.449058)
			(xy 339.76818 -261.493254) (xy 340.12378 -261.493254)
		)
		(stroke
			(width 0)
			(type solid)
		)
		(fill yes)
		(layer "In11.Cu")
		(net "M_D_CPU0_SA_CB<6>")
	)
	(gr_poly
		(pts
			(xy 340.12378 -256.565654) (xy 340.07679 -256.413254) (xy 339.81517 -256.413254) (xy 339.76818 -256.565654)
			(xy 339.76818 -256.60985) (xy 340.12378 -256.60985)
		)
		(stroke
			(width 0)
			(type solid)
		)
		(fill yes)
		(layer "In11.Cu")
		(net "M_D_CPU0_SA_CA<3>")
	)
	(gr_poly
		(pts
			(xy 340.12632 -274.062698) (xy 340.12632 -274.018248) (xy 339.77072 -274.018248) (xy 339.77072 -274.062698)
			(xy 339.81771 -274.215098) (xy 340.07933 -274.215098)
		)
		(stroke
			(width 0)
			(type solid)
		)
		(fill yes)
		(layer "In11.Cu")
		(net "M_D_CPU0_SA_DQ<17>")
	)
	(gr_poly
		(pts
			(xy 340.12632 -269.179294) (xy 340.12632 -269.134844) (xy 339.77072 -269.134844) (xy 339.77072 -269.179294)
			(xy 339.81771 -269.331694) (xy 340.07933 -269.331694)
		)
		(stroke
			(width 0)
			(type solid)
		)
		(fill yes)
		(layer "In11.Cu")
		(net "M_D_CPU0_SA_DQ<25>")
	)
	(gr_poly
		(pts
			(xy 340.12632 -264.29589) (xy 340.12632 -264.251694) (xy 339.77072 -264.251694) (xy 339.77072 -264.29589)
			(xy 339.81771 -264.44829) (xy 340.07933 -264.44829)
		)
		(stroke
			(width 0)
			(type solid)
		)
		(fill yes)
		(layer "In11.Cu")
		(net "M_D_CPU0_SA_CB<1>")
	)
	(gr_poly
		(pts
			(xy 340.12632 -259.412486) (xy 340.12632 -259.36829) (xy 339.77072 -259.36829) (xy 339.77072 -259.412486)
			(xy 339.81771 -259.564886) (xy 340.07933 -259.564886)
		)
		(stroke
			(width 0)
			(type solid)
		)
		(fill yes)
		(layer "In11.Cu")
		(net "M_D_CPU0_SA_CS_N<2>")
	)
	(gr_poly
		(pts
			(xy 340.12632 -258.193286) (xy 340.07933 -258.040886) (xy 339.81771 -258.040886) (xy 339.77072 -258.193286)
			(xy 339.77072 -258.237482) (xy 340.12632 -258.237482)
		)
		(stroke
			(width 0)
			(type solid)
		)
		(fill yes)
		(layer "In11.Cu")
		(net "M_D_CPU0_SA_CS_N<1>")
	)
	(gr_poly
		(pts
			(xy 340.12632 -257.784854) (xy 340.12632 -257.740658) (xy 339.77072 -257.740658) (xy 339.77072 -257.784854)
			(xy 339.81771 -257.937254) (xy 340.07933 -257.937254)
		)
		(stroke
			(width 0)
			(type solid)
		)
		(fill yes)
		(layer "In11.Cu")
		(net "M_D_CPU0_SA_CA<0>")
	)
	(gr_poly
		(pts
			(xy 340.132162 -275.690584) (xy 340.132162 -275.646134) (xy 339.776562 -275.646134) (xy 339.776562 -275.690584)
			(xy 339.823552 -275.842984) (xy 340.085172 -275.842984)
		)
		(stroke
			(width 0)
			(type solid)
		)
		(fill yes)
		(layer "In11.Cu")
		(net "M_D_CPU0_SA_DQ<13>")
	)
	(gr_poly
		(pts
			(xy 340.132162 -270.806926) (xy 340.132162 -270.76273) (xy 339.776562 -270.76273) (xy 339.776562 -270.806926)
			(xy 339.823552 -270.959326) (xy 340.085172 -270.959326)
		)
		(stroke
			(width 0)
			(type solid)
		)
		(fill yes)
		(layer "In11.Cu")
		(net "M_D_CPU0_SA_DQ<21>")
	)
	(gr_poly
		(pts
			(xy 340.132162 -265.923522) (xy 340.132162 -265.879326) (xy 339.776562 -265.879326) (xy 339.776562 -265.923522)
			(xy 339.823552 -266.075922) (xy 340.085172 -266.075922)
		)
		(stroke
			(width 0)
			(type solid)
		)
		(fill yes)
		(layer "In11.Cu")
		(net "M_D_CPU0_SA_DQ<29>")
	)
	(gr_poly
		(pts
			(xy 340.132162 -261.040626) (xy 340.132162 -260.996176) (xy 339.776562 -260.996176) (xy 339.776562 -261.040626)
			(xy 339.823552 -261.193026) (xy 340.085172 -261.193026)
		)
		(stroke
			(width 0)
			(type solid)
		)
		(fill yes)
		(layer "In11.Cu")
		(net "M_D_CPU0_SA_CB<5>")
	)
	(gr_poly
		(pts
			(xy 340.132162 -256.157222) (xy 340.132162 -256.112772) (xy 339.776562 -256.112772) (xy 339.776562 -256.157222)
			(xy 339.823552 -256.309622) (xy 340.085172 -256.309622)
		)
		(stroke
			(width 0)
			(type solid)
		)
		(fill yes)
		(layer "In11.Cu")
		(net "M_D_CPU0_SA_CA<4>")
	)
	(gr_poly
		(pts
			(xy 340.135718 -262.668258) (xy 340.135718 -262.623808) (xy 339.780118 -262.623808) (xy 339.780118 -262.668258)
			(xy 339.827108 -262.820658) (xy 340.088728 -262.820658)
		)
		(stroke
			(width 0)
			(type solid)
		)
		(fill yes)
		(layer "In11.Cu")
		(net "M_D_CPU0_SA_DQS_DN<9>")
	)
	(gr_poly
		(pts
			(xy 340.138258 -274.47113) (xy 340.091268 -274.31873) (xy 339.829648 -274.31873) (xy 339.782658 -274.47113)
			(xy 339.782658 -274.51558) (xy 340.138258 -274.51558)
		)
		(stroke
			(width 0)
			(type solid)
		)
		(fill yes)
		(layer "In11.Cu")
		(net "M_D_CPU0_SA_DQ<18>")
	)
	(gr_poly
		(pts
			(xy 340.138258 -269.587726) (xy 340.091268 -269.435326) (xy 339.829648 -269.435326) (xy 339.782658 -269.587726)
			(xy 339.782658 -269.632176) (xy 340.138258 -269.632176)
		)
		(stroke
			(width 0)
			(type solid)
		)
		(fill yes)
		(layer "In11.Cu")
		(net "M_D_CPU0_SA_DQ<26>")
	)
	(gr_poly
		(pts
			(xy 340.138258 -264.70483) (xy 340.091268 -264.55243) (xy 339.829648 -264.55243) (xy 339.782658 -264.70483)
			(xy 339.782658 -264.749026) (xy 340.138258 -264.749026)
		)
		(stroke
			(width 0)
			(type solid)
		)
		(fill yes)
		(layer "In11.Cu")
		(net "M_D_CPU0_SA_CB<2>")
	)
	(gr_poly
		(pts
			(xy 340.349078 -234.621578) (xy 340.387432 -234.59948) (xy 340.209632 -234.291632) (xy 340.171278 -234.31373)
			(xy 340.06282 -234.43057) (xy 340.19363 -234.657138)
		)
		(stroke
			(width 0)
			(type solid)
		)
		(fill yes)
		(layer "In11.Cu")
		(net "M_D_CPU0_SB_DQS_DP<1>")
	)
	(gr_poly
		(pts
			(xy 340.45779 -233.999278) (xy 340.566248 -233.882438) (xy 340.435438 -233.65587) (xy 340.27999 -233.69143)
			(xy 340.241636 -233.713528) (xy 340.419436 -234.021376)
		)
		(stroke
			(width 0)
			(type solid)
		)
		(fill yes)
		(layer "In11.Cu")
		(net "M_D_CPU0_SB_DQS_DN<1>")
	)
	(gr_poly
		(pts
			(xy 340.486238 -245.346474) (xy 340.486238 -245.302024) (xy 340.130638 -245.302024) (xy 340.130638 -245.346474)
			(xy 340.177628 -245.498874) (xy 340.439248 -245.498874)
		)
		(stroke
			(width 0)
			(type solid)
		)
		(fill yes)
		(layer "In11.Cu")
		(net "M_D_CPU0_SB_DQS_DP<9>")
	)
	(gr_poly
		(pts
			(xy 340.492334 -244.127274) (xy 340.445344 -243.974874) (xy 340.183724 -243.974874) (xy 340.136734 -244.127274)
			(xy 340.136734 -244.17147) (xy 340.492334 -244.17147)
		)
		(stroke
			(width 0)
			(type solid)
		)
		(fill yes)
		(layer "In11.Cu")
		(net "M_D_CPU0_SB_DQS_DP<4>")
	)
	(gr_poly
		(pts
			(xy 340.498176 -247.382538) (xy 340.451186 -247.230138) (xy 340.189566 -247.230138) (xy 340.142576 -247.382538)
			(xy 340.142576 -247.426734) (xy 340.498176 -247.426734)
		)
		(stroke
			(width 0)
			(type solid)
		)
		(fill yes)
		(layer "In11.Cu")
		(net "M_D_CPU0_SB_CA<6>")
	)
	(gr_poly
		(pts
			(xy 340.498176 -246.974106) (xy 340.498176 -246.92991) (xy 340.142576 -246.92991) (xy 340.142576 -246.974106)
			(xy 340.189566 -247.126506) (xy 340.451186 -247.126506)
		)
		(stroke
			(width 0)
			(type solid)
		)
		(fill yes)
		(layer "In11.Cu")
		(net "M_D_CPU0_SB_CB<4>")
	)
	(gr_poly
		(pts
			(xy 340.498176 -245.754906) (xy 340.451186 -245.602506) (xy 340.189566 -245.602506) (xy 340.142576 -245.754906)
			(xy 340.142576 -245.799356) (xy 340.498176 -245.799356)
		)
		(stroke
			(width 0)
			(type solid)
		)
		(fill yes)
		(layer "In11.Cu")
		(net "M_D_CPU0_SB_CB<7>")
	)
	(gr_poly
		(pts
			(xy 340.498176 -237.61573) (xy 340.451186 -237.46333) (xy 340.189566 -237.46333) (xy 340.142576 -237.61573)
			(xy 340.142576 -237.659926) (xy 340.498176 -237.659926)
		)
		(stroke
			(width 0)
			(type solid)
		)
		(fill yes)
		(layer "In11.Cu")
		(net "M_D_CPU0_SB_DQ<7>")
	)
	(gr_poly
		(pts
			(xy 340.498176 -237.207806) (xy 340.498176 -237.163356) (xy 340.142576 -237.163356) (xy 340.142576 -237.207806)
			(xy 340.189566 -237.360206) (xy 340.451186 -237.360206)
		)
		(stroke
			(width 0)
			(type solid)
		)
		(fill yes)
		(layer "In11.Cu")
		(net "M_D_CPU0_SB_DQ<8>")
	)
	(gr_poly
		(pts
			(xy 340.498176 -232.324402) (xy 340.498176 -232.279952) (xy 340.142576 -232.279952) (xy 340.142576 -232.324402)
			(xy 340.189566 -232.476802) (xy 340.451186 -232.476802)
		)
		(stroke
			(width 0)
			(type solid)
		)
		(fill yes)
		(layer "In11.Cu")
		(net "M_D_CPU0_SB_DQS_DN<6>")
	)
	(gr_poly
		(pts
			(xy 340.498176 -227.848922) (xy 340.451186 -227.696522) (xy 340.189566 -227.696522) (xy 340.142576 -227.848922)
			(xy 340.142576 -227.893372) (xy 340.498176 -227.893372)
		)
		(stroke
			(width 0)
			(type solid)
		)
		(fill yes)
		(layer "In11.Cu")
		(net "M_D_CPU0_SB_DQS_DN<3>")
	)
	(gr_poly
		(pts
			(xy 340.498176 -227.440998) (xy 340.498176 -227.396548) (xy 340.142576 -227.396548) (xy 340.142576 -227.440998)
			(xy 340.189566 -227.593398) (xy 340.451186 -227.593398)
		)
		(stroke
			(width 0)
			(type solid)
		)
		(fill yes)
		(layer "In11.Cu")
		(net "M_D_CPU0_SB_DQS_DN<8>")
	)
	(gr_poly
		(pts
			(xy 340.500716 -249.01017) (xy 340.453726 -248.85777) (xy 340.192106 -248.85777) (xy 340.145116 -249.01017)
			(xy 340.145116 -249.05462) (xy 340.500716 -249.05462)
		)
		(stroke
			(width 0)
			(type solid)
		)
		(fill yes)
		(layer "In11.Cu")
		(net "M_D_CPU0_SB_CA<3>")
	)
	(gr_poly
		(pts
			(xy 340.500716 -248.602246) (xy 340.500716 -248.557796) (xy 340.145116 -248.557796) (xy 340.145116 -248.602246)
			(xy 340.192106 -248.754646) (xy 340.453726 -248.754646)
		)
		(stroke
			(width 0)
			(type solid)
		)
		(fill yes)
		(layer "In11.Cu")
		(net "M_D_CPU0_SB_CA<4>")
	)
	(gr_poly
		(pts
			(xy 340.500716 -243.718842) (xy 340.500716 -243.674392) (xy 340.145116 -243.674392) (xy 340.145116 -243.718842)
			(xy 340.192106 -243.871242) (xy 340.453726 -243.871242)
		)
		(stroke
			(width 0)
			(type solid)
		)
		(fill yes)
		(layer "In11.Cu")
		(net "M_D_CPU0_SB_CB<0>")
	)
	(gr_poly
		(pts
			(xy 340.500716 -242.499134) (xy 340.453726 -242.346734) (xy 340.192106 -242.346734) (xy 340.145116 -242.499134)
			(xy 340.145116 -242.54333) (xy 340.500716 -242.54333)
		)
		(stroke
			(width 0)
			(type solid)
		)
		(fill yes)
		(layer "In11.Cu")
		(net "M_D_CPU0_SB_CB<3>")
	)
	(gr_poly
		(pts
			(xy 340.500716 -242.090702) (xy 340.500716 -242.046506) (xy 340.145116 -242.046506) (xy 340.145116 -242.090702)
			(xy 340.192106 -242.243102) (xy 340.453726 -242.243102)
		)
		(stroke
			(width 0)
			(type solid)
		)
		(fill yes)
		(layer "In11.Cu")
		(net "M_D_CPU0_SB_DQ<0>")
	)
	(gr_poly
		(pts
			(xy 340.500716 -240.871502) (xy 340.453726 -240.719102) (xy 340.192106 -240.719102) (xy 340.145116 -240.871502)
			(xy 340.145116 -240.915698) (xy 340.500716 -240.915698)
		)
		(stroke
			(width 0)
			(type solid)
		)
		(fill yes)
		(layer "In11.Cu")
		(net "M_D_CPU0_SB_DQ<3>")
	)
	(gr_poly
		(pts
			(xy 340.500716 -240.46307) (xy 340.500716 -240.418874) (xy 340.145116 -240.418874) (xy 340.145116 -240.46307)
			(xy 340.192106 -240.61547) (xy 340.453726 -240.61547)
		)
		(stroke
			(width 0)
			(type solid)
		)
		(fill yes)
		(layer "In11.Cu")
		(net "M_D_CPU0_SB_DQS_DP<0>")
	)
	(gr_poly
		(pts
			(xy 340.500716 -239.243362) (xy 340.453726 -239.090962) (xy 340.192106 -239.090962) (xy 340.145116 -239.243362)
			(xy 340.145116 -239.287812) (xy 340.500716 -239.287812)
		)
		(stroke
			(width 0)
			(type solid)
		)
		(fill yes)
		(layer "In11.Cu")
		(net "M_D_CPU0_SB_DQS_DP<5>")
	)
	(gr_poly
		(pts
			(xy 340.500716 -238.835438) (xy 340.500716 -238.790988) (xy 340.145116 -238.790988) (xy 340.145116 -238.835438)
			(xy 340.192106 -238.987838) (xy 340.453726 -238.987838)
		)
		(stroke
			(width 0)
			(type solid)
		)
		(fill yes)
		(layer "In11.Cu")
		(net "M_D_CPU0_SB_DQ<4>")
	)
	(gr_poly
		(pts
			(xy 340.500716 -235.988098) (xy 340.453726 -235.835698) (xy 340.192106 -235.835698) (xy 340.145116 -235.988098)
			(xy 340.145116 -236.032294) (xy 340.500716 -236.032294)
		)
		(stroke
			(width 0)
			(type solid)
		)
		(fill yes)
		(layer "In11.Cu")
		(net "M_D_CPU0_SB_DQ<11>")
	)
	(gr_poly
		(pts
			(xy 340.500716 -231.104694) (xy 340.453726 -230.952294) (xy 340.192106 -230.952294) (xy 340.145116 -231.104694)
			(xy 340.145116 -231.14889) (xy 340.500716 -231.14889)
		)
		(stroke
			(width 0)
			(type solid)
		)
		(fill yes)
		(layer "In11.Cu")
		(net "M_D_CPU0_SB_DQ<14>")
	)
	(gr_poly
		(pts
			(xy 340.500716 -230.696262) (xy 340.500716 -230.652066) (xy 340.145116 -230.652066) (xy 340.145116 -230.696262)
			(xy 340.192106 -230.848662) (xy 340.453726 -230.848662)
		)
		(stroke
			(width 0)
			(type solid)
		)
		(fill yes)
		(layer "In11.Cu")
		(net "M_D_CPU0_SB_DQ<13>")
	)
	(gr_poly
		(pts
			(xy 340.500716 -229.477062) (xy 340.453726 -229.324662) (xy 340.192106 -229.324662) (xy 340.145116 -229.477062)
			(xy 340.145116 -229.521258) (xy 340.500716 -229.521258)
		)
		(stroke
			(width 0)
			(type solid)
		)
		(fill yes)
		(layer "In11.Cu")
		(net "M_D_CPU0_SB_DQ<26>")
	)
	(gr_poly
		(pts
			(xy 340.500716 -229.06863) (xy 340.500716 -229.024434) (xy 340.145116 -229.024434) (xy 340.145116 -229.06863)
			(xy 340.192106 -229.22103) (xy 340.453726 -229.22103)
		)
		(stroke
			(width 0)
			(type solid)
		)
		(fill yes)
		(layer "In11.Cu")
		(net "M_D_CPU0_SB_DQ<25>")
	)
	(gr_poly
		(pts
			(xy 340.500716 -226.22129) (xy 340.453726 -226.06889) (xy 340.192106 -226.06889) (xy 340.145116 -226.22129)
			(xy 340.145116 -226.26574) (xy 340.500716 -226.26574)
		)
		(stroke
			(width 0)
			(type solid)
		)
		(fill yes)
		(layer "In11.Cu")
		(net "M_D_CPU0_SB_DQ<30>")
	)
	(gr_poly
		(pts
			(xy 340.500716 -225.813366) (xy 340.500716 -225.768916) (xy 340.145116 -225.768916) (xy 340.145116 -225.813366)
			(xy 340.192106 -225.965766) (xy 340.453726 -225.965766)
		)
		(stroke
			(width 0)
			(type solid)
		)
		(fill yes)
		(layer "In11.Cu")
		(net "M_D_CPU0_SB_DQ<29>")
	)
	(gr_poly
		(pts
			(xy 340.59622 -257.37947) (xy 340.54923 -257.22707) (xy 340.28761 -257.22707) (xy 340.24062 -257.37947)
			(xy 340.24062 -257.42392) (xy 340.59622 -257.42392)
		)
		(stroke
			(width 0)
			(type solid)
		)
		(fill yes)
		(layer "In11.Cu")
		(net "M_D_CPU0_SA_CA<1>")
	)
	(gr_poly
		(pts
			(xy 340.59876 -262.262874) (xy 340.55177 -262.110474) (xy 340.29015 -262.110474) (xy 340.24316 -262.262874)
			(xy 340.24316 -262.307324) (xy 340.59876 -262.307324)
		)
		(stroke
			(width 0)
			(type solid)
		)
		(fill yes)
		(layer "In11.Cu")
		(net "M_D_CPU0_SA_DQS_DP<9>")
	)
	(gr_poly
		(pts
			(xy 340.602316 -258.59867) (xy 340.602316 -258.554474) (xy 340.246716 -258.554474) (xy 340.246716 -258.59867)
			(xy 340.293706 -258.75107) (xy 340.555326 -258.75107)
		)
		(stroke
			(width 0)
			(type solid)
		)
		(fill yes)
		(layer "In11.Cu")
		(net "M_D_CPU0_SA_CS_N<3>")
	)
	(gr_poly
		(pts
			(xy 340.608158 -275.284946) (xy 340.561168 -275.132546) (xy 340.299548 -275.132546) (xy 340.252558 -275.284946)
			(xy 340.252558 -275.329142) (xy 340.608158 -275.329142)
		)
		(stroke
			(width 0)
			(type solid)
		)
		(fill yes)
		(layer "In11.Cu")
		(net "M_D_CPU0_SA_DQ<15>")
	)
	(gr_poly
		(pts
			(xy 340.608158 -274.876514) (xy 340.608158 -274.832318) (xy 340.252558 -274.832318) (xy 340.252558 -274.876514)
			(xy 340.299548 -275.028914) (xy 340.561168 -275.028914)
		)
		(stroke
			(width 0)
			(type solid)
		)
		(fill yes)
		(layer "In11.Cu")
		(net "M_D_CPU0_SA_DQ<16>")
	)
	(gr_poly
		(pts
			(xy 340.608158 -270.401542) (xy 340.561168 -270.249142) (xy 340.299548 -270.249142) (xy 340.252558 -270.401542)
			(xy 340.252558 -270.445992) (xy 340.608158 -270.445992)
		)
		(stroke
			(width 0)
			(type solid)
		)
		(fill yes)
		(layer "In11.Cu")
		(net "M_D_CPU0_SA_DQ<23>")
	)
	(gr_poly
		(pts
			(xy 340.608158 -269.993618) (xy 340.608158 -269.949168) (xy 340.252558 -269.949168) (xy 340.252558 -269.993618)
			(xy 340.299548 -270.146018) (xy 340.561168 -270.146018)
		)
		(stroke
			(width 0)
			(type solid)
		)
		(fill yes)
		(layer "In11.Cu")
		(net "M_D_CPU0_SA_DQ<24>")
	)
	(gr_poly
		(pts
			(xy 340.608158 -265.518138) (xy 340.561168 -265.365738) (xy 340.299548 -265.365738) (xy 340.252558 -265.518138)
			(xy 340.252558 -265.562588) (xy 340.608158 -265.562588)
		)
		(stroke
			(width 0)
			(type solid)
		)
		(fill yes)
		(layer "In11.Cu")
		(net "M_D_CPU0_SA_DQ<31>")
	)
	(gr_poly
		(pts
			(xy 340.608158 -265.110214) (xy 340.608158 -265.065764) (xy 340.252558 -265.065764) (xy 340.252558 -265.110214)
			(xy 340.299548 -265.262614) (xy 340.561168 -265.262614)
		)
		(stroke
			(width 0)
			(type solid)
		)
		(fill yes)
		(layer "In11.Cu")
		(net "M_D_CPU0_SA_CB<0>")
	)
	(gr_poly
		(pts
			(xy 340.608158 -260.634734) (xy 340.561168 -260.482334) (xy 340.299548 -260.482334) (xy 340.252558 -260.634734)
			(xy 340.252558 -260.679184) (xy 340.608158 -260.679184)
		)
		(stroke
			(width 0)
			(type solid)
		)
		(fill yes)
		(layer "In11.Cu")
		(net "M_D_CPU0_SA_CB<7>")
	)
	(gr_poly
		(pts
			(xy 340.608158 -256.971038) (xy 340.608158 -256.926588) (xy 340.252558 -256.926588) (xy 340.252558 -256.971038)
			(xy 340.299548 -257.123438) (xy 340.561168 -257.123438)
		)
		(stroke
			(width 0)
			(type solid)
		)
		(fill yes)
		(layer "In11.Cu")
		(net "M_D_CPU0_SA_CA<2>")
	)
	(gr_poly
		(pts
			(xy 340.608158 -255.751838) (xy 340.561168 -255.599438) (xy 340.299548 -255.599438) (xy 340.252558 -255.751838)
			(xy 340.252558 -255.796034) (xy 340.608158 -255.796034)
		)
		(stroke
			(width 0)
			(type solid)
		)
		(fill yes)
		(layer "In11.Cu")
		(net "M_D_CPU0_SA_CA<5>")
	)
	(gr_poly
		(pts
			(xy 340.610698 -279.759918) (xy 340.610698 -279.715722) (xy 340.255098 -279.715722) (xy 340.255098 -279.759918)
			(xy 340.302088 -279.912318) (xy 340.563708 -279.912318)
		)
		(stroke
			(width 0)
			(type solid)
		)
		(fill yes)
		(layer "In11.Cu")
		(net "M_D_CPU0_SA_DQ<8>")
	)
	(gr_poly
		(pts
			(xy 340.610698 -278.540718) (xy 340.563708 -278.388318) (xy 340.302088 -278.388318) (xy 340.255098 -278.540718)
			(xy 340.255098 -278.584914) (xy 340.610698 -278.584914)
		)
		(stroke
			(width 0)
			(type solid)
		)
		(fill yes)
		(layer "In11.Cu")
		(net "M_D_CPU0_SA_DQ<11>")
	)
	(gr_poly
		(pts
			(xy 340.610698 -278.132286) (xy 340.610698 -278.08809) (xy 340.255098 -278.08809) (xy 340.255098 -278.132286)
			(xy 340.302088 -278.284686) (xy 340.563708 -278.284686)
		)
		(stroke
			(width 0)
			(type solid)
		)
		(fill yes)
		(layer "In11.Cu")
		(net "M_D_CPU0_SA_DQS_DP<1>")
	)
	(gr_poly
		(pts
			(xy 340.610698 -276.912578) (xy 340.563708 -276.760178) (xy 340.302088 -276.760178) (xy 340.255098 -276.912578)
			(xy 340.255098 -276.957028) (xy 340.610698 -276.957028)
		)
		(stroke
			(width 0)
			(type solid)
		)
		(fill yes)
		(layer "In11.Cu")
		(net "M_D_CPU0_SA_DQS_DP<6>")
	)
	(gr_poly
		(pts
			(xy 340.610698 -276.5044) (xy 340.610698 -276.460204) (xy 340.255098 -276.460204) (xy 340.255098 -276.5044)
			(xy 340.302088 -276.6568) (xy 340.563708 -276.6568)
		)
		(stroke
			(width 0)
			(type solid)
		)
		(fill yes)
		(layer "In11.Cu")
		(net "M_D_CPU0_SA_DQ<12>")
	)
	(gr_poly
		(pts
			(xy 340.610698 -273.657314) (xy 340.563708 -273.504914) (xy 340.302088 -273.504914) (xy 340.255098 -273.657314)
			(xy 340.255098 -273.70151) (xy 340.610698 -273.70151)
		)
		(stroke
			(width 0)
			(type solid)
		)
		(fill yes)
		(layer "In11.Cu")
		(net "M_D_CPU0_SA_DQ<19>")
	)
	(gr_poly
		(pts
			(xy 340.610698 -273.248882) (xy 340.610698 -273.204686) (xy 340.255098 -273.204686) (xy 340.255098 -273.248882)
			(xy 340.302088 -273.401282) (xy 340.563708 -273.401282)
		)
		(stroke
			(width 0)
			(type solid)
		)
		(fill yes)
		(layer "In11.Cu")
		(net "M_D_CPU0_SA_DQS_DP<2>")
	)
	(gr_poly
		(pts
			(xy 340.610698 -272.029174) (xy 340.563708 -271.876774) (xy 340.302088 -271.876774) (xy 340.255098 -272.029174)
			(xy 340.255098 -272.073624) (xy 340.610698 -272.073624)
		)
		(stroke
			(width 0)
			(type solid)
		)
		(fill yes)
		(layer "In11.Cu")
		(net "M_D_CPU0_SA_DQS_DP<7>")
	)
	(gr_poly
		(pts
			(xy 340.610698 -271.62125) (xy 340.610698 -271.5768) (xy 340.255098 -271.5768) (xy 340.255098 -271.62125)
			(xy 340.302088 -271.77365) (xy 340.563708 -271.77365)
		)
		(stroke
			(width 0)
			(type solid)
		)
		(fill yes)
		(layer "In11.Cu")
		(net "M_D_CPU0_SA_DQ<20>")
	)
	(gr_poly
		(pts
			(xy 340.610698 -268.77391) (xy 340.563708 -268.62151) (xy 340.302088 -268.62151) (xy 340.255098 -268.77391)
			(xy 340.255098 -268.818106) (xy 340.610698 -268.818106)
		)
		(stroke
			(width 0)
			(type solid)
		)
		(fill yes)
		(layer "In11.Cu")
		(net "M_D_CPU0_SA_DQ<27>")
	)
	(gr_poly
		(pts
			(xy 340.610698 -268.365478) (xy 340.610698 -268.321282) (xy 340.255098 -268.321282) (xy 340.255098 -268.365478)
			(xy 340.302088 -268.517878) (xy 340.563708 -268.517878)
		)
		(stroke
			(width 0)
			(type solid)
		)
		(fill yes)
		(layer "In11.Cu")
		(net "M_D_CPU0_SA_DQS_DP<3>")
	)
	(gr_poly
		(pts
			(xy 340.610698 -267.14577) (xy 340.563708 -266.99337) (xy 340.302088 -266.99337) (xy 340.255098 -267.14577)
			(xy 340.255098 -267.19022) (xy 340.610698 -267.19022)
		)
		(stroke
			(width 0)
			(type solid)
		)
		(fill yes)
		(layer "In11.Cu")
		(net "M_D_CPU0_SA_DQS_DP<8>")
	)
	(gr_poly
		(pts
			(xy 340.610698 -266.737846) (xy 340.610698 -266.69365) (xy 340.255098 -266.69365) (xy 340.255098 -266.737846)
			(xy 340.302088 -266.890246) (xy 340.563708 -266.890246)
		)
		(stroke
			(width 0)
			(type solid)
		)
		(fill yes)
		(layer "In11.Cu")
		(net "M_D_CPU0_SA_DQ<28>")
	)
	(gr_poly
		(pts
			(xy 340.610698 -263.890506) (xy 340.563708 -263.738106) (xy 340.302088 -263.738106) (xy 340.255098 -263.890506)
			(xy 340.255098 -263.934956) (xy 340.610698 -263.934956)
		)
		(stroke
			(width 0)
			(type solid)
		)
		(fill yes)
		(layer "In11.Cu")
		(net "M_D_CPU0_SA_CB<3>")
	)
	(gr_poly
		(pts
			(xy 340.610698 -263.482582) (xy 340.610698 -263.438132) (xy 340.255098 -263.438132) (xy 340.255098 -263.482582)
			(xy 340.302088 -263.634982) (xy 340.563708 -263.634982)
		)
		(stroke
			(width 0)
			(type solid)
		)
		(fill yes)
		(layer "In11.Cu")
		(net "M_D_CPU0_SA_DQS_DP<4>")
	)
	(gr_poly
		(pts
			(xy 340.610698 -261.854442) (xy 340.610698 -261.810246) (xy 340.255098 -261.810246) (xy 340.255098 -261.854442)
			(xy 340.302088 -262.006842) (xy 340.563708 -262.006842)
		)
		(stroke
			(width 0)
			(type solid)
		)
		(fill yes)
		(layer "In11.Cu")
		(net "M_D_CPU0_SA_CB<4>")
	)
	(gr_poly
		(pts
			(xy 340.610698 -259.007102) (xy 340.563708 -258.854702) (xy 340.302088 -258.854702) (xy 340.255098 -259.007102)
			(xy 340.255098 -259.051552) (xy 340.610698 -259.051552)
		)
		(stroke
			(width 0)
			(type solid)
		)
		(fill yes)
		(layer "In11.Cu")
		(net "M_D_CPU0_SA_CS_N<0>")
	)
	(gr_poly
		(pts
			(xy 340.81339 -235.425742) (xy 340.851744 -235.403644) (xy 340.673944 -235.095796) (xy 340.63559 -235.117894)
			(xy 340.527132 -235.234734) (xy 340.657942 -235.461302)
		)
		(stroke
			(width 0)
			(type solid)
		)
		(fill yes)
		(layer "In11.Cu")
		(net "M_D_CPU0_SB_DQS_DP<1>")
	)
	(gr_poly
		(pts
			(xy 340.927436 -234.812586) (xy 341.035894 -234.695746) (xy 340.905084 -234.469178) (xy 340.749636 -234.504738)
			(xy 340.711282 -234.526836) (xy 340.889082 -234.834684)
		)
		(stroke
			(width 0)
			(type solid)
		)
		(fill yes)
		(layer "In11.Cu")
		(net "M_D_CPU0_SB_DQS_DN<1>")
	)
	(gr_poly
		(pts
			(xy 340.953598 -249.416062) (xy 340.953598 -249.371612) (xy 340.597998 -249.371612) (xy 340.597998 -249.416062)
			(xy 340.644988 -249.568462) (xy 340.906608 -249.568462)
		)
		(stroke
			(width 0)
			(type solid)
		)
		(fill yes)
		(layer "In11.Cu")
		(net "M_D_CPU0_SB_CA<2>")
	)
	(gr_poly
		(pts
			(xy 340.953598 -248.196354) (xy 340.906608 -248.043954) (xy 340.644988 -248.043954) (xy 340.597998 -248.196354)
			(xy 340.597998 -248.24055) (xy 340.953598 -248.24055)
		)
		(stroke
			(width 0)
			(type solid)
		)
		(fill yes)
		(layer "In11.Cu")
		(net "M_D_CPU0_SB_CA<5>")
	)
	(gr_poly
		(pts
			(xy 340.953598 -247.787922) (xy 340.953598 -247.743726) (xy 340.597998 -247.743726) (xy 340.597998 -247.787922)
			(xy 340.644988 -247.940322) (xy 340.906608 -247.940322)
		)
		(stroke
			(width 0)
			(type solid)
		)
		(fill yes)
		(layer "In11.Cu")
		(net "M_D_CPU0_SB_PAR")
	)
	(gr_poly
		(pts
			(xy 340.953598 -246.568722) (xy 340.906608 -246.416322) (xy 340.644988 -246.416322) (xy 340.597998 -246.568722)
			(xy 340.597998 -246.612918) (xy 340.953598 -246.612918)
		)
		(stroke
			(width 0)
			(type solid)
		)
		(fill yes)
		(layer "In11.Cu")
		(net "M_D_CPU0_SB_CB<6>")
	)
	(gr_poly
		(pts
			(xy 340.953598 -243.31295) (xy 340.906608 -243.16055) (xy 340.644988 -243.16055) (xy 340.597998 -243.31295)
			(xy 340.597998 -243.3574) (xy 340.953598 -243.3574)
		)
		(stroke
			(width 0)
			(type solid)
		)
		(fill yes)
		(layer "In11.Cu")
		(net "M_D_CPU0_SB_CB<2>")
	)
	(gr_poly
		(pts
			(xy 340.953598 -242.905026) (xy 340.953598 -242.860576) (xy 340.597998 -242.860576) (xy 340.597998 -242.905026)
			(xy 340.644988 -243.057426) (xy 340.906608 -243.057426)
		)
		(stroke
			(width 0)
			(type solid)
		)
		(fill yes)
		(layer "In11.Cu")
		(net "M_D_CPU0_SB_CB<1>")
	)
	(gr_poly
		(pts
			(xy 340.953598 -241.685318) (xy 340.906608 -241.532918) (xy 340.644988 -241.532918) (xy 340.597998 -241.685318)
			(xy 340.597998 -241.729514) (xy 340.953598 -241.729514)
		)
		(stroke
			(width 0)
			(type solid)
		)
		(fill yes)
		(layer "In11.Cu")
		(net "M_D_CPU0_SB_DQ<2>")
	)
	(gr_poly
		(pts
			(xy 340.953598 -241.276886) (xy 340.953598 -241.23269) (xy 340.597998 -241.23269) (xy 340.597998 -241.276886)
			(xy 340.644988 -241.429286) (xy 340.906608 -241.429286)
		)
		(stroke
			(width 0)
			(type solid)
		)
		(fill yes)
		(layer "In11.Cu")
		(net "M_D_CPU0_SB_DQ<1>")
	)
	(gr_poly
		(pts
			(xy 340.953598 -240.057178) (xy 340.906608 -239.904778) (xy 340.644988 -239.904778) (xy 340.597998 -240.057178)
			(xy 340.597998 -240.101628) (xy 340.953598 -240.101628)
		)
		(stroke
			(width 0)
			(type solid)
		)
		(fill yes)
		(layer "In11.Cu")
		(net "M_D_CPU0_SB_DQS_DN<0>")
	)
	(gr_poly
		(pts
			(xy 340.953598 -239.649254) (xy 340.953598 -239.604804) (xy 340.597998 -239.604804) (xy 340.597998 -239.649254)
			(xy 340.644988 -239.801654) (xy 340.906608 -239.801654)
		)
		(stroke
			(width 0)
			(type solid)
		)
		(fill yes)
		(layer "In11.Cu")
		(net "M_D_CPU0_SB_DQS_DN<5>")
	)
	(gr_poly
		(pts
			(xy 340.953598 -238.429546) (xy 340.906608 -238.277146) (xy 340.644988 -238.277146) (xy 340.597998 -238.429546)
			(xy 340.597998 -238.473996) (xy 340.953598 -238.473996)
		)
		(stroke
			(width 0)
			(type solid)
		)
		(fill yes)
		(layer "In11.Cu")
		(net "M_D_CPU0_SB_DQ<6>")
	)
	(gr_poly
		(pts
			(xy 340.953598 -238.021622) (xy 340.953598 -237.977172) (xy 340.597998 -237.977172) (xy 340.597998 -238.021622)
			(xy 340.644988 -238.174022) (xy 340.906608 -238.174022)
		)
		(stroke
			(width 0)
			(type solid)
		)
		(fill yes)
		(layer "In11.Cu")
		(net "M_D_CPU0_SB_DQ<5>")
	)
	(gr_poly
		(pts
			(xy 340.953598 -236.801914) (xy 340.906608 -236.649514) (xy 340.644988 -236.649514) (xy 340.597998 -236.801914)
			(xy 340.597998 -236.84611) (xy 340.953598 -236.84611)
		)
		(stroke
			(width 0)
			(type solid)
		)
		(fill yes)
		(layer "In11.Cu")
		(net "M_D_CPU0_SB_DQ<10>")
	)
	(gr_poly
		(pts
			(xy 340.953598 -236.39399) (xy 340.953598 -236.34954) (xy 340.597998 -236.34954) (xy 340.597998 -236.39399)
			(xy 340.644988 -236.54639) (xy 340.906608 -236.54639)
		)
		(stroke
			(width 0)
			(type solid)
		)
		(fill yes)
		(layer "In11.Cu")
		(net "M_D_CPU0_SB_DQ<9>")
	)
	(gr_poly
		(pts
			(xy 340.953598 -231.91851) (xy 340.906608 -231.76611) (xy 340.644988 -231.76611) (xy 340.597998 -231.91851)
			(xy 340.597998 -231.96296) (xy 340.953598 -231.96296)
		)
		(stroke
			(width 0)
			(type solid)
		)
		(fill yes)
		(layer "In11.Cu")
		(net "M_D_CPU0_SB_DQS_DP<6>")
	)
	(gr_poly
		(pts
			(xy 340.953598 -231.510586) (xy 340.953598 -231.466136) (xy 340.597998 -231.466136) (xy 340.597998 -231.510586)
			(xy 340.644988 -231.662986) (xy 340.906608 -231.662986)
		)
		(stroke
			(width 0)
			(type solid)
		)
		(fill yes)
		(layer "In11.Cu")
		(net "M_D_CPU0_SB_DQ<12>")
	)
	(gr_poly
		(pts
			(xy 340.953598 -230.290878) (xy 340.906608 -230.138478) (xy 340.644988 -230.138478) (xy 340.597998 -230.290878)
			(xy 340.597998 -230.335074) (xy 340.953598 -230.335074)
		)
		(stroke
			(width 0)
			(type solid)
		)
		(fill yes)
		(layer "In11.Cu")
		(net "M_D_CPU0_SB_DQ<15>")
	)
	(gr_poly
		(pts
			(xy 340.953598 -229.882446) (xy 340.953598 -229.83825) (xy 340.597998 -229.83825) (xy 340.597998 -229.882446)
			(xy 340.644988 -230.034846) (xy 340.906608 -230.034846)
		)
		(stroke
			(width 0)
			(type solid)
		)
		(fill yes)
		(layer "In11.Cu")
		(net "M_D_CPU0_SB_DQ<24>")
	)
	(gr_poly
		(pts
			(xy 340.953598 -228.663246) (xy 340.906608 -228.510846) (xy 340.644988 -228.510846) (xy 340.597998 -228.663246)
			(xy 340.597998 -228.707442) (xy 340.953598 -228.707442)
		)
		(stroke
			(width 0)
			(type solid)
		)
		(fill yes)
		(layer "In11.Cu")
		(net "M_D_CPU0_SB_DQ<27>")
	)
	(gr_poly
		(pts
			(xy 340.953598 -228.254814) (xy 340.953598 -228.210618) (xy 340.597998 -228.210618) (xy 340.597998 -228.254814)
			(xy 340.644988 -228.407214) (xy 340.906608 -228.407214)
		)
		(stroke
			(width 0)
			(type solid)
		)
		(fill yes)
		(layer "In11.Cu")
		(net "M_D_CPU0_SB_DQS_DP<3>")
	)
	(gr_poly
		(pts
			(xy 340.953598 -226.627182) (xy 340.953598 -226.582732) (xy 340.597998 -226.582732) (xy 340.597998 -226.627182)
			(xy 340.644988 -226.779582) (xy 340.906608 -226.779582)
		)
		(stroke
			(width 0)
			(type solid)
		)
		(fill yes)
		(layer "In11.Cu")
		(net "M_D_CPU0_SB_DQ<28>")
	)
	(gr_poly
		(pts
			(xy 340.953598 -225.407474) (xy 340.906608 -225.255074) (xy 340.644988 -225.255074) (xy 340.597998 -225.407474)
			(xy 340.597998 -225.45167) (xy 340.953598 -225.45167)
		)
		(stroke
			(width 0)
			(type solid)
		)
		(fill yes)
		(layer "In11.Cu")
		(net "M_D_CPU0_SB_DQ<31>")
	)
	(gr_poly
		(pts
			(xy 340.956138 -244.53215) (xy 340.956138 -244.487954) (xy 340.600538 -244.487954) (xy 340.600538 -244.53215)
			(xy 340.647528 -244.68455) (xy 340.909148 -244.68455)
		)
		(stroke
			(width 0)
			(type solid)
		)
		(fill yes)
		(layer "In11.Cu")
		(net "M_D_CPU0_SB_DQS_DN<4>")
	)
	(gr_poly
		(pts
			(xy 340.96198 -246.16029) (xy 340.96198 -246.11584) (xy 340.60638 -246.11584) (xy 340.60638 -246.16029)
			(xy 340.65337 -246.31269) (xy 340.91499 -246.31269)
		)
		(stroke
			(width 0)
			(type solid)
		)
		(fill yes)
		(layer "In11.Cu")
		(net "M_D_CPU0_SB_CB<5>")
	)
	(gr_poly
		(pts
			(xy 340.962742 -227.035614) (xy 340.915752 -226.883214) (xy 340.654132 -226.883214) (xy 340.607142 -227.035614)
			(xy 340.607142 -227.07981) (xy 340.962742 -227.07981)
		)
		(stroke
			(width 0)
			(type solid)
		)
		(fill yes)
		(layer "In11.Cu")
		(net "M_D_CPU0_SB_DQS_DP<8>")
	)
	(gr_poly
		(pts
			(xy 340.968076 -244.94109) (xy 340.921086 -244.78869) (xy 340.659466 -244.78869) (xy 340.612476 -244.94109)
			(xy 340.612476 -244.985286) (xy 340.968076 -244.985286)
		)
		(stroke
			(width 0)
			(type solid)
		)
		(fill yes)
		(layer "In11.Cu")
		(net "M_D_CPU0_SB_DQS_DN<9>")
	)
	(gr_poly
		(pts
			(xy 341.06358 -279.354534) (xy 341.01659 -279.202134) (xy 340.75497 -279.202134) (xy 340.70798 -279.354534)
			(xy 340.70798 -279.39873) (xy 341.06358 -279.39873)
		)
		(stroke
			(width 0)
			(type solid)
		)
		(fill yes)
		(layer "In11.Cu")
		(net "M_D_CPU0_SA_DQ<10>")
	)
	(gr_poly
		(pts
			(xy 341.06358 -278.946102) (xy 341.06358 -278.901906) (xy 340.70798 -278.901906) (xy 340.70798 -278.946102)
			(xy 340.75497 -279.098502) (xy 341.01659 -279.098502)
		)
		(stroke
			(width 0)
			(type solid)
		)
		(fill yes)
		(layer "In11.Cu")
		(net "M_D_CPU0_SA_DQ<9>")
	)
	(gr_poly
		(pts
			(xy 341.06358 -277.726394) (xy 341.01659 -277.573994) (xy 340.75497 -277.573994) (xy 340.70798 -277.726394)
			(xy 340.70798 -277.770844) (xy 341.06358 -277.770844)
		)
		(stroke
			(width 0)
			(type solid)
		)
		(fill yes)
		(layer "In11.Cu")
		(net "M_D_CPU0_SA_DQS_DN<1>")
	)
	(gr_poly
		(pts
			(xy 341.06358 -277.318216) (xy 341.06358 -277.27402) (xy 340.70798 -277.27402) (xy 340.70798 -277.318216)
			(xy 340.75497 -277.470616) (xy 341.01659 -277.470616)
		)
		(stroke
			(width 0)
			(type solid)
		)
		(fill yes)
		(layer "In11.Cu")
		(net "M_D_CPU0_SA_DQS_DN<6>")
	)
	(gr_poly
		(pts
			(xy 341.06358 -276.098762) (xy 341.01659 -275.946362) (xy 340.75497 -275.946362) (xy 340.70798 -276.098762)
			(xy 340.70798 -276.143212) (xy 341.06358 -276.143212)
		)
		(stroke
			(width 0)
			(type solid)
		)
		(fill yes)
		(layer "In11.Cu")
		(net "M_D_CPU0_SA_DQ<14>")
	)
	(gr_poly
		(pts
			(xy 341.06358 -275.690584) (xy 341.06358 -275.646388) (xy 340.70798 -275.646388) (xy 340.70798 -275.690584)
			(xy 340.75497 -275.842984) (xy 341.01659 -275.842984)
		)
		(stroke
			(width 0)
			(type solid)
		)
		(fill yes)
		(layer "In11.Cu")
		(net "M_D_CPU0_SA_DQ<13>")
	)
	(gr_poly
		(pts
			(xy 341.06358 -274.47113) (xy 341.01659 -274.31873) (xy 340.75497 -274.31873) (xy 340.70798 -274.47113)
			(xy 340.70798 -274.515326) (xy 341.06358 -274.515326)
		)
		(stroke
			(width 0)
			(type solid)
		)
		(fill yes)
		(layer "In11.Cu")
		(net "M_D_CPU0_SA_DQ<18>")
	)
	(gr_poly
		(pts
			(xy 341.06358 -274.062698) (xy 341.06358 -274.018502) (xy 340.70798 -274.018502) (xy 340.70798 -274.062698)
			(xy 340.75497 -274.215098) (xy 341.01659 -274.215098)
		)
		(stroke
			(width 0)
			(type solid)
		)
		(fill yes)
		(layer "In11.Cu")
		(net "M_D_CPU0_SA_DQ<17>")
	)
	(gr_poly
		(pts
			(xy 341.06358 -272.843498) (xy 341.01659 -272.691098) (xy 340.75497 -272.691098) (xy 340.70798 -272.843498)
			(xy 340.70798 -272.887694) (xy 341.06358 -272.887694)
		)
		(stroke
			(width 0)
			(type solid)
		)
		(fill yes)
		(layer "In11.Cu")
		(net "M_D_CPU0_SA_DQS_DN<2>")
	)
	(gr_poly
		(pts
			(xy 341.06358 -272.435066) (xy 341.06358 -272.39087) (xy 340.70798 -272.39087) (xy 340.70798 -272.435066)
			(xy 340.75497 -272.587466) (xy 341.01659 -272.587466)
		)
		(stroke
			(width 0)
			(type solid)
		)
		(fill yes)
		(layer "In11.Cu")
		(net "M_D_CPU0_SA_DQS_DN<7>")
	)
	(gr_poly
		(pts
			(xy 341.06358 -271.215358) (xy 341.01659 -271.062958) (xy 340.75497 -271.062958) (xy 340.70798 -271.215358)
			(xy 340.70798 -271.259808) (xy 341.06358 -271.259808)
		)
		(stroke
			(width 0)
			(type solid)
		)
		(fill yes)
		(layer "In11.Cu")
		(net "M_D_CPU0_SA_DQ<22>")
	)
	(gr_poly
		(pts
			(xy 341.06358 -270.807434) (xy 341.06358 -270.762984) (xy 340.70798 -270.762984) (xy 340.70798 -270.807434)
			(xy 340.75497 -270.959834) (xy 341.01659 -270.959834)
		)
		(stroke
			(width 0)
			(type solid)
		)
		(fill yes)
		(layer "In11.Cu")
		(net "M_D_CPU0_SA_DQ<21>")
	)
	(gr_poly
		(pts
			(xy 341.06358 -269.587726) (xy 341.01659 -269.435326) (xy 340.75497 -269.435326) (xy 340.70798 -269.587726)
			(xy 340.70798 -269.631922) (xy 341.06358 -269.631922)
		)
		(stroke
			(width 0)
			(type solid)
		)
		(fill yes)
		(layer "In11.Cu")
		(net "M_D_CPU0_SA_DQ<26>")
	)
	(gr_poly
		(pts
			(xy 341.06358 -269.179294) (xy 341.06358 -269.135098) (xy 340.70798 -269.135098) (xy 340.70798 -269.179294)
			(xy 340.75497 -269.331694) (xy 341.01659 -269.331694)
		)
		(stroke
			(width 0)
			(type solid)
		)
		(fill yes)
		(layer "In11.Cu")
		(net "M_D_CPU0_SA_DQ<25>")
	)
	(gr_poly
		(pts
			(xy 341.06358 -267.960094) (xy 341.01659 -267.807694) (xy 340.75497 -267.807694) (xy 340.70798 -267.960094)
			(xy 340.70798 -268.00429) (xy 341.06358 -268.00429)
		)
		(stroke
			(width 0)
			(type solid)
		)
		(fill yes)
		(layer "In11.Cu")
		(net "M_D_CPU0_SA_DQS_DN<3>")
	)
	(gr_poly
		(pts
			(xy 341.06358 -267.551662) (xy 341.06358 -267.507466) (xy 340.70798 -267.507466) (xy 340.70798 -267.551662)
			(xy 340.75497 -267.704062) (xy 341.01659 -267.704062)
		)
		(stroke
			(width 0)
			(type solid)
		)
		(fill yes)
		(layer "In11.Cu")
		(net "M_D_CPU0_SA_DQS_DN<8>")
	)
	(gr_poly
		(pts
			(xy 341.06358 -266.331954) (xy 341.01659 -266.179554) (xy 340.75497 -266.179554) (xy 340.70798 -266.331954)
			(xy 340.70798 -266.376404) (xy 341.06358 -266.376404)
		)
		(stroke
			(width 0)
			(type solid)
		)
		(fill yes)
		(layer "In11.Cu")
		(net "M_D_CPU0_SA_DQ<30>")
	)
	(gr_poly
		(pts
			(xy 341.06358 -265.92403) (xy 341.06358 -265.87958) (xy 340.70798 -265.87958) (xy 340.70798 -265.92403)
			(xy 340.75497 -266.07643) (xy 341.01659 -266.07643)
		)
		(stroke
			(width 0)
			(type solid)
		)
		(fill yes)
		(layer "In11.Cu")
		(net "M_D_CPU0_SA_DQ<29>")
	)
	(gr_poly
		(pts
			(xy 341.06358 -264.704322) (xy 341.01659 -264.551922) (xy 340.75497 -264.551922) (xy 340.70798 -264.704322)
			(xy 340.70798 -264.748772) (xy 341.06358 -264.748772)
		)
		(stroke
			(width 0)
			(type solid)
		)
		(fill yes)
		(layer "In11.Cu")
		(net "M_D_CPU0_SA_CB<2>")
	)
	(gr_poly
		(pts
			(xy 341.06358 -264.296398) (xy 341.06358 -264.251948) (xy 340.70798 -264.251948) (xy 340.70798 -264.296398)
			(xy 340.75497 -264.448798) (xy 341.01659 -264.448798)
		)
		(stroke
			(width 0)
			(type solid)
		)
		(fill yes)
		(layer "In11.Cu")
		(net "M_D_CPU0_SA_CB<1>")
	)
	(gr_poly
		(pts
			(xy 341.06358 -263.07669) (xy 341.01659 -262.92429) (xy 340.75497 -262.92429) (xy 340.70798 -263.07669)
			(xy 340.70798 -263.120886) (xy 341.06358 -263.120886)
		)
		(stroke
			(width 0)
			(type solid)
		)
		(fill yes)
		(layer "In11.Cu")
		(net "M_D_CPU0_SA_DQS_DN<4>")
	)
	(gr_poly
		(pts
			(xy 341.06358 -261.449058) (xy 341.01659 -261.296658) (xy 340.75497 -261.296658) (xy 340.70798 -261.449058)
			(xy 340.70798 -261.493254) (xy 341.06358 -261.493254)
		)
		(stroke
			(width 0)
			(type solid)
		)
		(fill yes)
		(layer "In11.Cu")
		(net "M_D_CPU0_SA_CB<6>")
	)
	(gr_poly
		(pts
			(xy 341.06358 -261.040626) (xy 341.06358 -260.99643) (xy 340.70798 -260.99643) (xy 340.70798 -261.040626)
			(xy 340.75497 -261.193026) (xy 341.01659 -261.193026)
		)
		(stroke
			(width 0)
			(type solid)
		)
		(fill yes)
		(layer "In11.Cu")
		(net "M_D_CPU0_SA_CB<5>")
	)
	(gr_poly
		(pts
			(xy 341.06358 -259.412994) (xy 341.06358 -259.368544) (xy 340.70798 -259.368544) (xy 340.70798 -259.412994)
			(xy 340.75497 -259.565394) (xy 341.01659 -259.565394)
		)
		(stroke
			(width 0)
			(type solid)
		)
		(fill yes)
		(layer "In11.Cu")
		(net "M_D_CPU0_SA_CS_N<2>")
	)
	(gr_poly
		(pts
			(xy 341.06358 -256.157222) (xy 341.06358 -256.113026) (xy 340.70798 -256.113026) (xy 340.70798 -256.157222)
			(xy 340.75497 -256.309622) (xy 341.01659 -256.309622)
		)
		(stroke
			(width 0)
			(type solid)
		)
		(fill yes)
		(layer "In11.Cu")
		(net "M_D_CPU0_SA_CA<4>")
	)
	(gr_poly
		(pts
			(xy 341.06612 -258.193286) (xy 341.01913 -258.040886) (xy 340.75751 -258.040886) (xy 340.71052 -258.193286)
			(xy 340.71052 -258.237736) (xy 341.06612 -258.237736)
		)
		(stroke
			(width 0)
			(type solid)
		)
		(fill yes)
		(layer "In11.Cu")
		(net "M_D_CPU0_SA_CS_N<1>")
	)
	(gr_poly
		(pts
			(xy 341.071962 -256.565654) (xy 341.024972 -256.413254) (xy 340.763352 -256.413254) (xy 340.716362 -256.565654)
			(xy 340.716362 -256.610104) (xy 341.071962 -256.610104)
		)
		(stroke
			(width 0)
			(type solid)
		)
		(fill yes)
		(layer "In11.Cu")
		(net "M_D_CPU0_SA_CA<3>")
	)
	(gr_poly
		(pts
			(xy 341.075518 -262.668258) (xy 341.075518 -262.623808) (xy 340.719918 -262.623808) (xy 340.719918 -262.668258)
			(xy 340.766908 -262.820658) (xy 341.028528 -262.820658)
		)
		(stroke
			(width 0)
			(type solid)
		)
		(fill yes)
		(layer "In11.Cu")
		(net "M_D_CPU0_SA_DQS_DN<9>")
	)
	(gr_poly
		(pts
			(xy 341.078058 -257.784854) (xy 341.078058 -257.740404) (xy 340.722458 -257.740404) (xy 340.722458 -257.784854)
			(xy 340.769448 -257.937254) (xy 341.031068 -257.937254)
		)
		(stroke
			(width 0)
			(type solid)
		)
		(fill yes)
		(layer "In11.Cu")
		(net "M_D_CPU0_SA_CA<0>")
	)
	(gr_poly
		(pts
			(xy 341.288878 -232.993692) (xy 341.327232 -232.971594) (xy 341.149432 -232.663746) (xy 341.111078 -232.685844)
			(xy 341.00262 -232.802684) (xy 341.13343 -233.029252)
		)
		(stroke
			(width 0)
			(type solid)
		)
		(fill yes)
		(layer "In11.Cu")
		(net "M_D_CPU0_SB_DQS_DN<6>")
	)
	(gr_poly
		(pts
			(xy 341.402924 -232.380536) (xy 341.511382 -232.263696) (xy 341.380572 -232.037128) (xy 341.225124 -232.072688)
			(xy 341.18677 -232.094786) (xy 341.36457 -232.402634)
		)
		(stroke
			(width 0)
			(type solid)
		)
		(fill yes)
		(layer "In11.Cu")
		(net "M_D_CPU0_SB_DQS_DP<6>")
	)
	(gr_poly
		(pts
			(xy 341.437976 -245.754906) (xy 341.390986 -245.602506) (xy 341.129366 -245.602506) (xy 341.082376 -245.754906)
			(xy 341.082376 -245.799102) (xy 341.437976 -245.799102)
		)
		(stroke
			(width 0)
			(type solid)
		)
		(fill yes)
		(layer "In11.Cu")
		(net "M_D_CPU0_SB_CB<7>")
	)
	(gr_poly
		(pts
			(xy 341.437976 -245.346474) (xy 341.437976 -245.302278) (xy 341.082376 -245.302278) (xy 341.082376 -245.346474)
			(xy 341.129366 -245.498874) (xy 341.390986 -245.498874)
		)
		(stroke
			(width 0)
			(type solid)
		)
		(fill yes)
		(layer "In11.Cu")
		(net "M_D_CPU0_SB_DQS_DP<9>")
	)
	(gr_poly
		(pts
			(xy 341.440516 -249.01017) (xy 341.393526 -248.85777) (xy 341.131906 -248.85777) (xy 341.084916 -249.01017)
			(xy 341.084916 -249.05462) (xy 341.440516 -249.05462)
		)
		(stroke
			(width 0)
			(type solid)
		)
		(fill yes)
		(layer "In11.Cu")
		(net "M_D_CPU0_SB_CA<3>")
	)
	(gr_poly
		(pts
			(xy 341.440516 -248.602246) (xy 341.440516 -248.557796) (xy 341.084916 -248.557796) (xy 341.084916 -248.602246)
			(xy 341.131906 -248.754646) (xy 341.393526 -248.754646)
		)
		(stroke
			(width 0)
			(type solid)
		)
		(fill yes)
		(layer "In11.Cu")
		(net "M_D_CPU0_SB_CA<4>")
	)
	(gr_poly
		(pts
			(xy 341.440516 -247.382538) (xy 341.393526 -247.230138) (xy 341.131906 -247.230138) (xy 341.084916 -247.382538)
			(xy 341.084916 -247.426734) (xy 341.440516 -247.426734)
		)
		(stroke
			(width 0)
			(type solid)
		)
		(fill yes)
		(layer "In11.Cu")
		(net "M_D_CPU0_SB_CA<6>")
	)
	(gr_poly
		(pts
			(xy 341.440516 -246.974106) (xy 341.440516 -246.92991) (xy 341.084916 -246.92991) (xy 341.084916 -246.974106)
			(xy 341.131906 -247.126506) (xy 341.393526 -247.126506)
		)
		(stroke
			(width 0)
			(type solid)
		)
		(fill yes)
		(layer "In11.Cu")
		(net "M_D_CPU0_SB_CB<4>")
	)
	(gr_poly
		(pts
			(xy 341.440516 -244.126766) (xy 341.393526 -243.974366) (xy 341.131906 -243.974366) (xy 341.084916 -244.126766)
			(xy 341.084916 -244.171216) (xy 341.440516 -244.171216)
		)
		(stroke
			(width 0)
			(type solid)
		)
		(fill yes)
		(layer "In11.Cu")
		(net "M_D_CPU0_SB_DQS_DP<4>")
	)
	(gr_poly
		(pts
			(xy 341.440516 -243.718842) (xy 341.440516 -243.674392) (xy 341.084916 -243.674392) (xy 341.084916 -243.718842)
			(xy 341.131906 -243.871242) (xy 341.393526 -243.871242)
		)
		(stroke
			(width 0)
			(type solid)
		)
		(fill yes)
		(layer "In11.Cu")
		(net "M_D_CPU0_SB_CB<0>")
	)
	(gr_poly
		(pts
			(xy 341.440516 -242.499134) (xy 341.393526 -242.346734) (xy 341.131906 -242.346734) (xy 341.084916 -242.499134)
			(xy 341.084916 -242.54333) (xy 341.440516 -242.54333)
		)
		(stroke
			(width 0)
			(type solid)
		)
		(fill yes)
		(layer "In11.Cu")
		(net "M_D_CPU0_SB_CB<3>")
	)
	(gr_poly
		(pts
			(xy 341.440516 -242.090702) (xy 341.440516 -242.046506) (xy 341.084916 -242.046506) (xy 341.084916 -242.090702)
			(xy 341.131906 -242.243102) (xy 341.393526 -242.243102)
		)
		(stroke
			(width 0)
			(type solid)
		)
		(fill yes)
		(layer "In11.Cu")
		(net "M_D_CPU0_SB_DQ<0>")
	)
	(gr_poly
		(pts
			(xy 341.440516 -240.871502) (xy 341.393526 -240.719102) (xy 341.131906 -240.719102) (xy 341.084916 -240.871502)
			(xy 341.084916 -240.915698) (xy 341.440516 -240.915698)
		)
		(stroke
			(width 0)
			(type solid)
		)
		(fill yes)
		(layer "In11.Cu")
		(net "M_D_CPU0_SB_DQ<3>")
	)
	(gr_poly
		(pts
			(xy 341.440516 -240.46307) (xy 341.440516 -240.418874) (xy 341.084916 -240.418874) (xy 341.084916 -240.46307)
			(xy 341.131906 -240.61547) (xy 341.393526 -240.61547)
		)
		(stroke
			(width 0)
			(type solid)
		)
		(fill yes)
		(layer "In11.Cu")
		(net "M_D_CPU0_SB_DQS_DP<0>")
	)
	(gr_poly
		(pts
			(xy 341.440516 -239.243362) (xy 341.393526 -239.090962) (xy 341.131906 -239.090962) (xy 341.084916 -239.243362)
			(xy 341.084916 -239.287812) (xy 341.440516 -239.287812)
		)
		(stroke
			(width 0)
			(type solid)
		)
		(fill yes)
		(layer "In11.Cu")
		(net "M_D_CPU0_SB_DQS_DP<5>")
	)
	(gr_poly
		(pts
			(xy 341.440516 -238.835438) (xy 341.440516 -238.790988) (xy 341.084916 -238.790988) (xy 341.084916 -238.835438)
			(xy 341.131906 -238.987838) (xy 341.393526 -238.987838)
		)
		(stroke
			(width 0)
			(type solid)
		)
		(fill yes)
		(layer "In11.Cu")
		(net "M_D_CPU0_SB_DQ<4>")
	)
	(gr_poly
		(pts
			(xy 341.440516 -237.61573) (xy 341.393526 -237.46333) (xy 341.131906 -237.46333) (xy 341.084916 -237.61573)
			(xy 341.084916 -237.659926) (xy 341.440516 -237.659926)
		)
		(stroke
			(width 0)
			(type solid)
		)
		(fill yes)
		(layer "In11.Cu")
		(net "M_D_CPU0_SB_DQ<7>")
	)
	(gr_poly
		(pts
			(xy 341.440516 -237.207806) (xy 341.440516 -237.163356) (xy 341.084916 -237.163356) (xy 341.084916 -237.207806)
			(xy 341.131906 -237.360206) (xy 341.393526 -237.360206)
		)
		(stroke
			(width 0)
			(type solid)
		)
		(fill yes)
		(layer "In11.Cu")
		(net "M_D_CPU0_SB_DQ<8>")
	)
	(gr_poly
		(pts
			(xy 341.440516 -235.988098) (xy 341.393526 -235.835698) (xy 341.131906 -235.835698) (xy 341.084916 -235.988098)
			(xy 341.084916 -236.032294) (xy 341.440516 -236.032294)
		)
		(stroke
			(width 0)
			(type solid)
		)
		(fill yes)
		(layer "In11.Cu")
		(net "M_D_CPU0_SB_DQ<11>")
	)
	(gr_poly
		(pts
			(xy 341.440516 -235.579666) (xy 341.440516 -235.53547) (xy 341.084916 -235.53547) (xy 341.084916 -235.579666)
			(xy 341.131906 -235.732066) (xy 341.393526 -235.732066)
		)
		(stroke
			(width 0)
			(type solid)
		)
		(fill yes)
		(layer "In11.Cu")
		(net "M_D_CPU0_SB_DQS_DP<1>")
	)
	(gr_poly
		(pts
			(xy 341.440516 -231.104694) (xy 341.393526 -230.952294) (xy 341.131906 -230.952294) (xy 341.084916 -231.104694)
			(xy 341.084916 -231.14889) (xy 341.440516 -231.14889)
		)
		(stroke
			(width 0)
			(type solid)
		)
		(fill yes)
		(layer "In11.Cu")
		(net "M_D_CPU0_SB_DQ<14>")
	)
	(gr_poly
		(pts
			(xy 341.440516 -230.696262) (xy 341.440516 -230.652066) (xy 341.084916 -230.652066) (xy 341.084916 -230.696262)
			(xy 341.131906 -230.848662) (xy 341.393526 -230.848662)
		)
		(stroke
			(width 0)
			(type solid)
		)
		(fill yes)
		(layer "In11.Cu")
		(net "M_D_CPU0_SB_DQ<13>")
	)
	(gr_poly
		(pts
			(xy 341.440516 -229.477062) (xy 341.393526 -229.324662) (xy 341.131906 -229.324662) (xy 341.084916 -229.477062)
			(xy 341.084916 -229.521258) (xy 341.440516 -229.521258)
		)
		(stroke
			(width 0)
			(type solid)
		)
		(fill yes)
		(layer "In11.Cu")
		(net "M_D_CPU0_SB_DQ<26>")
	)
	(gr_poly
		(pts
			(xy 341.440516 -229.06863) (xy 341.440516 -229.024434) (xy 341.084916 -229.024434) (xy 341.084916 -229.06863)
			(xy 341.131906 -229.22103) (xy 341.393526 -229.22103)
		)
		(stroke
			(width 0)
			(type solid)
		)
		(fill yes)
		(layer "In11.Cu")
		(net "M_D_CPU0_SB_DQ<25>")
	)
	(gr_poly
		(pts
			(xy 341.440516 -227.848922) (xy 341.393526 -227.696522) (xy 341.131906 -227.696522) (xy 341.084916 -227.848922)
			(xy 341.084916 -227.893372) (xy 341.440516 -227.893372)
		)
		(stroke
			(width 0)
			(type solid)
		)
		(fill yes)
		(layer "In11.Cu")
		(net "M_D_CPU0_SB_DQS_DN<3>")
	)
	(gr_poly
		(pts
			(xy 341.440516 -227.440998) (xy 341.440516 -227.396548) (xy 341.084916 -227.396548) (xy 341.084916 -227.440998)
			(xy 341.131906 -227.593398) (xy 341.393526 -227.593398)
		)
		(stroke
			(width 0)
			(type solid)
		)
		(fill yes)
		(layer "In11.Cu")
		(net "M_D_CPU0_SB_DQS_DN<8>")
	)
	(gr_poly
		(pts
			(xy 341.440516 -226.22129) (xy 341.393526 -226.06889) (xy 341.131906 -226.06889) (xy 341.084916 -226.22129)
			(xy 341.084916 -226.26574) (xy 341.440516 -226.26574)
		)
		(stroke
			(width 0)
			(type solid)
		)
		(fill yes)
		(layer "In11.Cu")
		(net "M_D_CPU0_SB_DQ<30>")
	)
	(gr_poly
		(pts
			(xy 341.440516 -225.813366) (xy 341.440516 -225.768916) (xy 341.084916 -225.768916) (xy 341.084916 -225.813366)
			(xy 341.131906 -225.965766) (xy 341.393526 -225.965766)
		)
		(stroke
			(width 0)
			(type solid)
		)
		(fill yes)
		(layer "In11.Cu")
		(net "M_D_CPU0_SB_DQ<29>")
	)
	(gr_poly
		(pts
			(xy 341.53856 -268.77391) (xy 341.49157 -268.62151) (xy 341.22995 -268.62151) (xy 341.18296 -268.77391)
			(xy 341.18296 -268.81836) (xy 341.53856 -268.81836)
		)
		(stroke
			(width 0)
			(type solid)
		)
		(fill yes)
		(layer "In11.Cu")
		(net "M_D_CPU0_SA_DQ<27>")
	)
	(gr_poly
		(pts
			(xy 341.53856 -262.262874) (xy 341.49157 -262.110474) (xy 341.22995 -262.110474) (xy 341.18296 -262.262874)
			(xy 341.18296 -262.307324) (xy 341.53856 -262.307324)
		)
		(stroke
			(width 0)
			(type solid)
		)
		(fill yes)
		(layer "In11.Cu")
		(net "M_D_CPU0_SA_DQS_DP<9>")
	)
	(gr_poly
		(pts
			(xy 341.547958 -279.759664) (xy 341.547958 -279.715468) (xy 341.192358 -279.715468) (xy 341.192358 -279.759664)
			(xy 341.239348 -279.912064) (xy 341.500968 -279.912064)
		)
		(stroke
			(width 0)
			(type solid)
		)
		(fill yes)
		(layer "In11.Cu")
		(net "M_D_CPU0_SA_DQ<8>")
	)
	(gr_poly
		(pts
			(xy 341.547958 -257.37947) (xy 341.500968 -257.22707) (xy 341.239348 -257.22707) (xy 341.192358 -257.37947)
			(xy 341.192358 -257.423666) (xy 341.547958 -257.423666)
		)
		(stroke
			(width 0)
			(type solid)
		)
		(fill yes)
		(layer "In11.Cu")
		(net "M_D_CPU0_SA_CA<1>")
	)
	(gr_poly
		(pts
			(xy 341.547958 -256.971038) (xy 341.547958 -256.926842) (xy 341.192358 -256.926842) (xy 341.192358 -256.971038)
			(xy 341.239348 -257.123438) (xy 341.500968 -257.123438)
		)
		(stroke
			(width 0)
			(type solid)
		)
		(fill yes)
		(layer "In11.Cu")
		(net "M_D_CPU0_SA_CA<2>")
	)
	(gr_poly
		(pts
			(xy 341.550498 -278.540718) (xy 341.503508 -278.388318) (xy 341.241888 -278.388318) (xy 341.194898 -278.540718)
			(xy 341.194898 -278.584914) (xy 341.550498 -278.584914)
		)
		(stroke
			(width 0)
			(type solid)
		)
		(fill yes)
		(layer "In11.Cu")
		(net "M_D_CPU0_SA_DQ<11>")
	)
	(gr_poly
		(pts
			(xy 341.550498 -278.132286) (xy 341.550498 -278.08809) (xy 341.194898 -278.08809) (xy 341.194898 -278.132286)
			(xy 341.241888 -278.284686) (xy 341.503508 -278.284686)
		)
		(stroke
			(width 0)
			(type solid)
		)
		(fill yes)
		(layer "In11.Cu")
		(net "M_D_CPU0_SA_DQS_DP<1>")
	)
	(gr_poly
		(pts
			(xy 341.550498 -276.912578) (xy 341.503508 -276.760178) (xy 341.241888 -276.760178) (xy 341.194898 -276.912578)
			(xy 341.194898 -276.957028) (xy 341.550498 -276.957028)
		)
		(stroke
			(width 0)
			(type solid)
		)
		(fill yes)
		(layer "In11.Cu")
		(net "M_D_CPU0_SA_DQS_DP<6>")
	)
	(gr_poly
		(pts
			(xy 341.550498 -276.5044) (xy 341.550498 -276.460204) (xy 341.194898 -276.460204) (xy 341.194898 -276.5044)
			(xy 341.241888 -276.6568) (xy 341.503508 -276.6568)
		)
		(stroke
			(width 0)
			(type solid)
		)
		(fill yes)
		(layer "In11.Cu")
		(net "M_D_CPU0_SA_DQ<12>")
	)
	(gr_poly
		(pts
			(xy 341.550498 -275.284946) (xy 341.503508 -275.132546) (xy 341.241888 -275.132546) (xy 341.194898 -275.284946)
			(xy 341.194898 -275.329142) (xy 341.550498 -275.329142)
		)
		(stroke
			(width 0)
			(type solid)
		)
		(fill yes)
		(layer "In11.Cu")
		(net "M_D_CPU0_SA_DQ<15>")
	)
	(gr_poly
		(pts
			(xy 341.550498 -274.876514) (xy 341.550498 -274.832318) (xy 341.194898 -274.832318) (xy 341.194898 -274.876514)
			(xy 341.241888 -275.028914) (xy 341.503508 -275.028914)
		)
		(stroke
			(width 0)
			(type solid)
		)
		(fill yes)
		(layer "In11.Cu")
		(net "M_D_CPU0_SA_DQ<16>")
	)
	(gr_poly
		(pts
			(xy 341.550498 -273.657314) (xy 341.503508 -273.504914) (xy 341.241888 -273.504914) (xy 341.194898 -273.657314)
			(xy 341.194898 -273.70151) (xy 341.550498 -273.70151)
		)
		(stroke
			(width 0)
			(type solid)
		)
		(fill yes)
		(layer "In11.Cu")
		(net "M_D_CPU0_SA_DQ<19>")
	)
	(gr_poly
		(pts
			(xy 341.550498 -273.248882) (xy 341.550498 -273.204686) (xy 341.194898 -273.204686) (xy 341.194898 -273.248882)
			(xy 341.241888 -273.401282) (xy 341.503508 -273.401282)
		)
		(stroke
			(width 0)
			(type solid)
		)
		(fill yes)
		(layer "In11.Cu")
		(net "M_D_CPU0_SA_DQS_DP<2>")
	)
	(gr_poly
		(pts
			(xy 341.550498 -272.029174) (xy 341.503508 -271.876774) (xy 341.241888 -271.876774) (xy 341.194898 -272.029174)
			(xy 341.194898 -272.073624) (xy 341.550498 -272.073624)
		)
		(stroke
			(width 0)
			(type solid)
		)
		(fill yes)
		(layer "In11.Cu")
		(net "M_D_CPU0_SA_DQS_DP<7>")
	)
	(gr_poly
		(pts
			(xy 341.550498 -271.62125) (xy 341.550498 -271.5768) (xy 341.194898 -271.5768) (xy 341.194898 -271.62125)
			(xy 341.241888 -271.77365) (xy 341.503508 -271.77365)
		)
		(stroke
			(width 0)
			(type solid)
		)
		(fill yes)
		(layer "In11.Cu")
		(net "M_D_CPU0_SA_DQ<20>")
	)
	(gr_poly
		(pts
			(xy 341.550498 -270.401542) (xy 341.503508 -270.249142) (xy 341.241888 -270.249142) (xy 341.194898 -270.401542)
			(xy 341.194898 -270.445992) (xy 341.550498 -270.445992)
		)
		(stroke
			(width 0)
			(type solid)
		)
		(fill yes)
		(layer "In11.Cu")
		(net "M_D_CPU0_SA_DQ<23>")
	)
	(gr_poly
		(pts
			(xy 341.550498 -269.993618) (xy 341.550498 -269.949168) (xy 341.194898 -269.949168) (xy 341.194898 -269.993618)
			(xy 341.241888 -270.146018) (xy 341.503508 -270.146018)
		)
		(stroke
			(width 0)
			(type solid)
		)
		(fill yes)
		(layer "In11.Cu")
		(net "M_D_CPU0_SA_DQ<24>")
	)
	(gr_poly
		(pts
			(xy 341.550498 -268.365478) (xy 341.550498 -268.321282) (xy 341.194898 -268.321282) (xy 341.194898 -268.365478)
			(xy 341.241888 -268.517878) (xy 341.503508 -268.517878)
		)
		(stroke
			(width 0)
			(type solid)
		)
		(fill yes)
		(layer "In11.Cu")
		(net "M_D_CPU0_SA_DQS_DP<3>")
	)
	(gr_poly
		(pts
			(xy 341.550498 -267.14577) (xy 341.503508 -266.99337) (xy 341.241888 -266.99337) (xy 341.194898 -267.14577)
			(xy 341.194898 -267.19022) (xy 341.550498 -267.19022)
		)
		(stroke
			(width 0)
			(type solid)
		)
		(fill yes)
		(layer "In11.Cu")
		(net "M_D_CPU0_SA_DQS_DP<8>")
	)
	(gr_poly
		(pts
			(xy 341.550498 -266.737846) (xy 341.550498 -266.69365) (xy 341.194898 -266.69365) (xy 341.194898 -266.737846)
			(xy 341.241888 -266.890246) (xy 341.503508 -266.890246)
		)
		(stroke
			(width 0)
			(type solid)
		)
		(fill yes)
		(layer "In11.Cu")
		(net "M_D_CPU0_SA_DQ<28>")
	)
	(gr_poly
		(pts
			(xy 341.550498 -265.518138) (xy 341.503508 -265.365738) (xy 341.241888 -265.365738) (xy 341.194898 -265.518138)
			(xy 341.194898 -265.562588) (xy 341.550498 -265.562588)
		)
		(stroke
			(width 0)
			(type solid)
		)
		(fill yes)
		(layer "In11.Cu")
		(net "M_D_CPU0_SA_DQ<31>")
	)
	(gr_poly
		(pts
			(xy 341.550498 -265.110214) (xy 341.550498 -265.065764) (xy 341.194898 -265.065764) (xy 341.194898 -265.110214)
			(xy 341.241888 -265.262614) (xy 341.503508 -265.262614)
		)
		(stroke
			(width 0)
			(type solid)
		)
		(fill yes)
		(layer "In11.Cu")
		(net "M_D_CPU0_SA_CB<0>")
	)
	(gr_poly
		(pts
			(xy 341.550498 -263.890506) (xy 341.503508 -263.738106) (xy 341.241888 -263.738106) (xy 341.194898 -263.890506)
			(xy 341.194898 -263.934956) (xy 341.550498 -263.934956)
		)
		(stroke
			(width 0)
			(type solid)
		)
		(fill yes)
		(layer "In11.Cu")
		(net "M_D_CPU0_SA_CB<3>")
	)
	(gr_poly
		(pts
			(xy 341.550498 -263.482582) (xy 341.550498 -263.438132) (xy 341.194898 -263.438132) (xy 341.194898 -263.482582)
			(xy 341.241888 -263.634982) (xy 341.503508 -263.634982)
		)
		(stroke
			(width 0)
			(type solid)
		)
		(fill yes)
		(layer "In11.Cu")
		(net "M_D_CPU0_SA_DQS_DP<4>")
	)
	(gr_poly
		(pts
			(xy 341.550498 -261.854442) (xy 341.550498 -261.810246) (xy 341.194898 -261.810246) (xy 341.194898 -261.854442)
			(xy 341.241888 -262.006842) (xy 341.503508 -262.006842)
		)
		(stroke
			(width 0)
			(type solid)
		)
		(fill yes)
		(layer "In11.Cu")
		(net "M_D_CPU0_SA_CB<4>")
	)
	(gr_poly
		(pts
			(xy 341.550498 -260.634734) (xy 341.503508 -260.482334) (xy 341.241888 -260.482334) (xy 341.194898 -260.634734)
			(xy 341.194898 -260.679184) (xy 341.550498 -260.679184)
		)
		(stroke
			(width 0)
			(type solid)
		)
		(fill yes)
		(layer "In11.Cu")
		(net "M_D_CPU0_SA_CB<7>")
	)
	(gr_poly
		(pts
			(xy 341.550498 -259.007102) (xy 341.503508 -258.854702) (xy 341.241888 -258.854702) (xy 341.194898 -259.007102)
			(xy 341.194898 -259.051552) (xy 341.550498 -259.051552)
		)
		(stroke
			(width 0)
			(type solid)
		)
		(fill yes)
		(layer "In11.Cu")
		(net "M_D_CPU0_SA_CS_N<0>")
	)
	(gr_poly
		(pts
			(xy 341.550498 -258.599178) (xy 341.550498 -258.554728) (xy 341.194898 -258.554728) (xy 341.194898 -258.599178)
			(xy 341.241888 -258.751578) (xy 341.503508 -258.751578)
		)
		(stroke
			(width 0)
			(type solid)
		)
		(fill yes)
		(layer "In11.Cu")
		(net "M_D_CPU0_SA_CS_N<3>")
	)
	(gr_poly
		(pts
			(xy 341.550498 -255.751838) (xy 341.503508 -255.599438) (xy 341.241888 -255.599438) (xy 341.194898 -255.751838)
			(xy 341.194898 -255.796034) (xy 341.550498 -255.796034)
		)
		(stroke
			(width 0)
			(type solid)
		)
		(fill yes)
		(layer "In11.Cu")
		(net "M_D_CPU0_SA_CA<5>")
	)
	(gr_poly
		(pts
			(xy 341.751412 -232.167176) (xy 341.789766 -232.145078) (xy 341.611966 -231.83723) (xy 341.573612 -231.859328)
			(xy 341.465154 -231.976168) (xy 341.595964 -232.202736)
		)
		(stroke
			(width 0)
			(type solid)
		)
		(fill yes)
		(layer "In11.Cu")
		(net "M_D_CPU0_SB_DQ<12>")
	)
	(gr_poly
		(pts
			(xy 341.758524 -233.807) (xy 341.796878 -233.784902) (xy 341.619078 -233.477054) (xy 341.580724 -233.499152)
			(xy 341.472266 -233.615992) (xy 341.603076 -233.84256)
		)
		(stroke
			(width 0)
			(type solid)
		)
		(fill yes)
		(layer "In11.Cu")
		(net "M_D_CPU0_SB_DQS_DN<6>")
	)
	(gr_poly
		(pts
			(xy 341.867236 -233.1847) (xy 341.975694 -233.06786) (xy 341.844884 -232.841292) (xy 341.689436 -232.876852)
			(xy 341.651082 -232.89895) (xy 341.828882 -233.206798)
		)
		(stroke
			(width 0)
			(type solid)
		)
		(fill yes)
		(layer "In11.Cu")
		(net "M_D_CPU0_SB_DQS_DP<6>")
	)
	(gr_poly
		(pts
			(xy 341.86749 -231.557576) (xy 341.975948 -231.440736) (xy 341.845138 -231.214168) (xy 341.68969 -231.249728)
			(xy 341.651336 -231.271826) (xy 341.829136 -231.579674)
		)
		(stroke
			(width 0)
			(type solid)
		)
		(fill yes)
		(layer "In11.Cu")
		(net "M_D_CPU0_SB_DQ<14>")
	)
	(gr_poly
		(pts
			(xy 341.893398 -249.416062) (xy 341.893398 -249.371612) (xy 341.537798 -249.371612) (xy 341.537798 -249.416062)
			(xy 341.584788 -249.568462) (xy 341.846408 -249.568462)
		)
		(stroke
			(width 0)
			(type solid)
		)
		(fill yes)
		(layer "In11.Cu")
		(net "M_D_CPU0_SB_CA<2>")
	)
	(gr_poly
		(pts
			(xy 341.893398 -248.196354) (xy 341.846408 -248.043954) (xy 341.584788 -248.043954) (xy 341.537798 -248.196354)
			(xy 341.537798 -248.24055) (xy 341.893398 -248.24055)
		)
		(stroke
			(width 0)
			(type solid)
		)
		(fill yes)
		(layer "In11.Cu")
		(net "M_D_CPU0_SB_CA<5>")
	)
	(gr_poly
		(pts
			(xy 341.893398 -247.787922) (xy 341.893398 -247.743726) (xy 341.537798 -247.743726) (xy 341.537798 -247.787922)
			(xy 341.584788 -247.940322) (xy 341.846408 -247.940322)
		)
		(stroke
			(width 0)
			(type solid)
		)
		(fill yes)
		(layer "In11.Cu")
		(net "M_D_CPU0_SB_PAR")
	)
	(gr_poly
		(pts
			(xy 341.893398 -244.940582) (xy 341.846408 -244.788182) (xy 341.584788 -244.788182) (xy 341.537798 -244.940582)
			(xy 341.537798 -244.985032) (xy 341.893398 -244.985032)
		)
		(stroke
			(width 0)
			(type solid)
		)
		(fill yes)
		(layer "In11.Cu")
		(net "M_D_CPU0_SB_DQS_DN<9>")
	)
	(gr_poly
		(pts
			(xy 341.893398 -244.532658) (xy 341.893398 -244.488208) (xy 341.537798 -244.488208) (xy 341.537798 -244.532658)
			(xy 341.584788 -244.685058) (xy 341.846408 -244.685058)
		)
		(stroke
			(width 0)
			(type solid)
		)
		(fill yes)
		(layer "In11.Cu")
		(net "M_D_CPU0_SB_DQS_DN<4>")
	)
	(gr_poly
		(pts
			(xy 341.893398 -243.31295) (xy 341.846408 -243.16055) (xy 341.584788 -243.16055) (xy 341.537798 -243.31295)
			(xy 341.537798 -243.3574) (xy 341.893398 -243.3574)
		)
		(stroke
			(width 0)
			(type solid)
		)
		(fill yes)
		(layer "In11.Cu")
		(net "M_D_CPU0_SB_CB<2>")
	)
	(gr_poly
		(pts
			(xy 341.893398 -242.905026) (xy 341.893398 -242.860576) (xy 341.537798 -242.860576) (xy 341.537798 -242.905026)
			(xy 341.584788 -243.057426) (xy 341.846408 -243.057426)
		)
		(stroke
			(width 0)
			(type solid)
		)
		(fill yes)
		(layer "In11.Cu")
		(net "M_D_CPU0_SB_CB<1>")
	)
	(gr_poly
		(pts
			(xy 341.893398 -240.057178) (xy 341.846408 -239.904778) (xy 341.584788 -239.904778) (xy 341.537798 -240.057178)
			(xy 341.537798 -240.101628) (xy 341.893398 -240.101628)
		)
		(stroke
			(width 0)
			(type solid)
		)
		(fill yes)
		(layer "In11.Cu")
		(net "M_D_CPU0_SB_DQS_DN<0>")
	)
	(gr_poly
		(pts
			(xy 341.893398 -239.649254) (xy 341.893398 -239.604804) (xy 341.537798 -239.604804) (xy 341.537798 -239.649254)
			(xy 341.584788 -239.801654) (xy 341.846408 -239.801654)
		)
		(stroke
			(width 0)
			(type solid)
		)
		(fill yes)
		(layer "In11.Cu")
		(net "M_D_CPU0_SB_DQS_DN<5>")
	)
	(gr_poly
		(pts
			(xy 341.893398 -238.429546) (xy 341.846408 -238.277146) (xy 341.584788 -238.277146) (xy 341.537798 -238.429546)
			(xy 341.537798 -238.473996) (xy 341.893398 -238.473996)
		)
		(stroke
			(width 0)
			(type solid)
		)
		(fill yes)
		(layer "In11.Cu")
		(net "M_D_CPU0_SB_DQ<6>")
	)
	(gr_poly
		(pts
			(xy 341.893398 -238.021622) (xy 341.893398 -237.977172) (xy 341.537798 -237.977172) (xy 341.537798 -238.021622)
			(xy 341.584788 -238.174022) (xy 341.846408 -238.174022)
		)
		(stroke
			(width 0)
			(type solid)
		)
		(fill yes)
		(layer "In11.Cu")
		(net "M_D_CPU0_SB_DQ<5>")
	)
	(gr_poly
		(pts
			(xy 341.893398 -235.174282) (xy 341.846408 -235.021882) (xy 341.584788 -235.021882) (xy 341.537798 -235.174282)
			(xy 341.537798 -235.218478) (xy 341.893398 -235.218478)
		)
		(stroke
			(width 0)
			(type solid)
		)
		(fill yes)
		(layer "In11.Cu")
		(net "M_D_CPU0_SB_DQS_DN<1>")
	)
	(gr_poly
		(pts
			(xy 341.893398 -230.290878) (xy 341.846408 -230.138478) (xy 341.584788 -230.138478) (xy 341.537798 -230.290878)
			(xy 341.537798 -230.335074) (xy 341.893398 -230.335074)
		)
		(stroke
			(width 0)
			(type solid)
		)
		(fill yes)
		(layer "In11.Cu")
		(net "M_D_CPU0_SB_DQ<15>")
	)
	(gr_poly
		(pts
			(xy 341.893398 -229.882446) (xy 341.893398 -229.83825) (xy 341.537798 -229.83825) (xy 341.537798 -229.882446)
			(xy 341.584788 -230.034846) (xy 341.846408 -230.034846)
		)
		(stroke
			(width 0)
			(type solid)
		)
		(fill yes)
		(layer "In11.Cu")
		(net "M_D_CPU0_SB_DQ<24>")
	)
	(gr_poly
		(pts
			(xy 341.893398 -228.663246) (xy 341.846408 -228.510846) (xy 341.584788 -228.510846) (xy 341.537798 -228.663246)
			(xy 341.537798 -228.707442) (xy 341.893398 -228.707442)
		)
		(stroke
			(width 0)
			(type solid)
		)
		(fill yes)
		(layer "In11.Cu")
		(net "M_D_CPU0_SB_DQ<27>")
	)
	(gr_poly
		(pts
			(xy 341.893398 -228.254814) (xy 341.893398 -228.210618) (xy 341.537798 -228.210618) (xy 341.537798 -228.254814)
			(xy 341.584788 -228.407214) (xy 341.846408 -228.407214)
		)
		(stroke
			(width 0)
			(type solid)
		)
		(fill yes)
		(layer "In11.Cu")
		(net "M_D_CPU0_SB_DQS_DP<3>")
	)
	(gr_poly
		(pts
			(xy 341.893398 -226.627182) (xy 341.893398 -226.582732) (xy 341.537798 -226.582732) (xy 341.537798 -226.627182)
			(xy 341.584788 -226.779582) (xy 341.846408 -226.779582)
		)
		(stroke
			(width 0)
			(type solid)
		)
		(fill yes)
		(layer "In11.Cu")
		(net "M_D_CPU0_SB_DQ<28>")
	)
	(gr_poly
		(pts
			(xy 341.893398 -225.407474) (xy 341.846408 -225.255074) (xy 341.584788 -225.255074) (xy 341.537798 -225.407474)
			(xy 341.537798 -225.45167) (xy 341.893398 -225.45167)
		)
		(stroke
			(width 0)
			(type solid)
		)
		(fill yes)
		(layer "In11.Cu")
		(net "M_D_CPU0_SB_DQ<31>")
	)
	(gr_poly
		(pts
			(xy 341.895938 -246.568722) (xy 341.848948 -246.416322) (xy 341.587328 -246.416322) (xy 341.540338 -246.568722)
			(xy 341.540338 -246.612918) (xy 341.895938 -246.612918)
		)
		(stroke
			(width 0)
			(type solid)
		)
		(fill yes)
		(layer "In11.Cu")
		(net "M_D_CPU0_SB_CB<6>")
	)
	(gr_poly
		(pts
			(xy 341.895938 -246.16029) (xy 341.895938 -246.116094) (xy 341.540338 -246.116094) (xy 341.540338 -246.16029)
			(xy 341.587328 -246.31269) (xy 341.848948 -246.31269)
		)
		(stroke
			(width 0)
			(type solid)
		)
		(fill yes)
		(layer "In11.Cu")
		(net "M_D_CPU0_SB_CB<5>")
	)
	(gr_poly
		(pts
			(xy 341.895938 -241.685318) (xy 341.848948 -241.532918) (xy 341.587328 -241.532918) (xy 341.540338 -241.685318)
			(xy 341.540338 -241.729514) (xy 341.895938 -241.729514)
		)
		(stroke
			(width 0)
			(type solid)
		)
		(fill yes)
		(layer "In11.Cu")
		(net "M_D_CPU0_SB_DQ<2>")
	)
	(gr_poly
		(pts
			(xy 341.895938 -241.276886) (xy 341.895938 -241.23269) (xy 341.540338 -241.23269) (xy 341.540338 -241.276886)
			(xy 341.587328 -241.429286) (xy 341.848948 -241.429286)
		)
		(stroke
			(width 0)
			(type solid)
		)
		(fill yes)
		(layer "In11.Cu")
		(net "M_D_CPU0_SB_DQ<1>")
	)
	(gr_poly
		(pts
			(xy 341.895938 -236.801914) (xy 341.848948 -236.649514) (xy 341.587328 -236.649514) (xy 341.540338 -236.801914)
			(xy 341.540338 -236.84611) (xy 341.895938 -236.84611)
		)
		(stroke
			(width 0)
			(type solid)
		)
		(fill yes)
		(layer "In11.Cu")
		(net "M_D_CPU0_SB_DQ<10>")
	)
	(gr_poly
		(pts
			(xy 341.895938 -236.39399) (xy 341.895938 -236.34954) (xy 341.540338 -236.34954) (xy 341.540338 -236.39399)
			(xy 341.587328 -236.54639) (xy 341.848948 -236.54639)
		)
		(stroke
			(width 0)
			(type solid)
		)
		(fill yes)
		(layer "In11.Cu")
		(net "M_D_CPU0_SB_DQ<9>")
	)
	(gr_poly
		(pts
			(xy 341.902288 -227.035614) (xy 341.855298 -226.883214) (xy 341.593678 -226.883214) (xy 341.546688 -227.035614)
			(xy 341.546688 -227.07981) (xy 341.902288 -227.07981)
		)
		(stroke
			(width 0)
			(type solid)
		)
		(fill yes)
		(layer "In11.Cu")
		(net "M_D_CPU0_SB_DQS_DP<8>")
	)
	(gr_poly
		(pts
			(xy 342.00338 -277.726394) (xy 341.95639 -277.573994) (xy 341.69477 -277.573994) (xy 341.64778 -277.726394)
			(xy 341.64778 -277.770844) (xy 342.00338 -277.770844)
		)
		(stroke
			(width 0)
			(type solid)
		)
		(fill yes)
		(layer "In11.Cu")
		(net "M_D_CPU0_SA_DQS_DN<1>")
	)
	(gr_poly
		(pts
			(xy 342.00338 -277.318216) (xy 342.00338 -277.27402) (xy 341.64778 -277.27402) (xy 341.64778 -277.318216)
			(xy 341.69477 -277.470616) (xy 341.95639 -277.470616)
		)
		(stroke
			(width 0)
			(type solid)
		)
		(fill yes)
		(layer "In11.Cu")
		(net "M_D_CPU0_SA_DQS_DN<6>")
	)
	(gr_poly
		(pts
			(xy 342.00338 -274.47113) (xy 341.95639 -274.31873) (xy 341.69477 -274.31873) (xy 341.64778 -274.47113)
			(xy 341.64778 -274.515326) (xy 342.00338 -274.515326)
		)
		(stroke
			(width 0)
			(type solid)
		)
		(fill yes)
		(layer "In11.Cu")
		(net "M_D_CPU0_SA_DQ<18>")
	)
	(gr_poly
		(pts
			(xy 342.00338 -274.062698) (xy 342.00338 -274.018502) (xy 341.64778 -274.018502) (xy 341.64778 -274.062698)
			(xy 341.69477 -274.215098) (xy 341.95639 -274.215098)
		)
		(stroke
			(width 0)
			(type solid)
		)
		(fill yes)
		(layer "In11.Cu")
		(net "M_D_CPU0_SA_DQ<17>")
	)
	(gr_poly
		(pts
			(xy 342.00338 -272.843498) (xy 341.95639 -272.691098) (xy 341.69477 -272.691098) (xy 341.64778 -272.843498)
			(xy 341.64778 -272.887694) (xy 342.00338 -272.887694)
		)
		(stroke
			(width 0)
			(type solid)
		)
		(fill yes)
		(layer "In11.Cu")
		(net "M_D_CPU0_SA_DQS_DN<2>")
	)
	(gr_poly
		(pts
			(xy 342.00338 -272.435066) (xy 342.00338 -272.39087) (xy 341.64778 -272.39087) (xy 341.64778 -272.435066)
			(xy 341.69477 -272.587466) (xy 341.95639 -272.587466)
		)
		(stroke
			(width 0)
			(type solid)
		)
		(fill yes)
		(layer "In11.Cu")
		(net "M_D_CPU0_SA_DQS_DN<7>")
	)
	(gr_poly
		(pts
			(xy 342.00338 -269.587726) (xy 341.95639 -269.435326) (xy 341.69477 -269.435326) (xy 341.64778 -269.587726)
			(xy 341.64778 -269.631922) (xy 342.00338 -269.631922)
		)
		(stroke
			(width 0)
			(type solid)
		)
		(fill yes)
		(layer "In11.Cu")
		(net "M_D_CPU0_SA_DQ<26>")
	)
	(gr_poly
		(pts
			(xy 342.00338 -267.960094) (xy 341.95639 -267.807694) (xy 341.69477 -267.807694) (xy 341.64778 -267.960094)
			(xy 341.64778 -268.00429) (xy 342.00338 -268.00429)
		)
		(stroke
			(width 0)
			(type solid)
		)
		(fill yes)
		(layer "In11.Cu")
		(net "M_D_CPU0_SA_DQS_DN<3>")
	)
	(gr_poly
		(pts
			(xy 342.00338 -267.551662) (xy 342.00338 -267.507466) (xy 341.64778 -267.507466) (xy 341.64778 -267.551662)
			(xy 341.69477 -267.704062) (xy 341.95639 -267.704062)
		)
		(stroke
			(width 0)
			(type solid)
		)
		(fill yes)
		(layer "In11.Cu")
		(net "M_D_CPU0_SA_DQS_DN<8>")
	)
	(gr_poly
		(pts
			(xy 342.00338 -266.331954) (xy 341.95639 -266.179554) (xy 341.69477 -266.179554) (xy 341.64778 -266.331954)
			(xy 341.64778 -266.376404) (xy 342.00338 -266.376404)
		)
		(stroke
			(width 0)
			(type solid)
		)
		(fill yes)
		(layer "In11.Cu")
		(net "M_D_CPU0_SA_DQ<30>")
	)
	(gr_poly
		(pts
			(xy 342.00338 -265.92403) (xy 342.00338 -265.87958) (xy 341.64778 -265.87958) (xy 341.64778 -265.92403)
			(xy 341.69477 -266.07643) (xy 341.95639 -266.07643)
		)
		(stroke
			(width 0)
			(type solid)
		)
		(fill yes)
		(layer "In11.Cu")
		(net "M_D_CPU0_SA_DQ<29>")
	)
	(gr_poly
		(pts
			(xy 342.00338 -264.704322) (xy 341.95639 -264.551922) (xy 341.69477 -264.551922) (xy 341.64778 -264.704322)
			(xy 341.64778 -264.748772) (xy 342.00338 -264.748772)
		)
		(stroke
			(width 0)
			(type solid)
		)
		(fill yes)
		(layer "In11.Cu")
		(net "M_D_CPU0_SA_CB<2>")
	)
	(gr_poly
		(pts
			(xy 342.00338 -264.296398) (xy 342.00338 -264.251948) (xy 341.64778 -264.251948) (xy 341.64778 -264.296398)
			(xy 341.69477 -264.448798) (xy 341.95639 -264.448798)
		)
		(stroke
			(width 0)
			(type solid)
		)
		(fill yes)
		(layer "In11.Cu")
		(net "M_D_CPU0_SA_CB<1>")
	)
	(gr_poly
		(pts
			(xy 342.00338 -263.07669) (xy 341.95639 -262.92429) (xy 341.69477 -262.92429) (xy 341.64778 -263.07669)
			(xy 341.64778 -263.120886) (xy 342.00338 -263.120886)
		)
		(stroke
			(width 0)
			(type solid)
		)
		(fill yes)
		(layer "In11.Cu")
		(net "M_D_CPU0_SA_DQS_DN<4>")
	)
	(gr_poly
		(pts
			(xy 342.00338 -261.449058) (xy 341.95639 -261.296658) (xy 341.69477 -261.296658) (xy 341.64778 -261.449058)
			(xy 341.64778 -261.493254) (xy 342.00338 -261.493254)
		)
		(stroke
			(width 0)
			(type solid)
		)
		(fill yes)
		(layer "In11.Cu")
		(net "M_D_CPU0_SA_CB<6>")
	)
	(gr_poly
		(pts
			(xy 342.00338 -261.040626) (xy 342.00338 -260.99643) (xy 341.64778 -260.99643) (xy 341.64778 -261.040626)
			(xy 341.69477 -261.193026) (xy 341.95639 -261.193026)
		)
		(stroke
			(width 0)
			(type solid)
		)
		(fill yes)
		(layer "In11.Cu")
		(net "M_D_CPU0_SA_CB<5>")
	)
	(gr_poly
		(pts
			(xy 342.00338 -259.412994) (xy 342.00338 -259.368544) (xy 341.64778 -259.368544) (xy 341.64778 -259.412994)
			(xy 341.69477 -259.565394) (xy 341.95639 -259.565394)
		)
		(stroke
			(width 0)
			(type solid)
		)
		(fill yes)
		(layer "In11.Cu")
		(net "M_D_CPU0_SA_CS_N<2>")
	)
	(gr_poly
		(pts
			(xy 342.00338 -258.193286) (xy 341.95639 -258.040886) (xy 341.69477 -258.040886) (xy 341.64778 -258.193286)
			(xy 341.64778 -258.237482) (xy 342.00338 -258.237482)
		)
		(stroke
			(width 0)
			(type solid)
		)
		(fill yes)
		(layer "In11.Cu")
		(net "M_D_CPU0_SA_CS_N<1>")
	)
	(gr_poly
		(pts
			(xy 342.00338 -257.784854) (xy 342.00338 -257.740658) (xy 341.64778 -257.740658) (xy 341.64778 -257.784854)
			(xy 341.69477 -257.937254) (xy 341.95639 -257.937254)
		)
		(stroke
			(width 0)
			(type solid)
		)
		(fill yes)
		(layer "In11.Cu")
		(net "M_D_CPU0_SA_CA<0>")
	)
	(gr_poly
		(pts
			(xy 342.00592 -276.098762) (xy 341.95893 -275.946362) (xy 341.69731 -275.946362) (xy 341.65032 -276.098762)
			(xy 341.65032 -276.143212) (xy 342.00592 -276.143212)
		)
		(stroke
			(width 0)
			(type solid)
		)
		(fill yes)
		(layer "In11.Cu")
		(net "M_D_CPU0_SA_DQ<14>")
	)
	(gr_poly
		(pts
			(xy 342.00592 -275.690584) (xy 342.00592 -275.646388) (xy 341.65032 -275.646388) (xy 341.65032 -275.690584)
			(xy 341.69731 -275.842984) (xy 341.95893 -275.842984)
		)
		(stroke
			(width 0)
			(type solid)
		)
		(fill yes)
		(layer "In11.Cu")
		(net "M_D_CPU0_SA_DQ<13>")
	)
	(gr_poly
		(pts
			(xy 342.00592 -271.215358) (xy 341.95893 -271.062958) (xy 341.69731 -271.062958) (xy 341.65032 -271.215358)
			(xy 341.65032 -271.259808) (xy 342.00592 -271.259808)
		)
		(stroke
			(width 0)
			(type solid)
		)
		(fill yes)
		(layer "In11.Cu")
		(net "M_D_CPU0_SA_DQ<22>")
	)
	(gr_poly
		(pts
			(xy 342.00592 -270.807434) (xy 342.00592 -270.762984) (xy 341.65032 -270.762984) (xy 341.65032 -270.807434)
			(xy 341.69731 -270.959834) (xy 341.95893 -270.959834)
		)
		(stroke
			(width 0)
			(type solid)
		)
		(fill yes)
		(layer "In11.Cu")
		(net "M_D_CPU0_SA_DQ<21>")
	)
	(gr_poly
		(pts
			(xy 342.00592 -256.565654) (xy 341.95893 -256.413254) (xy 341.69731 -256.413254) (xy 341.65032 -256.565654)
			(xy 341.65032 -256.60985) (xy 342.00592 -256.60985)
		)
		(stroke
			(width 0)
			(type solid)
		)
		(fill yes)
		(layer "In11.Cu")
		(net "M_D_CPU0_SA_CA<3>")
	)
	(gr_poly
		(pts
			(xy 342.00592 -256.157222) (xy 342.00592 -256.113026) (xy 341.65032 -256.113026) (xy 341.65032 -256.157222)
			(xy 341.69731 -256.309622) (xy 341.95893 -256.309622)
		)
		(stroke
			(width 0)
			(type solid)
		)
		(fill yes)
		(layer "In11.Cu")
		(net "M_D_CPU0_SA_CA<4>")
	)
	(gr_poly
		(pts
			(xy 342.011762 -278.945848) (xy 342.011762 -278.901652) (xy 341.656162 -278.901652) (xy 341.656162 -278.945848)
			(xy 341.703152 -279.098248) (xy 341.964772 -279.098248)
		)
		(stroke
			(width 0)
			(type solid)
		)
		(fill yes)
		(layer "In11.Cu")
		(net "M_D_CPU0_SA_DQ<9>")
	)
	(gr_poly
		(pts
			(xy 342.015318 -269.179294) (xy 342.015318 -269.134844) (xy 341.659718 -269.134844) (xy 341.659718 -269.179294)
			(xy 341.706708 -269.331694) (xy 341.968328 -269.331694)
		)
		(stroke
			(width 0)
			(type solid)
		)
		(fill yes)
		(layer "In11.Cu")
		(net "M_D_CPU0_SA_DQ<25>")
	)
	(gr_poly
		(pts
			(xy 342.015318 -262.668258) (xy 342.015318 -262.623808) (xy 341.659718 -262.623808) (xy 341.659718 -262.668258)
			(xy 341.706708 -262.820658) (xy 341.968328 -262.820658)
		)
		(stroke
			(width 0)
			(type solid)
		)
		(fill yes)
		(layer "In11.Cu")
		(net "M_D_CPU0_SA_DQS_DN<9>")
	)
	(gr_poly
		(pts
			(xy 342.017858 -279.354534) (xy 341.970868 -279.202134) (xy 341.709248 -279.202134) (xy 341.662258 -279.354534)
			(xy 341.662258 -279.39873) (xy 342.017858 -279.39873)
		)
		(stroke
			(width 0)
			(type solid)
		)
		(fill yes)
		(layer "In11.Cu")
		(net "M_D_CPU0_SA_DQ<10>")
	)
	(gr_poly
		(pts
			(xy 342.227408 -234.619038) (xy 342.265762 -234.59694) (xy 342.087962 -234.289092) (xy 342.049608 -234.31119)
			(xy 341.94115 -234.42803) (xy 342.07196 -234.654598)
		)
		(stroke
			(width 0)
			(type solid)
		)
		(fill yes)
		(layer "In11.Cu")
		(net "M_D_CPU0_SB_DQS_DN<6>")
	)
	(gr_poly
		(pts
			(xy 342.228678 -232.993692) (xy 342.267032 -232.971594) (xy 342.089232 -232.663746) (xy 342.050878 -232.685844)
			(xy 341.94242 -232.802684) (xy 342.07323 -233.029252)
		)
		(stroke
			(width 0)
			(type solid)
		)
		(fill yes)
		(layer "In11.Cu")
		(net "M_D_CPU0_SB_DQ<12>")
	)
	(gr_poly
		(pts
			(xy 342.338406 -232.373424) (xy 342.446864 -232.256584) (xy 342.316054 -232.030016) (xy 342.160606 -232.065576)
			(xy 342.122252 -232.087674) (xy 342.300052 -232.395522)
		)
		(stroke
			(width 0)
			(type solid)
		)
		(fill yes)
		(layer "In11.Cu")
		(net "M_D_CPU0_SB_DQ<14>")
	)
	(gr_poly
		(pts
			(xy 342.340946 -234.00512) (xy 342.449404 -233.88828) (xy 342.318594 -233.661712) (xy 342.163146 -233.697272)
			(xy 342.124792 -233.71937) (xy 342.302592 -234.027218)
		)
		(stroke
			(width 0)
			(type solid)
		)
		(fill yes)
		(layer "In11.Cu")
		(net "M_D_CPU0_SB_DQS_DP<6>")
	)
	(gr_poly
		(pts
			(xy 342.371934 -246.974106) (xy 342.371934 -246.929656) (xy 342.016334 -246.929656) (xy 342.016334 -246.974106)
			(xy 342.063324 -247.126506) (xy 342.324944 -247.126506)
		)
		(stroke
			(width 0)
			(type solid)
		)
		(fill yes)
		(layer "In11.Cu")
		(net "M_D_CPU0_SB_CB<4>")
	)
	(gr_poly
		(pts
			(xy 342.371934 -245.754906) (xy 342.324944 -245.602506) (xy 342.063324 -245.602506) (xy 342.016334 -245.754906)
			(xy 342.016334 -245.799356) (xy 342.371934 -245.799356)
		)
		(stroke
			(width 0)
			(type solid)
		)
		(fill yes)
		(layer "In11.Cu")
		(net "M_D_CPU0_SB_CB<7>")
	)
	(gr_poly
		(pts
			(xy 342.371934 -242.090702) (xy 342.371934 -242.046252) (xy 342.016334 -242.046252) (xy 342.016334 -242.090702)
			(xy 342.063324 -242.243102) (xy 342.324944 -242.243102)
		)
		(stroke
			(width 0)
			(type solid)
		)
		(fill yes)
		(layer "In11.Cu")
		(net "M_D_CPU0_SB_DQ<0>")
	)
	(gr_poly
		(pts
			(xy 342.371934 -240.871502) (xy 342.324944 -240.719102) (xy 342.063324 -240.719102) (xy 342.016334 -240.871502)
			(xy 342.016334 -240.915952) (xy 342.371934 -240.915952)
		)
		(stroke
			(width 0)
			(type solid)
		)
		(fill yes)
		(layer "In11.Cu")
		(net "M_D_CPU0_SB_DQ<3>")
	)
	(gr_poly
		(pts
			(xy 342.371934 -237.207298) (xy 342.371934 -237.163102) (xy 342.016334 -237.163102) (xy 342.016334 -237.207298)
			(xy 342.063324 -237.359698) (xy 342.324944 -237.359698)
		)
		(stroke
			(width 0)
			(type solid)
		)
		(fill yes)
		(layer "In11.Cu")
		(net "M_D_CPU0_SB_DQ<8>")
	)
	(gr_poly
		(pts
			(xy 342.371934 -235.988098) (xy 342.324944 -235.835698) (xy 342.063324 -235.835698) (xy 342.016334 -235.988098)
			(xy 342.016334 -236.032548) (xy 342.371934 -236.032548)
		)
		(stroke
			(width 0)
			(type solid)
		)
		(fill yes)
		(layer "In11.Cu")
		(net "M_D_CPU0_SB_DQ<11>")
	)
	(gr_poly
		(pts
			(xy 342.377776 -249.010678) (xy 342.330786 -248.858278) (xy 342.069166 -248.858278) (xy 342.022176 -249.010678)
			(xy 342.022176 -249.054874) (xy 342.377776 -249.054874)
		)
		(stroke
			(width 0)
			(type solid)
		)
		(fill yes)
		(layer "In11.Cu")
		(net "M_D_CPU0_SB_CA<3>")
	)
	(gr_poly
		(pts
			(xy 342.377776 -248.601738) (xy 342.377776 -248.557542) (xy 342.022176 -248.557542) (xy 342.022176 -248.601738)
			(xy 342.069166 -248.754138) (xy 342.330786 -248.754138)
		)
		(stroke
			(width 0)
			(type solid)
		)
		(fill yes)
		(layer "In11.Cu")
		(net "M_D_CPU0_SB_CA<4>")
	)
	(gr_poly
		(pts
			(xy 342.377776 -244.127274) (xy 342.330786 -243.974874) (xy 342.069166 -243.974874) (xy 342.022176 -244.127274)
			(xy 342.022176 -244.17147) (xy 342.377776 -244.17147)
		)
		(stroke
			(width 0)
			(type solid)
		)
		(fill yes)
		(layer "In11.Cu")
		(net "M_D_CPU0_SB_DQS_DP<4>")
	)
	(gr_poly
		(pts
			(xy 342.377776 -243.718334) (xy 342.377776 -243.674138) (xy 342.022176 -243.674138) (xy 342.022176 -243.718334)
			(xy 342.069166 -243.870734) (xy 342.330786 -243.870734)
		)
		(stroke
			(width 0)
			(type solid)
		)
		(fill yes)
		(layer "In11.Cu")
		(net "M_D_CPU0_SB_CB<0>")
	)
	(gr_poly
		(pts
			(xy 342.377776 -239.24387) (xy 342.330786 -239.09147) (xy 342.069166 -239.09147) (xy 342.022176 -239.24387)
			(xy 342.022176 -239.288066) (xy 342.377776 -239.288066)
		)
		(stroke
			(width 0)
			(type solid)
		)
		(fill yes)
		(layer "In11.Cu")
		(net "M_D_CPU0_SB_DQS_DP<5>")
	)
	(gr_poly
		(pts
			(xy 342.377776 -238.83493) (xy 342.377776 -238.790734) (xy 342.022176 -238.790734) (xy 342.022176 -238.83493)
			(xy 342.069166 -238.98733) (xy 342.330786 -238.98733)
		)
		(stroke
			(width 0)
			(type solid)
		)
		(fill yes)
		(layer "In11.Cu")
		(net "M_D_CPU0_SB_DQ<4>")
	)
	(gr_poly
		(pts
			(xy 342.377776 -229.477062) (xy 342.330786 -229.324662) (xy 342.069166 -229.324662) (xy 342.022176 -229.477062)
			(xy 342.022176 -229.521512) (xy 342.377776 -229.521512)
		)
		(stroke
			(width 0)
			(type solid)
		)
		(fill yes)
		(layer "In11.Cu")
		(net "M_D_CPU0_SB_DQ<26>")
	)
	(gr_poly
		(pts
			(xy 342.377776 -229.06863) (xy 342.377776 -229.02418) (xy 342.022176 -229.02418) (xy 342.022176 -229.06863)
			(xy 342.069166 -229.22103) (xy 342.330786 -229.22103)
		)
		(stroke
			(width 0)
			(type solid)
		)
		(fill yes)
		(layer "In11.Cu")
		(net "M_D_CPU0_SB_DQ<25>")
	)
	(gr_poly
		(pts
			(xy 342.380316 -245.346474) (xy 342.380316 -245.302278) (xy 342.024716 -245.302278) (xy 342.024716 -245.346474)
			(xy 342.071706 -245.498874) (xy 342.333326 -245.498874)
		)
		(stroke
			(width 0)
			(type solid)
		)
		(fill yes)
		(layer "In11.Cu")
		(net "M_D_CPU0_SB_DQS_DP<9>")
	)
	(gr_poly
		(pts
			(xy 342.380316 -242.499134) (xy 342.333326 -242.346734) (xy 342.071706 -242.346734) (xy 342.024716 -242.499134)
			(xy 342.024716 -242.54333) (xy 342.380316 -242.54333)
		)
		(stroke
			(width 0)
			(type solid)
		)
		(fill yes)
		(layer "In11.Cu")
		(net "M_D_CPU0_SB_CB<3>")
	)
	(gr_poly
		(pts
			(xy 342.380316 -240.46307) (xy 342.380316 -240.418874) (xy 342.024716 -240.418874) (xy 342.024716 -240.46307)
			(xy 342.071706 -240.61547) (xy 342.333326 -240.61547)
		)
		(stroke
			(width 0)
			(type solid)
		)
		(fill yes)
		(layer "In11.Cu")
		(net "M_D_CPU0_SB_DQS_DP<0>")
	)
	(gr_poly
		(pts
			(xy 342.380316 -237.61573) (xy 342.333326 -237.46333) (xy 342.071706 -237.46333) (xy 342.024716 -237.61573)
			(xy 342.024716 -237.66018) (xy 342.380316 -237.66018)
		)
		(stroke
			(width 0)
			(type solid)
		)
		(fill yes)
		(layer "In11.Cu")
		(net "M_D_CPU0_SB_DQ<7>")
	)
	(gr_poly
		(pts
			(xy 342.380316 -235.579666) (xy 342.380316 -235.53547) (xy 342.024716 -235.53547) (xy 342.024716 -235.579666)
			(xy 342.071706 -235.732066) (xy 342.333326 -235.732066)
		)
		(stroke
			(width 0)
			(type solid)
		)
		(fill yes)
		(layer "In11.Cu")
		(net "M_D_CPU0_SB_DQS_DP<1>")
	)
	(gr_poly
		(pts
			(xy 342.380316 -230.696262) (xy 342.380316 -230.652066) (xy 342.024716 -230.652066) (xy 342.024716 -230.696262)
			(xy 342.071706 -230.848662) (xy 342.333326 -230.848662)
		)
		(stroke
			(width 0)
			(type solid)
		)
		(fill yes)
		(layer "In11.Cu")
		(net "M_D_CPU0_SB_DQ<13>")
	)
	(gr_poly
		(pts
			(xy 342.380316 -227.848922) (xy 342.333326 -227.696522) (xy 342.071706 -227.696522) (xy 342.024716 -227.848922)
			(xy 342.024716 -227.893372) (xy 342.380316 -227.893372)
		)
		(stroke
			(width 0)
			(type solid)
		)
		(fill yes)
		(layer "In11.Cu")
		(net "M_D_CPU0_SB_DQS_DN<3>")
	)
	(gr_poly
		(pts
			(xy 342.380316 -227.440998) (xy 342.380316 -227.396548) (xy 342.024716 -227.396548) (xy 342.024716 -227.440998)
			(xy 342.071706 -227.593398) (xy 342.333326 -227.593398)
		)
		(stroke
			(width 0)
			(type solid)
		)
		(fill yes)
		(layer "In11.Cu")
		(net "M_D_CPU0_SB_DQS_DN<8>")
	)
	(gr_poly
		(pts
			(xy 342.380316 -226.22129) (xy 342.333326 -226.06889) (xy 342.071706 -226.06889) (xy 342.024716 -226.22129)
			(xy 342.024716 -226.26574) (xy 342.380316 -226.26574)
		)
		(stroke
			(width 0)
			(type solid)
		)
		(fill yes)
		(layer "In11.Cu")
		(net "M_D_CPU0_SB_DQ<30>")
	)
	(gr_poly
		(pts
			(xy 342.380316 -225.813366) (xy 342.380316 -225.768916) (xy 342.024716 -225.768916) (xy 342.024716 -225.813366)
			(xy 342.071706 -225.965766) (xy 342.333326 -225.965766)
		)
		(stroke
			(width 0)
			(type solid)
		)
		(fill yes)
		(layer "In11.Cu")
		(net "M_D_CPU0_SB_DQ<29>")
	)
	(gr_poly
		(pts
			(xy 342.47328 -279.759918) (xy 342.47328 -279.715722) (xy 342.11768 -279.715722) (xy 342.11768 -279.759918)
			(xy 342.16467 -279.912318) (xy 342.42629 -279.912318)
		)
		(stroke
			(width 0)
			(type solid)
		)
		(fill yes)
		(layer "In11.Cu")
		(net "M_D_CPU0_SA_DQ<8>")
	)
	(gr_poly
		(pts
			(xy 342.47836 -268.77391) (xy 342.43137 -268.62151) (xy 342.16975 -268.62151) (xy 342.12276 -268.77391)
			(xy 342.12276 -268.81836) (xy 342.47836 -268.81836)
		)
		(stroke
			(width 0)
			(type solid)
		)
		(fill yes)
		(layer "In11.Cu")
		(net "M_D_CPU0_SA_DQ<27>")
	)
	(gr_poly
		(pts
			(xy 342.47836 -262.262874) (xy 342.43137 -262.110474) (xy 342.16975 -262.110474) (xy 342.12276 -262.262874)
			(xy 342.12276 -262.307324) (xy 342.47836 -262.307324)
		)
		(stroke
			(width 0)
			(type solid)
		)
		(fill yes)
		(layer "In11.Cu")
		(net "M_D_CPU0_SA_DQS_DP<9>")
	)
	(gr_poly
		(pts
			(xy 342.481662 -260.635242) (xy 342.434672 -260.482842) (xy 342.173052 -260.482842) (xy 342.126062 -260.635242)
			(xy 342.126062 -260.679438) (xy 342.481662 -260.679438)
		)
		(stroke
			(width 0)
			(type solid)
		)
		(fill yes)
		(layer "In11.Cu")
		(net "M_D_CPU0_SA_CB<7>")
	)
	(gr_poly
		(pts
			(xy 342.481916 -278.540718) (xy 342.434926 -278.388318) (xy 342.173306 -278.388318) (xy 342.126316 -278.540718)
			(xy 342.126316 -278.585168) (xy 342.481916 -278.585168)
		)
		(stroke
			(width 0)
			(type solid)
		)
		(fill yes)
		(layer "In11.Cu")
		(net "M_D_CPU0_SA_DQ<11>")
	)
	(gr_poly
		(pts
			(xy 342.481916 -276.504146) (xy 342.481916 -276.45995) (xy 342.126316 -276.45995) (xy 342.126316 -276.504146)
			(xy 342.173306 -276.656546) (xy 342.434926 -276.656546)
		)
		(stroke
			(width 0)
			(type solid)
		)
		(fill yes)
		(layer "In11.Cu")
		(net "M_D_CPU0_SA_DQ<12>")
	)
	(gr_poly
		(pts
			(xy 342.481916 -275.284946) (xy 342.434926 -275.132546) (xy 342.173306 -275.132546) (xy 342.126316 -275.284946)
			(xy 342.126316 -275.329396) (xy 342.481916 -275.329396)
		)
		(stroke
			(width 0)
			(type solid)
		)
		(fill yes)
		(layer "In11.Cu")
		(net "M_D_CPU0_SA_DQ<15>")
	)
	(gr_poly
		(pts
			(xy 342.481916 -271.620742) (xy 342.481916 -271.576546) (xy 342.126316 -271.576546) (xy 342.126316 -271.620742)
			(xy 342.173306 -271.773142) (xy 342.434926 -271.773142)
		)
		(stroke
			(width 0)
			(type solid)
		)
		(fill yes)
		(layer "In11.Cu")
		(net "M_D_CPU0_SA_DQ<20>")
	)
	(gr_poly
		(pts
			(xy 342.481916 -270.40205) (xy 342.434926 -270.24965) (xy 342.173306 -270.24965) (xy 342.126316 -270.40205)
			(xy 342.126316 -270.446246) (xy 342.481916 -270.446246)
		)
		(stroke
			(width 0)
			(type solid)
		)
		(fill yes)
		(layer "In11.Cu")
		(net "M_D_CPU0_SA_DQ<23>")
	)
	(gr_poly
		(pts
			(xy 342.481916 -256.971038) (xy 342.481916 -256.926588) (xy 342.126316 -256.926588) (xy 342.126316 -256.971038)
			(xy 342.173306 -257.123438) (xy 342.434926 -257.123438)
		)
		(stroke
			(width 0)
			(type solid)
		)
		(fill yes)
		(layer "In11.Cu")
		(net "M_D_CPU0_SA_CA<2>")
	)
	(gr_poly
		(pts
			(xy 342.481916 -255.751838) (xy 342.434926 -255.599438) (xy 342.173306 -255.599438) (xy 342.126316 -255.751838)
			(xy 342.126316 -255.796288) (xy 342.481916 -255.796288)
		)
		(stroke
			(width 0)
			(type solid)
		)
		(fill yes)
		(layer "In11.Cu")
		(net "M_D_CPU0_SA_CA<5>")
	)
	(gr_poly
		(pts
			(xy 342.487758 -273.657314) (xy 342.440768 -273.504914) (xy 342.179148 -273.504914) (xy 342.132158 -273.657314)
			(xy 342.132158 -273.701764) (xy 342.487758 -273.701764)
		)
		(stroke
			(width 0)
			(type solid)
		)
		(fill yes)
		(layer "In11.Cu")
		(net "M_D_CPU0_SA_DQ<19>")
	)
	(gr_poly
		(pts
			(xy 342.487758 -273.248882) (xy 342.487758 -273.204432) (xy 342.132158 -273.204432) (xy 342.132158 -273.248882)
			(xy 342.179148 -273.401282) (xy 342.440768 -273.401282)
		)
		(stroke
			(width 0)
			(type solid)
		)
		(fill yes)
		(layer "In11.Cu")
		(net "M_D_CPU0_SA_DQS_DP<2>")
	)
	(gr_poly
		(pts
			(xy 342.487758 -268.365478) (xy 342.487758 -268.321028) (xy 342.132158 -268.321028) (xy 342.132158 -268.365478)
			(xy 342.179148 -268.517878) (xy 342.440768 -268.517878)
		)
		(stroke
			(width 0)
			(type solid)
		)
		(fill yes)
		(layer "In11.Cu")
		(net "M_D_CPU0_SA_DQS_DP<3>")
	)
	(gr_poly
		(pts
			(xy 342.487758 -263.891014) (xy 342.440768 -263.738614) (xy 342.179148 -263.738614) (xy 342.132158 -263.891014)
			(xy 342.132158 -263.93521) (xy 342.487758 -263.93521)
		)
		(stroke
			(width 0)
			(type solid)
		)
		(fill yes)
		(layer "In11.Cu")
		(net "M_D_CPU0_SA_CB<3>")
	)
	(gr_poly
		(pts
			(xy 342.487758 -263.482074) (xy 342.487758 -263.437878) (xy 342.132158 -263.437878) (xy 342.132158 -263.482074)
			(xy 342.179148 -263.634474) (xy 342.440768 -263.634474)
		)
		(stroke
			(width 0)
			(type solid)
		)
		(fill yes)
		(layer "In11.Cu")
		(net "M_D_CPU0_SA_DQS_DP<4>")
	)
	(gr_poly
		(pts
			(xy 342.487758 -259.00761) (xy 342.440768 -258.85521) (xy 342.179148 -258.85521) (xy 342.132158 -259.00761)
			(xy 342.132158 -259.051806) (xy 342.487758 -259.051806)
		)
		(stroke
			(width 0)
			(type solid)
		)
		(fill yes)
		(layer "In11.Cu")
		(net "M_D_CPU0_SA_CS_N<0>")
	)
	(gr_poly
		(pts
			(xy 342.487758 -258.59867) (xy 342.487758 -258.554474) (xy 342.132158 -258.554474) (xy 342.132158 -258.59867)
			(xy 342.179148 -258.75107) (xy 342.440768 -258.75107)
		)
		(stroke
			(width 0)
			(type solid)
		)
		(fill yes)
		(layer "In11.Cu")
		(net "M_D_CPU0_SA_CS_N<3>")
	)
	(gr_poly
		(pts
			(xy 342.490298 -278.132286) (xy 342.490298 -278.08809) (xy 342.134698 -278.08809) (xy 342.134698 -278.132286)
			(xy 342.181688 -278.284686) (xy 342.443308 -278.284686)
		)
		(stroke
			(width 0)
			(type solid)
		)
		(fill yes)
		(layer "In11.Cu")
		(net "M_D_CPU0_SA_DQS_DP<1>")
	)
	(gr_poly
		(pts
			(xy 342.490298 -276.912578) (xy 342.443308 -276.760178) (xy 342.181688 -276.760178) (xy 342.134698 -276.912578)
			(xy 342.134698 -276.957028) (xy 342.490298 -276.957028)
		)
		(stroke
			(width 0)
			(type solid)
		)
		(fill yes)
		(layer "In11.Cu")
		(net "M_D_CPU0_SA_DQS_DP<6>")
	)
	(gr_poly
		(pts
			(xy 342.490298 -274.876514) (xy 342.490298 -274.832318) (xy 342.134698 -274.832318) (xy 342.134698 -274.876514)
			(xy 342.181688 -275.028914) (xy 342.443308 -275.028914)
		)
		(stroke
			(width 0)
			(type solid)
		)
		(fill yes)
		(layer "In11.Cu")
		(net "M_D_CPU0_SA_DQ<16>")
	)
	(gr_poly
		(pts
			(xy 342.490298 -272.029174) (xy 342.443308 -271.876774) (xy 342.181688 -271.876774) (xy 342.134698 -272.029174)
			(xy 342.134698 -272.073624) (xy 342.490298 -272.073624)
		)
		(stroke
			(width 0)
			(type solid)
		)
		(fill yes)
		(layer "In11.Cu")
		(net "M_D_CPU0_SA_DQS_DP<7>")
	)
	(gr_poly
		(pts
			(xy 342.490298 -269.993618) (xy 342.490298 -269.949168) (xy 342.134698 -269.949168) (xy 342.134698 -269.993618)
			(xy 342.181688 -270.146018) (xy 342.443308 -270.146018)
		)
		(stroke
			(width 0)
			(type solid)
		)
		(fill yes)
		(layer "In11.Cu")
		(net "M_D_CPU0_SA_DQ<24>")
	)
	(gr_poly
		(pts
			(xy 342.490298 -267.14577) (xy 342.443308 -266.99337) (xy 342.181688 -266.99337) (xy 342.134698 -267.14577)
			(xy 342.134698 -267.19022) (xy 342.490298 -267.19022)
		)
		(stroke
			(width 0)
			(type solid)
		)
		(fill yes)
		(layer "In11.Cu")
		(net "M_D_CPU0_SA_DQS_DP<8>")
	)
	(gr_poly
		(pts
			(xy 342.490298 -266.737846) (xy 342.490298 -266.69365) (xy 342.134698 -266.69365) (xy 342.134698 -266.737846)
			(xy 342.181688 -266.890246) (xy 342.443308 -266.890246)
		)
		(stroke
			(width 0)
			(type solid)
		)
		(fill yes)
		(layer "In11.Cu")
		(net "M_D_CPU0_SA_DQ<28>")
	)
	(gr_poly
		(pts
			(xy 342.490298 -265.518138) (xy 342.443308 -265.365738) (xy 342.181688 -265.365738) (xy 342.134698 -265.518138)
			(xy 342.134698 -265.562588) (xy 342.490298 -265.562588)
		)
		(stroke
			(width 0)
			(type solid)
		)
		(fill yes)
		(layer "In11.Cu")
		(net "M_D_CPU0_SA_DQ<31>")
	)
	(gr_poly
		(pts
			(xy 342.490298 -265.110214) (xy 342.490298 -265.065764) (xy 342.134698 -265.065764) (xy 342.134698 -265.110214)
			(xy 342.181688 -265.262614) (xy 342.443308 -265.262614)
		)
		(stroke
			(width 0)
			(type solid)
		)
		(fill yes)
		(layer "In11.Cu")
		(net "M_D_CPU0_SA_CB<0>")
	)
	(gr_poly
		(pts
			(xy 342.490298 -261.854442) (xy 342.490298 -261.810246) (xy 342.134698 -261.810246) (xy 342.134698 -261.854442)
			(xy 342.181688 -262.006842) (xy 342.443308 -262.006842)
		)
		(stroke
			(width 0)
			(type solid)
		)
		(fill yes)
		(layer "In11.Cu")
		(net "M_D_CPU0_SA_CB<4>")
	)
	(gr_poly
		(pts
			(xy 342.490298 -257.37947) (xy 342.443308 -257.22707) (xy 342.181688 -257.22707) (xy 342.134698 -257.37947)
			(xy 342.134698 -257.423666) (xy 342.490298 -257.423666)
		)
		(stroke
			(width 0)
			(type solid)
		)
		(fill yes)
		(layer "In11.Cu")
		(net "M_D_CPU0_SA_CA<1>")
	)
	(gr_poly
		(pts
			(xy 342.69934 -233.809032) (xy 342.737694 -233.786934) (xy 342.559894 -233.479086) (xy 342.52154 -233.501184)
			(xy 342.413082 -233.618024) (xy 342.543892 -233.844592)
		)
		(stroke
			(width 0)
			(type solid)
		)
		(fill yes)
		(layer "In11.Cu")
		(net "M_D_CPU0_SB_DQ<12>")
	)
	(gr_poly
		(pts
			(xy 342.807036 -233.1847) (xy 342.915494 -233.06786) (xy 342.784684 -232.841292) (xy 342.629236 -232.876852)
			(xy 342.590882 -232.89895) (xy 342.768682 -233.206798)
		)
		(stroke
			(width 0)
			(type solid)
		)
		(fill yes)
		(layer "In11.Cu")
		(net "M_D_CPU0_SB_DQ<14>")
	)
	(gr_poly
		(pts
			(xy 342.833198 -244.940582) (xy 342.786208 -244.788182) (xy 342.524588 -244.788182) (xy 342.477598 -244.940582)
			(xy 342.477598 -244.985032) (xy 342.833198 -244.985032)
		)
		(stroke
			(width 0)
			(type solid)
		)
		(fill yes)
		(layer "In11.Cu")
		(net "M_D_CPU0_SB_DQS_DN<9>")
	)
	(gr_poly
		(pts
			(xy 342.833198 -242.905026) (xy 342.833198 -242.860576) (xy 342.477598 -242.860576) (xy 342.477598 -242.905026)
			(xy 342.524588 -243.057426) (xy 342.786208 -243.057426)
		)
		(stroke
			(width 0)
			(type solid)
		)
		(fill yes)
		(layer "In11.Cu")
		(net "M_D_CPU0_SB_CB<1>")
	)
	(gr_poly
		(pts
			(xy 342.833198 -240.057178) (xy 342.786208 -239.904778) (xy 342.524588 -239.904778) (xy 342.477598 -240.057178)
			(xy 342.477598 -240.101628) (xy 342.833198 -240.101628)
		)
		(stroke
			(width 0)
			(type solid)
		)
		(fill yes)
		(layer "In11.Cu")
		(net "M_D_CPU0_SB_DQS_DN<0>")
	)
	(gr_poly
		(pts
			(xy 342.833198 -238.021622) (xy 342.833198 -237.977172) (xy 342.477598 -237.977172) (xy 342.477598 -238.021622)
			(xy 342.524588 -238.174022) (xy 342.786208 -238.174022)
		)
		(stroke
			(width 0)
			(type solid)
		)
		(fill yes)
		(layer "In11.Cu")
		(net "M_D_CPU0_SB_DQ<5>")
	)
	(gr_poly
		(pts
			(xy 342.833198 -235.174282) (xy 342.786208 -235.021882) (xy 342.524588 -235.021882) (xy 342.477598 -235.174282)
			(xy 342.477598 -235.218478) (xy 342.833198 -235.218478)
		)
		(stroke
			(width 0)
			(type solid)
		)
		(fill yes)
		(layer "In11.Cu")
		(net "M_D_CPU0_SB_DQS_DN<1>")
	)
	(gr_poly
		(pts
			(xy 342.833198 -230.290878) (xy 342.786208 -230.138478) (xy 342.524588 -230.138478) (xy 342.477598 -230.290878)
			(xy 342.477598 -230.335074) (xy 342.833198 -230.335074)
		)
		(stroke
			(width 0)
			(type solid)
		)
		(fill yes)
		(layer "In11.Cu")
		(net "M_D_CPU0_SB_DQ<15>")
	)
	(gr_poly
		(pts
			(xy 342.833198 -228.254814) (xy 342.833198 -228.210618) (xy 342.477598 -228.210618) (xy 342.477598 -228.254814)
			(xy 342.524588 -228.407214) (xy 342.786208 -228.407214)
		)
		(stroke
			(width 0)
			(type solid)
		)
		(fill yes)
		(layer "In11.Cu")
		(net "M_D_CPU0_SB_DQS_DP<3>")
	)
	(gr_poly
		(pts
			(xy 342.833198 -226.627182) (xy 342.833198 -226.582732) (xy 342.477598 -226.582732) (xy 342.477598 -226.627182)
			(xy 342.524588 -226.779582) (xy 342.786208 -226.779582)
		)
		(stroke
			(width 0)
			(type solid)
		)
		(fill yes)
		(layer "In11.Cu")
		(net "M_D_CPU0_SB_DQ<28>")
	)
	(gr_poly
		(pts
			(xy 342.833198 -225.407474) (xy 342.786208 -225.255074) (xy 342.524588 -225.255074) (xy 342.477598 -225.407474)
			(xy 342.477598 -225.45167) (xy 342.833198 -225.45167)
		)
		(stroke
			(width 0)
			(type solid)
		)
		(fill yes)
		(layer "In11.Cu")
		(net "M_D_CPU0_SB_DQ<31>")
	)
	(gr_poly
		(pts
			(xy 342.835738 -246.568722) (xy 342.788748 -246.416322) (xy 342.527128 -246.416322) (xy 342.480138 -246.568722)
			(xy 342.480138 -246.613172) (xy 342.835738 -246.613172)
		)
		(stroke
			(width 0)
			(type solid)
		)
		(fill yes)
		(layer "In11.Cu")
		(net "M_D_CPU0_SB_CB<6>")
	)
	(gr_poly
		(pts
			(xy 342.835738 -246.16029) (xy 342.835738 -246.11584) (xy 342.480138 -246.11584) (xy 342.480138 -246.16029)
			(xy 342.527128 -246.31269) (xy 342.788748 -246.31269)
		)
		(stroke
			(width 0)
			(type solid)
		)
		(fill yes)
		(layer "In11.Cu")
		(net "M_D_CPU0_SB_CB<5>")
	)
	(gr_poly
		(pts
			(xy 342.835738 -241.685318) (xy 342.788748 -241.532918) (xy 342.527128 -241.532918) (xy 342.480138 -241.685318)
			(xy 342.480138 -241.729768) (xy 342.835738 -241.729768)
		)
		(stroke
			(width 0)
			(type solid)
		)
		(fill yes)
		(layer "In11.Cu")
		(net "M_D_CPU0_SB_DQ<2>")
	)
	(gr_poly
		(pts
			(xy 342.835738 -241.276886) (xy 342.835738 -241.232436) (xy 342.480138 -241.232436) (xy 342.480138 -241.276886)
			(xy 342.527128 -241.429286) (xy 342.788748 -241.429286)
		)
		(stroke
			(width 0)
			(type solid)
		)
		(fill yes)
		(layer "In11.Cu")
		(net "M_D_CPU0_SB_DQ<1>")
	)
	(gr_poly
		(pts
			(xy 342.835738 -236.801914) (xy 342.788748 -236.649514) (xy 342.527128 -236.649514) (xy 342.480138 -236.801914)
			(xy 342.480138 -236.846364) (xy 342.835738 -236.846364)
		)
		(stroke
			(width 0)
			(type solid)
		)
		(fill yes)
		(layer "In11.Cu")
		(net "M_D_CPU0_SB_DQ<10>")
	)
	(gr_poly
		(pts
			(xy 342.835738 -236.393482) (xy 342.835738 -236.349286) (xy 342.480138 -236.349286) (xy 342.480138 -236.393482)
			(xy 342.527128 -236.545882) (xy 342.788748 -236.545882)
		)
		(stroke
			(width 0)
			(type solid)
		)
		(fill yes)
		(layer "In11.Cu")
		(net "M_D_CPU0_SB_DQ<9>")
	)
	(gr_poly
		(pts
			(xy 342.84158 -249.415554) (xy 342.84158 -249.371358) (xy 342.48598 -249.371358) (xy 342.48598 -249.415554)
			(xy 342.53297 -249.567954) (xy 342.79459 -249.567954)
		)
		(stroke
			(width 0)
			(type solid)
		)
		(fill yes)
		(layer "In11.Cu")
		(net "M_D_CPU0_SB_CA<2>")
	)
	(gr_poly
		(pts
			(xy 342.84158 -244.53215) (xy 342.84158 -244.487954) (xy 342.48598 -244.487954) (xy 342.48598 -244.53215)
			(xy 342.53297 -244.68455) (xy 342.79459 -244.68455)
		)
		(stroke
			(width 0)
			(type solid)
		)
		(fill yes)
		(layer "In11.Cu")
		(net "M_D_CPU0_SB_DQS_DN<4>")
	)
	(gr_poly
		(pts
			(xy 342.84158 -243.313458) (xy 342.79459 -243.161058) (xy 342.53297 -243.161058) (xy 342.48598 -243.313458)
			(xy 342.48598 -243.357654) (xy 342.84158 -243.357654)
		)
		(stroke
			(width 0)
			(type solid)
		)
		(fill yes)
		(layer "In11.Cu")
		(net "M_D_CPU0_SB_CB<2>")
	)
	(gr_poly
		(pts
			(xy 342.84158 -239.648746) (xy 342.84158 -239.60455) (xy 342.48598 -239.60455) (xy 342.48598 -239.648746)
			(xy 342.53297 -239.801146) (xy 342.79459 -239.801146)
		)
		(stroke
			(width 0)
			(type solid)
		)
		(fill yes)
		(layer "In11.Cu")
		(net "M_D_CPU0_SB_DQS_DN<5>")
	)
	(gr_poly
		(pts
			(xy 342.84158 -238.430054) (xy 342.79459 -238.277654) (xy 342.53297 -238.277654) (xy 342.48598 -238.430054)
			(xy 342.48598 -238.47425) (xy 342.84158 -238.47425)
		)
		(stroke
			(width 0)
			(type solid)
		)
		(fill yes)
		(layer "In11.Cu")
		(net "M_D_CPU0_SB_DQ<6>")
	)
	(gr_poly
		(pts
			(xy 342.84158 -234.76585) (xy 342.84158 -234.7214) (xy 342.48598 -234.7214) (xy 342.48598 -234.76585)
			(xy 342.53297 -234.91825) (xy 342.79459 -234.91825)
		)
		(stroke
			(width 0)
			(type solid)
		)
		(fill yes)
		(layer "In11.Cu")
		(net "M_D_CPU0_SB_DQS_DN<6>")
	)
	(gr_poly
		(pts
			(xy 342.84158 -229.882446) (xy 342.84158 -229.837996) (xy 342.48598 -229.837996) (xy 342.48598 -229.882446)
			(xy 342.53297 -230.034846) (xy 342.79459 -230.034846)
		)
		(stroke
			(width 0)
			(type solid)
		)
		(fill yes)
		(layer "In11.Cu")
		(net "M_D_CPU0_SB_DQ<24>")
	)
	(gr_poly
		(pts
			(xy 342.84158 -228.663246) (xy 342.79459 -228.510846) (xy 342.53297 -228.510846) (xy 342.48598 -228.663246)
			(xy 342.48598 -228.707696) (xy 342.84158 -228.707696)
		)
		(stroke
			(width 0)
			(type solid)
		)
		(fill yes)
		(layer "In11.Cu")
		(net "M_D_CPU0_SB_DQ<27>")
	)
	(gr_poly
		(pts
			(xy 342.842088 -227.035614) (xy 342.795098 -226.883214) (xy 342.533478 -226.883214) (xy 342.486488 -227.035614)
			(xy 342.486488 -227.07981) (xy 342.842088 -227.07981)
		)
		(stroke
			(width 0)
			(type solid)
		)
		(fill yes)
		(layer "In11.Cu")
		(net "M_D_CPU0_SB_DQS_DP<8>")
	)
	(gr_poly
		(pts
			(xy 342.94318 -277.726394) (xy 342.89619 -277.573994) (xy 342.63457 -277.573994) (xy 342.58758 -277.726394)
			(xy 342.58758 -277.770844) (xy 342.94318 -277.770844)
		)
		(stroke
			(width 0)
			(type solid)
		)
		(fill yes)
		(layer "In11.Cu")
		(net "M_D_CPU0_SA_DQS_DN<1>")
	)
	(gr_poly
		(pts
			(xy 342.94318 -277.318216) (xy 342.94318 -277.27402) (xy 342.58758 -277.27402) (xy 342.58758 -277.318216)
			(xy 342.63457 -277.470616) (xy 342.89619 -277.470616)
		)
		(stroke
			(width 0)
			(type solid)
		)
		(fill yes)
		(layer "In11.Cu")
		(net "M_D_CPU0_SA_DQS_DN<6>")
	)
	(gr_poly
		(pts
			(xy 342.94318 -274.47113) (xy 342.89619 -274.31873) (xy 342.63457 -274.31873) (xy 342.58758 -274.47113)
			(xy 342.58758 -274.515326) (xy 342.94318 -274.515326)
		)
		(stroke
			(width 0)
			(type solid)
		)
		(fill yes)
		(layer "In11.Cu")
		(net "M_D_CPU0_SA_DQ<18>")
	)
	(gr_poly
		(pts
			(xy 342.94318 -272.435066) (xy 342.94318 -272.39087) (xy 342.58758 -272.39087) (xy 342.58758 -272.435066)
			(xy 342.63457 -272.587466) (xy 342.89619 -272.587466)
		)
		(stroke
			(width 0)
			(type solid)
		)
		(fill yes)
		(layer "In11.Cu")
		(net "M_D_CPU0_SA_DQS_DN<7>")
	)
	(gr_poly
		(pts
			(xy 342.94318 -269.587726) (xy 342.89619 -269.435326) (xy 342.63457 -269.435326) (xy 342.58758 -269.587726)
			(xy 342.58758 -269.631922) (xy 342.94318 -269.631922)
		)
		(stroke
			(width 0)
			(type solid)
		)
		(fill yes)
		(layer "In11.Cu")
		(net "M_D_CPU0_SA_DQ<26>")
	)
	(gr_poly
		(pts
			(xy 342.94318 -267.551662) (xy 342.94318 -267.507466) (xy 342.58758 -267.507466) (xy 342.58758 -267.551662)
			(xy 342.63457 -267.704062) (xy 342.89619 -267.704062)
		)
		(stroke
			(width 0)
			(type solid)
		)
		(fill yes)
		(layer "In11.Cu")
		(net "M_D_CPU0_SA_DQS_DN<8>")
	)
	(gr_poly
		(pts
			(xy 342.94318 -266.331954) (xy 342.89619 -266.179554) (xy 342.63457 -266.179554) (xy 342.58758 -266.331954)
			(xy 342.58758 -266.376404) (xy 342.94318 -266.376404)
		)
		(stroke
			(width 0)
			(type solid)
		)
		(fill yes)
		(layer "In11.Cu")
		(net "M_D_CPU0_SA_DQ<30>")
	)
	(gr_poly
		(pts
			(xy 342.94318 -265.92403) (xy 342.94318 -265.87958) (xy 342.58758 -265.87958) (xy 342.58758 -265.92403)
			(xy 342.63457 -266.07643) (xy 342.89619 -266.07643)
		)
		(stroke
			(width 0)
			(type solid)
		)
		(fill yes)
		(layer "In11.Cu")
		(net "M_D_CPU0_SA_DQ<29>")
	)
	(gr_poly
		(pts
			(xy 342.94318 -264.704322) (xy 342.89619 -264.551922) (xy 342.63457 -264.551922) (xy 342.58758 -264.704322)
			(xy 342.58758 -264.748772) (xy 342.94318 -264.748772)
		)
		(stroke
			(width 0)
			(type solid)
		)
		(fill yes)
		(layer "In11.Cu")
		(net "M_D_CPU0_SA_CB<2>")
	)
	(gr_poly
		(pts
			(xy 342.94318 -261.449058) (xy 342.89619 -261.296658) (xy 342.63457 -261.296658) (xy 342.58758 -261.449058)
			(xy 342.58758 -261.493254) (xy 342.94318 -261.493254)
		)
		(stroke
			(width 0)
			(type solid)
		)
		(fill yes)
		(layer "In11.Cu")
		(net "M_D_CPU0_SA_CB<6>")
	)
	(gr_poly
		(pts
			(xy 342.94318 -257.784854) (xy 342.94318 -257.740658) (xy 342.58758 -257.740658) (xy 342.58758 -257.784854)
			(xy 342.63457 -257.937254) (xy 342.89619 -257.937254)
		)
		(stroke
			(width 0)
			(type solid)
		)
		(fill yes)
		(layer "In11.Cu")
		(net "M_D_CPU0_SA_CA<0>")
	)
	(gr_poly
		(pts
			(xy 342.94572 -278.945848) (xy 342.94572 -278.901652) (xy 342.59012 -278.901652) (xy 342.59012 -278.945848)
			(xy 342.63711 -279.098248) (xy 342.89873 -279.098248)
		)
		(stroke
			(width 0)
			(type solid)
		)
		(fill yes)
		(layer "In11.Cu")
		(net "M_D_CPU0_SA_DQ<9>")
	)
	(gr_poly
		(pts
			(xy 342.94572 -276.09927) (xy 342.89873 -275.94687) (xy 342.63711 -275.94687) (xy 342.59012 -276.09927)
			(xy 342.59012 -276.143466) (xy 342.94572 -276.143466)
		)
		(stroke
			(width 0)
			(type solid)
		)
		(fill yes)
		(layer "In11.Cu")
		(net "M_D_CPU0_SA_DQ<14>")
	)
	(gr_poly
		(pts
			(xy 342.94572 -275.690584) (xy 342.94572 -275.646134) (xy 342.59012 -275.646134) (xy 342.59012 -275.690584)
			(xy 342.63711 -275.842984) (xy 342.89873 -275.842984)
		)
		(stroke
			(width 0)
			(type solid)
		)
		(fill yes)
		(layer "In11.Cu")
		(net "M_D_CPU0_SA_DQ<13>")
	)
	(gr_poly
		(pts
			(xy 342.94572 -271.215866) (xy 342.89873 -271.063466) (xy 342.63711 -271.063466) (xy 342.59012 -271.215866)
			(xy 342.59012 -271.260062) (xy 342.94572 -271.260062)
		)
		(stroke
			(width 0)
			(type solid)
		)
		(fill yes)
		(layer "In11.Cu")
		(net "M_D_CPU0_SA_DQ<22>")
	)
	(gr_poly
		(pts
			(xy 342.94572 -270.806926) (xy 342.94572 -270.76273) (xy 342.59012 -270.76273) (xy 342.59012 -270.806926)
			(xy 342.63711 -270.959326) (xy 342.89873 -270.959326)
		)
		(stroke
			(width 0)
			(type solid)
		)
		(fill yes)
		(layer "In11.Cu")
		(net "M_D_CPU0_SA_DQ<21>")
	)
	(gr_poly
		(pts
			(xy 342.94572 -256.565654) (xy 342.89873 -256.413254) (xy 342.63711 -256.413254) (xy 342.59012 -256.565654)
			(xy 342.59012 -256.610104) (xy 342.94572 -256.610104)
		)
		(stroke
			(width 0)
			(type solid)
		)
		(fill yes)
		(layer "In11.Cu")
		(net "M_D_CPU0_SA_CA<3>")
	)
	(gr_poly
		(pts
			(xy 342.94572 -256.157222) (xy 342.94572 -256.112772) (xy 342.59012 -256.112772) (xy 342.59012 -256.157222)
			(xy 342.63711 -256.309622) (xy 342.89873 -256.309622)
		)
		(stroke
			(width 0)
			(type solid)
		)
		(fill yes)
		(layer "In11.Cu")
		(net "M_D_CPU0_SA_CA<4>")
	)
	(gr_poly
		(pts
			(xy 342.951562 -274.062698) (xy 342.951562 -274.018248) (xy 342.595962 -274.018248) (xy 342.595962 -274.062698)
			(xy 342.642952 -274.215098) (xy 342.904572 -274.215098)
		)
		(stroke
			(width 0)
			(type solid)
		)
		(fill yes)
		(layer "In11.Cu")
		(net "M_D_CPU0_SA_DQ<17>")
	)
	(gr_poly
		(pts
			(xy 342.951562 -272.843498) (xy 342.904572 -272.691098) (xy 342.642952 -272.691098) (xy 342.595962 -272.843498)
			(xy 342.595962 -272.887948) (xy 342.951562 -272.887948)
		)
		(stroke
			(width 0)
			(type solid)
		)
		(fill yes)
		(layer "In11.Cu")
		(net "M_D_CPU0_SA_DQS_DN<2>")
	)
	(gr_poly
		(pts
			(xy 342.951562 -267.960094) (xy 342.904572 -267.807694) (xy 342.642952 -267.807694) (xy 342.595962 -267.960094)
			(xy 342.595962 -268.004544) (xy 342.951562 -268.004544)
		)
		(stroke
			(width 0)
			(type solid)
		)
		(fill yes)
		(layer "In11.Cu")
		(net "M_D_CPU0_SA_DQS_DN<3>")
	)
	(gr_poly
		(pts
			(xy 342.951562 -264.29589) (xy 342.951562 -264.251694) (xy 342.595962 -264.251694) (xy 342.595962 -264.29589)
			(xy 342.642952 -264.44829) (xy 342.904572 -264.44829)
		)
		(stroke
			(width 0)
			(type solid)
		)
		(fill yes)
		(layer "In11.Cu")
		(net "M_D_CPU0_SA_CB<1>")
	)
	(gr_poly
		(pts
			(xy 342.951562 -263.07669) (xy 342.904572 -262.92429) (xy 342.642952 -262.92429) (xy 342.595962 -263.07669)
			(xy 342.595962 -263.12114) (xy 342.951562 -263.12114)
		)
		(stroke
			(width 0)
			(type solid)
		)
		(fill yes)
		(layer "In11.Cu")
		(net "M_D_CPU0_SA_DQS_DN<4>")
	)
	(gr_poly
		(pts
			(xy 342.951562 -259.412486) (xy 342.951562 -259.36829) (xy 342.595962 -259.36829) (xy 342.595962 -259.412486)
			(xy 342.642952 -259.564886) (xy 342.904572 -259.564886)
		)
		(stroke
			(width 0)
			(type solid)
		)
		(fill yes)
		(layer "In11.Cu")
		(net "M_D_CPU0_SA_CS_N<2>")
	)
	(gr_poly
		(pts
			(xy 342.951562 -258.193286) (xy 342.904572 -258.040886) (xy 342.642952 -258.040886) (xy 342.595962 -258.193286)
			(xy 342.595962 -258.237736) (xy 342.951562 -258.237736)
		)
		(stroke
			(width 0)
			(type solid)
		)
		(fill yes)
		(layer "In11.Cu")
		(net "M_D_CPU0_SA_CS_N<1>")
	)
	(gr_poly
		(pts
			(xy 342.955118 -269.179294) (xy 342.955118 -269.134844) (xy 342.599518 -269.134844) (xy 342.599518 -269.179294)
			(xy 342.646508 -269.331694) (xy 342.908128 -269.331694)
		)
		(stroke
			(width 0)
			(type solid)
		)
		(fill yes)
		(layer "In11.Cu")
		(net "M_D_CPU0_SA_DQ<25>")
	)
	(gr_poly
		(pts
			(xy 342.955118 -262.668258) (xy 342.955118 -262.623808) (xy 342.599518 -262.623808) (xy 342.599518 -262.668258)
			(xy 342.646508 -262.820658) (xy 342.908128 -262.820658)
		)
		(stroke
			(width 0)
			(type solid)
		)
		(fill yes)
		(layer "In11.Cu")
		(net "M_D_CPU0_SA_DQS_DN<9>")
	)
	(gr_poly
		(pts
			(xy 342.957658 -279.354788) (xy 342.910668 -279.202388) (xy 342.649048 -279.202388) (xy 342.602058 -279.354788)
			(xy 342.602058 -279.398984) (xy 342.957658 -279.398984)
		)
		(stroke
			(width 0)
			(type solid)
		)
		(fill yes)
		(layer "In11.Cu")
		(net "M_D_CPU0_SA_DQ<10>")
	)
	(gr_poly
		(pts
			(xy 342.959944 -261.040626) (xy 342.959944 -260.99643) (xy 342.604344 -260.99643) (xy 342.604344 -261.040626)
			(xy 342.651334 -261.193026) (xy 342.912954 -261.193026)
		)
		(stroke
			(width 0)
			(type solid)
		)
		(fill yes)
		(layer "In11.Cu")
		(net "M_D_CPU0_SA_CB<5>")
	)
	(gr_poly
		(pts
			(xy 343.170256 -231.36733) (xy 343.20861 -231.345232) (xy 343.03081 -231.037384) (xy 342.992456 -231.059482)
			(xy 342.883998 -231.176322) (xy 343.014808 -231.40289)
		)
		(stroke
			(width 0)
			(type solid)
		)
		(fill yes)
		(layer "In11.Cu")
		(net "M_D_CPU0_SB_DQ<13>")
	)
	(gr_poly
		(pts
			(xy 343.282524 -230.75265) (xy 343.390982 -230.63581) (xy 343.260172 -230.409242) (xy 343.104724 -230.444802)
			(xy 343.06637 -230.4669) (xy 343.24417 -230.774748)
		)
		(stroke
			(width 0)
			(type solid)
		)
		(fill yes)
		(layer "In11.Cu")
		(net "M_D_CPU0_SB_DQ<15>")
	)
	(gr_poly
		(pts
			(xy 343.317576 -244.126766) (xy 343.270586 -243.974366) (xy 343.008966 -243.974366) (xy 342.961976 -244.126766)
			(xy 342.961976 -244.171216) (xy 343.317576 -244.171216)
		)
		(stroke
			(width 0)
			(type solid)
		)
		(fill yes)
		(layer "In11.Cu")
		(net "M_D_CPU0_SB_DQS_DP<4>")
	)
	(gr_poly
		(pts
			(xy 343.317576 -243.718842) (xy 343.317576 -243.674392) (xy 342.961976 -243.674392) (xy 342.961976 -243.718842)
			(xy 343.008966 -243.871242) (xy 343.270586 -243.871242)
		)
		(stroke
			(width 0)
			(type solid)
		)
		(fill yes)
		(layer "In11.Cu")
		(net "M_D_CPU0_SB_CB<0>")
	)
	(gr_poly
		(pts
			(xy 343.317576 -239.243362) (xy 343.270586 -239.090962) (xy 343.008966 -239.090962) (xy 342.961976 -239.243362)
			(xy 342.961976 -239.287812) (xy 343.317576 -239.287812)
		)
		(stroke
			(width 0)
			(type solid)
		)
		(fill yes)
		(layer "In11.Cu")
		(net "M_D_CPU0_SB_DQS_DP<5>")
	)
	(gr_poly
		(pts
			(xy 343.317576 -238.835438) (xy 343.317576 -238.790988) (xy 342.961976 -238.790988) (xy 342.961976 -238.835438)
			(xy 343.008966 -238.987838) (xy 343.270586 -238.987838)
		)
		(stroke
			(width 0)
			(type solid)
		)
		(fill yes)
		(layer "In11.Cu")
		(net "M_D_CPU0_SB_DQ<4>")
	)
	(gr_poly
		(pts
			(xy 343.317576 -234.360466) (xy 343.270586 -234.208066) (xy 343.008966 -234.208066) (xy 342.961976 -234.360466)
			(xy 342.961976 -234.404662) (xy 343.317576 -234.404662)
		)
		(stroke
			(width 0)
			(type solid)
		)
		(fill yes)
		(layer "In11.Cu")
		(net "M_D_CPU0_SB_DQS_DP<6>")
	)
	(gr_poly
		(pts
			(xy 343.317576 -233.952034) (xy 343.317576 -233.907838) (xy 342.961976 -233.907838) (xy 342.961976 -233.952034)
			(xy 343.008966 -234.104434) (xy 343.270586 -234.104434)
		)
		(stroke
			(width 0)
			(type solid)
		)
		(fill yes)
		(layer "In11.Cu")
		(net "M_D_CPU0_SB_DQ<12>")
	)
	(gr_poly
		(pts
			(xy 343.317576 -229.477062) (xy 343.270586 -229.324662) (xy 343.008966 -229.324662) (xy 342.961976 -229.477062)
			(xy 342.961976 -229.521258) (xy 343.317576 -229.521258)
		)
		(stroke
			(width 0)
			(type solid)
		)
		(fill yes)
		(layer "In11.Cu")
		(net "M_D_CPU0_SB_DQ<26>")
	)
	(gr_poly
		(pts
			(xy 343.317576 -229.06863) (xy 343.317576 -229.024434) (xy 342.961976 -229.024434) (xy 342.961976 -229.06863)
			(xy 343.008966 -229.22103) (xy 343.270586 -229.22103)
		)
		(stroke
			(width 0)
			(type solid)
		)
		(fill yes)
		(layer "In11.Cu")
		(net "M_D_CPU0_SB_DQ<25>")
	)
	(gr_poly
		(pts
			(xy 343.320116 -247.382538) (xy 343.273126 -247.230138) (xy 343.011506 -247.230138) (xy 342.964516 -247.382538)
			(xy 342.964516 -247.426734) (xy 343.320116 -247.426734)
		)
		(stroke
			(width 0)
			(type solid)
		)
		(fill yes)
		(layer "In11.Cu")
		(net "M_D_CPU0_SB_PAR")
	)
	(gr_poly
		(pts
			(xy 343.320116 -246.974106) (xy 343.320116 -246.92991) (xy 342.964516 -246.92991) (xy 342.964516 -246.974106)
			(xy 343.011506 -247.126506) (xy 343.273126 -247.126506)
		)
		(stroke
			(width 0)
			(type solid)
		)
		(fill yes)
		(layer "In11.Cu")
		(net "M_D_CPU0_SB_CB<4>")
	)
	(gr_poly
		(pts
			(xy 343.320116 -245.754906) (xy 343.273126 -245.602506) (xy 343.011506 -245.602506) (xy 342.964516 -245.754906)
			(xy 342.964516 -245.799102) (xy 343.320116 -245.799102)
		)
		(stroke
			(width 0)
			(type solid)
		)
		(fill yes)
		(layer "In11.Cu")
		(net "M_D_CPU0_SB_CB<7>")
	)
	(gr_poly
		(pts
			(xy 343.320116 -245.346474) (xy 343.320116 -245.302278) (xy 342.964516 -245.302278) (xy 342.964516 -245.346474)
			(xy 343.011506 -245.498874) (xy 343.273126 -245.498874)
		)
		(stroke
			(width 0)
			(type solid)
		)
		(fill yes)
		(layer "In11.Cu")
		(net "M_D_CPU0_SB_DQS_DP<9>")
	)
	(gr_poly
		(pts
			(xy 343.320116 -242.499134) (xy 343.273126 -242.346734) (xy 343.011506 -242.346734) (xy 342.964516 -242.499134)
			(xy 342.964516 -242.54333) (xy 343.320116 -242.54333)
		)
		(stroke
			(width 0)
			(type solid)
		)
		(fill yes)
		(layer "In11.Cu")
		(net "M_D_CPU0_SB_CB<3>")
	)
	(gr_poly
		(pts
			(xy 343.320116 -242.090702) (xy 343.320116 -242.046506) (xy 342.964516 -242.046506) (xy 342.964516 -242.090702)
			(xy 343.011506 -242.243102) (xy 343.273126 -242.243102)
		)
		(stroke
			(width 0)
			(type solid)
		)
		(fill yes)
		(layer "In11.Cu")
		(net "M_D_CPU0_SB_DQ<0>")
	)
	(gr_poly
		(pts
			(xy 343.320116 -240.871502) (xy 343.273126 -240.719102) (xy 343.011506 -240.719102) (xy 342.964516 -240.871502)
			(xy 342.964516 -240.915698) (xy 343.320116 -240.915698)
		)
		(stroke
			(width 0)
			(type solid)
		)
		(fill yes)
		(layer "In11.Cu")
		(net "M_D_CPU0_SB_DQ<3>")
	)
	(gr_poly
		(pts
			(xy 343.320116 -240.46307) (xy 343.320116 -240.418874) (xy 342.964516 -240.418874) (xy 342.964516 -240.46307)
			(xy 343.011506 -240.61547) (xy 343.273126 -240.61547)
		)
		(stroke
			(width 0)
			(type solid)
		)
		(fill yes)
		(layer "In11.Cu")
		(net "M_D_CPU0_SB_DQS_DP<0>")
	)
	(gr_poly
		(pts
			(xy 343.320116 -237.61573) (xy 343.273126 -237.46333) (xy 343.011506 -237.46333) (xy 342.964516 -237.61573)
			(xy 342.964516 -237.66018) (xy 343.320116 -237.66018)
		)
		(stroke
			(width 0)
			(type solid)
		)
		(fill yes)
		(layer "In11.Cu")
		(net "M_D_CPU0_SB_DQ<7>")
	)
	(gr_poly
		(pts
			(xy 343.320116 -237.207806) (xy 343.320116 -237.163356) (xy 342.964516 -237.163356) (xy 342.964516 -237.207806)
			(xy 343.011506 -237.360206) (xy 343.273126 -237.360206)
		)
		(stroke
			(width 0)
			(type solid)
		)
		(fill yes)
		(layer "In11.Cu")
		(net "M_D_CPU0_SB_DQ<8>")
	)
	(gr_poly
		(pts
			(xy 343.320116 -235.988098) (xy 343.273126 -235.835698) (xy 343.011506 -235.835698) (xy 342.964516 -235.988098)
			(xy 342.964516 -236.032294) (xy 343.320116 -236.032294)
		)
		(stroke
			(width 0)
			(type solid)
		)
		(fill yes)
		(layer "In11.Cu")
		(net "M_D_CPU0_SB_DQ<11>")
	)
	(gr_poly
		(pts
			(xy 343.320116 -235.579666) (xy 343.320116 -235.53547) (xy 342.964516 -235.53547) (xy 342.964516 -235.579666)
			(xy 343.011506 -235.732066) (xy 343.273126 -235.732066)
		)
		(stroke
			(width 0)
			(type solid)
		)
		(fill yes)
		(layer "In11.Cu")
		(net "M_D_CPU0_SB_DQS_DP<1>")
	)
	(gr_poly
		(pts
			(xy 343.320116 -227.848922) (xy 343.273126 -227.696522) (xy 343.011506 -227.696522) (xy 342.964516 -227.848922)
			(xy 342.964516 -227.893372) (xy 343.320116 -227.893372)
		)
		(stroke
			(width 0)
			(type solid)
		)
		(fill yes)
		(layer "In11.Cu")
		(net "M_D_CPU0_SB_DQS_DN<3>")
	)
	(gr_poly
		(pts
			(xy 343.320116 -227.440998) (xy 343.320116 -227.396548) (xy 342.964516 -227.396548) (xy 342.964516 -227.440998)
			(xy 343.011506 -227.593398) (xy 343.273126 -227.593398)
		)
		(stroke
			(width 0)
			(type solid)
		)
		(fill yes)
		(layer "In11.Cu")
		(net "M_D_CPU0_SB_DQS_DN<8>")
	)
	(gr_poly
		(pts
			(xy 343.320116 -226.22129) (xy 343.273126 -226.06889) (xy 343.011506 -226.06889) (xy 342.964516 -226.22129)
			(xy 342.964516 -226.26574) (xy 343.320116 -226.26574)
		)
		(stroke
			(width 0)
			(type solid)
		)
		(fill yes)
		(layer "In11.Cu")
		(net "M_D_CPU0_SB_DQ<30>")
	)
	(gr_poly
		(pts
			(xy 343.320116 -225.813366) (xy 343.320116 -225.768916) (xy 342.964516 -225.768916) (xy 342.964516 -225.813366)
			(xy 343.011506 -225.965766) (xy 343.273126 -225.965766)
		)
		(stroke
			(width 0)
			(type solid)
		)
		(fill yes)
		(layer "In11.Cu")
		(net "M_D_CPU0_SB_DQ<29>")
	)
	(gr_poly
		(pts
			(xy 343.41816 -268.77391) (xy 343.37117 -268.62151) (xy 343.10955 -268.62151) (xy 343.06256 -268.77391)
			(xy 343.06256 -268.81836) (xy 343.41816 -268.81836)
		)
		(stroke
			(width 0)
			(type solid)
		)
		(fill yes)
		(layer "In11.Cu")
		(net "M_D_CPU0_SA_DQ<27>")
	)
	(gr_poly
		(pts
			(xy 343.41816 -262.262874) (xy 343.37117 -262.110474) (xy 343.10955 -262.110474) (xy 343.06256 -262.262874)
			(xy 343.06256 -262.307324) (xy 343.41816 -262.307324)
		)
		(stroke
			(width 0)
			(type solid)
		)
		(fill yes)
		(layer "In11.Cu")
		(net "M_D_CPU0_SA_DQS_DP<9>")
	)
	(gr_poly
		(pts
			(xy 343.421462 -260.634734) (xy 343.374472 -260.482334) (xy 343.112852 -260.482334) (xy 343.065862 -260.634734)
			(xy 343.065862 -260.679184) (xy 343.421462 -260.679184)
		)
		(stroke
			(width 0)
			(type solid)
		)
		(fill yes)
		(layer "In11.Cu")
		(net "M_D_CPU0_SA_CB<7>")
	)
	(gr_poly
		(pts
			(xy 343.427558 -279.759918) (xy 343.427558 -279.715722) (xy 343.071958 -279.715722) (xy 343.071958 -279.759918)
			(xy 343.118948 -279.912318) (xy 343.380568 -279.912318)
		)
		(stroke
			(width 0)
			(type solid)
		)
		(fill yes)
		(layer "In11.Cu")
		(net "M_D_CPU0_SA_DQ<8>")
	)
	(gr_poly
		(pts
			(xy 343.427558 -273.657314) (xy 343.380568 -273.504914) (xy 343.118948 -273.504914) (xy 343.071958 -273.657314)
			(xy 343.071958 -273.70151) (xy 343.427558 -273.70151)
		)
		(stroke
			(width 0)
			(type solid)
		)
		(fill yes)
		(layer "In11.Cu")
		(net "M_D_CPU0_SA_DQ<19>")
	)
	(gr_poly
		(pts
			(xy 343.427558 -273.248882) (xy 343.427558 -273.204686) (xy 343.071958 -273.204686) (xy 343.071958 -273.248882)
			(xy 343.118948 -273.401282) (xy 343.380568 -273.401282)
		)
		(stroke
			(width 0)
			(type solid)
		)
		(fill yes)
		(layer "In11.Cu")
		(net "M_D_CPU0_SA_DQS_DP<2>")
	)
	(gr_poly
		(pts
			(xy 343.427558 -268.365478) (xy 343.427558 -268.321282) (xy 343.071958 -268.321282) (xy 343.071958 -268.365478)
			(xy 343.118948 -268.517878) (xy 343.380568 -268.517878)
		)
		(stroke
			(width 0)
			(type solid)
		)
		(fill yes)
		(layer "In11.Cu")
		(net "M_D_CPU0_SA_DQS_DP<3>")
	)
	(gr_poly
		(pts
			(xy 343.427558 -263.890506) (xy 343.380568 -263.738106) (xy 343.118948 -263.738106) (xy 343.071958 -263.890506)
			(xy 343.071958 -263.934956) (xy 343.427558 -263.934956)
		)
		(stroke
			(width 0)
			(type solid)
		)
		(fill yes)
		(layer "In11.Cu")
		(net "M_D_CPU0_SA_CB<3>")
	)
	(gr_poly
		(pts
			(xy 343.427558 -263.482582) (xy 343.427558 -263.438132) (xy 343.071958 -263.438132) (xy 343.071958 -263.482582)
			(xy 343.118948 -263.634982) (xy 343.380568 -263.634982)
		)
		(stroke
			(width 0)
			(type solid)
		)
		(fill yes)
		(layer "In11.Cu")
		(net "M_D_CPU0_SA_DQS_DP<4>")
	)
	(gr_poly
		(pts
			(xy 343.427558 -259.007102) (xy 343.380568 -258.854702) (xy 343.118948 -258.854702) (xy 343.071958 -259.007102)
			(xy 343.071958 -259.051552) (xy 343.427558 -259.051552)
		)
		(stroke
			(width 0)
			(type solid)
		)
		(fill yes)
		(layer "In11.Cu")
		(net "M_D_CPU0_SA_CS_N<0>")
	)
	(gr_poly
		(pts
			(xy 343.427558 -258.599178) (xy 343.427558 -258.554728) (xy 343.071958 -258.554728) (xy 343.071958 -258.599178)
			(xy 343.118948 -258.751578) (xy 343.380568 -258.751578)
		)
		(stroke
			(width 0)
			(type solid)
		)
		(fill yes)
		(layer "In11.Cu")
		(net "M_D_CPU0_SA_CS_N<3>")
	)
	(gr_poly
		(pts
			(xy 343.430098 -278.540718) (xy 343.383108 -278.388318) (xy 343.121488 -278.388318) (xy 343.074498 -278.540718)
			(xy 343.074498 -278.584914) (xy 343.430098 -278.584914)
		)
		(stroke
			(width 0)
			(type solid)
		)
		(fill yes)
		(layer "In11.Cu")
		(net "M_D_CPU0_SA_DQ<11>")
	)
	(gr_poly
		(pts
			(xy 343.430098 -278.132286) (xy 343.430098 -278.08809) (xy 343.074498 -278.08809) (xy 343.074498 -278.132286)
			(xy 343.121488 -278.284686) (xy 343.383108 -278.284686)
		)
		(stroke
			(width 0)
			(type solid)
		)
		(fill yes)
		(layer "In11.Cu")
		(net "M_D_CPU0_SA_DQS_DP<1>")
	)
	(gr_poly
		(pts
			(xy 343.430098 -276.912578) (xy 343.383108 -276.760178) (xy 343.121488 -276.760178) (xy 343.074498 -276.912578)
			(xy 343.074498 -276.957028) (xy 343.430098 -276.957028)
		)
		(stroke
			(width 0)
			(type solid)
		)
		(fill yes)
		(layer "In11.Cu")
		(net "M_D_CPU0_SA_DQS_DP<6>")
	)
	(gr_poly
		(pts
			(xy 343.430098 -276.5044) (xy 343.430098 -276.460204) (xy 343.074498 -276.460204) (xy 343.074498 -276.5044)
			(xy 343.121488 -276.6568) (xy 343.383108 -276.6568)
		)
		(stroke
			(width 0)
			(type solid)
		)
		(fill yes)
		(layer "In11.Cu")
		(net "M_D_CPU0_SA_DQ<12>")
	)
	(gr_poly
		(pts
			(xy 343.430098 -275.284946) (xy 343.383108 -275.132546) (xy 343.121488 -275.132546) (xy 343.074498 -275.284946)
			(xy 343.074498 -275.329142) (xy 343.430098 -275.329142)
		)
		(stroke
			(width 0)
			(type solid)
		)
		(fill yes)
		(layer "In11.Cu")
		(net "M_D_CPU0_SA_DQ<15>")
	)
	(gr_poly
		(pts
			(xy 343.430098 -274.876514) (xy 343.430098 -274.832318) (xy 343.074498 -274.832318) (xy 343.074498 -274.876514)
			(xy 343.121488 -275.028914) (xy 343.383108 -275.028914)
		)
		(stroke
			(width 0)
			(type solid)
		)
		(fill yes)
		(layer "In11.Cu")
		(net "M_D_CPU0_SA_DQ<16>")
	)
	(gr_poly
		(pts
			(xy 343.430098 -272.029174) (xy 343.383108 -271.876774) (xy 343.121488 -271.876774) (xy 343.074498 -272.029174)
			(xy 343.074498 -272.073624) (xy 343.430098 -272.073624)
		)
		(stroke
			(width 0)
			(type solid)
		)
		(fill yes)
		(layer "In11.Cu")
		(net "M_D_CPU0_SA_DQS_DP<7>")
	)
	(gr_poly
		(pts
			(xy 343.430098 -271.62125) (xy 343.430098 -271.5768) (xy 343.074498 -271.5768) (xy 343.074498 -271.62125)
			(xy 343.121488 -271.77365) (xy 343.383108 -271.77365)
		)
		(stroke
			(width 0)
			(type solid)
		)
		(fill yes)
		(layer "In11.Cu")
		(net "M_D_CPU0_SA_DQ<20>")
	)
	(gr_poly
		(pts
			(xy 343.430098 -270.401542) (xy 343.383108 -270.249142) (xy 343.121488 -270.249142) (xy 343.074498 -270.401542)
			(xy 343.074498 -270.445992) (xy 343.430098 -270.445992)
		)
		(stroke
			(width 0)
			(type solid)
		)
		(fill yes)
		(layer "In11.Cu")
		(net "M_D_CPU0_SA_DQ<23>")
	)
	(gr_poly
		(pts
			(xy 343.430098 -269.993618) (xy 343.430098 -269.949168) (xy 343.074498 -269.949168) (xy 343.074498 -269.993618)
			(xy 343.121488 -270.146018) (xy 343.383108 -270.146018)
		)
		(stroke
			(width 0)
			(type solid)
		)
		(fill yes)
		(layer "In11.Cu")
		(net "M_D_CPU0_SA_DQ<24>")
	)
	(gr_poly
		(pts
			(xy 343.430098 -267.14577) (xy 343.383108 -266.99337) (xy 343.121488 -266.99337) (xy 343.074498 -267.14577)
			(xy 343.074498 -267.19022) (xy 343.430098 -267.19022)
		)
		(stroke
			(width 0)
			(type solid)
		)
		(fill yes)
		(layer "In11.Cu")
		(net "M_D_CPU0_SA_DQS_DP<8>")
	)
	(gr_poly
		(pts
			(xy 343.430098 -266.737846) (xy 343.430098 -266.69365) (xy 343.074498 -266.69365) (xy 343.074498 -266.737846)
			(xy 343.121488 -266.890246) (xy 343.383108 -266.890246)
		)
		(stroke
			(width 0)
			(type solid)
		)
		(fill yes)
		(layer "In11.Cu")
		(net "M_D_CPU0_SA_DQ<28>")
	)
	(gr_poly
		(pts
			(xy 343.430098 -265.518138) (xy 343.383108 -265.365738) (xy 343.121488 -265.365738) (xy 343.074498 -265.518138)
			(xy 343.074498 -265.562588) (xy 343.430098 -265.562588)
		)
		(stroke
			(width 0)
			(type solid)
		)
		(fill yes)
		(layer "In11.Cu")
		(net "M_D_CPU0_SA_DQ<31>")
	)
	(gr_poly
		(pts
			(xy 343.430098 -265.110214) (xy 343.430098 -265.065764) (xy 343.074498 -265.065764) (xy 343.074498 -265.110214)
			(xy 343.121488 -265.262614) (xy 343.383108 -265.262614)
		)
		(stroke
			(width 0)
			(type solid)
		)
		(fill yes)
		(layer "In11.Cu")
		(net "M_D_CPU0_SA_CB<0>")
	)
	(gr_poly
		(pts
			(xy 343.430098 -261.854442) (xy 343.430098 -261.810246) (xy 343.074498 -261.810246) (xy 343.074498 -261.854442)
			(xy 343.121488 -262.006842) (xy 343.383108 -262.006842)
		)
		(stroke
			(width 0)
			(type solid)
		)
		(fill yes)
		(layer "In11.Cu")
		(net "M_D_CPU0_SA_CB<4>")
	)
	(gr_poly
		(pts
			(xy 343.430098 -257.37947) (xy 343.383108 -257.22707) (xy 343.121488 -257.22707) (xy 343.074498 -257.37947)
			(xy 343.074498 -257.423666) (xy 343.430098 -257.423666)
		)
		(stroke
			(width 0)
			(type solid)
		)
		(fill yes)
		(layer "In11.Cu")
		(net "M_D_CPU0_SA_CA<1>")
	)
	(gr_poly
		(pts
			(xy 343.430098 -256.971038) (xy 343.430098 -256.926842) (xy 343.074498 -256.926842) (xy 343.074498 -256.971038)
			(xy 343.121488 -257.123438) (xy 343.383108 -257.123438)
		)
		(stroke
			(width 0)
			(type solid)
		)
		(fill yes)
		(layer "In11.Cu")
		(net "M_D_CPU0_SA_CA<2>")
	)
	(gr_poly
		(pts
			(xy 343.430098 -255.751838) (xy 343.383108 -255.599438) (xy 343.121488 -255.599438) (xy 343.074498 -255.751838)
			(xy 343.074498 -255.796034) (xy 343.430098 -255.796034)
		)
		(stroke
			(width 0)
			(type solid)
		)
		(fill yes)
		(layer "In11.Cu")
		(net "M_D_CPU0_SA_CA<5>")
	)
	(gr_poly
		(pts
			(xy 343.63279 -232.170224) (xy 343.671144 -232.148126) (xy 343.493344 -231.840278) (xy 343.45499 -231.862376)
			(xy 343.346532 -231.979216) (xy 343.477342 -232.205784)
		)
		(stroke
			(width 0)
			(type solid)
		)
		(fill yes)
		(layer "In11.Cu")
		(net "M_D_CPU0_SB_DQ<13>")
	)
	(gr_poly
		(pts
			(xy 343.63279 -230.542338) (xy 343.671144 -230.52024) (xy 343.493344 -230.212392) (xy 343.45499 -230.23449)
			(xy 343.346532 -230.35133) (xy 343.477342 -230.577898)
		)
		(stroke
			(width 0)
			(type solid)
		)
		(fill yes)
		(layer "In11.Cu")
		(net "M_D_CPU0_SB_DQ<24>")
	)
	(gr_poly
		(pts
			(xy 343.745058 -231.555544) (xy 343.853516 -231.438704) (xy 343.722706 -231.212136) (xy 343.567258 -231.247696)
			(xy 343.528904 -231.269794) (xy 343.706704 -231.577642)
		)
		(stroke
			(width 0)
			(type solid)
		)
		(fill yes)
		(layer "In11.Cu")
		(net "M_D_CPU0_SB_DQ<15>")
	)
	(gr_poly
		(pts
			(xy 343.746836 -229.929182) (xy 343.855294 -229.812342) (xy 343.724484 -229.585774) (xy 343.569036 -229.621334)
			(xy 343.530682 -229.643432) (xy 343.708482 -229.95128)
		)
		(stroke
			(width 0)
			(type solid)
		)
		(fill yes)
		(layer "In11.Cu")
		(net "M_D_CPU0_SB_DQ<26>")
	)
	(gr_poly
		(pts
			(xy 343.772998 -246.568722) (xy 343.726008 -246.416322) (xy 343.464388 -246.416322) (xy 343.417398 -246.568722)
			(xy 343.417398 -246.612918) (xy 343.772998 -246.612918)
		)
		(stroke
			(width 0)
			(type solid)
		)
		(fill yes)
		(layer "In11.Cu")
		(net "M_D_CPU0_SB_CB<6>")
	)
	(gr_poly
		(pts
			(xy 343.772998 -246.16029) (xy 343.772998 -246.116094) (xy 343.417398 -246.116094) (xy 343.417398 -246.16029)
			(xy 343.464388 -246.31269) (xy 343.726008 -246.31269)
		)
		(stroke
			(width 0)
			(type solid)
		)
		(fill yes)
		(layer "In11.Cu")
		(net "M_D_CPU0_SB_CB<5>")
	)
	(gr_poly
		(pts
			(xy 343.772998 -244.940582) (xy 343.726008 -244.788182) (xy 343.464388 -244.788182) (xy 343.417398 -244.940582)
			(xy 343.417398 -244.985032) (xy 343.772998 -244.985032)
		)
		(stroke
			(width 0)
			(type solid)
		)
		(fill yes)
		(layer "In11.Cu")
		(net "M_D_CPU0_SB_DQS_DN<9>")
	)
	(gr_poly
		(pts
			(xy 343.772998 -244.532658) (xy 343.772998 -244.488208) (xy 343.417398 -244.488208) (xy 343.417398 -244.532658)
			(xy 343.464388 -244.685058) (xy 343.726008 -244.685058)
		)
		(stroke
			(width 0)
			(type solid)
		)
		(fill yes)
		(layer "In11.Cu")
		(net "M_D_CPU0_SB_DQS_DN<4>")
	)
	(gr_poly
		(pts
			(xy 343.772998 -243.31295) (xy 343.726008 -243.16055) (xy 343.464388 -243.16055) (xy 343.417398 -243.31295)
			(xy 343.417398 -243.3574) (xy 343.772998 -243.3574)
		)
		(stroke
			(width 0)
			(type solid)
		)
		(fill yes)
		(layer "In11.Cu")
		(net "M_D_CPU0_SB_CB<2>")
	)
	(gr_poly
		(pts
			(xy 343.772998 -242.905026) (xy 343.772998 -242.860576) (xy 343.417398 -242.860576) (xy 343.417398 -242.905026)
			(xy 343.464388 -243.057426) (xy 343.726008 -243.057426)
		)
		(stroke
			(width 0)
			(type solid)
		)
		(fill yes)
		(layer "In11.Cu")
		(net "M_D_CPU0_SB_CB<1>")
	)
	(gr_poly
		(pts
			(xy 343.772998 -241.685318) (xy 343.726008 -241.532918) (xy 343.464388 -241.532918) (xy 343.417398 -241.685318)
			(xy 343.417398 -241.729514) (xy 343.772998 -241.729514)
		)
		(stroke
			(width 0)
			(type solid)
		)
		(fill yes)
		(layer "In11.Cu")
		(net "M_D_CPU0_SB_DQ<2>")
	)
	(gr_poly
		(pts
			(xy 343.772998 -241.276886) (xy 343.772998 -241.23269) (xy 343.417398 -241.23269) (xy 343.417398 -241.276886)
			(xy 343.464388 -241.429286) (xy 343.726008 -241.429286)
		)
		(stroke
			(width 0)
			(type solid)
		)
		(fill yes)
		(layer "In11.Cu")
		(net "M_D_CPU0_SB_DQ<1>")
	)
	(gr_poly
		(pts
			(xy 343.772998 -240.057178) (xy 343.726008 -239.904778) (xy 343.464388 -239.904778) (xy 343.417398 -240.057178)
			(xy 343.417398 -240.101628) (xy 343.772998 -240.101628)
		)
		(stroke
			(width 0)
			(type solid)
		)
		(fill yes)
		(layer "In11.Cu")
		(net "M_D_CPU0_SB_DQS_DN<0>")
	)
	(gr_poly
		(pts
			(xy 343.772998 -239.649254) (xy 343.772998 -239.604804) (xy 343.417398 -239.604804) (xy 343.417398 -239.649254)
			(xy 343.464388 -239.801654) (xy 343.726008 -239.801654)
		)
		(stroke
			(width 0)
			(type solid)
		)
		(fill yes)
		(layer "In11.Cu")
		(net "M_D_CPU0_SB_DQS_DN<5>")
	)
	(gr_poly
		(pts
			(xy 343.772998 -238.429546) (xy 343.726008 -238.277146) (xy 343.464388 -238.277146) (xy 343.417398 -238.429546)
			(xy 343.417398 -238.473996) (xy 343.772998 -238.473996)
		)
		(stroke
			(width 0)
			(type solid)
		)
		(fill yes)
		(layer "In11.Cu")
		(net "M_D_CPU0_SB_DQ<6>")
	)
	(gr_poly
		(pts
			(xy 343.772998 -238.021622) (xy 343.772998 -237.977172) (xy 343.417398 -237.977172) (xy 343.417398 -238.021622)
			(xy 343.464388 -238.174022) (xy 343.726008 -238.174022)
		)
		(stroke
			(width 0)
			(type solid)
		)
		(fill yes)
		(layer "In11.Cu")
		(net "M_D_CPU0_SB_DQ<5>")
	)
	(gr_poly
		(pts
			(xy 343.772998 -236.801914) (xy 343.726008 -236.649514) (xy 343.464388 -236.649514) (xy 343.417398 -236.801914)
			(xy 343.417398 -236.84611) (xy 343.772998 -236.84611)
		)
		(stroke
			(width 0)
			(type solid)
		)
		(fill yes)
		(layer "In11.Cu")
		(net "M_D_CPU0_SB_DQ<10>")
	)
	(gr_poly
		(pts
			(xy 343.772998 -236.39399) (xy 343.772998 -236.34954) (xy 343.417398 -236.34954) (xy 343.417398 -236.39399)
			(xy 343.464388 -236.54639) (xy 343.726008 -236.54639)
		)
		(stroke
			(width 0)
			(type solid)
		)
		(fill yes)
		(layer "In11.Cu")
		(net "M_D_CPU0_SB_DQ<9>")
	)
	(gr_poly
		(pts
			(xy 343.772998 -235.174282) (xy 343.726008 -235.021882) (xy 343.464388 -235.021882) (xy 343.417398 -235.174282)
			(xy 343.417398 -235.218478) (xy 343.772998 -235.218478)
		)
		(stroke
			(width 0)
			(type solid)
		)
		(fill yes)
		(layer "In11.Cu")
		(net "M_D_CPU0_SB_DQS_DN<1>")
	)
	(gr_poly
		(pts
			(xy 343.772998 -234.76585) (xy 343.772998 -234.721654) (xy 343.417398 -234.721654) (xy 343.417398 -234.76585)
			(xy 343.464388 -234.91825) (xy 343.726008 -234.91825)
		)
		(stroke
			(width 0)
			(type solid)
		)
		(fill yes)
		(layer "In11.Cu")
		(net "M_D_CPU0_SB_DQS_DN<6>")
	)
	(gr_poly
		(pts
			(xy 343.772998 -233.546142) (xy 343.726008 -233.393742) (xy 343.464388 -233.393742) (xy 343.417398 -233.546142)
			(xy 343.417398 -233.590592) (xy 343.772998 -233.590592)
		)
		(stroke
			(width 0)
			(type solid)
		)
		(fill yes)
		(layer "In11.Cu")
		(net "M_D_CPU0_SB_DQ<14>")
	)
	(gr_poly
		(pts
			(xy 343.772998 -228.663246) (xy 343.726008 -228.510846) (xy 343.464388 -228.510846) (xy 343.417398 -228.663246)
			(xy 343.417398 -228.707442) (xy 343.772998 -228.707442)
		)
		(stroke
			(width 0)
			(type solid)
		)
		(fill yes)
		(layer "In11.Cu")
		(net "M_D_CPU0_SB_DQ<27>")
	)
	(gr_poly
		(pts
			(xy 343.772998 -228.254814) (xy 343.772998 -228.210618) (xy 343.417398 -228.210618) (xy 343.417398 -228.254814)
			(xy 343.464388 -228.407214) (xy 343.726008 -228.407214)
		)
		(stroke
			(width 0)
			(type solid)
		)
		(fill yes)
		(layer "In11.Cu")
		(net "M_D_CPU0_SB_DQS_DP<3>")
	)
	(gr_poly
		(pts
			(xy 343.772998 -225.407474) (xy 343.726008 -225.255074) (xy 343.464388 -225.255074) (xy 343.417398 -225.407474)
			(xy 343.417398 -225.45167) (xy 343.772998 -225.45167)
		)
		(stroke
			(width 0)
			(type solid)
		)
		(fill yes)
		(layer "In11.Cu")
		(net "M_D_CPU0_SB_DQ<31>")
	)
	(gr_poly
		(pts
			(xy 343.775538 -247.787922) (xy 343.775538 -247.743726) (xy 343.419938 -247.743726) (xy 343.419938 -247.787922)
			(xy 343.466928 -247.940322) (xy 343.728548 -247.940322)
		)
		(stroke
			(width 0)
			(type solid)
		)
		(fill yes)
		(layer "In11.Cu")
		(net "M_D_CPU0_SB_CA<5>")
	)
	(gr_poly
		(pts
			(xy 343.775538 -226.627182) (xy 343.775538 -226.582732) (xy 343.419938 -226.582732) (xy 343.419938 -226.627182)
			(xy 343.466928 -226.779582) (xy 343.728548 -226.779582)
		)
		(stroke
			(width 0)
			(type solid)
		)
		(fill yes)
		(layer "In11.Cu")
		(net "M_D_CPU0_SB_DQ<28>")
	)
	(gr_poly
		(pts
			(xy 343.78138 -227.035614) (xy 343.73439 -226.883214) (xy 343.47277 -226.883214) (xy 343.42578 -227.035614)
			(xy 343.42578 -227.07981) (xy 343.78138 -227.07981)
		)
		(stroke
			(width 0)
			(type solid)
		)
		(fill yes)
		(layer "In11.Cu")
		(net "M_D_CPU0_SB_DQS_DP<8>")
	)
	(gr_poly
		(pts
			(xy 343.88298 -279.354534) (xy 343.83599 -279.202134) (xy 343.57437 -279.202134) (xy 343.52738 -279.354534)
			(xy 343.52738 -279.39873) (xy 343.88298 -279.39873)
		)
		(stroke
			(width 0)
			(type solid)
		)
		(fill yes)
		(layer "In11.Cu")
		(net "M_D_CPU0_SA_DQ<10>")
	)
	(gr_poly
		(pts
			(xy 343.88298 -278.946102) (xy 343.88298 -278.901906) (xy 343.52738 -278.901906) (xy 343.52738 -278.946102)
			(xy 343.57437 -279.098502) (xy 343.83599 -279.098502)
		)
		(stroke
			(width 0)
			(type solid)
		)
		(fill yes)
		(layer "In11.Cu")
		(net "M_D_CPU0_SA_DQ<9>")
	)
	(gr_poly
		(pts
			(xy 343.88298 -277.726394) (xy 343.83599 -277.573994) (xy 343.57437 -277.573994) (xy 343.52738 -277.726394)
			(xy 343.52738 -277.770844) (xy 343.88298 -277.770844)
		)
		(stroke
			(width 0)
			(type solid)
		)
		(fill yes)
		(layer "In11.Cu")
		(net "M_D_CPU0_SA_DQS_DN<1>")
	)
	(gr_poly
		(pts
			(xy 343.88298 -277.318216) (xy 343.88298 -277.27402) (xy 343.52738 -277.27402) (xy 343.52738 -277.318216)
			(xy 343.57437 -277.470616) (xy 343.83599 -277.470616)
		)
		(stroke
			(width 0)
			(type solid)
		)
		(fill yes)
		(layer "In11.Cu")
		(net "M_D_CPU0_SA_DQS_DN<6>")
	)
	(gr_poly
		(pts
			(xy 343.88298 -276.098762) (xy 343.83599 -275.946362) (xy 343.57437 -275.946362) (xy 343.52738 -276.098762)
			(xy 343.52738 -276.143212) (xy 343.88298 -276.143212)
		)
		(stroke
			(width 0)
			(type solid)
		)
		(fill yes)
		(layer "In11.Cu")
		(net "M_D_CPU0_SA_DQ<14>")
	)
	(gr_poly
		(pts
			(xy 343.88298 -275.690584) (xy 343.88298 -275.646388) (xy 343.52738 -275.646388) (xy 343.52738 -275.690584)
			(xy 343.57437 -275.842984) (xy 343.83599 -275.842984)
		)
		(stroke
			(width 0)
			(type solid)
		)
		(fill yes)
		(layer "In11.Cu")
		(net "M_D_CPU0_SA_DQ<13>")
	)
	(gr_poly
		(pts
			(xy 343.88298 -274.47113) (xy 343.83599 -274.31873) (xy 343.57437 -274.31873) (xy 343.52738 -274.47113)
			(xy 343.52738 -274.515326) (xy 343.88298 -274.515326)
		)
		(stroke
			(width 0)
			(type solid)
		)
		(fill yes)
		(layer "In11.Cu")
		(net "M_D_CPU0_SA_DQ<18>")
	)
	(gr_poly
		(pts
			(xy 343.88298 -274.062698) (xy 343.88298 -274.018502) (xy 343.52738 -274.018502) (xy 343.52738 -274.062698)
			(xy 343.57437 -274.215098) (xy 343.83599 -274.215098)
		)
		(stroke
			(width 0)
			(type solid)
		)
		(fill yes)
		(layer "In11.Cu")
		(net "M_D_CPU0_SA_DQ<17>")
	)
	(gr_poly
		(pts
			(xy 343.88298 -272.843498) (xy 343.83599 -272.691098) (xy 343.57437 -272.691098) (xy 343.52738 -272.843498)
			(xy 343.52738 -272.887694) (xy 343.88298 -272.887694)
		)
		(stroke
			(width 0)
			(type solid)
		)
		(fill yes)
		(layer "In11.Cu")
		(net "M_D_CPU0_SA_DQS_DN<2>")
	)
	(gr_poly
		(pts
			(xy 343.88298 -272.435066) (xy 343.88298 -272.39087) (xy 343.52738 -272.39087) (xy 343.52738 -272.435066)
			(xy 343.57437 -272.587466) (xy 343.83599 -272.587466)
		)
		(stroke
			(width 0)
			(type solid)
		)
		(fill yes)
		(layer "In11.Cu")
		(net "M_D_CPU0_SA_DQS_DN<7>")
	)
	(gr_poly
		(pts
			(xy 343.88298 -271.215358) (xy 343.83599 -271.062958) (xy 343.57437 -271.062958) (xy 343.52738 -271.215358)
			(xy 343.52738 -271.259808) (xy 343.88298 -271.259808)
		)
		(stroke
			(width 0)
			(type solid)
		)
		(fill yes)
		(layer "In11.Cu")
		(net "M_D_CPU0_SA_DQ<22>")
	)
	(gr_poly
		(pts
			(xy 343.88298 -270.807434) (xy 343.88298 -270.762984) (xy 343.52738 -270.762984) (xy 343.52738 -270.807434)
			(xy 343.57437 -270.959834) (xy 343.83599 -270.959834)
		)
		(stroke
			(width 0)
			(type solid)
		)
		(fill yes)
		(layer "In11.Cu")
		(net "M_D_CPU0_SA_DQ<21>")
	)
	(gr_poly
		(pts
			(xy 343.88298 -269.587726) (xy 343.83599 -269.435326) (xy 343.57437 -269.435326) (xy 343.52738 -269.587726)
			(xy 343.52738 -269.631922) (xy 343.88298 -269.631922)
		)
		(stroke
			(width 0)
			(type solid)
		)
		(fill yes)
		(layer "In11.Cu")
		(net "M_D_CPU0_SA_DQ<26>")
	)
	(gr_poly
		(pts
			(xy 343.88298 -267.960094) (xy 343.83599 -267.807694) (xy 343.57437 -267.807694) (xy 343.52738 -267.960094)
			(xy 343.52738 -268.00429) (xy 343.88298 -268.00429)
		)
		(stroke
			(width 0)
			(type solid)
		)
		(fill yes)
		(layer "In11.Cu")
		(net "M_D_CPU0_SA_DQS_DN<3>")
	)
	(gr_poly
		(pts
			(xy 343.88298 -267.551662) (xy 343.88298 -267.507466) (xy 343.52738 -267.507466) (xy 343.52738 -267.551662)
			(xy 343.57437 -267.704062) (xy 343.83599 -267.704062)
		)
		(stroke
			(width 0)
			(type solid)
		)
		(fill yes)
		(layer "In11.Cu")
		(net "M_D_CPU0_SA_DQS_DN<8>")
	)
	(gr_poly
		(pts
			(xy 343.88298 -266.331954) (xy 343.83599 -266.179554) (xy 343.57437 -266.179554) (xy 343.52738 -266.331954)
			(xy 343.52738 -266.376404) (xy 343.88298 -266.376404)
		)
		(stroke
			(width 0)
			(type solid)
		)
		(fill yes)
		(layer "In11.Cu")
		(net "M_D_CPU0_SA_DQ<30>")
	)
	(gr_poly
		(pts
			(xy 343.88298 -265.92403) (xy 343.88298 -265.87958) (xy 343.52738 -265.87958) (xy 343.52738 -265.92403)
			(xy 343.57437 -266.07643) (xy 343.83599 -266.07643)
		)
		(stroke
			(width 0)
			(type solid)
		)
		(fill yes)
		(layer "In11.Cu")
		(net "M_D_CPU0_SA_DQ<29>")
	)
	(gr_poly
		(pts
			(xy 343.88298 -264.704322) (xy 343.83599 -264.551922) (xy 343.57437 -264.551922) (xy 343.52738 -264.704322)
			(xy 343.52738 -264.748772) (xy 343.88298 -264.748772)
		)
		(stroke
			(width 0)
			(type solid)
		)
		(fill yes)
		(layer "In11.Cu")
		(net "M_D_CPU0_SA_CB<2>")
	)
	(gr_poly
		(pts
			(xy 343.88298 -264.296398) (xy 343.88298 -264.251948) (xy 343.52738 -264.251948) (xy 343.52738 -264.296398)
			(xy 343.57437 -264.448798) (xy 343.83599 -264.448798)
		)
		(stroke
			(width 0)
			(type solid)
		)
		(fill yes)
		(layer "In11.Cu")
		(net "M_D_CPU0_SA_CB<1>")
	)
	(gr_poly
		(pts
			(xy 343.88298 -263.07669) (xy 343.83599 -262.92429) (xy 343.57437 -262.92429) (xy 343.52738 -263.07669)
			(xy 343.52738 -263.120886) (xy 343.88298 -263.120886)
		)
		(stroke
			(width 0)
			(type solid)
		)
		(fill yes)
		(layer "In11.Cu")
		(net "M_D_CPU0_SA_DQS_DN<4>")
	)
	(gr_poly
		(pts
			(xy 343.88298 -261.449058) (xy 343.83599 -261.296658) (xy 343.57437 -261.296658) (xy 343.52738 -261.449058)
			(xy 343.52738 -261.493254) (xy 343.88298 -261.493254)
		)
		(stroke
			(width 0)
			(type solid)
		)
		(fill yes)
		(layer "In11.Cu")
		(net "M_D_CPU0_SA_CB<6>")
	)
	(gr_poly
		(pts
			(xy 343.88298 -261.040626) (xy 343.88298 -260.99643) (xy 343.52738 -260.99643) (xy 343.52738 -261.040626)
			(xy 343.57437 -261.193026) (xy 343.83599 -261.193026)
		)
		(stroke
			(width 0)
			(type solid)
		)
		(fill yes)
		(layer "In11.Cu")
		(net "M_D_CPU0_SA_CB<5>")
	)
	(gr_poly
		(pts
			(xy 343.88298 -259.412994) (xy 343.88298 -259.368544) (xy 343.52738 -259.368544) (xy 343.52738 -259.412994)
			(xy 343.57437 -259.565394) (xy 343.83599 -259.565394)
		)
		(stroke
			(width 0)
			(type solid)
		)
		(fill yes)
		(layer "In11.Cu")
		(net "M_D_CPU0_SA_CS_N<2>")
	)
	(gr_poly
		(pts
			(xy 343.88298 -258.193286) (xy 343.83599 -258.040886) (xy 343.57437 -258.040886) (xy 343.52738 -258.193286)
			(xy 343.52738 -258.237482) (xy 343.88298 -258.237482)
		)
		(stroke
			(width 0)
			(type solid)
		)
		(fill yes)
		(layer "In11.Cu")
		(net "M_D_CPU0_SA_CS_N<1>")
	)
	(gr_poly
		(pts
			(xy 343.88298 -257.784854) (xy 343.88298 -257.740658) (xy 343.52738 -257.740658) (xy 343.52738 -257.784854)
			(xy 343.57437 -257.937254) (xy 343.83599 -257.937254)
		)
		(stroke
			(width 0)
			(type solid)
		)
		(fill yes)
		(layer "In11.Cu")
		(net "M_D_CPU0_SA_CA<0>")
	)
	(gr_poly
		(pts
			(xy 343.88298 -256.565654) (xy 343.83599 -256.413254) (xy 343.57437 -256.413254) (xy 343.52738 -256.565654)
			(xy 343.52738 -256.60985) (xy 343.88298 -256.60985)
		)
		(stroke
			(width 0)
			(type solid)
		)
		(fill yes)
		(layer "In11.Cu")
		(net "M_D_CPU0_SA_CA<3>")
	)
	(gr_poly
		(pts
			(xy 343.88298 -256.157222) (xy 343.88298 -256.113026) (xy 343.52738 -256.113026) (xy 343.52738 -256.157222)
			(xy 343.57437 -256.309622) (xy 343.83599 -256.309622)
		)
		(stroke
			(width 0)
			(type solid)
		)
		(fill yes)
		(layer "In11.Cu")
		(net "M_D_CPU0_SA_CA<4>")
	)
	(gr_poly
		(pts
			(xy 343.894918 -269.179294) (xy 343.894918 -269.134844) (xy 343.539318 -269.134844) (xy 343.539318 -269.179294)
			(xy 343.586308 -269.331694) (xy 343.847928 -269.331694)
		)
		(stroke
			(width 0)
			(type solid)
		)
		(fill yes)
		(layer "In11.Cu")
		(net "M_D_CPU0_SA_DQ<25>")
	)
	(gr_poly
		(pts
			(xy 343.894918 -262.668258) (xy 343.894918 -262.623808) (xy 343.539318 -262.623808) (xy 343.539318 -262.668258)
			(xy 343.586308 -262.820658) (xy 343.847928 -262.820658)
		)
		(stroke
			(width 0)
			(type solid)
		)
		(fill yes)
		(layer "In11.Cu")
		(net "M_D_CPU0_SA_DQS_DN<9>")
	)
	(gr_poly
		(pts
			(xy 344.108278 -232.993692) (xy 344.146632 -232.971594) (xy 343.968832 -232.663746) (xy 343.930478 -232.685844)
			(xy 343.82202 -232.802684) (xy 343.95283 -233.029252)
		)
		(stroke
			(width 0)
			(type solid)
		)
		(fill yes)
		(layer "In11.Cu")
		(net "M_D_CPU0_SB_DQ<13>")
	)
	(gr_poly
		(pts
			(xy 344.108278 -229.738174) (xy 344.146632 -229.716076) (xy 343.968832 -229.408228) (xy 343.930478 -229.430326)
			(xy 343.82202 -229.547166) (xy 343.95283 -229.773734)
		)
		(stroke
			(width 0)
			(type solid)
		)
		(fill yes)
		(layer "In11.Cu")
		(net "M_D_CPU0_SB_DQ<25>")
	)
	(gr_poly
		(pts
			(xy 344.110056 -231.36733) (xy 344.14841 -231.345232) (xy 343.97061 -231.037384) (xy 343.932256 -231.059482)
			(xy 343.823798 -231.176322) (xy 343.954608 -231.40289)
		)
		(stroke
			(width 0)
			(type solid)
		)
		(fill yes)
		(layer "In11.Cu")
		(net "M_D_CPU0_SB_DQ<24>")
	)
	(gr_poly
		(pts
			(xy 344.222324 -232.380536) (xy 344.330782 -232.263696) (xy 344.199972 -232.037128) (xy 344.044524 -232.072688)
			(xy 344.00617 -232.094786) (xy 344.18397 -232.402634)
		)
		(stroke
			(width 0)
			(type solid)
		)
		(fill yes)
		(layer "In11.Cu")
		(net "M_D_CPU0_SB_DQ<15>")
	)
	(gr_poly
		(pts
			(xy 344.222324 -230.75265) (xy 344.330782 -230.63581) (xy 344.199972 -230.409242) (xy 344.044524 -230.444802)
			(xy 344.00617 -230.4669) (xy 344.18397 -230.774748)
		)
		(stroke
			(width 0)
			(type solid)
		)
		(fill yes)
		(layer "In11.Cu")
		(net "M_D_CPU0_SB_DQ<26>")
	)
	(gr_poly
		(pts
			(xy 344.222324 -229.125018) (xy 344.330782 -229.008178) (xy 344.199972 -228.78161) (xy 344.044524 -228.81717)
			(xy 344.00617 -228.839268) (xy 344.18397 -229.147116)
		)
		(stroke
			(width 0)
			(type solid)
		)
		(fill yes)
		(layer "In11.Cu")
		(net "M_D_CPU0_SB_DQ<27>")
	)
	(gr_poly
		(pts
			(xy 344.245438 -247.382538) (xy 344.198448 -247.230138) (xy 343.936828 -247.230138) (xy 343.889838 -247.382538)
			(xy 343.889838 -247.426988) (xy 344.245438 -247.426988)
		)
		(stroke
			(width 0)
			(type solid)
		)
		(fill yes)
		(layer "In11.Cu")
		(net "M_D_CPU0_SB_PAR")
	)
	(gr_poly
		(pts
			(xy 344.251534 -227.44049) (xy 344.251534 -227.396294) (xy 343.895934 -227.396294) (xy 343.895934 -227.44049)
			(xy 343.942924 -227.59289) (xy 344.204544 -227.59289)
		)
		(stroke
			(width 0)
			(type solid)
		)
		(fill yes)
		(layer "In11.Cu")
		(net "M_D_CPU0_SB_DQS_DN<8>")
	)
	(gr_poly
		(pts
			(xy 344.251534 -226.221798) (xy 344.204544 -226.069398) (xy 343.942924 -226.069398) (xy 343.895934 -226.221798)
			(xy 343.895934 -226.265994) (xy 344.251534 -226.265994)
		)
		(stroke
			(width 0)
			(type solid)
		)
		(fill yes)
		(layer "In11.Cu")
		(net "M_D_CPU0_SB_DQ<30>")
	)
	(gr_poly
		(pts
			(xy 344.257376 -246.974106) (xy 344.257376 -246.929656) (xy 343.901776 -246.929656) (xy 343.901776 -246.974106)
			(xy 343.948766 -247.126506) (xy 344.210386 -247.126506)
		)
		(stroke
			(width 0)
			(type solid)
		)
		(fill yes)
		(layer "In11.Cu")
		(net "M_D_CPU0_SB_CB<4>")
	)
	(gr_poly
		(pts
			(xy 344.259916 -245.754906) (xy 344.212926 -245.602506) (xy 343.951306 -245.602506) (xy 343.904316 -245.754906)
			(xy 343.904316 -245.799102) (xy 344.259916 -245.799102)
		)
		(stroke
			(width 0)
			(type solid)
		)
		(fill yes)
		(layer "In11.Cu")
		(net "M_D_CPU0_SB_CB<7>")
	)
	(gr_poly
		(pts
			(xy 344.259916 -245.346474) (xy 344.259916 -245.302278) (xy 343.904316 -245.302278) (xy 343.904316 -245.346474)
			(xy 343.951306 -245.498874) (xy 344.212926 -245.498874)
		)
		(stroke
			(width 0)
			(type solid)
		)
		(fill yes)
		(layer "In11.Cu")
		(net "M_D_CPU0_SB_DQS_DP<9>")
	)
	(gr_poly
		(pts
			(xy 344.259916 -244.126766) (xy 344.212926 -243.974366) (xy 343.951306 -243.974366) (xy 343.904316 -244.126766)
			(xy 343.904316 -244.171216) (xy 344.259916 -244.171216)
		)
		(stroke
			(width 0)
			(type solid)
		)
		(fill yes)
		(layer "In11.Cu")
		(net "M_D_CPU0_SB_DQS_DP<4>")
	)
	(gr_poly
		(pts
			(xy 344.259916 -243.718842) (xy 344.259916 -243.674392) (xy 343.904316 -243.674392) (xy 343.904316 -243.718842)
			(xy 343.951306 -243.871242) (xy 344.212926 -243.871242)
		)
		(stroke
			(width 0)
			(type solid)
		)
		(fill yes)
		(layer "In11.Cu")
		(net "M_D_CPU0_SB_CB<0>")
	)
	(gr_poly
		(pts
			(xy 344.259916 -242.499134) (xy 344.212926 -242.346734) (xy 343.951306 -242.346734) (xy 343.904316 -242.499134)
			(xy 343.904316 -242.54333) (xy 344.259916 -242.54333)
		)
		(stroke
			(width 0)
			(type solid)
		)
		(fill yes)
		(layer "In11.Cu")
		(net "M_D_CPU0_SB_CB<3>")
	)
	(gr_poly
		(pts
			(xy 344.259916 -242.090702) (xy 344.259916 -242.046506) (xy 343.904316 -242.046506) (xy 343.904316 -242.090702)
			(xy 343.951306 -242.243102) (xy 344.212926 -242.243102)
		)
		(stroke
			(width 0)
			(type solid)
		)
		(fill yes)
		(layer "In11.Cu")
		(net "M_D_CPU0_SB_DQ<0>")
	)
	(gr_poly
		(pts
			(xy 344.259916 -240.871502) (xy 344.212926 -240.719102) (xy 343.951306 -240.719102) (xy 343.904316 -240.871502)
			(xy 343.904316 -240.915698) (xy 344.259916 -240.915698)
		)
		(stroke
			(width 0)
			(type solid)
		)
		(fill yes)
		(layer "In11.Cu")
		(net "M_D_CPU0_SB_DQ<3>")
	)
	(gr_poly
		(pts
			(xy 344.259916 -240.46307) (xy 344.259916 -240.418874) (xy 343.904316 -240.418874) (xy 343.904316 -240.46307)
			(xy 343.951306 -240.61547) (xy 344.212926 -240.61547)
		)
		(stroke
			(width 0)
			(type solid)
		)
		(fill yes)
		(layer "In11.Cu")
		(net "M_D_CPU0_SB_DQS_DP<0>")
	)
	(gr_poly
		(pts
			(xy 344.259916 -239.243362) (xy 344.212926 -239.090962) (xy 343.951306 -239.090962) (xy 343.904316 -239.243362)
			(xy 343.904316 -239.287812) (xy 344.259916 -239.287812)
		)
		(stroke
			(width 0)
			(type solid)
		)
		(fill yes)
		(layer "In11.Cu")
		(net "M_D_CPU0_SB_DQS_DP<5>")
	)
	(gr_poly
		(pts
			(xy 344.259916 -238.835438) (xy 344.259916 -238.790988) (xy 343.904316 -238.790988) (xy 343.904316 -238.835438)
			(xy 343.951306 -238.987838) (xy 344.212926 -238.987838)
		)
		(stroke
			(width 0)
			(type solid)
		)
		(fill yes)
		(layer "In11.Cu")
		(net "M_D_CPU0_SB_DQ<4>")
	)
	(gr_poly
		(pts
			(xy 344.259916 -237.61573) (xy 344.212926 -237.46333) (xy 343.951306 -237.46333) (xy 343.904316 -237.61573)
			(xy 343.904316 -237.66018) (xy 344.259916 -237.66018)
		)
		(stroke
			(width 0)
			(type solid)
		)
		(fill yes)
		(layer "In11.Cu")
		(net "M_D_CPU0_SB_DQ<7>")
	)
	(gr_poly
		(pts
			(xy 344.259916 -237.207806) (xy 344.259916 -237.163356) (xy 343.904316 -237.163356) (xy 343.904316 -237.207806)
			(xy 343.951306 -237.360206) (xy 344.212926 -237.360206)
		)
		(stroke
			(width 0)
			(type solid)
		)
		(fill yes)
		(layer "In11.Cu")
		(net "M_D_CPU0_SB_DQ<8>")
	)
	(gr_poly
		(pts
			(xy 344.259916 -235.988098) (xy 344.212926 -235.835698) (xy 343.951306 -235.835698) (xy 343.904316 -235.988098)
			(xy 343.904316 -236.032294) (xy 344.259916 -236.032294)
		)
		(stroke
			(width 0)
			(type solid)
		)
		(fill yes)
		(layer "In11.Cu")
		(net "M_D_CPU0_SB_DQ<11>")
	)
	(gr_poly
		(pts
			(xy 344.259916 -235.579666) (xy 344.259916 -235.53547) (xy 343.904316 -235.53547) (xy 343.904316 -235.579666)
			(xy 343.951306 -235.732066) (xy 344.212926 -235.732066)
		)
		(stroke
			(width 0)
			(type solid)
		)
		(fill yes)
		(layer "In11.Cu")
		(net "M_D_CPU0_SB_DQS_DP<1>")
	)
	(gr_poly
		(pts
			(xy 344.259916 -234.360466) (xy 344.212926 -234.208066) (xy 343.951306 -234.208066) (xy 343.904316 -234.360466)
			(xy 343.904316 -234.404662) (xy 344.259916 -234.404662)
		)
		(stroke
			(width 0)
			(type solid)
		)
		(fill yes)
		(layer "In11.Cu")
		(net "M_D_CPU0_SB_DQS_DP<6>")
	)
	(gr_poly
		(pts
			(xy 344.259916 -233.952034) (xy 344.259916 -233.907838) (xy 343.904316 -233.907838) (xy 343.904316 -233.952034)
			(xy 343.951306 -234.104434) (xy 344.212926 -234.104434)
		)
		(stroke
			(width 0)
			(type solid)
		)
		(fill yes)
		(layer "In11.Cu")
		(net "M_D_CPU0_SB_DQ<12>")
	)
	(gr_poly
		(pts
			(xy 344.259916 -227.848922) (xy 344.212926 -227.696522) (xy 343.951306 -227.696522) (xy 343.904316 -227.848922)
			(xy 343.904316 -227.893372) (xy 344.259916 -227.893372)
		)
		(stroke
			(width 0)
			(type solid)
		)
		(fill yes)
		(layer "In11.Cu")
		(net "M_D_CPU0_SB_DQS_DN<3>")
	)
	(gr_poly
		(pts
			(xy 344.259916 -225.813366) (xy 344.259916 -225.768916) (xy 343.904316 -225.768916) (xy 343.904316 -225.813366)
			(xy 343.951306 -225.965766) (xy 344.212926 -225.965766)
		)
		(stroke
			(width 0)
			(type solid)
		)
		(fill yes)
		(layer "In11.Cu")
		(net "M_D_CPU0_SB_DQ<29>")
	)
	(gr_poly
		(pts
			(xy 344.35796 -270.40205) (xy 344.31097 -270.24965) (xy 344.04935 -270.24965) (xy 344.00236 -270.40205)
			(xy 344.00236 -270.446246) (xy 344.35796 -270.446246)
		)
		(stroke
			(width 0)
			(type solid)
		)
		(fill yes)
		(layer "In11.Cu")
		(net "M_D_CPU0_SA_DQ<23>")
	)
	(gr_poly
		(pts
			(xy 344.35796 -268.77391) (xy 344.31097 -268.62151) (xy 344.04935 -268.62151) (xy 344.00236 -268.77391)
			(xy 344.00236 -268.81836) (xy 344.35796 -268.81836)
		)
		(stroke
			(width 0)
			(type solid)
		)
		(fill yes)
		(layer "In11.Cu")
		(net "M_D_CPU0_SA_DQ<27>")
	)
	(gr_poly
		(pts
			(xy 344.35796 -262.262874) (xy 344.31097 -262.110474) (xy 344.04935 -262.110474) (xy 344.00236 -262.262874)
			(xy 344.00236 -262.307324) (xy 344.35796 -262.307324)
		)
		(stroke
			(width 0)
			(type solid)
		)
		(fill yes)
		(layer "In11.Cu")
		(net "M_D_CPU0_SA_DQS_DP<9>")
	)
	(gr_poly
		(pts
			(xy 344.361262 -260.635242) (xy 344.314272 -260.482842) (xy 344.052652 -260.482842) (xy 344.005662 -260.635242)
			(xy 344.005662 -260.679438) (xy 344.361262 -260.679438)
		)
		(stroke
			(width 0)
			(type solid)
		)
		(fill yes)
		(layer "In11.Cu")
		(net "M_D_CPU0_SA_CB<7>")
	)
	(gr_poly
		(pts
			(xy 344.369898 -279.759918) (xy 344.369898 -279.715722) (xy 344.014298 -279.715722) (xy 344.014298 -279.759918)
			(xy 344.061288 -279.912318) (xy 344.322908 -279.912318)
		)
		(stroke
			(width 0)
			(type solid)
		)
		(fill yes)
		(layer "In11.Cu")
		(net "M_D_CPU0_SA_DQ<8>")
	)
	(gr_poly
		(pts
			(xy 344.369898 -278.540718) (xy 344.322908 -278.388318) (xy 344.061288 -278.388318) (xy 344.014298 -278.540718)
			(xy 344.014298 -278.584914) (xy 344.369898 -278.584914)
		)
		(stroke
			(width 0)
			(type solid)
		)
		(fill yes)
		(layer "In11.Cu")
		(net "M_D_CPU0_SA_DQ<11>")
	)
	(gr_poly
		(pts
			(xy 344.369898 -278.132286) (xy 344.369898 -278.08809) (xy 344.014298 -278.08809) (xy 344.014298 -278.132286)
			(xy 344.061288 -278.284686) (xy 344.322908 -278.284686)
		)
		(stroke
			(width 0)
			(type solid)
		)
		(fill yes)
		(layer "In11.Cu")
		(net "M_D_CPU0_SA_DQS_DP<1>")
	)
	(gr_poly
		(pts
			(xy 344.369898 -276.912578) (xy 344.322908 -276.760178) (xy 344.061288 -276.760178) (xy 344.014298 -276.912578)
			(xy 344.014298 -276.957028) (xy 344.369898 -276.957028)
		)
		(stroke
			(width 0)
			(type solid)
		)
		(fill yes)
		(layer "In11.Cu")
		(net "M_D_CPU0_SA_DQS_DP<6>")
	)
	(gr_poly
		(pts
			(xy 344.369898 -276.5044) (xy 344.369898 -276.460204) (xy 344.014298 -276.460204) (xy 344.014298 -276.5044)
			(xy 344.061288 -276.6568) (xy 344.322908 -276.6568)
		)
		(stroke
			(width 0)
			(type solid)
		)
		(fill yes)
		(layer "In11.Cu")
		(net "M_D_CPU0_SA_DQ<12>")
	)
	(gr_poly
		(pts
			(xy 344.369898 -275.284946) (xy 344.322908 -275.132546) (xy 344.061288 -275.132546) (xy 344.014298 -275.284946)
			(xy 344.014298 -275.329142) (xy 344.369898 -275.329142)
		)
		(stroke
			(width 0)
			(type solid)
		)
		(fill yes)
		(layer "In11.Cu")
		(net "M_D_CPU0_SA_DQ<15>")
	)
	(gr_poly
		(pts
			(xy 344.369898 -274.876514) (xy 344.369898 -274.832318) (xy 344.014298 -274.832318) (xy 344.014298 -274.876514)
			(xy 344.061288 -275.028914) (xy 344.322908 -275.028914)
		)
		(stroke
			(width 0)
			(type solid)
		)
		(fill yes)
		(layer "In11.Cu")
		(net "M_D_CPU0_SA_DQ<16>")
	)
	(gr_poly
		(pts
			(xy 344.369898 -273.657314) (xy 344.322908 -273.504914) (xy 344.061288 -273.504914) (xy 344.014298 -273.657314)
			(xy 344.014298 -273.70151) (xy 344.369898 -273.70151)
		)
		(stroke
			(width 0)
			(type solid)
		)
		(fill yes)
		(layer "In11.Cu")
		(net "M_D_CPU0_SA_DQ<19>")
	)
	(gr_poly
		(pts
			(xy 344.369898 -273.248882) (xy 344.369898 -273.204686) (xy 344.014298 -273.204686) (xy 344.014298 -273.248882)
			(xy 344.061288 -273.401282) (xy 344.322908 -273.401282)
		)
		(stroke
			(width 0)
			(type solid)
		)
		(fill yes)
		(layer "In11.Cu")
		(net "M_D_CPU0_SA_DQS_DP<2>")
	)
	(gr_poly
		(pts
			(xy 344.369898 -272.029174) (xy 344.322908 -271.876774) (xy 344.061288 -271.876774) (xy 344.014298 -272.029174)
			(xy 344.014298 -272.073624) (xy 344.369898 -272.073624)
		)
		(stroke
			(width 0)
			(type solid)
		)
		(fill yes)
		(layer "In11.Cu")
		(net "M_D_CPU0_SA_DQS_DP<7>")
	)
	(gr_poly
		(pts
			(xy 344.369898 -271.62125) (xy 344.369898 -271.5768) (xy 344.014298 -271.5768) (xy 344.014298 -271.62125)
			(xy 344.061288 -271.77365) (xy 344.322908 -271.77365)
		)
		(stroke
			(width 0)
			(type solid)
		)
		(fill yes)
		(layer "In11.Cu")
		(net "M_D_CPU0_SA_DQ<20>")
	)
	(gr_poly
		(pts
			(xy 344.369898 -269.993618) (xy 344.369898 -269.949168) (xy 344.014298 -269.949168) (xy 344.014298 -269.993618)
			(xy 344.061288 -270.146018) (xy 344.322908 -270.146018)
		)
		(stroke
			(width 0)
			(type solid)
		)
		(fill yes)
		(layer "In11.Cu")
		(net "M_D_CPU0_SA_DQ<24>")
	)
	(gr_poly
		(pts
			(xy 344.369898 -268.365478) (xy 344.369898 -268.321282) (xy 344.014298 -268.321282) (xy 344.014298 -268.365478)
			(xy 344.061288 -268.517878) (xy 344.322908 -268.517878)
		)
		(stroke
			(width 0)
			(type solid)
		)
		(fill yes)
		(layer "In11.Cu")
		(net "M_D_CPU0_SA_DQS_DP<3>")
	)
	(gr_poly
		(pts
			(xy 344.369898 -267.14577) (xy 344.322908 -266.99337) (xy 344.061288 -266.99337) (xy 344.014298 -267.14577)
			(xy 344.014298 -267.19022) (xy 344.369898 -267.19022)
		)
		(stroke
			(width 0)
			(type solid)
		)
		(fill yes)
		(layer "In11.Cu")
		(net "M_D_CPU0_SA_DQS_DP<8>")
	)
	(gr_poly
		(pts
			(xy 344.369898 -266.737846) (xy 344.369898 -266.69365) (xy 344.014298 -266.69365) (xy 344.014298 -266.737846)
			(xy 344.061288 -266.890246) (xy 344.322908 -266.890246)
		)
		(stroke
			(width 0)
			(type solid)
		)
		(fill yes)
		(layer "In11.Cu")
		(net "M_D_CPU0_SA_DQ<28>")
	)
	(gr_poly
		(pts
			(xy 344.369898 -265.518138) (xy 344.322908 -265.365738) (xy 344.061288 -265.365738) (xy 344.014298 -265.518138)
			(xy 344.014298 -265.562588) (xy 344.369898 -265.562588)
		)
		(stroke
			(width 0)
			(type solid)
		)
		(fill yes)
		(layer "In11.Cu")
		(net "M_D_CPU0_SA_DQ<31>")
	)
	(gr_poly
		(pts
			(xy 344.369898 -265.110214) (xy 344.369898 -265.065764) (xy 344.014298 -265.065764) (xy 344.014298 -265.110214)
			(xy 344.061288 -265.262614) (xy 344.322908 -265.262614)
		)
		(stroke
			(width 0)
			(type solid)
		)
		(fill yes)
		(layer "In11.Cu")
		(net "M_D_CPU0_SA_CB<0>")
	)
	(gr_poly
		(pts
			(xy 344.369898 -263.890506) (xy 344.322908 -263.738106) (xy 344.061288 -263.738106) (xy 344.014298 -263.890506)
			(xy 344.014298 -263.934956) (xy 344.369898 -263.934956)
		)
		(stroke
			(width 0)
			(type solid)
		)
		(fill yes)
		(layer "In11.Cu")
		(net "M_D_CPU0_SA_CB<3>")
	)
	(gr_poly
		(pts
			(xy 344.369898 -263.482582) (xy 344.369898 -263.438132) (xy 344.014298 -263.438132) (xy 344.014298 -263.482582)
			(xy 344.061288 -263.634982) (xy 344.322908 -263.634982)
		)
		(stroke
			(width 0)
			(type solid)
		)
		(fill yes)
		(layer "In11.Cu")
		(net "M_D_CPU0_SA_DQS_DP<4>")
	)
	(gr_poly
		(pts
			(xy 344.369898 -261.854442) (xy 344.369898 -261.810246) (xy 344.014298 -261.810246) (xy 344.014298 -261.854442)
			(xy 344.061288 -262.006842) (xy 344.322908 -262.006842)
		)
		(stroke
			(width 0)
			(type solid)
		)
		(fill yes)
		(layer "In11.Cu")
		(net "M_D_CPU0_SA_CB<4>")
	)
	(gr_poly
		(pts
			(xy 344.369898 -259.007102) (xy 344.322908 -258.854702) (xy 344.061288 -258.854702) (xy 344.014298 -259.007102)
			(xy 344.014298 -259.051552) (xy 344.369898 -259.051552)
		)
		(stroke
			(width 0)
			(type solid)
		)
		(fill yes)
		(layer "In11.Cu")
		(net "M_D_CPU0_SA_CS_N<0>")
	)
	(gr_poly
		(pts
			(xy 344.369898 -258.599178) (xy 344.369898 -258.554728) (xy 344.014298 -258.554728) (xy 344.014298 -258.599178)
			(xy 344.061288 -258.751578) (xy 344.322908 -258.751578)
		)
		(stroke
			(width 0)
			(type solid)
		)
		(fill yes)
		(layer "In11.Cu")
		(net "M_D_CPU0_SA_CS_N<3>")
	)
	(gr_poly
		(pts
			(xy 344.369898 -257.37947) (xy 344.322908 -257.22707) (xy 344.061288 -257.22707) (xy 344.014298 -257.37947)
			(xy 344.014298 -257.423666) (xy 344.369898 -257.423666)
		)
		(stroke
			(width 0)
			(type solid)
		)
		(fill yes)
		(layer "In11.Cu")
		(net "M_D_CPU0_SA_CA<1>")
	)
	(gr_poly
		(pts
			(xy 344.369898 -256.971038) (xy 344.369898 -256.926842) (xy 344.014298 -256.926842) (xy 344.014298 -256.971038)
			(xy 344.061288 -257.123438) (xy 344.322908 -257.123438)
		)
		(stroke
			(width 0)
			(type solid)
		)
		(fill yes)
		(layer "In11.Cu")
		(net "M_D_CPU0_SA_CA<2>")
	)
	(gr_poly
		(pts
			(xy 344.369898 -255.751838) (xy 344.322908 -255.599438) (xy 344.061288 -255.599438) (xy 344.014298 -255.751838)
			(xy 344.014298 -255.796034) (xy 344.369898 -255.796034)
		)
		(stroke
			(width 0)
			(type solid)
		)
		(fill yes)
		(layer "In11.Cu")
		(net "M_D_CPU0_SA_CA<5>")
	)
	(gr_poly
		(pts
			(xy 344.570812 -230.53929) (xy 344.609166 -230.517192) (xy 344.431366 -230.209344) (xy 344.393012 -230.231442)
			(xy 344.284554 -230.348282) (xy 344.415364 -230.57485)
		)
		(stroke
			(width 0)
			(type solid)
		)
		(fill yes)
		(layer "In11.Cu")
		(net "M_D_CPU0_SB_DQ<25>")
	)
	(gr_poly
		(pts
			(xy 344.57259 -232.170224) (xy 344.610944 -232.148126) (xy 344.433144 -231.840278) (xy 344.39479 -231.862376)
			(xy 344.286332 -231.979216) (xy 344.417142 -232.205784)
		)
		(stroke
			(width 0)
			(type solid)
		)
		(fill yes)
		(layer "In11.Cu")
		(net "M_D_CPU0_SB_DQ<24>")
	)
	(gr_poly
		(pts
			(xy 344.57259 -228.914706) (xy 344.610944 -228.892608) (xy 344.433144 -228.58476) (xy 344.39479 -228.606858)
			(xy 344.286332 -228.723698) (xy 344.417142 -228.950266)
		)
		(stroke
			(width 0)
			(type solid)
		)
		(fill yes)
		(layer "In11.Cu")
		(net "M_D_CPU0_SB_DQS_DP<3>")
	)
	(gr_poly
		(pts
			(xy 344.684858 -231.555544) (xy 344.793316 -231.438704) (xy 344.662506 -231.212136) (xy 344.507058 -231.247696)
			(xy 344.468704 -231.269794) (xy 344.646504 -231.577642)
		)
		(stroke
			(width 0)
			(type solid)
		)
		(fill yes)
		(layer "In11.Cu")
		(net "M_D_CPU0_SB_DQ<26>")
	)
	(gr_poly
		(pts
			(xy 344.684858 -228.300026) (xy 344.793316 -228.183186) (xy 344.662506 -227.956618) (xy 344.507058 -227.992178)
			(xy 344.468704 -228.014276) (xy 344.646504 -228.322124)
		)
		(stroke
			(width 0)
			(type solid)
		)
		(fill yes)
		(layer "In11.Cu")
		(net "M_D_CPU0_SB_DQS_DN<3>")
	)
	(gr_poly
		(pts
			(xy 344.692224 -229.939088) (xy 344.800682 -229.822248) (xy 344.669872 -229.59568) (xy 344.514424 -229.63124)
			(xy 344.47607 -229.653338) (xy 344.65387 -229.961186)
		)
		(stroke
			(width 0)
			(type solid)
		)
		(fill yes)
		(layer "In11.Cu")
		(net "M_D_CPU0_SB_DQ<27>")
	)
	(gr_poly
		(pts
			(xy 344.712798 -246.16029) (xy 344.712798 -246.116094) (xy 344.357198 -246.116094) (xy 344.357198 -246.16029)
			(xy 344.404188 -246.31269) (xy 344.665808 -246.31269)
		)
		(stroke
			(width 0)
			(type solid)
		)
		(fill yes)
		(layer "In11.Cu")
		(net "M_D_CPU0_SB_CB<5>")
	)
	(gr_poly
		(pts
			(xy 344.712798 -243.31295) (xy 344.665808 -243.16055) (xy 344.404188 -243.16055) (xy 344.357198 -243.31295)
			(xy 344.357198 -243.3574) (xy 344.712798 -243.3574)
		)
		(stroke
			(width 0)
			(type solid)
		)
		(fill yes)
		(layer "In11.Cu")
		(net "M_D_CPU0_SB_CB<2>")
	)
	(gr_poly
		(pts
			(xy 344.712798 -242.905026) (xy 344.712798 -242.860576) (xy 344.357198 -242.860576) (xy 344.357198 -242.905026)
			(xy 344.404188 -243.057426) (xy 344.665808 -243.057426)
		)
		(stroke
			(width 0)
			(type solid)
		)
		(fill yes)
		(layer "In11.Cu")
		(net "M_D_CPU0_SB_CB<1>")
	)
	(gr_poly
		(pts
			(xy 344.712798 -241.685318) (xy 344.665808 -241.532918) (xy 344.404188 -241.532918) (xy 344.357198 -241.685318)
			(xy 344.357198 -241.729514) (xy 344.712798 -241.729514)
		)
		(stroke
			(width 0)
			(type solid)
		)
		(fill yes)
		(layer "In11.Cu")
		(net "M_D_CPU0_SB_DQ<2>")
	)
	(gr_poly
		(pts
			(xy 344.712798 -241.276886) (xy 344.712798 -241.23269) (xy 344.357198 -241.23269) (xy 344.357198 -241.276886)
			(xy 344.404188 -241.429286) (xy 344.665808 -241.429286)
		)
		(stroke
			(width 0)
			(type solid)
		)
		(fill yes)
		(layer "In11.Cu")
		(net "M_D_CPU0_SB_DQ<1>")
	)
	(gr_poly
		(pts
			(xy 344.712798 -238.429546) (xy 344.665808 -238.277146) (xy 344.404188 -238.277146) (xy 344.357198 -238.429546)
			(xy 344.357198 -238.473996) (xy 344.712798 -238.473996)
		)
		(stroke
			(width 0)
			(type solid)
		)
		(fill yes)
		(layer "In11.Cu")
		(net "M_D_CPU0_SB_DQ<6>")
	)
	(gr_poly
		(pts
			(xy 344.712798 -238.021622) (xy 344.712798 -237.977172) (xy 344.357198 -237.977172) (xy 344.357198 -238.021622)
			(xy 344.404188 -238.174022) (xy 344.665808 -238.174022)
		)
		(stroke
			(width 0)
			(type solid)
		)
		(fill yes)
		(layer "In11.Cu")
		(net "M_D_CPU0_SB_DQ<5>")
	)
	(gr_poly
		(pts
			(xy 344.712798 -236.801914) (xy 344.665808 -236.649514) (xy 344.404188 -236.649514) (xy 344.357198 -236.801914)
			(xy 344.357198 -236.84611) (xy 344.712798 -236.84611)
		)
		(stroke
			(width 0)
			(type solid)
		)
		(fill yes)
		(layer "In11.Cu")
		(net "M_D_CPU0_SB_DQ<10>")
	)
	(gr_poly
		(pts
			(xy 344.712798 -236.39399) (xy 344.712798 -236.34954) (xy 344.357198 -236.34954) (xy 344.357198 -236.39399)
			(xy 344.404188 -236.54639) (xy 344.665808 -236.54639)
		)
		(stroke
			(width 0)
			(type solid)
		)
		(fill yes)
		(layer "In11.Cu")
		(net "M_D_CPU0_SB_DQ<9>")
	)
	(gr_poly
		(pts
			(xy 344.712798 -233.546142) (xy 344.665808 -233.393742) (xy 344.404188 -233.393742) (xy 344.357198 -233.546142)
			(xy 344.357198 -233.590592) (xy 344.712798 -233.590592)
		)
		(stroke
			(width 0)
			(type solid)
		)
		(fill yes)
		(layer "In11.Cu")
		(net "M_D_CPU0_SB_DQ<14>")
	)
	(gr_poly
		(pts
			(xy 344.712798 -233.138218) (xy 344.712798 -233.093768) (xy 344.357198 -233.093768) (xy 344.357198 -233.138218)
			(xy 344.404188 -233.290618) (xy 344.665808 -233.290618)
		)
		(stroke
			(width 0)
			(type solid)
		)
		(fill yes)
		(layer "In11.Cu")
		(net "M_D_CPU0_SB_DQ<13>")
	)
	(gr_poly
		(pts
			(xy 344.712798 -225.407474) (xy 344.665808 -225.255074) (xy 344.404188 -225.255074) (xy 344.357198 -225.407474)
			(xy 344.357198 -225.45167) (xy 344.712798 -225.45167)
		)
		(stroke
			(width 0)
			(type solid)
		)
		(fill yes)
		(layer "In11.Cu")
		(net "M_D_CPU0_SB_DQ<31>")
	)
	(gr_poly
		(pts
			(xy 344.715338 -244.940582) (xy 344.668348 -244.788182) (xy 344.406728 -244.788182) (xy 344.359738 -244.940582)
			(xy 344.359738 -244.985032) (xy 344.715338 -244.985032)
		)
		(stroke
			(width 0)
			(type solid)
		)
		(fill yes)
		(layer "In11.Cu")
		(net "M_D_CPU0_SB_DQS_DN<9>")
	)
	(gr_poly
		(pts
			(xy 344.715338 -244.532658) (xy 344.715338 -244.488208) (xy 344.359738 -244.488208) (xy 344.359738 -244.532658)
			(xy 344.406728 -244.685058) (xy 344.668348 -244.685058)
		)
		(stroke
			(width 0)
			(type solid)
		)
		(fill yes)
		(layer "In11.Cu")
		(net "M_D_CPU0_SB_DQS_DN<4>")
	)
	(gr_poly
		(pts
			(xy 344.715338 -240.057178) (xy 344.668348 -239.904778) (xy 344.406728 -239.904778) (xy 344.359738 -240.057178)
			(xy 344.359738 -240.101628) (xy 344.715338 -240.101628)
		)
		(stroke
			(width 0)
			(type solid)
		)
		(fill yes)
		(layer "In11.Cu")
		(net "M_D_CPU0_SB_DQS_DN<0>")
	)
	(gr_poly
		(pts
			(xy 344.715338 -239.649254) (xy 344.715338 -239.604804) (xy 344.359738 -239.604804) (xy 344.359738 -239.649254)
			(xy 344.406728 -239.801654) (xy 344.668348 -239.801654)
		)
		(stroke
			(width 0)
			(type solid)
		)
		(fill yes)
		(layer "In11.Cu")
		(net "M_D_CPU0_SB_DQS_DN<5>")
	)
	(gr_poly
		(pts
			(xy 344.715338 -235.174282) (xy 344.668348 -235.021882) (xy 344.406728 -235.021882) (xy 344.359738 -235.174282)
			(xy 344.359738 -235.218478) (xy 344.715338 -235.218478)
		)
		(stroke
			(width 0)
			(type solid)
		)
		(fill yes)
		(layer "In11.Cu")
		(net "M_D_CPU0_SB_DQS_DN<1>")
	)
	(gr_poly
		(pts
			(xy 344.715338 -234.76585) (xy 344.715338 -234.721654) (xy 344.359738 -234.721654) (xy 344.359738 -234.76585)
			(xy 344.406728 -234.91825) (xy 344.668348 -234.91825)
		)
		(stroke
			(width 0)
			(type solid)
		)
		(fill yes)
		(layer "In11.Cu")
		(net "M_D_CPU0_SB_DQS_DN<6>")
	)
	(gr_poly
		(pts
			(xy 344.715338 -227.035614) (xy 344.668348 -226.883214) (xy 344.406728 -226.883214) (xy 344.359738 -227.035614)
			(xy 344.359738 -227.07981) (xy 344.715338 -227.07981)
		)
		(stroke
			(width 0)
			(type solid)
		)
		(fill yes)
		(layer "In11.Cu")
		(net "M_D_CPU0_SB_DQS_DP<8>")
	)
	(gr_poly
		(pts
			(xy 344.715338 -226.626674) (xy 344.715338 -226.582478) (xy 344.359738 -226.582478) (xy 344.359738 -226.626674)
			(xy 344.406728 -226.779074) (xy 344.668348 -226.779074)
		)
		(stroke
			(width 0)
			(type solid)
		)
		(fill yes)
		(layer "In11.Cu")
		(net "M_D_CPU0_SB_DQ<28>")
	)
	(gr_poly
		(pts
			(xy 344.72118 -246.568722) (xy 344.67419 -246.416322) (xy 344.41257 -246.416322) (xy 344.36558 -246.568722)
			(xy 344.36558 -246.613172) (xy 344.72118 -246.613172)
		)
		(stroke
			(width 0)
			(type solid)
		)
		(fill yes)
		(layer "In11.Cu")
		(net "M_D_CPU0_SB_CB<6>")
	)
	(gr_poly
		(pts
			(xy 344.727276 -247.787922) (xy 344.727276 -247.743472) (xy 344.371676 -247.743472) (xy 344.371676 -247.787922)
			(xy 344.418666 -247.940322) (xy 344.680286 -247.940322)
		)
		(stroke
			(width 0)
			(type solid)
		)
		(fill yes)
		(layer "In11.Cu")
		(net "M_D_CPU0_SB_CA<5>")
	)
	(gr_poly
		(pts
			(xy 344.82278 -279.354534) (xy 344.77579 -279.202134) (xy 344.51417 -279.202134) (xy 344.46718 -279.354534)
			(xy 344.46718 -279.39873) (xy 344.82278 -279.39873)
		)
		(stroke
			(width 0)
			(type solid)
		)
		(fill yes)
		(layer "In11.Cu")
		(net "M_D_CPU0_SA_DQ<10>")
	)
	(gr_poly
		(pts
			(xy 344.82278 -278.946102) (xy 344.82278 -278.901906) (xy 344.46718 -278.901906) (xy 344.46718 -278.946102)
			(xy 344.51417 -279.098502) (xy 344.77579 -279.098502)
		)
		(stroke
			(width 0)
			(type solid)
		)
		(fill yes)
		(layer "In11.Cu")
		(net "M_D_CPU0_SA_DQ<9>")
	)
	(gr_poly
		(pts
			(xy 344.82278 -277.726394) (xy 344.77579 -277.573994) (xy 344.51417 -277.573994) (xy 344.46718 -277.726394)
			(xy 344.46718 -277.770844) (xy 344.82278 -277.770844)
		)
		(stroke
			(width 0)
			(type solid)
		)
		(fill yes)
		(layer "In11.Cu")
		(net "M_D_CPU0_SA_DQS_DN<1>")
	)
	(gr_poly
		(pts
			(xy 344.82278 -277.318216) (xy 344.82278 -277.27402) (xy 344.46718 -277.27402) (xy 344.46718 -277.318216)
			(xy 344.51417 -277.470616) (xy 344.77579 -277.470616)
		)
		(stroke
			(width 0)
			(type solid)
		)
		(fill yes)
		(layer "In11.Cu")
		(net "M_D_CPU0_SA_DQS_DN<6>")
	)
	(gr_poly
		(pts
			(xy 344.82278 -276.098762) (xy 344.77579 -275.946362) (xy 344.51417 -275.946362) (xy 344.46718 -276.098762)
			(xy 344.46718 -276.143212) (xy 344.82278 -276.143212)
		)
		(stroke
			(width 0)
			(type solid)
		)
		(fill yes)
		(layer "In11.Cu")
		(net "M_D_CPU0_SA_DQ<14>")
	)
	(gr_poly
		(pts
			(xy 344.82278 -275.690584) (xy 344.82278 -275.646388) (xy 344.46718 -275.646388) (xy 344.46718 -275.690584)
			(xy 344.51417 -275.842984) (xy 344.77579 -275.842984)
		)
		(stroke
			(width 0)
			(type solid)
		)
		(fill yes)
		(layer "In11.Cu")
		(net "M_D_CPU0_SA_DQ<13>")
	)
	(gr_poly
		(pts
			(xy 344.82278 -274.47113) (xy 344.77579 -274.31873) (xy 344.51417 -274.31873) (xy 344.46718 -274.47113)
			(xy 344.46718 -274.515326) (xy 344.82278 -274.515326)
		)
		(stroke
			(width 0)
			(type solid)
		)
		(fill yes)
		(layer "In11.Cu")
		(net "M_D_CPU0_SA_DQ<18>")
	)
	(gr_poly
		(pts
			(xy 344.82278 -274.062698) (xy 344.82278 -274.018502) (xy 344.46718 -274.018502) (xy 344.46718 -274.062698)
			(xy 344.51417 -274.215098) (xy 344.77579 -274.215098)
		)
		(stroke
			(width 0)
			(type solid)
		)
		(fill yes)
		(layer "In11.Cu")
		(net "M_D_CPU0_SA_DQ<17>")
	)
	(gr_poly
		(pts
			(xy 344.82278 -269.587726) (xy 344.77579 -269.435326) (xy 344.51417 -269.435326) (xy 344.46718 -269.587726)
			(xy 344.46718 -269.631922) (xy 344.82278 -269.631922)
		)
		(stroke
			(width 0)
			(type solid)
		)
		(fill yes)
		(layer "In11.Cu")
		(net "M_D_CPU0_SA_DQ<26>")
	)
	(gr_poly
		(pts
			(xy 344.82278 -266.331954) (xy 344.77579 -266.179554) (xy 344.51417 -266.179554) (xy 344.46718 -266.331954)
			(xy 344.46718 -266.376404) (xy 344.82278 -266.376404)
		)
		(stroke
			(width 0)
			(type solid)
		)
		(fill yes)
		(layer "In11.Cu")
		(net "M_D_CPU0_SA_DQ<30>")
	)
	(gr_poly
		(pts
			(xy 344.82278 -265.92403) (xy 344.82278 -265.87958) (xy 344.46718 -265.87958) (xy 344.46718 -265.92403)
			(xy 344.51417 -266.07643) (xy 344.77579 -266.07643)
		)
		(stroke
			(width 0)
			(type solid)
		)
		(fill yes)
		(layer "In11.Cu")
		(net "M_D_CPU0_SA_DQ<29>")
	)
	(gr_poly
		(pts
			(xy 344.82278 -264.704322) (xy 344.77579 -264.551922) (xy 344.51417 -264.551922) (xy 344.46718 -264.704322)
			(xy 344.46718 -264.748772) (xy 344.82278 -264.748772)
		)
		(stroke
			(width 0)
			(type solid)
		)
		(fill yes)
		(layer "In11.Cu")
		(net "M_D_CPU0_SA_CB<2>")
	)
	(gr_poly
		(pts
			(xy 344.82278 -264.296398) (xy 344.82278 -264.251948) (xy 344.46718 -264.251948) (xy 344.46718 -264.296398)
			(xy 344.51417 -264.448798) (xy 344.77579 -264.448798)
		)
		(stroke
			(width 0)
			(type solid)
		)
		(fill yes)
		(layer "In11.Cu")
		(net "M_D_CPU0_SA_CB<1>")
	)
	(gr_poly
		(pts
			(xy 344.82278 -261.449058) (xy 344.77579 -261.296658) (xy 344.51417 -261.296658) (xy 344.46718 -261.449058)
			(xy 344.46718 -261.493254) (xy 344.82278 -261.493254)
		)
		(stroke
			(width 0)
			(type solid)
		)
		(fill yes)
		(layer "In11.Cu")
		(net "M_D_CPU0_SA_CB<6>")
	)
	(gr_poly
		(pts
			(xy 344.82278 -259.412994) (xy 344.82278 -259.368544) (xy 344.46718 -259.368544) (xy 344.46718 -259.412994)
			(xy 344.51417 -259.565394) (xy 344.77579 -259.565394)
		)
		(stroke
			(width 0)
			(type solid)
		)
		(fill yes)
		(layer "In11.Cu")
		(net "M_D_CPU0_SA_CS_N<2>")
	)
	(gr_poly
		(pts
			(xy 344.82278 -256.565654) (xy 344.77579 -256.413254) (xy 344.51417 -256.413254) (xy 344.46718 -256.565654)
			(xy 344.46718 -256.60985) (xy 344.82278 -256.60985)
		)
		(stroke
			(width 0)
			(type solid)
		)
		(fill yes)
		(layer "In11.Cu")
		(net "M_D_CPU0_SA_CA<3>")
	)
	(gr_poly
		(pts
			(xy 344.82278 -256.157222) (xy 344.82278 -256.113026) (xy 344.46718 -256.113026) (xy 344.46718 -256.157222)
			(xy 344.51417 -256.309622) (xy 344.77579 -256.309622)
		)
		(stroke
			(width 0)
			(type solid)
		)
		(fill yes)
		(layer "In11.Cu")
		(net "M_D_CPU0_SA_CA<4>")
	)
	(gr_poly
		(pts
			(xy 344.82532 -272.843498) (xy 344.77833 -272.691098) (xy 344.51671 -272.691098) (xy 344.46972 -272.843498)
			(xy 344.46972 -272.887694) (xy 344.82532 -272.887694)
		)
		(stroke
			(width 0)
			(type solid)
		)
		(fill yes)
		(layer "In11.Cu")
		(net "M_D_CPU0_SA_DQS_DN<2>")
	)
	(gr_poly
		(pts
			(xy 344.82532 -272.435066) (xy 344.82532 -272.39087) (xy 344.46972 -272.39087) (xy 344.46972 -272.435066)
			(xy 344.51671 -272.587466) (xy 344.77833 -272.587466)
		)
		(stroke
			(width 0)
			(type solid)
		)
		(fill yes)
		(layer "In11.Cu")
		(net "M_D_CPU0_SA_DQS_DN<7>")
	)
	(gr_poly
		(pts
			(xy 344.82532 -267.960094) (xy 344.77833 -267.807694) (xy 344.51671 -267.807694) (xy 344.46972 -267.960094)
			(xy 344.46972 -268.00429) (xy 344.82532 -268.00429)
		)
		(stroke
			(width 0)
			(type solid)
		)
		(fill yes)
		(layer "In11.Cu")
		(net "M_D_CPU0_SA_DQS_DN<3>")
	)
	(gr_poly
		(pts
			(xy 344.82532 -267.551662) (xy 344.82532 -267.507466) (xy 344.46972 -267.507466) (xy 344.46972 -267.551662)
			(xy 344.51671 -267.704062) (xy 344.77833 -267.704062)
		)
		(stroke
			(width 0)
			(type solid)
		)
		(fill yes)
		(layer "In11.Cu")
		(net "M_D_CPU0_SA_DQS_DN<8>")
	)
	(gr_poly
		(pts
			(xy 344.82532 -263.07669) (xy 344.77833 -262.92429) (xy 344.51671 -262.92429) (xy 344.46972 -263.07669)
			(xy 344.46972 -263.120886) (xy 344.82532 -263.120886)
		)
		(stroke
			(width 0)
			(type solid)
		)
		(fill yes)
		(layer "In11.Cu")
		(net "M_D_CPU0_SA_DQS_DN<4>")
	)
	(gr_poly
		(pts
			(xy 344.82532 -258.193286) (xy 344.77833 -258.040886) (xy 344.51671 -258.040886) (xy 344.46972 -258.193286)
			(xy 344.46972 -258.237482) (xy 344.82532 -258.237482)
		)
		(stroke
			(width 0)
			(type solid)
		)
		(fill yes)
		(layer "In11.Cu")
		(net "M_D_CPU0_SA_CS_N<1>")
	)
	(gr_poly
		(pts
			(xy 344.82532 -257.784854) (xy 344.82532 -257.740658) (xy 344.46972 -257.740658) (xy 344.46972 -257.784854)
			(xy 344.51671 -257.937254) (xy 344.77833 -257.937254)
		)
		(stroke
			(width 0)
			(type solid)
		)
		(fill yes)
		(layer "In11.Cu")
		(net "M_D_CPU0_SA_CA<0>")
	)
	(gr_poly
		(pts
			(xy 344.83167 -271.215866) (xy 344.78468 -271.063466) (xy 344.52306 -271.063466) (xy 344.47607 -271.215866)
			(xy 344.47607 -271.260316) (xy 344.83167 -271.260316)
		)
		(stroke
			(width 0)
			(type solid)
		)
		(fill yes)
		(layer "In11.Cu")
		(net "M_D_CPU0_SA_DQ<22>")
	)
	(gr_poly
		(pts
			(xy 344.834718 -270.806926) (xy 344.834718 -270.76273) (xy 344.479118 -270.76273) (xy 344.479118 -270.806926)
			(xy 344.526108 -270.959326) (xy 344.787728 -270.959326)
		)
		(stroke
			(width 0)
			(type solid)
		)
		(fill yes)
		(layer "In11.Cu")
		(net "M_D_CPU0_SA_DQ<21>")
	)
	(gr_poly
		(pts
			(xy 344.834718 -269.179294) (xy 344.834718 -269.134844) (xy 344.479118 -269.134844) (xy 344.479118 -269.179294)
			(xy 344.526108 -269.331694) (xy 344.787728 -269.331694)
		)
		(stroke
			(width 0)
			(type solid)
		)
		(fill yes)
		(layer "In11.Cu")
		(net "M_D_CPU0_SA_DQ<25>")
	)
	(gr_poly
		(pts
			(xy 344.834718 -262.668258) (xy 344.834718 -262.623808) (xy 344.479118 -262.623808) (xy 344.479118 -262.668258)
			(xy 344.526108 -262.820658) (xy 344.787728 -262.820658)
		)
		(stroke
			(width 0)
			(type solid)
		)
		(fill yes)
		(layer "In11.Cu")
		(net "M_D_CPU0_SA_DQS_DN<9>")
	)
	(gr_poly
		(pts
			(xy 344.839544 -261.040626) (xy 344.839544 -260.99643) (xy 344.483944 -260.99643) (xy 344.483944 -261.040626)
			(xy 344.530934 -261.193026) (xy 344.792554 -261.193026)
		)
		(stroke
			(width 0)
			(type solid)
		)
		(fill yes)
		(layer "In11.Cu")
		(net "M_D_CPU0_SA_CB<5>")
	)
	(gr_poly
		(pts
			(xy 345.162124 -229.125018) (xy 345.270582 -229.008178) (xy 345.139772 -228.78161) (xy 344.984324 -228.81717)
			(xy 344.94597 -228.839268) (xy 345.12377 -229.147116)
		)
		(stroke
			(width 0)
			(type solid)
		)
		(fill yes)
		(layer "In11.Cu")
		(net "M_D_CPU0_SB_DQS_DN<3>")
	)
	(gr_poly
		(pts
			(xy 345.182952 -245.346474) (xy 345.182952 -245.302024) (xy 344.827352 -245.302024) (xy 344.827352 -245.346474)
			(xy 344.874342 -245.498874) (xy 345.135962 -245.498874)
		)
		(stroke
			(width 0)
			(type solid)
		)
		(fill yes)
		(layer "In11.Cu")
		(net "M_D_CPU0_SB_DQS_DP<9>")
	)
	(gr_poly
		(pts
			(xy 345.182952 -240.46307) (xy 345.182952 -240.41862) (xy 344.827352 -240.41862) (xy 344.827352 -240.46307)
			(xy 344.874342 -240.61547) (xy 345.135962 -240.61547)
		)
		(stroke
			(width 0)
			(type solid)
		)
		(fill yes)
		(layer "In11.Cu")
		(net "M_D_CPU0_SB_DQS_DP<0>")
	)
	(gr_poly
		(pts
			(xy 345.182952 -235.579666) (xy 345.182952 -235.53547) (xy 344.827352 -235.53547) (xy 344.827352 -235.579666)
			(xy 344.874342 -235.732066) (xy 345.135962 -235.732066)
		)
		(stroke
			(width 0)
			(type solid)
		)
		(fill yes)
		(layer "In11.Cu")
		(net "M_D_CPU0_SB_DQS_DP<1>")
	)
	(gr_poly
		(pts
			(xy 345.191334 -244.127274) (xy 345.144344 -243.974874) (xy 344.882724 -243.974874) (xy 344.835734 -244.127274)
			(xy 344.835734 -244.17147) (xy 345.191334 -244.17147)
		)
		(stroke
			(width 0)
			(type solid)
		)
		(fill yes)
		(layer "In11.Cu")
		(net "M_D_CPU0_SB_DQS_DP<4>")
	)
	(gr_poly
		(pts
			(xy 345.191334 -239.24387) (xy 345.144344 -239.09147) (xy 344.882724 -239.09147) (xy 344.835734 -239.24387)
			(xy 344.835734 -239.288066) (xy 345.191334 -239.288066)
		)
		(stroke
			(width 0)
			(type solid)
		)
		(fill yes)
		(layer "In11.Cu")
		(net "M_D_CPU0_SB_DQS_DP<5>")
	)
	(gr_poly
		(pts
			(xy 345.191334 -234.360466) (xy 345.144344 -234.208066) (xy 344.882724 -234.208066) (xy 344.835734 -234.360466)
			(xy 344.835734 -234.404916) (xy 345.191334 -234.404916)
		)
		(stroke
			(width 0)
			(type solid)
		)
		(fill yes)
		(layer "In11.Cu")
		(net "M_D_CPU0_SB_DQS_DP<6>")
	)
	(gr_poly
		(pts
			(xy 345.197176 -246.974106) (xy 345.197176 -246.92991) (xy 344.841576 -246.92991) (xy 344.841576 -246.974106)
			(xy 344.888566 -247.126506) (xy 345.150186 -247.126506)
		)
		(stroke
			(width 0)
			(type solid)
		)
		(fill yes)
		(layer "In11.Cu")
		(net "M_D_CPU0_SB_CB<4>")
	)
	(gr_poly
		(pts
			(xy 345.197176 -245.754906) (xy 345.150186 -245.602506) (xy 344.888566 -245.602506) (xy 344.841576 -245.754906)
			(xy 344.841576 -245.799356) (xy 345.197176 -245.799356)
		)
		(stroke
			(width 0)
			(type solid)
		)
		(fill yes)
		(layer "In11.Cu")
		(net "M_D_CPU0_SB_CB<7>")
	)
	(gr_poly
		(pts
			(xy 345.197176 -240.871502) (xy 345.150186 -240.719102) (xy 344.888566 -240.719102) (xy 344.841576 -240.871502)
			(xy 344.841576 -240.915952) (xy 345.197176 -240.915952)
		)
		(stroke
			(width 0)
			(type solid)
		)
		(fill yes)
		(layer "In11.Cu")
		(net "M_D_CPU0_SB_DQ<3>")
	)
	(gr_poly
		(pts
			(xy 345.197176 -235.988098) (xy 345.150186 -235.835698) (xy 344.888566 -235.835698) (xy 344.841576 -235.988098)
			(xy 344.841576 -236.032548) (xy 345.197176 -236.032548)
		)
		(stroke
			(width 0)
			(type solid)
		)
		(fill yes)
		(layer "In11.Cu")
		(net "M_D_CPU0_SB_DQ<11>")
	)
	(gr_poly
		(pts
			(xy 345.199716 -243.718842) (xy 345.199716 -243.674392) (xy 344.844116 -243.674392) (xy 344.844116 -243.718842)
			(xy 344.891106 -243.871242) (xy 345.152726 -243.871242)
		)
		(stroke
			(width 0)
			(type solid)
		)
		(fill yes)
		(layer "In11.Cu")
		(net "M_D_CPU0_SB_CB<0>")
	)
	(gr_poly
		(pts
			(xy 345.199716 -242.499134) (xy 345.152726 -242.346734) (xy 344.891106 -242.346734) (xy 344.844116 -242.499134)
			(xy 344.844116 -242.54333) (xy 345.199716 -242.54333)
		)
		(stroke
			(width 0)
			(type solid)
		)
		(fill yes)
		(layer "In11.Cu")
		(net "M_D_CPU0_SB_CB<3>")
	)
	(gr_poly
		(pts
			(xy 345.199716 -242.090702) (xy 345.199716 -242.046506) (xy 344.844116 -242.046506) (xy 344.844116 -242.090702)
			(xy 344.891106 -242.243102) (xy 345.152726 -242.243102)
		)
		(stroke
			(width 0)
			(type solid)
		)
		(fill yes)
		(layer "In11.Cu")
		(net "M_D_CPU0_SB_DQ<0>")
	)
	(gr_poly
		(pts
			(xy 345.199716 -238.835438) (xy 345.199716 -238.790988) (xy 344.844116 -238.790988) (xy 344.844116 -238.835438)
			(xy 344.891106 -238.987838) (xy 345.152726 -238.987838)
		)
		(stroke
			(width 0)
			(type solid)
		)
		(fill yes)
		(layer "In11.Cu")
		(net "M_D_CPU0_SB_DQ<4>")
	)
	(gr_poly
		(pts
			(xy 345.199716 -237.61573) (xy 345.152726 -237.46333) (xy 344.891106 -237.46333) (xy 344.844116 -237.61573)
			(xy 344.844116 -237.66018) (xy 345.199716 -237.66018)
		)
		(stroke
			(width 0)
			(type solid)
		)
		(fill yes)
		(layer "In11.Cu")
		(net "M_D_CPU0_SB_DQ<7>")
	)
	(gr_poly
		(pts
			(xy 345.199716 -237.207806) (xy 345.199716 -237.163356) (xy 344.844116 -237.163356) (xy 344.844116 -237.207806)
			(xy 344.891106 -237.360206) (xy 345.152726 -237.360206)
		)
		(stroke
			(width 0)
			(type solid)
		)
		(fill yes)
		(layer "In11.Cu")
		(net "M_D_CPU0_SB_DQ<8>")
	)
	(gr_poly
		(pts
			(xy 345.199716 -233.952034) (xy 345.199716 -233.907838) (xy 344.844116 -233.907838) (xy 344.844116 -233.952034)
			(xy 344.891106 -234.104434) (xy 345.152726 -234.104434)
		)
		(stroke
			(width 0)
			(type solid)
		)
		(fill yes)
		(layer "In11.Cu")
		(net "M_D_CPU0_SB_DQ<12>")
	)
	(gr_poly
		(pts
			(xy 345.199716 -232.732326) (xy 345.152726 -232.579926) (xy 344.891106 -232.579926) (xy 344.844116 -232.732326)
			(xy 344.844116 -232.776776) (xy 345.199716 -232.776776)
		)
		(stroke
			(width 0)
			(type solid)
		)
		(fill yes)
		(layer "In11.Cu")
		(net "M_D_CPU0_SB_DQ<15>")
	)
	(gr_poly
		(pts
			(xy 345.199716 -232.324402) (xy 345.199716 -232.279952) (xy 344.844116 -232.279952) (xy 344.844116 -232.324402)
			(xy 344.891106 -232.476802) (xy 345.152726 -232.476802)
		)
		(stroke
			(width 0)
			(type solid)
		)
		(fill yes)
		(layer "In11.Cu")
		(net "M_D_CPU0_SB_DQ<24>")
	)
	(gr_poly
		(pts
			(xy 345.199716 -227.440998) (xy 345.199716 -227.396548) (xy 344.844116 -227.396548) (xy 344.844116 -227.440998)
			(xy 344.891106 -227.593398) (xy 345.152726 -227.593398)
		)
		(stroke
			(width 0)
			(type solid)
		)
		(fill yes)
		(layer "In11.Cu")
		(net "M_D_CPU0_SB_DQS_DN<8>")
	)
	(gr_poly
		(pts
			(xy 345.199716 -226.22129) (xy 345.152726 -226.06889) (xy 344.891106 -226.06889) (xy 344.844116 -226.22129)
			(xy 344.844116 -226.26574) (xy 345.199716 -226.26574)
		)
		(stroke
			(width 0)
			(type solid)
		)
		(fill yes)
		(layer "In11.Cu")
		(net "M_D_CPU0_SB_DQ<30>")
	)
	(gr_poly
		(pts
			(xy 345.199716 -225.813366) (xy 345.199716 -225.768916) (xy 344.844116 -225.768916) (xy 344.844116 -225.813366)
			(xy 344.891106 -225.965766) (xy 345.152726 -225.965766)
		)
		(stroke
			(width 0)
			(type solid)
		)
		(fill yes)
		(layer "In11.Cu")
		(net "M_D_CPU0_SB_DQ<29>")
	)
	(gr_poly
		(pts
			(xy 345.292934 -278.132032) (xy 345.292934 -278.087836) (xy 344.937334 -278.087836) (xy 344.937334 -278.132032)
			(xy 344.984324 -278.284432) (xy 345.245944 -278.284432)
		)
		(stroke
			(width 0)
			(type solid)
		)
		(fill yes)
		(layer "In11.Cu")
		(net "M_D_CPU0_SA_DQS_DP<1>")
	)
	(gr_poly
		(pts
			(xy 345.292934 -273.248882) (xy 345.292934 -273.204686) (xy 344.937334 -273.204686) (xy 344.937334 -273.248882)
			(xy 344.984324 -273.401282) (xy 345.245944 -273.401282)
		)
		(stroke
			(width 0)
			(type solid)
		)
		(fill yes)
		(layer "In11.Cu")
		(net "M_D_CPU0_SA_DQS_DP<2>")
	)
	(gr_poly
		(pts
			(xy 345.292934 -268.365478) (xy 345.292934 -268.321282) (xy 344.937334 -268.321282) (xy 344.937334 -268.365478)
			(xy 344.984324 -268.517878) (xy 345.245944 -268.517878)
		)
		(stroke
			(width 0)
			(type solid)
		)
		(fill yes)
		(layer "In11.Cu")
		(net "M_D_CPU0_SA_DQS_DP<3>")
	)
	(gr_poly
		(pts
			(xy 345.292934 -263.482074) (xy 345.292934 -263.437878) (xy 344.937334 -263.437878) (xy 344.937334 -263.482074)
			(xy 344.984324 -263.634474) (xy 345.245944 -263.634474)
		)
		(stroke
			(width 0)
			(type solid)
		)
		(fill yes)
		(layer "In11.Cu")
		(net "M_D_CPU0_SA_DQS_DP<4>")
	)
	(gr_poly
		(pts
			(xy 345.29522 -272.029682) (xy 345.24823 -271.877282) (xy 344.98661 -271.877282) (xy 344.93962 -272.029682)
			(xy 344.93962 -272.073878) (xy 345.29522 -272.073878)
		)
		(stroke
			(width 0)
			(type solid)
		)
		(fill yes)
		(layer "In11.Cu")
		(net "M_D_CPU0_SA_DQS_DP<7>")
	)
	(gr_poly
		(pts
			(xy 345.29522 -267.146278) (xy 345.24823 -266.993878) (xy 344.98661 -266.993878) (xy 344.93962 -267.146278)
			(xy 344.93962 -267.190474) (xy 345.29522 -267.190474)
		)
		(stroke
			(width 0)
			(type solid)
		)
		(fill yes)
		(layer "In11.Cu")
		(net "M_D_CPU0_SA_DQS_DP<8>")
	)
	(gr_poly
		(pts
			(xy 345.29522 -257.37947) (xy 345.24823 -257.22707) (xy 344.98661 -257.22707) (xy 344.93962 -257.37947)
			(xy 344.93962 -257.42392) (xy 345.29522 -257.42392)
		)
		(stroke
			(width 0)
			(type solid)
		)
		(fill yes)
		(layer "In11.Cu")
		(net "M_D_CPU0_SA_CA<1>")
	)
	(gr_poly
		(pts
			(xy 345.29776 -271.620742) (xy 345.29776 -271.576546) (xy 344.94216 -271.576546) (xy 344.94216 -271.620742)
			(xy 344.98915 -271.773142) (xy 345.25077 -271.773142)
		)
		(stroke
			(width 0)
			(type solid)
		)
		(fill yes)
		(layer "In11.Cu")
		(net "M_D_CPU0_SA_DQ<20>")
	)
	(gr_poly
		(pts
			(xy 345.29776 -270.40205) (xy 345.25077 -270.24965) (xy 344.98915 -270.24965) (xy 344.94216 -270.40205)
			(xy 344.94216 -270.446246) (xy 345.29776 -270.446246)
		)
		(stroke
			(width 0)
			(type solid)
		)
		(fill yes)
		(layer "In11.Cu")
		(net "M_D_CPU0_SA_DQ<23>")
	)
	(gr_poly
		(pts
			(xy 345.29776 -268.77391) (xy 345.25077 -268.62151) (xy 344.98915 -268.62151) (xy 344.94216 -268.77391)
			(xy 344.94216 -268.81836) (xy 345.29776 -268.81836)
		)
		(stroke
			(width 0)
			(type solid)
		)
		(fill yes)
		(layer "In11.Cu")
		(net "M_D_CPU0_SA_DQ<27>")
	)
	(gr_poly
		(pts
			(xy 345.29776 -262.262874) (xy 345.25077 -262.110474) (xy 344.98915 -262.110474) (xy 344.94216 -262.262874)
			(xy 344.94216 -262.307324) (xy 345.29776 -262.307324)
		)
		(stroke
			(width 0)
			(type solid)
		)
		(fill yes)
		(layer "In11.Cu")
		(net "M_D_CPU0_SA_DQS_DP<9>")
	)
	(gr_poly
		(pts
			(xy 345.301062 -260.634734) (xy 345.254072 -260.482334) (xy 344.992452 -260.482334) (xy 344.945462 -260.634734)
			(xy 344.945462 -260.679184) (xy 345.301062 -260.679184)
		)
		(stroke
			(width 0)
			(type solid)
		)
		(fill yes)
		(layer "In11.Cu")
		(net "M_D_CPU0_SA_CB<7>")
	)
	(gr_poly
		(pts
			(xy 345.301316 -258.59867) (xy 345.301316 -258.554474) (xy 344.945716 -258.554474) (xy 344.945716 -258.59867)
			(xy 344.992706 -258.75107) (xy 345.254326 -258.75107)
		)
		(stroke
			(width 0)
			(type solid)
		)
		(fill yes)
		(layer "In11.Cu")
		(net "M_D_CPU0_SA_CS_N<3>")
	)
	(gr_poly
		(pts
			(xy 345.307158 -276.913086) (xy 345.260168 -276.760686) (xy 344.998548 -276.760686) (xy 344.951558 -276.913086)
			(xy 344.951558 -276.957282) (xy 345.307158 -276.957282)
		)
		(stroke
			(width 0)
			(type solid)
		)
		(fill yes)
		(layer "In11.Cu")
		(net "M_D_CPU0_SA_DQS_DP<6>")
	)
	(gr_poly
		(pts
			(xy 345.307158 -276.504146) (xy 345.307158 -276.45995) (xy 344.951558 -276.45995) (xy 344.951558 -276.504146)
			(xy 344.998548 -276.656546) (xy 345.260168 -276.656546)
		)
		(stroke
			(width 0)
			(type solid)
		)
		(fill yes)
		(layer "In11.Cu")
		(net "M_D_CPU0_SA_DQ<12>")
	)
	(gr_poly
		(pts
			(xy 345.307158 -266.737846) (xy 345.307158 -266.693396) (xy 344.951558 -266.693396) (xy 344.951558 -266.737846)
			(xy 344.998548 -266.890246) (xy 345.260168 -266.890246)
		)
		(stroke
			(width 0)
			(type solid)
		)
		(fill yes)
		(layer "In11.Cu")
		(net "M_D_CPU0_SA_DQ<28>")
	)
	(gr_poly
		(pts
			(xy 345.307158 -261.854442) (xy 345.307158 -261.809992) (xy 344.951558 -261.809992) (xy 344.951558 -261.854442)
			(xy 344.998548 -262.006842) (xy 345.260168 -262.006842)
		)
		(stroke
			(width 0)
			(type solid)
		)
		(fill yes)
		(layer "In11.Cu")
		(net "M_D_CPU0_SA_CB<4>")
	)
	(gr_poly
		(pts
			(xy 345.307158 -256.971038) (xy 345.307158 -256.926588) (xy 344.951558 -256.926588) (xy 344.951558 -256.971038)
			(xy 344.998548 -257.123438) (xy 345.260168 -257.123438)
		)
		(stroke
			(width 0)
			(type solid)
		)
		(fill yes)
		(layer "In11.Cu")
		(net "M_D_CPU0_SA_CA<2>")
	)
	(gr_poly
		(pts
			(xy 345.309698 -279.759918) (xy 345.309698 -279.715722) (xy 344.954098 -279.715722) (xy 344.954098 -279.759918)
			(xy 345.001088 -279.912318) (xy 345.262708 -279.912318)
		)
		(stroke
			(width 0)
			(type solid)
		)
		(fill yes)
		(layer "In11.Cu")
		(net "M_D_CPU0_SA_DQ<8>")
	)
	(gr_poly
		(pts
			(xy 345.309698 -278.540718) (xy 345.262708 -278.388318) (xy 345.001088 -278.388318) (xy 344.954098 -278.540718)
			(xy 344.954098 -278.584914) (xy 345.309698 -278.584914)
		)
		(stroke
			(width 0)
			(type solid)
		)
		(fill yes)
		(layer "In11.Cu")
		(net "M_D_CPU0_SA_DQ<11>")
	)
	(gr_poly
		(pts
			(xy 345.309698 -275.284946) (xy 345.262708 -275.132546) (xy 345.001088 -275.132546) (xy 344.954098 -275.284946)
			(xy 344.954098 -275.329142) (xy 345.309698 -275.329142)
		)
		(stroke
			(width 0)
			(type solid)
		)
		(fill yes)
		(layer "In11.Cu")
		(net "M_D_CPU0_SA_DQ<15>")
	)
	(gr_poly
		(pts
			(xy 345.309698 -274.876514) (xy 345.309698 -274.832318) (xy 344.954098 -274.832318) (xy 344.954098 -274.876514)
			(xy 345.001088 -275.028914) (xy 345.262708 -275.028914)
		)
		(stroke
			(width 0)
			(type solid)
		)
		(fill yes)
		(layer "In11.Cu")
		(net "M_D_CPU0_SA_DQ<16>")
	)
	(gr_poly
		(pts
			(xy 345.309698 -273.657314) (xy 345.262708 -273.504914) (xy 345.001088 -273.504914) (xy 344.954098 -273.657314)
			(xy 344.954098 -273.70151) (xy 345.309698 -273.70151)
		)
		(stroke
			(width 0)
			(type solid)
		)
		(fill yes)
		(layer "In11.Cu")
		(net "M_D_CPU0_SA_DQ<19>")
	)
	(gr_poly
		(pts
			(xy 345.309698 -269.993618) (xy 345.309698 -269.949168) (xy 344.954098 -269.949168) (xy 344.954098 -269.993618)
			(xy 345.001088 -270.146018) (xy 345.262708 -270.146018)
		)
		(stroke
			(width 0)
			(type solid)
		)
		(fill yes)
		(layer "In11.Cu")
		(net "M_D_CPU0_SA_DQ<24>")
	)
	(gr_poly
		(pts
			(xy 345.309698 -265.518138) (xy 345.262708 -265.365738) (xy 345.001088 -265.365738) (xy 344.954098 -265.518138)
			(xy 344.954098 -265.562588) (xy 345.309698 -265.562588)
		)
		(stroke
			(width 0)
			(type solid)
		)
		(fill yes)
		(layer "In11.Cu")
		(net "M_D_CPU0_SA_DQ<31>")
	)
	(gr_poly
		(pts
			(xy 345.309698 -265.110214) (xy 345.309698 -265.065764) (xy 344.954098 -265.065764) (xy 344.954098 -265.110214)
			(xy 345.001088 -265.262614) (xy 345.262708 -265.262614)
		)
		(stroke
			(width 0)
			(type solid)
		)
		(fill yes)
		(layer "In11.Cu")
		(net "M_D_CPU0_SA_CB<0>")
	)
	(gr_poly
		(pts
			(xy 345.309698 -263.890506) (xy 345.262708 -263.738106) (xy 345.001088 -263.738106) (xy 344.954098 -263.890506)
			(xy 344.954098 -263.934956) (xy 345.309698 -263.934956)
		)
		(stroke
			(width 0)
			(type solid)
		)
		(fill yes)
		(layer "In11.Cu")
		(net "M_D_CPU0_SA_CB<3>")
	)
	(gr_poly
		(pts
			(xy 345.309698 -259.007102) (xy 345.262708 -258.854702) (xy 345.001088 -258.854702) (xy 344.954098 -259.007102)
			(xy 344.954098 -259.051552) (xy 345.309698 -259.051552)
		)
		(stroke
			(width 0)
			(type solid)
		)
		(fill yes)
		(layer "In11.Cu")
		(net "M_D_CPU0_SA_CS_N<0>")
	)
	(gr_poly
		(pts
			(xy 345.309698 -255.751838) (xy 345.262708 -255.599438) (xy 345.001088 -255.599438) (xy 344.954098 -255.751838)
			(xy 344.954098 -255.796034) (xy 345.309698 -255.796034)
		)
		(stroke
			(width 0)
			(type solid)
		)
		(fill yes)
		(layer "In11.Cu")
		(net "M_D_CPU0_SA_CA<5>")
	)
	(gr_poly
		(pts
			(xy 345.550744 -249.186446) (xy 345.51239 -249.164348) (xy 345.356942 -249.128788) (xy 345.226132 -249.355356)
			(xy 345.33459 -249.472196) (xy 345.372944 -249.494294)
		)
		(stroke
			(width 0)
			(type solid)
		)
		(fill yes)
		(layer "In11.Cu")
		(net "M_D_CPU0_SB_CA<1>")
	)
	(gr_poly
		(pts
			(xy 345.652598 -246.568722) (xy 345.605608 -246.416322) (xy 345.343988 -246.416322) (xy 345.296998 -246.568722)
			(xy 345.296998 -246.612918) (xy 345.652598 -246.612918)
		)
		(stroke
			(width 0)
			(type solid)
		)
		(fill yes)
		(layer "In11.Cu")
		(net "M_D_CPU0_SB_CB<6>")
	)
	(gr_poly
		(pts
			(xy 345.652598 -241.685318) (xy 345.605608 -241.532918) (xy 345.343988 -241.532918) (xy 345.296998 -241.685318)
			(xy 345.296998 -241.729514) (xy 345.652598 -241.729514)
		)
		(stroke
			(width 0)
			(type solid)
		)
		(fill yes)
		(layer "In11.Cu")
		(net "M_D_CPU0_SB_DQ<2>")
	)
	(gr_poly
		(pts
			(xy 345.652598 -236.801914) (xy 345.605608 -236.649514) (xy 345.343988 -236.649514) (xy 345.296998 -236.801914)
			(xy 345.296998 -236.84611) (xy 345.652598 -236.84611)
		)
		(stroke
			(width 0)
			(type solid)
		)
		(fill yes)
		(layer "In11.Cu")
		(net "M_D_CPU0_SB_DQ<10>")
	)
	(gr_poly
		(pts
			(xy 345.652598 -227.035106) (xy 345.605608 -226.882706) (xy 345.343988 -226.882706) (xy 345.296998 -227.035106)
			(xy 345.296998 -227.079556) (xy 345.652598 -227.079556)
		)
		(stroke
			(width 0)
			(type solid)
		)
		(fill yes)
		(layer "In11.Cu")
		(net "M_D_CPU0_SB_DQS_DP<8>")
	)
	(gr_poly
		(pts
			(xy 345.652598 -225.407474) (xy 345.605608 -225.255074) (xy 345.343988 -225.255074) (xy 345.296998 -225.407474)
			(xy 345.296998 -225.45167) (xy 345.652598 -225.45167)
		)
		(stroke
			(width 0)
			(type solid)
		)
		(fill yes)
		(layer "In11.Cu")
		(net "M_D_CPU0_SB_DQ<31>")
	)
	(gr_poly
		(pts
			(xy 345.655138 -244.53215) (xy 345.655138 -244.487954) (xy 345.299538 -244.487954) (xy 345.299538 -244.53215)
			(xy 345.346528 -244.68455) (xy 345.608148 -244.68455)
		)
		(stroke
			(width 0)
			(type solid)
		)
		(fill yes)
		(layer "In11.Cu")
		(net "M_D_CPU0_SB_DQS_DN<4>")
	)
	(gr_poly
		(pts
			(xy 345.655138 -243.31295) (xy 345.608148 -243.16055) (xy 345.346528 -243.16055) (xy 345.299538 -243.31295)
			(xy 345.299538 -243.3574) (xy 345.655138 -243.3574)
		)
		(stroke
			(width 0)
			(type solid)
		)
		(fill yes)
		(layer "In11.Cu")
		(net "M_D_CPU0_SB_CB<2>")
	)
	(gr_poly
		(pts
			(xy 345.655138 -242.905026) (xy 345.655138 -242.860576) (xy 345.299538 -242.860576) (xy 345.299538 -242.905026)
			(xy 345.346528 -243.057426) (xy 345.608148 -243.057426)
		)
		(stroke
			(width 0)
			(type solid)
		)
		(fill yes)
		(layer "In11.Cu")
		(net "M_D_CPU0_SB_CB<1>")
	)
	(gr_poly
		(pts
			(xy 345.655138 -239.648746) (xy 345.655138 -239.60455) (xy 345.299538 -239.60455) (xy 345.299538 -239.648746)
			(xy 345.346528 -239.801146) (xy 345.608148 -239.801146)
		)
		(stroke
			(width 0)
			(type solid)
		)
		(fill yes)
		(layer "In11.Cu")
		(net "M_D_CPU0_SB_DQS_DN<5>")
	)
	(gr_poly
		(pts
			(xy 345.655138 -238.429546) (xy 345.608148 -238.277146) (xy 345.346528 -238.277146) (xy 345.299538 -238.429546)
			(xy 345.299538 -238.473996) (xy 345.655138 -238.473996)
		)
		(stroke
			(width 0)
			(type solid)
		)
		(fill yes)
		(layer "In11.Cu")
		(net "M_D_CPU0_SB_DQ<6>")
	)
	(gr_poly
		(pts
			(xy 345.655138 -238.021622) (xy 345.655138 -237.977172) (xy 345.299538 -237.977172) (xy 345.299538 -238.021622)
			(xy 345.346528 -238.174022) (xy 345.608148 -238.174022)
		)
		(stroke
			(width 0)
			(type solid)
		)
		(fill yes)
		(layer "In11.Cu")
		(net "M_D_CPU0_SB_DQ<5>")
	)
	(gr_poly
		(pts
			(xy 345.655138 -234.76585) (xy 345.655138 -234.7214) (xy 345.299538 -234.7214) (xy 345.299538 -234.76585)
			(xy 345.346528 -234.91825) (xy 345.608148 -234.91825)
		)
		(stroke
			(width 0)
			(type solid)
		)
		(fill yes)
		(layer "In11.Cu")
		(net "M_D_CPU0_SB_DQS_DN<6>")
	)
	(gr_poly
		(pts
			(xy 345.655138 -233.546142) (xy 345.608148 -233.393742) (xy 345.346528 -233.393742) (xy 345.299538 -233.546142)
			(xy 345.299538 -233.590592) (xy 345.655138 -233.590592)
		)
		(stroke
			(width 0)
			(type solid)
		)
		(fill yes)
		(layer "In11.Cu")
		(net "M_D_CPU0_SB_DQ<14>")
	)
	(gr_poly
		(pts
			(xy 345.655138 -233.138218) (xy 345.655138 -233.093768) (xy 345.299538 -233.093768) (xy 345.299538 -233.138218)
			(xy 345.346528 -233.290618) (xy 345.608148 -233.290618)
		)
		(stroke
			(width 0)
			(type solid)
		)
		(fill yes)
		(layer "In11.Cu")
		(net "M_D_CPU0_SB_DQ<13>")
	)
	(gr_poly
		(pts
			(xy 345.66098 -246.16029) (xy 345.66098 -246.11584) (xy 345.30538 -246.11584) (xy 345.30538 -246.16029)
			(xy 345.35237 -246.31269) (xy 345.61399 -246.31269)
		)
		(stroke
			(width 0)
			(type solid)
		)
		(fill yes)
		(layer "In11.Cu")
		(net "M_D_CPU0_SB_CB<5>")
	)
	(gr_poly
		(pts
			(xy 345.66098 -241.276886) (xy 345.66098 -241.232436) (xy 345.30538 -241.232436) (xy 345.30538 -241.276886)
			(xy 345.35237 -241.429286) (xy 345.61399 -241.429286)
		)
		(stroke
			(width 0)
			(type solid)
		)
		(fill yes)
		(layer "In11.Cu")
		(net "M_D_CPU0_SB_DQ<1>")
	)
	(gr_poly
		(pts
			(xy 345.66098 -236.393482) (xy 345.66098 -236.349286) (xy 345.30538 -236.349286) (xy 345.30538 -236.393482)
			(xy 345.35237 -236.545882) (xy 345.61399 -236.545882)
		)
		(stroke
			(width 0)
			(type solid)
		)
		(fill yes)
		(layer "In11.Cu")
		(net "M_D_CPU0_SB_DQ<9>")
	)
	(gr_poly
		(pts
			(xy 345.66098 -226.626674) (xy 345.66098 -226.582478) (xy 345.30538 -226.582478) (xy 345.30538 -226.626674)
			(xy 345.35237 -226.779074) (xy 345.61399 -226.779074)
		)
		(stroke
			(width 0)
			(type solid)
		)
		(fill yes)
		(layer "In11.Cu")
		(net "M_D_CPU0_SB_DQ<28>")
	)
	(gr_poly
		(pts
			(xy 345.76258 -275.690584) (xy 345.76258 -275.646388) (xy 345.40698 -275.646388) (xy 345.40698 -275.690584)
			(xy 345.45397 -275.842984) (xy 345.71559 -275.842984)
		)
		(stroke
			(width 0)
			(type solid)
		)
		(fill yes)
		(layer "In11.Cu")
		(net "M_D_CPU0_SA_DQ<13>")
	)
	(gr_poly
		(pts
			(xy 345.76258 -274.47113) (xy 345.71559 -274.31873) (xy 345.45397 -274.31873) (xy 345.40698 -274.47113)
			(xy 345.40698 -274.515326) (xy 345.76258 -274.515326)
		)
		(stroke
			(width 0)
			(type solid)
		)
		(fill yes)
		(layer "In11.Cu")
		(net "M_D_CPU0_SA_DQ<18>")
	)
	(gr_poly
		(pts
			(xy 345.76258 -274.062698) (xy 345.76258 -274.018502) (xy 345.40698 -274.018502) (xy 345.40698 -274.062698)
			(xy 345.45397 -274.215098) (xy 345.71559 -274.215098)
		)
		(stroke
			(width 0)
			(type solid)
		)
		(fill yes)
		(layer "In11.Cu")
		(net "M_D_CPU0_SA_DQ<17>")
	)
	(gr_poly
		(pts
			(xy 345.76258 -265.92403) (xy 345.76258 -265.87958) (xy 345.40698 -265.87958) (xy 345.40698 -265.92403)
			(xy 345.45397 -266.07643) (xy 345.71559 -266.07643)
		)
		(stroke
			(width 0)
			(type solid)
		)
		(fill yes)
		(layer "In11.Cu")
		(net "M_D_CPU0_SA_DQ<29>")
	)
	(gr_poly
		(pts
			(xy 345.76258 -261.040626) (xy 345.76258 -260.99643) (xy 345.40698 -260.99643) (xy 345.40698 -261.040626)
			(xy 345.45397 -261.193026) (xy 345.71559 -261.193026)
		)
		(stroke
			(width 0)
			(type solid)
		)
		(fill yes)
		(layer "In11.Cu")
		(net "M_D_CPU0_SA_CB<5>")
	)
	(gr_poly
		(pts
			(xy 345.76258 -256.157222) (xy 345.76258 -256.113026) (xy 345.40698 -256.113026) (xy 345.40698 -256.157222)
			(xy 345.45397 -256.309622) (xy 345.71559 -256.309622)
		)
		(stroke
			(width 0)
			(type solid)
		)
		(fill yes)
		(layer "In11.Cu")
		(net "M_D_CPU0_SA_CA<4>")
	)
	(gr_poly
		(pts
			(xy 345.76512 -279.354534) (xy 345.71813 -279.202134) (xy 345.45651 -279.202134) (xy 345.40952 -279.354534)
			(xy 345.40952 -279.39873) (xy 345.76512 -279.39873)
		)
		(stroke
			(width 0)
			(type solid)
		)
		(fill yes)
		(layer "In11.Cu")
		(net "M_D_CPU0_SA_DQ<10>")
	)
	(gr_poly
		(pts
			(xy 345.76512 -269.587726) (xy 345.71813 -269.435326) (xy 345.45651 -269.435326) (xy 345.40952 -269.587726)
			(xy 345.40952 -269.631922) (xy 345.76512 -269.631922)
		)
		(stroke
			(width 0)
			(type solid)
		)
		(fill yes)
		(layer "In11.Cu")
		(net "M_D_CPU0_SA_DQ<26>")
	)
	(gr_poly
		(pts
			(xy 345.76512 -264.704322) (xy 345.71813 -264.551922) (xy 345.45651 -264.551922) (xy 345.40952 -264.704322)
			(xy 345.40952 -264.748772) (xy 345.76512 -264.748772)
		)
		(stroke
			(width 0)
			(type solid)
		)
		(fill yes)
		(layer "In11.Cu")
		(net "M_D_CPU0_SA_CB<2>")
	)
	(gr_poly
		(pts
			(xy 345.76512 -264.296398) (xy 345.76512 -264.251948) (xy 345.40952 -264.251948) (xy 345.40952 -264.296398)
			(xy 345.45651 -264.448798) (xy 345.71813 -264.448798)
		)
		(stroke
			(width 0)
			(type solid)
		)
		(fill yes)
		(layer "In11.Cu")
		(net "M_D_CPU0_SA_CB<1>")
	)
	(gr_poly
		(pts
			(xy 345.770708 -258.193286) (xy 345.723718 -258.040886) (xy 345.462098 -258.040886) (xy 345.415108 -258.193286)
			(xy 345.415108 -258.237736) (xy 345.770708 -258.237736)
		)
		(stroke
			(width 0)
			(type solid)
		)
		(fill yes)
		(layer "In11.Cu")
		(net "M_D_CPU0_SA_CS_N<1>")
	)
	(gr_poly
		(pts
			(xy 345.770962 -278.945848) (xy 345.770962 -278.901652) (xy 345.415362 -278.901652) (xy 345.415362 -278.945848)
			(xy 345.462352 -279.098248) (xy 345.723972 -279.098248)
		)
		(stroke
			(width 0)
			(type solid)
		)
		(fill yes)
		(layer "In11.Cu")
		(net "M_D_CPU0_SA_DQ<9>")
	)
	(gr_poly
		(pts
			(xy 345.770962 -277.317962) (xy 345.770962 -277.273766) (xy 345.415362 -277.273766) (xy 345.415362 -277.317962)
			(xy 345.462352 -277.470362) (xy 345.723972 -277.470362)
		)
		(stroke
			(width 0)
			(type solid)
		)
		(fill yes)
		(layer "In11.Cu")
		(net "M_D_CPU0_SA_DQS_DN<6>")
	)
	(gr_poly
		(pts
			(xy 345.770962 -276.09927) (xy 345.723972 -275.94687) (xy 345.462352 -275.94687) (xy 345.415362 -276.09927)
			(xy 345.415362 -276.143466) (xy 345.770962 -276.143466)
		)
		(stroke
			(width 0)
			(type solid)
		)
		(fill yes)
		(layer "In11.Cu")
		(net "M_D_CPU0_SA_DQ<14>")
	)
	(gr_poly
		(pts
			(xy 345.770962 -266.332462) (xy 345.723972 -266.180062) (xy 345.462352 -266.180062) (xy 345.415362 -266.332462)
			(xy 345.415362 -266.376658) (xy 345.770962 -266.376658)
		)
		(stroke
			(width 0)
			(type solid)
		)
		(fill yes)
		(layer "In11.Cu")
		(net "M_D_CPU0_SA_DQ<30>")
	)
	(gr_poly
		(pts
			(xy 345.770962 -261.449058) (xy 345.723972 -261.296658) (xy 345.462352 -261.296658) (xy 345.415362 -261.449058)
			(xy 345.415362 -261.493508) (xy 345.770962 -261.493508)
		)
		(stroke
			(width 0)
			(type solid)
		)
		(fill yes)
		(layer "In11.Cu")
		(net "M_D_CPU0_SA_CB<6>")
	)
	(gr_poly
		(pts
			(xy 345.770962 -256.565654) (xy 345.723972 -256.413254) (xy 345.462352 -256.413254) (xy 345.415362 -256.565654)
			(xy 345.415362 -256.610104) (xy 345.770962 -256.610104)
		)
		(stroke
			(width 0)
			(type solid)
		)
		(fill yes)
		(layer "In11.Cu")
		(net "M_D_CPU0_SA_CA<3>")
	)
	(gr_poly
		(pts
			(xy 345.774518 -271.215866) (xy 345.727528 -271.063466) (xy 345.465908 -271.063466) (xy 345.418918 -271.215866)
			(xy 345.418918 -271.260062) (xy 345.774518 -271.260062)
		)
		(stroke
			(width 0)
			(type solid)
		)
		(fill yes)
		(layer "In11.Cu")
		(net "M_D_CPU0_SA_DQ<22>")
	)
	(gr_poly
		(pts
			(xy 345.774518 -270.806926) (xy 345.774518 -270.76273) (xy 345.418918 -270.76273) (xy 345.418918 -270.806926)
			(xy 345.465908 -270.959326) (xy 345.727528 -270.959326)
		)
		(stroke
			(width 0)
			(type solid)
		)
		(fill yes)
		(layer "In11.Cu")
		(net "M_D_CPU0_SA_DQ<21>")
	)
	(gr_poly
		(pts
			(xy 345.774518 -269.179294) (xy 345.774518 -269.134844) (xy 345.418918 -269.134844) (xy 345.418918 -269.179294)
			(xy 345.465908 -269.331694) (xy 345.727528 -269.331694)
		)
		(stroke
			(width 0)
			(type solid)
		)
		(fill yes)
		(layer "In11.Cu")
		(net "M_D_CPU0_SA_DQ<25>")
	)
	(gr_poly
		(pts
			(xy 345.774518 -262.668258) (xy 345.774518 -262.623808) (xy 345.418918 -262.623808) (xy 345.418918 -262.668258)
			(xy 345.465908 -262.820658) (xy 345.727528 -262.820658)
		)
		(stroke
			(width 0)
			(type solid)
		)
		(fill yes)
		(layer "In11.Cu")
		(net "M_D_CPU0_SA_DQS_DN<9>")
	)
	(gr_poly
		(pts
			(xy 345.777058 -272.435066) (xy 345.777058 -272.390616) (xy 345.421458 -272.390616) (xy 345.421458 -272.435066)
			(xy 345.468448 -272.587466) (xy 345.730068 -272.587466)
		)
		(stroke
			(width 0)
			(type solid)
		)
		(fill yes)
		(layer "In11.Cu")
		(net "M_D_CPU0_SA_DQS_DN<7>")
	)
	(gr_poly
		(pts
			(xy 345.777058 -267.551662) (xy 345.777058 -267.507212) (xy 345.421458 -267.507212) (xy 345.421458 -267.551662)
			(xy 345.468448 -267.704062) (xy 345.730068 -267.704062)
		)
		(stroke
			(width 0)
			(type solid)
		)
		(fill yes)
		(layer "In11.Cu")
		(net "M_D_CPU0_SA_DQS_DN<8>")
	)
	(gr_poly
		(pts
			(xy 346.027248 -248.361454) (xy 345.988894 -248.339356) (xy 345.833446 -248.303796) (xy 345.702636 -248.530364)
			(xy 345.811094 -248.647204) (xy 345.849448 -248.669302)
		)
		(stroke
			(width 0)
			(type solid)
		)
		(fill yes)
		(layer "In11.Cu")
		(net "M_D_CPU0_SB_CA<1>")
	)
	(gr_poly
		(pts
			(xy 346.101924 -227.497132) (xy 346.210382 -227.380292) (xy 346.079572 -227.153724) (xy 345.924124 -227.189284)
			(xy 345.88577 -227.211382) (xy 346.06357 -227.51923)
		)
		(stroke
			(width 0)
			(type solid)
		)
		(fill yes)
		(layer "In11.Cu")
		(net "M_D_CPU0_SB_DQS_DP<8>")
	)
	(gr_poly
		(pts
			(xy 346.125038 -237.616238) (xy 346.078048 -237.463838) (xy 345.816428 -237.463838) (xy 345.769438 -237.616238)
			(xy 345.769438 -237.660434) (xy 346.125038 -237.660434)
		)
		(stroke
			(width 0)
			(type solid)
		)
		(fill yes)
		(layer "In11.Cu")
		(net "M_D_CPU0_SB_DQ<7>")
	)
	(gr_poly
		(pts
			(xy 346.125038 -232.732834) (xy 346.078048 -232.580434) (xy 345.816428 -232.580434) (xy 345.769438 -232.732834)
			(xy 345.769438 -232.77703) (xy 346.125038 -232.77703)
		)
		(stroke
			(width 0)
			(type solid)
		)
		(fill yes)
		(layer "In11.Cu")
		(net "M_D_CPU0_SB_DQ<15>")
	)
	(gr_poly
		(pts
			(xy 346.136976 -246.974106) (xy 346.136976 -246.929656) (xy 345.781376 -246.929656) (xy 345.781376 -246.974106)
			(xy 345.828366 -247.126506) (xy 346.089986 -247.126506)
		)
		(stroke
			(width 0)
			(type solid)
		)
		(fill yes)
		(layer "In11.Cu")
		(net "M_D_CPU0_SB_CB<4>")
	)
	(gr_poly
		(pts
			(xy 346.136976 -237.207298) (xy 346.136976 -237.163102) (xy 345.781376 -237.163102) (xy 345.781376 -237.207298)
			(xy 345.828366 -237.359698) (xy 346.089986 -237.359698)
		)
		(stroke
			(width 0)
			(type solid)
		)
		(fill yes)
		(layer "In11.Cu")
		(net "M_D_CPU0_SB_DQ<8>")
	)
	(gr_poly
		(pts
			(xy 346.139516 -242.090702) (xy 346.139516 -242.046506) (xy 345.783916 -242.046506) (xy 345.783916 -242.090702)
			(xy 345.830906 -242.243102) (xy 346.092526 -242.243102)
		)
		(stroke
			(width 0)
			(type solid)
		)
		(fill yes)
		(layer "In11.Cu")
		(net "M_D_CPU0_SB_DQ<0>")
	)
	(gr_poly
		(pts
			(xy 346.139516 -239.243362) (xy 346.092526 -239.090962) (xy 345.830906 -239.090962) (xy 345.783916 -239.243362)
			(xy 345.783916 -239.287812) (xy 346.139516 -239.287812)
		)
		(stroke
			(width 0)
			(type solid)
		)
		(fill yes)
		(layer "In11.Cu")
		(net "M_D_CPU0_SB_DQS_DP<5>")
	)
	(gr_poly
		(pts
			(xy 346.139516 -234.360466) (xy 346.092526 -234.208066) (xy 345.830906 -234.208066) (xy 345.783916 -234.360466)
			(xy 345.783916 -234.404662) (xy 346.139516 -234.404662)
		)
		(stroke
			(width 0)
			(type solid)
		)
		(fill yes)
		(layer "In11.Cu")
		(net "M_D_CPU0_SB_DQS_DP<6>")
	)
	(gr_poly
		(pts
			(xy 346.139516 -226.22129) (xy 346.092526 -226.06889) (xy 345.830906 -226.06889) (xy 345.783916 -226.22129)
			(xy 345.783916 -226.26574) (xy 346.139516 -226.26574)
		)
		(stroke
			(width 0)
			(type solid)
		)
		(fill yes)
		(layer "In11.Cu")
		(net "M_D_CPU0_SB_DQ<30>")
	)
	(gr_poly
		(pts
			(xy 346.139516 -225.813366) (xy 346.139516 -225.768916) (xy 345.783916 -225.768916) (xy 345.783916 -225.813366)
			(xy 345.830906 -225.965766) (xy 346.092526 -225.965766)
		)
		(stroke
			(width 0)
			(type solid)
		)
		(fill yes)
		(layer "In11.Cu")
		(net "M_D_CPU0_SB_DQ<29>")
	)
	(gr_poly
		(pts
			(xy 346.210382 -249.070876) (xy 346.101924 -248.954036) (xy 346.06357 -248.931938) (xy 345.88577 -249.239786)
			(xy 345.924124 -249.261884) (xy 346.079572 -249.297444)
		)
		(stroke
			(width 0)
			(type solid)
		)
		(fill yes)
		(layer "In11.Cu")
		(net "M_D_CPU0_SB_CA<0>")
	)
	(gr_poly
		(pts
			(xy 346.23502 -269.99311) (xy 346.23502 -269.948914) (xy 345.87942 -269.948914) (xy 345.87942 -269.99311)
			(xy 345.92641 -270.14551) (xy 346.18803 -270.14551)
		)
		(stroke
			(width 0)
			(type solid)
		)
		(fill yes)
		(layer "In11.Cu")
		(net "M_D_CPU0_SA_DQ<24>")
	)
	(gr_poly
		(pts
			(xy 346.23502 -265.109706) (xy 346.23502 -265.06551) (xy 345.87942 -265.06551) (xy 345.87942 -265.109706)
			(xy 345.92641 -265.262106) (xy 346.18803 -265.262106)
		)
		(stroke
			(width 0)
			(type solid)
		)
		(fill yes)
		(layer "In11.Cu")
		(net "M_D_CPU0_SA_CB<0>")
	)
	(gr_poly
		(pts
			(xy 346.23502 -260.226302) (xy 346.23502 -260.182106) (xy 345.87942 -260.182106) (xy 345.87942 -260.226302)
			(xy 345.92641 -260.378702) (xy 346.18803 -260.378702)
		)
		(stroke
			(width 0)
			(type solid)
		)
		(fill yes)
		(layer "In11.Cu")
		(net "M_D_CPU0_ALERT_N")
	)
	(gr_poly
		(pts
			(xy 346.23756 -270.40205) (xy 346.19057 -270.24965) (xy 345.92895 -270.24965) (xy 345.88196 -270.40205)
			(xy 345.88196 -270.446246) (xy 346.23756 -270.446246)
		)
		(stroke
			(width 0)
			(type solid)
		)
		(fill yes)
		(layer "In11.Cu")
		(net "M_D_CPU0_SA_DQ<23>")
	)
	(gr_poly
		(pts
			(xy 346.241116 -279.759664) (xy 346.241116 -279.715468) (xy 345.885516 -279.715468) (xy 345.885516 -279.759664)
			(xy 345.932506 -279.912064) (xy 346.194126 -279.912064)
		)
		(stroke
			(width 0)
			(type solid)
		)
		(fill yes)
		(layer "In11.Cu")
		(net "M_D_CPU0_SA_DQ<8>")
	)
	(gr_poly
		(pts
			(xy 346.246958 -276.912578) (xy 346.199968 -276.760178) (xy 345.938348 -276.760178) (xy 345.891358 -276.912578)
			(xy 345.891358 -276.957028) (xy 346.246958 -276.957028)
		)
		(stroke
			(width 0)
			(type solid)
		)
		(fill yes)
		(layer "In11.Cu")
		(net "M_D_CPU0_SA_DQS_DP<6>")
	)
	(gr_poly
		(pts
			(xy 346.246958 -274.876514) (xy 346.246958 -274.832064) (xy 345.891358 -274.832064) (xy 345.891358 -274.876514)
			(xy 345.938348 -275.028914) (xy 346.199968 -275.028914)
		)
		(stroke
			(width 0)
			(type solid)
		)
		(fill yes)
		(layer "In11.Cu")
		(net "M_D_CPU0_SA_DQ<16>")
	)
	(gr_poly
		(pts
			(xy 346.246958 -267.14577) (xy 346.199968 -266.99337) (xy 345.938348 -266.99337) (xy 345.891358 -267.14577)
			(xy 345.891358 -267.19022) (xy 346.246958 -267.19022)
		)
		(stroke
			(width 0)
			(type solid)
		)
		(fill yes)
		(layer "In11.Cu")
		(net "M_D_CPU0_SA_DQS_DP<8>")
	)
	(gr_poly
		(pts
			(xy 346.246958 -265.518646) (xy 346.199968 -265.366246) (xy 345.938348 -265.366246) (xy 345.891358 -265.518646)
			(xy 345.891358 -265.562842) (xy 346.246958 -265.562842)
		)
		(stroke
			(width 0)
			(type solid)
		)
		(fill yes)
		(layer "In11.Cu")
		(net "M_D_CPU0_SA_DQ<31>")
	)
	(gr_poly
		(pts
			(xy 346.246958 -260.635242) (xy 346.199968 -260.482842) (xy 345.938348 -260.482842) (xy 345.891358 -260.635242)
			(xy 345.891358 -260.679438) (xy 346.246958 -260.679438)
		)
		(stroke
			(width 0)
			(type solid)
		)
		(fill yes)
		(layer "In11.Cu")
		(net "M_D_CPU0_SA_CB<7>")
	)
	(gr_poly
		(pts
			(xy 346.246958 -257.37947) (xy 346.199968 -257.22707) (xy 345.938348 -257.22707) (xy 345.891358 -257.37947)
			(xy 345.891358 -257.423666) (xy 346.246958 -257.423666)
		)
		(stroke
			(width 0)
			(type solid)
		)
		(fill yes)
		(layer "In11.Cu")
		(net "M_D_CPU0_SA_CA<1>")
	)
	(gr_poly
		(pts
			(xy 346.246958 -255.751838) (xy 346.199968 -255.599438) (xy 345.938348 -255.599438) (xy 345.891358 -255.751838)
			(xy 345.891358 -255.796288) (xy 346.246958 -255.796288)
		)
		(stroke
			(width 0)
			(type solid)
		)
		(fill yes)
		(layer "In11.Cu")
		(net "M_D_CPU0_SA_CA<5>")
	)
	(gr_poly
		(pts
			(xy 346.453968 -227.289614) (xy 346.492322 -227.267516) (xy 346.314522 -226.959668) (xy 346.276168 -226.981766)
			(xy 346.16771 -227.098606) (xy 346.29852 -227.325174)
		)
		(stroke
			(width 0)
			(type solid)
		)
		(fill yes)
		(layer "In11.Cu")
		(net "M_D_CPU0_SB_DQ<28>")
	)
	(gr_poly
		(pts
			(xy 346.571824 -226.68357) (xy 346.680282 -226.56673) (xy 346.549472 -226.340162) (xy 346.394024 -226.375722)
			(xy 346.35567 -226.39782) (xy 346.53347 -226.705668)
		)
		(stroke
			(width 0)
			(type solid)
		)
		(fill yes)
		(layer "In11.Cu")
		(net "M_D_CPU0_SB_DQ<30>")
	)
	(gr_poly
		(pts
			(xy 346.592398 -225.407474) (xy 346.545408 -225.255074) (xy 346.283788 -225.255074) (xy 346.236798 -225.407474)
			(xy 346.236798 -225.45167) (xy 346.592398 -225.45167)
		)
		(stroke
			(width 0)
			(type solid)
		)
		(fill yes)
		(layer "In11.Cu")
		(net "M_D_CPU0_SB_DQ<31>")
	)
	(gr_poly
		(pts
			(xy 346.594938 -233.54665) (xy 346.547948 -233.39425) (xy 346.286328 -233.39425) (xy 346.239338 -233.54665)
			(xy 346.239338 -233.590846) (xy 346.594938 -233.590846)
		)
		(stroke
			(width 0)
			(type solid)
		)
		(fill yes)
		(layer "In11.Cu")
		(net "M_D_CPU0_SB_DQ<14>")
	)
	(gr_poly
		(pts
			(xy 346.600526 -264.066782) (xy 346.562172 -264.044684) (xy 346.406724 -264.009124) (xy 346.275914 -264.235692)
			(xy 346.384372 -264.352532) (xy 346.422726 -264.37463)
		)
		(stroke
			(width 0)
			(type solid)
		)
		(fill yes)
		(layer "In11.Cu")
		(net "M_D_CPU0_SA_CB<2>")
	)
	(gr_poly
		(pts
			(xy 346.606876 -238.021114) (xy 346.606876 -237.976918) (xy 346.251276 -237.976918) (xy 346.251276 -238.021114)
			(xy 346.298266 -238.173514) (xy 346.559886 -238.173514)
		)
		(stroke
			(width 0)
			(type solid)
		)
		(fill yes)
		(layer "In11.Cu")
		(net "M_D_CPU0_SB_DQ<5>")
	)
	(gr_poly
		(pts
			(xy 346.606876 -233.13771) (xy 346.606876 -233.093514) (xy 346.251276 -233.093514) (xy 346.251276 -233.13771)
			(xy 346.298266 -233.29011) (xy 346.559886 -233.29011)
		)
		(stroke
			(width 0)
			(type solid)
		)
		(fill yes)
		(layer "In11.Cu")
		(net "M_D_CPU0_SB_DQ<13>")
	)
	(gr_poly
		(pts
			(xy 346.70238 -256.565654) (xy 346.65539 -256.413254) (xy 346.39377 -256.413254) (xy 346.34678 -256.565654)
			(xy 346.34678 -256.60985) (xy 346.70238 -256.60985)
		)
		(stroke
			(width 0)
			(type solid)
		)
		(fill yes)
		(layer "In11.Cu")
		(net "M_D_CPU0_SA_CA<3>")
	)
	(gr_poly
		(pts
			(xy 346.710762 -265.923522) (xy 346.710762 -265.879326) (xy 346.355162 -265.879326) (xy 346.355162 -265.923522)
			(xy 346.402152 -266.075922) (xy 346.663772 -266.075922)
		)
		(stroke
			(width 0)
			(type solid)
		)
		(fill yes)
		(layer "In11.Cu")
		(net "M_D_CPU0_SA_DQ<29>")
	)
	(gr_poly
		(pts
			(xy 346.710762 -261.040626) (xy 346.710762 -260.996176) (xy 346.355162 -260.996176) (xy 346.355162 -261.040626)
			(xy 346.402152 -261.193026) (xy 346.663772 -261.193026)
		)
		(stroke
			(width 0)
			(type solid)
		)
		(fill yes)
		(layer "In11.Cu")
		(net "M_D_CPU0_SA_CB<5>")
	)
	(gr_poly
		(pts
			(xy 346.714318 -271.215866) (xy 346.667328 -271.063466) (xy 346.405708 -271.063466) (xy 346.358718 -271.215866)
			(xy 346.358718 -271.260062) (xy 346.714318 -271.260062)
		)
		(stroke
			(width 0)
			(type solid)
		)
		(fill yes)
		(layer "In11.Cu")
		(net "M_D_CPU0_SA_DQ<22>")
	)
	(gr_poly
		(pts
			(xy 346.714318 -270.806926) (xy 346.714318 -270.76273) (xy 346.358718 -270.76273) (xy 346.358718 -270.806926)
			(xy 346.405708 -270.959326) (xy 346.667328 -270.959326)
		)
		(stroke
			(width 0)
			(type solid)
		)
		(fill yes)
		(layer "In11.Cu")
		(net "M_D_CPU0_SA_DQ<21>")
	)
	(gr_poly
		(pts
			(xy 346.716858 -259.821426) (xy 346.669868 -259.669026) (xy 346.408248 -259.669026) (xy 346.361258 -259.821426)
			(xy 346.361258 -259.865622) (xy 346.716858 -259.865622)
		)
		(stroke
			(width 0)
			(type solid)
		)
		(fill yes)
		(layer "In11.Cu")
		(net "M_D_CPU0_SA_CS_N<2>")
	)
	(gr_poly
		(pts
			(xy 346.926662 -226.480116) (xy 346.965016 -226.458018) (xy 346.787216 -226.15017) (xy 346.748862 -226.172268)
			(xy 346.640404 -226.289108) (xy 346.771214 -226.515676)
		)
		(stroke
			(width 0)
			(type solid)
		)
		(fill yes)
		(layer "In11.Cu")
		(net "M_D_CPU0_SB_DQ<29>")
	)
	(gr_poly
		(pts
			(xy 347.076776 -232.732326) (xy 347.029786 -232.579926) (xy 346.768166 -232.579926) (xy 346.721176 -232.732326)
			(xy 346.721176 -232.776776) (xy 347.076776 -232.776776)
		)
		(stroke
			(width 0)
			(type solid)
		)
		(fill yes)
		(layer "In11.Cu")
		(net "M_D_CPU0_SB_DQ<15>")
	)
	(gr_poly
		(pts
			(xy 347.079316 -234.360466) (xy 347.032326 -234.208066) (xy 346.770706 -234.208066) (xy 346.723716 -234.360466)
			(xy 346.723716 -234.404662) (xy 347.079316 -234.404662)
		)
		(stroke
			(width 0)
			(type solid)
		)
		(fill yes)
		(layer "In11.Cu")
		(net "M_D_CPU0_SB_DQS_DP<6>")
	)
	(gr_poly
		(pts
			(xy 347.17736 -270.40205) (xy 347.13037 -270.24965) (xy 346.86875 -270.24965) (xy 346.82176 -270.40205)
			(xy 346.82176 -270.446246) (xy 347.17736 -270.446246)
		)
		(stroke
			(width 0)
			(type solid)
		)
		(fill yes)
		(layer "In11.Cu")
		(net "M_D_CPU0_SA_DQ<23>")
	)
	(gr_poly
		(pts
			(xy 347.186758 -260.22681) (xy 347.186758 -260.18236) (xy 346.831158 -260.18236) (xy 346.831158 -260.22681)
			(xy 346.878148 -260.37921) (xy 347.139768 -260.37921)
		)
		(stroke
			(width 0)
			(type solid)
		)
		(fill yes)
		(layer "In11.Cu")
		(net "M_D_CPU0_ALERT_N")
	)
	(gr_poly
		(pts
			(xy 370.422678 -247.64365) (xy 370.461032 -247.621552) (xy 370.283232 -247.313704) (xy 370.244878 -247.335802)
			(xy 370.13642 -247.452642) (xy 370.26723 -247.67921)
		)
		(stroke
			(width 0)
			(type solid)
		)
		(fill yes)
		(layer "In11.Cu")
		(net "M_H_CPU0_SA_CA<6>")
	)
	(gr_poly
		(pts
			(xy 370.460016 -246.737632) (xy 370.421662 -246.715534) (xy 370.266214 -246.679974) (xy 370.135404 -246.906542)
			(xy 370.243862 -247.023382) (xy 370.282216 -247.04548)
		)
		(stroke
			(width 0)
			(type solid)
		)
		(fill yes)
		(layer "In11.Cu")
		(net "M_H_CPU0_SA_CA<6>")
	)
	(gr_poly
		(pts
			(xy 370.89334 -248.45899) (xy 370.931694 -248.436892) (xy 370.753894 -248.129044) (xy 370.71554 -248.151142)
			(xy 370.607082 -248.267982) (xy 370.737892 -248.49455)
		)
		(stroke
			(width 0)
			(type solid)
		)
		(fill yes)
		(layer "In11.Cu")
		(net "M_H_CPU0_SA_CA<6>")
	)
	(gr_poly
		(pts
			(xy 371.001036 -247.834658) (xy 371.109494 -247.717818) (xy 370.978684 -247.49125) (xy 370.823236 -247.52681)
			(xy 370.784882 -247.548908) (xy 370.962682 -247.856756)
		)
		(stroke
			(width 0)
			(type solid)
		)
		(fill yes)
		(layer "In11.Cu")
		(net "M_H_CPU0_SA_PAR")
	)
	(gr_poly
		(pts
			(xy 371.029738 -246.568722) (xy 370.982748 -246.416322) (xy 370.721128 -246.416322) (xy 370.674138 -246.568722)
			(xy 370.674138 -246.613172) (xy 371.029738 -246.613172)
		)
		(stroke
			(width 0)
			(type solid)
		)
		(fill yes)
		(layer "In11.Cu")
		(net "M_H_CPU0_SA_CA<6>")
	)
	(gr_poly
		(pts
			(xy 371.13718 -257.784854) (xy 371.13718 -257.740658) (xy 370.78158 -257.740658) (xy 370.78158 -257.784854)
			(xy 370.82857 -257.937254) (xy 371.09019 -257.937254)
		)
		(stroke
			(width 0)
			(type solid)
		)
		(fill yes)
		(layer "In11.Cu")
		(net "M_E_CPU0_ALERT_N")
	)
	(gr_poly
		(pts
			(xy 371.35689 -249.26163) (xy 371.395244 -249.239532) (xy 371.217444 -248.931684) (xy 371.17909 -248.953782)
			(xy 371.070632 -249.070622) (xy 371.201442 -249.29719)
		)
		(stroke
			(width 0)
			(type solid)
		)
		(fill yes)
		(layer "In11.Cu")
		(net "M_H_CPU0_SA_CA<6>")
	)
	(gr_poly
		(pts
			(xy 371.472714 -248.65203) (xy 371.581172 -248.53519) (xy 371.450362 -248.308622) (xy 371.294914 -248.344182)
			(xy 371.25656 -248.36628) (xy 371.43436 -248.674128)
		)
		(stroke
			(width 0)
			(type solid)
		)
		(fill yes)
		(layer "In11.Cu")
		(net "M_H_CPU0_SA_PAR")
	)
	(gr_poly
		(pts
			(xy 371.832124 -248.456958) (xy 371.870478 -248.43486) (xy 371.692678 -248.127012) (xy 371.654324 -248.14911)
			(xy 371.545866 -248.26595) (xy 371.676676 -248.492518)
		)
		(stroke
			(width 0)
			(type solid)
		)
		(fill yes)
		(layer "In11.Cu")
		(net "M_H_CPU0_CLK_DP<1>")
	)
	(gr_poly
		(pts
			(xy 371.940836 -249.462544) (xy 372.049294 -249.345704) (xy 371.918484 -249.119136) (xy 371.763036 -249.154696)
			(xy 371.724682 -249.176794) (xy 371.902482 -249.484642)
		)
		(stroke
			(width 0)
			(type solid)
		)
		(fill yes)
		(layer "In11.Cu")
		(net "M_H_CPU0_SA_PAR")
	)
	(gr_poly
		(pts
			(xy 371.940836 -247.834658) (xy 372.049294 -247.717818) (xy 371.918484 -247.49125) (xy 371.763036 -247.52681)
			(xy 371.724682 -247.548908) (xy 371.902482 -247.856756)
		)
		(stroke
			(width 0)
			(type solid)
		)
		(fill yes)
		(layer "In11.Cu")
		(net "M_H_CPU0_CLK_DN<1>")
	)
	(gr_poly
		(pts
			(xy 371.975126 -255.92786) (xy 371.936772 -255.905762) (xy 371.781324 -255.870202) (xy 371.650514 -256.09677)
			(xy 371.758972 -256.21361) (xy 371.797326 -256.235708)
		)
		(stroke
			(width 0)
			(type solid)
		)
		(fill yes)
		(layer "In11.Cu")
		(net "M_H_CPU0_SA_CS_N<3>")
	)
	(gr_poly
		(pts
			(xy 372.07698 -257.784854) (xy 372.07698 -257.740658) (xy 371.72138 -257.740658) (xy 371.72138 -257.784854)
			(xy 371.76837 -257.937254) (xy 372.02999 -257.937254)
		)
		(stroke
			(width 0)
			(type solid)
		)
		(fill yes)
		(layer "In11.Cu")
		(net "M_E_CPU0_ALERT_N")
	)
	(gr_poly
		(pts
			(xy 372.07952 -254.937514) (xy 372.03253 -254.785114) (xy 371.77091 -254.785114) (xy 371.72392 -254.937514)
			(xy 371.72392 -254.981964) (xy 372.07952 -254.981964)
		)
		(stroke
			(width 0)
			(type solid)
		)
		(fill yes)
		(layer "In11.Cu")
		(net "M_H_CPU0_SA_CA<2>")
	)
	(gr_poly
		(pts
			(xy 372.302278 -249.271536) (xy 372.340632 -249.249438) (xy 372.162832 -248.94159) (xy 372.124478 -248.963688)
			(xy 372.01602 -249.080528) (xy 372.14683 -249.307096)
		)
		(stroke
			(width 0)
			(type solid)
		)
		(fill yes)
		(layer "In11.Cu")
		(net "M_H_CPU0_CLK_DP<1>")
	)
	(gr_poly
		(pts
			(xy 372.41099 -248.649236) (xy 372.519448 -248.532396) (xy 372.388638 -248.305828) (xy 372.23319 -248.341388)
			(xy 372.194836 -248.363486) (xy 372.372636 -248.671334)
		)
		(stroke
			(width 0)
			(type solid)
		)
		(fill yes)
		(layer "In11.Cu")
		(net "M_H_CPU0_CLK_DN<1>")
	)
	(gr_poly
		(pts
			(xy 372.54942 -255.343406) (xy 372.54942 -255.298956) (xy 372.19382 -255.298956) (xy 372.19382 -255.343406)
			(xy 372.24081 -255.495806) (xy 372.50243 -255.495806)
		)
		(stroke
			(width 0)
			(type solid)
		)
		(fill yes)
		(layer "In11.Cu")
		(net "M_H_CPU0_SA_CA<0>")
	)
	(gr_poly
		(pts
			(xy 372.561358 -255.751838) (xy 372.514368 -255.599438) (xy 372.252748 -255.599438) (xy 372.205758 -255.751838)
			(xy 372.205758 -255.796288) (xy 372.561358 -255.796288)
		)
		(stroke
			(width 0)
			(type solid)
		)
		(fill yes)
		(layer "In11.Cu")
		(net "M_H_CPU0_SA_CS_N<3>")
	)
	(gr_poly
		(pts
			(xy 372.886224 -249.47245) (xy 372.994682 -249.35561) (xy 372.863872 -249.129042) (xy 372.708424 -249.164602)
			(xy 372.67007 -249.1867) (xy 372.84787 -249.494548)
		)
		(stroke
			(width 0)
			(type solid)
		)
		(fill yes)
		(layer "In11.Cu")
		(net "M_H_CPU0_CLK_DN<1>")
	)
	(gr_poly
		(pts
			(xy 372.906798 -242.905026) (xy 372.906798 -242.860576) (xy 372.551198 -242.860576) (xy 372.551198 -242.905026)
			(xy 372.598188 -243.057426) (xy 372.859808 -243.057426)
		)
		(stroke
			(width 0)
			(type solid)
		)
		(fill yes)
		(layer "In11.Cu")
		(net "M_H_CPU0_SB_DQS_DP<9>")
	)
	(gr_poly
		(pts
			(xy 372.909338 -244.532658) (xy 372.909338 -244.488208) (xy 372.553738 -244.488208) (xy 372.553738 -244.532658)
			(xy 372.600728 -244.685058) (xy 372.862348 -244.685058)
		)
		(stroke
			(width 0)
			(type solid)
		)
		(fill yes)
		(layer "In11.Cu")
		(net "M_H_CPU0_SB_CB<6>")
	)
	(gr_poly
		(pts
			(xy 372.918736 -233.13771) (xy 372.918736 -233.093514) (xy 372.563136 -233.093514) (xy 372.563136 -233.13771)
			(xy 372.610126 -233.29011) (xy 372.871746 -233.29011)
		)
		(stroke
			(width 0)
			(type solid)
		)
		(fill yes)
		(layer "In11.Cu")
		(net "M_H_CPU0_SB_DQS_DP<1>")
	)
	(gr_poly
		(pts
			(xy 373.01678 -261.449058) (xy 372.96979 -261.296658) (xy 372.70817 -261.296658) (xy 372.66118 -261.449058)
			(xy 372.66118 -261.493254) (xy 373.01678 -261.493254)
		)
		(stroke
			(width 0)
			(type solid)
		)
		(fill yes)
		(layer "In11.Cu")
		(net "M_H_CPU0_SA_CB<1>")
	)
	(gr_poly
		(pts
			(xy 373.01932 -257.784854) (xy 373.01932 -257.740658) (xy 372.66372 -257.740658) (xy 372.66372 -257.784854)
			(xy 372.71071 -257.937254) (xy 372.97233 -257.937254)
		)
		(stroke
			(width 0)
			(type solid)
		)
		(fill yes)
		(layer "In11.Cu")
		(net "M_E_CPU0_ALERT_N")
	)
	(gr_poly
		(pts
			(xy 373.025162 -256.157222) (xy 373.025162 -256.112772) (xy 372.669562 -256.112772) (xy 372.669562 -256.157222)
			(xy 372.716552 -256.309622) (xy 372.978172 -256.309622)
		)
		(stroke
			(width 0)
			(type solid)
		)
		(fill yes)
		(layer "In11.Cu")
		(net "M_H_CPU0_SA_CS_N<2>")
	)
	(gr_poly
		(pts
			(xy 373.028718 -270.806926) (xy 373.028718 -270.76273) (xy 372.673118 -270.76273) (xy 372.673118 -270.806926)
			(xy 372.720108 -270.959326) (xy 372.981728 -270.959326)
		)
		(stroke
			(width 0)
			(type solid)
		)
		(fill yes)
		(layer "In11.Cu")
		(net "M_H_CPU0_SA_DQS_DP<2>")
	)
	(gr_poly
		(pts
			(xy 373.031258 -254.938022) (xy 372.984268 -254.785622) (xy 372.722648 -254.785622) (xy 372.675658 -254.938022)
			(xy 372.675658 -254.982218) (xy 373.031258 -254.982218)
		)
		(stroke
			(width 0)
			(type solid)
		)
		(fill yes)
		(layer "In11.Cu")
		(net "M_H_CPU0_SA_CA<2>")
	)
	(gr_poly
		(pts
			(xy 373.346726 -280.41981) (xy 373.38508 -280.397712) (xy 373.20728 -280.089864) (xy 373.168926 -280.111962)
			(xy 373.060468 -280.228802) (xy 373.191278 -280.45537)
		)
		(stroke
			(width 0)
			(type solid)
		)
		(fill yes)
		(layer "In11.Cu")
		(net "M_H_CPU0_SA_DQ<8>")
	)
	(gr_poly
		(pts
			(xy 373.35206 -278.80183) (xy 373.390414 -278.779732) (xy 373.212614 -278.471884) (xy 373.17426 -278.493982)
			(xy 373.065802 -278.610822) (xy 373.196612 -278.83739)
		)
		(stroke
			(width 0)
			(type solid)
		)
		(fill yes)
		(layer "In11.Cu")
		(net "M_H_CPU0_SA_DQ<9>")
	)
	(gr_poly
		(pts
			(xy 373.381778 -234.360466) (xy 373.334788 -234.208066) (xy 373.073168 -234.208066) (xy 373.026178 -234.360466)
			(xy 373.026178 -234.404916) (xy 373.381778 -234.404916)
		)
		(stroke
			(width 0)
			(type solid)
		)
		(fill yes)
		(layer "In11.Cu")
		(net "M_H_CPU0_SB_DQ<10>")
	)
	(gr_poly
		(pts
			(xy 373.385334 -244.127274) (xy 373.338344 -243.974874) (xy 373.076724 -243.974874) (xy 373.029734 -244.127274)
			(xy 373.029734 -244.17147) (xy 373.385334 -244.17147)
		)
		(stroke
			(width 0)
			(type solid)
		)
		(fill yes)
		(layer "In11.Cu")
		(net "M_H_CPU0_SB_CB<4>")
	)
	(gr_poly
		(pts
			(xy 373.390922 -263.242552) (xy 373.352568 -263.220454) (xy 373.19712 -263.184894) (xy 373.06631 -263.411462)
			(xy 373.174768 -263.528302) (xy 373.213122 -263.5504)
		)
		(stroke
			(width 0)
			(type solid)
		)
		(fill yes)
		(layer "In11.Cu")
		(net "M_H_CPU0_SA_DQ<31>")
	)
	(gr_poly
		(pts
			(xy 373.393716 -233.952034) (xy 373.393716 -233.907838) (xy 373.038116 -233.907838) (xy 373.038116 -233.952034)
			(xy 373.085106 -234.104434) (xy 373.346726 -234.104434)
		)
		(stroke
			(width 0)
			(type solid)
		)
		(fill yes)
		(layer "In11.Cu")
		(net "M_H_CPU0_SB_DQ<9>")
	)
	(gr_poly
		(pts
			(xy 373.466106 -279.816306) (xy 373.574564 -279.699466) (xy 373.443754 -279.472898) (xy 373.288306 -279.508458)
			(xy 373.249952 -279.530556) (xy 373.427752 -279.838404)
		)
		(stroke
			(width 0)
			(type solid)
		)
		(fill yes)
		(layer "In11.Cu")
		(net "M_H_CPU0_SA_DQ<10>")
	)
	(gr_poly
		(pts
			(xy 373.48668 -257.37947) (xy 373.43969 -257.22707) (xy 373.17807 -257.22707) (xy 373.13108 -257.37947)
			(xy 373.13108 -257.423666) (xy 373.48668 -257.423666)
		)
		(stroke
			(width 0)
			(type solid)
		)
		(fill yes)
		(layer "In11.Cu")
		(net "M_H_CPU0_ALERT_N")
	)
	(gr_poly
		(pts
			(xy 373.48922 -272.029682) (xy 373.44223 -271.877282) (xy 373.18061 -271.877282) (xy 373.13362 -272.029682)
			(xy 373.13362 -272.073878) (xy 373.48922 -272.073878)
		)
		(stroke
			(width 0)
			(type solid)
		)
		(fill yes)
		(layer "In11.Cu")
		(net "M_H_CPU0_SA_DQ<18>")
	)
	(gr_poly
		(pts
			(xy 373.48922 -262.262874) (xy 373.44223 -262.110474) (xy 373.18061 -262.110474) (xy 373.13362 -262.262874)
			(xy 373.13362 -262.307324) (xy 373.48922 -262.307324)
		)
		(stroke
			(width 0)
			(type solid)
		)
		(fill yes)
		(layer "In11.Cu")
		(net "M_H_CPU0_SA_CB<2>")
	)
	(gr_poly
		(pts
			(xy 373.49176 -271.620742) (xy 373.49176 -271.576546) (xy 373.13616 -271.576546) (xy 373.13616 -271.620742)
			(xy 373.18315 -271.773142) (xy 373.44477 -271.773142)
		)
		(stroke
			(width 0)
			(type solid)
		)
		(fill yes)
		(layer "In11.Cu")
		(net "M_H_CPU0_SA_DQ<17>")
	)
	(gr_poly
		(pts
			(xy 373.495062 -256.971038) (xy 373.495062 -256.926588) (xy 373.139462 -256.926588) (xy 373.139462 -256.971038)
			(xy 373.186452 -257.123438) (xy 373.448072 -257.123438)
		)
		(stroke
			(width 0)
			(type solid)
		)
		(fill yes)
		(layer "In11.Cu")
		(net "M_H_CPU0_SA_CS_N<0>")
	)
	(gr_poly
		(pts
			(xy 373.501158 -267.146278) (xy 373.454168 -266.993878) (xy 373.192548 -266.993878) (xy 373.145558 -267.146278)
			(xy 373.145558 -267.190474) (xy 373.501158 -267.190474)
		)
		(stroke
			(width 0)
			(type solid)
		)
		(fill yes)
		(layer "In11.Cu")
		(net "M_H_CPU0_SA_DQ<26>")
	)
	(gr_poly
		(pts
			(xy 373.501158 -255.751838) (xy 373.454168 -255.599438) (xy 373.192548 -255.599438) (xy 373.145558 -255.751838)
			(xy 373.145558 -255.796034) (xy 373.501158 -255.796034)
		)
		(stroke
			(width 0)
			(type solid)
		)
		(fill yes)
		(layer "In11.Cu")
		(net "M_H_CPU0_SA_CS_N<3>")
	)
	(gr_poly
		(pts
			(xy 373.501158 -255.343406) (xy 373.501158 -255.29921) (xy 373.145558 -255.29921) (xy 373.145558 -255.343406)
			(xy 373.192548 -255.495806) (xy 373.454168 -255.495806)
		)
		(stroke
			(width 0)
			(type solid)
		)
		(fill yes)
		(layer "In11.Cu")
		(net "M_H_CPU0_SA_CA<0>")
	)
	(gr_poly
		(pts
			(xy 373.574564 -263.951212) (xy 373.466106 -263.834372) (xy 373.427752 -263.812274) (xy 373.249952 -264.120122)
			(xy 373.288306 -264.14222) (xy 373.443754 -264.17778)
		)
		(stroke
			(width 0)
			(type solid)
		)
		(fill yes)
		(layer "In11.Cu")
		(net "M_H_CPU0_SA_DQ<29>")
	)
	(gr_poly
		(pts
			(xy 373.7102 -248.454164) (xy 373.748554 -248.432066) (xy 373.570754 -248.124218) (xy 373.5324 -248.146316)
			(xy 373.423942 -248.263156) (xy 373.554752 -248.489724)
		)
		(stroke
			(width 0)
			(type solid)
		)
		(fill yes)
		(layer "In11.Cu")
		(net "M_H_CPU0_CLK_DP<0>")
	)
	(gr_poly
		(pts
			(xy 373.816372 -279.605994) (xy 373.854726 -279.583896) (xy 373.676926 -279.276048) (xy 373.638572 -279.298146)
			(xy 373.530114 -279.414986) (xy 373.660924 -279.641554)
		)
		(stroke
			(width 0)
			(type solid)
		)
		(fill yes)
		(layer "In11.Cu")
		(net "M_H_CPU0_SA_DQ<9>")
	)
	(gr_poly
		(pts
			(xy 373.821706 -277.987252) (xy 373.86006 -277.965154) (xy 373.68226 -277.657306) (xy 373.643906 -277.679404)
			(xy 373.535448 -277.796244) (xy 373.666258 -278.022812)
		)
		(stroke
			(width 0)
			(type solid)
		)
		(fill yes)
		(layer "In11.Cu")
		(net "M_H_CPU0_SA_DQS_DP<1>")
	)
	(gr_poly
		(pts
			(xy 373.826024 -247.844564) (xy 373.934482 -247.727724) (xy 373.803672 -247.501156) (xy 373.648224 -247.536716)
			(xy 373.60987 -247.558814) (xy 373.78767 -247.866662)
		)
		(stroke
			(width 0)
			(type solid)
		)
		(fill yes)
		(layer "In11.Cu")
		(net "M_H_CPU0_CLK_DN<0>")
	)
	(gr_poly
		(pts
			(xy 373.846598 -225.407474) (xy 373.799608 -225.255074) (xy 373.537988 -225.255074) (xy 373.490998 -225.407474)
			(xy 373.490998 -225.45167) (xy 373.846598 -225.45167)
		)
		(stroke
			(width 0)
			(type solid)
		)
		(fill yes)
		(layer "In11.Cu")
		(net "M_H_CPU0_SB_DQ<29>")
	)
	(gr_poly
		(pts
			(xy 373.849138 -244.53215) (xy 373.849138 -244.487954) (xy 373.493538 -244.487954) (xy 373.493538 -244.53215)
			(xy 373.540528 -244.68455) (xy 373.802148 -244.68455)
		)
		(stroke
			(width 0)
			(type solid)
		)
		(fill yes)
		(layer "In11.Cu")
		(net "M_H_CPU0_SB_CB<6>")
	)
	(gr_poly
		(pts
			(xy 373.849138 -242.905026) (xy 373.849138 -242.860576) (xy 373.493538 -242.860576) (xy 373.493538 -242.905026)
			(xy 373.540528 -243.057426) (xy 373.802148 -243.057426)
		)
		(stroke
			(width 0)
			(type solid)
		)
		(fill yes)
		(layer "In11.Cu")
		(net "M_H_CPU0_SB_DQS_DP<9>")
	)
	(gr_poly
		(pts
			(xy 373.849138 -230.290878) (xy 373.802148 -230.138478) (xy 373.540528 -230.138478) (xy 373.493538 -230.290878)
			(xy 373.493538 -230.335328) (xy 373.849138 -230.335328)
		)
		(stroke
			(width 0)
			(type solid)
		)
		(fill yes)
		(layer "In11.Cu")
		(net "M_H_CPU0_SB_DQ<15>")
	)
	(gr_poly
		(pts
			(xy 373.849138 -229.882446) (xy 373.849138 -229.837996) (xy 373.493538 -229.837996) (xy 373.493538 -229.882446)
			(xy 373.540528 -230.034846) (xy 373.802148 -230.034846)
		)
		(stroke
			(width 0)
			(type solid)
		)
		(fill yes)
		(layer "In11.Cu")
		(net "M_H_CPU0_SB_DQ<26>")
	)
	(gr_poly
		(pts
			(xy 373.858536 -235.174282) (xy 373.811546 -235.021882) (xy 373.549926 -235.021882) (xy 373.502936 -235.174282)
			(xy 373.502936 -235.218732) (xy 373.858536 -235.218732)
		)
		(stroke
			(width 0)
			(type solid)
		)
		(fill yes)
		(layer "In11.Cu")
		(net "M_H_CPU0_SB_DQ<7>")
	)
	(gr_poly
		(pts
			(xy 373.858536 -234.76585) (xy 373.858536 -234.7214) (xy 373.502936 -234.7214) (xy 373.502936 -234.76585)
			(xy 373.549926 -234.91825) (xy 373.811546 -234.91825)
		)
		(stroke
			(width 0)
			(type solid)
		)
		(fill yes)
		(layer "In11.Cu")
		(net "M_H_CPU0_SB_DQ<8>")
	)
	(gr_poly
		(pts
			(xy 373.858536 -233.13771) (xy 373.858536 -233.093514) (xy 373.502936 -233.093514) (xy 373.502936 -233.13771)
			(xy 373.549926 -233.29011) (xy 373.811546 -233.29011)
		)
		(stroke
			(width 0)
			(type solid)
		)
		(fill yes)
		(layer "In11.Cu")
		(net "M_H_CPU0_SB_DQS_DP<1>")
	)
	(gr_poly
		(pts
			(xy 373.859044 -277.081742) (xy 373.82069 -277.059644) (xy 373.665242 -277.024084) (xy 373.534432 -277.250652)
			(xy 373.64289 -277.367492) (xy 373.681244 -277.38959)
		)
		(stroke
			(width 0)
			(type solid)
		)
		(fill yes)
		(layer "In11.Cu")
		(net "M_H_CPU0_SA_DQS_DP<1>")
	)
	(gr_poly
		(pts
			(xy 373.930418 -278.992838) (xy 374.038876 -278.875998) (xy 373.908066 -278.64943) (xy 373.752618 -278.68499)
			(xy 373.714264 -278.707088) (xy 373.892064 -279.014936)
		)
		(stroke
			(width 0)
			(type solid)
		)
		(fill yes)
		(layer "In11.Cu")
		(net "M_H_CPU0_SA_DQ<11>")
	)
	(gr_poly
		(pts
			(xy 373.95658 -256.157222) (xy 373.95658 -256.113026) (xy 373.60098 -256.113026) (xy 373.60098 -256.157222)
			(xy 373.64797 -256.309622) (xy 373.90959 -256.309622)
		)
		(stroke
			(width 0)
			(type solid)
		)
		(fill yes)
		(layer "In11.Cu")
		(net "M_H_CPU0_SA_CS_N<2>")
	)
	(gr_poly
		(pts
			(xy 373.95912 -280.574242) (xy 373.95912 -280.529792) (xy 373.60352 -280.529792) (xy 373.60352 -280.574242)
			(xy 373.65051 -280.726642) (xy 373.91213 -280.726642)
		)
		(stroke
			(width 0)
			(type solid)
		)
		(fill yes)
		(layer "In11.Cu")
		(net "M_H_CPU0_SA_DQ<8>")
	)
	(gr_poly
		(pts
			(xy 373.95912 -272.843498) (xy 373.91213 -272.691098) (xy 373.65051 -272.691098) (xy 373.60352 -272.843498)
			(xy 373.60352 -272.887948) (xy 373.95912 -272.887948)
		)
		(stroke
			(width 0)
			(type solid)
		)
		(fill yes)
		(layer "In11.Cu")
		(net "M_H_CPU0_SA_DQ<15>")
	)
	(gr_poly
		(pts
			(xy 373.95912 -263.07669) (xy 373.91213 -262.92429) (xy 373.65051 -262.92429) (xy 373.60352 -263.07669)
			(xy 373.60352 -263.12114) (xy 373.95912 -263.12114)
		)
		(stroke
			(width 0)
			(type solid)
		)
		(fill yes)
		(layer "In11.Cu")
		(net "M_H_CPU0_SA_DQ<31>")
	)
	(gr_poly
		(pts
			(xy 373.95912 -258.193286) (xy 373.91213 -258.040886) (xy 373.65051 -258.040886) (xy 373.60352 -258.193286)
			(xy 373.60352 -258.237736) (xy 373.95912 -258.237736)
		)
		(stroke
			(width 0)
			(type solid)
		)
		(fill yes)
		(layer "In11.Cu")
		(net "M_H_CPU0_SA_CB<7>")
	)
	(gr_poly
		(pts
			(xy 373.964962 -267.551662) (xy 373.964962 -267.507212) (xy 373.609362 -267.507212) (xy 373.609362 -267.551662)
			(xy 373.656352 -267.704062) (xy 373.917972 -267.704062)
		)
		(stroke
			(width 0)
			(type solid)
		)
		(fill yes)
		(layer "In11.Cu")
		(net "M_H_CPU0_SA_DQ<24>")
	)
	(gr_poly
		(pts
			(xy 373.968518 -270.806926) (xy 373.968518 -270.76273) (xy 373.612918 -270.76273) (xy 373.612918 -270.806926)
			(xy 373.659908 -270.959326) (xy 373.921528 -270.959326)
		)
		(stroke
			(width 0)
			(type solid)
		)
		(fill yes)
		(layer "In11.Cu")
		(net "M_H_CPU0_SA_DQS_DP<2>")
	)
	(gr_poly
		(pts
			(xy 373.971058 -272.435066) (xy 373.971058 -272.390616) (xy 373.615458 -272.390616) (xy 373.615458 -272.435066)
			(xy 373.662448 -272.587466) (xy 373.924068 -272.587466)
		)
		(stroke
			(width 0)
			(type solid)
		)
		(fill yes)
		(layer "In11.Cu")
		(net "M_H_CPU0_SA_DQ<16>")
	)
	(gr_poly
		(pts
			(xy 373.971058 -262.668258) (xy 373.971058 -262.623808) (xy 373.615458 -262.623808) (xy 373.615458 -262.668258)
			(xy 373.662448 -262.820658) (xy 373.924068 -262.820658)
		)
		(stroke
			(width 0)
			(type solid)
		)
		(fill yes)
		(layer "In11.Cu")
		(net "M_H_CPU0_SA_CB<0>")
	)
	(gr_poly
		(pts
			(xy 373.971058 -257.784854) (xy 373.971058 -257.740404) (xy 373.615458 -257.740404) (xy 373.615458 -257.784854)
			(xy 373.662448 -257.937254) (xy 373.924068 -257.937254)
		)
		(stroke
			(width 0)
			(type solid)
		)
		(fill yes)
		(layer "In11.Cu")
		(net "M_E_CPU0_ALERT_N")
	)
	(gr_poly
		(pts
			(xy 374.17629 -247.633998) (xy 374.214644 -247.6119) (xy 374.036844 -247.304052) (xy 373.99849 -247.32615)
			(xy 373.890032 -247.44299) (xy 374.020842 -247.669558)
		)
		(stroke
			(width 0)
			(type solid)
		)
		(fill yes)
		(layer "In11.Cu")
		(net "M_H_CPU0_SB_CA<0>")
	)
	(gr_poly
		(pts
			(xy 374.181878 -249.271536) (xy 374.220232 -249.249438) (xy 374.042432 -248.94159) (xy 374.004078 -248.963688)
			(xy 373.89562 -249.080528) (xy 374.02643 -249.307096)
		)
		(stroke
			(width 0)
			(type solid)
		)
		(fill yes)
		(layer "In11.Cu")
		(net "M_H_CPU0_CLK_DP<0>")
	)
	(gr_poly
		(pts
			(xy 374.289574 -248.647204) (xy 374.398032 -248.530364) (xy 374.267222 -248.303796) (xy 374.111774 -248.339356)
			(xy 374.07342 -248.361454) (xy 374.25122 -248.669302)
		)
		(stroke
			(width 0)
			(type solid)
		)
		(fill yes)
		(layer "In11.Cu")
		(net "M_H_CPU0_CLK_DN<0>")
	)
	(gr_poly
		(pts
			(xy 374.29186 -278.80183) (xy 374.330214 -278.779732) (xy 374.152414 -278.471884) (xy 374.11406 -278.493982)
			(xy 374.005602 -278.610822) (xy 374.136412 -278.83739)
		)
		(stroke
			(width 0)
			(type solid)
		)
		(fill yes)
		(layer "In11.Cu")
		(net "M_H_CPU0_SA_DQS_DP<1>")
	)
	(gr_poly
		(pts
			(xy 374.295924 -247.030494) (xy 374.404382 -246.913654) (xy 374.273572 -246.687086) (xy 374.118124 -246.722646)
			(xy 374.07977 -246.744744) (xy 374.25757 -247.052592)
		)
		(stroke
			(width 0)
			(type solid)
		)
		(fill yes)
		(layer "In11.Cu")
		(net "M_H_CPU0_SB_CA<1>")
	)
	(gr_poly
		(pts
			(xy 374.319038 -242.499642) (xy 374.272048 -242.347242) (xy 374.010428 -242.347242) (xy 373.963438 -242.499642)
			(xy 373.963438 -242.543838) (xy 374.319038 -242.543838)
		)
		(stroke
			(width 0)
			(type solid)
		)
		(fill yes)
		(layer "In11.Cu")
		(net "M_H_CPU0_SB_DQS_DN<9>")
	)
	(gr_poly
		(pts
			(xy 374.319038 -237.616238) (xy 374.272048 -237.463838) (xy 374.010428 -237.463838) (xy 373.963438 -237.616238)
			(xy 373.963438 -237.660434) (xy 374.319038 -237.660434)
		)
		(stroke
			(width 0)
			(type solid)
		)
		(fill yes)
		(layer "In11.Cu")
		(net "M_H_CPU0_SB_DQS_DN<0>")
	)
	(gr_poly
		(pts
			(xy 374.321578 -235.579666) (xy 374.321578 -235.535216) (xy 373.965978 -235.535216) (xy 373.965978 -235.579666)
			(xy 374.012968 -235.732066) (xy 374.274588 -235.732066)
		)
		(stroke
			(width 0)
			(type solid)
		)
		(fill yes)
		(layer "In11.Cu")
		(net "M_H_CPU0_SB_DQ<5>")
	)
	(gr_poly
		(pts
			(xy 374.325134 -243.718334) (xy 374.325134 -243.674138) (xy 373.969534 -243.674138) (xy 373.969534 -243.718334)
			(xy 374.016524 -243.870734) (xy 374.278144 -243.870734)
		)
		(stroke
			(width 0)
			(type solid)
		)
		(fill yes)
		(layer "In11.Cu")
		(net "M_H_CPU0_SB_CB<7>")
	)
	(gr_poly
		(pts
			(xy 374.325134 -238.83493) (xy 374.325134 -238.790734) (xy 373.969534 -238.790734) (xy 373.969534 -238.83493)
			(xy 374.016524 -238.98733) (xy 374.278144 -238.98733)
		)
		(stroke
			(width 0)
			(type solid)
		)
		(fill yes)
		(layer "In11.Cu")
		(net "M_H_CPU0_SB_DQ<1>")
	)
	(gr_poly
		(pts
			(xy 374.325134 -233.952034) (xy 374.325134 -233.907584) (xy 373.969534 -233.907584) (xy 373.969534 -233.952034)
			(xy 374.016524 -234.104434) (xy 374.278144 -234.104434)
		)
		(stroke
			(width 0)
			(type solid)
		)
		(fill yes)
		(layer "In11.Cu")
		(net "M_H_CPU0_SB_DQ<9>")
	)
	(gr_poly
		(pts
			(xy 374.325134 -229.06863) (xy 374.325134 -229.02418) (xy 373.969534 -229.02418) (xy 373.969534 -229.06863)
			(xy 374.016524 -229.22103) (xy 374.278144 -229.22103)
		)
		(stroke
			(width 0)
			(type solid)
		)
		(fill yes)
		(layer "In11.Cu")
		(net "M_H_CPU0_SB_DQ<27>")
	)
	(gr_poly
		(pts
			(xy 374.328436 -232.732834) (xy 374.281446 -232.580434) (xy 374.019826 -232.580434) (xy 373.972836 -232.732834)
			(xy 373.972836 -232.77703) (xy 374.328436 -232.77703)
		)
		(stroke
			(width 0)
			(type solid)
		)
		(fill yes)
		(layer "In11.Cu")
		(net "M_H_CPU0_SB_DQS_DN<1>")
	)
	(gr_poly
		(pts
			(xy 374.330976 -240.871502) (xy 374.283986 -240.719102) (xy 374.022366 -240.719102) (xy 373.975376 -240.871502)
			(xy 373.975376 -240.915698) (xy 374.330976 -240.915698)
		)
		(stroke
			(width 0)
			(type solid)
		)
		(fill yes)
		(layer "In11.Cu")
		(net "M_H_CPU0_SB_CB<2>")
	)
	(gr_poly
		(pts
			(xy 374.330976 -240.46307) (xy 374.330976 -240.418874) (xy 373.975376 -240.418874) (xy 373.975376 -240.46307)
			(xy 374.022366 -240.61547) (xy 374.283986 -240.61547)
		)
		(stroke
			(width 0)
			(type solid)
		)
		(fill yes)
		(layer "In11.Cu")
		(net "M_H_CPU0_SB_CB<1>")
	)
	(gr_poly
		(pts
			(xy 374.330976 -235.988098) (xy 374.283986 -235.835698) (xy 374.022366 -235.835698) (xy 373.975376 -235.988098)
			(xy 373.975376 -236.032294) (xy 374.330976 -236.032294)
		)
		(stroke
			(width 0)
			(type solid)
		)
		(fill yes)
		(layer "In11.Cu")
		(net "M_H_CPU0_SB_DQ<6>")
	)
	(gr_poly
		(pts
			(xy 374.333516 -244.126766) (xy 374.286526 -243.974366) (xy 374.024906 -243.974366) (xy 373.977916 -244.126766)
			(xy 373.977916 -244.171216) (xy 374.333516 -244.171216)
		)
		(stroke
			(width 0)
			(type solid)
		)
		(fill yes)
		(layer "In11.Cu")
		(net "M_H_CPU0_SB_CB<4>")
	)
	(gr_poly
		(pts
			(xy 374.333516 -239.243362) (xy 374.286526 -239.090962) (xy 374.024906 -239.090962) (xy 373.977916 -239.243362)
			(xy 373.977916 -239.287812) (xy 374.333516 -239.287812)
		)
		(stroke
			(width 0)
			(type solid)
		)
		(fill yes)
		(layer "In11.Cu")
		(net "M_H_CPU0_SB_DQ<2>")
	)
	(gr_poly
		(pts
			(xy 374.333516 -234.360466) (xy 374.286526 -234.208066) (xy 374.024906 -234.208066) (xy 373.977916 -234.360466)
			(xy 373.977916 -234.404662) (xy 374.333516 -234.404662)
		)
		(stroke
			(width 0)
			(type solid)
		)
		(fill yes)
		(layer "In11.Cu")
		(net "M_H_CPU0_SB_DQ<10>")
	)
	(gr_poly
		(pts
			(xy 374.333516 -231.104694) (xy 374.286526 -230.952294) (xy 374.024906 -230.952294) (xy 373.977916 -231.104694)
			(xy 373.977916 -231.14889) (xy 374.333516 -231.14889)
		)
		(stroke
			(width 0)
			(type solid)
		)
		(fill yes)
		(layer "In11.Cu")
		(net "M_H_CPU0_SB_DQ<14>")
	)
	(gr_poly
		(pts
			(xy 374.333516 -230.696262) (xy 374.333516 -230.652066) (xy 373.977916 -230.652066) (xy 373.977916 -230.696262)
			(xy 374.024906 -230.848662) (xy 374.286526 -230.848662)
		)
		(stroke
			(width 0)
			(type solid)
		)
		(fill yes)
		(layer "In11.Cu")
		(net "M_H_CPU0_SB_DQ<13>")
	)
	(gr_poly
		(pts
			(xy 374.333516 -229.477062) (xy 374.286526 -229.324662) (xy 374.024906 -229.324662) (xy 373.977916 -229.477062)
			(xy 373.977916 -229.521258) (xy 374.333516 -229.521258)
		)
		(stroke
			(width 0)
			(type solid)
		)
		(fill yes)
		(layer "In11.Cu")
		(net "M_H_CPU0_SB_DQ<24>")
	)
	(gr_poly
		(pts
			(xy 374.333516 -226.22129) (xy 374.286526 -226.06889) (xy 374.024906 -226.06889) (xy 373.977916 -226.22129)
			(xy 373.977916 -226.26574) (xy 374.333516 -226.26574)
		)
		(stroke
			(width 0)
			(type solid)
		)
		(fill yes)
		(layer "In11.Cu")
		(net "M_H_CPU0_SB_DQ<28>")
	)
	(gr_poly
		(pts
			(xy 374.333516 -225.813366) (xy 374.333516 -225.768916) (xy 373.977916 -225.768916) (xy 373.977916 -225.813366)
			(xy 374.024906 -225.965766) (xy 374.286526 -225.965766)
		)
		(stroke
			(width 0)
			(type solid)
		)
		(fill yes)
		(layer "In11.Cu")
		(net "M_H_CPU0_SB_DQ<31>")
	)
	(gr_poly
		(pts
			(xy 374.400572 -278.17953) (xy 374.50903 -278.06269) (xy 374.37822 -277.836122) (xy 374.222772 -277.871682)
			(xy 374.184418 -277.89378) (xy 374.362218 -278.201628)
		)
		(stroke
			(width 0)
			(type solid)
		)
		(fill yes)
		(layer "In11.Cu")
		(net "M_H_CPU0_SA_DQS_DN<1>")
	)
	(gr_poly
		(pts
			(xy 374.42902 -280.16835) (xy 374.38203 -280.01595) (xy 374.12041 -280.01595) (xy 374.07342 -280.16835)
			(xy 374.07342 -280.2128) (xy 374.42902 -280.2128)
		)
		(stroke
			(width 0)
			(type solid)
		)
		(fill yes)
		(layer "In11.Cu")
		(net "M_H_CPU0_SA_DQ<10>")
	)
	(gr_poly
		(pts
			(xy 374.430798 -270.40205) (xy 374.383808 -270.24965) (xy 374.122188 -270.24965) (xy 374.075198 -270.40205)
			(xy 374.075198 -270.446246) (xy 374.430798 -270.446246)
		)
		(stroke
			(width 0)
			(type solid)
		)
		(fill yes)
		(layer "In11.Cu")
		(net "M_H_CPU0_SA_DQS_DN<2>")
	)
	(gr_poly
		(pts
			(xy 374.43156 -268.77391) (xy 374.38457 -268.62151) (xy 374.12295 -268.62151) (xy 374.07596 -268.77391)
			(xy 374.07596 -268.81836) (xy 374.43156 -268.81836)
		)
		(stroke
			(width 0)
			(type solid)
		)
		(fill yes)
		(layer "In11.Cu")
		(net "M_H_CPU0_SA_DQ<22>")
	)
	(gr_poly
		(pts
			(xy 374.435116 -268.365478) (xy 374.435116 -268.321028) (xy 374.079516 -268.321028) (xy 374.079516 -268.365478)
			(xy 374.126506 -268.517878) (xy 374.388126 -268.517878)
		)
		(stroke
			(width 0)
			(type solid)
		)
		(fill yes)
		(layer "In11.Cu")
		(net "M_H_CPU0_SA_DQ<21>")
	)
	(gr_poly
		(pts
			(xy 374.435116 -263.891014) (xy 374.388126 -263.738614) (xy 374.126506 -263.738614) (xy 374.079516 -263.891014)
			(xy 374.079516 -263.93521) (xy 374.435116 -263.93521)
		)
		(stroke
			(width 0)
			(type solid)
		)
		(fill yes)
		(layer "In11.Cu")
		(net "M_H_CPU0_SA_DQ<30>")
	)
	(gr_poly
		(pts
			(xy 374.435116 -254.124206) (xy 374.388126 -253.971806) (xy 374.126506 -253.971806) (xy 374.079516 -254.124206)
			(xy 374.079516 -254.168402) (xy 374.435116 -254.168402)
		)
		(stroke
			(width 0)
			(type solid)
		)
		(fill yes)
		(layer "In11.Cu")
		(net "M_H_CPU0_SA_CA<3>")
	)
	(gr_poly
		(pts
			(xy 374.43537 -266.737846) (xy 374.43537 -266.693396) (xy 374.07977 -266.693396) (xy 374.07977 -266.737846)
			(xy 374.12676 -266.890246) (xy 374.38838 -266.890246)
		)
		(stroke
			(width 0)
			(type solid)
		)
		(fill yes)
		(layer "In11.Cu")
		(net "M_H_CPU0_SA_DQ<25>")
	)
	(gr_poly
		(pts
			(xy 374.440958 -279.759664) (xy 374.440958 -279.715468) (xy 374.085358 -279.715468) (xy 374.085358 -279.759664)
			(xy 374.132348 -279.912064) (xy 374.393968 -279.912064)
		)
		(stroke
			(width 0)
			(type solid)
		)
		(fill yes)
		(layer "In11.Cu")
		(net "M_H_CPU0_SA_DQ<9>")
	)
	(gr_poly
		(pts
			(xy 374.440958 -272.029174) (xy 374.393968 -271.876774) (xy 374.132348 -271.876774) (xy 374.085358 -272.029174)
			(xy 374.085358 -272.073624) (xy 374.440958 -272.073624)
		)
		(stroke
			(width 0)
			(type solid)
		)
		(fill yes)
		(layer "In11.Cu")
		(net "M_H_CPU0_SA_DQ<18>")
	)
	(gr_poly
		(pts
			(xy 374.440958 -271.62125) (xy 374.440958 -271.5768) (xy 374.085358 -271.5768) (xy 374.085358 -271.62125)
			(xy 374.132348 -271.77365) (xy 374.393968 -271.77365)
		)
		(stroke
			(width 0)
			(type solid)
		)
		(fill yes)
		(layer "In11.Cu")
		(net "M_H_CPU0_SA_DQ<17>")
	)
	(gr_poly
		(pts
			(xy 374.440958 -267.14577) (xy 374.393968 -266.99337) (xy 374.132348 -266.99337) (xy 374.085358 -267.14577)
			(xy 374.085358 -267.19022) (xy 374.440958 -267.19022)
		)
		(stroke
			(width 0)
			(type solid)
		)
		(fill yes)
		(layer "In11.Cu")
		(net "M_H_CPU0_SA_DQ<26>")
	)
	(gr_poly
		(pts
			(xy 374.440958 -265.518646) (xy 374.393968 -265.366246) (xy 374.132348 -265.366246) (xy 374.085358 -265.518646)
			(xy 374.085358 -265.562842) (xy 374.440958 -265.562842)
		)
		(stroke
			(width 0)
			(type solid)
		)
		(fill yes)
		(layer "In11.Cu")
		(net "M_H_CPU0_SA_DQS_DN<3>")
	)
	(gr_poly
		(pts
			(xy 374.440958 -262.262874) (xy 374.393968 -262.110474) (xy 374.132348 -262.110474) (xy 374.085358 -262.262874)
			(xy 374.085358 -262.30707) (xy 374.440958 -262.30707)
		)
		(stroke
			(width 0)
			(type solid)
		)
		(fill yes)
		(layer "In11.Cu")
		(net "M_H_CPU0_SA_CB<2>")
	)
	(gr_poly
		(pts
			(xy 374.440958 -261.854442) (xy 374.440958 -261.810246) (xy 374.085358 -261.810246) (xy 374.085358 -261.854442)
			(xy 374.132348 -262.006842) (xy 374.393968 -262.006842)
		)
		(stroke
			(width 0)
			(type solid)
		)
		(fill yes)
		(layer "In11.Cu")
		(net "M_H_CPU0_SA_CB<1>")
	)
	(gr_poly
		(pts
			(xy 374.440958 -260.635242) (xy 374.393968 -260.482842) (xy 374.132348 -260.482842) (xy 374.085358 -260.635242)
			(xy 374.085358 -260.679438) (xy 374.440958 -260.679438)
		)
		(stroke
			(width 0)
			(type solid)
		)
		(fill yes)
		(layer "In11.Cu")
		(net "M_H_CPU0_SA_DQS_DN<4>")
	)
	(gr_poly
		(pts
			(xy 374.440958 -257.37947) (xy 374.393968 -257.22707) (xy 374.132348 -257.22707) (xy 374.085358 -257.37947)
			(xy 374.085358 -257.423666) (xy 374.440958 -257.423666)
		)
		(stroke
			(width 0)
			(type solid)
		)
		(fill yes)
		(layer "In11.Cu")
		(net "M_H_CPU0_ALERT_N")
	)
	(gr_poly
		(pts
			(xy 374.440958 -256.971038) (xy 374.440958 -256.926842) (xy 374.085358 -256.926842) (xy 374.085358 -256.971038)
			(xy 374.132348 -257.123438) (xy 374.393968 -257.123438)
		)
		(stroke
			(width 0)
			(type solid)
		)
		(fill yes)
		(layer "In11.Cu")
		(net "M_H_CPU0_SA_CS_N<0>")
	)
	(gr_poly
		(pts
			(xy 374.440958 -255.751838) (xy 374.393968 -255.599438) (xy 374.132348 -255.599438) (xy 374.085358 -255.751838)
			(xy 374.085358 -255.796288) (xy 374.440958 -255.796288)
		)
		(stroke
			(width 0)
			(type solid)
		)
		(fill yes)
		(layer "In11.Cu")
		(net "M_H_CPU0_SA_CS_N<3>")
	)
	(gr_poly
		(pts
			(xy 374.443498 -273.248882) (xy 374.443498 -273.204686) (xy 374.087898 -273.204686) (xy 374.087898 -273.248882)
			(xy 374.134888 -273.401282) (xy 374.396508 -273.401282)
		)
		(stroke
			(width 0)
			(type solid)
		)
		(fill yes)
		(layer "In11.Cu")
		(net "M_H_CPU0_SA_DQ<13>")
	)
	(gr_poly
		(pts
			(xy 374.443498 -263.482582) (xy 374.443498 -263.438132) (xy 374.087898 -263.438132) (xy 374.087898 -263.482582)
			(xy 374.134888 -263.634982) (xy 374.396508 -263.634982)
		)
		(stroke
			(width 0)
			(type solid)
		)
		(fill yes)
		(layer "In11.Cu")
		(net "M_H_CPU0_SA_DQ<29>")
	)
	(gr_poly
		(pts
			(xy 374.443498 -259.007102) (xy 374.396508 -258.854702) (xy 374.134888 -258.854702) (xy 374.087898 -259.007102)
			(xy 374.087898 -259.051552) (xy 374.443498 -259.051552)
		)
		(stroke
			(width 0)
			(type solid)
		)
		(fill yes)
		(layer "In11.Cu")
		(net "M_H_CPU0_SA_CB<6>")
	)
	(gr_poly
		(pts
			(xy 374.443498 -258.599178) (xy 374.443498 -258.554728) (xy 374.087898 -258.554728) (xy 374.087898 -258.599178)
			(xy 374.134888 -258.751578) (xy 374.396508 -258.751578)
		)
		(stroke
			(width 0)
			(type solid)
		)
		(fill yes)
		(layer "In11.Cu")
		(net "M_H_CPU0_SA_CB<5>")
	)
	(gr_poly
		(pts
			(xy 374.651524 -248.456958) (xy 374.689878 -248.43486) (xy 374.512078 -248.127012) (xy 374.473724 -248.14911)
			(xy 374.365266 -248.26595) (xy 374.496076 -248.492518)
		)
		(stroke
			(width 0)
			(type solid)
		)
		(fill yes)
		(layer "In11.Cu")
		(net "M_H_CPU0_SB_CA<0>")
	)
	(gr_poly
		(pts
			(xy 374.756172 -276.350476) (xy 374.794526 -276.328378) (xy 374.616726 -276.02053) (xy 374.578372 -276.042628)
			(xy 374.469914 -276.159468) (xy 374.600724 -276.386036)
		)
		(stroke
			(width 0)
			(type solid)
		)
		(fill yes)
		(layer "In11.Cu")
		(net "M_H_CPU0_SA_DQS_DN<6>")
	)
	(gr_poly
		(pts
			(xy 374.76049 -274.729702) (xy 374.798844 -274.707604) (xy 374.621044 -274.399756) (xy 374.58269 -274.421854)
			(xy 374.474232 -274.538694) (xy 374.605042 -274.765262)
		)
		(stroke
			(width 0)
			(type solid)
		)
		(fill yes)
		(layer "In11.Cu")
		(net "M_H_CPU0_SA_DQ<12>")
	)
	(gr_poly
		(pts
			(xy 374.765824 -247.84431) (xy 374.874282 -247.72747) (xy 374.743472 -247.500902) (xy 374.588024 -247.536462)
			(xy 374.54967 -247.55856) (xy 374.72747 -247.866408)
		)
		(stroke
			(width 0)
			(type solid)
		)
		(fill yes)
		(layer "In11.Cu")
		(net "M_H_CPU0_SB_CA<1>")
	)
	(gr_poly
		(pts
			(xy 374.786398 -241.685318) (xy 374.739408 -241.532918) (xy 374.477788 -241.532918) (xy 374.430798 -241.685318)
			(xy 374.430798 -241.729514) (xy 374.786398 -241.729514)
		)
		(stroke
			(width 0)
			(type solid)
		)
		(fill yes)
		(layer "In11.Cu")
		(net "M_H_CPU0_SB_DQS_DP<4>")
	)
	(gr_poly
		(pts
			(xy 374.786398 -241.276886) (xy 374.786398 -241.23269) (xy 374.430798 -241.23269) (xy 374.430798 -241.276886)
			(xy 374.477788 -241.429286) (xy 374.739408 -241.429286)
		)
		(stroke
			(width 0)
			(type solid)
		)
		(fill yes)
		(layer "In11.Cu")
		(net "M_H_CPU0_SB_CB<0>")
	)
	(gr_poly
		(pts
			(xy 374.786398 -240.057178) (xy 374.739408 -239.904778) (xy 374.477788 -239.904778) (xy 374.430798 -240.057178)
			(xy 374.430798 -240.101628) (xy 374.786398 -240.101628)
		)
		(stroke
			(width 0)
			(type solid)
		)
		(fill yes)
		(layer "In11.Cu")
		(net "M_H_CPU0_SB_CB<3>")
	)
	(gr_poly
		(pts
			(xy 374.786398 -239.649254) (xy 374.786398 -239.604804) (xy 374.430798 -239.604804) (xy 374.430798 -239.649254)
			(xy 374.477788 -239.801654) (xy 374.739408 -239.801654)
		)
		(stroke
			(width 0)
			(type solid)
		)
		(fill yes)
		(layer "In11.Cu")
		(net "M_H_CPU0_SB_DQ<0>")
	)
	(gr_poly
		(pts
			(xy 374.786398 -236.801914) (xy 374.739408 -236.649514) (xy 374.477788 -236.649514) (xy 374.430798 -236.801914)
			(xy 374.430798 -236.84611) (xy 374.786398 -236.84611)
		)
		(stroke
			(width 0)
			(type solid)
		)
		(fill yes)
		(layer "In11.Cu")
		(net "M_H_CPU0_SB_DQS_DP<5>")
	)
	(gr_poly
		(pts
			(xy 374.786398 -236.39399) (xy 374.786398 -236.34954) (xy 374.430798 -236.34954) (xy 374.430798 -236.39399)
			(xy 374.477788 -236.54639) (xy 374.739408 -236.54639)
		)
		(stroke
			(width 0)
			(type solid)
		)
		(fill yes)
		(layer "In11.Cu")
		(net "M_H_CPU0_SB_DQ<4>")
	)
	(gr_poly
		(pts
			(xy 374.786398 -234.76585) (xy 374.786398 -234.721654) (xy 374.430798 -234.721654) (xy 374.430798 -234.76585)
			(xy 374.477788 -234.91825) (xy 374.739408 -234.91825)
		)
		(stroke
			(width 0)
			(type solid)
		)
		(fill yes)
		(layer "In11.Cu")
		(net "M_H_CPU0_SB_DQ<8>")
	)
	(gr_poly
		(pts
			(xy 374.786398 -231.510586) (xy 374.786398 -231.466136) (xy 374.430798 -231.466136) (xy 374.430798 -231.510586)
			(xy 374.477788 -231.662986) (xy 374.739408 -231.662986)
		)
		(stroke
			(width 0)
			(type solid)
		)
		(fill yes)
		(layer "In11.Cu")
		(net "M_H_CPU0_SB_DQ<12>")
	)
	(gr_poly
		(pts
			(xy 374.786398 -230.290878) (xy 374.739408 -230.138478) (xy 374.477788 -230.138478) (xy 374.430798 -230.290878)
			(xy 374.430798 -230.335074) (xy 374.786398 -230.335074)
		)
		(stroke
			(width 0)
			(type solid)
		)
		(fill yes)
		(layer "In11.Cu")
		(net "M_H_CPU0_SB_DQ<15>")
	)
	(gr_poly
		(pts
			(xy 374.786398 -229.882446) (xy 374.786398 -229.83825) (xy 374.430798 -229.83825) (xy 374.430798 -229.882446)
			(xy 374.477788 -230.034846) (xy 374.739408 -230.034846)
		)
		(stroke
			(width 0)
			(type solid)
		)
		(fill yes)
		(layer "In11.Cu")
		(net "M_H_CPU0_SB_DQ<26>")
	)
	(gr_poly
		(pts
			(xy 374.786398 -225.407474) (xy 374.739408 -225.255074) (xy 374.477788 -225.255074) (xy 374.430798 -225.407474)
			(xy 374.430798 -225.45167) (xy 374.786398 -225.45167)
		)
		(stroke
			(width 0)
			(type solid)
		)
		(fill yes)
		(layer "In11.Cu")
		(net "M_H_CPU0_SB_DQ<29>")
	)
	(gr_poly
		(pts
			(xy 374.786652 -233.546142) (xy 374.739662 -233.393742) (xy 374.478042 -233.393742) (xy 374.431052 -233.546142)
			(xy 374.431052 -233.590592) (xy 374.786652 -233.590592)
		)
		(stroke
			(width 0)
			(type solid)
		)
		(fill yes)
		(layer "In11.Cu")
		(net "M_H_CPU0_SB_DQ<11>")
	)
	(gr_poly
		(pts
			(xy 374.788938 -244.532658) (xy 374.788938 -244.488208) (xy 374.433338 -244.488208) (xy 374.433338 -244.532658)
			(xy 374.480328 -244.685058) (xy 374.741948 -244.685058)
		)
		(stroke
			(width 0)
			(type solid)
		)
		(fill yes)
		(layer "In11.Cu")
		(net "M_H_CPU0_SB_CB<6>")
	)
	(gr_poly
		(pts
			(xy 374.788938 -243.313458) (xy 374.741948 -243.161058) (xy 374.480328 -243.161058) (xy 374.433338 -243.313458)
			(xy 374.433338 -243.357654) (xy 374.788938 -243.357654)
		)
		(stroke
			(width 0)
			(type solid)
		)
		(fill yes)
		(layer "In11.Cu")
		(net "M_H_CPU0_SB_CB<5>")
	)
	(gr_poly
		(pts
			(xy 374.788938 -238.430054) (xy 374.741948 -238.277654) (xy 374.480328 -238.277654) (xy 374.433338 -238.430054)
			(xy 374.433338 -238.47425) (xy 374.788938 -238.47425)
		)
		(stroke
			(width 0)
			(type solid)
		)
		(fill yes)
		(layer "In11.Cu")
		(net "M_H_CPU0_SB_DQ<3>")
	)
	(gr_poly
		(pts
			(xy 374.788938 -238.021114) (xy 374.788938 -237.976918) (xy 374.433338 -237.976918) (xy 374.433338 -238.021114)
			(xy 374.480328 -238.173514) (xy 374.741948 -238.173514)
		)
		(stroke
			(width 0)
			(type solid)
		)
		(fill yes)
		(layer "In11.Cu")
		(net "M_H_CPU0_SB_DQS_DP<0>")
	)
	(gr_poly
		(pts
			(xy 374.788938 -228.663246) (xy 374.741948 -228.510846) (xy 374.480328 -228.510846) (xy 374.433338 -228.663246)
			(xy 374.433338 -228.707696) (xy 374.788938 -228.707696)
		)
		(stroke
			(width 0)
			(type solid)
		)
		(fill yes)
		(layer "In11.Cu")
		(net "M_H_CPU0_SB_DQ<25>")
	)
	(gr_poly
		(pts
			(xy 374.788938 -228.254814) (xy 374.788938 -228.210364) (xy 374.433338 -228.210364) (xy 374.433338 -228.254814)
			(xy 374.480328 -228.407214) (xy 374.741948 -228.407214)
		)
		(stroke
			(width 0)
			(type solid)
		)
		(fill yes)
		(layer "In11.Cu")
		(net "M_H_CPU0_SB_DQS_DN<8>")
	)
	(gr_poly
		(pts
			(xy 374.788938 -227.035106) (xy 374.741948 -226.882706) (xy 374.480328 -226.882706) (xy 374.433338 -227.035106)
			(xy 374.433338 -227.079556) (xy 374.788938 -227.079556)
		)
		(stroke
			(width 0)
			(type solid)
		)
		(fill yes)
		(layer "In11.Cu")
		(net "M_H_CPU0_SB_DQS_DN<3>")
	)
	(gr_poly
		(pts
			(xy 374.788938 -226.627182) (xy 374.788938 -226.582732) (xy 374.433338 -226.582732) (xy 374.433338 -226.627182)
			(xy 374.480328 -226.779582) (xy 374.741948 -226.779582)
		)
		(stroke
			(width 0)
			(type solid)
		)
		(fill yes)
		(layer "In11.Cu")
		(net "M_H_CPU0_SB_DQ<30>")
	)
	(gr_poly
		(pts
			(xy 374.792748 -233.13771) (xy 374.792748 -233.093514) (xy 374.437148 -233.093514) (xy 374.437148 -233.13771)
			(xy 374.484138 -233.29011) (xy 374.745758 -233.29011)
		)
		(stroke
			(width 0)
			(type solid)
		)
		(fill yes)
		(layer "In11.Cu")
		(net "M_H_CPU0_SB_DQS_DP<1>")
	)
	(gr_poly
		(pts
			(xy 374.794272 -231.919018) (xy 374.747282 -231.766618) (xy 374.485662 -231.766618) (xy 374.438672 -231.919018)
			(xy 374.438672 -231.963214) (xy 374.794272 -231.963214)
		)
		(stroke
			(width 0)
			(type solid)
		)
		(fill yes)
		(layer "In11.Cu")
		(net "M_H_CPU0_SB_DQS_DP<6>")
	)
	(gr_poly
		(pts
			(xy 374.798336 -235.174282) (xy 374.751346 -235.021882) (xy 374.489726 -235.021882) (xy 374.442736 -235.174282)
			(xy 374.442736 -235.218732) (xy 374.798336 -235.218732)
		)
		(stroke
			(width 0)
			(type solid)
		)
		(fill yes)
		(layer "In11.Cu")
		(net "M_H_CPU0_SB_DQ<7>")
	)
	(gr_poly
		(pts
			(xy 374.800876 -242.904518) (xy 374.800876 -242.860322) (xy 374.445276 -242.860322) (xy 374.445276 -242.904518)
			(xy 374.492266 -243.056918) (xy 374.753886 -243.056918)
		)
		(stroke
			(width 0)
			(type solid)
		)
		(fill yes)
		(layer "In11.Cu")
		(net "M_H_CPU0_SB_DQS_DP<9>")
	)
	(gr_poly
		(pts
			(xy 374.871488 -274.111974) (xy 374.979946 -273.995134) (xy 374.849136 -273.768566) (xy 374.693688 -273.804126)
			(xy 374.655334 -273.826224) (xy 374.833134 -274.134072)
		)
		(stroke
			(width 0)
			(type solid)
		)
		(fill yes)
		(layer "In11.Cu")
		(net "M_H_CPU0_SA_DQ<14>")
	)
	(gr_poly
		(pts
			(xy 374.89638 -278.946356) (xy 374.89638 -278.901906) (xy 374.54078 -278.901906) (xy 374.54078 -278.946356)
			(xy 374.58777 -279.098756) (xy 374.84939 -279.098756)
		)
		(stroke
			(width 0)
			(type solid)
		)
		(fill yes)
		(layer "In11.Cu")
		(net "M_H_CPU0_SA_DQS_DP<1>")
	)
	(gr_poly
		(pts
			(xy 374.89638 -272.843498) (xy 374.84939 -272.691098) (xy 374.58777 -272.691098) (xy 374.54078 -272.843498)
			(xy 374.54078 -272.887694) (xy 374.89638 -272.887694)
		)
		(stroke
			(width 0)
			(type solid)
		)
		(fill yes)
		(layer "In11.Cu")
		(net "M_H_CPU0_SA_DQ<15>")
	)
	(gr_poly
		(pts
			(xy 374.89638 -272.435066) (xy 374.89638 -272.39087) (xy 374.54078 -272.39087) (xy 374.54078 -272.435066)
			(xy 374.58777 -272.587466) (xy 374.84939 -272.587466)
		)
		(stroke
			(width 0)
			(type solid)
		)
		(fill yes)
		(layer "In11.Cu")
		(net "M_H_CPU0_SA_DQ<16>")
	)
	(gr_poly
		(pts
			(xy 374.89638 -271.215358) (xy 374.84939 -271.062958) (xy 374.58777 -271.062958) (xy 374.54078 -271.215358)
			(xy 374.54078 -271.259808) (xy 374.89638 -271.259808)
		)
		(stroke
			(width 0)
			(type solid)
		)
		(fill yes)
		(layer "In11.Cu")
		(net "M_H_CPU0_SA_DQ<19>")
	)
	(gr_poly
		(pts
			(xy 374.89638 -267.960094) (xy 374.84939 -267.807694) (xy 374.58777 -267.807694) (xy 374.54078 -267.960094)
			(xy 374.54078 -268.00429) (xy 374.89638 -268.00429)
		)
		(stroke
			(width 0)
			(type solid)
		)
		(fill yes)
		(layer "In11.Cu")
		(net "M_H_CPU0_SA_DQ<23>")
	)
	(gr_poly
		(pts
			(xy 374.89638 -267.551662) (xy 374.89638 -267.507466) (xy 374.54078 -267.507466) (xy 374.54078 -267.551662)
			(xy 374.58777 -267.704062) (xy 374.84939 -267.704062)
		)
		(stroke
			(width 0)
			(type solid)
		)
		(fill yes)
		(layer "In11.Cu")
		(net "M_H_CPU0_SA_DQ<24>")
	)
	(gr_poly
		(pts
			(xy 374.89638 -266.331954) (xy 374.84939 -266.179554) (xy 374.58777 -266.179554) (xy 374.54078 -266.331954)
			(xy 374.54078 -266.376404) (xy 374.89638 -266.376404)
		)
		(stroke
			(width 0)
			(type solid)
		)
		(fill yes)
		(layer "In11.Cu")
		(net "M_H_CPU0_SA_DQ<27>")
	)
	(gr_poly
		(pts
			(xy 374.89638 -263.07669) (xy 374.84939 -262.92429) (xy 374.58777 -262.92429) (xy 374.54078 -263.07669)
			(xy 374.54078 -263.120886) (xy 374.89638 -263.120886)
		)
		(stroke
			(width 0)
			(type solid)
		)
		(fill yes)
		(layer "In11.Cu")
		(net "M_H_CPU0_SA_DQ<31>")
	)
	(gr_poly
		(pts
			(xy 374.89638 -262.668258) (xy 374.89638 -262.624062) (xy 374.54078 -262.624062) (xy 374.54078 -262.668258)
			(xy 374.58777 -262.820658) (xy 374.84939 -262.820658)
		)
		(stroke
			(width 0)
			(type solid)
		)
		(fill yes)
		(layer "In11.Cu")
		(net "M_H_CPU0_SA_CB<0>")
	)
	(gr_poly
		(pts
			(xy 374.89638 -261.449058) (xy 374.84939 -261.296658) (xy 374.58777 -261.296658) (xy 374.54078 -261.449058)
			(xy 374.54078 -261.493254) (xy 374.89638 -261.493254)
		)
		(stroke
			(width 0)
			(type solid)
		)
		(fill yes)
		(layer "In11.Cu")
		(net "M_H_CPU0_SA_CB<3>")
	)
	(gr_poly
		(pts
			(xy 374.89638 -259.412994) (xy 374.89638 -259.368544) (xy 374.54078 -259.368544) (xy 374.54078 -259.412994)
			(xy 374.58777 -259.565394) (xy 374.84939 -259.565394)
		)
		(stroke
			(width 0)
			(type solid)
		)
		(fill yes)
		(layer "In11.Cu")
		(net "M_H_CPU0_SA_CB<4>")
	)
	(gr_poly
		(pts
			(xy 374.89638 -256.565654) (xy 374.84939 -256.413254) (xy 374.58777 -256.413254) (xy 374.54078 -256.565654)
			(xy 374.54078 -256.60985) (xy 374.89638 -256.60985)
		)
		(stroke
			(width 0)
			(type solid)
		)
		(fill yes)
		(layer "In11.Cu")
		(net "M_H_CPU0_SA_CS_N<1>")
	)
	(gr_poly
		(pts
			(xy 374.89892 -264.29589) (xy 374.89892 -264.251694) (xy 374.54332 -264.251694) (xy 374.54332 -264.29589)
			(xy 374.59031 -264.44829) (xy 374.85193 -264.44829)
		)
		(stroke
			(width 0)
			(type solid)
		)
		(fill yes)
		(layer "In11.Cu")
		(net "M_H_CPU0_SA_DQ<28>")
	)
	(gr_poly
		(pts
			(xy 374.89892 -258.193286) (xy 374.85193 -258.040886) (xy 374.59031 -258.040886) (xy 374.54332 -258.193286)
			(xy 374.54332 -258.237482) (xy 374.89892 -258.237482)
		)
		(stroke
			(width 0)
			(type solid)
		)
		(fill yes)
		(layer "In11.Cu")
		(net "M_H_CPU0_SA_CB<7>")
	)
	(gr_poly
		(pts
			(xy 374.89892 -257.784854) (xy 374.89892 -257.740658) (xy 374.54332 -257.740658) (xy 374.54332 -257.784854)
			(xy 374.59031 -257.937254) (xy 374.85193 -257.937254)
		)
		(stroke
			(width 0)
			(type solid)
		)
		(fill yes)
		(layer "In11.Cu")
		(net "M_E_CPU0_ALERT_N")
	)
	(gr_poly
		(pts
			(xy 374.89892 -254.529082) (xy 374.89892 -254.484886) (xy 374.54332 -254.484886) (xy 374.54332 -254.529082)
			(xy 374.59031 -254.681482) (xy 374.85193 -254.681482)
		)
		(stroke
			(width 0)
			(type solid)
		)
		(fill yes)
		(layer "In11.Cu")
		(net "M_H_CPU0_SA_CA<2>")
	)
	(gr_poly
		(pts
			(xy 374.904508 -269.179294) (xy 374.904508 -269.134844) (xy 374.548908 -269.134844) (xy 374.548908 -269.179294)
			(xy 374.595898 -269.331694) (xy 374.857518 -269.331694)
		)
		(stroke
			(width 0)
			(type solid)
		)
		(fill yes)
		(layer "In11.Cu")
		(net "M_H_CPU0_SA_DQ<20>")
	)
	(gr_poly
		(pts
			(xy 374.904508 -259.821426) (xy 374.857518 -259.669026) (xy 374.595898 -259.669026) (xy 374.548908 -259.821426)
			(xy 374.548908 -259.865876) (xy 374.904508 -259.865876)
		)
		(stroke
			(width 0)
			(type solid)
		)
		(fill yes)
		(layer "In11.Cu")
		(net "M_H_CPU0_SA_DQS_DP<9>")
	)
	(gr_poly
		(pts
			(xy 374.904762 -279.354788) (xy 374.857772 -279.202388) (xy 374.596152 -279.202388) (xy 374.549162 -279.354788)
			(xy 374.549162 -279.398984) (xy 374.904762 -279.398984)
		)
		(stroke
			(width 0)
			(type solid)
		)
		(fill yes)
		(layer "In11.Cu")
		(net "M_H_CPU0_SA_DQ<11>")
	)
	(gr_poly
		(pts
			(xy 374.904762 -265.92403) (xy 374.904762 -265.87958) (xy 374.549162 -265.87958) (xy 374.549162 -265.92403)
			(xy 374.596152 -266.07643) (xy 374.857772 -266.07643)
		)
		(stroke
			(width 0)
			(type solid)
		)
		(fill yes)
		(layer "In11.Cu")
		(net "M_H_CPU0_SA_DQS_DP<3>")
	)
	(gr_poly
		(pts
			(xy 374.904762 -261.040626) (xy 374.904762 -260.996176) (xy 374.549162 -260.996176) (xy 374.549162 -261.040626)
			(xy 374.596152 -261.193026) (xy 374.857772 -261.193026)
		)
		(stroke
			(width 0)
			(type solid)
		)
		(fill yes)
		(layer "In11.Cu")
		(net "M_H_CPU0_SA_DQS_DP<4>")
	)
	(gr_poly
		(pts
			(xy 374.904762 -256.157222) (xy 374.904762 -256.112772) (xy 374.549162 -256.112772) (xy 374.549162 -256.157222)
			(xy 374.596152 -256.309622) (xy 374.857772 -256.309622)
		)
		(stroke
			(width 0)
			(type solid)
		)
		(fill yes)
		(layer "In11.Cu")
		(net "M_H_CPU0_SA_CS_N<2>")
	)
	(gr_poly
		(pts
			(xy 374.905016 -269.588234) (xy 374.858026 -269.435834) (xy 374.596406 -269.435834) (xy 374.549416 -269.588234)
			(xy 374.549416 -269.632684) (xy 374.905016 -269.632684)
		)
		(stroke
			(width 0)
			(type solid)
		)
		(fill yes)
		(layer "In11.Cu")
		(net "M_H_CPU0_SA_DQS_DP<7>")
	)
	(gr_poly
		(pts
			(xy 374.908318 -270.806926) (xy 374.908318 -270.76273) (xy 374.552718 -270.76273) (xy 374.552718 -270.806926)
			(xy 374.599708 -270.959326) (xy 374.861328 -270.959326)
		)
		(stroke
			(width 0)
			(type solid)
		)
		(fill yes)
		(layer "In11.Cu")
		(net "M_H_CPU0_SA_DQS_DP<2>")
	)
	(gr_poly
		(pts
			(xy 374.90908 -264.70483) (xy 374.86209 -264.55243) (xy 374.60047 -264.55243) (xy 374.55348 -264.70483)
			(xy 374.55348 -264.749026) (xy 374.90908 -264.749026)
		)
		(stroke
			(width 0)
			(type solid)
		)
		(fill yes)
		(layer "In11.Cu")
		(net "M_H_CPU0_SA_DQS_DP<8>")
	)
	(gr_poly
		(pts
			(xy 374.910858 -280.573988) (xy 374.910858 -280.529538) (xy 374.555258 -280.529538) (xy 374.555258 -280.573988)
			(xy 374.602248 -280.726388) (xy 374.863868 -280.726388)
		)
		(stroke
			(width 0)
			(type solid)
		)
		(fill yes)
		(layer "In11.Cu")
		(net "M_H_CPU0_SA_DQ<8>")
	)
	(gr_poly
		(pts
			(xy 374.910858 -254.938022) (xy 374.863868 -254.785622) (xy 374.602248 -254.785622) (xy 374.555258 -254.938022)
			(xy 374.555258 -254.982218) (xy 374.910858 -254.982218)
		)
		(stroke
			(width 0)
			(type solid)
		)
		(fill yes)
		(layer "In11.Cu")
		(net "M_H_CPU0_SA_CA<0>")
	)
	(gr_poly
		(pts
			(xy 375.231406 -275.54555) (xy 375.26976 -275.523452) (xy 375.09196 -275.215604) (xy 375.053606 -275.237702)
			(xy 374.945148 -275.354542) (xy 375.075958 -275.58111)
		)
		(stroke
			(width 0)
			(type solid)
		)
		(fill yes)
		(layer "In11.Cu")
		(net "M_H_CPU0_SA_DQ<12>")
	)
	(gr_poly
		(pts
			(xy 375.23166 -277.173944) (xy 375.270014 -277.151846) (xy 375.092214 -276.843998) (xy 375.05386 -276.866096)
			(xy 374.945402 -276.982936) (xy 375.076212 -277.209504)
		)
		(stroke
			(width 0)
			(type solid)
		)
		(fill yes)
		(layer "In11.Cu")
		(net "M_H_CPU0_SA_DQS_DN<6>")
	)
	(gr_poly
		(pts
			(xy 375.23166 -273.918426) (xy 375.270014 -273.896328) (xy 375.092214 -273.58848) (xy 375.05386 -273.610578)
			(xy 374.945402 -273.727418) (xy 375.076212 -273.953986)
		)
		(stroke
			(width 0)
			(type solid)
		)
		(fill yes)
		(layer "In11.Cu")
		(net "M_H_CPU0_SA_DQ<13>")
	)
	(gr_poly
		(pts
			(xy 375.258838 -227.44049) (xy 375.258838 -227.396294) (xy 374.903238 -227.396294) (xy 374.903238 -227.44049)
			(xy 374.950228 -227.59289) (xy 375.211848 -227.59289)
		)
		(stroke
			(width 0)
			(type solid)
		)
		(fill yes)
		(layer "In11.Cu")
		(net "M_H_CPU0_SB_DQS_DP<3>")
	)
	(gr_poly
		(pts
			(xy 375.261378 -235.579666) (xy 375.261378 -235.535216) (xy 374.905778 -235.535216) (xy 374.905778 -235.579666)
			(xy 374.952768 -235.732066) (xy 375.214388 -235.732066)
		)
		(stroke
			(width 0)
			(type solid)
		)
		(fill yes)
		(layer "In11.Cu")
		(net "M_H_CPU0_SB_DQ<5>")
	)
	(gr_poly
		(pts
			(xy 375.264934 -244.127274) (xy 375.217944 -243.974874) (xy 374.956324 -243.974874) (xy 374.909334 -244.127274)
			(xy 374.909334 -244.17147) (xy 375.264934 -244.17147)
		)
		(stroke
			(width 0)
			(type solid)
		)
		(fill yes)
		(layer "In11.Cu")
		(net "M_H_CPU0_SB_CB<4>")
	)
	(gr_poly
		(pts
			(xy 375.264934 -226.221798) (xy 375.217944 -226.069398) (xy 374.956324 -226.069398) (xy 374.909334 -226.221798)
			(xy 374.909334 -226.265994) (xy 375.264934 -226.265994)
		)
		(stroke
			(width 0)
			(type solid)
		)
		(fill yes)
		(layer "In11.Cu")
		(net "M_H_CPU0_SB_DQ<28>")
	)
	(gr_poly
		(pts
			(xy 375.270776 -242.499134) (xy 375.223786 -242.346734) (xy 374.962166 -242.346734) (xy 374.915176 -242.499134)
			(xy 374.915176 -242.543584) (xy 375.270776 -242.543584)
		)
		(stroke
			(width 0)
			(type solid)
		)
		(fill yes)
		(layer "In11.Cu")
		(net "M_H_CPU0_SB_DQS_DN<9>")
	)
	(gr_poly
		(pts
			(xy 375.270776 -232.732326) (xy 375.223786 -232.579926) (xy 374.962166 -232.579926) (xy 374.915176 -232.732326)
			(xy 374.915176 -232.776776) (xy 375.270776 -232.776776)
		)
		(stroke
			(width 0)
			(type solid)
		)
		(fill yes)
		(layer "In11.Cu")
		(net "M_H_CPU0_SB_DQS_DN<1>")
	)
	(gr_poly
		(pts
			(xy 375.270776 -232.324402) (xy 375.270776 -232.279952) (xy 374.915176 -232.279952) (xy 374.915176 -232.324402)
			(xy 374.962166 -232.476802) (xy 375.223786 -232.476802)
		)
		(stroke
			(width 0)
			(type solid)
		)
		(fill yes)
		(layer "In11.Cu")
		(net "M_H_CPU0_SB_DQS_DN<6>")
	)
	(gr_poly
		(pts
			(xy 375.270776 -227.84943) (xy 375.223786 -227.69703) (xy 374.962166 -227.69703) (xy 374.915176 -227.84943)
			(xy 374.915176 -227.893626) (xy 375.270776 -227.893626)
		)
		(stroke
			(width 0)
			(type solid)
		)
		(fill yes)
		(layer "In11.Cu")
		(net "M_H_CPU0_SB_DQS_DP<8>")
	)
	(gr_poly
		(pts
			(xy 375.273316 -248.602246) (xy 375.273316 -248.557796) (xy 374.917716 -248.557796) (xy 374.917716 -248.602246)
			(xy 374.964706 -248.754646) (xy 375.226326 -248.754646)
		)
		(stroke
			(width 0)
			(type solid)
		)
		(fill yes)
		(layer "In11.Cu")
		(net "M_H_CPU0_SB_CA<0>")
	)
	(gr_poly
		(pts
			(xy 375.273316 -243.718842) (xy 375.273316 -243.674392) (xy 374.917716 -243.674392) (xy 374.917716 -243.718842)
			(xy 374.964706 -243.871242) (xy 375.226326 -243.871242)
		)
		(stroke
			(width 0)
			(type solid)
		)
		(fill yes)
		(layer "In11.Cu")
		(net "M_H_CPU0_SB_CB<7>")
	)
	(gr_poly
		(pts
			(xy 375.273316 -242.09121) (xy 375.273316 -242.04676) (xy 374.917716 -242.04676) (xy 374.917716 -242.09121)
			(xy 374.964706 -242.24361) (xy 375.226326 -242.24361)
		)
		(stroke
			(width 0)
			(type solid)
		)
		(fill yes)
		(layer "In11.Cu")
		(net "M_H_CPU0_SB_DQS_DN<4>")
	)
	(gr_poly
		(pts
			(xy 375.273316 -240.871502) (xy 375.226326 -240.719102) (xy 374.964706 -240.719102) (xy 374.917716 -240.871502)
			(xy 374.917716 -240.915698) (xy 375.273316 -240.915698)
		)
		(stroke
			(width 0)
			(type solid)
		)
		(fill yes)
		(layer "In11.Cu")
		(net "M_H_CPU0_SB_CB<2>")
	)
	(gr_poly
		(pts
			(xy 375.273316 -240.46307) (xy 375.273316 -240.418874) (xy 374.917716 -240.418874) (xy 374.917716 -240.46307)
			(xy 374.964706 -240.61547) (xy 375.226326 -240.61547)
		)
		(stroke
			(width 0)
			(type solid)
		)
		(fill yes)
		(layer "In11.Cu")
		(net "M_H_CPU0_SB_CB<1>")
	)
	(gr_poly
		(pts
			(xy 375.273316 -239.243362) (xy 375.226326 -239.090962) (xy 374.964706 -239.090962) (xy 374.917716 -239.243362)
			(xy 374.917716 -239.287812) (xy 375.273316 -239.287812)
		)
		(stroke
			(width 0)
			(type solid)
		)
		(fill yes)
		(layer "In11.Cu")
		(net "M_H_CPU0_SB_DQ<2>")
	)
	(gr_poly
		(pts
			(xy 375.273316 -238.835438) (xy 375.273316 -238.790988) (xy 374.917716 -238.790988) (xy 374.917716 -238.835438)
			(xy 374.964706 -238.987838) (xy 375.226326 -238.987838)
		)
		(stroke
			(width 0)
			(type solid)
		)
		(fill yes)
		(layer "In11.Cu")
		(net "M_H_CPU0_SB_DQ<1>")
	)
	(gr_poly
		(pts
			(xy 375.273316 -237.61573) (xy 375.226326 -237.46333) (xy 374.964706 -237.46333) (xy 374.917716 -237.61573)
			(xy 374.917716 -237.659926) (xy 375.273316 -237.659926)
		)
		(stroke
			(width 0)
			(type solid)
		)
		(fill yes)
		(layer "In11.Cu")
		(net "M_H_CPU0_SB_DQS_DN<0>")
	)
	(gr_poly
		(pts
			(xy 375.273316 -237.207806) (xy 375.273316 -237.163356) (xy 374.917716 -237.163356) (xy 374.917716 -237.207806)
			(xy 374.964706 -237.360206) (xy 375.226326 -237.360206)
		)
		(stroke
			(width 0)
			(type solid)
		)
		(fill yes)
		(layer "In11.Cu")
		(net "M_H_CPU0_SB_DQS_DN<5>")
	)
	(gr_poly
		(pts
			(xy 375.273316 -235.988098) (xy 375.226326 -235.835698) (xy 374.964706 -235.835698) (xy 374.917716 -235.988098)
			(xy 374.917716 -236.032294) (xy 375.273316 -236.032294)
		)
		(stroke
			(width 0)
			(type solid)
		)
		(fill yes)
		(layer "In11.Cu")
		(net "M_H_CPU0_SB_DQ<6>")
	)
	(gr_poly
		(pts
			(xy 375.273316 -234.360466) (xy 375.226326 -234.208066) (xy 374.964706 -234.208066) (xy 374.917716 -234.360466)
			(xy 374.917716 -234.404662) (xy 375.273316 -234.404662)
		)
		(stroke
			(width 0)
			(type solid)
		)
		(fill yes)
		(layer "In11.Cu")
		(net "M_H_CPU0_SB_DQ<10>")
	)
	(gr_poly
		(pts
			(xy 375.273316 -233.952034) (xy 375.273316 -233.907838) (xy 374.917716 -233.907838) (xy 374.917716 -233.952034)
			(xy 374.964706 -234.104434) (xy 375.226326 -234.104434)
		)
		(stroke
			(width 0)
			(type solid)
		)
		(fill yes)
		(layer "In11.Cu")
		(net "M_H_CPU0_SB_DQ<9>")
	)
	(gr_poly
		(pts
			(xy 375.273316 -231.104694) (xy 375.226326 -230.952294) (xy 374.964706 -230.952294) (xy 374.917716 -231.104694)
			(xy 374.917716 -231.14889) (xy 375.273316 -231.14889)
		)
		(stroke
			(width 0)
			(type solid)
		)
		(fill yes)
		(layer "In11.Cu")
		(net "M_H_CPU0_SB_DQ<14>")
	)
	(gr_poly
		(pts
			(xy 375.273316 -230.696262) (xy 375.273316 -230.652066) (xy 374.917716 -230.652066) (xy 374.917716 -230.696262)
			(xy 374.964706 -230.848662) (xy 375.226326 -230.848662)
		)
		(stroke
			(width 0)
			(type solid)
		)
		(fill yes)
		(layer "In11.Cu")
		(net "M_H_CPU0_SB_DQ<13>")
	)
	(gr_poly
		(pts
			(xy 375.273316 -229.477062) (xy 375.226326 -229.324662) (xy 374.964706 -229.324662) (xy 374.917716 -229.477062)
			(xy 374.917716 -229.521258) (xy 375.273316 -229.521258)
		)
		(stroke
			(width 0)
			(type solid)
		)
		(fill yes)
		(layer "In11.Cu")
		(net "M_H_CPU0_SB_DQ<24>")
	)
	(gr_poly
		(pts
			(xy 375.273316 -229.06863) (xy 375.273316 -229.024434) (xy 374.917716 -229.024434) (xy 374.917716 -229.06863)
			(xy 374.964706 -229.22103) (xy 375.226326 -229.22103)
		)
		(stroke
			(width 0)
			(type solid)
		)
		(fill yes)
		(layer "In11.Cu")
		(net "M_H_CPU0_SB_DQ<27>")
	)
	(gr_poly
		(pts
			(xy 375.273316 -225.813366) (xy 375.273316 -225.768916) (xy 374.917716 -225.768916) (xy 374.917716 -225.813366)
			(xy 374.964706 -225.965766) (xy 375.226326 -225.965766)
		)
		(stroke
			(width 0)
			(type solid)
		)
		(fill yes)
		(layer "In11.Cu")
		(net "M_H_CPU0_SB_DQ<31>")
	)
	(gr_poly
		(pts
			(xy 375.345706 -276.560788) (xy 375.454164 -276.443948) (xy 375.323354 -276.21738) (xy 375.167906 -276.25294)
			(xy 375.129552 -276.275038) (xy 375.307352 -276.582886)
		)
		(stroke
			(width 0)
			(type solid)
		)
		(fill yes)
		(layer "In11.Cu")
		(net "M_H_CPU0_SA_DQS_DP<6>")
	)
	(gr_poly
		(pts
			(xy 375.345706 -273.30527) (xy 375.454164 -273.18843) (xy 375.323354 -272.961862) (xy 375.167906 -272.997422)
			(xy 375.129552 -273.01952) (xy 375.307352 -273.327368)
		)
		(stroke
			(width 0)
			(type solid)
		)
		(fill yes)
		(layer "In11.Cu")
		(net "M_H_CPU0_SA_DQ<15>")
	)
	(gr_poly
		(pts
			(xy 375.347484 -274.93595) (xy 375.455942 -274.81911) (xy 375.325132 -274.592542) (xy 375.169684 -274.628102)
			(xy 375.13133 -274.6502) (xy 375.30913 -274.958048)
		)
		(stroke
			(width 0)
			(type solid)
		)
		(fill yes)
		(layer "In11.Cu")
		(net "M_H_CPU0_SA_DQ<14>")
	)
	(gr_poly
		(pts
			(xy 375.36882 -257.37947) (xy 375.32183 -257.22707) (xy 375.06021 -257.22707) (xy 375.01322 -257.37947)
			(xy 375.01322 -257.42392) (xy 375.36882 -257.42392)
		)
		(stroke
			(width 0)
			(type solid)
		)
		(fill yes)
		(layer "In11.Cu")
		(net "M_H_CPU0_ALERT_N")
	)
	(gr_poly
		(pts
			(xy 375.370598 -265.109706) (xy 375.370598 -265.06551) (xy 375.014998 -265.06551) (xy 375.014998 -265.109706)
			(xy 375.061988 -265.262106) (xy 375.323608 -265.262106)
		)
		(stroke
			(width 0)
			(type solid)
		)
		(fill yes)
		(layer "In11.Cu")
		(net "M_H_CPU0_SA_DQS_DN<8>")
	)
	(gr_poly
		(pts
			(xy 375.371614 -268.77391) (xy 375.324624 -268.62151) (xy 375.063004 -268.62151) (xy 375.016014 -268.77391)
			(xy 375.016014 -268.81836) (xy 375.371614 -268.81836)
		)
		(stroke
			(width 0)
			(type solid)
		)
		(fill yes)
		(layer "In11.Cu")
		(net "M_H_CPU0_SA_DQ<22>")
	)
	(gr_poly
		(pts
			(xy 375.374916 -258.59867) (xy 375.374916 -258.554474) (xy 375.019316 -258.554474) (xy 375.019316 -258.59867)
			(xy 375.066306 -258.75107) (xy 375.327926 -258.75107)
		)
		(stroke
			(width 0)
			(type solid)
		)
		(fill yes)
		(layer "In11.Cu")
		(net "M_H_CPU0_SA_CB<5>")
	)
	(gr_poly
		(pts
			(xy 375.380758 -280.168096) (xy 375.333768 -280.015696) (xy 375.072148 -280.015696) (xy 375.025158 -280.168096)
			(xy 375.025158 -280.212546) (xy 375.380758 -280.212546)
		)
		(stroke
			(width 0)
			(type solid)
		)
		(fill yes)
		(layer "In11.Cu")
		(net "M_H_CPU0_SA_DQ<10>")
	)
	(gr_poly
		(pts
			(xy 375.380758 -279.760172) (xy 375.380758 -279.715722) (xy 375.025158 -279.715722) (xy 375.025158 -279.760172)
			(xy 375.072148 -279.912572) (xy 375.333768 -279.912572)
		)
		(stroke
			(width 0)
			(type solid)
		)
		(fill yes)
		(layer "In11.Cu")
		(net "M_H_CPU0_SA_DQ<9>")
	)
	(gr_poly
		(pts
			(xy 375.380758 -265.518138) (xy 375.333768 -265.365738) (xy 375.072148 -265.365738) (xy 375.025158 -265.518138)
			(xy 375.025158 -265.562588) (xy 375.380758 -265.562588)
		)
		(stroke
			(width 0)
			(type solid)
		)
		(fill yes)
		(layer "In11.Cu")
		(net "M_H_CPU0_SA_DQS_DN<3>")
	)
	(gr_poly
		(pts
			(xy 375.380758 -260.634734) (xy 375.333768 -260.482334) (xy 375.072148 -260.482334) (xy 375.025158 -260.634734)
			(xy 375.025158 -260.679184) (xy 375.380758 -260.679184)
		)
		(stroke
			(width 0)
			(type solid)
		)
		(fill yes)
		(layer "In11.Cu")
		(net "M_H_CPU0_SA_DQS_DN<4>")
	)
	(gr_poly
		(pts
			(xy 375.380758 -260.22681) (xy 375.380758 -260.18236) (xy 375.025158 -260.18236) (xy 375.025158 -260.22681)
			(xy 375.072148 -260.37921) (xy 375.333768 -260.37921)
		)
		(stroke
			(width 0)
			(type solid)
		)
		(fill yes)
		(layer "In11.Cu")
		(net "M_H_CPU0_SA_DQS_DN<9>")
	)
	(gr_poly
		(pts
			(xy 375.380758 -256.971038) (xy 375.380758 -256.926588) (xy 375.025158 -256.926588) (xy 375.025158 -256.971038)
			(xy 375.072148 -257.123438) (xy 375.333768 -257.123438)
		)
		(stroke
			(width 0)
			(type solid)
		)
		(fill yes)
		(layer "In11.Cu")
		(net "M_H_CPU0_SA_CS_N<0>")
	)
	(gr_poly
		(pts
			(xy 375.380758 -255.751838) (xy 375.333768 -255.599438) (xy 375.072148 -255.599438) (xy 375.025158 -255.751838)
			(xy 375.025158 -255.796034) (xy 375.380758 -255.796034)
		)
		(stroke
			(width 0)
			(type solid)
		)
		(fill yes)
		(layer "In11.Cu")
		(net "M_H_CPU0_SA_CS_N<3>")
	)
	(gr_poly
		(pts
			(xy 375.380758 -255.343406) (xy 375.380758 -255.29921) (xy 375.025158 -255.29921) (xy 375.025158 -255.343406)
			(xy 375.072148 -255.495806) (xy 375.333768 -255.495806)
		)
		(stroke
			(width 0)
			(type solid)
		)
		(fill yes)
		(layer "In11.Cu")
		(net "M_H_CPU0_SA_CA<1>")
	)
	(gr_poly
		(pts
			(xy 375.383298 -278.540464) (xy 375.336308 -278.388064) (xy 375.074688 -278.388064) (xy 375.027698 -278.540464)
			(xy 375.027698 -278.584914) (xy 375.383298 -278.584914)
		)
		(stroke
			(width 0)
			(type solid)
		)
		(fill yes)
		(layer "In11.Cu")
		(net "M_H_CPU0_SA_DQS_DN<1>")
	)
	(gr_poly
		(pts
			(xy 375.383298 -272.029174) (xy 375.336308 -271.876774) (xy 375.074688 -271.876774) (xy 375.027698 -272.029174)
			(xy 375.027698 -272.073624) (xy 375.383298 -272.073624)
		)
		(stroke
			(width 0)
			(type solid)
		)
		(fill yes)
		(layer "In11.Cu")
		(net "M_H_CPU0_SA_DQ<18>")
	)
	(gr_poly
		(pts
			(xy 375.383298 -271.62125) (xy 375.383298 -271.5768) (xy 375.027698 -271.5768) (xy 375.027698 -271.62125)
			(xy 375.074688 -271.77365) (xy 375.336308 -271.77365)
		)
		(stroke
			(width 0)
			(type solid)
		)
		(fill yes)
		(layer "In11.Cu")
		(net "M_H_CPU0_SA_DQ<17>")
	)
	(gr_poly
		(pts
			(xy 375.383298 -270.401542) (xy 375.336308 -270.249142) (xy 375.074688 -270.249142) (xy 375.027698 -270.401542)
			(xy 375.027698 -270.445992) (xy 375.383298 -270.445992)
		)
		(stroke
			(width 0)
			(type solid)
		)
		(fill yes)
		(layer "In11.Cu")
		(net "M_H_CPU0_SA_DQS_DN<2>")
	)
	(gr_poly
		(pts
			(xy 375.383298 -269.993618) (xy 375.383298 -269.949168) (xy 375.027698 -269.949168) (xy 375.027698 -269.993618)
			(xy 375.074688 -270.146018) (xy 375.336308 -270.146018)
		)
		(stroke
			(width 0)
			(type solid)
		)
		(fill yes)
		(layer "In11.Cu")
		(net "M_H_CPU0_SA_DQS_DN<7>")
	)
	(gr_poly
		(pts
			(xy 375.383298 -268.365478) (xy 375.383298 -268.321282) (xy 375.027698 -268.321282) (xy 375.027698 -268.365478)
			(xy 375.074688 -268.517878) (xy 375.336308 -268.517878)
		)
		(stroke
			(width 0)
			(type solid)
		)
		(fill yes)
		(layer "In11.Cu")
		(net "M_H_CPU0_SA_DQ<21>")
	)
	(gr_poly
		(pts
			(xy 375.383298 -267.14577) (xy 375.336308 -266.99337) (xy 375.074688 -266.99337) (xy 375.027698 -267.14577)
			(xy 375.027698 -267.19022) (xy 375.383298 -267.19022)
		)
		(stroke
			(width 0)
			(type solid)
		)
		(fill yes)
		(layer "In11.Cu")
		(net "M_H_CPU0_SA_DQ<26>")
	)
	(gr_poly
		(pts
			(xy 375.383298 -266.737846) (xy 375.383298 -266.69365) (xy 375.027698 -266.69365) (xy 375.027698 -266.737846)
			(xy 375.074688 -266.890246) (xy 375.336308 -266.890246)
		)
		(stroke
			(width 0)
			(type solid)
		)
		(fill yes)
		(layer "In11.Cu")
		(net "M_H_CPU0_SA_DQ<25>")
	)
	(gr_poly
		(pts
			(xy 375.383298 -263.890506) (xy 375.336308 -263.738106) (xy 375.074688 -263.738106) (xy 375.027698 -263.890506)
			(xy 375.027698 -263.934956) (xy 375.383298 -263.934956)
		)
		(stroke
			(width 0)
			(type solid)
		)
		(fill yes)
		(layer "In11.Cu")
		(net "M_H_CPU0_SA_DQ<30>")
	)
	(gr_poly
		(pts
			(xy 375.383298 -263.482582) (xy 375.383298 -263.438132) (xy 375.027698 -263.438132) (xy 375.027698 -263.482582)
			(xy 375.074688 -263.634982) (xy 375.336308 -263.634982)
		)
		(stroke
			(width 0)
			(type solid)
		)
		(fill yes)
		(layer "In11.Cu")
		(net "M_H_CPU0_SA_DQ<29>")
	)
	(gr_poly
		(pts
			(xy 375.383298 -262.262874) (xy 375.336308 -262.110474) (xy 375.074688 -262.110474) (xy 375.027698 -262.262874)
			(xy 375.027698 -262.30707) (xy 375.383298 -262.30707)
		)
		(stroke
			(width 0)
			(type solid)
		)
		(fill yes)
		(layer "In11.Cu")
		(net "M_H_CPU0_SA_CB<2>")
	)
	(gr_poly
		(pts
			(xy 375.383298 -261.854442) (xy 375.383298 -261.810246) (xy 375.027698 -261.810246) (xy 375.027698 -261.854442)
			(xy 375.074688 -262.006842) (xy 375.336308 -262.006842)
		)
		(stroke
			(width 0)
			(type solid)
		)
		(fill yes)
		(layer "In11.Cu")
		(net "M_H_CPU0_SA_CB<1>")
	)
	(gr_poly
		(pts
			(xy 375.383298 -259.007102) (xy 375.336308 -258.854702) (xy 375.074688 -258.854702) (xy 375.027698 -259.007102)
			(xy 375.027698 -259.051552) (xy 375.383298 -259.051552)
		)
		(stroke
			(width 0)
			(type solid)
		)
		(fill yes)
		(layer "In11.Cu")
		(net "M_H_CPU0_SA_CB<6>")
	)
	(gr_poly
		(pts
			(xy 375.383298 -254.123698) (xy 375.336308 -253.971298) (xy 375.074688 -253.971298) (xy 375.027698 -254.123698)
			(xy 375.027698 -254.168148) (xy 375.383298 -254.168148)
		)
		(stroke
			(width 0)
			(type solid)
		)
		(fill yes)
		(layer "In11.Cu")
		(net "M_H_CPU0_SA_CA<3>")
	)
	(gr_poly
		(pts
			(xy 375.695972 -281.23388) (xy 375.734326 -281.211782) (xy 375.556526 -280.903934) (xy 375.518172 -280.926032)
			(xy 375.409714 -281.042872) (xy 375.540524 -281.26944)
		)
		(stroke
			(width 0)
			(type solid)
		)
		(fill yes)
		(layer "In11.Cu")
		(net "M_H_CPU0_SA_DQ<8>")
	)
	(gr_poly
		(pts
			(xy 375.695972 -276.350476) (xy 375.734326 -276.328378) (xy 375.556526 -276.02053) (xy 375.518172 -276.042628)
			(xy 375.409714 -276.159468) (xy 375.540524 -276.386036)
		)
		(stroke
			(width 0)
			(type solid)
		)
		(fill yes)
		(layer "In11.Cu")
		(net "M_H_CPU0_SA_DQ<12>")
	)
	(gr_poly
		(pts
			(xy 375.695972 -274.72259) (xy 375.734326 -274.700492) (xy 375.556526 -274.392644) (xy 375.518172 -274.414742)
			(xy 375.409714 -274.531582) (xy 375.540524 -274.75815)
		)
		(stroke
			(width 0)
			(type solid)
		)
		(fill yes)
		(layer "In11.Cu")
		(net "M_H_CPU0_SA_DQ<13>")
	)
	(gr_poly
		(pts
			(xy 375.695972 -273.094958) (xy 375.734326 -273.07286) (xy 375.556526 -272.765012) (xy 375.518172 -272.78711)
			(xy 375.409714 -272.90395) (xy 375.540524 -273.130518)
		)
		(stroke
			(width 0)
			(type solid)
		)
		(fill yes)
		(layer "In11.Cu")
		(net "M_H_CPU0_SA_DQ<16>")
	)
	(gr_poly
		(pts
			(xy 375.701306 -277.987252) (xy 375.73966 -277.965154) (xy 375.56186 -277.657306) (xy 375.523506 -277.679404)
			(xy 375.415048 -277.796244) (xy 375.545858 -278.022812)
		)
		(stroke
			(width 0)
			(type solid)
		)
		(fill yes)
		(layer "In11.Cu")
		(net "M_H_CPU0_SA_DQS_DN<6>")
	)
	(gr_poly
		(pts
			(xy 375.726198 -248.196354) (xy 375.679208 -248.043954) (xy 375.417588 -248.043954) (xy 375.370598 -248.196354)
			(xy 375.370598 -248.24055) (xy 375.726198 -248.24055)
		)
		(stroke
			(width 0)
			(type solid)
		)
		(fill yes)
		(layer "In11.Cu")
		(net "M_H_CPU0_SB_CA<1>")
	)
	(gr_poly
		(pts
			(xy 375.726198 -243.31295) (xy 375.679208 -243.16055) (xy 375.417588 -243.16055) (xy 375.370598 -243.31295)
			(xy 375.370598 -243.3574) (xy 375.726198 -243.3574)
		)
		(stroke
			(width 0)
			(type solid)
		)
		(fill yes)
		(layer "In11.Cu")
		(net "M_H_CPU0_SB_CB<5>")
	)
	(gr_poly
		(pts
			(xy 375.726198 -242.905026) (xy 375.726198 -242.860576) (xy 375.370598 -242.860576) (xy 375.370598 -242.905026)
			(xy 375.417588 -243.057426) (xy 375.679208 -243.057426)
		)
		(stroke
			(width 0)
			(type solid)
		)
		(fill yes)
		(layer "In11.Cu")
		(net "M_H_CPU0_SB_DQS_DP<9>")
	)
	(gr_poly
		(pts
			(xy 375.726198 -241.276886) (xy 375.726198 -241.23269) (xy 375.370598 -241.23269) (xy 375.370598 -241.276886)
			(xy 375.417588 -241.429286) (xy 375.679208 -241.429286)
		)
		(stroke
			(width 0)
			(type solid)
		)
		(fill yes)
		(layer "In11.Cu")
		(net "M_H_CPU0_SB_CB<0>")
	)
	(gr_poly
		(pts
			(xy 375.726198 -240.057178) (xy 375.679208 -239.904778) (xy 375.417588 -239.904778) (xy 375.370598 -240.057178)
			(xy 375.370598 -240.101628) (xy 375.726198 -240.101628)
		)
		(stroke
			(width 0)
			(type solid)
		)
		(fill yes)
		(layer "In11.Cu")
		(net "M_H_CPU0_SB_CB<3>")
	)
	(gr_poly
		(pts
			(xy 375.726198 -239.649254) (xy 375.726198 -239.604804) (xy 375.370598 -239.604804) (xy 375.370598 -239.649254)
			(xy 375.417588 -239.801654) (xy 375.679208 -239.801654)
		)
		(stroke
			(width 0)
			(type solid)
		)
		(fill yes)
		(layer "In11.Cu")
		(net "M_H_CPU0_SB_DQ<0>")
	)
	(gr_poly
		(pts
			(xy 375.726198 -238.429546) (xy 375.679208 -238.277146) (xy 375.417588 -238.277146) (xy 375.370598 -238.429546)
			(xy 375.370598 -238.473996) (xy 375.726198 -238.473996)
		)
		(stroke
			(width 0)
			(type solid)
		)
		(fill yes)
		(layer "In11.Cu")
		(net "M_H_CPU0_SB_DQ<3>")
	)
	(gr_poly
		(pts
			(xy 375.726198 -238.021622) (xy 375.726198 -237.977172) (xy 375.370598 -237.977172) (xy 375.370598 -238.021622)
			(xy 375.417588 -238.174022) (xy 375.679208 -238.174022)
		)
		(stroke
			(width 0)
			(type solid)
		)
		(fill yes)
		(layer "In11.Cu")
		(net "M_H_CPU0_SB_DQS_DP<0>")
	)
	(gr_poly
		(pts
			(xy 375.726198 -236.801914) (xy 375.679208 -236.649514) (xy 375.417588 -236.649514) (xy 375.370598 -236.801914)
			(xy 375.370598 -236.84611) (xy 375.726198 -236.84611)
		)
		(stroke
			(width 0)
			(type solid)
		)
		(fill yes)
		(layer "In11.Cu")
		(net "M_H_CPU0_SB_DQS_DP<5>")
	)
	(gr_poly
		(pts
			(xy 375.726198 -236.39399) (xy 375.726198 -236.34954) (xy 375.370598 -236.34954) (xy 375.370598 -236.39399)
			(xy 375.417588 -236.54639) (xy 375.679208 -236.54639)
		)
		(stroke
			(width 0)
			(type solid)
		)
		(fill yes)
		(layer "In11.Cu")
		(net "M_H_CPU0_SB_DQ<4>")
	)
	(gr_poly
		(pts
			(xy 375.726198 -234.76585) (xy 375.726198 -234.721654) (xy 375.370598 -234.721654) (xy 375.370598 -234.76585)
			(xy 375.417588 -234.91825) (xy 375.679208 -234.91825)
		)
		(stroke
			(width 0)
			(type solid)
		)
		(fill yes)
		(layer "In11.Cu")
		(net "M_H_CPU0_SB_DQ<8>")
	)
	(gr_poly
		(pts
			(xy 375.726198 -233.546142) (xy 375.679208 -233.393742) (xy 375.417588 -233.393742) (xy 375.370598 -233.546142)
			(xy 375.370598 -233.590592) (xy 375.726198 -233.590592)
		)
		(stroke
			(width 0)
			(type solid)
		)
		(fill yes)
		(layer "In11.Cu")
		(net "M_H_CPU0_SB_DQ<11>")
	)
	(gr_poly
		(pts
			(xy 375.726198 -233.138218) (xy 375.726198 -233.093768) (xy 375.370598 -233.093768) (xy 375.370598 -233.138218)
			(xy 375.417588 -233.290618) (xy 375.679208 -233.290618)
		)
		(stroke
			(width 0)
			(type solid)
		)
		(fill yes)
		(layer "In11.Cu")
		(net "M_H_CPU0_SB_DQS_DP<1>")
	)
	(gr_poly
		(pts
			(xy 375.726198 -231.91851) (xy 375.679208 -231.76611) (xy 375.417588 -231.76611) (xy 375.370598 -231.91851)
			(xy 375.370598 -231.96296) (xy 375.726198 -231.96296)
		)
		(stroke
			(width 0)
			(type solid)
		)
		(fill yes)
		(layer "In11.Cu")
		(net "M_H_CPU0_SB_DQS_DP<6>")
	)
	(gr_poly
		(pts
			(xy 375.726198 -231.510586) (xy 375.726198 -231.466136) (xy 375.370598 -231.466136) (xy 375.370598 -231.510586)
			(xy 375.417588 -231.662986) (xy 375.679208 -231.662986)
		)
		(stroke
			(width 0)
			(type solid)
		)
		(fill yes)
		(layer "In11.Cu")
		(net "M_H_CPU0_SB_DQ<12>")
	)
	(gr_poly
		(pts
			(xy 375.726198 -230.290878) (xy 375.679208 -230.138478) (xy 375.417588 -230.138478) (xy 375.370598 -230.290878)
			(xy 375.370598 -230.335074) (xy 375.726198 -230.335074)
		)
		(stroke
			(width 0)
			(type solid)
		)
		(fill yes)
		(layer "In11.Cu")
		(net "M_H_CPU0_SB_DQ<15>")
	)
	(gr_poly
		(pts
			(xy 375.726198 -229.882446) (xy 375.726198 -229.83825) (xy 375.370598 -229.83825) (xy 375.370598 -229.882446)
			(xy 375.417588 -230.034846) (xy 375.679208 -230.034846)
		)
		(stroke
			(width 0)
			(type solid)
		)
		(fill yes)
		(layer "In11.Cu")
		(net "M_H_CPU0_SB_DQ<26>")
	)
	(gr_poly
		(pts
			(xy 375.726198 -228.663246) (xy 375.679208 -228.510846) (xy 375.417588 -228.510846) (xy 375.370598 -228.663246)
			(xy 375.370598 -228.707442) (xy 375.726198 -228.707442)
		)
		(stroke
			(width 0)
			(type solid)
		)
		(fill yes)
		(layer "In11.Cu")
		(net "M_H_CPU0_SB_DQ<25>")
	)
	(gr_poly
		(pts
			(xy 375.726198 -225.407474) (xy 375.679208 -225.255074) (xy 375.417588 -225.255074) (xy 375.370598 -225.407474)
			(xy 375.370598 -225.45167) (xy 375.726198 -225.45167)
		)
		(stroke
			(width 0)
			(type solid)
		)
		(fill yes)
		(layer "In11.Cu")
		(net "M_H_CPU0_SB_DQ<29>")
	)
	(gr_poly
		(pts
			(xy 375.728738 -244.53215) (xy 375.728738 -244.487954) (xy 375.373138 -244.487954) (xy 375.373138 -244.53215)
			(xy 375.420128 -244.68455) (xy 375.681748 -244.68455)
		)
		(stroke
			(width 0)
			(type solid)
		)
		(fill yes)
		(layer "In11.Cu")
		(net "M_H_CPU0_SB_CB<6>")
	)
	(gr_poly
		(pts
			(xy 375.73458 -228.254814) (xy 375.73458 -228.210364) (xy 375.37898 -228.210364) (xy 375.37898 -228.254814)
			(xy 375.42597 -228.407214) (xy 375.68759 -228.407214)
		)
		(stroke
			(width 0)
			(type solid)
		)
		(fill yes)
		(layer "In11.Cu")
		(net "M_H_CPU0_SB_DQS_DN<8>")
	)
	(gr_poly
		(pts
			(xy 375.734834 -226.626674) (xy 375.734834 -226.582478) (xy 375.379234 -226.582478) (xy 375.379234 -226.626674)
			(xy 375.426224 -226.779074) (xy 375.687844 -226.779074)
		)
		(stroke
			(width 0)
			(type solid)
		)
		(fill yes)
		(layer "In11.Cu")
		(net "M_H_CPU0_SB_DQ<30>")
	)
	(gr_poly
		(pts
			(xy 375.735088 -241.685826) (xy 375.688098 -241.533426) (xy 375.426478 -241.533426) (xy 375.379488 -241.685826)
			(xy 375.379488 -241.730022) (xy 375.735088 -241.730022)
		)
		(stroke
			(width 0)
			(type solid)
		)
		(fill yes)
		(layer "In11.Cu")
		(net "M_H_CPU0_SB_DQS_DP<4>")
	)
	(gr_poly
		(pts
			(xy 375.738136 -235.174282) (xy 375.691146 -235.021882) (xy 375.429526 -235.021882) (xy 375.382536 -235.174282)
			(xy 375.382536 -235.218732) (xy 375.738136 -235.218732)
		)
		(stroke
			(width 0)
			(type solid)
		)
		(fill yes)
		(layer "In11.Cu")
		(net "M_H_CPU0_SB_DQ<7>")
	)
	(gr_poly
		(pts
			(xy 375.743216 -227.035106) (xy 375.696226 -226.882706) (xy 375.434606 -226.882706) (xy 375.387616 -227.035106)
			(xy 375.387616 -227.079556) (xy 375.743216 -227.079556)
		)
		(stroke
			(width 0)
			(type solid)
		)
		(fill yes)
		(layer "In11.Cu")
		(net "M_H_CPU0_SB_DQS_DN<3>")
	)
	(gr_poly
		(pts
			(xy 375.80824 -275.735796) (xy 375.916698 -275.618956) (xy 375.785888 -275.392388) (xy 375.63044 -275.427948)
			(xy 375.592086 -275.450046) (xy 375.769886 -275.757894)
		)
		(stroke
			(width 0)
			(type solid)
		)
		(fill yes)
		(layer "In11.Cu")
		(net "M_H_CPU0_SA_DQ<14>")
	)
	(gr_poly
		(pts
			(xy 375.810018 -277.364952) (xy 375.918476 -277.248112) (xy 375.787666 -277.021544) (xy 375.632218 -277.057104)
			(xy 375.593864 -277.079202) (xy 375.771664 -277.38705)
		)
		(stroke
			(width 0)
			(type solid)
		)
		(fill yes)
		(layer "In11.Cu")
		(net "M_H_CPU0_SA_DQS_DP<6>")
	)
	(gr_poly
		(pts
			(xy 375.810018 -274.109434) (xy 375.918476 -273.992594) (xy 375.787666 -273.766026) (xy 375.632218 -273.801586)
			(xy 375.593864 -273.823684) (xy 375.771664 -274.131532)
		)
		(stroke
			(width 0)
			(type solid)
		)
		(fill yes)
		(layer "In11.Cu")
		(net "M_H_CPU0_SA_DQ<15>")
	)
	(gr_poly
		(pts
			(xy 375.813574 -272.488152) (xy 375.922032 -272.371312) (xy 375.791222 -272.144744) (xy 375.635774 -272.180304)
			(xy 375.59742 -272.202402) (xy 375.77522 -272.51025)
		)
		(stroke
			(width 0)
			(type solid)
		)
		(fill yes)
		(layer "In11.Cu")
		(net "M_H_CPU0_SA_DQ<18>")
	)
	(gr_poly
		(pts
			(xy 375.815352 -280.630376) (xy 375.92381 -280.513536) (xy 375.793 -280.286968) (xy 375.637552 -280.322528)
			(xy 375.599198 -280.344626) (xy 375.776998 -280.652474)
		)
		(stroke
			(width 0)
			(type solid)
		)
		(fill yes)
		(layer "In11.Cu")
		(net "M_H_CPU0_SA_DQ<10>")
	)
	(gr_poly
		(pts
			(xy 375.83618 -279.35428) (xy 375.78919 -279.20188) (xy 375.52757 -279.20188) (xy 375.48058 -279.35428)
			(xy 375.48058 -279.39873) (xy 375.83618 -279.39873)
		)
		(stroke
			(width 0)
			(type solid)
		)
		(fill yes)
		(layer "In11.Cu")
		(net "M_H_CPU0_SA_DQ<11>")
	)
	(gr_poly
		(pts
			(xy 375.83618 -278.946356) (xy 375.83618 -278.901906) (xy 375.48058 -278.901906) (xy 375.48058 -278.946356)
			(xy 375.52757 -279.098756) (xy 375.78919 -279.098756)
		)
		(stroke
			(width 0)
			(type solid)
		)
		(fill yes)
		(layer "In11.Cu")
		(net "M_H_CPU0_SA_DQS_DP<1>")
	)
	(gr_poly
		(pts
			(xy 375.83618 -271.215358) (xy 375.78919 -271.062958) (xy 375.52757 -271.062958) (xy 375.48058 -271.215358)
			(xy 375.48058 -271.259808) (xy 375.83618 -271.259808)
		)
		(stroke
			(width 0)
			(type solid)
		)
		(fill yes)
		(layer "In11.Cu")
		(net "M_H_CPU0_SA_DQ<19>")
	)
	(gr_poly
		(pts
			(xy 375.83618 -270.807434) (xy 375.83618 -270.762984) (xy 375.48058 -270.762984) (xy 375.48058 -270.807434)
			(xy 375.52757 -270.959834) (xy 375.78919 -270.959834)
		)
		(stroke
			(width 0)
			(type solid)
		)
		(fill yes)
		(layer "In11.Cu")
		(net "M_H_CPU0_SA_DQS_DP<2>")
	)
	(gr_poly
		(pts
			(xy 375.83618 -269.587726) (xy 375.78919 -269.435326) (xy 375.52757 -269.435326) (xy 375.48058 -269.587726)
			(xy 375.48058 -269.631922) (xy 375.83618 -269.631922)
		)
		(stroke
			(width 0)
			(type solid)
		)
		(fill yes)
		(layer "In11.Cu")
		(net "M_H_CPU0_SA_DQS_DP<7>")
	)
	(gr_poly
		(pts
			(xy 375.83618 -267.960094) (xy 375.78919 -267.807694) (xy 375.52757 -267.807694) (xy 375.48058 -267.960094)
			(xy 375.48058 -268.00429) (xy 375.83618 -268.00429)
		)
		(stroke
			(width 0)
			(type solid)
		)
		(fill yes)
		(layer "In11.Cu")
		(net "M_H_CPU0_SA_DQ<23>")
	)
	(gr_poly
		(pts
			(xy 375.83618 -267.551662) (xy 375.83618 -267.507466) (xy 375.48058 -267.507466) (xy 375.48058 -267.551662)
			(xy 375.52757 -267.704062) (xy 375.78919 -267.704062)
		)
		(stroke
			(width 0)
			(type solid)
		)
		(fill yes)
		(layer "In11.Cu")
		(net "M_H_CPU0_SA_DQ<24>")
	)
	(gr_poly
		(pts
			(xy 375.83618 -266.331954) (xy 375.78919 -266.179554) (xy 375.52757 -266.179554) (xy 375.48058 -266.331954)
			(xy 375.48058 -266.376404) (xy 375.83618 -266.376404)
		)
		(stroke
			(width 0)
			(type solid)
		)
		(fill yes)
		(layer "In11.Cu")
		(net "M_H_CPU0_SA_DQ<27>")
	)
	(gr_poly
		(pts
			(xy 375.83618 -265.92403) (xy 375.83618 -265.879834) (xy 375.48058 -265.879834) (xy 375.48058 -265.92403)
			(xy 375.52757 -266.07643) (xy 375.78919 -266.07643)
		)
		(stroke
			(width 0)
			(type solid)
		)
		(fill yes)
		(layer "In11.Cu")
		(net "M_H_CPU0_SA_DQS_DP<3>")
	)
	(gr_poly
		(pts
			(xy 375.83618 -264.296398) (xy 375.83618 -264.251948) (xy 375.48058 -264.251948) (xy 375.48058 -264.296398)
			(xy 375.52757 -264.448798) (xy 375.78919 -264.448798)
		)
		(stroke
			(width 0)
			(type solid)
		)
		(fill yes)
		(layer "In11.Cu")
		(net "M_H_CPU0_SA_DQ<28>")
	)
	(gr_poly
		(pts
			(xy 375.83618 -263.07669) (xy 375.78919 -262.92429) (xy 375.52757 -262.92429) (xy 375.48058 -263.07669)
			(xy 375.48058 -263.120886) (xy 375.83618 -263.120886)
		)
		(stroke
			(width 0)
			(type solid)
		)
		(fill yes)
		(layer "In11.Cu")
		(net "M_H_CPU0_SA_DQ<31>")
	)
	(gr_poly
		(pts
			(xy 375.83618 -262.668258) (xy 375.83618 -262.624062) (xy 375.48058 -262.624062) (xy 375.48058 -262.668258)
			(xy 375.52757 -262.820658) (xy 375.78919 -262.820658)
		)
		(stroke
			(width 0)
			(type solid)
		)
		(fill yes)
		(layer "In11.Cu")
		(net "M_H_CPU0_SA_CB<0>")
	)
	(gr_poly
		(pts
			(xy 375.83618 -261.449058) (xy 375.78919 -261.296658) (xy 375.52757 -261.296658) (xy 375.48058 -261.449058)
			(xy 375.48058 -261.493254) (xy 375.83618 -261.493254)
		)
		(stroke
			(width 0)
			(type solid)
		)
		(fill yes)
		(layer "In11.Cu")
		(net "M_H_CPU0_SA_CB<3>")
	)
	(gr_poly
		(pts
			(xy 375.83618 -261.040626) (xy 375.83618 -260.99643) (xy 375.48058 -260.99643) (xy 375.48058 -261.040626)
			(xy 375.52757 -261.193026) (xy 375.78919 -261.193026)
		)
		(stroke
			(width 0)
			(type solid)
		)
		(fill yes)
		(layer "In11.Cu")
		(net "M_H_CPU0_SA_DQS_DP<4>")
	)
	(gr_poly
		(pts
			(xy 375.83618 -259.820918) (xy 375.78919 -259.668518) (xy 375.52757 -259.668518) (xy 375.48058 -259.820918)
			(xy 375.48058 -259.865368) (xy 375.83618 -259.865368)
		)
		(stroke
			(width 0)
			(type solid)
		)
		(fill yes)
		(layer "In11.Cu")
		(net "M_H_CPU0_SA_DQS_DP<9>")
	)
	(gr_poly
		(pts
			(xy 375.83618 -259.412994) (xy 375.83618 -259.368544) (xy 375.48058 -259.368544) (xy 375.48058 -259.412994)
			(xy 375.52757 -259.565394) (xy 375.78919 -259.565394)
		)
		(stroke
			(width 0)
			(type solid)
		)
		(fill yes)
		(layer "In11.Cu")
		(net "M_H_CPU0_SA_CB<4>")
	)
	(gr_poly
		(pts
			(xy 375.83618 -256.157222) (xy 375.83618 -256.113026) (xy 375.48058 -256.113026) (xy 375.48058 -256.157222)
			(xy 375.52757 -256.309622) (xy 375.78919 -256.309622)
		)
		(stroke
			(width 0)
			(type solid)
		)
		(fill yes)
		(layer "In11.Cu")
		(net "M_H_CPU0_SA_CS_N<2>")
	)
	(gr_poly
		(pts
			(xy 375.83618 -254.937514) (xy 375.78919 -254.785114) (xy 375.52757 -254.785114) (xy 375.48058 -254.937514)
			(xy 375.48058 -254.981964) (xy 375.83618 -254.981964)
		)
		(stroke
			(width 0)
			(type solid)
		)
		(fill yes)
		(layer "In11.Cu")
		(net "M_H_CPU0_SA_CA<0>")
	)
	(gr_poly
		(pts
			(xy 375.83618 -254.52959) (xy 375.83618 -254.48514) (xy 375.48058 -254.48514) (xy 375.48058 -254.52959)
			(xy 375.52757 -254.68199) (xy 375.78919 -254.68199)
		)
		(stroke
			(width 0)
			(type solid)
		)
		(fill yes)
		(layer "In11.Cu")
		(net "M_H_CPU0_SA_CA<2>")
	)
	(gr_poly
		(pts
			(xy 375.83872 -258.193286) (xy 375.79173 -258.040886) (xy 375.53011 -258.040886) (xy 375.48312 -258.193286)
			(xy 375.48312 -258.237736) (xy 375.83872 -258.237736)
		)
		(stroke
			(width 0)
			(type solid)
		)
		(fill yes)
		(layer "In11.Cu")
		(net "M_H_CPU0_SA_CB<7>")
	)
	(gr_poly
		(pts
			(xy 375.844308 -269.179294) (xy 375.844308 -269.134844) (xy 375.488708 -269.134844) (xy 375.488708 -269.179294)
			(xy 375.535698 -269.331694) (xy 375.797318 -269.331694)
		)
		(stroke
			(width 0)
			(type solid)
		)
		(fill yes)
		(layer "In11.Cu")
		(net "M_H_CPU0_SA_DQ<20>")
	)
	(gr_poly
		(pts
			(xy 375.844562 -256.565654) (xy 375.797572 -256.413254) (xy 375.535952 -256.413254) (xy 375.488962 -256.565654)
			(xy 375.488962 -256.610104) (xy 375.844562 -256.610104)
		)
		(stroke
			(width 0)
			(type solid)
		)
		(fill yes)
		(layer "In11.Cu")
		(net "M_H_CPU0_SA_CS_N<1>")
	)
	(gr_poly
		(pts
			(xy 375.84888 -264.70483) (xy 375.80189 -264.55243) (xy 375.54027 -264.55243) (xy 375.49328 -264.70483)
			(xy 375.49328 -264.749026) (xy 375.84888 -264.749026)
		)
		(stroke
			(width 0)
			(type solid)
		)
		(fill yes)
		(layer "In11.Cu")
		(net "M_H_CPU0_SA_DQS_DP<8>")
	)
	(gr_poly
		(pts
			(xy 375.850658 -257.784854) (xy 375.850658 -257.740404) (xy 375.495058 -257.740404) (xy 375.495058 -257.784854)
			(xy 375.542048 -257.937254) (xy 375.803668 -257.937254)
		)
		(stroke
			(width 0)
			(type solid)
		)
		(fill yes)
		(layer "In11.Cu")
		(net "M_E_CPU0_ALERT_N")
	)
	(gr_poly
		(pts
			(xy 376.061478 -247.64365) (xy 376.099832 -247.621552) (xy 375.922032 -247.313704) (xy 375.883678 -247.335802)
			(xy 375.77522 -247.452642) (xy 375.90603 -247.67921)
		)
		(stroke
			(width 0)
			(type solid)
		)
		(fill yes)
		(layer "In11.Cu")
		(net "M_H_CPU0_SB_CA<2>")
	)
	(gr_poly
		(pts
			(xy 376.165618 -280.420064) (xy 376.203972 -280.397966) (xy 376.026172 -280.090118) (xy 375.987818 -280.112216)
			(xy 375.87936 -280.229056) (xy 376.01017 -280.455624)
		)
		(stroke
			(width 0)
			(type solid)
		)
		(fill yes)
		(layer "In11.Cu")
		(net "M_H_CPU0_SA_DQ<9>")
	)
	(gr_poly
		(pts
			(xy 376.17146 -277.173944) (xy 376.209814 -277.151846) (xy 376.032014 -276.843998) (xy 375.99366 -276.866096)
			(xy 375.885202 -276.982936) (xy 376.016012 -277.209504)
		)
		(stroke
			(width 0)
			(type solid)
		)
		(fill yes)
		(layer "In11.Cu")
		(net "M_H_CPU0_SA_DQ<12>")
	)
	(gr_poly
		(pts
			(xy 376.17146 -273.918426) (xy 376.209814 -273.896328) (xy 376.032014 -273.58848) (xy 375.99366 -273.610578)
			(xy 375.885202 -273.727418) (xy 376.016012 -273.953986)
		)
		(stroke
			(width 0)
			(type solid)
		)
		(fill yes)
		(layer "In11.Cu")
		(net "M_H_CPU0_SA_DQ<16>")
	)
	(gr_poly
		(pts
			(xy 376.173238 -275.547582) (xy 376.211592 -275.525484) (xy 376.033792 -275.217636) (xy 375.995438 -275.239734)
			(xy 375.88698 -275.356574) (xy 376.01779 -275.583142)
		)
		(stroke
			(width 0)
			(type solid)
		)
		(fill yes)
		(layer "In11.Cu")
		(net "M_H_CPU0_SA_DQ<13>")
	)
	(gr_poly
		(pts
			(xy 376.173238 -272.292064) (xy 376.211592 -272.269966) (xy 376.033792 -271.962118) (xy 375.995438 -271.984216)
			(xy 375.88698 -272.101056) (xy 376.01779 -272.327624)
		)
		(stroke
			(width 0)
			(type solid)
		)
		(fill yes)
		(layer "In11.Cu")
		(net "M_H_CPU0_SA_DQ<17>")
	)
	(gr_poly
		(pts
			(xy 376.175524 -247.030494) (xy 376.283982 -246.913654) (xy 376.153172 -246.687086) (xy 375.997724 -246.722646)
			(xy 375.95937 -246.744744) (xy 376.13717 -247.052592)
		)
		(stroke
			(width 0)
			(type solid)
		)
		(fill yes)
		(layer "In11.Cu")
		(net "M_H_CPU0_SB_CA<3>")
	)
	(gr_poly
		(pts
			(xy 376.196098 -227.440998) (xy 376.196098 -227.396548) (xy 375.840498 -227.396548) (xy 375.840498 -227.440998)
			(xy 375.887488 -227.593398) (xy 376.149108 -227.593398)
		)
		(stroke
			(width 0)
			(type solid)
		)
		(fill yes)
		(layer "In11.Cu")
		(net "M_H_CPU0_SB_DQS_DP<3>")
	)
	(gr_poly
		(pts
			(xy 376.20448 -227.84943) (xy 376.15749 -227.69703) (xy 375.89587 -227.69703) (xy 375.84888 -227.84943)
			(xy 375.84888 -227.893626) (xy 376.20448 -227.893626)
		)
		(stroke
			(width 0)
			(type solid)
		)
		(fill yes)
		(layer "In11.Cu")
		(net "M_H_CPU0_SB_DQS_DP<8>")
	)
	(gr_poly
		(pts
			(xy 376.204734 -226.221798) (xy 376.157744 -226.069398) (xy 375.896124 -226.069398) (xy 375.849134 -226.221798)
			(xy 375.849134 -226.265994) (xy 376.204734 -226.265994)
		)
		(stroke
			(width 0)
			(type solid)
		)
		(fill yes)
		(layer "In11.Cu")
		(net "M_H_CPU0_SB_DQ<28>")
	)
	(gr_poly
		(pts
			(xy 376.213116 -248.602246) (xy 376.213116 -248.557796) (xy 375.857516 -248.557796) (xy 375.857516 -248.602246)
			(xy 375.904506 -248.754646) (xy 376.166126 -248.754646)
		)
		(stroke
			(width 0)
			(type solid)
		)
		(fill yes)
		(layer "In11.Cu")
		(net "M_H_CPU0_SB_CA<0>")
	)
	(gr_poly
		(pts
			(xy 376.213116 -244.126766) (xy 376.166126 -243.974366) (xy 375.904506 -243.974366) (xy 375.857516 -244.126766)
			(xy 375.857516 -244.171216) (xy 376.213116 -244.171216)
		)
		(stroke
			(width 0)
			(type solid)
		)
		(fill yes)
		(layer "In11.Cu")
		(net "M_H_CPU0_SB_CB<4>")
	)
	(gr_poly
		(pts
			(xy 376.213116 -243.718842) (xy 376.213116 -243.674392) (xy 375.857516 -243.674392) (xy 375.857516 -243.718842)
			(xy 375.904506 -243.871242) (xy 376.166126 -243.871242)
		)
		(stroke
			(width 0)
			(type solid)
		)
		(fill yes)
		(layer "In11.Cu")
		(net "M_H_CPU0_SB_CB<7>")
	)
	(gr_poly
		(pts
			(xy 376.213116 -242.499134) (xy 376.166126 -242.346734) (xy 375.904506 -242.346734) (xy 375.857516 -242.499134)
			(xy 375.857516 -242.54333) (xy 376.213116 -242.54333)
		)
		(stroke
			(width 0)
			(type solid)
		)
		(fill yes)
		(layer "In11.Cu")
		(net "M_H_CPU0_SB_DQS_DN<9>")
	)
	(gr_poly
		(pts
			(xy 376.213116 -242.090702) (xy 376.213116 -242.046506) (xy 375.857516 -242.046506) (xy 375.857516 -242.090702)
			(xy 375.904506 -242.243102) (xy 376.166126 -242.243102)
		)
		(stroke
			(width 0)
			(type solid)
		)
		(fill yes)
		(layer "In11.Cu")
		(net "M_H_CPU0_SB_DQS_DN<4>")
	)
	(gr_poly
		(pts
			(xy 376.213116 -240.871502) (xy 376.166126 -240.719102) (xy 375.904506 -240.719102) (xy 375.857516 -240.871502)
			(xy 375.857516 -240.915698) (xy 376.213116 -240.915698)
		)
		(stroke
			(width 0)
			(type solid)
		)
		(fill yes)
		(layer "In11.Cu")
		(net "M_H_CPU0_SB_CB<2>")
	)
	(gr_poly
		(pts
			(xy 376.213116 -240.46307) (xy 376.213116 -240.418874) (xy 375.857516 -240.418874) (xy 375.857516 -240.46307)
			(xy 375.904506 -240.61547) (xy 376.166126 -240.61547)
		)
		(stroke
			(width 0)
			(type solid)
		)
		(fill yes)
		(layer "In11.Cu")
		(net "M_H_CPU0_SB_CB<1>")
	)
	(gr_poly
		(pts
			(xy 376.213116 -239.243362) (xy 376.166126 -239.090962) (xy 375.904506 -239.090962) (xy 375.857516 -239.243362)
			(xy 375.857516 -239.287812) (xy 376.213116 -239.287812)
		)
		(stroke
			(width 0)
			(type solid)
		)
		(fill yes)
		(layer "In11.Cu")
		(net "M_H_CPU0_SB_DQ<2>")
	)
	(gr_poly
		(pts
			(xy 376.213116 -238.835438) (xy 376.213116 -238.790988) (xy 375.857516 -238.790988) (xy 375.857516 -238.835438)
			(xy 375.904506 -238.987838) (xy 376.166126 -238.987838)
		)
		(stroke
			(width 0)
			(type solid)
		)
		(fill yes)
		(layer "In11.Cu")
		(net "M_H_CPU0_SB_DQ<1>")
	)
	(gr_poly
		(pts
			(xy 376.213116 -237.61573) (xy 376.166126 -237.46333) (xy 375.904506 -237.46333) (xy 375.857516 -237.61573)
			(xy 375.857516 -237.66018) (xy 376.213116 -237.66018)
		)
		(stroke
			(width 0)
			(type solid)
		)
		(fill yes)
		(layer "In11.Cu")
		(net "M_H_CPU0_SB_DQS_DN<0>")
	)
	(gr_poly
		(pts
			(xy 376.213116 -237.207806) (xy 376.213116 -237.163356) (xy 375.857516 -237.163356) (xy 375.857516 -237.207806)
			(xy 375.904506 -237.360206) (xy 376.166126 -237.360206)
		)
		(stroke
			(width 0)
			(type solid)
		)
		(fill yes)
		(layer "In11.Cu")
		(net "M_H_CPU0_SB_DQS_DN<5>")
	)
	(gr_poly
		(pts
			(xy 376.213116 -235.988098) (xy 376.166126 -235.835698) (xy 375.904506 -235.835698) (xy 375.857516 -235.988098)
			(xy 375.857516 -236.032294) (xy 376.213116 -236.032294)
		)
		(stroke
			(width 0)
			(type solid)
		)
		(fill yes)
		(layer "In11.Cu")
		(net "M_H_CPU0_SB_DQ<6>")
	)
	(gr_poly
		(pts
			(xy 376.213116 -235.579666) (xy 376.213116 -235.53547) (xy 375.857516 -235.53547) (xy 375.857516 -235.579666)
			(xy 375.904506 -235.732066) (xy 376.166126 -235.732066)
		)
		(stroke
			(width 0)
			(type solid)
		)
		(fill yes)
		(layer "In11.Cu")
		(net "M_H_CPU0_SB_DQ<5>")
	)
	(gr_poly
		(pts
			(xy 376.213116 -234.360466) (xy 376.166126 -234.208066) (xy 375.904506 -234.208066) (xy 375.857516 -234.360466)
			(xy 375.857516 -234.404662) (xy 376.213116 -234.404662)
		)
		(stroke
			(width 0)
			(type solid)
		)
		(fill yes)
		(layer "In11.Cu")
		(net "M_H_CPU0_SB_DQ<10>")
	)
	(gr_poly
		(pts
			(xy 376.213116 -233.952034) (xy 376.213116 -233.907838) (xy 375.857516 -233.907838) (xy 375.857516 -233.952034)
			(xy 375.904506 -234.104434) (xy 376.166126 -234.104434)
		)
		(stroke
			(width 0)
			(type solid)
		)
		(fill yes)
		(layer "In11.Cu")
		(net "M_H_CPU0_SB_DQ<9>")
	)
	(gr_poly
		(pts
			(xy 376.213116 -232.732326) (xy 376.166126 -232.579926) (xy 375.904506 -232.579926) (xy 375.857516 -232.732326)
			(xy 375.857516 -232.776776) (xy 376.213116 -232.776776)
		)
		(stroke
			(width 0)
			(type solid)
		)
		(fill yes)
		(layer "In11.Cu")
		(net "M_H_CPU0_SB_DQS_DN<1>")
	)
	(gr_poly
		(pts
			(xy 376.213116 -232.324402) (xy 376.213116 -232.279952) (xy 375.857516 -232.279952) (xy 375.857516 -232.324402)
			(xy 375.904506 -232.476802) (xy 376.166126 -232.476802)
		)
		(stroke
			(width 0)
			(type solid)
		)
		(fill yes)
		(layer "In11.Cu")
		(net "M_H_CPU0_SB_DQS_DN<6>")
	)
	(gr_poly
		(pts
			(xy 376.213116 -231.104694) (xy 376.166126 -230.952294) (xy 375.904506 -230.952294) (xy 375.857516 -231.104694)
			(xy 375.857516 -231.14889) (xy 376.213116 -231.14889)
		)
		(stroke
			(width 0)
			(type solid)
		)
		(fill yes)
		(layer "In11.Cu")
		(net "M_H_CPU0_SB_DQ<14>")
	)
	(gr_poly
		(pts
			(xy 376.213116 -230.696262) (xy 376.213116 -230.652066) (xy 375.857516 -230.652066) (xy 375.857516 -230.696262)
			(xy 375.904506 -230.848662) (xy 376.166126 -230.848662)
		)
		(stroke
			(width 0)
			(type solid)
		)
		(fill yes)
		(layer "In11.Cu")
		(net "M_H_CPU0_SB_DQ<13>")
	)
	(gr_poly
		(pts
			(xy 376.213116 -229.477062) (xy 376.166126 -229.324662) (xy 375.904506 -229.324662) (xy 375.857516 -229.477062)
			(xy 375.857516 -229.521258) (xy 376.213116 -229.521258)
		)
		(stroke
			(width 0)
			(type solid)
		)
		(fill yes)
		(layer "In11.Cu")
		(net "M_H_CPU0_SB_DQ<24>")
	)
	(gr_poly
		(pts
			(xy 376.213116 -229.06863) (xy 376.213116 -229.024434) (xy 375.857516 -229.024434) (xy 375.857516 -229.06863)
			(xy 375.904506 -229.22103) (xy 376.166126 -229.22103)
		)
		(stroke
			(width 0)
			(type solid)
		)
		(fill yes)
		(layer "In11.Cu")
		(net "M_H_CPU0_SB_DQ<27>")
	)
	(gr_poly
		(pts
			(xy 376.213116 -225.813366) (xy 376.213116 -225.768916) (xy 375.857516 -225.768916) (xy 375.857516 -225.813366)
			(xy 375.904506 -225.965766) (xy 376.166126 -225.965766)
		)
		(stroke
			(width 0)
			(type solid)
		)
		(fill yes)
		(layer "In11.Cu")
		(net "M_H_CPU0_SB_DQ<31>")
	)
	(gr_poly
		(pts
			(xy 376.285506 -279.816306) (xy 376.393964 -279.699466) (xy 376.263154 -279.472898) (xy 376.107706 -279.508458)
			(xy 376.069352 -279.530556) (xy 376.247152 -279.838404)
		)
		(stroke
			(width 0)
			(type solid)
		)
		(fill yes)
		(layer "In11.Cu")
		(net "M_H_CPU0_SA_DQ<11>")
	)
	(gr_poly
		(pts
			(xy 376.285506 -276.560788) (xy 376.393964 -276.443948) (xy 376.263154 -276.21738) (xy 376.107706 -276.25294)
			(xy 376.069352 -276.275038) (xy 376.247152 -276.582886)
		)
		(stroke
			(width 0)
			(type solid)
		)
		(fill yes)
		(layer "In11.Cu")
		(net "M_H_CPU0_SA_DQ<14>")
	)
	(gr_poly
		(pts
			(xy 376.285506 -274.932902) (xy 376.393964 -274.816062) (xy 376.263154 -274.589494) (xy 376.107706 -274.625054)
			(xy 376.069352 -274.647152) (xy 376.247152 -274.955)
		)
		(stroke
			(width 0)
			(type solid)
		)
		(fill yes)
		(layer "In11.Cu")
		(net "M_H_CPU0_SA_DQ<15>")
	)
	(gr_poly
		(pts
			(xy 376.285506 -273.30527) (xy 376.393964 -273.18843) (xy 376.263154 -272.961862) (xy 376.107706 -272.997422)
			(xy 376.069352 -273.01952) (xy 376.247152 -273.327368)
		)
		(stroke
			(width 0)
			(type solid)
		)
		(fill yes)
		(layer "In11.Cu")
		(net "M_H_CPU0_SA_DQ<18>")
	)
	(gr_poly
		(pts
			(xy 376.285506 -271.677384) (xy 376.393964 -271.560544) (xy 376.263154 -271.333976) (xy 376.107706 -271.369536)
			(xy 376.069352 -271.391634) (xy 376.247152 -271.699482)
		)
		(stroke
			(width 0)
			(type solid)
		)
		(fill yes)
		(layer "In11.Cu")
		(net "M_H_CPU0_SA_DQ<19>")
	)
	(gr_poly
		(pts
			(xy 376.310398 -265.109706) (xy 376.310398 -265.06551) (xy 375.954798 -265.06551) (xy 375.954798 -265.109706)
			(xy 376.001788 -265.262106) (xy 376.263408 -265.262106)
		)
		(stroke
			(width 0)
			(type solid)
		)
		(fill yes)
		(layer "In11.Cu")
		(net "M_H_CPU0_SA_DQS_DN<8>")
	)
	(gr_poly
		(pts
			(xy 376.31116 -268.77391) (xy 376.26417 -268.62151) (xy 376.00255 -268.62151) (xy 375.95556 -268.77391)
			(xy 375.95556 -268.81836) (xy 376.31116 -268.81836)
		)
		(stroke
			(width 0)
			(type solid)
		)
		(fill yes)
		(layer "In11.Cu")
		(net "M_H_CPU0_SA_DQ<22>")
	)
	(gr_poly
		(pts
			(xy 376.320558 -278.540718) (xy 376.273568 -278.388318) (xy 376.011948 -278.388318) (xy 375.964958 -278.540718)
			(xy 375.964958 -278.585168) (xy 376.320558 -278.585168)
		)
		(stroke
			(width 0)
			(type solid)
		)
		(fill yes)
		(layer "In11.Cu")
		(net "M_H_CPU0_SA_DQS_DN<1>")
	)
	(gr_poly
		(pts
			(xy 376.320558 -257.37947) (xy 376.273568 -257.22707) (xy 376.011948 -257.22707) (xy 375.964958 -257.37947)
			(xy 375.964958 -257.423666) (xy 376.320558 -257.423666)
		)
		(stroke
			(width 0)
			(type solid)
		)
		(fill yes)
		(layer "In11.Cu")
		(net "M_H_CPU0_ALERT_N")
	)
	(gr_poly
		(pts
			(xy 376.320558 -256.971038) (xy 376.320558 -256.926842) (xy 375.964958 -256.926842) (xy 375.964958 -256.971038)
			(xy 376.011948 -257.123438) (xy 376.273568 -257.123438)
		)
		(stroke
			(width 0)
			(type solid)
		)
		(fill yes)
		(layer "In11.Cu")
		(net "M_H_CPU0_SA_CS_N<0>")
	)
	(gr_poly
		(pts
			(xy 376.320558 -254.124206) (xy 376.273568 -253.971806) (xy 376.011948 -253.971806) (xy 375.964958 -254.124206)
			(xy 375.964958 -254.168402) (xy 376.320558 -254.168402)
		)
		(stroke
			(width 0)
			(type solid)
		)
		(fill yes)
		(layer "In11.Cu")
		(net "M_H_CPU0_SA_CA<3>")
	)
	(gr_poly
		(pts
			(xy 376.323098 -281.387804) (xy 376.323098 -281.343608) (xy 375.967498 -281.343608) (xy 375.967498 -281.387804)
			(xy 376.014488 -281.540204) (xy 376.276108 -281.540204)
		)
		(stroke
			(width 0)
			(type solid)
		)
		(fill yes)
		(layer "In11.Cu")
		(net "M_H_CPU0_SA_DQ<8>")
	)
	(gr_poly
		(pts
			(xy 376.323098 -278.132286) (xy 376.323098 -278.08809) (xy 375.967498 -278.08809) (xy 375.967498 -278.132286)
			(xy 376.014488 -278.284686) (xy 376.276108 -278.284686)
		)
		(stroke
			(width 0)
			(type solid)
		)
		(fill yes)
		(layer "In11.Cu")
		(net "M_H_CPU0_SA_DQS_DN<6>")
	)
	(gr_poly
		(pts
			(xy 376.323098 -270.401542) (xy 376.276108 -270.249142) (xy 376.014488 -270.249142) (xy 375.967498 -270.401542)
			(xy 375.967498 -270.445992) (xy 376.323098 -270.445992)
		)
		(stroke
			(width 0)
			(type solid)
		)
		(fill yes)
		(layer "In11.Cu")
		(net "M_H_CPU0_SA_DQS_DN<2>")
	)
	(gr_poly
		(pts
			(xy 376.323098 -269.993618) (xy 376.323098 -269.949168) (xy 375.967498 -269.949168) (xy 375.967498 -269.993618)
			(xy 376.014488 -270.146018) (xy 376.276108 -270.146018)
		)
		(stroke
			(width 0)
			(type solid)
		)
		(fill yes)
		(layer "In11.Cu")
		(net "M_H_CPU0_SA_DQS_DN<7>")
	)
	(gr_poly
		(pts
			(xy 376.323098 -268.365478) (xy 376.323098 -268.321282) (xy 375.967498 -268.321282) (xy 375.967498 -268.365478)
			(xy 376.014488 -268.517878) (xy 376.276108 -268.517878)
		)
		(stroke
			(width 0)
			(type solid)
		)
		(fill yes)
		(layer "In11.Cu")
		(net "M_H_CPU0_SA_DQ<21>")
	)
	(gr_poly
		(pts
			(xy 376.323098 -267.14577) (xy 376.276108 -266.99337) (xy 376.014488 -266.99337) (xy 375.967498 -267.14577)
			(xy 375.967498 -267.19022) (xy 376.323098 -267.19022)
		)
		(stroke
			(width 0)
			(type solid)
		)
		(fill yes)
		(layer "In11.Cu")
		(net "M_H_CPU0_SA_DQ<26>")
	)
	(gr_poly
		(pts
			(xy 376.323098 -266.737846) (xy 376.323098 -266.69365) (xy 375.967498 -266.69365) (xy 375.967498 -266.737846)
			(xy 376.014488 -266.890246) (xy 376.276108 -266.890246)
		)
		(stroke
			(width 0)
			(type solid)
		)
		(fill yes)
		(layer "In11.Cu")
		(net "M_H_CPU0_SA_DQ<25>")
	)
	(gr_poly
		(pts
			(xy 376.323098 -265.518138) (xy 376.276108 -265.365738) (xy 376.014488 -265.365738) (xy 375.967498 -265.518138)
			(xy 375.967498 -265.562588) (xy 376.323098 -265.562588)
		)
		(stroke
			(width 0)
			(type solid)
		)
		(fill yes)
		(layer "In11.Cu")
		(net "M_H_CPU0_SA_DQS_DN<3>")
	)
	(gr_poly
		(pts
			(xy 376.323098 -263.890506) (xy 376.276108 -263.738106) (xy 376.014488 -263.738106) (xy 375.967498 -263.890506)
			(xy 375.967498 -263.934956) (xy 376.323098 -263.934956)
		)
		(stroke
			(width 0)
			(type solid)
		)
		(fill yes)
		(layer "In11.Cu")
		(net "M_H_CPU0_SA_DQ<30>")
	)
	(gr_poly
		(pts
			(xy 376.323098 -263.482582) (xy 376.323098 -263.438132) (xy 375.967498 -263.438132) (xy 375.967498 -263.482582)
			(xy 376.014488 -263.634982) (xy 376.276108 -263.634982)
		)
		(stroke
			(width 0)
			(type solid)
		)
		(fill yes)
		(layer "In11.Cu")
		(net "M_H_CPU0_SA_DQ<29>")
	)
	(gr_poly
		(pts
			(xy 376.323098 -262.262874) (xy 376.276108 -262.110474) (xy 376.014488 -262.110474) (xy 375.967498 -262.262874)
			(xy 375.967498 -262.30707) (xy 376.323098 -262.30707)
		)
		(stroke
			(width 0)
			(type solid)
		)
		(fill yes)
		(layer "In11.Cu")
		(net "M_H_CPU0_SA_CB<2>")
	)
	(gr_poly
		(pts
			(xy 376.323098 -261.854442) (xy 376.323098 -261.810246) (xy 375.967498 -261.810246) (xy 375.967498 -261.854442)
			(xy 376.014488 -262.006842) (xy 376.276108 -262.006842)
		)
		(stroke
			(width 0)
			(type solid)
		)
		(fill yes)
		(layer "In11.Cu")
		(net "M_H_CPU0_SA_CB<1>")
	)
	(gr_poly
		(pts
			(xy 376.323098 -260.634734) (xy 376.276108 -260.482334) (xy 376.014488 -260.482334) (xy 375.967498 -260.634734)
			(xy 375.967498 -260.679184) (xy 376.323098 -260.679184)
		)
		(stroke
			(width 0)
			(type solid)
		)
		(fill yes)
		(layer "In11.Cu")
		(net "M_H_CPU0_SA_DQS_DN<4>")
	)
	(gr_poly
		(pts
			(xy 376.323098 -260.22681) (xy 376.323098 -260.18236) (xy 375.967498 -260.18236) (xy 375.967498 -260.22681)
			(xy 376.014488 -260.37921) (xy 376.276108 -260.37921)
		)
		(stroke
			(width 0)
			(type solid)
		)
		(fill yes)
		(layer "In11.Cu")
		(net "M_H_CPU0_SA_DQS_DN<9>")
	)
	(gr_poly
		(pts
			(xy 376.323098 -259.007102) (xy 376.276108 -258.854702) (xy 376.014488 -258.854702) (xy 375.967498 -259.007102)
			(xy 375.967498 -259.051552) (xy 376.323098 -259.051552)
		)
		(stroke
			(width 0)
			(type solid)
		)
		(fill yes)
		(layer "In11.Cu")
		(net "M_H_CPU0_SA_CB<6>")
	)
	(gr_poly
		(pts
			(xy 376.323098 -258.599178) (xy 376.323098 -258.554728) (xy 375.967498 -258.554728) (xy 375.967498 -258.599178)
			(xy 376.014488 -258.751578) (xy 376.276108 -258.751578)
		)
		(stroke
			(width 0)
			(type solid)
		)
		(fill yes)
		(layer "In11.Cu")
		(net "M_H_CPU0_SA_CB<5>")
	)
	(gr_poly
		(pts
			(xy 376.323098 -255.751838) (xy 376.276108 -255.599438) (xy 376.014488 -255.599438) (xy 375.967498 -255.751838)
			(xy 375.967498 -255.796034) (xy 376.323098 -255.796034)
		)
		(stroke
			(width 0)
			(type solid)
		)
		(fill yes)
		(layer "In11.Cu")
		(net "M_H_CPU0_SA_CS_N<3>")
	)
	(gr_poly
		(pts
			(xy 376.323098 -255.343406) (xy 376.323098 -255.29921) (xy 375.967498 -255.29921) (xy 375.967498 -255.343406)
			(xy 376.014488 -255.495806) (xy 376.276108 -255.495806)
		)
		(stroke
			(width 0)
			(type solid)
		)
		(fill yes)
		(layer "In11.Cu")
		(net "M_H_CPU0_SA_CA<1>")
	)
	(gr_poly
		(pts
			(xy 376.524012 -246.817134) (xy 376.562366 -246.795036) (xy 376.384566 -246.487188) (xy 376.346212 -246.509286)
			(xy 376.237754 -246.626126) (xy 376.368564 -246.852694)
		)
		(stroke
			(width 0)
			(type solid)
		)
		(fill yes)
		(layer "In11.Cu")
		(net "M_H_CPU0_SB_CA<4>")
	)
	(gr_poly
		(pts
			(xy 376.633994 -276.347428) (xy 376.672348 -276.32533) (xy 376.494548 -276.017482) (xy 376.456194 -276.03958)
			(xy 376.347736 -276.15642) (xy 376.478546 -276.382988)
		)
		(stroke
			(width 0)
			(type solid)
		)
		(fill yes)
		(layer "In11.Cu")
		(net "M_H_CPU0_SA_DQ<13>")
	)
	(gr_poly
		(pts
			(xy 376.635772 -279.605994) (xy 376.674126 -279.583896) (xy 376.496326 -279.276048) (xy 376.457972 -279.298146)
			(xy 376.349514 -279.414986) (xy 376.480324 -279.641554)
		)
		(stroke
			(width 0)
			(type solid)
		)
		(fill yes)
		(layer "In11.Cu")
		(net "M_H_CPU0_SA_DQS_DP<1>")
	)
	(gr_poly
		(pts
			(xy 376.635772 -274.72259) (xy 376.674126 -274.700492) (xy 376.496326 -274.392644) (xy 376.457972 -274.414742)
			(xy 376.349514 -274.531582) (xy 376.480324 -274.75815)
		)
		(stroke
			(width 0)
			(type solid)
		)
		(fill yes)
		(layer "In11.Cu")
		(net "M_H_CPU0_SA_DQ<16>")
	)
	(gr_poly
		(pts
			(xy 376.635772 -271.467072) (xy 376.674126 -271.444974) (xy 376.496326 -271.137126) (xy 376.457972 -271.159224)
			(xy 376.349514 -271.276064) (xy 376.480324 -271.502632)
		)
		(stroke
			(width 0)
			(type solid)
		)
		(fill yes)
		(layer "In11.Cu")
		(net "M_H_CPU0_SA_DQS_DP<2>")
	)
	(gr_poly
		(pts
			(xy 376.665998 -248.196354) (xy 376.619008 -248.043954) (xy 376.357388 -248.043954) (xy 376.310398 -248.196354)
			(xy 376.310398 -248.24055) (xy 376.665998 -248.24055)
		)
		(stroke
			(width 0)
			(type solid)
		)
		(fill yes)
		(layer "In11.Cu")
		(net "M_H_CPU0_SB_CA<1>")
	)
	(gr_poly
		(pts
			(xy 376.665998 -247.787922) (xy 376.665998 -247.743726) (xy 376.310398 -247.743726) (xy 376.310398 -247.787922)
			(xy 376.357388 -247.940322) (xy 376.619008 -247.940322)
		)
		(stroke
			(width 0)
			(type solid)
		)
		(fill yes)
		(layer "In11.Cu")
		(net "M_H_CPU0_SB_CA<2>")
	)
	(gr_poly
		(pts
			(xy 376.665998 -244.532658) (xy 376.665998 -244.488208) (xy 376.310398 -244.488208) (xy 376.310398 -244.532658)
			(xy 376.357388 -244.685058) (xy 376.619008 -244.685058)
		)
		(stroke
			(width 0)
			(type solid)
		)
		(fill yes)
		(layer "In11.Cu")
		(net "M_H_CPU0_SB_CB<6>")
	)
	(gr_poly
		(pts
			(xy 376.665998 -243.31295) (xy 376.619008 -243.16055) (xy 376.357388 -243.16055) (xy 376.310398 -243.31295)
			(xy 376.310398 -243.3574) (xy 376.665998 -243.3574)
		)
		(stroke
			(width 0)
			(type solid)
		)
		(fill yes)
		(layer "In11.Cu")
		(net "M_H_CPU0_SB_CB<5>")
	)
	(gr_poly
		(pts
			(xy 376.665998 -242.905026) (xy 376.665998 -242.860576) (xy 376.310398 -242.860576) (xy 376.310398 -242.905026)
			(xy 376.357388 -243.057426) (xy 376.619008 -243.057426)
		)
		(stroke
			(width 0)
			(type solid)
		)
		(fill yes)
		(layer "In11.Cu")
		(net "M_H_CPU0_SB_DQS_DP<9>")
	)
	(gr_poly
		(pts
			(xy 376.665998 -240.057178) (xy 376.619008 -239.904778) (xy 376.357388 -239.904778) (xy 376.310398 -240.057178)
			(xy 376.310398 -240.101628) (xy 376.665998 -240.101628)
		)
		(stroke
			(width 0)
			(type solid)
		)
		(fill yes)
		(layer "In11.Cu")
		(net "M_H_CPU0_SB_CB<3>")
	)
	(gr_poly
		(pts
			(xy 376.665998 -239.649254) (xy 376.665998 -239.604804) (xy 376.310398 -239.604804) (xy 376.310398 -239.649254)
			(xy 376.357388 -239.801654) (xy 376.619008 -239.801654)
		)
		(stroke
			(width 0)
			(type solid)
		)
		(fill yes)
		(layer "In11.Cu")
		(net "M_H_CPU0_SB_DQ<0>")
	)
	(gr_poly
		(pts
			(xy 376.665998 -238.429546) (xy 376.619008 -238.277146) (xy 376.357388 -238.277146) (xy 376.310398 -238.429546)
			(xy 376.310398 -238.473996) (xy 376.665998 -238.473996)
		)
		(stroke
			(width 0)
			(type solid)
		)
		(fill yes)
		(layer "In11.Cu")
		(net "M_H_CPU0_SB_DQ<3>")
	)
	(gr_poly
		(pts
			(xy 376.665998 -238.021622) (xy 376.665998 -237.977172) (xy 376.310398 -237.977172) (xy 376.310398 -238.021622)
			(xy 376.357388 -238.174022) (xy 376.619008 -238.174022)
		)
		(stroke
			(width 0)
			(type solid)
		)
		(fill yes)
		(layer "In11.Cu")
		(net "M_H_CPU0_SB_DQS_DP<0>")
	)
	(gr_poly
		(pts
			(xy 376.665998 -235.174282) (xy 376.619008 -235.021882) (xy 376.357388 -235.021882) (xy 376.310398 -235.174282)
			(xy 376.310398 -235.218478) (xy 376.665998 -235.218478)
		)
		(stroke
			(width 0)
			(type solid)
		)
		(fill yes)
		(layer "In11.Cu")
		(net "M_H_CPU0_SB_DQ<7>")
	)
	(gr_poly
		(pts
			(xy 376.665998 -234.76585) (xy 376.665998 -234.721654) (xy 376.310398 -234.721654) (xy 376.310398 -234.76585)
			(xy 376.357388 -234.91825) (xy 376.619008 -234.91825)
		)
		(stroke
			(width 0)
			(type solid)
		)
		(fill yes)
		(layer "In11.Cu")
		(net "M_H_CPU0_SB_DQ<8>")
	)
	(gr_poly
		(pts
			(xy 376.665998 -233.138218) (xy 376.665998 -233.093768) (xy 376.310398 -233.093768) (xy 376.310398 -233.138218)
			(xy 376.357388 -233.290618) (xy 376.619008 -233.290618)
		)
		(stroke
			(width 0)
			(type solid)
		)
		(fill yes)
		(layer "In11.Cu")
		(net "M_H_CPU0_SB_DQS_DP<1>")
	)
	(gr_poly
		(pts
			(xy 376.665998 -230.290878) (xy 376.619008 -230.138478) (xy 376.357388 -230.138478) (xy 376.310398 -230.290878)
			(xy 376.310398 -230.335074) (xy 376.665998 -230.335074)
		)
		(stroke
			(width 0)
			(type solid)
		)
		(fill yes)
		(layer "In11.Cu")
		(net "M_H_CPU0_SB_DQ<15>")
	)
	(gr_poly
		(pts
			(xy 376.665998 -229.882446) (xy 376.665998 -229.83825) (xy 376.310398 -229.83825) (xy 376.310398 -229.882446)
			(xy 376.357388 -230.034846) (xy 376.619008 -230.034846)
		)
		(stroke
			(width 0)
			(type solid)
		)
		(fill yes)
		(layer "In11.Cu")
		(net "M_H_CPU0_SB_DQ<26>")
	)
	(gr_poly
		(pts
			(xy 376.665998 -228.663246) (xy 376.619008 -228.510846) (xy 376.357388 -228.510846) (xy 376.310398 -228.663246)
			(xy 376.310398 -228.707442) (xy 376.665998 -228.707442)
		)
		(stroke
			(width 0)
			(type solid)
		)
		(fill yes)
		(layer "In11.Cu")
		(net "M_H_CPU0_SB_DQ<25>")
	)
	(gr_poly
		(pts
			(xy 376.665998 -225.407474) (xy 376.619008 -225.255074) (xy 376.357388 -225.255074) (xy 376.310398 -225.407474)
			(xy 376.310398 -225.45167) (xy 376.665998 -225.45167)
		)
		(stroke
			(width 0)
			(type solid)
		)
		(fill yes)
		(layer "In11.Cu")
		(net "M_H_CPU0_SB_DQ<29>")
	)
	(gr_poly
		(pts
			(xy 376.668538 -241.276886) (xy 376.668538 -241.23269) (xy 376.312938 -241.23269) (xy 376.312938 -241.276886)
			(xy 376.359928 -241.429286) (xy 376.621548 -241.429286)
		)
		(stroke
			(width 0)
			(type solid)
		)
		(fill yes)
		(layer "In11.Cu")
		(net "M_H_CPU0_SB_CB<0>")
	)
	(gr_poly
		(pts
			(xy 376.668538 -236.39399) (xy 376.668538 -236.34954) (xy 376.312938 -236.34954) (xy 376.312938 -236.39399)
			(xy 376.359928 -236.54639) (xy 376.621548 -236.54639)
		)
		(stroke
			(width 0)
			(type solid)
		)
		(fill yes)
		(layer "In11.Cu")
		(net "M_H_CPU0_SB_DQ<4>")
	)
	(gr_poly
		(pts
			(xy 376.668538 -231.510586) (xy 376.668538 -231.466136) (xy 376.312938 -231.466136) (xy 376.312938 -231.510586)
			(xy 376.359928 -231.662986) (xy 376.621548 -231.662986)
		)
		(stroke
			(width 0)
			(type solid)
		)
		(fill yes)
		(layer "In11.Cu")
		(net "M_H_CPU0_SB_DQ<12>")
	)
	(gr_poly
		(pts
			(xy 376.668538 -226.626674) (xy 376.668538 -226.582478) (xy 376.312938 -226.582478) (xy 376.312938 -226.626674)
			(xy 376.359928 -226.779074) (xy 376.621548 -226.779074)
		)
		(stroke
			(width 0)
			(type solid)
		)
		(fill yes)
		(layer "In11.Cu")
		(net "M_H_CPU0_SB_DQ<30>")
	)
	(gr_poly
		(pts
			(xy 376.668792 -233.54665) (xy 376.621802 -233.39425) (xy 376.360182 -233.39425) (xy 376.313192 -233.54665)
			(xy 376.313192 -233.590846) (xy 376.668792 -233.590846)
		)
		(stroke
			(width 0)
			(type solid)
		)
		(fill yes)
		(layer "In11.Cu")
		(net "M_H_CPU0_SB_DQ<11>")
	)
	(gr_poly
		(pts
			(xy 376.67438 -228.254814) (xy 376.67438 -228.210364) (xy 376.31878 -228.210364) (xy 376.31878 -228.254814)
			(xy 376.36577 -228.407214) (xy 376.62739 -228.407214)
		)
		(stroke
			(width 0)
			(type solid)
		)
		(fill yes)
		(layer "In11.Cu")
		(net "M_H_CPU0_SB_DQS_DN<8>")
	)
	(gr_poly
		(pts
			(xy 376.674634 -241.685826) (xy 376.627644 -241.533426) (xy 376.366024 -241.533426) (xy 376.319034 -241.685826)
			(xy 376.319034 -241.730022) (xy 376.674634 -241.730022)
		)
		(stroke
			(width 0)
			(type solid)
		)
		(fill yes)
		(layer "In11.Cu")
		(net "M_H_CPU0_SB_DQS_DP<4>")
	)
	(gr_poly
		(pts
			(xy 376.674634 -236.802422) (xy 376.627644 -236.650022) (xy 376.366024 -236.650022) (xy 376.319034 -236.802422)
			(xy 376.319034 -236.846872) (xy 376.674634 -236.846872)
		)
		(stroke
			(width 0)
			(type solid)
		)
		(fill yes)
		(layer "In11.Cu")
		(net "M_H_CPU0_SB_DQS_DP<5>")
	)
	(gr_poly
		(pts
			(xy 376.674634 -231.919018) (xy 376.627644 -231.766618) (xy 376.366024 -231.766618) (xy 376.319034 -231.919018)
			(xy 376.319034 -231.963468) (xy 376.674634 -231.963468)
		)
		(stroke
			(width 0)
			(type solid)
		)
		(fill yes)
		(layer "In11.Cu")
		(net "M_H_CPU0_SB_DQS_DP<6>")
	)
	(gr_poly
		(pts
			(xy 376.680476 -227.035614) (xy 376.633486 -226.883214) (xy 376.371866 -226.883214) (xy 376.324876 -227.035614)
			(xy 376.324876 -227.07981) (xy 376.680476 -227.07981)
		)
		(stroke
			(width 0)
			(type solid)
		)
		(fill yes)
		(layer "In11.Cu")
		(net "M_H_CPU0_SB_DQS_DN<3>")
	)
	(gr_poly
		(pts
			(xy 376.749818 -274.109434) (xy 376.858276 -273.992594) (xy 376.727466 -273.766026) (xy 376.572018 -273.801586)
			(xy 376.533664 -273.823684) (xy 376.711464 -274.131532)
		)
		(stroke
			(width 0)
			(type solid)
		)
		(fill yes)
		(layer "In11.Cu")
		(net "M_H_CPU0_SA_DQ<18>")
	)
	(gr_poly
		(pts
			(xy 376.749818 -270.853916) (xy 376.858276 -270.737076) (xy 376.727466 -270.510508) (xy 376.572018 -270.546068)
			(xy 376.533664 -270.568166) (xy 376.711464 -270.876014)
		)
		(stroke
			(width 0)
			(type solid)
		)
		(fill yes)
		(layer "In11.Cu")
		(net "M_H_CPU0_SA_DQS_DN<2>")
	)
	(gr_poly
		(pts
			(xy 376.750072 -275.737828) (xy 376.85853 -275.620988) (xy 376.72772 -275.39442) (xy 376.572272 -275.42998)
			(xy 376.533918 -275.452078) (xy 376.711718 -275.759926)
		)
		(stroke
			(width 0)
			(type solid)
		)
		(fill yes)
		(layer "In11.Cu")
		(net "M_H_CPU0_SA_DQ<15>")
	)
	(gr_poly
		(pts
			(xy 376.750834 -278.995378) (xy 376.859292 -278.878538) (xy 376.728482 -278.65197) (xy 376.573034 -278.68753)
			(xy 376.53468 -278.709628) (xy 376.71248 -279.017476)
		)
		(stroke
			(width 0)
			(type solid)
		)
		(fill yes)
		(layer "In11.Cu")
		(net "M_H_CPU0_SA_DQS_DN<1>")
	)
	(gr_poly
		(pts
			(xy 376.77598 -280.98242) (xy 376.72899 -280.83002) (xy 376.46737 -280.83002) (xy 376.42038 -280.98242)
			(xy 376.42038 -281.026616) (xy 376.77598 -281.026616)
		)
		(stroke
			(width 0)
			(type solid)
		)
		(fill yes)
		(layer "In11.Cu")
		(net "M_H_CPU0_SA_DQ<10>")
	)
	(gr_poly
		(pts
			(xy 376.77598 -280.574242) (xy 376.77598 -280.529792) (xy 376.42038 -280.529792) (xy 376.42038 -280.574242)
			(xy 376.46737 -280.726642) (xy 376.72899 -280.726642)
		)
		(stroke
			(width 0)
			(type solid)
		)
		(fill yes)
		(layer "In11.Cu")
		(net "M_H_CPU0_SA_DQ<9>")
	)
	(gr_poly
		(pts
			(xy 376.77598 -277.726394) (xy 376.72899 -277.573994) (xy 376.46737 -277.573994) (xy 376.42038 -277.726394)
			(xy 376.42038 -277.770844) (xy 376.77598 -277.770844)
		)
		(stroke
			(width 0)
			(type solid)
		)
		(fill yes)
		(layer "In11.Cu")
		(net "M_H_CPU0_SA_DQS_DP<6>")
	)
	(gr_poly
		(pts
			(xy 376.77598 -277.318216) (xy 376.77598 -277.27402) (xy 376.42038 -277.27402) (xy 376.42038 -277.318216)
			(xy 376.46737 -277.470616) (xy 376.72899 -277.470616)
		)
		(stroke
			(width 0)
			(type solid)
		)
		(fill yes)
		(layer "In11.Cu")
		(net "M_H_CPU0_SA_DQ<12>")
	)
	(gr_poly
		(pts
			(xy 376.77598 -272.435066) (xy 376.77598 -272.39087) (xy 376.42038 -272.39087) (xy 376.42038 -272.435066)
			(xy 376.46737 -272.587466) (xy 376.72899 -272.587466)
		)
		(stroke
			(width 0)
			(type solid)
		)
		(fill yes)
		(layer "In11.Cu")
		(net "M_H_CPU0_SA_DQ<17>")
	)
	(gr_poly
		(pts
			(xy 376.77598 -269.587726) (xy 376.72899 -269.435326) (xy 376.46737 -269.435326) (xy 376.42038 -269.587726)
			(xy 376.42038 -269.631922) (xy 376.77598 -269.631922)
		)
		(stroke
			(width 0)
			(type solid)
		)
		(fill yes)
		(layer "In11.Cu")
		(net "M_H_CPU0_SA_DQS_DP<7>")
	)
	(gr_poly
		(pts
			(xy 376.77598 -267.960094) (xy 376.72899 -267.807694) (xy 376.46737 -267.807694) (xy 376.42038 -267.960094)
			(xy 376.42038 -268.00429) (xy 376.77598 -268.00429)
		)
		(stroke
			(width 0)
			(type solid)
		)
		(fill yes)
		(layer "In11.Cu")
		(net "M_H_CPU0_SA_DQ<23>")
	)
	(gr_poly
		(pts
			(xy 376.77598 -267.551662) (xy 376.77598 -267.507466) (xy 376.42038 -267.507466) (xy 376.42038 -267.551662)
			(xy 376.46737 -267.704062) (xy 376.72899 -267.704062)
		)
		(stroke
			(width 0)
			(type solid)
		)
		(fill yes)
		(layer "In11.Cu")
		(net "M_H_CPU0_SA_DQ<24>")
	)
	(gr_poly
		(pts
			(xy 376.77598 -266.331954) (xy 376.72899 -266.179554) (xy 376.46737 -266.179554) (xy 376.42038 -266.331954)
			(xy 376.42038 -266.376404) (xy 376.77598 -266.376404)
		)
		(stroke
			(width 0)
			(type solid)
		)
		(fill yes)
		(layer "In11.Cu")
		(net "M_H_CPU0_SA_DQ<27>")
	)
	(gr_poly
		(pts
			(xy 376.77598 -265.92403) (xy 376.77598 -265.879834) (xy 376.42038 -265.879834) (xy 376.42038 -265.92403)
			(xy 376.46737 -266.07643) (xy 376.72899 -266.07643)
		)
		(stroke
			(width 0)
			(type solid)
		)
		(fill yes)
		(layer "In11.Cu")
		(net "M_H_CPU0_SA_DQS_DP<3>")
	)
	(gr_poly
		(pts
			(xy 376.77598 -264.296398) (xy 376.77598 -264.251948) (xy 376.42038 -264.251948) (xy 376.42038 -264.296398)
			(xy 376.46737 -264.448798) (xy 376.72899 -264.448798)
		)
		(stroke
			(width 0)
			(type solid)
		)
		(fill yes)
		(layer "In11.Cu")
		(net "M_H_CPU0_SA_DQ<28>")
	)
	(gr_poly
		(pts
			(xy 376.77598 -263.07669) (xy 376.72899 -262.92429) (xy 376.46737 -262.92429) (xy 376.42038 -263.07669)
			(xy 376.42038 -263.120886) (xy 376.77598 -263.120886)
		)
		(stroke
			(width 0)
			(type solid)
		)
		(fill yes)
		(layer "In11.Cu")
		(net "M_H_CPU0_SA_DQ<31>")
	)
	(gr_poly
		(pts
			(xy 376.77598 -262.668258) (xy 376.77598 -262.624062) (xy 376.42038 -262.624062) (xy 376.42038 -262.668258)
			(xy 376.46737 -262.820658) (xy 376.72899 -262.820658)
		)
		(stroke
			(width 0)
			(type solid)
		)
		(fill yes)
		(layer "In11.Cu")
		(net "M_H_CPU0_SA_CB<0>")
	)
	(gr_poly
		(pts
			(xy 376.77598 -261.449058) (xy 376.72899 -261.296658) (xy 376.46737 -261.296658) (xy 376.42038 -261.449058)
			(xy 376.42038 -261.493254) (xy 376.77598 -261.493254)
		)
		(stroke
			(width 0)
			(type solid)
		)
		(fill yes)
		(layer "In11.Cu")
		(net "M_H_CPU0_SA_CB<3>")
	)
	(gr_poly
		(pts
			(xy 376.77598 -261.040626) (xy 376.77598 -260.99643) (xy 376.42038 -260.99643) (xy 376.42038 -261.040626)
			(xy 376.46737 -261.193026) (xy 376.72899 -261.193026)
		)
		(stroke
			(width 0)
			(type solid)
		)
		(fill yes)
		(layer "In11.Cu")
		(net "M_H_CPU0_SA_DQS_DP<4>")
	)
	(gr_poly
		(pts
			(xy 376.77598 -259.820918) (xy 376.72899 -259.668518) (xy 376.46737 -259.668518) (xy 376.42038 -259.820918)
			(xy 376.42038 -259.865368) (xy 376.77598 -259.865368)
		)
		(stroke
			(width 0)
			(type solid)
		)
		(fill yes)
		(layer "In11.Cu")
		(net "M_H_CPU0_SA_DQS_DP<9>")
	)
	(gr_poly
		(pts
			(xy 376.77598 -259.412994) (xy 376.77598 -259.368544) (xy 376.42038 -259.368544) (xy 376.42038 -259.412994)
			(xy 376.46737 -259.565394) (xy 376.72899 -259.565394)
		)
		(stroke
			(width 0)
			(type solid)
		)
		(fill yes)
		(layer "In11.Cu")
		(net "M_H_CPU0_SA_CB<4>")
	)
	(gr_poly
		(pts
			(xy 376.77598 -258.193286) (xy 376.72899 -258.040886) (xy 376.46737 -258.040886) (xy 376.42038 -258.193286)
			(xy 376.42038 -258.237482) (xy 376.77598 -258.237482)
		)
		(stroke
			(width 0)
			(type solid)
		)
		(fill yes)
		(layer "In11.Cu")
		(net "M_H_CPU0_SA_CB<7>")
	)
	(gr_poly
		(pts
			(xy 376.77598 -257.784854) (xy 376.77598 -257.740658) (xy 376.42038 -257.740658) (xy 376.42038 -257.784854)
			(xy 376.46737 -257.937254) (xy 376.72899 -257.937254)
		)
		(stroke
			(width 0)
			(type solid)
		)
		(fill yes)
		(layer "In11.Cu")
		(net "M_E_CPU0_ALERT_N")
	)
	(gr_poly
		(pts
			(xy 376.77598 -254.937514) (xy 376.72899 -254.785114) (xy 376.46737 -254.785114) (xy 376.42038 -254.937514)
			(xy 376.42038 -254.981964) (xy 376.77598 -254.981964)
		)
		(stroke
			(width 0)
			(type solid)
		)
		(fill yes)
		(layer "In11.Cu")
		(net "M_H_CPU0_SA_CA<0>")
	)
	(gr_poly
		(pts
			(xy 376.77598 -254.52959) (xy 376.77598 -254.48514) (xy 376.42038 -254.48514) (xy 376.42038 -254.52959)
			(xy 376.46737 -254.68199) (xy 376.72899 -254.68199)
		)
		(stroke
			(width 0)
			(type solid)
		)
		(fill yes)
		(layer "In11.Cu")
		(net "M_H_CPU0_SA_CA<2>")
	)
	(gr_poly
		(pts
			(xy 376.77852 -256.565654) (xy 376.73153 -256.413254) (xy 376.46991 -256.413254) (xy 376.42292 -256.565654)
			(xy 376.42292 -256.60985) (xy 376.77852 -256.60985)
		)
		(stroke
			(width 0)
			(type solid)
		)
		(fill yes)
		(layer "In11.Cu")
		(net "M_H_CPU0_SA_CS_N<1>")
	)
	(gr_poly
		(pts
			(xy 376.77852 -256.157222) (xy 376.77852 -256.113026) (xy 376.42292 -256.113026) (xy 376.42292 -256.157222)
			(xy 376.46991 -256.309622) (xy 376.73153 -256.309622)
		)
		(stroke
			(width 0)
			(type solid)
		)
		(fill yes)
		(layer "In11.Cu")
		(net "M_H_CPU0_SA_CS_N<2>")
	)
	(gr_poly
		(pts
			(xy 376.787918 -269.179294) (xy 376.787918 -269.134844) (xy 376.432318 -269.134844) (xy 376.432318 -269.179294)
			(xy 376.479308 -269.331694) (xy 376.740928 -269.331694)
		)
		(stroke
			(width 0)
			(type solid)
		)
		(fill yes)
		(layer "In11.Cu")
		(net "M_H_CPU0_SA_DQ<20>")
	)
	(gr_poly
		(pts
			(xy 376.78868 -264.70483) (xy 376.74169 -264.55243) (xy 376.48007 -264.55243) (xy 376.43308 -264.70483)
			(xy 376.43308 -264.749026) (xy 376.78868 -264.749026)
		)
		(stroke
			(width 0)
			(type solid)
		)
		(fill yes)
		(layer "In11.Cu")
		(net "M_H_CPU0_SA_DQS_DP<8>")
	)
	(gr_poly
		(pts
			(xy 377.11126 -278.80183) (xy 377.149614 -278.779732) (xy 376.971814 -278.471884) (xy 376.93346 -278.493982)
			(xy 376.825002 -278.610822) (xy 376.955812 -278.83739)
		)
		(stroke
			(width 0)
			(type solid)
		)
		(fill yes)
		(layer "In11.Cu")
		(net "M_H_CPU0_SA_DQS_DN<6>")
	)
	(gr_poly
		(pts
			(xy 377.11126 -270.662908) (xy 377.149614 -270.64081) (xy 376.971814 -270.332962) (xy 376.93346 -270.35506)
			(xy 376.825002 -270.4719) (xy 376.955812 -270.698468)
		)
		(stroke
			(width 0)
			(type solid)
		)
		(fill yes)
		(layer "In11.Cu")
		(net "M_H_CPU0_SA_DQS_DN<7>")
	)
	(gr_poly
		(pts
			(xy 377.112276 -275.547836) (xy 377.15063 -275.525738) (xy 376.97283 -275.21789) (xy 376.934476 -275.239988)
			(xy 376.826018 -275.356828) (xy 376.956828 -275.583396)
		)
		(stroke
			(width 0)
			(type solid)
		)
		(fill yes)
		(layer "In11.Cu")
		(net "M_H_CPU0_SA_DQ<16>")
	)
	(gr_poly
		(pts
			(xy 377.144534 -246.974106) (xy 377.144534 -246.929656) (xy 376.788934 -246.929656) (xy 376.788934 -246.974106)
			(xy 376.835924 -247.126506) (xy 377.097544 -247.126506)
		)
		(stroke
			(width 0)
			(type solid)
		)
		(fill yes)
		(layer "In11.Cu")
		(net "M_H_CPU0_SB_CA<4>")
	)
	(gr_poly
		(pts
			(xy 377.144534 -242.090702) (xy 377.144534 -242.046252) (xy 376.788934 -242.046252) (xy 376.788934 -242.090702)
			(xy 376.835924 -242.243102) (xy 377.097544 -242.243102)
		)
		(stroke
			(width 0)
			(type solid)
		)
		(fill yes)
		(layer "In11.Cu")
		(net "M_H_CPU0_SB_DQS_DN<4>")
	)
	(gr_poly
		(pts
			(xy 377.144534 -240.871502) (xy 377.097544 -240.719102) (xy 376.835924 -240.719102) (xy 376.788934 -240.871502)
			(xy 376.788934 -240.915952) (xy 377.144534 -240.915952)
		)
		(stroke
			(width 0)
			(type solid)
		)
		(fill yes)
		(layer "In11.Cu")
		(net "M_H_CPU0_SB_CB<2>")
	)
	(gr_poly
		(pts
			(xy 377.144534 -237.207298) (xy 377.144534 -237.163102) (xy 376.788934 -237.163102) (xy 376.788934 -237.207298)
			(xy 376.835924 -237.359698) (xy 377.097544 -237.359698)
		)
		(stroke
			(width 0)
			(type solid)
		)
		(fill yes)
		(layer "In11.Cu")
		(net "M_H_CPU0_SB_DQS_DN<5>")
	)
	(gr_poly
		(pts
			(xy 377.144534 -235.988098) (xy 377.097544 -235.835698) (xy 376.835924 -235.835698) (xy 376.788934 -235.988098)
			(xy 376.788934 -236.032548) (xy 377.144534 -236.032548)
		)
		(stroke
			(width 0)
			(type solid)
		)
		(fill yes)
		(layer "In11.Cu")
		(net "M_H_CPU0_SB_DQ<6>")
	)
	(gr_poly
		(pts
			(xy 377.144534 -232.323894) (xy 377.144534 -232.279698) (xy 376.788934 -232.279698) (xy 376.788934 -232.323894)
			(xy 376.835924 -232.476294) (xy 377.097544 -232.476294)
		)
		(stroke
			(width 0)
			(type solid)
		)
		(fill yes)
		(layer "In11.Cu")
		(net "M_H_CPU0_SB_DQS_DN<6>")
	)
	(gr_poly
		(pts
			(xy 377.144534 -231.104694) (xy 377.097544 -230.952294) (xy 376.835924 -230.952294) (xy 376.788934 -231.104694)
			(xy 376.788934 -231.149144) (xy 377.144534 -231.149144)
		)
		(stroke
			(width 0)
			(type solid)
		)
		(fill yes)
		(layer "In11.Cu")
		(net "M_H_CPU0_SB_DQ<14>")
	)
	(gr_poly
		(pts
			(xy 377.150376 -248.601738) (xy 377.150376 -248.557542) (xy 376.794776 -248.557542) (xy 376.794776 -248.601738)
			(xy 376.841766 -248.754138) (xy 377.103386 -248.754138)
		)
		(stroke
			(width 0)
			(type solid)
		)
		(fill yes)
		(layer "In11.Cu")
		(net "M_H_CPU0_SB_CA<0>")
	)
	(gr_poly
		(pts
			(xy 377.150376 -244.127274) (xy 377.103386 -243.974874) (xy 376.841766 -243.974874) (xy 376.794776 -244.127274)
			(xy 376.794776 -244.17147) (xy 377.150376 -244.17147)
		)
		(stroke
			(width 0)
			(type solid)
		)
		(fill yes)
		(layer "In11.Cu")
		(net "M_H_CPU0_SB_CB<4>")
	)
	(gr_poly
		(pts
			(xy 377.150376 -243.718334) (xy 377.150376 -243.674138) (xy 376.794776 -243.674138) (xy 376.794776 -243.718334)
			(xy 376.841766 -243.870734) (xy 377.103386 -243.870734)
		)
		(stroke
			(width 0)
			(type solid)
		)
		(fill yes)
		(layer "In11.Cu")
		(net "M_H_CPU0_SB_CB<7>")
	)
	(gr_poly
		(pts
			(xy 377.150376 -239.24387) (xy 377.103386 -239.09147) (xy 376.841766 -239.09147) (xy 376.794776 -239.24387)
			(xy 376.794776 -239.288066) (xy 377.150376 -239.288066)
		)
		(stroke
			(width 0)
			(type solid)
		)
		(fill yes)
		(layer "In11.Cu")
		(net "M_H_CPU0_SB_DQ<2>")
	)
	(gr_poly
		(pts
			(xy 377.150376 -238.83493) (xy 377.150376 -238.790734) (xy 376.794776 -238.790734) (xy 376.794776 -238.83493)
			(xy 376.841766 -238.98733) (xy 377.103386 -238.98733)
		)
		(stroke
			(width 0)
			(type solid)
		)
		(fill yes)
		(layer "In11.Cu")
		(net "M_H_CPU0_SB_DQ<1>")
	)
	(gr_poly
		(pts
			(xy 377.150376 -234.360466) (xy 377.103386 -234.208066) (xy 376.841766 -234.208066) (xy 376.794776 -234.360466)
			(xy 376.794776 -234.404916) (xy 377.150376 -234.404916)
		)
		(stroke
			(width 0)
			(type solid)
		)
		(fill yes)
		(layer "In11.Cu")
		(net "M_H_CPU0_SB_DQ<10>")
	)
	(gr_poly
		(pts
			(xy 377.150376 -233.952034) (xy 377.150376 -233.907584) (xy 376.794776 -233.907584) (xy 376.794776 -233.952034)
			(xy 376.841766 -234.104434) (xy 377.103386 -234.104434)
		)
		(stroke
			(width 0)
			(type solid)
		)
		(fill yes)
		(layer "In11.Cu")
		(net "M_H_CPU0_SB_DQ<9>")
	)
	(gr_poly
		(pts
			(xy 377.150376 -229.477062) (xy 377.103386 -229.324662) (xy 376.841766 -229.324662) (xy 376.794776 -229.477062)
			(xy 376.794776 -229.521512) (xy 377.150376 -229.521512)
		)
		(stroke
			(width 0)
			(type solid)
		)
		(fill yes)
		(layer "In11.Cu")
		(net "M_H_CPU0_SB_DQ<24>")
	)
	(gr_poly
		(pts
			(xy 377.150376 -229.06863) (xy 377.150376 -229.02418) (xy 376.794776 -229.02418) (xy 376.794776 -229.06863)
			(xy 376.841766 -229.22103) (xy 377.103386 -229.22103)
		)
		(stroke
			(width 0)
			(type solid)
		)
		(fill yes)
		(layer "In11.Cu")
		(net "M_H_CPU0_SB_DQ<27>")
	)
	(gr_poly
		(pts
			(xy 377.150376 -227.848922) (xy 377.103386 -227.696522) (xy 376.841766 -227.696522) (xy 376.794776 -227.848922)
			(xy 376.794776 -227.893372) (xy 377.150376 -227.893372)
		)
		(stroke
			(width 0)
			(type solid)
		)
		(fill yes)
		(layer "In11.Cu")
		(net "M_H_CPU0_SB_DQS_DP<8>")
	)
	(gr_poly
		(pts
			(xy 377.150376 -227.440998) (xy 377.150376 -227.396548) (xy 376.794776 -227.396548) (xy 376.794776 -227.440998)
			(xy 376.841766 -227.593398) (xy 377.103386 -227.593398)
		)
		(stroke
			(width 0)
			(type solid)
		)
		(fill yes)
		(layer "In11.Cu")
		(net "M_H_CPU0_SB_DQS_DP<3>")
	)
	(gr_poly
		(pts
			(xy 377.152916 -247.382538) (xy 377.105926 -247.230138) (xy 376.844306 -247.230138) (xy 376.797316 -247.382538)
			(xy 376.797316 -247.426734) (xy 377.152916 -247.426734)
		)
		(stroke
			(width 0)
			(type solid)
		)
		(fill yes)
		(layer "In11.Cu")
		(net "M_H_CPU0_SB_CA<3>")
	)
	(gr_poly
		(pts
			(xy 377.152916 -242.499134) (xy 377.105926 -242.346734) (xy 376.844306 -242.346734) (xy 376.797316 -242.499134)
			(xy 376.797316 -242.54333) (xy 377.152916 -242.54333)
		)
		(stroke
			(width 0)
			(type solid)
		)
		(fill yes)
		(layer "In11.Cu")
		(net "M_H_CPU0_SB_DQS_DN<9>")
	)
	(gr_poly
		(pts
			(xy 377.152916 -240.46307) (xy 377.152916 -240.418874) (xy 376.797316 -240.418874) (xy 376.797316 -240.46307)
			(xy 376.844306 -240.61547) (xy 377.105926 -240.61547)
		)
		(stroke
			(width 0)
			(type solid)
		)
		(fill yes)
		(layer "In11.Cu")
		(net "M_H_CPU0_SB_CB<1>")
	)
	(gr_poly
		(pts
			(xy 377.152916 -237.61573) (xy 377.105926 -237.46333) (xy 376.844306 -237.46333) (xy 376.797316 -237.61573)
			(xy 376.797316 -237.66018) (xy 377.152916 -237.66018)
		)
		(stroke
			(width 0)
			(type solid)
		)
		(fill yes)
		(layer "In11.Cu")
		(net "M_H_CPU0_SB_DQS_DN<0>")
	)
	(gr_poly
		(pts
			(xy 377.152916 -235.579666) (xy 377.152916 -235.53547) (xy 376.797316 -235.53547) (xy 376.797316 -235.579666)
			(xy 376.844306 -235.732066) (xy 377.105926 -235.732066)
		)
		(stroke
			(width 0)
			(type solid)
		)
		(fill yes)
		(layer "In11.Cu")
		(net "M_H_CPU0_SB_DQ<5>")
	)
	(gr_poly
		(pts
			(xy 377.152916 -232.732326) (xy 377.105926 -232.579926) (xy 376.844306 -232.579926) (xy 376.797316 -232.732326)
			(xy 376.797316 -232.776776) (xy 377.152916 -232.776776)
		)
		(stroke
			(width 0)
			(type solid)
		)
		(fill yes)
		(layer "In11.Cu")
		(net "M_H_CPU0_SB_DQS_DN<1>")
	)
	(gr_poly
		(pts
			(xy 377.152916 -230.696262) (xy 377.152916 -230.652066) (xy 376.797316 -230.652066) (xy 376.797316 -230.696262)
			(xy 376.844306 -230.848662) (xy 377.105926 -230.848662)
		)
		(stroke
			(width 0)
			(type solid)
		)
		(fill yes)
		(layer "In11.Cu")
		(net "M_H_CPU0_SB_DQ<13>")
	)
	(gr_poly
		(pts
			(xy 377.152916 -226.22129) (xy 377.105926 -226.06889) (xy 376.844306 -226.06889) (xy 376.797316 -226.22129)
			(xy 376.797316 -226.26574) (xy 377.152916 -226.26574)
		)
		(stroke
			(width 0)
			(type solid)
		)
		(fill yes)
		(layer "In11.Cu")
		(net "M_H_CPU0_SB_DQ<28>")
	)
	(gr_poly
		(pts
			(xy 377.152916 -225.813366) (xy 377.152916 -225.768916) (xy 376.797316 -225.768916) (xy 376.797316 -225.813366)
			(xy 376.844306 -225.965766) (xy 377.105926 -225.965766)
		)
		(stroke
			(width 0)
			(type solid)
		)
		(fill yes)
		(layer "In11.Cu")
		(net "M_H_CPU0_SB_DQ<31>")
	)
	(gr_poly
		(pts
			(xy 377.219972 -278.17953) (xy 377.32843 -278.06269) (xy 377.19762 -277.836122) (xy 377.042172 -277.871682)
			(xy 377.003818 -277.89378) (xy 377.181618 -278.201628)
		)
		(stroke
			(width 0)
			(type solid)
		)
		(fill yes)
		(layer "In11.Cu")
		(net "M_H_CPU0_SA_DQS_DP<6>")
	)
	(gr_poly
		(pts
			(xy 377.219972 -270.040608) (xy 377.32843 -269.923768) (xy 377.19762 -269.6972) (xy 377.042172 -269.73276)
			(xy 377.003818 -269.754858) (xy 377.181618 -270.062706)
		)
		(stroke
			(width 0)
			(type solid)
		)
		(fill yes)
		(layer "In11.Cu")
		(net "M_H_CPU0_SA_DQS_DP<7>")
	)
	(gr_poly
		(pts
			(xy 377.225306 -274.932902) (xy 377.333764 -274.816062) (xy 377.202954 -274.589494) (xy 377.047506 -274.625054)
			(xy 377.009152 -274.647152) (xy 377.186952 -274.955)
		)
		(stroke
			(width 0)
			(type solid)
		)
		(fill yes)
		(layer "In11.Cu")
		(net "M_H_CPU0_SA_DQ<18>")
	)
	(gr_poly
		(pts
			(xy 377.250198 -265.109706) (xy 377.250198 -265.06551) (xy 376.894598 -265.06551) (xy 376.894598 -265.109706)
			(xy 376.941588 -265.262106) (xy 377.203208 -265.262106)
		)
		(stroke
			(width 0)
			(type solid)
		)
		(fill yes)
		(layer "In11.Cu")
		(net "M_H_CPU0_SA_DQS_DN<8>")
	)
	(gr_poly
		(pts
			(xy 377.254262 -254.124206) (xy 377.207272 -253.971806) (xy 376.945652 -253.971806) (xy 376.898662 -254.124206)
			(xy 376.898662 -254.168402) (xy 377.254262 -254.168402)
		)
		(stroke
			(width 0)
			(type solid)
		)
		(fill yes)
		(layer "In11.Cu")
		(net "M_H_CPU0_SA_CA<3>")
	)
	(gr_poly
		(pts
			(xy 377.254516 -276.504146) (xy 377.254516 -276.45995) (xy 376.898916 -276.45995) (xy 376.898916 -276.504146)
			(xy 376.945906 -276.656546) (xy 377.207526 -276.656546)
		)
		(stroke
			(width 0)
			(type solid)
		)
		(fill yes)
		(layer "In11.Cu")
		(net "M_H_CPU0_SA_DQ<13>")
	)
	(gr_poly
		(pts
			(xy 377.254516 -256.971038) (xy 377.254516 -256.926588) (xy 376.898916 -256.926588) (xy 376.898916 -256.971038)
			(xy 376.945906 -257.123438) (xy 377.207526 -257.123438)
		)
		(stroke
			(width 0)
			(type solid)
		)
		(fill yes)
		(layer "In11.Cu")
		(net "M_H_CPU0_SA_CS_N<0>")
	)
	(gr_poly
		(pts
			(xy 377.254516 -255.751838) (xy 377.207526 -255.599438) (xy 376.945906 -255.599438) (xy 376.898916 -255.751838)
			(xy 376.898916 -255.796288) (xy 377.254516 -255.796288)
		)
		(stroke
			(width 0)
			(type solid)
		)
		(fill yes)
		(layer "In11.Cu")
		(net "M_H_CPU0_SA_CS_N<3>")
	)
	(gr_poly
		(pts
			(xy 377.260358 -263.891014) (xy 377.213368 -263.738614) (xy 376.951748 -263.738614) (xy 376.904758 -263.891014)
			(xy 376.904758 -263.93521) (xy 377.260358 -263.93521)
		)
		(stroke
			(width 0)
			(type solid)
		)
		(fill yes)
		(layer "In11.Cu")
		(net "M_H_CPU0_SA_DQ<30>")
	)
	(gr_poly
		(pts
			(xy 377.260358 -263.482074) (xy 377.260358 -263.437878) (xy 376.904758 -263.437878) (xy 376.904758 -263.482074)
			(xy 376.951748 -263.634474) (xy 377.213368 -263.634474)
		)
		(stroke
			(width 0)
			(type solid)
		)
		(fill yes)
		(layer "In11.Cu")
		(net "M_H_CPU0_SA_DQ<29>")
	)
	(gr_poly
		(pts
			(xy 377.260358 -259.00761) (xy 377.213368 -258.85521) (xy 376.951748 -258.85521) (xy 376.904758 -259.00761)
			(xy 376.904758 -259.051806) (xy 377.260358 -259.051806)
		)
		(stroke
			(width 0)
			(type solid)
		)
		(fill yes)
		(layer "In11.Cu")
		(net "M_H_CPU0_SA_CB<6>")
	)
	(gr_poly
		(pts
			(xy 377.260358 -258.59867) (xy 377.260358 -258.554474) (xy 376.904758 -258.554474) (xy 376.904758 -258.59867)
			(xy 376.951748 -258.75107) (xy 377.213368 -258.75107)
		)
		(stroke
			(width 0)
			(type solid)
		)
		(fill yes)
		(layer "In11.Cu")
		(net "M_H_CPU0_SA_CB<5>")
	)
	(gr_poly
		(pts
			(xy 377.262898 -281.387804) (xy 377.262898 -281.343608) (xy 376.907298 -281.343608) (xy 376.907298 -281.387804)
			(xy 376.954288 -281.540204) (xy 377.215908 -281.540204)
		)
		(stroke
			(width 0)
			(type solid)
		)
		(fill yes)
		(layer "In11.Cu")
		(net "M_H_CPU0_SA_DQ<8>")
	)
	(gr_poly
		(pts
			(xy 377.262898 -280.168096) (xy 377.215908 -280.015696) (xy 376.954288 -280.015696) (xy 376.907298 -280.168096)
			(xy 376.907298 -280.212546) (xy 377.262898 -280.212546)
		)
		(stroke
			(width 0)
			(type solid)
		)
		(fill yes)
		(layer "In11.Cu")
		(net "M_H_CPU0_SA_DQ<11>")
	)
	(gr_poly
		(pts
			(xy 377.262898 -279.759918) (xy 377.262898 -279.715722) (xy 376.907298 -279.715722) (xy 376.907298 -279.759918)
			(xy 376.954288 -279.912318) (xy 377.215908 -279.912318)
		)
		(stroke
			(width 0)
			(type solid)
		)
		(fill yes)
		(layer "In11.Cu")
		(net "M_H_CPU0_SA_DQS_DP<1>")
	)
	(gr_poly
		(pts
			(xy 377.262898 -276.912578) (xy 377.215908 -276.760178) (xy 376.954288 -276.760178) (xy 376.907298 -276.912578)
			(xy 376.907298 -276.957028) (xy 377.262898 -276.957028)
		)
		(stroke
			(width 0)
			(type solid)
		)
		(fill yes)
		(layer "In11.Cu")
		(net "M_H_CPU0_SA_DQ<14>")
	)
	(gr_poly
		(pts
			(xy 377.262898 -272.029174) (xy 377.215908 -271.876774) (xy 376.954288 -271.876774) (xy 376.907298 -272.029174)
			(xy 376.907298 -272.073624) (xy 377.262898 -272.073624)
		)
		(stroke
			(width 0)
			(type solid)
		)
		(fill yes)
		(layer "In11.Cu")
		(net "M_H_CPU0_SA_DQ<19>")
	)
	(gr_poly
		(pts
			(xy 377.262898 -271.62125) (xy 377.262898 -271.5768) (xy 376.907298 -271.5768) (xy 376.907298 -271.62125)
			(xy 376.954288 -271.77365) (xy 377.215908 -271.77365)
		)
		(stroke
			(width 0)
			(type solid)
		)
		(fill yes)
		(layer "In11.Cu")
		(net "M_H_CPU0_SA_DQS_DP<2>")
	)
	(gr_poly
		(pts
			(xy 377.262898 -268.77391) (xy 377.215908 -268.62151) (xy 376.954288 -268.62151) (xy 376.907298 -268.77391)
			(xy 376.907298 -268.818106) (xy 377.262898 -268.818106)
		)
		(stroke
			(width 0)
			(type solid)
		)
		(fill yes)
		(layer "In11.Cu")
		(net "M_H_CPU0_SA_DQ<22>")
	)
	(gr_poly
		(pts
			(xy 377.262898 -268.365478) (xy 377.262898 -268.321282) (xy 376.907298 -268.321282) (xy 376.907298 -268.365478)
			(xy 376.954288 -268.517878) (xy 377.215908 -268.517878)
		)
		(stroke
			(width 0)
			(type solid)
		)
		(fill yes)
		(layer "In11.Cu")
		(net "M_H_CPU0_SA_DQ<21>")
	)
	(gr_poly
		(pts
			(xy 377.262898 -267.14577) (xy 377.215908 -266.99337) (xy 376.954288 -266.99337) (xy 376.907298 -267.14577)
			(xy 376.907298 -267.19022) (xy 377.262898 -267.19022)
		)
		(stroke
			(width 0)
			(type solid)
		)
		(fill yes)
		(layer "In11.Cu")
		(net "M_H_CPU0_SA_DQ<26>")
	)
	(gr_poly
		(pts
			(xy 377.262898 -266.737846) (xy 377.262898 -266.69365) (xy 376.907298 -266.69365) (xy 376.907298 -266.737846)
			(xy 376.954288 -266.890246) (xy 377.215908 -266.890246)
		)
		(stroke
			(width 0)
			(type solid)
		)
		(fill yes)
		(layer "In11.Cu")
		(net "M_H_CPU0_SA_DQ<25>")
	)
	(gr_poly
		(pts
			(xy 377.262898 -265.518138) (xy 377.215908 -265.365738) (xy 376.954288 -265.365738) (xy 376.907298 -265.518138)
			(xy 376.907298 -265.562588) (xy 377.262898 -265.562588)
		)
		(stroke
			(width 0)
			(type solid)
		)
		(fill yes)
		(layer "In11.Cu")
		(net "M_H_CPU0_SA_DQS_DN<3>")
	)
	(gr_poly
		(pts
			(xy 377.262898 -262.262874) (xy 377.215908 -262.110474) (xy 376.954288 -262.110474) (xy 376.907298 -262.262874)
			(xy 376.907298 -262.30707) (xy 377.262898 -262.30707)
		)
		(stroke
			(width 0)
			(type solid)
		)
		(fill yes)
		(layer "In11.Cu")
		(net "M_H_CPU0_SA_CB<2>")
	)
	(gr_poly
		(pts
			(xy 377.262898 -261.854442) (xy 377.262898 -261.810246) (xy 376.907298 -261.810246) (xy 376.907298 -261.854442)
			(xy 376.954288 -262.006842) (xy 377.215908 -262.006842)
		)
		(stroke
			(width 0)
			(type solid)
		)
		(fill yes)
		(layer "In11.Cu")
		(net "M_H_CPU0_SA_CB<1>")
	)
	(gr_poly
		(pts
			(xy 377.262898 -260.634734) (xy 377.215908 -260.482334) (xy 376.954288 -260.482334) (xy 376.907298 -260.634734)
			(xy 376.907298 -260.679184) (xy 377.262898 -260.679184)
		)
		(stroke
			(width 0)
			(type solid)
		)
		(fill yes)
		(layer "In11.Cu")
		(net "M_H_CPU0_SA_DQS_DN<4>")
	)
	(gr_poly
		(pts
			(xy 377.262898 -260.22681) (xy 377.262898 -260.18236) (xy 376.907298 -260.18236) (xy 376.907298 -260.22681)
			(xy 376.954288 -260.37921) (xy 377.215908 -260.37921)
		)
		(stroke
			(width 0)
			(type solid)
		)
		(fill yes)
		(layer "In11.Cu")
		(net "M_H_CPU0_SA_DQS_DN<9>")
	)
	(gr_poly
		(pts
			(xy 377.262898 -257.37947) (xy 377.215908 -257.22707) (xy 376.954288 -257.22707) (xy 376.907298 -257.37947)
			(xy 376.907298 -257.423666) (xy 377.262898 -257.423666)
		)
		(stroke
			(width 0)
			(type solid)
		)
		(fill yes)
		(layer "In11.Cu")
		(net "M_H_CPU0_ALERT_N")
	)
	(gr_poly
		(pts
			(xy 377.262898 -255.343406) (xy 377.262898 -255.29921) (xy 376.907298 -255.29921) (xy 376.907298 -255.343406)
			(xy 376.954288 -255.495806) (xy 377.215908 -255.495806)
		)
		(stroke
			(width 0)
			(type solid)
		)
		(fill yes)
		(layer "In11.Cu")
		(net "M_H_CPU0_SA_CA<1>")
	)
	(gr_poly
		(pts
			(xy 377.575572 -273.094958) (xy 377.613926 -273.07286) (xy 377.436126 -272.765012) (xy 377.397772 -272.78711)
			(xy 377.289314 -272.90395) (xy 377.420124 -273.130518)
		)
		(stroke
			(width 0)
			(type solid)
		)
		(fill yes)
		(layer "In11.Cu")
		(net "M_H_CPU0_SA_DQ<17>")
	)
	(gr_poly
		(pts
			(xy 377.579382 -277.984458) (xy 377.617736 -277.96236) (xy 377.439936 -277.654512) (xy 377.401582 -277.67661)
			(xy 377.293124 -277.79345) (xy 377.423934 -278.020018)
		)
		(stroke
			(width 0)
			(type solid)
		)
		(fill yes)
		(layer "In11.Cu")
		(net "M_H_CPU0_SA_DQ<12>")
	)
	(gr_poly
		(pts
			(xy 377.605798 -247.787922) (xy 377.605798 -247.743726) (xy 377.250198 -247.743726) (xy 377.250198 -247.787922)
			(xy 377.297188 -247.940322) (xy 377.558808 -247.940322)
		)
		(stroke
			(width 0)
			(type solid)
		)
		(fill yes)
		(layer "In11.Cu")
		(net "M_H_CPU0_SB_CA<2>")
	)
	(gr_poly
		(pts
			(xy 377.605798 -242.905026) (xy 377.605798 -242.860576) (xy 377.250198 -242.860576) (xy 377.250198 -242.905026)
			(xy 377.297188 -243.057426) (xy 377.558808 -243.057426)
		)
		(stroke
			(width 0)
			(type solid)
		)
		(fill yes)
		(layer "In11.Cu")
		(net "M_H_CPU0_SB_DQS_DP<9>")
	)
	(gr_poly
		(pts
			(xy 377.605798 -240.057178) (xy 377.558808 -239.904778) (xy 377.297188 -239.904778) (xy 377.250198 -240.057178)
			(xy 377.250198 -240.101628) (xy 377.605798 -240.101628)
		)
		(stroke
			(width 0)
			(type solid)
		)
		(fill yes)
		(layer "In11.Cu")
		(net "M_H_CPU0_SB_CB<3>")
	)
	(gr_poly
		(pts
			(xy 377.605798 -238.021622) (xy 377.605798 -237.977172) (xy 377.250198 -237.977172) (xy 377.250198 -238.021622)
			(xy 377.297188 -238.174022) (xy 377.558808 -238.174022)
		)
		(stroke
			(width 0)
			(type solid)
		)
		(fill yes)
		(layer "In11.Cu")
		(net "M_H_CPU0_SB_DQS_DP<0>")
	)
	(gr_poly
		(pts
			(xy 377.605798 -235.174282) (xy 377.558808 -235.021882) (xy 377.297188 -235.021882) (xy 377.250198 -235.174282)
			(xy 377.250198 -235.218478) (xy 377.605798 -235.218478)
		)
		(stroke
			(width 0)
			(type solid)
		)
		(fill yes)
		(layer "In11.Cu")
		(net "M_H_CPU0_SB_DQ<7>")
	)
	(gr_poly
		(pts
			(xy 377.605798 -233.138218) (xy 377.605798 -233.093768) (xy 377.250198 -233.093768) (xy 377.250198 -233.138218)
			(xy 377.297188 -233.290618) (xy 377.558808 -233.290618)
		)
		(stroke
			(width 0)
			(type solid)
		)
		(fill yes)
		(layer "In11.Cu")
		(net "M_H_CPU0_SB_DQS_DP<1>")
	)
	(gr_poly
		(pts
			(xy 377.605798 -230.290878) (xy 377.558808 -230.138478) (xy 377.297188 -230.138478) (xy 377.250198 -230.290878)
			(xy 377.250198 -230.335074) (xy 377.605798 -230.335074)
		)
		(stroke
			(width 0)
			(type solid)
		)
		(fill yes)
		(layer "In11.Cu")
		(net "M_H_CPU0_SB_DQ<15>")
	)
	(gr_poly
		(pts
			(xy 377.605798 -228.254814) (xy 377.605798 -228.210618) (xy 377.250198 -228.210618) (xy 377.250198 -228.254814)
			(xy 377.297188 -228.407214) (xy 377.558808 -228.407214)
		)
		(stroke
			(width 0)
			(type solid)
		)
		(fill yes)
		(layer "In11.Cu")
		(net "M_H_CPU0_SB_DQS_DN<8>")
	)
	(gr_poly
		(pts
			(xy 377.605798 -227.035106) (xy 377.558808 -226.882706) (xy 377.297188 -226.882706) (xy 377.250198 -227.035106)
			(xy 377.250198 -227.079556) (xy 377.605798 -227.079556)
		)
		(stroke
			(width 0)
			(type solid)
		)
		(fill yes)
		(layer "In11.Cu")
		(net "M_H_CPU0_SB_DQS_DN<3>")
	)
	(gr_poly
		(pts
			(xy 377.605798 -226.627182) (xy 377.605798 -226.582732) (xy 377.250198 -226.582732) (xy 377.250198 -226.627182)
			(xy 377.297188 -226.779582) (xy 377.558808 -226.779582)
		)
		(stroke
			(width 0)
			(type solid)
		)
		(fill yes)
		(layer "In11.Cu")
		(net "M_H_CPU0_SB_DQ<30>")
	)
	(gr_poly
		(pts
			(xy 377.605798 -225.407474) (xy 377.558808 -225.255074) (xy 377.297188 -225.255074) (xy 377.250198 -225.407474)
			(xy 377.250198 -225.45167) (xy 377.605798 -225.45167)
		)
		(stroke
			(width 0)
			(type solid)
		)
		(fill yes)
		(layer "In11.Cu")
		(net "M_H_CPU0_SB_DQ<29>")
	)
	(gr_poly
		(pts
			(xy 377.606052 -233.546142) (xy 377.559062 -233.393742) (xy 377.297442 -233.393742) (xy 377.250452 -233.546142)
			(xy 377.250452 -233.590592) (xy 377.606052 -233.590592)
		)
		(stroke
			(width 0)
			(type solid)
		)
		(fill yes)
		(layer "In11.Cu")
		(net "M_H_CPU0_SB_DQ<11>")
	)
	(gr_poly
		(pts
			(xy 377.608338 -246.568722) (xy 377.561348 -246.416322) (xy 377.299728 -246.416322) (xy 377.252738 -246.568722)
			(xy 377.252738 -246.613172) (xy 377.608338 -246.613172)
		)
		(stroke
			(width 0)
			(type solid)
		)
		(fill yes)
		(layer "In11.Cu")
		(net "M_H_CPU0_SB_CA<5>")
	)
	(gr_poly
		(pts
			(xy 377.608338 -241.276886) (xy 377.608338 -241.232436) (xy 377.252738 -241.232436) (xy 377.252738 -241.276886)
			(xy 377.299728 -241.429286) (xy 377.561348 -241.429286)
		)
		(stroke
			(width 0)
			(type solid)
		)
		(fill yes)
		(layer "In11.Cu")
		(net "M_H_CPU0_SB_CB<0>")
	)
	(gr_poly
		(pts
			(xy 377.608338 -236.393482) (xy 377.608338 -236.349286) (xy 377.252738 -236.349286) (xy 377.252738 -236.393482)
			(xy 377.299728 -236.545882) (xy 377.561348 -236.545882)
		)
		(stroke
			(width 0)
			(type solid)
		)
		(fill yes)
		(layer "In11.Cu")
		(net "M_H_CPU0_SB_DQ<4>")
	)
	(gr_poly
		(pts
			(xy 377.608338 -231.510078) (xy 377.608338 -231.465882) (xy 377.252738 -231.465882) (xy 377.252738 -231.510078)
			(xy 377.299728 -231.662478) (xy 377.561348 -231.662478)
		)
		(stroke
			(width 0)
			(type solid)
		)
		(fill yes)
		(layer "In11.Cu")
		(net "M_H_CPU0_SB_DQ<12>")
	)
	(gr_poly
		(pts
			(xy 377.61418 -248.196354) (xy 377.56719 -248.043954) (xy 377.30557 -248.043954) (xy 377.25858 -248.196354)
			(xy 377.25858 -248.240804) (xy 377.61418 -248.240804)
		)
		(stroke
			(width 0)
			(type solid)
		)
		(fill yes)
		(layer "In11.Cu")
		(net "M_H_CPU0_SB_CA<1>")
	)
	(gr_poly
		(pts
			(xy 377.61418 -244.53215) (xy 377.61418 -244.487954) (xy 377.25858 -244.487954) (xy 377.25858 -244.53215)
			(xy 377.30557 -244.68455) (xy 377.56719 -244.68455)
		)
		(stroke
			(width 0)
			(type solid)
		)
		(fill yes)
		(layer "In11.Cu")
		(net "M_H_CPU0_SB_CB<6>")
	)
	(gr_poly
		(pts
			(xy 377.61418 -243.313458) (xy 377.56719 -243.161058) (xy 377.30557 -243.161058) (xy 377.25858 -243.313458)
			(xy 377.25858 -243.357654) (xy 377.61418 -243.357654)
		)
		(stroke
			(width 0)
			(type solid)
		)
		(fill yes)
		(layer "In11.Cu")
		(net "M_H_CPU0_SB_CB<5>")
	)
	(gr_poly
		(pts
			(xy 377.61418 -239.648746) (xy 377.61418 -239.60455) (xy 377.25858 -239.60455) (xy 377.25858 -239.648746)
			(xy 377.30557 -239.801146) (xy 377.56719 -239.801146)
		)
		(stroke
			(width 0)
			(type solid)
		)
		(fill yes)
		(layer "In11.Cu")
		(net "M_H_CPU0_SB_DQ<0>")
	)
	(gr_poly
		(pts
			(xy 377.61418 -238.430054) (xy 377.56719 -238.277654) (xy 377.30557 -238.277654) (xy 377.25858 -238.430054)
			(xy 377.25858 -238.47425) (xy 377.61418 -238.47425)
		)
		(stroke
			(width 0)
			(type solid)
		)
		(fill yes)
		(layer "In11.Cu")
		(net "M_H_CPU0_SB_DQ<3>")
	)
	(gr_poly
		(pts
			(xy 377.61418 -234.76585) (xy 377.61418 -234.7214) (xy 377.25858 -234.7214) (xy 377.25858 -234.76585)
			(xy 377.30557 -234.91825) (xy 377.56719 -234.91825)
		)
		(stroke
			(width 0)
			(type solid)
		)
		(fill yes)
		(layer "In11.Cu")
		(net "M_H_CPU0_SB_DQ<8>")
	)
	(gr_poly
		(pts
			(xy 377.61418 -229.882446) (xy 377.61418 -229.837996) (xy 377.25858 -229.837996) (xy 377.25858 -229.882446)
			(xy 377.30557 -230.034846) (xy 377.56719 -230.034846)
		)
		(stroke
			(width 0)
			(type solid)
		)
		(fill yes)
		(layer "In11.Cu")
		(net "M_H_CPU0_SB_DQ<26>")
	)
	(gr_poly
		(pts
			(xy 377.61418 -228.663246) (xy 377.56719 -228.510846) (xy 377.30557 -228.510846) (xy 377.25858 -228.663246)
			(xy 377.25858 -228.707696) (xy 377.61418 -228.707696)
		)
		(stroke
			(width 0)
			(type solid)
		)
		(fill yes)
		(layer "In11.Cu")
		(net "M_H_CPU0_SB_DQ<25>")
	)
	(gr_poly
		(pts
			(xy 377.614688 -241.685826) (xy 377.567698 -241.533426) (xy 377.306078 -241.533426) (xy 377.259088 -241.685826)
			(xy 377.259088 -241.730022) (xy 377.614688 -241.730022)
		)
		(stroke
			(width 0)
			(type solid)
		)
		(fill yes)
		(layer "In11.Cu")
		(net "M_H_CPU0_SB_DQS_DP<4>")
	)
	(gr_poly
		(pts
			(xy 377.614688 -236.802422) (xy 377.567698 -236.650022) (xy 377.306078 -236.650022) (xy 377.259088 -236.802422)
			(xy 377.259088 -236.846872) (xy 377.614688 -236.846872)
		)
		(stroke
			(width 0)
			(type solid)
		)
		(fill yes)
		(layer "In11.Cu")
		(net "M_H_CPU0_SB_DQS_DP<5>")
	)
	(gr_poly
		(pts
			(xy 377.614688 -231.919018) (xy 377.567698 -231.766618) (xy 377.306078 -231.766618) (xy 377.259088 -231.919018)
			(xy 377.259088 -231.963468) (xy 377.614688 -231.963468)
		)
		(stroke
			(width 0)
			(type solid)
		)
		(fill yes)
		(layer "In11.Cu")
		(net "M_H_CPU0_SB_DQS_DP<6>")
	)
	(gr_poly
		(pts
			(xy 377.693174 -272.488152) (xy 377.801632 -272.371312) (xy 377.670822 -272.144744) (xy 377.515374 -272.180304)
			(xy 377.47702 -272.202402) (xy 377.65482 -272.51025)
		)
		(stroke
			(width 0)
			(type solid)
		)
		(fill yes)
		(layer "In11.Cu")
		(net "M_H_CPU0_SA_DQ<19>")
	)
	(gr_poly
		(pts
			(xy 377.695206 -277.374858) (xy 377.803664 -277.258018) (xy 377.672854 -277.03145) (xy 377.517406 -277.06701)
			(xy 377.479052 -277.089108) (xy 377.656852 -277.396956)
		)
		(stroke
			(width 0)
			(type solid)
		)
		(fill yes)
		(layer "In11.Cu")
		(net "M_H_CPU0_SA_DQ<14>")
	)
	(gr_poly
		(pts
			(xy 377.71578 -280.98242) (xy 377.66879 -280.83002) (xy 377.40717 -280.83002) (xy 377.36018 -280.98242)
			(xy 377.36018 -281.026616) (xy 377.71578 -281.026616)
		)
		(stroke
			(width 0)
			(type solid)
		)
		(fill yes)
		(layer "In11.Cu")
		(net "M_H_CPU0_SA_DQ<10>")
	)
	(gr_poly
		(pts
			(xy 377.71578 -280.574242) (xy 377.71578 -280.529792) (xy 377.36018 -280.529792) (xy 377.36018 -280.574242)
			(xy 377.40717 -280.726642) (xy 377.66879 -280.726642)
		)
		(stroke
			(width 0)
			(type solid)
		)
		(fill yes)
		(layer "In11.Cu")
		(net "M_H_CPU0_SA_DQ<9>")
	)
	(gr_poly
		(pts
			(xy 377.71578 -271.215358) (xy 377.66879 -271.062958) (xy 377.40717 -271.062958) (xy 377.36018 -271.215358)
			(xy 377.36018 -271.259808) (xy 377.71578 -271.259808)
		)
		(stroke
			(width 0)
			(type solid)
		)
		(fill yes)
		(layer "In11.Cu")
		(net "M_H_CPU0_SA_DQS_DN<2>")
	)
	(gr_poly
		(pts
			(xy 377.71578 -270.807434) (xy 377.71578 -270.762984) (xy 377.36018 -270.762984) (xy 377.36018 -270.807434)
			(xy 377.40717 -270.959834) (xy 377.66879 -270.959834)
		)
		(stroke
			(width 0)
			(type solid)
		)
		(fill yes)
		(layer "In11.Cu")
		(net "M_H_CPU0_SA_DQS_DN<7>")
	)
	(gr_poly
		(pts
			(xy 377.71578 -269.179294) (xy 377.71578 -269.135098) (xy 377.36018 -269.135098) (xy 377.36018 -269.179294)
			(xy 377.40717 -269.331694) (xy 377.66879 -269.331694)
		)
		(stroke
			(width 0)
			(type solid)
		)
		(fill yes)
		(layer "In11.Cu")
		(net "M_H_CPU0_SA_DQ<20>")
	)
	(gr_poly
		(pts
			(xy 377.71578 -267.551662) (xy 377.71578 -267.507466) (xy 377.36018 -267.507466) (xy 377.36018 -267.551662)
			(xy 377.40717 -267.704062) (xy 377.66879 -267.704062)
		)
		(stroke
			(width 0)
			(type solid)
		)
		(fill yes)
		(layer "In11.Cu")
		(net "M_H_CPU0_SA_DQ<24>")
	)
	(gr_poly
		(pts
			(xy 377.71578 -266.331954) (xy 377.66879 -266.179554) (xy 377.40717 -266.179554) (xy 377.36018 -266.331954)
			(xy 377.36018 -266.376404) (xy 377.71578 -266.376404)
		)
		(stroke
			(width 0)
			(type solid)
		)
		(fill yes)
		(layer "In11.Cu")
		(net "M_H_CPU0_SA_DQ<27>")
	)
	(gr_poly
		(pts
			(xy 377.71578 -265.92403) (xy 377.71578 -265.879834) (xy 377.36018 -265.879834) (xy 377.36018 -265.92403)
			(xy 377.40717 -266.07643) (xy 377.66879 -266.07643)
		)
		(stroke
			(width 0)
			(type solid)
		)
		(fill yes)
		(layer "In11.Cu")
		(net "M_H_CPU0_SA_DQS_DP<3>")
	)
	(gr_poly
		(pts
			(xy 377.71578 -262.668258) (xy 377.71578 -262.624062) (xy 377.36018 -262.624062) (xy 377.36018 -262.668258)
			(xy 377.40717 -262.820658) (xy 377.66879 -262.820658)
		)
		(stroke
			(width 0)
			(type solid)
		)
		(fill yes)
		(layer "In11.Cu")
		(net "M_H_CPU0_SA_CB<0>")
	)
	(gr_poly
		(pts
			(xy 377.71578 -261.449058) (xy 377.66879 -261.296658) (xy 377.40717 -261.296658) (xy 377.36018 -261.449058)
			(xy 377.36018 -261.493254) (xy 377.71578 -261.493254)
		)
		(stroke
			(width 0)
			(type solid)
		)
		(fill yes)
		(layer "In11.Cu")
		(net "M_H_CPU0_SA_CB<3>")
	)
	(gr_poly
		(pts
			(xy 377.71578 -261.040626) (xy 377.71578 -260.99643) (xy 377.36018 -260.99643) (xy 377.36018 -261.040626)
			(xy 377.40717 -261.193026) (xy 377.66879 -261.193026)
		)
		(stroke
			(width 0)
			(type solid)
		)
		(fill yes)
		(layer "In11.Cu")
		(net "M_H_CPU0_SA_DQS_DP<4>")
	)
	(gr_poly
		(pts
			(xy 377.71578 -259.820918) (xy 377.66879 -259.668518) (xy 377.40717 -259.668518) (xy 377.36018 -259.820918)
			(xy 377.36018 -259.865368) (xy 377.71578 -259.865368)
		)
		(stroke
			(width 0)
			(type solid)
		)
		(fill yes)
		(layer "In11.Cu")
		(net "M_H_CPU0_SA_DQS_DP<9>")
	)
	(gr_poly
		(pts
			(xy 377.71578 -257.784854) (xy 377.71578 -257.740658) (xy 377.36018 -257.740658) (xy 377.36018 -257.784854)
			(xy 377.40717 -257.937254) (xy 377.66879 -257.937254)
		)
		(stroke
			(width 0)
			(type solid)
		)
		(fill yes)
		(layer "In11.Cu")
		(net "M_E_CPU0_ALERT_N")
	)
	(gr_poly
		(pts
			(xy 377.71578 -254.937514) (xy 377.66879 -254.785114) (xy 377.40717 -254.785114) (xy 377.36018 -254.937514)
			(xy 377.36018 -254.981964) (xy 377.71578 -254.981964)
		)
		(stroke
			(width 0)
			(type solid)
		)
		(fill yes)
		(layer "In11.Cu")
		(net "M_H_CPU0_SA_CA<0>")
	)
	(gr_poly
		(pts
			(xy 377.71832 -279.354534) (xy 377.67133 -279.202134) (xy 377.40971 -279.202134) (xy 377.36272 -279.354534)
			(xy 377.36272 -279.39873) (xy 377.71832 -279.39873)
		)
		(stroke
			(width 0)
			(type solid)
		)
		(fill yes)
		(layer "In11.Cu")
		(net "M_H_CPU0_SA_DQS_DN<1>")
	)
	(gr_poly
		(pts
			(xy 377.71832 -278.946102) (xy 377.71832 -278.901906) (xy 377.36272 -278.901906) (xy 377.36272 -278.946102)
			(xy 377.40971 -279.098502) (xy 377.67133 -279.098502)
		)
		(stroke
			(width 0)
			(type solid)
		)
		(fill yes)
		(layer "In11.Cu")
		(net "M_H_CPU0_SA_DQS_DN<6>")
	)
	(gr_poly
		(pts
			(xy 377.71832 -276.09927) (xy 377.67133 -275.94687) (xy 377.40971 -275.94687) (xy 377.36272 -276.09927)
			(xy 377.36272 -276.143466) (xy 377.71832 -276.143466)
		)
		(stroke
			(width 0)
			(type solid)
		)
		(fill yes)
		(layer "In11.Cu")
		(net "M_H_CPU0_SA_DQ<15>")
	)
	(gr_poly
		(pts
			(xy 377.71832 -275.690584) (xy 377.71832 -275.646134) (xy 377.36272 -275.646134) (xy 377.36272 -275.690584)
			(xy 377.40971 -275.842984) (xy 377.67133 -275.842984)
		)
		(stroke
			(width 0)
			(type solid)
		)
		(fill yes)
		(layer "In11.Cu")
		(net "M_H_CPU0_SA_DQ<16>")
	)
	(gr_poly
		(pts
			(xy 377.71832 -256.565654) (xy 377.67133 -256.413254) (xy 377.40971 -256.413254) (xy 377.36272 -256.565654)
			(xy 377.36272 -256.610104) (xy 377.71832 -256.610104)
		)
		(stroke
			(width 0)
			(type solid)
		)
		(fill yes)
		(layer "In11.Cu")
		(net "M_H_CPU0_SA_CS_N<1>")
	)
	(gr_poly
		(pts
			(xy 377.71832 -256.157222) (xy 377.71832 -256.112772) (xy 377.36272 -256.112772) (xy 377.36272 -256.157222)
			(xy 377.40971 -256.309622) (xy 377.67133 -256.309622)
		)
		(stroke
			(width 0)
			(type solid)
		)
		(fill yes)
		(layer "In11.Cu")
		(net "M_H_CPU0_SA_CS_N<2>")
	)
	(gr_poly
		(pts
			(xy 377.723908 -267.960094) (xy 377.676918 -267.807694) (xy 377.415298 -267.807694) (xy 377.368308 -267.960094)
			(xy 377.368308 -268.004544) (xy 377.723908 -268.004544)
		)
		(stroke
			(width 0)
			(type solid)
		)
		(fill yes)
		(layer "In11.Cu")
		(net "M_H_CPU0_SA_DQ<23>")
	)
	(gr_poly
		(pts
			(xy 377.724162 -264.29589) (xy 377.724162 -264.251694) (xy 377.368562 -264.251694) (xy 377.368562 -264.29589)
			(xy 377.415552 -264.44829) (xy 377.677172 -264.44829)
		)
		(stroke
			(width 0)
			(type solid)
		)
		(fill yes)
		(layer "In11.Cu")
		(net "M_H_CPU0_SA_DQ<28>")
	)
	(gr_poly
		(pts
			(xy 377.724162 -263.07669) (xy 377.677172 -262.92429) (xy 377.415552 -262.92429) (xy 377.368562 -263.07669)
			(xy 377.368562 -263.12114) (xy 377.724162 -263.12114)
		)
		(stroke
			(width 0)
			(type solid)
		)
		(fill yes)
		(layer "In11.Cu")
		(net "M_H_CPU0_SA_DQ<31>")
	)
	(gr_poly
		(pts
			(xy 377.724162 -259.412486) (xy 377.724162 -259.36829) (xy 377.368562 -259.36829) (xy 377.368562 -259.412486)
			(xy 377.415552 -259.564886) (xy 377.677172 -259.564886)
		)
		(stroke
			(width 0)
			(type solid)
		)
		(fill yes)
		(layer "In11.Cu")
		(net "M_H_CPU0_SA_CB<4>")
	)
	(gr_poly
		(pts
			(xy 377.724162 -258.193286) (xy 377.677172 -258.040886) (xy 377.415552 -258.040886) (xy 377.368562 -258.193286)
			(xy 377.368562 -258.237736) (xy 377.724162 -258.237736)
		)
		(stroke
			(width 0)
			(type solid)
		)
		(fill yes)
		(layer "In11.Cu")
		(net "M_H_CPU0_SA_CB<7>")
	)
	(gr_poly
		(pts
			(xy 377.724162 -254.529082) (xy 377.724162 -254.484886) (xy 377.368562 -254.484886) (xy 377.368562 -254.529082)
			(xy 377.415552 -254.681482) (xy 377.677172 -254.681482)
		)
		(stroke
			(width 0)
			(type solid)
		)
		(fill yes)
		(layer "In11.Cu")
		(net "M_H_CPU0_SA_CA<2>")
	)
	(gr_poly
		(pts
			(xy 377.72848 -264.70483) (xy 377.68149 -264.55243) (xy 377.41987 -264.55243) (xy 377.37288 -264.70483)
			(xy 377.37288 -264.749026) (xy 377.72848 -264.749026)
		)
		(stroke
			(width 0)
			(type solid)
		)
		(fill yes)
		(layer "In11.Cu")
		(net "M_H_CPU0_SA_DQS_DP<8>")
	)
	(gr_poly
		(pts
			(xy 378.050044 -277.171404) (xy 378.088398 -277.149306) (xy 377.910598 -276.841458) (xy 377.872244 -276.863556)
			(xy 377.763786 -276.980396) (xy 377.894596 -277.206964)
		)
		(stroke
			(width 0)
			(type solid)
		)
		(fill yes)
		(layer "In11.Cu")
		(net "M_H_CPU0_SA_DQ<13>")
	)
	(gr_poly
		(pts
			(xy 378.05106 -273.918426) (xy 378.089414 -273.896328) (xy 377.911614 -273.58848) (xy 377.87326 -273.610578)
			(xy 377.764802 -273.727418) (xy 377.895612 -273.953986)
		)
		(stroke
			(width 0)
			(type solid)
		)
		(fill yes)
		(layer "In11.Cu")
		(net "M_H_CPU0_SA_DQ<17>")
	)
	(gr_poly
		(pts
			(xy 378.052838 -272.292064) (xy 378.091192 -272.269966) (xy 377.913392 -271.962118) (xy 377.875038 -271.984216)
			(xy 377.76658 -272.101056) (xy 377.89739 -272.327624)
		)
		(stroke
			(width 0)
			(type solid)
		)
		(fill yes)
		(layer "In11.Cu")
		(net "M_H_CPU0_SA_DQS_DP<2>")
	)
	(gr_poly
		(pts
			(xy 378.090176 -248.602246) (xy 378.090176 -248.557796) (xy 377.734576 -248.557796) (xy 377.734576 -248.602246)
			(xy 377.781566 -248.754646) (xy 378.043186 -248.754646)
		)
		(stroke
			(width 0)
			(type solid)
		)
		(fill yes)
		(layer "In11.Cu")
		(net "M_H_CPU0_SB_CA<0>")
	)
	(gr_poly
		(pts
			(xy 378.090176 -244.126766) (xy 378.043186 -243.974366) (xy 377.781566 -243.974366) (xy 377.734576 -244.126766)
			(xy 377.734576 -244.171216) (xy 378.090176 -244.171216)
		)
		(stroke
			(width 0)
			(type solid)
		)
		(fill yes)
		(layer "In11.Cu")
		(net "M_H_CPU0_SB_CB<4>")
	)
	(gr_poly
		(pts
			(xy 378.090176 -243.718842) (xy 378.090176 -243.674392) (xy 377.734576 -243.674392) (xy 377.734576 -243.718842)
			(xy 377.781566 -243.871242) (xy 378.043186 -243.871242)
		)
		(stroke
			(width 0)
			(type solid)
		)
		(fill yes)
		(layer "In11.Cu")
		(net "M_H_CPU0_SB_CB<7>")
	)
	(gr_poly
		(pts
			(xy 378.090176 -239.243362) (xy 378.043186 -239.090962) (xy 377.781566 -239.090962) (xy 377.734576 -239.243362)
			(xy 377.734576 -239.287812) (xy 378.090176 -239.287812)
		)
		(stroke
			(width 0)
			(type solid)
		)
		(fill yes)
		(layer "In11.Cu")
		(net "M_H_CPU0_SB_DQ<2>")
	)
	(gr_poly
		(pts
			(xy 378.090176 -238.835438) (xy 378.090176 -238.790988) (xy 377.734576 -238.790988) (xy 377.734576 -238.835438)
			(xy 377.781566 -238.987838) (xy 378.043186 -238.987838)
		)
		(stroke
			(width 0)
			(type solid)
		)
		(fill yes)
		(layer "In11.Cu")
		(net "M_H_CPU0_SB_DQ<1>")
	)
	(gr_poly
		(pts
			(xy 378.090176 -234.360466) (xy 378.043186 -234.208066) (xy 377.781566 -234.208066) (xy 377.734576 -234.360466)
			(xy 377.734576 -234.404662) (xy 378.090176 -234.404662)
		)
		(stroke
			(width 0)
			(type solid)
		)
		(fill yes)
		(layer "In11.Cu")
		(net "M_H_CPU0_SB_DQ<10>")
	)
	(gr_poly
		(pts
			(xy 378.090176 -233.952034) (xy 378.090176 -233.907838) (xy 377.734576 -233.907838) (xy 377.734576 -233.952034)
			(xy 377.781566 -234.104434) (xy 378.043186 -234.104434)
		)
		(stroke
			(width 0)
			(type solid)
		)
		(fill yes)
		(layer "In11.Cu")
		(net "M_H_CPU0_SB_DQ<9>")
	)
	(gr_poly
		(pts
			(xy 378.090176 -229.477062) (xy 378.043186 -229.324662) (xy 377.781566 -229.324662) (xy 377.734576 -229.477062)
			(xy 377.734576 -229.521258) (xy 378.090176 -229.521258)
		)
		(stroke
			(width 0)
			(type solid)
		)
		(fill yes)
		(layer "In11.Cu")
		(net "M_H_CPU0_SB_DQ<24>")
	)
	(gr_poly
		(pts
			(xy 378.090176 -229.06863) (xy 378.090176 -229.024434) (xy 377.734576 -229.024434) (xy 377.734576 -229.06863)
			(xy 377.781566 -229.22103) (xy 378.043186 -229.22103)
		)
		(stroke
			(width 0)
			(type solid)
		)
		(fill yes)
		(layer "In11.Cu")
		(net "M_H_CPU0_SB_DQ<27>")
	)
	(gr_poly
		(pts
			(xy 378.092716 -247.382538) (xy 378.045726 -247.230138) (xy 377.784106 -247.230138) (xy 377.737116 -247.382538)
			(xy 377.737116 -247.426734) (xy 378.092716 -247.426734)
		)
		(stroke
			(width 0)
			(type solid)
		)
		(fill yes)
		(layer "In11.Cu")
		(net "M_H_CPU0_SB_CA<3>")
	)
	(gr_poly
		(pts
			(xy 378.092716 -246.974106) (xy 378.092716 -246.92991) (xy 377.737116 -246.92991) (xy 377.737116 -246.974106)
			(xy 377.784106 -247.126506) (xy 378.045726 -247.126506)
		)
		(stroke
			(width 0)
			(type solid)
		)
		(fill yes)
		(layer "In11.Cu")
		(net "M_H_CPU0_SB_CA<4>")
	)
	(gr_poly
		(pts
			(xy 378.092716 -245.754906) (xy 378.045726 -245.602506) (xy 377.784106 -245.602506) (xy 377.737116 -245.754906)
			(xy 377.737116 -245.799102) (xy 378.092716 -245.799102)
		)
		(stroke
			(width 0)
			(type solid)
		)
		(fill yes)
		(layer "In11.Cu")
		(net "M_H_CPU0_SB_PAR")
	)
	(gr_poly
		(pts
			(xy 378.092716 -242.499134) (xy 378.045726 -242.346734) (xy 377.784106 -242.346734) (xy 377.737116 -242.499134)
			(xy 377.737116 -242.54333) (xy 378.092716 -242.54333)
		)
		(stroke
			(width 0)
			(type solid)
		)
		(fill yes)
		(layer "In11.Cu")
		(net "M_H_CPU0_SB_DQS_DN<9>")
	)
	(gr_poly
		(pts
			(xy 378.092716 -242.090702) (xy 378.092716 -242.046506) (xy 377.737116 -242.046506) (xy 377.737116 -242.090702)
			(xy 377.784106 -242.243102) (xy 378.045726 -242.243102)
		)
		(stroke
			(width 0)
			(type solid)
		)
		(fill yes)
		(layer "In11.Cu")
		(net "M_H_CPU0_SB_DQS_DN<4>")
	)
	(gr_poly
		(pts
			(xy 378.092716 -240.871502) (xy 378.045726 -240.719102) (xy 377.784106 -240.719102) (xy 377.737116 -240.871502)
			(xy 377.737116 -240.915698) (xy 378.092716 -240.915698)
		)
		(stroke
			(width 0)
			(type solid)
		)
		(fill yes)
		(layer "In11.Cu")
		(net "M_H_CPU0_SB_CB<2>")
	)
	(gr_poly
		(pts
			(xy 378.092716 -240.46307) (xy 378.092716 -240.418874) (xy 377.737116 -240.418874) (xy 377.737116 -240.46307)
			(xy 377.784106 -240.61547) (xy 378.045726 -240.61547)
		)
		(stroke
			(width 0)
			(type solid)
		)
		(fill yes)
		(layer "In11.Cu")
		(net "M_H_CPU0_SB_CB<1>")
	)
	(gr_poly
		(pts
			(xy 378.092716 -237.61573) (xy 378.045726 -237.46333) (xy 377.784106 -237.46333) (xy 377.737116 -237.61573)
			(xy 377.737116 -237.66018) (xy 378.092716 -237.66018)
		)
		(stroke
			(width 0)
			(type solid)
		)
		(fill yes)
		(layer "In11.Cu")
		(net "M_H_CPU0_SB_DQS_DN<0>")
	)
	(gr_poly
		(pts
			(xy 378.092716 -237.207806) (xy 378.092716 -237.163356) (xy 377.737116 -237.163356) (xy 377.737116 -237.207806)
			(xy 377.784106 -237.360206) (xy 378.045726 -237.360206)
		)
		(stroke
			(width 0)
			(type solid)
		)
		(fill yes)
		(layer "In11.Cu")
		(net "M_H_CPU0_SB_DQS_DN<5>")
	)
	(gr_poly
		(pts
			(xy 378.092716 -235.988098) (xy 378.045726 -235.835698) (xy 377.784106 -235.835698) (xy 377.737116 -235.988098)
			(xy 377.737116 -236.032294) (xy 378.092716 -236.032294)
		)
		(stroke
			(width 0)
			(type solid)
		)
		(fill yes)
		(layer "In11.Cu")
		(net "M_H_CPU0_SB_DQ<6>")
	)
	(gr_poly
		(pts
			(xy 378.092716 -235.579666) (xy 378.092716 -235.53547) (xy 377.737116 -235.53547) (xy 377.737116 -235.579666)
			(xy 377.784106 -235.732066) (xy 378.045726 -235.732066)
		)
		(stroke
			(width 0)
			(type solid)
		)
		(fill yes)
		(layer "In11.Cu")
		(net "M_H_CPU0_SB_DQ<5>")
	)
	(gr_poly
		(pts
			(xy 378.092716 -232.732326) (xy 378.045726 -232.579926) (xy 377.784106 -232.579926) (xy 377.737116 -232.732326)
			(xy 377.737116 -232.776776) (xy 378.092716 -232.776776)
		)
		(stroke
			(width 0)
			(type solid)
		)
		(fill yes)
		(layer "In11.Cu")
		(net "M_H_CPU0_SB_DQS_DN<1>")
	)
	(gr_poly
		(pts
			(xy 378.092716 -232.324402) (xy 378.092716 -232.279952) (xy 377.737116 -232.279952) (xy 377.737116 -232.324402)
			(xy 377.784106 -232.476802) (xy 378.045726 -232.476802)
		)
		(stroke
			(width 0)
			(type solid)
		)
		(fill yes)
		(layer "In11.Cu")
		(net "M_H_CPU0_SB_DQS_DN<6>")
	)
	(gr_poly
		(pts
			(xy 378.092716 -231.104694) (xy 378.045726 -230.952294) (xy 377.784106 -230.952294) (xy 377.737116 -231.104694)
			(xy 377.737116 -231.14889) (xy 378.092716 -231.14889)
		)
		(stroke
			(width 0)
			(type solid)
		)
		(fill yes)
		(layer "In11.Cu")
		(net "M_H_CPU0_SB_DQ<14>")
	)
	(gr_poly
		(pts
			(xy 378.092716 -230.696262) (xy 378.092716 -230.652066) (xy 377.737116 -230.652066) (xy 377.737116 -230.696262)
			(xy 377.784106 -230.848662) (xy 378.045726 -230.848662)
		)
		(stroke
			(width 0)
			(type solid)
		)
		(fill yes)
		(layer "In11.Cu")
		(net "M_H_CPU0_SB_DQ<13>")
	)
	(gr_poly
		(pts
			(xy 378.092716 -227.848922) (xy 378.045726 -227.696522) (xy 377.784106 -227.696522) (xy 377.737116 -227.848922)
			(xy 377.737116 -227.893372) (xy 378.092716 -227.893372)
		)
		(stroke
			(width 0)
			(type solid)
		)
		(fill yes)
		(layer "In11.Cu")
		(net "M_H_CPU0_SB_DQS_DP<8>")
	)
	(gr_poly
		(pts
			(xy 378.092716 -227.440998) (xy 378.092716 -227.396548) (xy 377.737116 -227.396548) (xy 377.737116 -227.440998)
			(xy 377.784106 -227.593398) (xy 378.045726 -227.593398)
		)
		(stroke
			(width 0)
			(type solid)
		)
		(fill yes)
		(layer "In11.Cu")
		(net "M_H_CPU0_SB_DQS_DP<3>")
	)
	(gr_poly
		(pts
			(xy 378.092716 -226.22129) (xy 378.045726 -226.06889) (xy 377.784106 -226.06889) (xy 377.737116 -226.22129)
			(xy 377.737116 -226.26574) (xy 378.092716 -226.26574)
		)
		(stroke
			(width 0)
			(type solid)
		)
		(fill yes)
		(layer "In11.Cu")
		(net "M_H_CPU0_SB_DQ<28>")
	)
	(gr_poly
		(pts
			(xy 378.092716 -225.813366) (xy 378.092716 -225.768916) (xy 377.737116 -225.768916) (xy 377.737116 -225.813366)
			(xy 377.784106 -225.965766) (xy 378.045726 -225.965766)
		)
		(stroke
			(width 0)
			(type solid)
		)
		(fill yes)
		(layer "In11.Cu")
		(net "M_H_CPU0_SB_DQ<31>")
	)
	(gr_poly
		(pts
			(xy 378.165106 -276.560788) (xy 378.273564 -276.443948) (xy 378.142754 -276.21738) (xy 377.987306 -276.25294)
			(xy 377.948952 -276.275038) (xy 378.126752 -276.582886)
		)
		(stroke
			(width 0)
			(type solid)
		)
		(fill yes)
		(layer "In11.Cu")
		(net "M_H_CPU0_SA_DQ<15>")
	)
	(gr_poly
		(pts
			(xy 378.165106 -273.30527) (xy 378.273564 -273.18843) (xy 378.142754 -272.961862) (xy 377.987306 -272.997422)
			(xy 377.948952 -273.01952) (xy 378.126752 -273.327368)
		)
		(stroke
			(width 0)
			(type solid)
		)
		(fill yes)
		(layer "In11.Cu")
		(net "M_H_CPU0_SA_DQ<19>")
	)
	(gr_poly
		(pts
			(xy 378.18822 -278.540718) (xy 378.14123 -278.388318) (xy 377.87961 -278.388318) (xy 377.83262 -278.540718)
			(xy 377.83262 -278.585168) (xy 378.18822 -278.585168)
		)
		(stroke
			(width 0)
			(type solid)
		)
		(fill yes)
		(layer "In11.Cu")
		(net "M_H_CPU0_SA_DQS_DP<6>")
	)
	(gr_poly
		(pts
			(xy 378.18822 -278.132032) (xy 378.18822 -278.087836) (xy 377.83262 -278.087836) (xy 377.83262 -278.132032)
			(xy 377.87961 -278.284432) (xy 378.14123 -278.284432)
		)
		(stroke
			(width 0)
			(type solid)
		)
		(fill yes)
		(layer "In11.Cu")
		(net "M_H_CPU0_SA_DQ<12>")
	)
	(gr_poly
		(pts
			(xy 378.194316 -279.759664) (xy 378.194316 -279.715468) (xy 377.838716 -279.715468) (xy 377.838716 -279.759664)
			(xy 377.885706 -279.912064) (xy 378.147326 -279.912064)
		)
		(stroke
			(width 0)
			(type solid)
		)
		(fill yes)
		(layer "In11.Cu")
		(net "M_H_CPU0_SA_DQS_DP<1>")
	)
	(gr_poly
		(pts
			(xy 378.200158 -263.890506) (xy 378.153168 -263.738106) (xy 377.891548 -263.738106) (xy 377.844558 -263.890506)
			(xy 377.844558 -263.934956) (xy 378.200158 -263.934956)
		)
		(stroke
			(width 0)
			(type solid)
		)
		(fill yes)
		(layer "In11.Cu")
		(net "M_H_CPU0_SA_DQ<30>")
	)
	(gr_poly
		(pts
			(xy 378.200158 -263.482582) (xy 378.200158 -263.438132) (xy 377.844558 -263.438132) (xy 377.844558 -263.482582)
			(xy 377.891548 -263.634982) (xy 378.153168 -263.634982)
		)
		(stroke
			(width 0)
			(type solid)
		)
		(fill yes)
		(layer "In11.Cu")
		(net "M_H_CPU0_SA_DQ<29>")
	)
	(gr_poly
		(pts
			(xy 378.200158 -259.007102) (xy 378.153168 -258.854702) (xy 377.891548 -258.854702) (xy 377.844558 -259.007102)
			(xy 377.844558 -259.051552) (xy 378.200158 -259.051552)
		)
		(stroke
			(width 0)
			(type solid)
		)
		(fill yes)
		(layer "In11.Cu")
		(net "M_H_CPU0_SA_CB<6>")
	)
	(gr_poly
		(pts
			(xy 378.200158 -258.599178) (xy 378.200158 -258.554728) (xy 377.844558 -258.554728) (xy 377.844558 -258.599178)
			(xy 377.891548 -258.751578) (xy 378.153168 -258.751578)
		)
		(stroke
			(width 0)
			(type solid)
		)
		(fill yes)
		(layer "In11.Cu")
		(net "M_H_CPU0_SA_CB<5>")
	)
	(gr_poly
		(pts
			(xy 378.200158 -254.123698) (xy 378.153168 -253.971298) (xy 377.891548 -253.971298) (xy 377.844558 -254.123698)
			(xy 377.844558 -254.168148) (xy 378.200158 -254.168148)
		)
		(stroke
			(width 0)
			(type solid)
		)
		(fill yes)
		(layer "In11.Cu")
		(net "M_H_CPU0_SA_CA<3>")
	)
	(gr_poly
		(pts
			(xy 378.202698 -281.387804) (xy 378.202698 -281.343608) (xy 377.847098 -281.343608) (xy 377.847098 -281.387804)
			(xy 377.894088 -281.540204) (xy 378.155708 -281.540204)
		)
		(stroke
			(width 0)
			(type solid)
		)
		(fill yes)
		(layer "In11.Cu")
		(net "M_H_CPU0_SA_DQ<8>")
	)
	(gr_poly
		(pts
			(xy 378.202698 -280.168096) (xy 378.155708 -280.015696) (xy 377.894088 -280.015696) (xy 377.847098 -280.168096)
			(xy 377.847098 -280.212546) (xy 378.202698 -280.212546)
		)
		(stroke
			(width 0)
			(type solid)
		)
		(fill yes)
		(layer "In11.Cu")
		(net "M_H_CPU0_SA_DQ<11>")
	)
	(gr_poly
		(pts
			(xy 378.202698 -275.284946) (xy 378.155708 -275.132546) (xy 377.894088 -275.132546) (xy 377.847098 -275.284946)
			(xy 377.847098 -275.329142) (xy 378.202698 -275.329142)
		)
		(stroke
			(width 0)
			(type solid)
		)
		(fill yes)
		(layer "In11.Cu")
		(net "M_H_CPU0_SA_DQ<18>")
	)
	(gr_poly
		(pts
			(xy 378.202698 -270.401542) (xy 378.155708 -270.249142) (xy 377.894088 -270.249142) (xy 377.847098 -270.401542)
			(xy 377.847098 -270.445992) (xy 378.202698 -270.445992)
		)
		(stroke
			(width 0)
			(type solid)
		)
		(fill yes)
		(layer "In11.Cu")
		(net "M_H_CPU0_SA_DQS_DP<7>")
	)
	(gr_poly
		(pts
			(xy 378.202698 -268.77391) (xy 378.155708 -268.62151) (xy 377.894088 -268.62151) (xy 377.847098 -268.77391)
			(xy 377.847098 -268.818106) (xy 378.202698 -268.818106)
		)
		(stroke
			(width 0)
			(type solid)
		)
		(fill yes)
		(layer "In11.Cu")
		(net "M_H_CPU0_SA_DQ<22>")
	)
	(gr_poly
		(pts
			(xy 378.202698 -268.365478) (xy 378.202698 -268.321282) (xy 377.847098 -268.321282) (xy 377.847098 -268.365478)
			(xy 377.894088 -268.517878) (xy 378.155708 -268.517878)
		)
		(stroke
			(width 0)
			(type solid)
		)
		(fill yes)
		(layer "In11.Cu")
		(net "M_H_CPU0_SA_DQ<21>")
	)
	(gr_poly
		(pts
			(xy 378.202698 -267.14577) (xy 378.155708 -266.99337) (xy 377.894088 -266.99337) (xy 377.847098 -267.14577)
			(xy 377.847098 -267.19022) (xy 378.202698 -267.19022)
		)
		(stroke
			(width 0)
			(type solid)
		)
		(fill yes)
		(layer "In11.Cu")
		(net "M_H_CPU0_SA_DQ<26>")
	)
	(gr_poly
		(pts
			(xy 378.202698 -266.737846) (xy 378.202698 -266.69365) (xy 377.847098 -266.69365) (xy 377.847098 -266.737846)
			(xy 377.894088 -266.890246) (xy 378.155708 -266.890246)
		)
		(stroke
			(width 0)
			(type solid)
		)
		(fill yes)
		(layer "In11.Cu")
		(net "M_H_CPU0_SA_DQ<25>")
	)
	(gr_poly
		(pts
			(xy 378.202698 -265.518138) (xy 378.155708 -265.365738) (xy 377.894088 -265.365738) (xy 377.847098 -265.518138)
			(xy 377.847098 -265.562588) (xy 378.202698 -265.562588)
		)
		(stroke
			(width 0)
			(type solid)
		)
		(fill yes)
		(layer "In11.Cu")
		(net "M_H_CPU0_SA_DQS_DN<3>")
	)
	(gr_poly
		(pts
			(xy 378.202698 -265.110214) (xy 378.202698 -265.065764) (xy 377.847098 -265.065764) (xy 377.847098 -265.110214)
			(xy 377.894088 -265.262614) (xy 378.155708 -265.262614)
		)
		(stroke
			(width 0)
			(type solid)
		)
		(fill yes)
		(layer "In11.Cu")
		(net "M_H_CPU0_SA_DQS_DN<8>")
	)
	(gr_poly
		(pts
			(xy 378.202698 -262.262874) (xy 378.155708 -262.110474) (xy 377.894088 -262.110474) (xy 377.847098 -262.262874)
			(xy 377.847098 -262.30707) (xy 378.202698 -262.30707)
		)
		(stroke
			(width 0)
			(type solid)
		)
		(fill yes)
		(layer "In11.Cu")
		(net "M_H_CPU0_SA_CB<2>")
	)
	(gr_poly
		(pts
			(xy 378.202698 -261.854442) (xy 378.202698 -261.810246) (xy 377.847098 -261.810246) (xy 377.847098 -261.854442)
			(xy 377.894088 -262.006842) (xy 378.155708 -262.006842)
		)
		(stroke
			(width 0)
			(type solid)
		)
		(fill yes)
		(layer "In11.Cu")
		(net "M_H_CPU0_SA_CB<1>")
	)
	(gr_poly
		(pts
			(xy 378.202698 -260.634734) (xy 378.155708 -260.482334) (xy 377.894088 -260.482334) (xy 377.847098 -260.634734)
			(xy 377.847098 -260.679184) (xy 378.202698 -260.679184)
		)
		(stroke
			(width 0)
			(type solid)
		)
		(fill yes)
		(layer "In11.Cu")
		(net "M_H_CPU0_SA_DQS_DN<4>")
	)
	(gr_poly
		(pts
			(xy 378.202698 -260.22681) (xy 378.202698 -260.18236) (xy 377.847098 -260.18236) (xy 377.847098 -260.22681)
			(xy 377.894088 -260.37921) (xy 378.155708 -260.37921)
		)
		(stroke
			(width 0)
			(type solid)
		)
		(fill yes)
		(layer "In11.Cu")
		(net "M_H_CPU0_SA_DQS_DN<9>")
	)
	(gr_poly
		(pts
			(xy 378.202698 -257.37947) (xy 378.155708 -257.22707) (xy 377.894088 -257.22707) (xy 377.847098 -257.37947)
			(xy 377.847098 -257.423666) (xy 378.202698 -257.423666)
		)
		(stroke
			(width 0)
			(type solid)
		)
		(fill yes)
		(layer "In11.Cu")
		(net "M_H_CPU0_ALERT_N")
	)
	(gr_poly
		(pts
			(xy 378.202698 -256.971038) (xy 378.202698 -256.926842) (xy 377.847098 -256.926842) (xy 377.847098 -256.971038)
			(xy 377.894088 -257.123438) (xy 378.155708 -257.123438)
		)
		(stroke
			(width 0)
			(type solid)
		)
		(fill yes)
		(layer "In11.Cu")
		(net "M_H_CPU0_SA_CS_N<0>")
	)
	(gr_poly
		(pts
			(xy 378.202698 -255.751838) (xy 378.155708 -255.599438) (xy 377.894088 -255.599438) (xy 377.847098 -255.751838)
			(xy 377.847098 -255.796034) (xy 378.202698 -255.796034)
		)
		(stroke
			(width 0)
			(type solid)
		)
		(fill yes)
		(layer "In11.Cu")
		(net "M_H_CPU0_SA_CS_N<3>")
	)
	(gr_poly
		(pts
			(xy 378.202698 -255.343406) (xy 378.202698 -255.29921) (xy 377.847098 -255.29921) (xy 377.847098 -255.343406)
			(xy 377.894088 -255.495806) (xy 378.155708 -255.495806)
		)
		(stroke
			(width 0)
			(type solid)
		)
		(fill yes)
		(layer "In11.Cu")
		(net "M_H_CPU0_SA_CA<1>")
	)
	(gr_poly
		(pts
			(xy 378.515372 -274.72259) (xy 378.553726 -274.700492) (xy 378.375926 -274.392644) (xy 378.337572 -274.414742)
			(xy 378.229114 -274.531582) (xy 378.359924 -274.75815)
		)
		(stroke
			(width 0)
			(type solid)
		)
		(fill yes)
		(layer "In11.Cu")
		(net "M_H_CPU0_SA_DQ<17>")
	)
	(gr_poly
		(pts
			(xy 378.515372 -273.094958) (xy 378.553726 -273.07286) (xy 378.375926 -272.765012) (xy 378.337572 -272.78711)
			(xy 378.229114 -272.90395) (xy 378.359924 -273.130518)
		)
		(stroke
			(width 0)
			(type solid)
		)
		(fill yes)
		(layer "In11.Cu")
		(net "M_H_CPU0_SA_DQS_DP<2>")
	)
	(gr_poly
		(pts
			(xy 378.515372 -271.467072) (xy 378.553726 -271.444974) (xy 378.375926 -271.137126) (xy 378.337572 -271.159224)
			(xy 378.229114 -271.276064) (xy 378.359924 -271.502632)
		)
		(stroke
			(width 0)
			(type solid)
		)
		(fill yes)
		(layer "In11.Cu")
		(net "M_H_CPU0_SA_DQS_DN<7>")
	)
	(gr_poly
		(pts
			(xy 378.520706 -269.84833) (xy 378.55906 -269.826232) (xy 378.38126 -269.518384) (xy 378.342906 -269.540482)
			(xy 378.234448 -269.657322) (xy 378.365258 -269.88389)
		)
		(stroke
			(width 0)
			(type solid)
		)
		(fill yes)
		(layer "In11.Cu")
		(net "M_H_CPU0_SA_DQ<20>")
	)
	(gr_poly
		(pts
			(xy 378.545598 -246.568722) (xy 378.498608 -246.416322) (xy 378.236988 -246.416322) (xy 378.189998 -246.568722)
			(xy 378.189998 -246.612918) (xy 378.545598 -246.612918)
		)
		(stroke
			(width 0)
			(type solid)
		)
		(fill yes)
		(layer "In11.Cu")
		(net "M_H_CPU0_SB_CA<5>")
	)
	(gr_poly
		(pts
			(xy 378.545598 -246.16029) (xy 378.545598 -246.116094) (xy 378.189998 -246.116094) (xy 378.189998 -246.16029)
			(xy 378.236988 -246.31269) (xy 378.498608 -246.31269)
		)
		(stroke
			(width 0)
			(type solid)
		)
		(fill yes)
		(layer "In11.Cu")
		(net "M_H_CPU0_SB_CA<6>")
	)
	(gr_poly
		(pts
			(xy 378.545598 -244.532658) (xy 378.545598 -244.488208) (xy 378.189998 -244.488208) (xy 378.189998 -244.532658)
			(xy 378.236988 -244.685058) (xy 378.498608 -244.685058)
		)
		(stroke
			(width 0)
			(type solid)
		)
		(fill yes)
		(layer "In11.Cu")
		(net "M_H_CPU0_SB_CB<6>")
	)
	(gr_poly
		(pts
			(xy 378.545598 -243.31295) (xy 378.498608 -243.16055) (xy 378.236988 -243.16055) (xy 378.189998 -243.31295)
			(xy 378.189998 -243.3574) (xy 378.545598 -243.3574)
		)
		(stroke
			(width 0)
			(type solid)
		)
		(fill yes)
		(layer "In11.Cu")
		(net "M_H_CPU0_SB_CB<5>")
	)
	(gr_poly
		(pts
			(xy 378.545598 -242.905026) (xy 378.545598 -242.860576) (xy 378.189998 -242.860576) (xy 378.189998 -242.905026)
			(xy 378.236988 -243.057426) (xy 378.498608 -243.057426)
		)
		(stroke
			(width 0)
			(type solid)
		)
		(fill yes)
		(layer "In11.Cu")
		(net "M_H_CPU0_SB_DQS_DP<9>")
	)
	(gr_poly
		(pts
			(xy 378.545598 -241.276886) (xy 378.545598 -241.23269) (xy 378.189998 -241.23269) (xy 378.189998 -241.276886)
			(xy 378.236988 -241.429286) (xy 378.498608 -241.429286)
		)
		(stroke
			(width 0)
			(type solid)
		)
		(fill yes)
		(layer "In11.Cu")
		(net "M_H_CPU0_SB_CB<0>")
	)
	(gr_poly
		(pts
			(xy 378.545598 -240.057178) (xy 378.498608 -239.904778) (xy 378.236988 -239.904778) (xy 378.189998 -240.057178)
			(xy 378.189998 -240.101628) (xy 378.545598 -240.101628)
		)
		(stroke
			(width 0)
			(type solid)
		)
		(fill yes)
		(layer "In11.Cu")
		(net "M_H_CPU0_SB_CB<3>")
	)
	(gr_poly
		(pts
			(xy 378.545598 -239.649254) (xy 378.545598 -239.604804) (xy 378.189998 -239.604804) (xy 378.189998 -239.649254)
			(xy 378.236988 -239.801654) (xy 378.498608 -239.801654)
		)
		(stroke
			(width 0)
			(type solid)
		)
		(fill yes)
		(layer "In11.Cu")
		(net "M_H_CPU0_SB_DQ<0>")
	)
	(gr_poly
		(pts
			(xy 378.545598 -238.429546) (xy 378.498608 -238.277146) (xy 378.236988 -238.277146) (xy 378.189998 -238.429546)
			(xy 378.189998 -238.473996) (xy 378.545598 -238.473996)
		)
		(stroke
			(width 0)
			(type solid)
		)
		(fill yes)
		(layer "In11.Cu")
		(net "M_H_CPU0_SB_DQ<3>")
	)
	(gr_poly
		(pts
			(xy 378.545598 -238.021622) (xy 378.545598 -237.977172) (xy 378.189998 -237.977172) (xy 378.189998 -238.021622)
			(xy 378.236988 -238.174022) (xy 378.498608 -238.174022)
		)
		(stroke
			(width 0)
			(type solid)
		)
		(fill yes)
		(layer "In11.Cu")
		(net "M_H_CPU0_SB_DQS_DP<0>")
	)
	(gr_poly
		(pts
			(xy 378.545598 -236.39399) (xy 378.545598 -236.34954) (xy 378.189998 -236.34954) (xy 378.189998 -236.39399)
			(xy 378.236988 -236.54639) (xy 378.498608 -236.54639)
		)
		(stroke
			(width 0)
			(type solid)
		)
		(fill yes)
		(layer "In11.Cu")
		(net "M_H_CPU0_SB_DQ<4>")
	)
	(gr_poly
		(pts
			(xy 378.545598 -235.174282) (xy 378.498608 -235.021882) (xy 378.236988 -235.021882) (xy 378.189998 -235.174282)
			(xy 378.189998 -235.218478) (xy 378.545598 -235.218478)
		)
		(stroke
			(width 0)
			(type solid)
		)
		(fill yes)
		(layer "In11.Cu")
		(net "M_H_CPU0_SB_DQ<7>")
	)
	(gr_poly
		(pts
			(xy 378.545598 -234.76585) (xy 378.545598 -234.721654) (xy 378.189998 -234.721654) (xy 378.189998 -234.76585)
			(xy 378.236988 -234.91825) (xy 378.498608 -234.91825)
		)
		(stroke
			(width 0)
			(type solid)
		)
		(fill yes)
		(layer "In11.Cu")
		(net "M_H_CPU0_SB_DQ<8>")
	)
	(gr_poly
		(pts
			(xy 378.545598 -233.138218) (xy 378.545598 -233.093768) (xy 378.189998 -233.093768) (xy 378.189998 -233.138218)
			(xy 378.236988 -233.290618) (xy 378.498608 -233.290618)
		)
		(stroke
			(width 0)
			(type solid)
		)
		(fill yes)
		(layer "In11.Cu")
		(net "M_H_CPU0_SB_DQS_DP<1>")
	)
	(gr_poly
		(pts
			(xy 378.545598 -231.510586) (xy 378.545598 -231.466136) (xy 378.189998 -231.466136) (xy 378.189998 -231.510586)
			(xy 378.236988 -231.662986) (xy 378.498608 -231.662986)
		)
		(stroke
			(width 0)
			(type solid)
		)
		(fill yes)
		(layer "In11.Cu")
		(net "M_H_CPU0_SB_DQ<12>")
	)
	(gr_poly
		(pts
			(xy 378.545598 -230.290878) (xy 378.498608 -230.138478) (xy 378.236988 -230.138478) (xy 378.189998 -230.290878)
			(xy 378.189998 -230.335074) (xy 378.545598 -230.335074)
		)
		(stroke
			(width 0)
			(type solid)
		)
		(fill yes)
		(layer "In11.Cu")
		(net "M_H_CPU0_SB_DQ<15>")
	)
	(gr_poly
		(pts
			(xy 378.545598 -229.882446) (xy 378.545598 -229.83825) (xy 378.189998 -229.83825) (xy 378.189998 -229.882446)
			(xy 378.236988 -230.034846) (xy 378.498608 -230.034846)
		)
		(stroke
			(width 0)
			(type solid)
		)
		(fill yes)
		(layer "In11.Cu")
		(net "M_H_CPU0_SB_DQ<26>")
	)
	(gr_poly
		(pts
			(xy 378.545598 -228.663246) (xy 378.498608 -228.510846) (xy 378.236988 -228.510846) (xy 378.189998 -228.663246)
			(xy 378.189998 -228.707442) (xy 378.545598 -228.707442)
		)
		(stroke
			(width 0)
			(type solid)
		)
		(fill yes)
		(layer "In11.Cu")
		(net "M_H_CPU0_SB_DQ<25>")
	)
	(gr_poly
		(pts
			(xy 378.545598 -228.254814) (xy 378.545598 -228.210618) (xy 378.189998 -228.210618) (xy 378.189998 -228.254814)
			(xy 378.236988 -228.407214) (xy 378.498608 -228.407214)
		)
		(stroke
			(width 0)
			(type solid)
		)
		(fill yes)
		(layer "In11.Cu")
		(net "M_H_CPU0_SB_DQS_DN<8>")
	)
	(gr_poly
		(pts
			(xy 378.545598 -225.407474) (xy 378.498608 -225.255074) (xy 378.236988 -225.255074) (xy 378.189998 -225.407474)
			(xy 378.189998 -225.45167) (xy 378.545598 -225.45167)
		)
		(stroke
			(width 0)
			(type solid)
		)
		(fill yes)
		(layer "In11.Cu")
		(net "M_H_CPU0_SB_DQ<29>")
	)
	(gr_poly
		(pts
			(xy 378.545852 -233.546142) (xy 378.498862 -233.393742) (xy 378.237242 -233.393742) (xy 378.190252 -233.546142)
			(xy 378.190252 -233.590592) (xy 378.545852 -233.590592)
		)
		(stroke
			(width 0)
			(type solid)
		)
		(fill yes)
		(layer "In11.Cu")
		(net "M_H_CPU0_SB_DQ<11>")
	)
	(gr_poly
		(pts
			(xy 378.548138 -248.196354) (xy 378.501148 -248.043954) (xy 378.239528 -248.043954) (xy 378.192538 -248.196354)
			(xy 378.192538 -248.24055) (xy 378.548138 -248.24055)
		)
		(stroke
			(width 0)
			(type solid)
		)
		(fill yes)
		(layer "In11.Cu")
		(net "M_H_CPU0_SB_CA<1>")
	)
	(gr_poly
		(pts
			(xy 378.548138 -247.787922) (xy 378.548138 -247.743726) (xy 378.192538 -247.743726) (xy 378.192538 -247.787922)
			(xy 378.239528 -247.940322) (xy 378.501148 -247.940322)
		)
		(stroke
			(width 0)
			(type solid)
		)
		(fill yes)
		(layer "In11.Cu")
		(net "M_H_CPU0_SB_CA<2>")
	)
	(gr_poly
		(pts
			(xy 378.548138 -227.035106) (xy 378.501148 -226.882706) (xy 378.239528 -226.882706) (xy 378.192538 -227.035106)
			(xy 378.192538 -227.079556) (xy 378.548138 -227.079556)
		)
		(stroke
			(width 0)
			(type solid)
		)
		(fill yes)
		(layer "In11.Cu")
		(net "M_H_CPU0_SB_DQS_DN<3>")
	)
	(gr_poly
		(pts
			(xy 378.548138 -226.627182) (xy 378.548138 -226.582732) (xy 378.192538 -226.582732) (xy 378.192538 -226.627182)
			(xy 378.239528 -226.779582) (xy 378.501148 -226.779582)
		)
		(stroke
			(width 0)
			(type solid)
		)
		(fill yes)
		(layer "In11.Cu")
		(net "M_H_CPU0_SB_DQ<30>")
	)
	(gr_poly
		(pts
			(xy 378.554488 -241.685826) (xy 378.507498 -241.533426) (xy 378.245878 -241.533426) (xy 378.198888 -241.685826)
			(xy 378.198888 -241.730022) (xy 378.554488 -241.730022)
		)
		(stroke
			(width 0)
			(type solid)
		)
		(fill yes)
		(layer "In11.Cu")
		(net "M_H_CPU0_SB_DQS_DP<4>")
	)
	(gr_poly
		(pts
			(xy 378.554488 -236.802422) (xy 378.507498 -236.650022) (xy 378.245878 -236.650022) (xy 378.198888 -236.802422)
			(xy 378.198888 -236.846872) (xy 378.554488 -236.846872)
		)
		(stroke
			(width 0)
			(type solid)
		)
		(fill yes)
		(layer "In11.Cu")
		(net "M_H_CPU0_SB_DQS_DP<5>")
	)
	(gr_poly
		(pts
			(xy 378.554488 -231.919018) (xy 378.507498 -231.766618) (xy 378.245878 -231.766618) (xy 378.198888 -231.919018)
			(xy 378.198888 -231.963468) (xy 378.554488 -231.963468)
		)
		(stroke
			(width 0)
			(type solid)
		)
		(fill yes)
		(layer "In11.Cu")
		(net "M_H_CPU0_SB_DQS_DP<6>")
	)
	(gr_poly
		(pts
			(xy 378.62764 -272.480278) (xy 378.736098 -272.363438) (xy 378.605288 -272.13687) (xy 378.44984 -272.17243)
			(xy 378.411486 -272.194528) (xy 378.589286 -272.502376)
		)
		(stroke
			(width 0)
			(type solid)
		)
		(fill yes)
		(layer "In11.Cu")
		(net "M_H_CPU0_SA_DQS_DN<2>")
	)
	(gr_poly
		(pts
			(xy 378.629418 -274.109434) (xy 378.737876 -273.992594) (xy 378.607066 -273.766026) (xy 378.451618 -273.801586)
			(xy 378.413264 -273.823684) (xy 378.591064 -274.131532)
		)
		(stroke
			(width 0)
			(type solid)
		)
		(fill yes)
		(layer "In11.Cu")
		(net "M_H_CPU0_SA_DQ<19>")
	)
	(gr_poly
		(pts
			(xy 378.629418 -270.853916) (xy 378.737876 -270.737076) (xy 378.607066 -270.510508) (xy 378.451618 -270.546068)
			(xy 378.413264 -270.568166) (xy 378.591064 -270.876014)
		)
		(stroke
			(width 0)
			(type solid)
		)
		(fill yes)
		(layer "In11.Cu")
		(net "M_H_CPU0_SA_DQS_DP<7>")
	)
	(gr_poly
		(pts
			(xy 378.629418 -269.22603) (xy 378.737876 -269.10919) (xy 378.607066 -268.882622) (xy 378.451618 -268.918182)
			(xy 378.413264 -268.94028) (xy 378.591064 -269.248128)
		)
		(stroke
			(width 0)
			(type solid)
		)
		(fill yes)
		(layer "In11.Cu")
		(net "M_H_CPU0_SA_DQ<22>")
	)
	(gr_poly
		(pts
			(xy 378.65558 -280.98242) (xy 378.60859 -280.83002) (xy 378.34697 -280.83002) (xy 378.29998 -280.98242)
			(xy 378.29998 -281.026616) (xy 378.65558 -281.026616)
		)
		(stroke
			(width 0)
			(type solid)
		)
		(fill yes)
		(layer "In11.Cu")
		(net "M_H_CPU0_SA_DQ<10>")
	)
	(gr_poly
		(pts
			(xy 378.65558 -280.574242) (xy 378.65558 -280.529792) (xy 378.29998 -280.529792) (xy 378.29998 -280.574242)
			(xy 378.34697 -280.726642) (xy 378.60859 -280.726642)
		)
		(stroke
			(width 0)
			(type solid)
		)
		(fill yes)
		(layer "In11.Cu")
		(net "M_H_CPU0_SA_DQ<9>")
	)
	(gr_poly
		(pts
			(xy 378.65558 -275.690584) (xy 378.65558 -275.646388) (xy 378.29998 -275.646388) (xy 378.29998 -275.690584)
			(xy 378.34697 -275.842984) (xy 378.60859 -275.842984)
		)
		(stroke
			(width 0)
			(type solid)
		)
		(fill yes)
		(layer "In11.Cu")
		(net "M_H_CPU0_SA_DQ<16>")
	)
	(gr_poly
		(pts
			(xy 378.65558 -267.960094) (xy 378.60859 -267.807694) (xy 378.34697 -267.807694) (xy 378.29998 -267.960094)
			(xy 378.29998 -268.00429) (xy 378.65558 -268.00429)
		)
		(stroke
			(width 0)
			(type solid)
		)
		(fill yes)
		(layer "In11.Cu")
		(net "M_H_CPU0_SA_DQ<23>")
	)
	(gr_poly
		(pts
			(xy 378.65558 -267.551662) (xy 378.65558 -267.507466) (xy 378.29998 -267.507466) (xy 378.29998 -267.551662)
			(xy 378.34697 -267.704062) (xy 378.60859 -267.704062)
		)
		(stroke
			(width 0)
			(type solid)
		)
		(fill yes)
		(layer "In11.Cu")
		(net "M_H_CPU0_SA_DQ<24>")
	)
	(gr_poly
		(pts
			(xy 378.65558 -266.331954) (xy 378.60859 -266.179554) (xy 378.34697 -266.179554) (xy 378.29998 -266.331954)
			(xy 378.29998 -266.376404) (xy 378.65558 -266.376404)
		)
		(stroke
			(width 0)
			(type solid)
		)
		(fill yes)
		(layer "In11.Cu")
		(net "M_H_CPU0_SA_DQ<27>")
	)
	(gr_poly
		(pts
			(xy 378.65558 -265.92403) (xy 378.65558 -265.879834) (xy 378.29998 -265.879834) (xy 378.29998 -265.92403)
			(xy 378.34697 -266.07643) (xy 378.60859 -266.07643)
		)
		(stroke
			(width 0)
			(type solid)
		)
		(fill yes)
		(layer "In11.Cu")
		(net "M_H_CPU0_SA_DQS_DP<3>")
	)
	(gr_poly
		(pts
			(xy 378.65558 -264.704322) (xy 378.60859 -264.551922) (xy 378.34697 -264.551922) (xy 378.29998 -264.704322)
			(xy 378.29998 -264.748772) (xy 378.65558 -264.748772)
		)
		(stroke
			(width 0)
			(type solid)
		)
		(fill yes)
		(layer "In11.Cu")
		(net "M_H_CPU0_SA_DQS_DP<8>")
	)
	(gr_poly
		(pts
			(xy 378.65558 -264.296398) (xy 378.65558 -264.251948) (xy 378.29998 -264.251948) (xy 378.29998 -264.296398)
			(xy 378.34697 -264.448798) (xy 378.60859 -264.448798)
		)
		(stroke
			(width 0)
			(type solid)
		)
		(fill yes)
		(layer "In11.Cu")
		(net "M_H_CPU0_SA_DQ<28>")
	)
	(gr_poly
		(pts
			(xy 378.65558 -263.07669) (xy 378.60859 -262.92429) (xy 378.34697 -262.92429) (xy 378.29998 -263.07669)
			(xy 378.29998 -263.120886) (xy 378.65558 -263.120886)
		)
		(stroke
			(width 0)
			(type solid)
		)
		(fill yes)
		(layer "In11.Cu")
		(net "M_H_CPU0_SA_DQ<31>")
	)
	(gr_poly
		(pts
			(xy 378.65558 -262.668258) (xy 378.65558 -262.624062) (xy 378.29998 -262.624062) (xy 378.29998 -262.668258)
			(xy 378.34697 -262.820658) (xy 378.60859 -262.820658)
		)
		(stroke
			(width 0)
			(type solid)
		)
		(fill yes)
		(layer "In11.Cu")
		(net "M_H_CPU0_SA_CB<0>")
	)
	(gr_poly
		(pts
			(xy 378.65558 -261.449058) (xy 378.60859 -261.296658) (xy 378.34697 -261.296658) (xy 378.29998 -261.449058)
			(xy 378.29998 -261.493254) (xy 378.65558 -261.493254)
		)
		(stroke
			(width 0)
			(type solid)
		)
		(fill yes)
		(layer "In11.Cu")
		(net "M_H_CPU0_SA_CB<3>")
	)
	(gr_poly
		(pts
			(xy 378.65558 -261.040626) (xy 378.65558 -260.99643) (xy 378.29998 -260.99643) (xy 378.29998 -261.040626)
			(xy 378.34697 -261.193026) (xy 378.60859 -261.193026)
		)
		(stroke
			(width 0)
			(type solid)
		)
		(fill yes)
		(layer "In11.Cu")
		(net "M_H_CPU0_SA_DQS_DP<4>")
	)
	(gr_poly
		(pts
			(xy 378.65558 -259.820918) (xy 378.60859 -259.668518) (xy 378.34697 -259.668518) (xy 378.29998 -259.820918)
			(xy 378.29998 -259.865368) (xy 378.65558 -259.865368)
		)
		(stroke
			(width 0)
			(type solid)
		)
		(fill yes)
		(layer "In11.Cu")
		(net "M_H_CPU0_SA_DQS_DP<9>")
	)
	(gr_poly
		(pts
			(xy 378.65558 -259.412994) (xy 378.65558 -259.368544) (xy 378.29998 -259.368544) (xy 378.29998 -259.412994)
			(xy 378.34697 -259.565394) (xy 378.60859 -259.565394)
		)
		(stroke
			(width 0)
			(type solid)
		)
		(fill yes)
		(layer "In11.Cu")
		(net "M_H_CPU0_SA_CB<4>")
	)
	(gr_poly
		(pts
			(xy 378.65558 -258.193286) (xy 378.60859 -258.040886) (xy 378.34697 -258.040886) (xy 378.29998 -258.193286)
			(xy 378.29998 -258.237482) (xy 378.65558 -258.237482)
		)
		(stroke
			(width 0)
			(type solid)
		)
		(fill yes)
		(layer "In11.Cu")
		(net "M_H_CPU0_SA_CB<7>")
	)
	(gr_poly
		(pts
			(xy 378.65558 -257.784854) (xy 378.65558 -257.740658) (xy 378.29998 -257.740658) (xy 378.29998 -257.784854)
			(xy 378.34697 -257.937254) (xy 378.60859 -257.937254)
		)
		(stroke
			(width 0)
			(type solid)
		)
		(fill yes)
		(layer "In11.Cu")
		(net "M_E_CPU0_ALERT_N")
	)
	(gr_poly
		(pts
			(xy 378.65558 -256.565654) (xy 378.60859 -256.413254) (xy 378.34697 -256.413254) (xy 378.29998 -256.565654)
			(xy 378.29998 -256.60985) (xy 378.65558 -256.60985)
		)
		(stroke
			(width 0)
			(type solid)
		)
		(fill yes)
		(layer "In11.Cu")
		(net "M_H_CPU0_SA_CS_N<1>")
	)
	(gr_poly
		(pts
			(xy 378.65558 -256.157222) (xy 378.65558 -256.113026) (xy 378.29998 -256.113026) (xy 378.29998 -256.157222)
			(xy 378.34697 -256.309622) (xy 378.60859 -256.309622)
		)
		(stroke
			(width 0)
			(type solid)
		)
		(fill yes)
		(layer "In11.Cu")
		(net "M_H_CPU0_SA_CS_N<2>")
	)
	(gr_poly
		(pts
			(xy 378.65558 -254.937514) (xy 378.60859 -254.785114) (xy 378.34697 -254.785114) (xy 378.29998 -254.937514)
			(xy 378.29998 -254.981964) (xy 378.65558 -254.981964)
		)
		(stroke
			(width 0)
			(type solid)
		)
		(fill yes)
		(layer "In11.Cu")
		(net "M_H_CPU0_SA_CA<0>")
	)
	(gr_poly
		(pts
			(xy 378.65558 -254.52959) (xy 378.65558 -254.48514) (xy 378.29998 -254.48514) (xy 378.29998 -254.52959)
			(xy 378.34697 -254.68199) (xy 378.60859 -254.68199)
		)
		(stroke
			(width 0)
			(type solid)
		)
		(fill yes)
		(layer "In11.Cu")
		(net "M_H_CPU0_SA_CA<2>")
	)
	(gr_poly
		(pts
			(xy 378.65812 -279.354788) (xy 378.61113 -279.202388) (xy 378.34951 -279.202388) (xy 378.30252 -279.354788)
			(xy 378.30252 -279.398984) (xy 378.65812 -279.398984)
		)
		(stroke
			(width 0)
			(type solid)
		)
		(fill yes)
		(layer "In11.Cu")
		(net "M_H_CPU0_SA_DQS_DN<1>")
	)
	(gr_poly
		(pts
			(xy 378.664216 -277.317962) (xy 378.664216 -277.273766) (xy 378.308616 -277.273766) (xy 378.308616 -277.317962)
			(xy 378.355606 -277.470362) (xy 378.617226 -277.470362)
		)
		(stroke
			(width 0)
			(type solid)
		)
		(fill yes)
		(layer "In11.Cu")
		(net "M_H_CPU0_SA_DQ<13>")
	)
	(gr_poly
		(pts
			(xy 378.670058 -278.945848) (xy 378.670058 -278.901652) (xy 378.314458 -278.901652) (xy 378.314458 -278.945848)
			(xy 378.361448 -279.098248) (xy 378.623068 -279.098248)
		)
		(stroke
			(width 0)
			(type solid)
		)
		(fill yes)
		(layer "In11.Cu")
		(net "M_H_CPU0_SA_DQS_DN<6>")
	)
	(gr_poly
		(pts
			(xy 378.672598 -277.726394) (xy 378.625608 -277.573994) (xy 378.363988 -277.573994) (xy 378.316998 -277.726394)
			(xy 378.316998 -277.770844) (xy 378.672598 -277.770844)
		)
		(stroke
			(width 0)
			(type solid)
		)
		(fill yes)
		(layer "In11.Cu")
		(net "M_H_CPU0_SA_DQ<14>")
	)
	(gr_poly
		(pts
			(xy 378.99086 -273.918426) (xy 379.029214 -273.896328) (xy 378.851414 -273.58848) (xy 378.81306 -273.610578)
			(xy 378.704602 -273.727418) (xy 378.835412 -273.953986)
		)
		(stroke
			(width 0)
			(type solid)
		)
		(fill yes)
		(layer "In11.Cu")
		(net "M_H_CPU0_SA_DQS_DP<2>")
	)
	(gr_poly
		(pts
			(xy 378.99086 -270.662908) (xy 379.029214 -270.64081) (xy 378.851414 -270.332962) (xy 378.81306 -270.35506)
			(xy 378.704602 -270.4719) (xy 378.835412 -270.698468)
		)
		(stroke
			(width 0)
			(type solid)
		)
		(fill yes)
		(layer "In11.Cu")
		(net "M_H_CPU0_SA_DQ<20>")
	)
	(gr_poly
		(pts
			(xy 378.99086 -269.035022) (xy 379.029214 -269.012924) (xy 378.851414 -268.705076) (xy 378.81306 -268.727174)
			(xy 378.704602 -268.844014) (xy 378.835412 -269.070582)
		)
		(stroke
			(width 0)
			(type solid)
		)
		(fill yes)
		(layer "In11.Cu")
		(net "M_H_CPU0_SA_DQ<21>")
	)
	(gr_poly
		(pts
			(xy 378.992638 -272.292064) (xy 379.030992 -272.269966) (xy 378.853192 -271.962118) (xy 378.814838 -271.984216)
			(xy 378.70638 -272.101056) (xy 378.83719 -272.327624)
		)
		(stroke
			(width 0)
			(type solid)
		)
		(fill yes)
		(layer "In11.Cu")
		(net "M_H_CPU0_SA_DQS_DN<7>")
	)
	(gr_poly
		(pts
			(xy 379.018038 -247.382538) (xy 378.971048 -247.230138) (xy 378.709428 -247.230138) (xy 378.662438 -247.382538)
			(xy 378.662438 -247.426988) (xy 379.018038 -247.426988)
		)
		(stroke
			(width 0)
			(type solid)
		)
		(fill yes)
		(layer "In11.Cu")
		(net "M_H_CPU0_SB_CA<3>")
	)
	(gr_poly
		(pts
			(xy 379.024134 -248.601738) (xy 379.024134 -248.557542) (xy 378.668534 -248.557542) (xy 378.668534 -248.601738)
			(xy 378.715524 -248.754138) (xy 378.977144 -248.754138)
		)
		(stroke
			(width 0)
			(type solid)
		)
		(fill yes)
		(layer "In11.Cu")
		(net "M_H_CPU0_SB_CA<0>")
	)
	(gr_poly
		(pts
			(xy 379.024134 -227.44049) (xy 379.024134 -227.396294) (xy 378.668534 -227.396294) (xy 378.668534 -227.44049)
			(xy 378.715524 -227.59289) (xy 378.977144 -227.59289)
		)
		(stroke
			(width 0)
			(type solid)
		)
		(fill yes)
		(layer "In11.Cu")
		(net "M_H_CPU0_SB_DQS_DP<3>")
	)
	(gr_poly
		(pts
			(xy 379.024134 -226.221798) (xy 378.977144 -226.069398) (xy 378.715524 -226.069398) (xy 378.668534 -226.221798)
			(xy 378.668534 -226.265994) (xy 379.024134 -226.265994)
		)
		(stroke
			(width 0)
			(type solid)
		)
		(fill yes)
		(layer "In11.Cu")
		(net "M_H_CPU0_SB_DQ<28>")
	)
	(gr_poly
		(pts
			(xy 379.029976 -246.974106) (xy 379.029976 -246.929656) (xy 378.674376 -246.929656) (xy 378.674376 -246.974106)
			(xy 378.721366 -247.126506) (xy 378.982986 -247.126506)
		)
		(stroke
			(width 0)
			(type solid)
		)
		(fill yes)
		(layer "In11.Cu")
		(net "M_H_CPU0_SB_CA<4>")
	)
	(gr_poly
		(pts
			(xy 379.032516 -245.754906) (xy 378.985526 -245.602506) (xy 378.723906 -245.602506) (xy 378.676916 -245.754906)
			(xy 378.676916 -245.799102) (xy 379.032516 -245.799102)
		)
		(stroke
			(width 0)
			(type solid)
		)
		(fill yes)
		(layer "In11.Cu")
		(net "M_H_CPU0_SB_PAR")
	)
	(gr_poly
		(pts
			(xy 379.032516 -244.126766) (xy 378.985526 -243.974366) (xy 378.723906 -243.974366) (xy 378.676916 -244.126766)
			(xy 378.676916 -244.171216) (xy 379.032516 -244.171216)
		)
		(stroke
			(width 0)
			(type solid)
		)
		(fill yes)
		(layer "In11.Cu")
		(net "M_H_CPU0_SB_CB<4>")
	)
	(gr_poly
		(pts
			(xy 379.032516 -243.718842) (xy 379.032516 -243.674392) (xy 378.676916 -243.674392) (xy 378.676916 -243.718842)
			(xy 378.723906 -243.871242) (xy 378.985526 -243.871242)
		)
		(stroke
			(width 0)
			(type solid)
		)
		(fill yes)
		(layer "In11.Cu")
		(net "M_H_CPU0_SB_CB<7>")
	)
	(gr_poly
		(pts
			(xy 379.032516 -242.499134) (xy 378.985526 -242.346734) (xy 378.723906 -242.346734) (xy 378.676916 -242.499134)
			(xy 378.676916 -242.54333) (xy 379.032516 -242.54333)
		)
		(stroke
			(width 0)
			(type solid)
		)
		(fill yes)
		(layer "In11.Cu")
		(net "M_H_CPU0_SB_DQS_DN<9>")
	)
	(gr_poly
		(pts
			(xy 379.032516 -242.090702) (xy 379.032516 -242.046506) (xy 378.676916 -242.046506) (xy 378.676916 -242.090702)
			(xy 378.723906 -242.243102) (xy 378.985526 -242.243102)
		)
		(stroke
			(width 0)
			(type solid)
		)
		(fill yes)
		(layer "In11.Cu")
		(net "M_H_CPU0_SB_DQS_DN<4>")
	)
	(gr_poly
		(pts
			(xy 379.032516 -240.871502) (xy 378.985526 -240.719102) (xy 378.723906 -240.719102) (xy 378.676916 -240.871502)
			(xy 378.676916 -240.915698) (xy 379.032516 -240.915698)
		)
		(stroke
			(width 0)
			(type solid)
		)
		(fill yes)
		(layer "In11.Cu")
		(net "M_H_CPU0_SB_CB<2>")
	)
	(gr_poly
		(pts
			(xy 379.032516 -240.46307) (xy 379.032516 -240.418874) (xy 378.676916 -240.418874) (xy 378.676916 -240.46307)
			(xy 378.723906 -240.61547) (xy 378.985526 -240.61547)
		)
		(stroke
			(width 0)
			(type solid)
		)
		(fill yes)
		(layer "In11.Cu")
		(net "M_H_CPU0_SB_CB<1>")
	)
	(gr_poly
		(pts
			(xy 379.032516 -239.243362) (xy 378.985526 -239.090962) (xy 378.723906 -239.090962) (xy 378.676916 -239.243362)
			(xy 378.676916 -239.287812) (xy 379.032516 -239.287812)
		)
		(stroke
			(width 0)
			(type solid)
		)
		(fill yes)
		(layer "In11.Cu")
		(net "M_H_CPU0_SB_DQ<2>")
	)
	(gr_poly
		(pts
			(xy 379.032516 -238.835438) (xy 379.032516 -238.790988) (xy 378.676916 -238.790988) (xy 378.676916 -238.835438)
			(xy 378.723906 -238.987838) (xy 378.985526 -238.987838)
		)
		(stroke
			(width 0)
			(type solid)
		)
		(fill yes)
		(layer "In11.Cu")
		(net "M_H_CPU0_SB_DQ<1>")
	)
	(gr_poly
		(pts
			(xy 379.032516 -237.61573) (xy 378.985526 -237.46333) (xy 378.723906 -237.46333) (xy 378.676916 -237.61573)
			(xy 378.676916 -237.66018) (xy 379.032516 -237.66018)
		)
		(stroke
			(width 0)
			(type solid)
		)
		(fill yes)
		(layer "In11.Cu")
		(net "M_H_CPU0_SB_DQS_DN<0>")
	)
	(gr_poly
		(pts
			(xy 379.032516 -237.207806) (xy 379.032516 -237.163356) (xy 378.676916 -237.163356) (xy 378.676916 -237.207806)
			(xy 378.723906 -237.360206) (xy 378.985526 -237.360206)
		)
		(stroke
			(width 0)
			(type solid)
		)
		(fill yes)
		(layer "In11.Cu")
		(net "M_H_CPU0_SB_DQS_DN<5>")
	)
	(gr_poly
		(pts
			(xy 379.032516 -235.988098) (xy 378.985526 -235.835698) (xy 378.723906 -235.835698) (xy 378.676916 -235.988098)
			(xy 378.676916 -236.032294) (xy 379.032516 -236.032294)
		)
		(stroke
			(width 0)
			(type solid)
		)
		(fill yes)
		(layer "In11.Cu")
		(net "M_H_CPU0_SB_DQ<6>")
	)
	(gr_poly
		(pts
			(xy 379.032516 -235.579666) (xy 379.032516 -235.53547) (xy 378.676916 -235.53547) (xy 378.676916 -235.579666)
			(xy 378.723906 -235.732066) (xy 378.985526 -235.732066)
		)
		(stroke
			(width 0)
			(type solid)
		)
		(fill yes)
		(layer "In11.Cu")
		(net "M_H_CPU0_SB_DQ<5>")
	)
	(gr_poly
		(pts
			(xy 379.032516 -234.360466) (xy 378.985526 -234.208066) (xy 378.723906 -234.208066) (xy 378.676916 -234.360466)
			(xy 378.676916 -234.404662) (xy 379.032516 -234.404662)
		)
		(stroke
			(width 0)
			(type solid)
		)
		(fill yes)
		(layer "In11.Cu")
		(net "M_H_CPU0_SB_DQ<10>")
	)
	(gr_poly
		(pts
			(xy 379.032516 -233.952034) (xy 379.032516 -233.907838) (xy 378.676916 -233.907838) (xy 378.676916 -233.952034)
			(xy 378.723906 -234.104434) (xy 378.985526 -234.104434)
		)
		(stroke
			(width 0)
			(type solid)
		)
		(fill yes)
		(layer "In11.Cu")
		(net "M_H_CPU0_SB_DQ<9>")
	)
	(gr_poly
		(pts
			(xy 379.032516 -232.732326) (xy 378.985526 -232.579926) (xy 378.723906 -232.579926) (xy 378.676916 -232.732326)
			(xy 378.676916 -232.776776) (xy 379.032516 -232.776776)
		)
		(stroke
			(width 0)
			(type solid)
		)
		(fill yes)
		(layer "In11.Cu")
		(net "M_H_CPU0_SB_DQS_DN<1>")
	)
	(gr_poly
		(pts
			(xy 379.032516 -232.324402) (xy 379.032516 -232.279952) (xy 378.676916 -232.279952) (xy 378.676916 -232.324402)
			(xy 378.723906 -232.476802) (xy 378.985526 -232.476802)
		)
		(stroke
			(width 0)
			(type solid)
		)
		(fill yes)
		(layer "In11.Cu")
		(net "M_H_CPU0_SB_DQS_DN<6>")
	)
	(gr_poly
		(pts
			(xy 379.032516 -231.104694) (xy 378.985526 -230.952294) (xy 378.723906 -230.952294) (xy 378.676916 -231.104694)
			(xy 378.676916 -231.14889) (xy 379.032516 -231.14889)
		)
		(stroke
			(width 0)
			(type solid)
		)
		(fill yes)
		(layer "In11.Cu")
		(net "M_H_CPU0_SB_DQ<14>")
	)
	(gr_poly
		(pts
			(xy 379.032516 -230.696262) (xy 379.032516 -230.652066) (xy 378.676916 -230.652066) (xy 378.676916 -230.696262)
			(xy 378.723906 -230.848662) (xy 378.985526 -230.848662)
		)
		(stroke
			(width 0)
			(type solid)
		)
		(fill yes)
		(layer "In11.Cu")
		(net "M_H_CPU0_SB_DQ<13>")
	)
	(gr_poly
		(pts
			(xy 379.032516 -229.477062) (xy 378.985526 -229.324662) (xy 378.723906 -229.324662) (xy 378.676916 -229.477062)
			(xy 378.676916 -229.521258) (xy 379.032516 -229.521258)
		)
		(stroke
			(width 0)
			(type solid)
		)
		(fill yes)
		(layer "In11.Cu")
		(net "M_H_CPU0_SB_DQ<24>")
	)
	(gr_poly
		(pts
			(xy 379.032516 -229.06863) (xy 379.032516 -229.024434) (xy 378.676916 -229.024434) (xy 378.676916 -229.06863)
			(xy 378.723906 -229.22103) (xy 378.985526 -229.22103)
		)
		(stroke
			(width 0)
			(type solid)
		)
		(fill yes)
		(layer "In11.Cu")
		(net "M_H_CPU0_SB_DQ<27>")
	)
	(gr_poly
		(pts
			(xy 379.032516 -227.848922) (xy 378.985526 -227.696522) (xy 378.723906 -227.696522) (xy 378.676916 -227.848922)
			(xy 378.676916 -227.893372) (xy 379.032516 -227.893372)
		)
		(stroke
			(width 0)
			(type solid)
		)
		(fill yes)
		(layer "In11.Cu")
		(net "M_H_CPU0_SB_DQS_DP<8>")
	)
	(gr_poly
		(pts
			(xy 379.032516 -225.813366) (xy 379.032516 -225.768916) (xy 378.676916 -225.768916) (xy 378.676916 -225.813366)
			(xy 378.723906 -225.965766) (xy 378.985526 -225.965766)
		)
		(stroke
			(width 0)
			(type solid)
		)
		(fill yes)
		(layer "In11.Cu")
		(net "M_H_CPU0_SB_DQ<31>")
	)
	(gr_poly
		(pts
			(xy 379.099572 -270.040608) (xy 379.20803 -269.923768) (xy 379.07722 -269.6972) (xy 378.921772 -269.73276)
			(xy 378.883418 -269.754858) (xy 379.061218 -270.062706)
		)
		(stroke
			(width 0)
			(type solid)
		)
		(fill yes)
		(layer "In11.Cu")
		(net "M_H_CPU0_SA_DQ<22>")
	)
	(gr_poly
		(pts
			(xy 379.104906 -273.30527) (xy 379.213364 -273.18843) (xy 379.082554 -272.961862) (xy 378.927106 -272.997422)
			(xy 378.888752 -273.01952) (xy 379.066552 -273.327368)
		)
		(stroke
			(width 0)
			(type solid)
		)
		(fill yes)
		(layer "In11.Cu")
		(net "M_H_CPU0_SA_DQS_DN<2>")
	)
	(gr_poly
		(pts
			(xy 379.104906 -271.677384) (xy 379.213364 -271.560544) (xy 379.082554 -271.333976) (xy 378.927106 -271.369536)
			(xy 378.888752 -271.391634) (xy 379.066552 -271.699482)
		)
		(stroke
			(width 0)
			(type solid)
		)
		(fill yes)
		(layer "In11.Cu")
		(net "M_H_CPU0_SA_DQS_DP<7>")
	)
	(gr_poly
		(pts
			(xy 379.104906 -268.421866) (xy 379.213364 -268.305026) (xy 379.082554 -268.078458) (xy 378.927106 -268.114018)
			(xy 378.888752 -268.136116) (xy 379.066552 -268.443964)
		)
		(stroke
			(width 0)
			(type solid)
		)
		(fill yes)
		(layer "In11.Cu")
		(net "M_H_CPU0_SA_DQ<23>")
	)
	(gr_poly
		(pts
			(xy 379.12802 -278.132286) (xy 379.12802 -278.08809) (xy 378.77242 -278.08809) (xy 378.77242 -278.132286)
			(xy 378.81941 -278.284686) (xy 379.08103 -278.284686)
		)
		(stroke
			(width 0)
			(type solid)
		)
		(fill yes)
		(layer "In11.Cu")
		(net "M_H_CPU0_SA_DQ<12>")
	)
	(gr_poly
		(pts
			(xy 379.134116 -276.913086) (xy 379.087126 -276.760686) (xy 378.825506 -276.760686) (xy 378.778516 -276.913086)
			(xy 378.778516 -276.957282) (xy 379.134116 -276.957282)
		)
		(stroke
			(width 0)
			(type solid)
		)
		(fill yes)
		(layer "In11.Cu")
		(net "M_H_CPU0_SA_DQ<15>")
	)
	(gr_poly
		(pts
			(xy 379.139958 -278.540718) (xy 379.092968 -278.388318) (xy 378.831348 -278.388318) (xy 378.784358 -278.540718)
			(xy 378.784358 -278.584914) (xy 379.139958 -278.584914)
		)
		(stroke
			(width 0)
			(type solid)
		)
		(fill yes)
		(layer "In11.Cu")
		(net "M_H_CPU0_SA_DQS_DP<6>")
	)
	(gr_poly
		(pts
			(xy 379.139958 -254.124206) (xy 379.092968 -253.971806) (xy 378.831348 -253.971806) (xy 378.784358 -254.124206)
			(xy 378.784358 -254.168402) (xy 379.139958 -254.168402)
		)
		(stroke
			(width 0)
			(type solid)
		)
		(fill yes)
		(layer "In11.Cu")
		(net "M_H_CPU0_SA_CA<3>")
	)
	(gr_poly
		(pts
			(xy 379.142498 -281.387804) (xy 379.142498 -281.343608) (xy 378.786898 -281.343608) (xy 378.786898 -281.387804)
			(xy 378.833888 -281.540204) (xy 379.095508 -281.540204)
		)
		(stroke
			(width 0)
			(type solid)
		)
		(fill yes)
		(layer "In11.Cu")
		(net "M_H_CPU0_SA_DQ<8>")
	)
	(gr_poly
		(pts
			(xy 379.142498 -280.168096) (xy 379.095508 -280.015696) (xy 378.833888 -280.015696) (xy 378.786898 -280.168096)
			(xy 378.786898 -280.212546) (xy 379.142498 -280.212546)
		)
		(stroke
			(width 0)
			(type solid)
		)
		(fill yes)
		(layer "In11.Cu")
		(net "M_H_CPU0_SA_DQ<11>")
	)
	(gr_poly
		(pts
			(xy 379.142498 -279.759918) (xy 379.142498 -279.715722) (xy 378.786898 -279.715722) (xy 378.786898 -279.759918)
			(xy 378.833888 -279.912318) (xy 379.095508 -279.912318)
		)
		(stroke
			(width 0)
			(type solid)
		)
		(fill yes)
		(layer "In11.Cu")
		(net "M_H_CPU0_SA_DQS_DP<1>")
	)
	(gr_poly
		(pts
			(xy 379.142498 -275.284946) (xy 379.095508 -275.132546) (xy 378.833888 -275.132546) (xy 378.786898 -275.284946)
			(xy 378.786898 -275.329142) (xy 379.142498 -275.329142)
		)
		(stroke
			(width 0)
			(type solid)
		)
		(fill yes)
		(layer "In11.Cu")
		(net "M_H_CPU0_SA_DQ<18>")
	)
	(gr_poly
		(pts
			(xy 379.142498 -274.876514) (xy 379.142498 -274.832318) (xy 378.786898 -274.832318) (xy 378.786898 -274.876514)
			(xy 378.833888 -275.028914) (xy 379.095508 -275.028914)
		)
		(stroke
			(width 0)
			(type solid)
		)
		(fill yes)
		(layer "In11.Cu")
		(net "M_H_CPU0_SA_DQ<17>")
	)
	(gr_poly
		(pts
			(xy 379.142498 -267.14577) (xy 379.095508 -266.99337) (xy 378.833888 -266.99337) (xy 378.786898 -267.14577)
			(xy 378.786898 -267.19022) (xy 379.142498 -267.19022)
		)
		(stroke
			(width 0)
			(type solid)
		)
		(fill yes)
		(layer "In11.Cu")
		(net "M_H_CPU0_SA_DQ<26>")
	)
	(gr_poly
		(pts
			(xy 379.142498 -266.737846) (xy 379.142498 -266.69365) (xy 378.786898 -266.69365) (xy 378.786898 -266.737846)
			(xy 378.833888 -266.890246) (xy 379.095508 -266.890246)
		)
		(stroke
			(width 0)
			(type solid)
		)
		(fill yes)
		(layer "In11.Cu")
		(net "M_H_CPU0_SA_DQ<25>")
	)
	(gr_poly
		(pts
			(xy 379.142498 -265.518138) (xy 379.095508 -265.365738) (xy 378.833888 -265.365738) (xy 378.786898 -265.518138)
			(xy 378.786898 -265.562588) (xy 379.142498 -265.562588)
		)
		(stroke
			(width 0)
			(type solid)
		)
		(fill yes)
		(layer "In11.Cu")
		(net "M_H_CPU0_SA_DQS_DN<3>")
	)
	(gr_poly
		(pts
			(xy 379.142498 -265.110214) (xy 379.142498 -265.065764) (xy 378.786898 -265.065764) (xy 378.786898 -265.110214)
			(xy 378.833888 -265.262614) (xy 379.095508 -265.262614)
		)
		(stroke
			(width 0)
			(type solid)
		)
		(fill yes)
		(layer "In11.Cu")
		(net "M_H_CPU0_SA_DQS_DN<8>")
	)
	(gr_poly
		(pts
			(xy 379.142498 -263.890506) (xy 379.095508 -263.738106) (xy 378.833888 -263.738106) (xy 378.786898 -263.890506)
			(xy 378.786898 -263.934956) (xy 379.142498 -263.934956)
		)
		(stroke
			(width 0)
			(type solid)
		)
		(fill yes)
		(layer "In11.Cu")
		(net "M_H_CPU0_SA_DQ<30>")
	)
	(gr_poly
		(pts
			(xy 379.142498 -263.482582) (xy 379.142498 -263.438132) (xy 378.786898 -263.438132) (xy 378.786898 -263.482582)
			(xy 378.833888 -263.634982) (xy 379.095508 -263.634982)
		)
		(stroke
			(width 0)
			(type solid)
		)
		(fill yes)
		(layer "In11.Cu")
		(net "M_H_CPU0_SA_DQ<29>")
	)
	(gr_poly
		(pts
			(xy 379.142498 -262.262874) (xy 379.095508 -262.110474) (xy 378.833888 -262.110474) (xy 378.786898 -262.262874)
			(xy 378.786898 -262.30707) (xy 379.142498 -262.30707)
		)
		(stroke
			(width 0)
			(type solid)
		)
		(fill yes)
		(layer "In11.Cu")
		(net "M_H_CPU0_SA_CB<2>")
	)
	(gr_poly
		(pts
			(xy 379.142498 -261.854442) (xy 379.142498 -261.810246) (xy 378.786898 -261.810246) (xy 378.786898 -261.854442)
			(xy 378.833888 -262.006842) (xy 379.095508 -262.006842)
		)
		(stroke
			(width 0)
			(type solid)
		)
		(fill yes)
		(layer "In11.Cu")
		(net "M_H_CPU0_SA_CB<1>")
	)
	(gr_poly
		(pts
			(xy 379.142498 -260.634734) (xy 379.095508 -260.482334) (xy 378.833888 -260.482334) (xy 378.786898 -260.634734)
			(xy 378.786898 -260.679184) (xy 379.142498 -260.679184)
		)
		(stroke
			(width 0)
			(type solid)
		)
		(fill yes)
		(layer "In11.Cu")
		(net "M_H_CPU0_SA_DQS_DN<4>")
	)
	(gr_poly
		(pts
			(xy 379.142498 -260.22681) (xy 379.142498 -260.18236) (xy 378.786898 -260.18236) (xy 378.786898 -260.22681)
			(xy 378.833888 -260.37921) (xy 379.095508 -260.37921)
		)
		(stroke
			(width 0)
			(type solid)
		)
		(fill yes)
		(layer "In11.Cu")
		(net "M_H_CPU0_SA_DQS_DN<9>")
	)
	(gr_poly
		(pts
			(xy 379.142498 -259.007102) (xy 379.095508 -258.854702) (xy 378.833888 -258.854702) (xy 378.786898 -259.007102)
			(xy 378.786898 -259.051552) (xy 379.142498 -259.051552)
		)
		(stroke
			(width 0)
			(type solid)
		)
		(fill yes)
		(layer "In11.Cu")
		(net "M_H_CPU0_SA_CB<6>")
	)
	(gr_poly
		(pts
			(xy 379.142498 -258.599178) (xy 379.142498 -258.554728) (xy 378.786898 -258.554728) (xy 378.786898 -258.599178)
			(xy 378.833888 -258.751578) (xy 379.095508 -258.751578)
		)
		(stroke
			(width 0)
			(type solid)
		)
		(fill yes)
		(layer "In11.Cu")
		(net "M_H_CPU0_SA_CB<5>")
	)
	(gr_poly
		(pts
			(xy 379.142498 -257.37947) (xy 379.095508 -257.22707) (xy 378.833888 -257.22707) (xy 378.786898 -257.37947)
			(xy 378.786898 -257.423666) (xy 379.142498 -257.423666)
		)
		(stroke
			(width 0)
			(type solid)
		)
		(fill yes)
		(layer "In11.Cu")
		(net "M_H_CPU0_ALERT_N")
	)
	(gr_poly
		(pts
			(xy 379.142498 -256.971038) (xy 379.142498 -256.926842) (xy 378.786898 -256.926842) (xy 378.786898 -256.971038)
			(xy 378.833888 -257.123438) (xy 379.095508 -257.123438)
		)
		(stroke
			(width 0)
			(type solid)
		)
		(fill yes)
		(layer "In11.Cu")
		(net "M_H_CPU0_SA_CS_N<0>")
	)
	(gr_poly
		(pts
			(xy 379.142498 -255.751838) (xy 379.095508 -255.599438) (xy 378.833888 -255.599438) (xy 378.786898 -255.751838)
			(xy 378.786898 -255.796034) (xy 379.142498 -255.796034)
		)
		(stroke
			(width 0)
			(type solid)
		)
		(fill yes)
		(layer "In11.Cu")
		(net "M_H_CPU0_SA_CS_N<3>")
	)
	(gr_poly
		(pts
			(xy 379.142498 -255.343406) (xy 379.142498 -255.29921) (xy 378.786898 -255.29921) (xy 378.786898 -255.343406)
			(xy 378.833888 -255.495806) (xy 379.095508 -255.495806)
		)
		(stroke
			(width 0)
			(type solid)
		)
		(fill yes)
		(layer "In11.Cu")
		(net "M_H_CPU0_SA_CA<1>")
	)
	(gr_poly
		(pts
			(xy 379.453394 -273.09191) (xy 379.491748 -273.069812) (xy 379.313948 -272.761964) (xy 379.275594 -272.784062)
			(xy 379.167136 -272.900902) (xy 379.297946 -273.12747)
		)
		(stroke
			(width 0)
			(type solid)
		)
		(fill yes)
		(layer "In11.Cu")
		(net "M_H_CPU0_SA_DQS_DN<7>")
	)
	(gr_poly
		(pts
			(xy 379.453394 -268.208506) (xy 379.491748 -268.186408) (xy 379.313948 -267.87856) (xy 379.275594 -267.900658)
			(xy 379.167136 -268.017498) (xy 379.297946 -268.244066)
		)
		(stroke
			(width 0)
			(type solid)
		)
		(fill yes)
		(layer "In11.Cu")
		(net "M_H_CPU0_SA_DQ<24>")
	)
	(gr_poly
		(pts
			(xy 379.455172 -271.467072) (xy 379.493526 -271.444974) (xy 379.315726 -271.137126) (xy 379.277372 -271.159224)
			(xy 379.168914 -271.276064) (xy 379.299724 -271.502632)
		)
		(stroke
			(width 0)
			(type solid)
		)
		(fill yes)
		(layer "In11.Cu")
		(net "M_H_CPU0_SA_DQ<20>")
	)
	(gr_poly
		(pts
			(xy 379.460506 -269.84833) (xy 379.49886 -269.826232) (xy 379.32106 -269.518384) (xy 379.282706 -269.540482)
			(xy 379.174248 -269.657322) (xy 379.305058 -269.88389)
		)
		(stroke
			(width 0)
			(type solid)
		)
		(fill yes)
		(layer "In11.Cu")
		(net "M_H_CPU0_SA_DQ<21>")
	)
	(gr_poly
		(pts
			(xy 379.485398 -246.16029) (xy 379.485398 -246.116094) (xy 379.129798 -246.116094) (xy 379.129798 -246.16029)
			(xy 379.176788 -246.31269) (xy 379.438408 -246.31269)
		)
		(stroke
			(width 0)
			(type solid)
		)
		(fill yes)
		(layer "In11.Cu")
		(net "M_H_CPU0_SB_CA<6>")
	)
	(gr_poly
		(pts
			(xy 379.485398 -243.31295) (xy 379.438408 -243.16055) (xy 379.176788 -243.16055) (xy 379.129798 -243.31295)
			(xy 379.129798 -243.3574) (xy 379.485398 -243.3574)
		)
		(stroke
			(width 0)
			(type solid)
		)
		(fill yes)
		(layer "In11.Cu")
		(net "M_H_CPU0_SB_CB<5>")
	)
	(gr_poly
		(pts
			(xy 379.485398 -242.905026) (xy 379.485398 -242.860576) (xy 379.129798 -242.860576) (xy 379.129798 -242.905026)
			(xy 379.176788 -243.057426) (xy 379.438408 -243.057426)
		)
		(stroke
			(width 0)
			(type solid)
		)
		(fill yes)
		(layer "In11.Cu")
		(net "M_H_CPU0_SB_DQS_DP<9>")
	)
	(gr_poly
		(pts
			(xy 379.485398 -241.276886) (xy 379.485398 -241.23269) (xy 379.129798 -241.23269) (xy 379.129798 -241.276886)
			(xy 379.176788 -241.429286) (xy 379.438408 -241.429286)
		)
		(stroke
			(width 0)
			(type solid)
		)
		(fill yes)
		(layer "In11.Cu")
		(net "M_H_CPU0_SB_CB<0>")
	)
	(gr_poly
		(pts
			(xy 379.485398 -238.429546) (xy 379.438408 -238.277146) (xy 379.176788 -238.277146) (xy 379.129798 -238.429546)
			(xy 379.129798 -238.473996) (xy 379.485398 -238.473996)
		)
		(stroke
			(width 0)
			(type solid)
		)
		(fill yes)
		(layer "In11.Cu")
		(net "M_H_CPU0_SB_DQ<3>")
	)
	(gr_poly
		(pts
			(xy 379.485398 -238.021622) (xy 379.485398 -237.977172) (xy 379.129798 -237.977172) (xy 379.129798 -238.021622)
			(xy 379.176788 -238.174022) (xy 379.438408 -238.174022)
		)
		(stroke
			(width 0)
			(type solid)
		)
		(fill yes)
		(layer "In11.Cu")
		(net "M_H_CPU0_SB_DQS_DP<0>")
	)
	(gr_poly
		(pts
			(xy 379.485398 -236.39399) (xy 379.485398 -236.34954) (xy 379.129798 -236.34954) (xy 379.129798 -236.39399)
			(xy 379.176788 -236.54639) (xy 379.438408 -236.54639)
		)
		(stroke
			(width 0)
			(type solid)
		)
		(fill yes)
		(layer "In11.Cu")
		(net "M_H_CPU0_SB_DQ<4>")
	)
	(gr_poly
		(pts
			(xy 379.485398 -233.138218) (xy 379.485398 -233.093768) (xy 379.129798 -233.093768) (xy 379.129798 -233.138218)
			(xy 379.176788 -233.290618) (xy 379.438408 -233.290618)
		)
		(stroke
			(width 0)
			(type solid)
		)
		(fill yes)
		(layer "In11.Cu")
		(net "M_H_CPU0_SB_DQS_DP<1>")
	)
	(gr_poly
		(pts
			(xy 379.485398 -231.510586) (xy 379.485398 -231.466136) (xy 379.129798 -231.466136) (xy 379.129798 -231.510586)
			(xy 379.176788 -231.662986) (xy 379.438408 -231.662986)
		)
		(stroke
			(width 0)
			(type solid)
		)
		(fill yes)
		(layer "In11.Cu")
		(net "M_H_CPU0_SB_DQ<12>")
	)
	(gr_poly
		(pts
			(xy 379.485398 -228.663246) (xy 379.438408 -228.510846) (xy 379.176788 -228.510846) (xy 379.129798 -228.663246)
			(xy 379.129798 -228.707442) (xy 379.485398 -228.707442)
		)
		(stroke
			(width 0)
			(type solid)
		)
		(fill yes)
		(layer "In11.Cu")
		(net "M_H_CPU0_SB_DQ<25>")
	)
	(gr_poly
		(pts
			(xy 379.485398 -228.254814) (xy 379.485398 -228.210618) (xy 379.129798 -228.210618) (xy 379.129798 -228.254814)
			(xy 379.176788 -228.407214) (xy 379.438408 -228.407214)
		)
		(stroke
			(width 0)
			(type solid)
		)
		(fill yes)
		(layer "In11.Cu")
		(net "M_H_CPU0_SB_DQS_DN<8>")
	)
	(gr_poly
		(pts
			(xy 379.485398 -225.407474) (xy 379.438408 -225.255074) (xy 379.176788 -225.255074) (xy 379.129798 -225.407474)
			(xy 379.129798 -225.45167) (xy 379.485398 -225.45167)
		)
		(stroke
			(width 0)
			(type solid)
		)
		(fill yes)
		(layer "In11.Cu")
		(net "M_H_CPU0_SB_DQ<29>")
	)
	(gr_poly
		(pts
			(xy 379.485652 -233.546142) (xy 379.438662 -233.393742) (xy 379.177042 -233.393742) (xy 379.130052 -233.546142)
			(xy 379.130052 -233.590592) (xy 379.485652 -233.590592)
		)
		(stroke
			(width 0)
			(type solid)
		)
		(fill yes)
		(layer "In11.Cu")
		(net "M_H_CPU0_SB_DQ<11>")
	)
	(gr_poly
		(pts
			(xy 379.487938 -248.196354) (xy 379.440948 -248.043954) (xy 379.179328 -248.043954) (xy 379.132338 -248.196354)
			(xy 379.132338 -248.240804) (xy 379.487938 -248.240804)
		)
		(stroke
			(width 0)
			(type solid)
		)
		(fill yes)
		(layer "In11.Cu")
		(net "M_H_CPU0_SB_CA<1>")
	)
	(gr_poly
		(pts
			(xy 379.487938 -244.532658) (xy 379.487938 -244.488208) (xy 379.132338 -244.488208) (xy 379.132338 -244.532658)
			(xy 379.179328 -244.685058) (xy 379.440948 -244.685058)
		)
		(stroke
			(width 0)
			(type solid)
		)
		(fill yes)
		(layer "In11.Cu")
		(net "M_H_CPU0_SB_CB<6>")
	)
	(gr_poly
		(pts
			(xy 379.487938 -240.057178) (xy 379.440948 -239.904778) (xy 379.179328 -239.904778) (xy 379.132338 -240.057178)
			(xy 379.132338 -240.101628) (xy 379.487938 -240.101628)
		)
		(stroke
			(width 0)
			(type solid)
		)
		(fill yes)
		(layer "In11.Cu")
		(net "M_H_CPU0_SB_CB<3>")
	)
	(gr_poly
		(pts
			(xy 379.487938 -239.649254) (xy 379.487938 -239.604804) (xy 379.132338 -239.604804) (xy 379.132338 -239.649254)
			(xy 379.179328 -239.801654) (xy 379.440948 -239.801654)
		)
		(stroke
			(width 0)
			(type solid)
		)
		(fill yes)
		(layer "In11.Cu")
		(net "M_H_CPU0_SB_DQ<0>")
	)
	(gr_poly
		(pts
			(xy 379.487938 -235.174282) (xy 379.440948 -235.021882) (xy 379.179328 -235.021882) (xy 379.132338 -235.174282)
			(xy 379.132338 -235.218478) (xy 379.487938 -235.218478)
		)
		(stroke
			(width 0)
			(type solid)
		)
		(fill yes)
		(layer "In11.Cu")
		(net "M_H_CPU0_SB_DQ<7>")
	)
	(gr_poly
		(pts
			(xy 379.487938 -234.76585) (xy 379.487938 -234.721654) (xy 379.132338 -234.721654) (xy 379.132338 -234.76585)
			(xy 379.179328 -234.91825) (xy 379.440948 -234.91825)
		)
		(stroke
			(width 0)
			(type solid)
		)
		(fill yes)
		(layer "In11.Cu")
		(net "M_H_CPU0_SB_DQ<8>")
	)
	(gr_poly
		(pts
			(xy 379.487938 -230.290878) (xy 379.440948 -230.138478) (xy 379.179328 -230.138478) (xy 379.132338 -230.290878)
			(xy 379.132338 -230.335074) (xy 379.487938 -230.335074)
		)
		(stroke
			(width 0)
			(type solid)
		)
		(fill yes)
		(layer "In11.Cu")
		(net "M_H_CPU0_SB_DQ<15>")
	)
	(gr_poly
		(pts
			(xy 379.487938 -229.882446) (xy 379.487938 -229.83825) (xy 379.132338 -229.83825) (xy 379.132338 -229.882446)
			(xy 379.179328 -230.034846) (xy 379.440948 -230.034846)
		)
		(stroke
			(width 0)
			(type solid)
		)
		(fill yes)
		(layer "In11.Cu")
		(net "M_H_CPU0_SB_DQ<26>")
	)
	(gr_poly
		(pts
			(xy 379.487938 -227.035614) (xy 379.440948 -226.883214) (xy 379.179328 -226.883214) (xy 379.132338 -227.035614)
			(xy 379.132338 -227.07981) (xy 379.487938 -227.07981)
		)
		(stroke
			(width 0)
			(type solid)
		)
		(fill yes)
		(layer "In11.Cu")
		(net "M_H_CPU0_SB_DQS_DN<3>")
	)
	(gr_poly
		(pts
			(xy 379.487938 -226.626674) (xy 379.487938 -226.582478) (xy 379.132338 -226.582478) (xy 379.132338 -226.626674)
			(xy 379.179328 -226.779074) (xy 379.440948 -226.779074)
		)
		(stroke
			(width 0)
			(type solid)
		)
		(fill yes)
		(layer "In11.Cu")
		(net "M_H_CPU0_SB_DQ<30>")
	)
	(gr_poly
		(pts
			(xy 379.49378 -246.568722) (xy 379.44679 -246.416322) (xy 379.18517 -246.416322) (xy 379.13818 -246.568722)
			(xy 379.13818 -246.613172) (xy 379.49378 -246.613172)
		)
		(stroke
			(width 0)
			(type solid)
		)
		(fill yes)
		(layer "In11.Cu")
		(net "M_H_CPU0_SB_CA<5>")
	)
	(gr_poly
		(pts
			(xy 379.494288 -241.685826) (xy 379.447298 -241.533426) (xy 379.185678 -241.533426) (xy 379.138688 -241.685826)
			(xy 379.138688 -241.730022) (xy 379.494288 -241.730022)
		)
		(stroke
			(width 0)
			(type solid)
		)
		(fill yes)
		(layer "In11.Cu")
		(net "M_H_CPU0_SB_DQS_DP<4>")
	)
	(gr_poly
		(pts
			(xy 379.494288 -236.802422) (xy 379.447298 -236.650022) (xy 379.185678 -236.650022) (xy 379.138688 -236.802422)
			(xy 379.138688 -236.846872) (xy 379.494288 -236.846872)
		)
		(stroke
			(width 0)
			(type solid)
		)
		(fill yes)
		(layer "In11.Cu")
		(net "M_H_CPU0_SB_DQS_DP<5>")
	)
	(gr_poly
		(pts
			(xy 379.494288 -231.919018) (xy 379.447298 -231.766618) (xy 379.185678 -231.766618) (xy 379.138688 -231.919018)
			(xy 379.138688 -231.963468) (xy 379.494288 -231.963468)
		)
		(stroke
			(width 0)
			(type solid)
		)
		(fill yes)
		(layer "In11.Cu")
		(net "M_H_CPU0_SB_DQS_DP<6>")
	)
	(gr_poly
		(pts
			(xy 379.499876 -247.787922) (xy 379.499876 -247.743472) (xy 379.144276 -247.743472) (xy 379.144276 -247.787922)
			(xy 379.191266 -247.940322) (xy 379.452886 -247.940322)
		)
		(stroke
			(width 0)
			(type solid)
		)
		(fill yes)
		(layer "In11.Cu")
		(net "M_H_CPU0_SB_CA<2>")
	)
	(gr_poly
		(pts
			(xy 379.569218 -270.853916) (xy 379.677676 -270.737076) (xy 379.546866 -270.510508) (xy 379.391418 -270.546068)
			(xy 379.353064 -270.568166) (xy 379.530864 -270.876014)
		)
		(stroke
			(width 0)
			(type solid)
		)
		(fill yes)
		(layer "In11.Cu")
		(net "M_H_CPU0_SA_DQ<22>")
	)
	(gr_poly
		(pts
			(xy 379.569218 -269.22603) (xy 379.677676 -269.10919) (xy 379.546866 -268.882622) (xy 379.391418 -268.918182)
			(xy 379.353064 -268.94028) (xy 379.530864 -269.248128)
		)
		(stroke
			(width 0)
			(type solid)
		)
		(fill yes)
		(layer "In11.Cu")
		(net "M_H_CPU0_SA_DQ<23>")
	)
	(gr_poly
		(pts
			(xy 379.569472 -272.48231) (xy 379.67793 -272.36547) (xy 379.54712 -272.138902) (xy 379.391672 -272.174462)
			(xy 379.353318 -272.19656) (xy 379.531118 -272.504408)
		)
		(stroke
			(width 0)
			(type solid)
		)
		(fill yes)
		(layer "In11.Cu")
		(net "M_H_CPU0_SA_DQS_DP<7>")
	)
	(gr_poly
		(pts
			(xy 379.569472 -267.598906) (xy 379.67793 -267.482066) (xy 379.54712 -267.255498) (xy 379.391672 -267.291058)
			(xy 379.353318 -267.313156) (xy 379.531118 -267.621004)
		)
		(stroke
			(width 0)
			(type solid)
		)
		(fill yes)
		(layer "In11.Cu")
		(net "M_H_CPU0_SA_DQ<26>")
	)
	(gr_poly
		(pts
			(xy 379.59538 -280.98242) (xy 379.54839 -280.83002) (xy 379.28677 -280.83002) (xy 379.23978 -280.98242)
			(xy 379.23978 -281.026616) (xy 379.59538 -281.026616)
		)
		(stroke
			(width 0)
			(type solid)
		)
		(fill yes)
		(layer "In11.Cu")
		(net "M_H_CPU0_SA_DQ<10>")
	)
	(gr_poly
		(pts
			(xy 379.59538 -280.574242) (xy 379.59538 -280.529792) (xy 379.23978 -280.529792) (xy 379.23978 -280.574242)
			(xy 379.28677 -280.726642) (xy 379.54839 -280.726642)
		)
		(stroke
			(width 0)
			(type solid)
		)
		(fill yes)
		(layer "In11.Cu")
		(net "M_H_CPU0_SA_DQ<9>")
	)
	(gr_poly
		(pts
			(xy 379.59538 -275.690584) (xy 379.59538 -275.646388) (xy 379.23978 -275.646388) (xy 379.23978 -275.690584)
			(xy 379.28677 -275.842984) (xy 379.54839 -275.842984)
		)
		(stroke
			(width 0)
			(type solid)
		)
		(fill yes)
		(layer "In11.Cu")
		(net "M_H_CPU0_SA_DQ<16>")
	)
	(gr_poly
		(pts
			(xy 379.59538 -274.47113) (xy 379.54839 -274.31873) (xy 379.28677 -274.31873) (xy 379.23978 -274.47113)
			(xy 379.23978 -274.515326) (xy 379.59538 -274.515326)
		)
		(stroke
			(width 0)
			(type solid)
		)
		(fill yes)
		(layer "In11.Cu")
		(net "M_H_CPU0_SA_DQ<19>")
	)
	(gr_poly
		(pts
			(xy 379.59538 -274.062698) (xy 379.59538 -274.018502) (xy 379.23978 -274.018502) (xy 379.23978 -274.062698)
			(xy 379.28677 -274.215098) (xy 379.54839 -274.215098)
		)
		(stroke
			(width 0)
			(type solid)
		)
		(fill yes)
		(layer "In11.Cu")
		(net "M_H_CPU0_SA_DQS_DP<2>")
	)
	(gr_poly
		(pts
			(xy 379.59538 -266.331954) (xy 379.54839 -266.179554) (xy 379.28677 -266.179554) (xy 379.23978 -266.331954)
			(xy 379.23978 -266.376404) (xy 379.59538 -266.376404)
		)
		(stroke
			(width 0)
			(type solid)
		)
		(fill yes)
		(layer "In11.Cu")
		(net "M_H_CPU0_SA_DQ<27>")
	)
	(gr_poly
		(pts
			(xy 379.59538 -265.92403) (xy 379.59538 -265.879834) (xy 379.23978 -265.879834) (xy 379.23978 -265.92403)
			(xy 379.28677 -266.07643) (xy 379.54839 -266.07643)
		)
		(stroke
			(width 0)
			(type solid)
		)
		(fill yes)
		(layer "In11.Cu")
		(net "M_H_CPU0_SA_DQS_DP<3>")
	)
	(gr_poly
		(pts
			(xy 379.59538 -264.704322) (xy 379.54839 -264.551922) (xy 379.28677 -264.551922) (xy 379.23978 -264.704322)
			(xy 379.23978 -264.748772) (xy 379.59538 -264.748772)
		)
		(stroke
			(width 0)
			(type solid)
		)
		(fill yes)
		(layer "In11.Cu")
		(net "M_H_CPU0_SA_DQS_DP<8>")
	)
	(gr_poly
		(pts
			(xy 379.59538 -264.296398) (xy 379.59538 -264.251948) (xy 379.23978 -264.251948) (xy 379.23978 -264.296398)
			(xy 379.28677 -264.448798) (xy 379.54839 -264.448798)
		)
		(stroke
			(width 0)
			(type solid)
		)
		(fill yes)
		(layer "In11.Cu")
		(net "M_H_CPU0_SA_DQ<28>")
	)
	(gr_poly
		(pts
			(xy 379.59538 -261.449058) (xy 379.54839 -261.296658) (xy 379.28677 -261.296658) (xy 379.23978 -261.449058)
			(xy 379.23978 -261.493254) (xy 379.59538 -261.493254)
		)
		(stroke
			(width 0)
			(type solid)
		)
		(fill yes)
		(layer "In11.Cu")
		(net "M_H_CPU0_SA_CB<3>")
	)
	(gr_poly
		(pts
			(xy 379.59538 -261.040626) (xy 379.59538 -260.99643) (xy 379.23978 -260.99643) (xy 379.23978 -261.040626)
			(xy 379.28677 -261.193026) (xy 379.54839 -261.193026)
		)
		(stroke
			(width 0)
			(type solid)
		)
		(fill yes)
		(layer "In11.Cu")
		(net "M_H_CPU0_SA_DQS_DP<4>")
	)
	(gr_poly
		(pts
			(xy 379.59538 -259.820918) (xy 379.54839 -259.668518) (xy 379.28677 -259.668518) (xy 379.23978 -259.820918)
			(xy 379.23978 -259.865368) (xy 379.59538 -259.865368)
		)
		(stroke
			(width 0)
			(type solid)
		)
		(fill yes)
		(layer "In11.Cu")
		(net "M_H_CPU0_SA_DQS_DP<9>")
	)
	(gr_poly
		(pts
			(xy 379.59538 -259.412994) (xy 379.59538 -259.368544) (xy 379.23978 -259.368544) (xy 379.23978 -259.412994)
			(xy 379.28677 -259.565394) (xy 379.54839 -259.565394)
		)
		(stroke
			(width 0)
			(type solid)
		)
		(fill yes)
		(layer "In11.Cu")
		(net "M_H_CPU0_SA_CB<4>")
	)
	(gr_poly
		(pts
			(xy 379.59538 -256.565654) (xy 379.54839 -256.413254) (xy 379.28677 -256.413254) (xy 379.23978 -256.565654)
			(xy 379.23978 -256.60985) (xy 379.59538 -256.60985)
		)
		(stroke
			(width 0)
			(type solid)
		)
		(fill yes)
		(layer "In11.Cu")
		(net "M_H_CPU0_SA_CS_N<1>")
	)
	(gr_poly
		(pts
			(xy 379.59538 -256.157222) (xy 379.59538 -256.113026) (xy 379.23978 -256.113026) (xy 379.23978 -256.157222)
			(xy 379.28677 -256.309622) (xy 379.54839 -256.309622)
		)
		(stroke
			(width 0)
			(type solid)
		)
		(fill yes)
		(layer "In11.Cu")
		(net "M_H_CPU0_SA_CS_N<2>")
	)
	(gr_poly
		(pts
			(xy 379.59538 -254.937514) (xy 379.54839 -254.785114) (xy 379.28677 -254.785114) (xy 379.23978 -254.937514)
			(xy 379.23978 -254.981964) (xy 379.59538 -254.981964)
		)
		(stroke
			(width 0)
			(type solid)
		)
		(fill yes)
		(layer "In11.Cu")
		(net "M_H_CPU0_SA_CA<0>")
	)
	(gr_poly
		(pts
			(xy 379.59792 -279.354534) (xy 379.55093 -279.202134) (xy 379.28931 -279.202134) (xy 379.24232 -279.354534)
			(xy 379.24232 -279.39873) (xy 379.59792 -279.39873)
		)
		(stroke
			(width 0)
			(type solid)
		)
		(fill yes)
		(layer "In11.Cu")
		(net "M_H_CPU0_SA_DQS_DN<1>")
	)
	(gr_poly
		(pts
			(xy 379.59792 -278.946102) (xy 379.59792 -278.901906) (xy 379.24232 -278.901906) (xy 379.24232 -278.946102)
			(xy 379.28931 -279.098502) (xy 379.55093 -279.098502)
		)
		(stroke
			(width 0)
			(type solid)
		)
		(fill yes)
		(layer "In11.Cu")
		(net "M_H_CPU0_SA_DQS_DN<6>")
	)
	(gr_poly
		(pts
			(xy 379.59792 -277.726902) (xy 379.55093 -277.574502) (xy 379.28931 -277.574502) (xy 379.24232 -277.726902)
			(xy 379.24232 -277.771098) (xy 379.59792 -277.771098)
		)
		(stroke
			(width 0)
			(type solid)
		)
		(fill yes)
		(layer "In11.Cu")
		(net "M_H_CPU0_SA_DQ<14>")
	)
	(gr_poly
		(pts
			(xy 379.59792 -277.317962) (xy 379.59792 -277.273766) (xy 379.24232 -277.273766) (xy 379.24232 -277.317962)
			(xy 379.28931 -277.470362) (xy 379.55093 -277.470362)
		)
		(stroke
			(width 0)
			(type solid)
		)
		(fill yes)
		(layer "In11.Cu")
		(net "M_H_CPU0_SA_DQ<13>")
	)
	(gr_poly
		(pts
			(xy 379.59792 -263.07669) (xy 379.55093 -262.92429) (xy 379.28931 -262.92429) (xy 379.24232 -263.07669)
			(xy 379.24232 -263.120886) (xy 379.59792 -263.120886)
		)
		(stroke
			(width 0)
			(type solid)
		)
		(fill yes)
		(layer "In11.Cu")
		(net "M_H_CPU0_SA_DQ<31>")
	)
	(gr_poly
		(pts
			(xy 379.59792 -262.668258) (xy 379.59792 -262.624062) (xy 379.24232 -262.624062) (xy 379.24232 -262.668258)
			(xy 379.28931 -262.820658) (xy 379.55093 -262.820658)
		)
		(stroke
			(width 0)
			(type solid)
		)
		(fill yes)
		(layer "In11.Cu")
		(net "M_H_CPU0_SA_CB<0>")
	)
	(gr_poly
		(pts
			(xy 379.59792 -258.193286) (xy 379.55093 -258.040886) (xy 379.28931 -258.040886) (xy 379.24232 -258.193286)
			(xy 379.24232 -258.237482) (xy 379.59792 -258.237482)
		)
		(stroke
			(width 0)
			(type solid)
		)
		(fill yes)
		(layer "In11.Cu")
		(net "M_H_CPU0_SA_CB<7>")
	)
	(gr_poly
		(pts
			(xy 379.59792 -257.784854) (xy 379.59792 -257.740658) (xy 379.24232 -257.740658) (xy 379.24232 -257.784854)
			(xy 379.28931 -257.937254) (xy 379.55093 -257.937254)
		)
		(stroke
			(width 0)
			(type solid)
		)
		(fill yes)
		(layer "In11.Cu")
		(net "M_E_CPU0_ALERT_N")
	)
	(gr_poly
		(pts
			(xy 379.609858 -254.52959) (xy 379.609858 -254.48514) (xy 379.254258 -254.48514) (xy 379.254258 -254.52959)
			(xy 379.301248 -254.68199) (xy 379.562868 -254.68199)
		)
		(stroke
			(width 0)
			(type solid)
		)
		(fill yes)
		(layer "In11.Cu")
		(net "M_H_CPU0_SA_CA<2>")
	)
	(gr_poly
		(pts
			(xy 379.930406 -272.290032) (xy 379.96876 -272.267934) (xy 379.79096 -271.960086) (xy 379.752606 -271.982184)
			(xy 379.644148 -272.099024) (xy 379.774958 -272.325592)
		)
		(stroke
			(width 0)
			(type solid)
		)
		(fill yes)
		(layer "In11.Cu")
		(net "M_H_CPU0_SA_DQ<20>")
	)
	(gr_poly
		(pts
			(xy 379.930406 -267.406628) (xy 379.96876 -267.38453) (xy 379.79096 -267.076682) (xy 379.752606 -267.09878)
			(xy 379.644148 -267.21562) (xy 379.774958 -267.442188)
		)
		(stroke
			(width 0)
			(type solid)
		)
		(fill yes)
		(layer "In11.Cu")
		(net "M_H_CPU0_SA_DQ<25>")
	)
	(gr_poly
		(pts
			(xy 379.93066 -269.035022) (xy 379.969014 -269.012924) (xy 379.791214 -268.705076) (xy 379.75286 -268.727174)
			(xy 379.644402 -268.844014) (xy 379.775212 -269.070582)
		)
		(stroke
			(width 0)
			(type solid)
		)
		(fill yes)
		(layer "In11.Cu")
		(net "M_H_CPU0_SA_DQ<24>")
	)
	(gr_poly
		(pts
			(xy 379.957838 -240.46307) (xy 379.957838 -240.41862) (xy 379.602238 -240.41862) (xy 379.602238 -240.46307)
			(xy 379.649228 -240.61547) (xy 379.910848 -240.61547)
		)
		(stroke
			(width 0)
			(type solid)
		)
		(fill yes)
		(layer "In11.Cu")
		(net "M_H_CPU0_SB_CB<1>")
	)
	(gr_poly
		(pts
			(xy 379.957838 -235.579666) (xy 379.957838 -235.535216) (xy 379.602238 -235.535216) (xy 379.602238 -235.579666)
			(xy 379.649228 -235.732066) (xy 379.910848 -235.732066)
		)
		(stroke
			(width 0)
			(type solid)
		)
		(fill yes)
		(layer "In11.Cu")
		(net "M_H_CPU0_SB_DQ<5>")
	)
	(gr_poly
		(pts
			(xy 379.957838 -230.696262) (xy 379.957838 -230.651812) (xy 379.602238 -230.651812) (xy 379.602238 -230.696262)
			(xy 379.649228 -230.848662) (xy 379.910848 -230.848662)
		)
		(stroke
			(width 0)
			(type solid)
		)
		(fill yes)
		(layer "In11.Cu")
		(net "M_H_CPU0_SB_DQ<13>")
	)
	(gr_poly
		(pts
			(xy 379.963934 -244.127274) (xy 379.916944 -243.974874) (xy 379.655324 -243.974874) (xy 379.608334 -244.127274)
			(xy 379.608334 -244.17147) (xy 379.963934 -244.17147)
		)
		(stroke
			(width 0)
			(type solid)
		)
		(fill yes)
		(layer "In11.Cu")
		(net "M_H_CPU0_SB_CB<4>")
	)
	(gr_poly
		(pts
			(xy 379.963934 -239.24387) (xy 379.916944 -239.09147) (xy 379.655324 -239.09147) (xy 379.608334 -239.24387)
			(xy 379.608334 -239.288066) (xy 379.963934 -239.288066)
		)
		(stroke
			(width 0)
			(type solid)
		)
		(fill yes)
		(layer "In11.Cu")
		(net "M_H_CPU0_SB_DQ<2>")
	)
	(gr_poly
		(pts
			(xy 379.963934 -234.360466) (xy 379.916944 -234.208066) (xy 379.655324 -234.208066) (xy 379.608334 -234.360466)
			(xy 379.608334 -234.404916) (xy 379.963934 -234.404916)
		)
		(stroke
			(width 0)
			(type solid)
		)
		(fill yes)
		(layer "In11.Cu")
		(net "M_H_CPU0_SB_DQ<10>")
	)
	(gr_poly
		(pts
			(xy 379.963934 -229.477062) (xy 379.916944 -229.324662) (xy 379.655324 -229.324662) (xy 379.608334 -229.477062)
			(xy 379.608334 -229.521512) (xy 379.963934 -229.521512)
		)
		(stroke
			(width 0)
			(type solid)
		)
		(fill yes)
		(layer "In11.Cu")
		(net "M_H_CPU0_SB_DQ<24>")
	)
	(gr_poly
		(pts
			(xy 379.969776 -247.382538) (xy 379.922786 -247.230138) (xy 379.661166 -247.230138) (xy 379.614176 -247.382538)
			(xy 379.614176 -247.426734) (xy 379.969776 -247.426734)
		)
		(stroke
			(width 0)
			(type solid)
		)
		(fill yes)
		(layer "In11.Cu")
		(net "M_H_CPU0_SB_CA<3>")
	)
	(gr_poly
		(pts
			(xy 379.969776 -246.974106) (xy 379.969776 -246.92991) (xy 379.614176 -246.92991) (xy 379.614176 -246.974106)
			(xy 379.661166 -247.126506) (xy 379.922786 -247.126506)
		)
		(stroke
			(width 0)
			(type solid)
		)
		(fill yes)
		(layer "In11.Cu")
		(net "M_H_CPU0_SB_CA<4>")
	)
	(gr_poly
		(pts
			(xy 379.969776 -245.754906) (xy 379.922786 -245.602506) (xy 379.661166 -245.602506) (xy 379.614176 -245.754906)
			(xy 379.614176 -245.799356) (xy 379.969776 -245.799356)
		)
		(stroke
			(width 0)
			(type solid)
		)
		(fill yes)
		(layer "In11.Cu")
		(net "M_H_CPU0_SB_PAR")
	)
	(gr_poly
		(pts
			(xy 379.969776 -240.871502) (xy 379.922786 -240.719102) (xy 379.661166 -240.719102) (xy 379.614176 -240.871502)
			(xy 379.614176 -240.915952) (xy 379.969776 -240.915952)
		)
		(stroke
			(width 0)
			(type solid)
		)
		(fill yes)
		(layer "In11.Cu")
		(net "M_H_CPU0_SB_CB<2>")
	)
	(gr_poly
		(pts
			(xy 379.969776 -235.988098) (xy 379.922786 -235.835698) (xy 379.661166 -235.835698) (xy 379.614176 -235.988098)
			(xy 379.614176 -236.032548) (xy 379.969776 -236.032548)
		)
		(stroke
			(width 0)
			(type solid)
		)
		(fill yes)
		(layer "In11.Cu")
		(net "M_H_CPU0_SB_DQ<6>")
	)
	(gr_poly
		(pts
			(xy 379.969776 -231.104694) (xy 379.922786 -230.952294) (xy 379.661166 -230.952294) (xy 379.614176 -231.104694)
			(xy 379.614176 -231.149144) (xy 379.969776 -231.149144)
		)
		(stroke
			(width 0)
			(type solid)
		)
		(fill yes)
		(layer "In11.Cu")
		(net "M_H_CPU0_SB_DQ<14>")
	)
	(gr_poly
		(pts
			(xy 379.972316 -248.602246) (xy 379.972316 -248.557796) (xy 379.616716 -248.557796) (xy 379.616716 -248.602246)
			(xy 379.663706 -248.754646) (xy 379.925326 -248.754646)
		)
		(stroke
			(width 0)
			(type solid)
		)
		(fill yes)
		(layer "In11.Cu")
		(net "M_H_CPU0_SB_CA<0>")
	)
	(gr_poly
		(pts
			(xy 379.972316 -243.718842) (xy 379.972316 -243.674392) (xy 379.616716 -243.674392) (xy 379.616716 -243.718842)
			(xy 379.663706 -243.871242) (xy 379.925326 -243.871242)
		)
		(stroke
			(width 0)
			(type solid)
		)
		(fill yes)
		(layer "In11.Cu")
		(net "M_H_CPU0_SB_CB<7>")
	)
	(gr_poly
		(pts
			(xy 379.972316 -242.499134) (xy 379.925326 -242.346734) (xy 379.663706 -242.346734) (xy 379.616716 -242.499134)
			(xy 379.616716 -242.54333) (xy 379.972316 -242.54333)
		)
		(stroke
			(width 0)
			(type solid)
		)
		(fill yes)
		(layer "In11.Cu")
		(net "M_H_CPU0_SB_DQS_DN<9>")
	)
	(gr_poly
		(pts
			(xy 379.972316 -242.090702) (xy 379.972316 -242.046506) (xy 379.616716 -242.046506) (xy 379.616716 -242.090702)
			(xy 379.663706 -242.243102) (xy 379.925326 -242.243102)
		)
		(stroke
			(width 0)
			(type solid)
		)
		(fill yes)
		(layer "In11.Cu")
		(net "M_H_CPU0_SB_DQS_DN<4>")
	)
	(gr_poly
		(pts
			(xy 379.972316 -238.835438) (xy 379.972316 -238.790988) (xy 379.616716 -238.790988) (xy 379.616716 -238.835438)
			(xy 379.663706 -238.987838) (xy 379.925326 -238.987838)
		)
		(stroke
			(width 0)
			(type solid)
		)
		(fill yes)
		(layer "In11.Cu")
		(net "M_H_CPU0_SB_DQ<1>")
	)
	(gr_poly
		(pts
			(xy 379.972316 -237.61573) (xy 379.925326 -237.46333) (xy 379.663706 -237.46333) (xy 379.616716 -237.61573)
			(xy 379.616716 -237.66018) (xy 379.972316 -237.66018)
		)
		(stroke
			(width 0)
			(type solid)
		)
		(fill yes)
		(layer "In11.Cu")
		(net "M_H_CPU0_SB_DQS_DN<0>")
	)
	(gr_poly
		(pts
			(xy 379.972316 -237.207806) (xy 379.972316 -237.163356) (xy 379.616716 -237.163356) (xy 379.616716 -237.207806)
			(xy 379.663706 -237.360206) (xy 379.925326 -237.360206)
		)
		(stroke
			(width 0)
			(type solid)
		)
		(fill yes)
		(layer "In11.Cu")
		(net "M_H_CPU0_SB_DQS_DN<5>")
	)
	(gr_poly
		(pts
			(xy 379.972316 -233.952034) (xy 379.972316 -233.907838) (xy 379.616716 -233.907838) (xy 379.616716 -233.952034)
			(xy 379.663706 -234.104434) (xy 379.925326 -234.104434)
		)
		(stroke
			(width 0)
			(type solid)
		)
		(fill yes)
		(layer "In11.Cu")
		(net "M_H_CPU0_SB_DQ<9>")
	)
	(gr_poly
		(pts
			(xy 379.972316 -232.732326) (xy 379.925326 -232.579926) (xy 379.663706 -232.579926) (xy 379.616716 -232.732326)
			(xy 379.616716 -232.776776) (xy 379.972316 -232.776776)
		)
		(stroke
			(width 0)
			(type solid)
		)
		(fill yes)
		(layer "In11.Cu")
		(net "M_H_CPU0_SB_DQS_DN<1>")
	)
	(gr_poly
		(pts
			(xy 379.972316 -232.324402) (xy 379.972316 -232.279952) (xy 379.616716 -232.279952) (xy 379.616716 -232.324402)
			(xy 379.663706 -232.476802) (xy 379.925326 -232.476802)
		)
		(stroke
			(width 0)
			(type solid)
		)
		(fill yes)
		(layer "In11.Cu")
		(net "M_H_CPU0_SB_DQS_DN<6>")
	)
	(gr_poly
		(pts
			(xy 379.972316 -229.06863) (xy 379.972316 -229.024434) (xy 379.616716 -229.024434) (xy 379.616716 -229.06863)
			(xy 379.663706 -229.22103) (xy 379.925326 -229.22103)
		)
		(stroke
			(width 0)
			(type solid)
		)
		(fill yes)
		(layer "In11.Cu")
		(net "M_H_CPU0_SB_DQ<27>")
	)
	(gr_poly
		(pts
			(xy 379.972316 -227.848922) (xy 379.925326 -227.696522) (xy 379.663706 -227.696522) (xy 379.616716 -227.848922)
			(xy 379.616716 -227.893372) (xy 379.972316 -227.893372)
		)
		(stroke
			(width 0)
			(type solid)
		)
		(fill yes)
		(layer "In11.Cu")
		(net "M_H_CPU0_SB_DQS_DP<8>")
	)
	(gr_poly
		(pts
			(xy 379.972316 -227.440998) (xy 379.972316 -227.396548) (xy 379.616716 -227.396548) (xy 379.616716 -227.440998)
			(xy 379.663706 -227.593398) (xy 379.925326 -227.593398)
		)
		(stroke
			(width 0)
			(type solid)
		)
		(fill yes)
		(layer "In11.Cu")
		(net "M_H_CPU0_SB_DQS_DP<3>")
	)
	(gr_poly
		(pts
			(xy 379.972316 -226.22129) (xy 379.925326 -226.06889) (xy 379.663706 -226.06889) (xy 379.616716 -226.22129)
			(xy 379.616716 -226.26574) (xy 379.972316 -226.26574)
		)
		(stroke
			(width 0)
			(type solid)
		)
		(fill yes)
		(layer "In11.Cu")
		(net "M_H_CPU0_SB_DQ<28>")
	)
	(gr_poly
		(pts
			(xy 379.972316 -225.813366) (xy 379.972316 -225.768916) (xy 379.616716 -225.768916) (xy 379.616716 -225.813366)
			(xy 379.663706 -225.965766) (xy 379.925326 -225.965766)
		)
		(stroke
			(width 0)
			(type solid)
		)
		(fill yes)
		(layer "In11.Cu")
		(net "M_H_CPU0_SB_DQ<31>")
	)
	(gr_poly
		(pts
			(xy 380.040388 -268.414754) (xy 380.148846 -268.297914) (xy 380.018036 -268.071346) (xy 379.862588 -268.106906)
			(xy 379.824234 -268.129004) (xy 380.002034 -268.436852)
		)
		(stroke
			(width 0)
			(type solid)
		)
		(fill yes)
		(layer "In11.Cu")
		(net "M_H_CPU0_SA_DQ<26>")
	)
	(gr_poly
		(pts
			(xy 380.044706 -271.677384) (xy 380.153164 -271.560544) (xy 380.022354 -271.333976) (xy 379.866906 -271.369536)
			(xy 379.828552 -271.391634) (xy 380.006352 -271.699482)
		)
		(stroke
			(width 0)
			(type solid)
		)
		(fill yes)
		(layer "In11.Cu")
		(net "M_H_CPU0_SA_DQ<22>")
	)
	(gr_poly
		(pts
			(xy 380.044706 -266.79398) (xy 380.153164 -266.67714) (xy 380.022354 -266.450572) (xy 379.866906 -266.486132)
			(xy 379.828552 -266.50823) (xy 380.006352 -266.816078)
		)
		(stroke
			(width 0)
			(type solid)
		)
		(fill yes)
		(layer "In11.Cu")
		(net "M_H_CPU0_SA_DQ<27>")
	)
	(gr_poly
		(pts
			(xy 380.065534 -255.343406) (xy 380.065534 -255.29921) (xy 379.709934 -255.29921) (xy 379.709934 -255.343406)
			(xy 379.756924 -255.495806) (xy 380.018544 -255.495806)
		)
		(stroke
			(width 0)
			(type solid)
		)
		(fill yes)
		(layer "In11.Cu")
		(net "M_H_CPU0_SA_CA<1>")
	)
	(gr_poly
		(pts
			(xy 380.065534 -254.123698) (xy 380.018544 -253.971298) (xy 379.756924 -253.971298) (xy 379.709934 -254.123698)
			(xy 379.709934 -254.168148) (xy 380.065534 -254.168148)
		)
		(stroke
			(width 0)
			(type solid)
		)
		(fill yes)
		(layer "In11.Cu")
		(net "M_H_CPU0_SA_CA<3>")
	)
	(gr_poly
		(pts
			(xy 380.06782 -279.759664) (xy 380.06782 -279.715468) (xy 379.71222 -279.715468) (xy 379.71222 -279.759664)
			(xy 379.75921 -279.912064) (xy 380.02083 -279.912064)
		)
		(stroke
			(width 0)
			(type solid)
		)
		(fill yes)
		(layer "In11.Cu")
		(net "M_H_CPU0_SA_DQS_DP<1>")
	)
	(gr_poly
		(pts
			(xy 380.06782 -262.262874) (xy 380.02083 -262.110474) (xy 379.75921 -262.110474) (xy 379.71222 -262.262874)
			(xy 379.71222 -262.307324) (xy 380.06782 -262.307324)
		)
		(stroke
			(width 0)
			(type solid)
		)
		(fill yes)
		(layer "In11.Cu")
		(net "M_H_CPU0_SA_CB<2>")
	)
	(gr_poly
		(pts
			(xy 380.06782 -257.37947) (xy 380.02083 -257.22707) (xy 379.75921 -257.22707) (xy 379.71222 -257.37947)
			(xy 379.71222 -257.42392) (xy 380.06782 -257.42392)
		)
		(stroke
			(width 0)
			(type solid)
		)
		(fill yes)
		(layer "In11.Cu")
		(net "M_H_CPU0_ALERT_N")
	)
	(gr_poly
		(pts
			(xy 380.073916 -278.540718) (xy 380.026926 -278.388318) (xy 379.765306 -278.388318) (xy 379.718316 -278.540718)
			(xy 379.718316 -278.585168) (xy 380.073916 -278.585168)
		)
		(stroke
			(width 0)
			(type solid)
		)
		(fill yes)
		(layer "In11.Cu")
		(net "M_H_CPU0_SA_DQS_DP<6>")
	)
	(gr_poly
		(pts
			(xy 380.073916 -273.248882) (xy 380.073916 -273.204432) (xy 379.718316 -273.204432) (xy 379.718316 -273.248882)
			(xy 379.765306 -273.401282) (xy 380.026926 -273.401282)
		)
		(stroke
			(width 0)
			(type solid)
		)
		(fill yes)
		(layer "In11.Cu")
		(net "M_H_CPU0_SA_DQS_DN<7>")
	)
	(gr_poly
		(pts
			(xy 380.073916 -263.482074) (xy 380.073916 -263.437878) (xy 379.718316 -263.437878) (xy 379.718316 -263.482074)
			(xy 379.765306 -263.634474) (xy 380.026926 -263.634474)
		)
		(stroke
			(width 0)
			(type solid)
		)
		(fill yes)
		(layer "In11.Cu")
		(net "M_H_CPU0_SA_DQ<29>")
	)
	(gr_poly
		(pts
			(xy 380.073916 -258.59867) (xy 380.073916 -258.554474) (xy 379.718316 -258.554474) (xy 379.718316 -258.59867)
			(xy 379.765306 -258.75107) (xy 380.026926 -258.75107)
		)
		(stroke
			(width 0)
			(type solid)
		)
		(fill yes)
		(layer "In11.Cu")
		(net "M_H_CPU0_SA_CB<5>")
	)
	(gr_poly
		(pts
			(xy 380.079758 -280.16835) (xy 380.032768 -280.01595) (xy 379.771148 -280.01595) (xy 379.724158 -280.16835)
			(xy 379.724158 -280.2128) (xy 380.079758 -280.2128)
		)
		(stroke
			(width 0)
			(type solid)
		)
		(fill yes)
		(layer "In11.Cu")
		(net "M_H_CPU0_SA_DQ<11>")
	)
	(gr_poly
		(pts
			(xy 380.079758 -276.913086) (xy 380.032768 -276.760686) (xy 379.771148 -276.760686) (xy 379.724158 -276.913086)
			(xy 379.724158 -276.957282) (xy 380.079758 -276.957282)
		)
		(stroke
			(width 0)
			(type solid)
		)
		(fill yes)
		(layer "In11.Cu")
		(net "M_H_CPU0_SA_DQ<15>")
	)
	(gr_poly
		(pts
			(xy 380.079758 -261.854442) (xy 380.079758 -261.809992) (xy 379.724158 -261.809992) (xy 379.724158 -261.854442)
			(xy 379.771148 -262.006842) (xy 380.032768 -262.006842)
		)
		(stroke
			(width 0)
			(type solid)
		)
		(fill yes)
		(layer "In11.Cu")
		(net "M_H_CPU0_SA_CB<1>")
	)
	(gr_poly
		(pts
			(xy 380.079758 -256.971038) (xy 380.079758 -256.926588) (xy 379.724158 -256.926588) (xy 379.724158 -256.971038)
			(xy 379.771148 -257.123438) (xy 380.032768 -257.123438)
		)
		(stroke
			(width 0)
			(type solid)
		)
		(fill yes)
		(layer "In11.Cu")
		(net "M_H_CPU0_SA_CS_N<0>")
	)
	(gr_poly
		(pts
			(xy 380.079758 -255.751838) (xy 380.032768 -255.599438) (xy 379.771148 -255.599438) (xy 379.724158 -255.751838)
			(xy 379.724158 -255.796288) (xy 380.079758 -255.796288)
		)
		(stroke
			(width 0)
			(type solid)
		)
		(fill yes)
		(layer "In11.Cu")
		(net "M_H_CPU0_SA_CS_N<3>")
	)
	(gr_poly
		(pts
			(xy 380.082298 -281.387804) (xy 380.082298 -281.343608) (xy 379.726698 -281.343608) (xy 379.726698 -281.387804)
			(xy 379.773688 -281.540204) (xy 380.035308 -281.540204)
		)
		(stroke
			(width 0)
			(type solid)
		)
		(fill yes)
		(layer "In11.Cu")
		(net "M_H_CPU0_SA_DQ<8>")
	)
	(gr_poly
		(pts
			(xy 380.082298 -278.132286) (xy 380.082298 -278.08809) (xy 379.726698 -278.08809) (xy 379.726698 -278.132286)
			(xy 379.773688 -278.284686) (xy 380.035308 -278.284686)
		)
		(stroke
			(width 0)
			(type solid)
		)
		(fill yes)
		(layer "In11.Cu")
		(net "M_H_CPU0_SA_DQ<12>")
	)
	(gr_poly
		(pts
			(xy 380.082298 -275.284946) (xy 380.035308 -275.132546) (xy 379.773688 -275.132546) (xy 379.726698 -275.284946)
			(xy 379.726698 -275.329142) (xy 380.082298 -275.329142)
		)
		(stroke
			(width 0)
			(type solid)
		)
		(fill yes)
		(layer "In11.Cu")
		(net "M_H_CPU0_SA_DQ<18>")
	)
	(gr_poly
		(pts
			(xy 380.082298 -274.876514) (xy 380.082298 -274.832318) (xy 379.726698 -274.832318) (xy 379.726698 -274.876514)
			(xy 379.773688 -275.028914) (xy 380.035308 -275.028914)
		)
		(stroke
			(width 0)
			(type solid)
		)
		(fill yes)
		(layer "In11.Cu")
		(net "M_H_CPU0_SA_DQ<17>")
	)
	(gr_poly
		(pts
			(xy 380.082298 -273.657314) (xy 380.035308 -273.504914) (xy 379.773688 -273.504914) (xy 379.726698 -273.657314)
			(xy 379.726698 -273.70151) (xy 380.082298 -273.70151)
		)
		(stroke
			(width 0)
			(type solid)
		)
		(fill yes)
		(layer "In11.Cu")
		(net "M_H_CPU0_SA_DQS_DN<2>")
	)
	(gr_poly
		(pts
			(xy 380.082298 -269.993618) (xy 380.082298 -269.949168) (xy 379.726698 -269.949168) (xy 379.726698 -269.993618)
			(xy 379.773688 -270.146018) (xy 380.035308 -270.146018)
		)
		(stroke
			(width 0)
			(type solid)
		)
		(fill yes)
		(layer "In11.Cu")
		(net "M_H_CPU0_SA_DQ<21>")
	)
	(gr_poly
		(pts
			(xy 380.082298 -265.518138) (xy 380.035308 -265.365738) (xy 379.773688 -265.365738) (xy 379.726698 -265.518138)
			(xy 379.726698 -265.562588) (xy 380.082298 -265.562588)
		)
		(stroke
			(width 0)
			(type solid)
		)
		(fill yes)
		(layer "In11.Cu")
		(net "M_H_CPU0_SA_DQS_DN<3>")
	)
	(gr_poly
		(pts
			(xy 380.082298 -265.110214) (xy 380.082298 -265.065764) (xy 379.726698 -265.065764) (xy 379.726698 -265.110214)
			(xy 379.773688 -265.262614) (xy 380.035308 -265.262614)
		)
		(stroke
			(width 0)
			(type solid)
		)
		(fill yes)
		(layer "In11.Cu")
		(net "M_H_CPU0_SA_DQS_DN<8>")
	)
	(gr_poly
		(pts
			(xy 380.082298 -263.890506) (xy 380.035308 -263.738106) (xy 379.773688 -263.738106) (xy 379.726698 -263.890506)
			(xy 379.726698 -263.934956) (xy 380.082298 -263.934956)
		)
		(stroke
			(width 0)
			(type solid)
		)
		(fill yes)
		(layer "In11.Cu")
		(net "M_H_CPU0_SA_DQ<30>")
	)
	(gr_poly
		(pts
			(xy 380.082298 -260.634734) (xy 380.035308 -260.482334) (xy 379.773688 -260.482334) (xy 379.726698 -260.634734)
			(xy 379.726698 -260.679184) (xy 380.082298 -260.679184)
		)
		(stroke
			(width 0)
			(type solid)
		)
		(fill yes)
		(layer "In11.Cu")
		(net "M_H_CPU0_SA_DQS_DN<4>")
	)
	(gr_poly
		(pts
			(xy 380.082298 -260.22681) (xy 380.082298 -260.18236) (xy 379.726698 -260.18236) (xy 379.726698 -260.22681)
			(xy 379.773688 -260.37921) (xy 380.035308 -260.37921)
		)
		(stroke
			(width 0)
			(type solid)
		)
		(fill yes)
		(layer "In11.Cu")
		(net "M_H_CPU0_SA_DQS_DN<9>")
	)
	(gr_poly
		(pts
			(xy 380.082298 -259.007102) (xy 380.035308 -258.854702) (xy 379.773688 -258.854702) (xy 379.726698 -259.007102)
			(xy 379.726698 -259.051552) (xy 380.082298 -259.051552)
		)
		(stroke
			(width 0)
			(type solid)
		)
		(fill yes)
		(layer "In11.Cu")
		(net "M_H_CPU0_SA_CB<6>")
	)
	(gr_poly
		(pts
			(xy 380.394972 -268.211554) (xy 380.433326 -268.189456) (xy 380.255526 -267.881608) (xy 380.217172 -267.903706)
			(xy 380.108714 -268.020546) (xy 380.239524 -268.247114)
		)
		(stroke
			(width 0)
			(type solid)
		)
		(fill yes)
		(layer "In11.Cu")
		(net "M_H_CPU0_SA_DQ<25>")
	)
	(gr_poly
		(pts
			(xy 380.425198 -246.568722) (xy 380.378208 -246.416322) (xy 380.116588 -246.416322) (xy 380.069598 -246.568722)
			(xy 380.069598 -246.612918) (xy 380.425198 -246.612918)
		)
		(stroke
			(width 0)
			(type solid)
		)
		(fill yes)
		(layer "In11.Cu")
		(net "M_H_CPU0_SB_CA<5>")
	)
	(gr_poly
		(pts
			(xy 380.425198 -227.035106) (xy 380.378208 -226.882706) (xy 380.116588 -226.882706) (xy 380.069598 -227.035106)
			(xy 380.069598 -227.079556) (xy 380.425198 -227.079556)
		)
		(stroke
			(width 0)
			(type solid)
		)
		(fill yes)
		(layer "In11.Cu")
		(net "M_H_CPU0_SB_DQS_DN<3>")
	)
	(gr_poly
		(pts
			(xy 380.425198 -226.627182) (xy 380.425198 -226.582732) (xy 380.069598 -226.582732) (xy 380.069598 -226.627182)
			(xy 380.116588 -226.779582) (xy 380.378208 -226.779582)
		)
		(stroke
			(width 0)
			(type solid)
		)
		(fill yes)
		(layer "In11.Cu")
		(net "M_H_CPU0_SB_DQ<30>")
	)
	(gr_poly
		(pts
			(xy 380.425198 -225.407474) (xy 380.378208 -225.255074) (xy 380.116588 -225.255074) (xy 380.069598 -225.407474)
			(xy 380.069598 -225.45167) (xy 380.425198 -225.45167)
		)
		(stroke
			(width 0)
			(type solid)
		)
		(fill yes)
		(layer "In11.Cu")
		(net "M_H_CPU0_SB_DQ<29>")
	)
	(gr_poly
		(pts
			(xy 380.427738 -248.196354) (xy 380.380748 -248.043954) (xy 380.119128 -248.043954) (xy 380.072138 -248.196354)
			(xy 380.072138 -248.24055) (xy 380.427738 -248.24055)
		)
		(stroke
			(width 0)
			(type solid)
		)
		(fill yes)
		(layer "In11.Cu")
		(net "M_H_CPU0_SB_CA<1>")
	)
	(gr_poly
		(pts
			(xy 380.427738 -247.787922) (xy 380.427738 -247.743726) (xy 380.072138 -247.743726) (xy 380.072138 -247.787922)
			(xy 380.119128 -247.940322) (xy 380.380748 -247.940322)
		)
		(stroke
			(width 0)
			(type solid)
		)
		(fill yes)
		(layer "In11.Cu")
		(net "M_H_CPU0_SB_CA<2>")
	)
	(gr_poly
		(pts
			(xy 380.427738 -244.53215) (xy 380.427738 -244.487954) (xy 380.072138 -244.487954) (xy 380.072138 -244.53215)
			(xy 380.119128 -244.68455) (xy 380.380748 -244.68455)
		)
		(stroke
			(width 0)
			(type solid)
		)
		(fill yes)
		(layer "In11.Cu")
		(net "M_H_CPU0_SB_CB<6>")
	)
	(gr_poly
		(pts
			(xy 380.427738 -243.31295) (xy 380.380748 -243.16055) (xy 380.119128 -243.16055) (xy 380.072138 -243.31295)
			(xy 380.072138 -243.3574) (xy 380.427738 -243.3574)
		)
		(stroke
			(width 0)
			(type solid)
		)
		(fill yes)
		(layer "In11.Cu")
		(net "M_H_CPU0_SB_CB<5>")
	)
	(gr_poly
		(pts
			(xy 380.427738 -242.905026) (xy 380.427738 -242.860576) (xy 380.072138 -242.860576) (xy 380.072138 -242.905026)
			(xy 380.119128 -243.057426) (xy 380.380748 -243.057426)
		)
		(stroke
			(width 0)
			(type solid)
		)
		(fill yes)
		(layer "In11.Cu")
		(net "M_H_CPU0_SB_DQS_DP<9>")
	)
	(gr_poly
		(pts
			(xy 380.427738 -239.648746) (xy 380.427738 -239.60455) (xy 380.072138 -239.60455) (xy 380.072138 -239.648746)
			(xy 380.119128 -239.801146) (xy 380.380748 -239.801146)
		)
		(stroke
			(width 0)
			(type solid)
		)
		(fill yes)
		(layer "In11.Cu")
		(net "M_H_CPU0_SB_DQ<0>")
	)
	(gr_poly
		(pts
			(xy 380.427738 -238.429546) (xy 380.380748 -238.277146) (xy 380.119128 -238.277146) (xy 380.072138 -238.429546)
			(xy 380.072138 -238.473996) (xy 380.427738 -238.473996)
		)
		(stroke
			(width 0)
			(type solid)
		)
		(fill yes)
		(layer "In11.Cu")
		(net "M_H_CPU0_SB_DQ<3>")
	)
	(gr_poly
		(pts
			(xy 380.427738 -238.021622) (xy 380.427738 -237.977172) (xy 380.072138 -237.977172) (xy 380.072138 -238.021622)
			(xy 380.119128 -238.174022) (xy 380.380748 -238.174022)
		)
		(stroke
			(width 0)
			(type solid)
		)
		(fill yes)
		(layer "In11.Cu")
		(net "M_H_CPU0_SB_DQS_DP<0>")
	)
	(gr_poly
		(pts
			(xy 380.427738 -234.76585) (xy 380.427738 -234.7214) (xy 380.072138 -234.7214) (xy 380.072138 -234.76585)
			(xy 380.119128 -234.91825) (xy 380.380748 -234.91825)
		)
		(stroke
			(width 0)
			(type solid)
		)
		(fill yes)
		(layer "In11.Cu")
		(net "M_H_CPU0_SB_DQ<8>")
	)
	(gr_poly
		(pts
			(xy 380.427738 -233.138218) (xy 380.427738 -233.093768) (xy 380.072138 -233.093768) (xy 380.072138 -233.138218)
			(xy 380.119128 -233.290618) (xy 380.380748 -233.290618)
		)
		(stroke
			(width 0)
			(type solid)
		)
		(fill yes)
		(layer "In11.Cu")
		(net "M_H_CPU0_SB_DQS_DP<1>")
	)
	(gr_poly
		(pts
			(xy 380.427738 -229.882446) (xy 380.427738 -229.837996) (xy 380.072138 -229.837996) (xy 380.072138 -229.882446)
			(xy 380.119128 -230.034846) (xy 380.380748 -230.034846)
		)
		(stroke
			(width 0)
			(type solid)
		)
		(fill yes)
		(layer "In11.Cu")
		(net "M_H_CPU0_SB_DQ<26>")
	)
	(gr_poly
		(pts
			(xy 380.427738 -228.663246) (xy 380.380748 -228.510846) (xy 380.119128 -228.510846) (xy 380.072138 -228.663246)
			(xy 380.072138 -228.707442) (xy 380.427738 -228.707442)
		)
		(stroke
			(width 0)
			(type solid)
		)
		(fill yes)
		(layer "In11.Cu")
		(net "M_H_CPU0_SB_DQ<25>")
	)
	(gr_poly
		(pts
			(xy 380.427738 -228.254814) (xy 380.427738 -228.210618) (xy 380.072138 -228.210618) (xy 380.072138 -228.254814)
			(xy 380.119128 -228.407214) (xy 380.380748 -228.407214)
		)
		(stroke
			(width 0)
			(type solid)
		)
		(fill yes)
		(layer "In11.Cu")
		(net "M_H_CPU0_SB_DQS_DN<8>")
	)
	(gr_poly
		(pts
			(xy 380.43358 -246.16029) (xy 380.43358 -246.11584) (xy 380.07798 -246.11584) (xy 380.07798 -246.16029)
			(xy 380.12497 -246.31269) (xy 380.38659 -246.31269)
		)
		(stroke
			(width 0)
			(type solid)
		)
		(fill yes)
		(layer "In11.Cu")
		(net "M_H_CPU0_SB_CA<6>")
	)
	(gr_poly
		(pts
			(xy 380.43358 -241.276886) (xy 380.43358 -241.232436) (xy 380.07798 -241.232436) (xy 380.07798 -241.276886)
			(xy 380.12497 -241.429286) (xy 380.38659 -241.429286)
		)
		(stroke
			(width 0)
			(type solid)
		)
		(fill yes)
		(layer "In11.Cu")
		(net "M_H_CPU0_SB_CB<0>")
	)
	(gr_poly
		(pts
			(xy 380.43358 -236.393482) (xy 380.43358 -236.349286) (xy 380.07798 -236.349286) (xy 380.07798 -236.393482)
			(xy 380.12497 -236.545882) (xy 380.38659 -236.545882)
		)
		(stroke
			(width 0)
			(type solid)
		)
		(fill yes)
		(layer "In11.Cu")
		(net "M_H_CPU0_SB_DQ<4>")
	)
	(gr_poly
		(pts
			(xy 380.43358 -231.510078) (xy 380.43358 -231.465882) (xy 380.07798 -231.465882) (xy 380.07798 -231.510078)
			(xy 380.12497 -231.662478) (xy 380.38659 -231.662478)
		)
		(stroke
			(width 0)
			(type solid)
		)
		(fill yes)
		(layer "In11.Cu")
		(net "M_H_CPU0_SB_DQ<12>")
	)
	(gr_poly
		(pts
			(xy 380.434088 -241.685826) (xy 380.387098 -241.533426) (xy 380.125478 -241.533426) (xy 380.078488 -241.685826)
			(xy 380.078488 -241.730022) (xy 380.434088 -241.730022)
		)
		(stroke
			(width 0)
			(type solid)
		)
		(fill yes)
		(layer "In11.Cu")
		(net "M_H_CPU0_SB_DQS_DP<4>")
	)
	(gr_poly
		(pts
			(xy 380.434088 -236.802422) (xy 380.387098 -236.650022) (xy 380.125478 -236.650022) (xy 380.078488 -236.802422)
			(xy 380.078488 -236.846872) (xy 380.434088 -236.846872)
		)
		(stroke
			(width 0)
			(type solid)
		)
		(fill yes)
		(layer "In11.Cu")
		(net "M_H_CPU0_SB_DQS_DP<5>")
	)
	(gr_poly
		(pts
			(xy 380.434088 -231.919018) (xy 380.387098 -231.766618) (xy 380.125478 -231.766618) (xy 380.078488 -231.919018)
			(xy 380.078488 -231.963468) (xy 380.434088 -231.963468)
		)
		(stroke
			(width 0)
			(type solid)
		)
		(fill yes)
		(layer "In11.Cu")
		(net "M_H_CPU0_SB_DQS_DP<6>")
	)
	(gr_poly
		(pts
			(xy 380.439676 -240.057686) (xy 380.392686 -239.905286) (xy 380.131066 -239.905286) (xy 380.084076 -240.057686)
			(xy 380.084076 -240.101882) (xy 380.439676 -240.101882)
		)
		(stroke
			(width 0)
			(type solid)
		)
		(fill yes)
		(layer "In11.Cu")
		(net "M_H_CPU0_SB_CB<3>")
	)
	(gr_poly
		(pts
			(xy 380.439676 -235.174282) (xy 380.392686 -235.021882) (xy 380.131066 -235.021882) (xy 380.084076 -235.174282)
			(xy 380.084076 -235.218732) (xy 380.439676 -235.218732)
		)
		(stroke
			(width 0)
			(type solid)
		)
		(fill yes)
		(layer "In11.Cu")
		(net "M_H_CPU0_SB_DQ<7>")
	)
	(gr_poly
		(pts
			(xy 380.439676 -230.290878) (xy 380.392686 -230.138478) (xy 380.131066 -230.138478) (xy 380.084076 -230.290878)
			(xy 380.084076 -230.335328) (xy 380.439676 -230.335328)
		)
		(stroke
			(width 0)
			(type solid)
		)
		(fill yes)
		(layer "In11.Cu")
		(net "M_H_CPU0_SB_DQ<15>")
	)
	(gr_poly
		(pts
			(xy 380.43993 -233.546142) (xy 380.39294 -233.393742) (xy 380.13132 -233.393742) (xy 380.08433 -233.546142)
			(xy 380.08433 -233.590592) (xy 380.43993 -233.590592)
		)
		(stroke
			(width 0)
			(type solid)
		)
		(fill yes)
		(layer "In11.Cu")
		(net "M_H_CPU0_SB_DQ<11>")
	)
	(gr_poly
		(pts
			(xy 380.509272 -267.598906) (xy 380.61773 -267.482066) (xy 380.48692 -267.255498) (xy 380.331472 -267.291058)
			(xy 380.293118 -267.313156) (xy 380.470918 -267.621004)
		)
		(stroke
			(width 0)
			(type solid)
		)
		(fill yes)
		(layer "In11.Cu")
		(net "M_H_CPU0_SA_DQ<27>")
	)
	(gr_poly
		(pts
			(xy 380.53518 -280.98242) (xy 380.48819 -280.83002) (xy 380.22657 -280.83002) (xy 380.17958 -280.98242)
			(xy 380.17958 -281.026616) (xy 380.53518 -281.026616)
		)
		(stroke
			(width 0)
			(type solid)
		)
		(fill yes)
		(layer "In11.Cu")
		(net "M_H_CPU0_SA_DQ<10>")
	)
	(gr_poly
		(pts
			(xy 380.53518 -277.726394) (xy 380.48819 -277.573994) (xy 380.22657 -277.573994) (xy 380.17958 -277.726394)
			(xy 380.17958 -277.770844) (xy 380.53518 -277.770844)
		)
		(stroke
			(width 0)
			(type solid)
		)
		(fill yes)
		(layer "In11.Cu")
		(net "M_H_CPU0_SA_DQ<14>")
	)
	(gr_poly
		(pts
			(xy 380.53518 -275.690584) (xy 380.53518 -275.646388) (xy 380.17958 -275.646388) (xy 380.17958 -275.690584)
			(xy 380.22657 -275.842984) (xy 380.48819 -275.842984)
		)
		(stroke
			(width 0)
			(type solid)
		)
		(fill yes)
		(layer "In11.Cu")
		(net "M_H_CPU0_SA_DQ<16>")
	)
	(gr_poly
		(pts
			(xy 380.53518 -265.92403) (xy 380.53518 -265.879834) (xy 380.17958 -265.879834) (xy 380.17958 -265.92403)
			(xy 380.22657 -266.07643) (xy 380.48819 -266.07643)
		)
		(stroke
			(width 0)
			(type solid)
		)
		(fill yes)
		(layer "In11.Cu")
		(net "M_H_CPU0_SA_DQS_DP<3>")
	)
	(gr_poly
		(pts
			(xy 380.53518 -261.040626) (xy 380.53518 -260.99643) (xy 380.17958 -260.99643) (xy 380.17958 -261.040626)
			(xy 380.22657 -261.193026) (xy 380.48819 -261.193026)
		)
		(stroke
			(width 0)
			(type solid)
		)
		(fill yes)
		(layer "In11.Cu")
		(net "M_H_CPU0_SA_DQS_DP<4>")
	)
	(gr_poly
		(pts
			(xy 380.53518 -259.820918) (xy 380.48819 -259.668518) (xy 380.22657 -259.668518) (xy 380.17958 -259.820918)
			(xy 380.17958 -259.865368) (xy 380.53518 -259.865368)
		)
		(stroke
			(width 0)
			(type solid)
		)
		(fill yes)
		(layer "In11.Cu")
		(net "M_H_CPU0_SA_DQS_DP<9>")
	)
	(gr_poly
		(pts
			(xy 380.53518 -259.412994) (xy 380.53518 -259.368544) (xy 380.17958 -259.368544) (xy 380.17958 -259.412994)
			(xy 380.22657 -259.565394) (xy 380.48819 -259.565394)
		)
		(stroke
			(width 0)
			(type solid)
		)
		(fill yes)
		(layer "In11.Cu")
		(net "M_H_CPU0_SA_CB<4>")
	)
	(gr_poly
		(pts
			(xy 380.53772 -274.47113) (xy 380.49073 -274.31873) (xy 380.22911 -274.31873) (xy 380.18212 -274.47113)
			(xy 380.18212 -274.515326) (xy 380.53772 -274.515326)
		)
		(stroke
			(width 0)
			(type solid)
		)
		(fill yes)
		(layer "In11.Cu")
		(net "M_H_CPU0_SA_DQ<19>")
	)
	(gr_poly
		(pts
			(xy 380.53772 -274.062698) (xy 380.53772 -274.018502) (xy 380.18212 -274.018502) (xy 380.18212 -274.062698)
			(xy 380.22911 -274.215098) (xy 380.49073 -274.215098)
		)
		(stroke
			(width 0)
			(type solid)
		)
		(fill yes)
		(layer "In11.Cu")
		(net "M_H_CPU0_SA_DQS_DP<2>")
	)
	(gr_poly
		(pts
			(xy 380.53772 -272.843498) (xy 380.49073 -272.691098) (xy 380.22911 -272.691098) (xy 380.18212 -272.843498)
			(xy 380.18212 -272.887948) (xy 380.53772 -272.887948)
		)
		(stroke
			(width 0)
			(type solid)
		)
		(fill yes)
		(layer "In11.Cu")
		(net "M_H_CPU0_SA_DQS_DP<7>")
	)
	(gr_poly
		(pts
			(xy 380.53772 -269.587726) (xy 380.49073 -269.435326) (xy 380.22911 -269.435326) (xy 380.18212 -269.587726)
			(xy 380.18212 -269.631922) (xy 380.53772 -269.631922)
		)
		(stroke
			(width 0)
			(type solid)
		)
		(fill yes)
		(layer "In11.Cu")
		(net "M_H_CPU0_SA_DQ<23>")
	)
	(gr_poly
		(pts
			(xy 380.53772 -269.179294) (xy 380.53772 -269.135098) (xy 380.18212 -269.135098) (xy 380.18212 -269.179294)
			(xy 380.22911 -269.331694) (xy 380.49073 -269.331694)
		)
		(stroke
			(width 0)
			(type solid)
		)
		(fill yes)
		(layer "In11.Cu")
		(net "M_H_CPU0_SA_DQ<24>")
	)
	(gr_poly
		(pts
			(xy 380.53772 -264.704322) (xy 380.49073 -264.551922) (xy 380.22911 -264.551922) (xy 380.18212 -264.704322)
			(xy 380.18212 -264.748772) (xy 380.53772 -264.748772)
		)
		(stroke
			(width 0)
			(type solid)
		)
		(fill yes)
		(layer "In11.Cu")
		(net "M_H_CPU0_SA_DQS_DP<8>")
	)
	(gr_poly
		(pts
			(xy 380.53772 -264.296398) (xy 380.53772 -264.251948) (xy 380.18212 -264.251948) (xy 380.18212 -264.296398)
			(xy 380.22911 -264.448798) (xy 380.49073 -264.448798)
		)
		(stroke
			(width 0)
			(type solid)
		)
		(fill yes)
		(layer "In11.Cu")
		(net "M_H_CPU0_SA_DQ<28>")
	)
	(gr_poly
		(pts
			(xy 380.53772 -263.07669) (xy 380.49073 -262.92429) (xy 380.22911 -262.92429) (xy 380.18212 -263.07669)
			(xy 380.18212 -263.12114) (xy 380.53772 -263.12114)
		)
		(stroke
			(width 0)
			(type solid)
		)
		(fill yes)
		(layer "In11.Cu")
		(net "M_H_CPU0_SA_DQ<31>")
	)
	(gr_poly
		(pts
			(xy 380.53772 -258.193286) (xy 380.49073 -258.040886) (xy 380.22911 -258.040886) (xy 380.18212 -258.193286)
			(xy 380.18212 -258.237736) (xy 380.53772 -258.237736)
		)
		(stroke
			(width 0)
			(type solid)
		)
		(fill yes)
		(layer "In11.Cu")
		(net "M_H_CPU0_SA_CB<7>")
	)
	(gr_poly
		(pts
			(xy 380.543562 -280.573988) (xy 380.543562 -280.529538) (xy 380.187962 -280.529538) (xy 380.187962 -280.573988)
			(xy 380.234952 -280.726388) (xy 380.496572 -280.726388)
		)
		(stroke
			(width 0)
			(type solid)
		)
		(fill yes)
		(layer "In11.Cu")
		(net "M_H_CPU0_SA_DQ<9>")
	)
	(gr_poly
		(pts
			(xy 380.543562 -277.317962) (xy 380.543562 -277.273766) (xy 380.187962 -277.273766) (xy 380.187962 -277.317962)
			(xy 380.234952 -277.470362) (xy 380.496572 -277.470362)
		)
		(stroke
			(width 0)
			(type solid)
		)
		(fill yes)
		(layer "In11.Cu")
		(net "M_H_CPU0_SA_DQ<13>")
	)
	(gr_poly
		(pts
			(xy 380.543562 -261.449058) (xy 380.496572 -261.296658) (xy 380.234952 -261.296658) (xy 380.187962 -261.449058)
			(xy 380.187962 -261.493508) (xy 380.543562 -261.493508)
		)
		(stroke
			(width 0)
			(type solid)
		)
		(fill yes)
		(layer "In11.Cu")
		(net "M_H_CPU0_SA_CB<3>")
	)
	(gr_poly
		(pts
			(xy 380.543562 -256.565654) (xy 380.496572 -256.413254) (xy 380.234952 -256.413254) (xy 380.187962 -256.565654)
			(xy 380.187962 -256.610104) (xy 380.543562 -256.610104)
		)
		(stroke
			(width 0)
			(type solid)
		)
		(fill yes)
		(layer "In11.Cu")
		(net "M_H_CPU0_SA_CS_N<1>")
	)
	(gr_poly
		(pts
			(xy 380.543562 -256.157222) (xy 380.543562 -256.112772) (xy 380.187962 -256.112772) (xy 380.187962 -256.157222)
			(xy 380.234952 -256.309622) (xy 380.496572 -256.309622)
		)
		(stroke
			(width 0)
			(type solid)
		)
		(fill yes)
		(layer "In11.Cu")
		(net "M_H_CPU0_SA_CS_N<2>")
	)
	(gr_poly
		(pts
			(xy 380.543816 -278.945848) (xy 380.543816 -278.901652) (xy 380.188216 -278.901652) (xy 380.188216 -278.945848)
			(xy 380.235206 -279.098248) (xy 380.496826 -279.098248)
		)
		(stroke
			(width 0)
			(type solid)
		)
		(fill yes)
		(layer "In11.Cu")
		(net "M_H_CPU0_SA_DQS_DN<6>")
	)
	(gr_poly
		(pts
			(xy 380.549658 -272.435066) (xy 380.549658 -272.390616) (xy 380.194058 -272.390616) (xy 380.194058 -272.435066)
			(xy 380.241048 -272.587466) (xy 380.502668 -272.587466)
		)
		(stroke
			(width 0)
			(type solid)
		)
		(fill yes)
		(layer "In11.Cu")
		(net "M_H_CPU0_SA_DQ<20>")
	)
	(gr_poly
		(pts
			(xy 380.549658 -262.668258) (xy 380.549658 -262.623808) (xy 380.194058 -262.623808) (xy 380.194058 -262.668258)
			(xy 380.241048 -262.820658) (xy 380.502668 -262.820658)
		)
		(stroke
			(width 0)
			(type solid)
		)
		(fill yes)
		(layer "In11.Cu")
		(net "M_H_CPU0_SA_CB<0>")
	)
	(gr_poly
		(pts
			(xy 380.549658 -257.784854) (xy 380.549658 -257.740404) (xy 380.194058 -257.740404) (xy 380.194058 -257.784854)
			(xy 380.241048 -257.937254) (xy 380.502668 -257.937254)
		)
		(stroke
			(width 0)
			(type solid)
		)
		(fill yes)
		(layer "In11.Cu")
		(net "M_E_CPU0_ALERT_N")
	)
	(gr_poly
		(pts
			(xy 380.549912 -254.938022) (xy 380.502922 -254.785622) (xy 380.241302 -254.785622) (xy 380.194312 -254.938022)
			(xy 380.194312 -254.982218) (xy 380.549912 -254.982218)
		)
		(stroke
			(width 0)
			(type solid)
		)
		(fill yes)
		(layer "In11.Cu")
		(net "M_H_CPU0_SA_CA<0>")
	)
	(gr_poly
		(pts
			(xy 380.552198 -279.35428) (xy 380.505208 -279.20188) (xy 380.243588 -279.20188) (xy 380.196598 -279.35428)
			(xy 380.196598 -279.39873) (xy 380.552198 -279.39873)
		)
		(stroke
			(width 0)
			(type solid)
		)
		(fill yes)
		(layer "In11.Cu")
		(net "M_H_CPU0_SA_DQS_DN<1>")
	)
	(gr_poly
		(pts
			(xy 380.552198 -254.52959) (xy 380.552198 -254.48514) (xy 380.196598 -254.48514) (xy 380.196598 -254.52959)
			(xy 380.243588 -254.68199) (xy 380.505208 -254.68199)
		)
		(stroke
			(width 0)
			(type solid)
		)
		(fill yes)
		(layer "In11.Cu")
		(net "M_H_CPU0_SA_CA<2>")
	)
	(gr_poly
		(pts
			(xy 380.759462 -249.268996) (xy 380.797816 -249.246898) (xy 380.620016 -248.93905) (xy 380.581662 -248.961148)
			(xy 380.473204 -249.077988) (xy 380.604014 -249.304556)
		)
		(stroke
			(width 0)
			(type solid)
		)
		(fill yes)
		(layer "In11.Cu")
		(net "M_H_CPU0_SB_CA<0>")
	)
	(gr_poly
		(pts
			(xy 380.868174 -248.647204) (xy 380.976632 -248.530364) (xy 380.845822 -248.303796) (xy 380.690374 -248.339356)
			(xy 380.65202 -248.361454) (xy 380.82982 -248.669302)
		)
		(stroke
			(width 0)
			(type solid)
		)
		(fill yes)
		(layer "In11.Cu")
		(net "M_H_CPU0_SB_CA<1>")
	)
	(gr_poly
		(pts
			(xy 380.86919 -270.660368) (xy 380.907544 -270.63827) (xy 380.729744 -270.330422) (xy 380.69139 -270.35252)
			(xy 380.582932 -270.46936) (xy 380.713742 -270.695928)
		)
		(stroke
			(width 0)
			(type solid)
		)
		(fill yes)
		(layer "In11.Cu")
		(net "M_H_CPU0_SA_DQ<21>")
	)
	(gr_poly
		(pts
			(xy 380.897638 -247.382538) (xy 380.850648 -247.230138) (xy 380.589028 -247.230138) (xy 380.542038 -247.382538)
			(xy 380.542038 -247.426988) (xy 380.897638 -247.426988)
		)
		(stroke
			(width 0)
			(type solid)
		)
		(fill yes)
		(layer "In11.Cu")
		(net "M_H_CPU0_SB_CA<3>")
	)
	(gr_poly
		(pts
			(xy 380.897638 -237.616238) (xy 380.850648 -237.463838) (xy 380.589028 -237.463838) (xy 380.542038 -237.616238)
			(xy 380.542038 -237.660434) (xy 380.897638 -237.660434)
		)
		(stroke
			(width 0)
			(type solid)
		)
		(fill yes)
		(layer "In11.Cu")
		(net "M_H_CPU0_SB_DQS_DN<0>")
	)
	(gr_poly
		(pts
			(xy 380.897638 -232.732834) (xy 380.850648 -232.580434) (xy 380.589028 -232.580434) (xy 380.542038 -232.732834)
			(xy 380.542038 -232.77703) (xy 380.897638 -232.77703)
		)
		(stroke
			(width 0)
			(type solid)
		)
		(fill yes)
		(layer "In11.Cu")
		(net "M_H_CPU0_SB_DQS_DN<1>")
	)
	(gr_poly
		(pts
			(xy 380.903734 -243.718334) (xy 380.903734 -243.674138) (xy 380.548134 -243.674138) (xy 380.548134 -243.718334)
			(xy 380.595124 -243.870734) (xy 380.856744 -243.870734)
		)
		(stroke
			(width 0)
			(type solid)
		)
		(fill yes)
		(layer "In11.Cu")
		(net "M_H_CPU0_SB_CB<7>")
	)
	(gr_poly
		(pts
			(xy 380.903734 -242.499134) (xy 380.856744 -242.346734) (xy 380.595124 -242.346734) (xy 380.548134 -242.499134)
			(xy 380.548134 -242.543584) (xy 380.903734 -242.543584)
		)
		(stroke
			(width 0)
			(type solid)
		)
		(fill yes)
		(layer "In11.Cu")
		(net "M_H_CPU0_SB_DQS_DN<9>")
	)
	(gr_poly
		(pts
			(xy 380.903734 -238.83493) (xy 380.903734 -238.790734) (xy 380.548134 -238.790734) (xy 380.548134 -238.83493)
			(xy 380.595124 -238.98733) (xy 380.856744 -238.98733)
		)
		(stroke
			(width 0)
			(type solid)
		)
		(fill yes)
		(layer "In11.Cu")
		(net "M_H_CPU0_SB_DQ<1>")
	)
	(gr_poly
		(pts
			(xy 380.903734 -233.952034) (xy 380.903734 -233.907584) (xy 380.548134 -233.907584) (xy 380.548134 -233.952034)
			(xy 380.595124 -234.104434) (xy 380.856744 -234.104434)
		)
		(stroke
			(width 0)
			(type solid)
		)
		(fill yes)
		(layer "In11.Cu")
		(net "M_H_CPU0_SB_DQ<9>")
	)
	(gr_poly
		(pts
			(xy 380.903734 -229.06863) (xy 380.903734 -229.02418) (xy 380.548134 -229.02418) (xy 380.548134 -229.06863)
			(xy 380.595124 -229.22103) (xy 380.856744 -229.22103)
		)
		(stroke
			(width 0)
			(type solid)
		)
		(fill yes)
		(layer "In11.Cu")
		(net "M_H_CPU0_SB_DQ<27>")
	)
	(gr_poly
		(pts
			(xy 380.903734 -227.84943) (xy 380.856744 -227.69703) (xy 380.595124 -227.69703) (xy 380.548134 -227.84943)
			(xy 380.548134 -227.893626) (xy 380.903734 -227.893626)
		)
		(stroke
			(width 0)
			(type solid)
		)
		(fill yes)
		(layer "In11.Cu")
		(net "M_H_CPU0_SB_DQS_DP<8>")
	)
	(gr_poly
		(pts
			(xy 380.909576 -246.974106) (xy 380.909576 -246.929656) (xy 380.553976 -246.929656) (xy 380.553976 -246.974106)
			(xy 380.600966 -247.126506) (xy 380.862586 -247.126506)
		)
		(stroke
			(width 0)
			(type solid)
		)
		(fill yes)
		(layer "In11.Cu")
		(net "M_H_CPU0_SB_CA<4>")
	)
	(gr_poly
		(pts
			(xy 380.909576 -245.754906) (xy 380.862586 -245.602506) (xy 380.600966 -245.602506) (xy 380.553976 -245.754906)
			(xy 380.553976 -245.799102) (xy 380.909576 -245.799102)
		)
		(stroke
			(width 0)
			(type solid)
		)
		(fill yes)
		(layer "In11.Cu")
		(net "M_H_CPU0_SB_PAR")
	)
	(gr_poly
		(pts
			(xy 380.909576 -240.871502) (xy 380.862586 -240.719102) (xy 380.600966 -240.719102) (xy 380.553976 -240.871502)
			(xy 380.553976 -240.915698) (xy 380.909576 -240.915698)
		)
		(stroke
			(width 0)
			(type solid)
		)
		(fill yes)
		(layer "In11.Cu")
		(net "M_H_CPU0_SB_CB<2>")
	)
	(gr_poly
		(pts
			(xy 380.909576 -240.46307) (xy 380.909576 -240.418874) (xy 380.553976 -240.418874) (xy 380.553976 -240.46307)
			(xy 380.600966 -240.61547) (xy 380.862586 -240.61547)
		)
		(stroke
			(width 0)
			(type solid)
		)
		(fill yes)
		(layer "In11.Cu")
		(net "M_H_CPU0_SB_CB<1>")
	)
	(gr_poly
		(pts
			(xy 380.909576 -237.207298) (xy 380.909576 -237.163102) (xy 380.553976 -237.163102) (xy 380.553976 -237.207298)
			(xy 380.600966 -237.359698) (xy 380.862586 -237.359698)
		)
		(stroke
			(width 0)
			(type solid)
		)
		(fill yes)
		(layer "In11.Cu")
		(net "M_H_CPU0_SB_DQS_DN<5>")
	)
	(gr_poly
		(pts
			(xy 380.909576 -235.988098) (xy 380.862586 -235.835698) (xy 380.600966 -235.835698) (xy 380.553976 -235.988098)
			(xy 380.553976 -236.032294) (xy 380.909576 -236.032294)
		)
		(stroke
			(width 0)
			(type solid)
		)
		(fill yes)
		(layer "In11.Cu")
		(net "M_H_CPU0_SB_DQ<6>")
	)
	(gr_poly
		(pts
			(xy 380.909576 -235.579666) (xy 380.909576 -235.53547) (xy 380.553976 -235.53547) (xy 380.553976 -235.579666)
			(xy 380.600966 -235.732066) (xy 380.862586 -235.732066)
		)
		(stroke
			(width 0)
			(type solid)
		)
		(fill yes)
		(layer "In11.Cu")
		(net "M_H_CPU0_SB_DQ<5>")
	)
	(gr_poly
		(pts
			(xy 380.909576 -232.323894) (xy 380.909576 -232.279698) (xy 380.553976 -232.279698) (xy 380.553976 -232.323894)
			(xy 380.600966 -232.476294) (xy 380.862586 -232.476294)
		)
		(stroke
			(width 0)
			(type solid)
		)
		(fill yes)
		(layer "In11.Cu")
		(net "M_H_CPU0_SB_DQS_DN<6>")
	)
	(gr_poly
		(pts
			(xy 380.909576 -231.104694) (xy 380.862586 -230.952294) (xy 380.600966 -230.952294) (xy 380.553976 -231.104694)
			(xy 380.553976 -231.14889) (xy 380.909576 -231.14889)
		)
		(stroke
			(width 0)
			(type solid)
		)
		(fill yes)
		(layer "In11.Cu")
		(net "M_H_CPU0_SB_DQ<14>")
	)
	(gr_poly
		(pts
			(xy 380.909576 -230.696262) (xy 380.909576 -230.652066) (xy 380.553976 -230.652066) (xy 380.553976 -230.696262)
			(xy 380.600966 -230.848662) (xy 380.862586 -230.848662)
		)
		(stroke
			(width 0)
			(type solid)
		)
		(fill yes)
		(layer "In11.Cu")
		(net "M_H_CPU0_SB_DQ<13>")
	)
	(gr_poly
		(pts
			(xy 380.912116 -244.126766) (xy 380.865126 -243.974366) (xy 380.603506 -243.974366) (xy 380.556516 -244.126766)
			(xy 380.556516 -244.171216) (xy 380.912116 -244.171216)
		)
		(stroke
			(width 0)
			(type solid)
		)
		(fill yes)
		(layer "In11.Cu")
		(net "M_H_CPU0_SB_CB<4>")
	)
	(gr_poly
		(pts
			(xy 380.912116 -242.090702) (xy 380.912116 -242.046506) (xy 380.556516 -242.046506) (xy 380.556516 -242.090702)
			(xy 380.603506 -242.243102) (xy 380.865126 -242.243102)
		)
		(stroke
			(width 0)
			(type solid)
		)
		(fill yes)
		(layer "In11.Cu")
		(net "M_H_CPU0_SB_DQS_DN<4>")
	)
	(gr_poly
		(pts
			(xy 380.912116 -239.243362) (xy 380.865126 -239.090962) (xy 380.603506 -239.090962) (xy 380.556516 -239.243362)
			(xy 380.556516 -239.287812) (xy 380.912116 -239.287812)
		)
		(stroke
			(width 0)
			(type solid)
		)
		(fill yes)
		(layer "In11.Cu")
		(net "M_H_CPU0_SB_DQ<2>")
	)
	(gr_poly
		(pts
			(xy 380.912116 -234.360466) (xy 380.865126 -234.208066) (xy 380.603506 -234.208066) (xy 380.556516 -234.360466)
			(xy 380.556516 -234.404662) (xy 380.912116 -234.404662)
		)
		(stroke
			(width 0)
			(type solid)
		)
		(fill yes)
		(layer "In11.Cu")
		(net "M_H_CPU0_SB_DQ<10>")
	)
	(gr_poly
		(pts
			(xy 380.912116 -229.477062) (xy 380.865126 -229.324662) (xy 380.603506 -229.324662) (xy 380.556516 -229.477062)
			(xy 380.556516 -229.521258) (xy 380.912116 -229.521258)
		)
		(stroke
			(width 0)
			(type solid)
		)
		(fill yes)
		(layer "In11.Cu")
		(net "M_H_CPU0_SB_DQ<24>")
	)
	(gr_poly
		(pts
			(xy 380.912116 -227.440998) (xy 380.912116 -227.396548) (xy 380.556516 -227.396548) (xy 380.556516 -227.440998)
			(xy 380.603506 -227.593398) (xy 380.865126 -227.593398)
		)
		(stroke
			(width 0)
			(type solid)
		)
		(fill yes)
		(layer "In11.Cu")
		(net "M_H_CPU0_SB_DQS_DP<3>")
	)
	(gr_poly
		(pts
			(xy 380.912116 -226.22129) (xy 380.865126 -226.06889) (xy 380.603506 -226.06889) (xy 380.556516 -226.22129)
			(xy 380.556516 -226.26574) (xy 380.912116 -226.26574)
		)
		(stroke
			(width 0)
			(type solid)
		)
		(fill yes)
		(layer "In11.Cu")
		(net "M_H_CPU0_SB_DQ<28>")
	)
	(gr_poly
		(pts
			(xy 380.912116 -225.813366) (xy 380.912116 -225.768916) (xy 380.556516 -225.768916) (xy 380.556516 -225.813366)
			(xy 380.603506 -225.965766) (xy 380.865126 -225.965766)
		)
		(stroke
			(width 0)
			(type solid)
		)
		(fill yes)
		(layer "In11.Cu")
		(net "M_H_CPU0_SB_DQ<31>")
	)
	(gr_poly
		(pts
			(xy 380.978156 -270.038576) (xy 381.086614 -269.921736) (xy 380.955804 -269.695168) (xy 380.800356 -269.730728)
			(xy 380.762002 -269.752826) (xy 380.939802 -270.060674)
		)
		(stroke
			(width 0)
			(type solid)
		)
		(fill yes)
		(layer "In11.Cu")
		(net "M_H_CPU0_SA_DQ<23>")
	)
	(gr_poly
		(pts
			(xy 381.00762 -279.760172) (xy 381.00762 -279.715722) (xy 380.65202 -279.715722) (xy 380.65202 -279.760172)
			(xy 380.69901 -279.912572) (xy 380.96063 -279.912572)
		)
		(stroke
			(width 0)
			(type solid)
		)
		(fill yes)
		(layer "In11.Cu")
		(net "M_H_CPU0_SA_DQS_DP<1>")
	)
	(gr_poly
		(pts
			(xy 381.00762 -274.876514) (xy 381.00762 -274.832064) (xy 380.65202 -274.832064) (xy 380.65202 -274.876514)
			(xy 380.69901 -275.028914) (xy 380.96063 -275.028914)
		)
		(stroke
			(width 0)
			(type solid)
		)
		(fill yes)
		(layer "In11.Cu")
		(net "M_H_CPU0_SA_DQ<17>")
	)
	(gr_poly
		(pts
			(xy 381.00762 -265.109706) (xy 381.00762 -265.06551) (xy 380.65202 -265.06551) (xy 380.65202 -265.109706)
			(xy 380.69901 -265.262106) (xy 380.96063 -265.262106)
		)
		(stroke
			(width 0)
			(type solid)
		)
		(fill yes)
		(layer "In11.Cu")
		(net "M_H_CPU0_SA_DQS_DN<8>")
	)
	(gr_poly
		(pts
			(xy 381.00762 -255.343406) (xy 381.00762 -255.298956) (xy 380.65202 -255.298956) (xy 380.65202 -255.343406)
			(xy 380.69901 -255.495806) (xy 380.96063 -255.495806)
		)
		(stroke
			(width 0)
			(type solid)
		)
		(fill yes)
		(layer "In11.Cu")
		(net "M_H_CPU0_SA_CA<1>")
	)
	(gr_poly
		(pts
			(xy 381.013462 -255.751838) (xy 380.966472 -255.599438) (xy 380.704852 -255.599438) (xy 380.657862 -255.751838)
			(xy 380.657862 -255.796288) (xy 381.013462 -255.796288)
		)
		(stroke
			(width 0)
			(type solid)
		)
		(fill yes)
		(layer "In11.Cu")
		(net "M_H_CPU0_SA_CS_N<3>")
	)
	(gr_poly
		(pts
			(xy 381.013716 -278.540718) (xy 380.966726 -278.388318) (xy 380.705106 -278.388318) (xy 380.658116 -278.540718)
			(xy 380.658116 -278.585168) (xy 381.013716 -278.585168)
		)
		(stroke
			(width 0)
			(type solid)
		)
		(fill yes)
		(layer "In11.Cu")
		(net "M_H_CPU0_SA_DQS_DP<6>")
	)
	(gr_poly
		(pts
			(xy 381.013716 -273.657314) (xy 380.966726 -273.504914) (xy 380.705106 -273.504914) (xy 380.658116 -273.657314)
			(xy 380.658116 -273.701764) (xy 381.013716 -273.701764)
		)
		(stroke
			(width 0)
			(type solid)
		)
		(fill yes)
		(layer "In11.Cu")
		(net "M_H_CPU0_SA_DQS_DN<2>")
	)
	(gr_poly
		(pts
			(xy 381.013716 -268.77391) (xy 380.966726 -268.62151) (xy 380.705106 -268.62151) (xy 380.658116 -268.77391)
			(xy 380.658116 -268.81836) (xy 381.013716 -268.81836)
		)
		(stroke
			(width 0)
			(type solid)
		)
		(fill yes)
		(layer "In11.Cu")
		(net "M_H_CPU0_SA_DQ<26>")
	)
	(gr_poly
		(pts
			(xy 381.013716 -263.891014) (xy 380.966726 -263.738614) (xy 380.705106 -263.738614) (xy 380.658116 -263.891014)
			(xy 380.658116 -263.93521) (xy 381.013716 -263.93521)
		)
		(stroke
			(width 0)
			(type solid)
		)
		(fill yes)
		(layer "In11.Cu")
		(net "M_H_CPU0_SA_DQ<30>")
	)
	(gr_poly
		(pts
			(xy 381.013716 -254.124206) (xy 380.966726 -253.971806) (xy 380.705106 -253.971806) (xy 380.658116 -254.124206)
			(xy 380.658116 -254.168402) (xy 381.013716 -254.168402)
		)
		(stroke
			(width 0)
			(type solid)
		)
		(fill yes)
		(layer "In11.Cu")
		(net "M_H_CPU0_SA_CA<3>")
	)
	(gr_poly
		(pts
			(xy 381.019558 -280.168096) (xy 380.972568 -280.015696) (xy 380.710948 -280.015696) (xy 380.663958 -280.168096)
			(xy 380.663958 -280.212546) (xy 381.019558 -280.212546)
		)
		(stroke
			(width 0)
			(type solid)
		)
		(fill yes)
		(layer "In11.Cu")
		(net "M_H_CPU0_SA_DQ<11>")
	)
	(gr_poly
		(pts
			(xy 381.019558 -276.912578) (xy 380.972568 -276.760178) (xy 380.710948 -276.760178) (xy 380.663958 -276.912578)
			(xy 380.663958 -276.957028) (xy 381.019558 -276.957028)
		)
		(stroke
			(width 0)
			(type solid)
		)
		(fill yes)
		(layer "In11.Cu")
		(net "M_H_CPU0_SA_DQ<15>")
	)
	(gr_poly
		(pts
			(xy 381.019558 -275.284946) (xy 380.972568 -275.132546) (xy 380.710948 -275.132546) (xy 380.663958 -275.284946)
			(xy 380.663958 -275.329396) (xy 381.019558 -275.329396)
		)
		(stroke
			(width 0)
			(type solid)
		)
		(fill yes)
		(layer "In11.Cu")
		(net "M_H_CPU0_SA_DQ<18>")
	)
	(gr_poly
		(pts
			(xy 381.019558 -272.029174) (xy 380.972568 -271.876774) (xy 380.710948 -271.876774) (xy 380.663958 -272.029174)
			(xy 380.663958 -272.073624) (xy 381.019558 -272.073624)
		)
		(stroke
			(width 0)
			(type solid)
		)
		(fill yes)
		(layer "In11.Cu")
		(net "M_H_CPU0_SA_DQ<22>")
	)
	(gr_poly
		(pts
			(xy 381.019558 -265.518646) (xy 380.972568 -265.366246) (xy 380.710948 -265.366246) (xy 380.663958 -265.518646)
			(xy 380.663958 -265.562842) (xy 381.019558 -265.562842)
		)
		(stroke
			(width 0)
			(type solid)
		)
		(fill yes)
		(layer "In11.Cu")
		(net "M_H_CPU0_SA_DQS_DN<3>")
	)
	(gr_poly
		(pts
			(xy 381.019558 -262.262874) (xy 380.972568 -262.110474) (xy 380.710948 -262.110474) (xy 380.663958 -262.262874)
			(xy 380.663958 -262.30707) (xy 381.019558 -262.30707)
		)
		(stroke
			(width 0)
			(type solid)
		)
		(fill yes)
		(layer "In11.Cu")
		(net "M_H_CPU0_SA_CB<2>")
	)
	(gr_poly
		(pts
			(xy 381.019558 -261.854442) (xy 381.019558 -261.810246) (xy 380.663958 -261.810246) (xy 380.663958 -261.854442)
			(xy 380.710948 -262.006842) (xy 380.972568 -262.006842)
		)
		(stroke
			(width 0)
			(type solid)
		)
		(fill yes)
		(layer "In11.Cu")
		(net "M_H_CPU0_SA_CB<1>")
	)
	(gr_poly
		(pts
			(xy 381.019558 -260.635242) (xy 380.972568 -260.482842) (xy 380.710948 -260.482842) (xy 380.663958 -260.635242)
			(xy 380.663958 -260.679438) (xy 381.019558 -260.679438)
		)
		(stroke
			(width 0)
			(type solid)
		)
		(fill yes)
		(layer "In11.Cu")
		(net "M_H_CPU0_SA_DQS_DN<4>")
	)
	(gr_poly
		(pts
			(xy 381.019558 -260.226302) (xy 381.019558 -260.182106) (xy 380.663958 -260.182106) (xy 380.663958 -260.226302)
			(xy 380.710948 -260.378702) (xy 380.972568 -260.378702)
		)
		(stroke
			(width 0)
			(type solid)
		)
		(fill yes)
		(layer "In11.Cu")
		(net "M_H_CPU0_SA_DQS_DN<9>")
	)
	(gr_poly
		(pts
			(xy 381.019558 -257.37947) (xy 380.972568 -257.22707) (xy 380.710948 -257.22707) (xy 380.663958 -257.37947)
			(xy 380.663958 -257.423666) (xy 381.019558 -257.423666)
		)
		(stroke
			(width 0)
			(type solid)
		)
		(fill yes)
		(layer "In11.Cu")
		(net "M_H_CPU0_ALERT_N")
	)
	(gr_poly
		(pts
			(xy 381.019558 -256.971038) (xy 381.019558 -256.926842) (xy 380.663958 -256.926842) (xy 380.663958 -256.971038)
			(xy 380.710948 -257.123438) (xy 380.972568 -257.123438)
		)
		(stroke
			(width 0)
			(type solid)
		)
		(fill yes)
		(layer "In11.Cu")
		(net "M_H_CPU0_SA_CS_N<0>")
	)
	(gr_poly
		(pts
			(xy 381.022098 -281.387804) (xy 381.022098 -281.343608) (xy 380.666498 -281.343608) (xy 380.666498 -281.387804)
			(xy 380.713488 -281.540204) (xy 380.975108 -281.540204)
		)
		(stroke
			(width 0)
			(type solid)
		)
		(fill yes)
		(layer "In11.Cu")
		(net "M_H_CPU0_SA_DQ<8>")
	)
	(gr_poly
		(pts
			(xy 381.022098 -278.132286) (xy 381.022098 -278.08809) (xy 380.666498 -278.08809) (xy 380.666498 -278.132286)
			(xy 380.713488 -278.284686) (xy 380.975108 -278.284686)
		)
		(stroke
			(width 0)
			(type solid)
		)
		(fill yes)
		(layer "In11.Cu")
		(net "M_H_CPU0_SA_DQ<12>")
	)
	(gr_poly
		(pts
			(xy 381.022098 -273.248882) (xy 381.022098 -273.204686) (xy 380.666498 -273.204686) (xy 380.666498 -273.248882)
			(xy 380.713488 -273.401282) (xy 380.975108 -273.401282)
		)
		(stroke
			(width 0)
			(type solid)
		)
		(fill yes)
		(layer "In11.Cu")
		(net "M_H_CPU0_SA_DQS_DN<7>")
	)
	(gr_poly
		(pts
			(xy 381.022098 -268.365478) (xy 381.022098 -268.321282) (xy 380.666498 -268.321282) (xy 380.666498 -268.365478)
			(xy 380.713488 -268.517878) (xy 380.975108 -268.517878)
		)
		(stroke
			(width 0)
			(type solid)
		)
		(fill yes)
		(layer "In11.Cu")
		(net "M_H_CPU0_SA_DQ<25>")
	)
	(gr_poly
		(pts
			(xy 381.022098 -263.482582) (xy 381.022098 -263.438132) (xy 380.666498 -263.438132) (xy 380.666498 -263.482582)
			(xy 380.713488 -263.634982) (xy 380.975108 -263.634982)
		)
		(stroke
			(width 0)
			(type solid)
		)
		(fill yes)
		(layer "In11.Cu")
		(net "M_H_CPU0_SA_DQ<29>")
	)
	(gr_poly
		(pts
			(xy 381.022098 -259.007102) (xy 380.975108 -258.854702) (xy 380.713488 -258.854702) (xy 380.666498 -259.007102)
			(xy 380.666498 -259.051552) (xy 381.022098 -259.051552)
		)
		(stroke
			(width 0)
			(type solid)
		)
		(fill yes)
		(layer "In11.Cu")
		(net "M_H_CPU0_SA_CB<6>")
	)
	(gr_poly
		(pts
			(xy 381.022098 -258.599178) (xy 381.022098 -258.554728) (xy 380.666498 -258.554728) (xy 380.666498 -258.599178)
			(xy 380.713488 -258.751578) (xy 380.975108 -258.751578)
		)
		(stroke
			(width 0)
			(type solid)
		)
		(fill yes)
		(layer "In11.Cu")
		(net "M_H_CPU0_SA_CB<5>")
	)
	(gr_poly
		(pts
			(xy 381.231394 -248.45899) (xy 381.269748 -248.436892) (xy 381.091948 -248.129044) (xy 381.053594 -248.151142)
			(xy 380.945136 -248.267982) (xy 381.075946 -248.49455)
		)
		(stroke
			(width 0)
			(type solid)
		)
		(fill yes)
		(layer "In11.Cu")
		(net "M_H_CPU0_SB_CA<2>")
	)
	(gr_poly
		(pts
			(xy 381.334772 -271.467072) (xy 381.373126 -271.444974) (xy 381.195326 -271.137126) (xy 381.156972 -271.159224)
			(xy 381.048514 -271.276064) (xy 381.179324 -271.502632)
		)
		(stroke
			(width 0)
			(type solid)
		)
		(fill yes)
		(layer "In11.Cu")
		(net "M_H_CPU0_SA_DQ<21>")
	)
	(gr_poly
		(pts
			(xy 381.33909 -266.591034) (xy 381.377444 -266.568936) (xy 381.199644 -266.261088) (xy 381.16129 -266.283186)
			(xy 381.052832 -266.400026) (xy 381.183642 -266.626594)
		)
		(stroke
			(width 0)
			(type solid)
		)
		(fill yes)
		(layer "In11.Cu")
		(net "M_H_CPU0_SA_DQS_DP<3>")
	)
	(gr_poly
		(pts
			(xy 381.341122 -269.850362) (xy 381.379476 -269.828264) (xy 381.201676 -269.520416) (xy 381.163322 -269.542514)
			(xy 381.054864 -269.659354) (xy 381.185674 -269.885922)
		)
		(stroke
			(width 0)
			(type solid)
		)
		(fill yes)
		(layer "In11.Cu")
		(net "M_H_CPU0_SA_DQ<24>")
	)
	(gr_poly
		(pts
			(xy 381.367538 -246.16029) (xy 381.367538 -246.116094) (xy 381.011938 -246.116094) (xy 381.011938 -246.16029)
			(xy 381.058928 -246.31269) (xy 381.320548 -246.31269)
		)
		(stroke
			(width 0)
			(type solid)
		)
		(fill yes)
		(layer "In11.Cu")
		(net "M_H_CPU0_SB_CA<6>")
	)
	(gr_poly
		(pts
			(xy 381.367538 -244.532658) (xy 381.367538 -244.488208) (xy 381.011938 -244.488208) (xy 381.011938 -244.532658)
			(xy 381.058928 -244.685058) (xy 381.320548 -244.685058)
		)
		(stroke
			(width 0)
			(type solid)
		)
		(fill yes)
		(layer "In11.Cu")
		(net "M_H_CPU0_SB_CB<6>")
	)
	(gr_poly
		(pts
			(xy 381.367538 -241.276886) (xy 381.367538 -241.23269) (xy 381.011938 -241.23269) (xy 381.011938 -241.276886)
			(xy 381.058928 -241.429286) (xy 381.320548 -241.429286)
		)
		(stroke
			(width 0)
			(type solid)
		)
		(fill yes)
		(layer "In11.Cu")
		(net "M_H_CPU0_SB_CB<0>")
	)
	(gr_poly
		(pts
			(xy 381.367538 -240.057178) (xy 381.320548 -239.904778) (xy 381.058928 -239.904778) (xy 381.011938 -240.057178)
			(xy 381.011938 -240.101628) (xy 381.367538 -240.101628)
		)
		(stroke
			(width 0)
			(type solid)
		)
		(fill yes)
		(layer "In11.Cu")
		(net "M_H_CPU0_SB_CB<3>")
	)
	(gr_poly
		(pts
			(xy 381.367538 -239.649254) (xy 381.367538 -239.604804) (xy 381.011938 -239.604804) (xy 381.011938 -239.649254)
			(xy 381.058928 -239.801654) (xy 381.320548 -239.801654)
		)
		(stroke
			(width 0)
			(type solid)
		)
		(fill yes)
		(layer "In11.Cu")
		(net "M_H_CPU0_SB_DQ<0>")
	)
	(gr_poly
		(pts
			(xy 381.367538 -236.39399) (xy 381.367538 -236.34954) (xy 381.011938 -236.34954) (xy 381.011938 -236.39399)
			(xy 381.058928 -236.54639) (xy 381.320548 -236.54639)
		)
		(stroke
			(width 0)
			(type solid)
		)
		(fill yes)
		(layer "In11.Cu")
		(net "M_H_CPU0_SB_DQ<4>")
	)
	(gr_poly
		(pts
			(xy 381.367538 -235.174282) (xy 381.320548 -235.021882) (xy 381.058928 -235.021882) (xy 381.011938 -235.174282)
			(xy 381.011938 -235.218478) (xy 381.367538 -235.218478)
		)
		(stroke
			(width 0)
			(type solid)
		)
		(fill yes)
		(layer "In11.Cu")
		(net "M_H_CPU0_SB_DQ<7>")
	)
	(gr_poly
		(pts
			(xy 381.367538 -234.76585) (xy 381.367538 -234.721654) (xy 381.011938 -234.721654) (xy 381.011938 -234.76585)
			(xy 381.058928 -234.91825) (xy 381.320548 -234.91825)
		)
		(stroke
			(width 0)
			(type solid)
		)
		(fill yes)
		(layer "In11.Cu")
		(net "M_H_CPU0_SB_DQ<8>")
	)
	(gr_poly
		(pts
			(xy 381.367538 -231.510586) (xy 381.367538 -231.466136) (xy 381.011938 -231.466136) (xy 381.011938 -231.510586)
			(xy 381.058928 -231.662986) (xy 381.320548 -231.662986)
		)
		(stroke
			(width 0)
			(type solid)
		)
		(fill yes)
		(layer "In11.Cu")
		(net "M_H_CPU0_SB_DQ<12>")
	)
	(gr_poly
		(pts
			(xy 381.367538 -230.290878) (xy 381.320548 -230.138478) (xy 381.058928 -230.138478) (xy 381.011938 -230.290878)
			(xy 381.011938 -230.335074) (xy 381.367538 -230.335074)
		)
		(stroke
			(width 0)
			(type solid)
		)
		(fill yes)
		(layer "In11.Cu")
		(net "M_H_CPU0_SB_DQ<15>")
	)
	(gr_poly
		(pts
			(xy 381.367538 -229.882446) (xy 381.367538 -229.83825) (xy 381.011938 -229.83825) (xy 381.011938 -229.882446)
			(xy 381.058928 -230.034846) (xy 381.320548 -230.034846)
		)
		(stroke
			(width 0)
			(type solid)
		)
		(fill yes)
		(layer "In11.Cu")
		(net "M_H_CPU0_SB_DQ<26>")
	)
	(gr_poly
		(pts
			(xy 381.367538 -227.035106) (xy 381.320548 -226.882706) (xy 381.058928 -226.882706) (xy 381.011938 -227.035106)
			(xy 381.011938 -227.079556) (xy 381.367538 -227.079556)
		)
		(stroke
			(width 0)
			(type solid)
		)
		(fill yes)
		(layer "In11.Cu")
		(net "M_H_CPU0_SB_DQS_DN<3>")
	)
	(gr_poly
		(pts
			(xy 381.367538 -226.627182) (xy 381.367538 -226.582732) (xy 381.011938 -226.582732) (xy 381.011938 -226.627182)
			(xy 381.058928 -226.779582) (xy 381.320548 -226.779582)
		)
		(stroke
			(width 0)
			(type solid)
		)
		(fill yes)
		(layer "In11.Cu")
		(net "M_H_CPU0_SB_DQ<30>")
	)
	(gr_poly
		(pts
			(xy 381.367538 -225.407474) (xy 381.320548 -225.255074) (xy 381.058928 -225.255074) (xy 381.011938 -225.407474)
			(xy 381.011938 -225.45167) (xy 381.367538 -225.45167)
		)
		(stroke
			(width 0)
			(type solid)
		)
		(fill yes)
		(layer "In11.Cu")
		(net "M_H_CPU0_SB_DQ<29>")
	)
	(gr_poly
		(pts
			(xy 381.37338 -236.802422) (xy 381.32639 -236.650022) (xy 381.06477 -236.650022) (xy 381.01778 -236.802422)
			(xy 381.01778 -236.846872) (xy 381.37338 -236.846872)
		)
		(stroke
			(width 0)
			(type solid)
		)
		(fill yes)
		(layer "In11.Cu")
		(net "M_H_CPU0_SB_DQS_DP<5>")
	)
	(gr_poly
		(pts
			(xy 381.37338 -231.919018) (xy 381.32639 -231.766618) (xy 381.06477 -231.766618) (xy 381.01778 -231.919018)
			(xy 381.01778 -231.963468) (xy 381.37338 -231.963468)
		)
		(stroke
			(width 0)
			(type solid)
		)
		(fill yes)
		(layer "In11.Cu")
		(net "M_H_CPU0_SB_DQS_DP<6>")
	)
	(gr_poly
		(pts
			(xy 381.373634 -249.415554) (xy 381.373634 -249.371358) (xy 381.018034 -249.371358) (xy 381.018034 -249.415554)
			(xy 381.065024 -249.567954) (xy 381.326644 -249.567954)
		)
		(stroke
			(width 0)
			(type solid)
		)
		(fill yes)
		(layer "In11.Cu")
		(net "M_H_CPU0_SB_CA<0>")
	)
	(gr_poly
		(pts
			(xy 381.373634 -243.313458) (xy 381.326644 -243.161058) (xy 381.065024 -243.161058) (xy 381.018034 -243.313458)
			(xy 381.018034 -243.357654) (xy 381.373634 -243.357654)
		)
		(stroke
			(width 0)
			(type solid)
		)
		(fill yes)
		(layer "In11.Cu")
		(net "M_H_CPU0_SB_CB<5>")
	)
	(gr_poly
		(pts
			(xy 381.373634 -242.904518) (xy 381.373634 -242.860322) (xy 381.018034 -242.860322) (xy 381.018034 -242.904518)
			(xy 381.065024 -243.056918) (xy 381.326644 -243.056918)
		)
		(stroke
			(width 0)
			(type solid)
		)
		(fill yes)
		(layer "In11.Cu")
		(net "M_H_CPU0_SB_DQS_DP<9>")
	)
	(gr_poly
		(pts
			(xy 381.373634 -241.685826) (xy 381.326644 -241.533426) (xy 381.065024 -241.533426) (xy 381.018034 -241.685826)
			(xy 381.018034 -241.730022) (xy 381.373634 -241.730022)
		)
		(stroke
			(width 0)
			(type solid)
		)
		(fill yes)
		(layer "In11.Cu")
		(net "M_H_CPU0_SB_DQS_DP<4>")
	)
	(gr_poly
		(pts
			(xy 381.373634 -238.430054) (xy 381.326644 -238.277654) (xy 381.065024 -238.277654) (xy 381.018034 -238.430054)
			(xy 381.018034 -238.47425) (xy 381.373634 -238.47425)
		)
		(stroke
			(width 0)
			(type solid)
		)
		(fill yes)
		(layer "In11.Cu")
		(net "M_H_CPU0_SB_DQ<3>")
	)
	(gr_poly
		(pts
			(xy 381.373634 -233.54665) (xy 381.326644 -233.39425) (xy 381.065024 -233.39425) (xy 381.018034 -233.54665)
			(xy 381.018034 -233.590846) (xy 381.373634 -233.590846)
		)
		(stroke
			(width 0)
			(type solid)
		)
		(fill yes)
		(layer "In11.Cu")
		(net "M_H_CPU0_SB_DQ<11>")
	)
	(gr_poly
		(pts
			(xy 381.373634 -228.663246) (xy 381.326644 -228.510846) (xy 381.065024 -228.510846) (xy 381.018034 -228.663246)
			(xy 381.018034 -228.707696) (xy 381.373634 -228.707696)
		)
		(stroke
			(width 0)
			(type solid)
		)
		(fill yes)
		(layer "In11.Cu")
		(net "M_H_CPU0_SB_DQ<25>")
	)
	(gr_poly
		(pts
			(xy 381.373634 -228.254814) (xy 381.373634 -228.210364) (xy 381.018034 -228.210364) (xy 381.018034 -228.254814)
			(xy 381.065024 -228.407214) (xy 381.326644 -228.407214)
		)
		(stroke
			(width 0)
			(type solid)
		)
		(fill yes)
		(layer "In11.Cu")
		(net "M_H_CPU0_SB_DQS_DN<8>")
	)
	(gr_poly
		(pts
			(xy 381.379476 -246.568722) (xy 381.332486 -246.416322) (xy 381.070866 -246.416322) (xy 381.023876 -246.568722)
			(xy 381.023876 -246.612918) (xy 381.379476 -246.612918)
		)
		(stroke
			(width 0)
			(type solid)
		)
		(fill yes)
		(layer "In11.Cu")
		(net "M_H_CPU0_SB_CA<5>")
	)
	(gr_poly
		(pts
			(xy 381.382016 -238.021622) (xy 381.382016 -237.977172) (xy 381.026416 -237.977172) (xy 381.026416 -238.021622)
			(xy 381.073406 -238.174022) (xy 381.335026 -238.174022)
		)
		(stroke
			(width 0)
			(type solid)
		)
		(fill yes)
		(layer "In11.Cu")
		(net "M_H_CPU0_SB_DQS_DP<0>")
	)
	(gr_poly
		(pts
			(xy 381.382016 -233.138218) (xy 381.382016 -233.093768) (xy 381.026416 -233.093768) (xy 381.026416 -233.138218)
			(xy 381.073406 -233.290618) (xy 381.335026 -233.290618)
		)
		(stroke
			(width 0)
			(type solid)
		)
		(fill yes)
		(layer "In11.Cu")
		(net "M_H_CPU0_SB_DQS_DP<1>")
	)
	(gr_poly
		(pts
			(xy 381.447802 -265.969242) (xy 381.55626 -265.852402) (xy 381.42545 -265.625834) (xy 381.270002 -265.661394)
			(xy 381.231648 -265.683492) (xy 381.409448 -265.99134)
		)
		(stroke
			(width 0)
			(type solid)
		)
		(fill yes)
		(layer "In11.Cu")
		(net "M_H_CPU0_SA_DQS_DN<3>")
	)
	(gr_poly
		(pts
			(xy 381.449834 -270.856456) (xy 381.558292 -270.739616) (xy 381.427482 -270.513048) (xy 381.272034 -270.548608)
			(xy 381.23368 -270.570706) (xy 381.41148 -270.878554)
		)
		(stroke
			(width 0)
			(type solid)
		)
		(fill yes)
		(layer "In11.Cu")
		(net "M_H_CPU0_SA_DQ<23>")
	)
	(gr_poly
		(pts
			(xy 381.450088 -269.22857) (xy 381.558546 -269.11173) (xy 381.427736 -268.885162) (xy 381.272288 -268.920722)
			(xy 381.233934 -268.94282) (xy 381.411734 -269.250668)
		)
		(stroke
			(width 0)
			(type solid)
		)
		(fill yes)
		(layer "In11.Cu")
		(net "M_H_CPU0_SA_DQ<26>")
	)
	(gr_poly
		(pts
			(xy 381.47498 -280.98242) (xy 381.42799 -280.83002) (xy 381.16637 -280.83002) (xy 381.11938 -280.98242)
			(xy 381.11938 -281.026616) (xy 381.47498 -281.026616)
		)
		(stroke
			(width 0)
			(type solid)
		)
		(fill yes)
		(layer "In11.Cu")
		(net "M_H_CPU0_SA_DQ<10>")
	)
	(gr_poly
		(pts
			(xy 381.47498 -280.574242) (xy 381.47498 -280.529792) (xy 381.11938 -280.529792) (xy 381.11938 -280.574242)
			(xy 381.16637 -280.726642) (xy 381.42799 -280.726642)
		)
		(stroke
			(width 0)
			(type solid)
		)
		(fill yes)
		(layer "In11.Cu")
		(net "M_H_CPU0_SA_DQ<9>")
	)
	(gr_poly
		(pts
			(xy 381.47498 -277.726394) (xy 381.42799 -277.573994) (xy 381.16637 -277.573994) (xy 381.11938 -277.726394)
			(xy 381.11938 -277.770844) (xy 381.47498 -277.770844)
		)
		(stroke
			(width 0)
			(type solid)
		)
		(fill yes)
		(layer "In11.Cu")
		(net "M_H_CPU0_SA_DQ<14>")
	)
	(gr_poly
		(pts
			(xy 381.47498 -277.318216) (xy 381.47498 -277.27402) (xy 381.11938 -277.27402) (xy 381.11938 -277.318216)
			(xy 381.16637 -277.470616) (xy 381.42799 -277.470616)
		)
		(stroke
			(width 0)
			(type solid)
		)
		(fill yes)
		(layer "In11.Cu")
		(net "M_H_CPU0_SA_DQ<13>")
	)
	(gr_poly
		(pts
			(xy 381.47498 -272.843498) (xy 381.42799 -272.691098) (xy 381.16637 -272.691098) (xy 381.11938 -272.843498)
			(xy 381.11938 -272.887694) (xy 381.47498 -272.887694)
		)
		(stroke
			(width 0)
			(type solid)
		)
		(fill yes)
		(layer "In11.Cu")
		(net "M_H_CPU0_SA_DQS_DP<7>")
	)
	(gr_poly
		(pts
			(xy 381.47498 -272.435066) (xy 381.47498 -272.39087) (xy 381.11938 -272.39087) (xy 381.11938 -272.435066)
			(xy 381.16637 -272.587466) (xy 381.42799 -272.587466)
		)
		(stroke
			(width 0)
			(type solid)
		)
		(fill yes)
		(layer "In11.Cu")
		(net "M_H_CPU0_SA_DQ<20>")
	)
	(gr_poly
		(pts
			(xy 381.47498 -267.960094) (xy 381.42799 -267.807694) (xy 381.16637 -267.807694) (xy 381.11938 -267.960094)
			(xy 381.11938 -268.00429) (xy 381.47498 -268.00429)
		)
		(stroke
			(width 0)
			(type solid)
		)
		(fill yes)
		(layer "In11.Cu")
		(net "M_H_CPU0_SA_DQ<27>")
	)
	(gr_poly
		(pts
			(xy 381.47498 -263.07669) (xy 381.42799 -262.92429) (xy 381.16637 -262.92429) (xy 381.11938 -263.07669)
			(xy 381.11938 -263.120886) (xy 381.47498 -263.120886)
		)
		(stroke
			(width 0)
			(type solid)
		)
		(fill yes)
		(layer "In11.Cu")
		(net "M_H_CPU0_SA_DQ<31>")
	)
	(gr_poly
		(pts
			(xy 381.47498 -262.668258) (xy 381.47498 -262.624062) (xy 381.11938 -262.624062) (xy 381.11938 -262.668258)
			(xy 381.16637 -262.820658) (xy 381.42799 -262.820658)
		)
		(stroke
			(width 0)
			(type solid)
		)
		(fill yes)
		(layer "In11.Cu")
		(net "M_H_CPU0_SA_CB<0>")
	)
	(gr_poly
		(pts
			(xy 381.47498 -261.449058) (xy 381.42799 -261.296658) (xy 381.16637 -261.296658) (xy 381.11938 -261.449058)
			(xy 381.11938 -261.493254) (xy 381.47498 -261.493254)
		)
		(stroke
			(width 0)
			(type solid)
		)
		(fill yes)
		(layer "In11.Cu")
		(net "M_H_CPU0_SA_CB<3>")
	)
	(gr_poly
		(pts
			(xy 381.47498 -259.412994) (xy 381.47498 -259.368544) (xy 381.11938 -259.368544) (xy 381.11938 -259.412994)
			(xy 381.16637 -259.565394) (xy 381.42799 -259.565394)
		)
		(stroke
			(width 0)
			(type solid)
		)
		(fill yes)
		(layer "In11.Cu")
		(net "M_H_CPU0_SA_CB<4>")
	)
	(gr_poly
		(pts
			(xy 381.47498 -256.565654) (xy 381.42799 -256.413254) (xy 381.16637 -256.413254) (xy 381.11938 -256.565654)
			(xy 381.11938 -256.60985) (xy 381.47498 -256.60985)
		)
		(stroke
			(width 0)
			(type solid)
		)
		(fill yes)
		(layer "In11.Cu")
		(net "M_H_CPU0_SA_CS_N<1>")
	)
	(gr_poly
		(pts
			(xy 381.47752 -279.354788) (xy 381.43053 -279.202388) (xy 381.16891 -279.202388) (xy 381.12192 -279.354788)
			(xy 381.12192 -279.398984) (xy 381.47752 -279.398984)
		)
		(stroke
			(width 0)
			(type solid)
		)
		(fill yes)
		(layer "In11.Cu")
		(net "M_H_CPU0_SA_DQS_DN<1>")
	)
	(gr_poly
		(pts
			(xy 381.47752 -278.945848) (xy 381.47752 -278.901652) (xy 381.12192 -278.901652) (xy 381.12192 -278.945848)
			(xy 381.16891 -279.098248) (xy 381.43053 -279.098248)
		)
		(stroke
			(width 0)
			(type solid)
		)
		(fill yes)
		(layer "In11.Cu")
		(net "M_H_CPU0_SA_DQS_DN<6>")
	)
	(gr_poly
		(pts
			(xy 381.47752 -274.062698) (xy 381.47752 -274.018248) (xy 381.12192 -274.018248) (xy 381.12192 -274.062698)
			(xy 381.16891 -274.215098) (xy 381.43053 -274.215098)
		)
		(stroke
			(width 0)
			(type solid)
		)
		(fill yes)
		(layer "In11.Cu")
		(net "M_H_CPU0_SA_DQS_DP<2>")
	)
	(gr_poly
		(pts
			(xy 381.47752 -264.29589) (xy 381.47752 -264.251694) (xy 381.12192 -264.251694) (xy 381.12192 -264.29589)
			(xy 381.16891 -264.44829) (xy 381.43053 -264.44829)
		)
		(stroke
			(width 0)
			(type solid)
		)
		(fill yes)
		(layer "In11.Cu")
		(net "M_H_CPU0_SA_DQ<28>")
	)
	(gr_poly
		(pts
			(xy 381.47752 -258.193286) (xy 381.43053 -258.040886) (xy 381.16891 -258.040886) (xy 381.12192 -258.193286)
			(xy 381.12192 -258.237482) (xy 381.47752 -258.237482)
		)
		(stroke
			(width 0)
			(type solid)
		)
		(fill yes)
		(layer "In11.Cu")
		(net "M_H_CPU0_SA_CB<7>")
	)
	(gr_poly
		(pts
			(xy 381.47752 -257.784854) (xy 381.47752 -257.740658) (xy 381.12192 -257.740658) (xy 381.12192 -257.784854)
			(xy 381.16891 -257.937254) (xy 381.43053 -257.937254)
		)
		(stroke
			(width 0)
			(type solid)
		)
		(fill yes)
		(layer "In11.Cu")
		(net "M_E_CPU0_ALERT_N")
	)
	(gr_poly
		(pts
			(xy 381.47752 -254.529082) (xy 381.47752 -254.484886) (xy 381.12192 -254.484886) (xy 381.12192 -254.529082)
			(xy 381.16891 -254.681482) (xy 381.43053 -254.681482)
		)
		(stroke
			(width 0)
			(type solid)
		)
		(fill yes)
		(layer "In11.Cu")
		(net "M_H_CPU0_SA_CA<2>")
	)
	(gr_poly
		(pts
			(xy 381.483362 -275.690584) (xy 381.483362 -275.646134) (xy 381.127762 -275.646134) (xy 381.127762 -275.690584)
			(xy 381.174752 -275.842984) (xy 381.436372 -275.842984)
		)
		(stroke
			(width 0)
			(type solid)
		)
		(fill yes)
		(layer "In11.Cu")
		(net "M_H_CPU0_SA_DQ<16>")
	)
	(gr_poly
		(pts
			(xy 381.483362 -261.040626) (xy 381.483362 -260.996176) (xy 381.127762 -260.996176) (xy 381.127762 -261.040626)
			(xy 381.174752 -261.193026) (xy 381.436372 -261.193026)
		)
		(stroke
			(width 0)
			(type solid)
		)
		(fill yes)
		(layer "In11.Cu")
		(net "M_H_CPU0_SA_DQS_DP<4>")
	)
	(gr_poly
		(pts
			(xy 381.483362 -259.821426) (xy 381.436372 -259.669026) (xy 381.174752 -259.669026) (xy 381.127762 -259.821426)
			(xy 381.127762 -259.865622) (xy 381.483362 -259.865622)
		)
		(stroke
			(width 0)
			(type solid)
		)
		(fill yes)
		(layer "In11.Cu")
		(net "M_H_CPU0_SA_DQS_DP<9>")
	)
	(gr_poly
		(pts
			(xy 381.483362 -256.157222) (xy 381.483362 -256.112772) (xy 381.127762 -256.112772) (xy 381.127762 -256.157222)
			(xy 381.174752 -256.309622) (xy 381.436372 -256.309622)
		)
		(stroke
			(width 0)
			(type solid)
		)
		(fill yes)
		(layer "In11.Cu")
		(net "M_H_CPU0_SA_CS_N<2>")
	)
	(gr_poly
		(pts
			(xy 381.489458 -274.47113) (xy 381.442468 -274.31873) (xy 381.180848 -274.31873) (xy 381.133858 -274.47113)
			(xy 381.133858 -274.51558) (xy 381.489458 -274.51558)
		)
		(stroke
			(width 0)
			(type solid)
		)
		(fill yes)
		(layer "In11.Cu")
		(net "M_H_CPU0_SA_DQ<19>")
	)
	(gr_poly
		(pts
			(xy 381.489458 -264.70483) (xy 381.442468 -264.55243) (xy 381.180848 -264.55243) (xy 381.133858 -264.70483)
			(xy 381.133858 -264.749026) (xy 381.489458 -264.749026)
		)
		(stroke
			(width 0)
			(type solid)
		)
		(fill yes)
		(layer "In11.Cu")
		(net "M_H_CPU0_SA_DQS_DP<8>")
	)
	(gr_poly
		(pts
			(xy 381.489458 -254.938022) (xy 381.442468 -254.785622) (xy 381.180848 -254.785622) (xy 381.133858 -254.938022)
			(xy 381.133858 -254.982218) (xy 381.489458 -254.982218)
		)
		(stroke
			(width 0)
			(type solid)
		)
		(fill yes)
		(layer "In11.Cu")
		(net "M_H_CPU0_SA_CA<0>")
	)
	(gr_poly
		(pts
			(xy 381.804672 -270.653002) (xy 381.843026 -270.630904) (xy 381.665226 -270.323056) (xy 381.626872 -270.345154)
			(xy 381.518414 -270.461994) (xy 381.649224 -270.688562)
		)
		(stroke
			(width 0)
			(type solid)
		)
		(fill yes)
		(layer "In11.Cu")
		(net "M_H_CPU0_SA_DQ<24>")
	)
	(gr_poly
		(pts
			(xy 381.810006 -267.406628) (xy 381.84836 -267.38453) (xy 381.67056 -267.076682) (xy 381.632206 -267.09878)
			(xy 381.523748 -267.21562) (xy 381.654558 -267.442188)
		)
		(stroke
			(width 0)
			(type solid)
		)
		(fill yes)
		(layer "In11.Cu")
		(net "M_H_CPU0_SA_DQS_DP<3>")
	)
	(gr_poly
		(pts
			(xy 381.81026 -269.035022) (xy 381.848614 -269.012924) (xy 381.670814 -268.705076) (xy 381.63246 -268.727174)
			(xy 381.524002 -268.844014) (xy 381.654812 -269.070582)
		)
		(stroke
			(width 0)
			(type solid)
		)
		(fill yes)
		(layer "In11.Cu")
		(net "M_H_CPU0_SA_DQ<25>")
	)
	(gr_poly
		(pts
			(xy 381.837438 -246.974106) (xy 381.837438 -246.92991) (xy 381.481838 -246.92991) (xy 381.481838 -246.974106)
			(xy 381.528828 -247.126506) (xy 381.790448 -247.126506)
		)
		(stroke
			(width 0)
			(type solid)
		)
		(fill yes)
		(layer "In11.Cu")
		(net "M_H_CPU0_SB_CA<4>")
	)
	(gr_poly
		(pts
			(xy 381.837438 -237.61573) (xy 381.790448 -237.46333) (xy 381.528828 -237.46333) (xy 381.481838 -237.61573)
			(xy 381.481838 -237.66018) (xy 381.837438 -237.66018)
		)
		(stroke
			(width 0)
			(type solid)
		)
		(fill yes)
		(layer "In11.Cu")
		(net "M_H_CPU0_SB_DQS_DN<0>")
	)
	(gr_poly
		(pts
			(xy 381.837438 -237.207806) (xy 381.837438 -237.163356) (xy 381.481838 -237.163356) (xy 381.481838 -237.207806)
			(xy 381.528828 -237.360206) (xy 381.790448 -237.360206)
		)
		(stroke
			(width 0)
			(type solid)
		)
		(fill yes)
		(layer "In11.Cu")
		(net "M_H_CPU0_SB_DQS_DN<5>")
	)
	(gr_poly
		(pts
			(xy 381.837438 -232.732326) (xy 381.790448 -232.579926) (xy 381.528828 -232.579926) (xy 381.481838 -232.732326)
			(xy 381.481838 -232.776776) (xy 381.837438 -232.776776)
		)
		(stroke
			(width 0)
			(type solid)
		)
		(fill yes)
		(layer "In11.Cu")
		(net "M_H_CPU0_SB_DQS_DN<1>")
	)
	(gr_poly
		(pts
			(xy 381.837438 -232.324402) (xy 381.837438 -232.279952) (xy 381.481838 -232.279952) (xy 381.481838 -232.324402)
			(xy 381.528828 -232.476802) (xy 381.790448 -232.476802)
		)
		(stroke
			(width 0)
			(type solid)
		)
		(fill yes)
		(layer "In11.Cu")
		(net "M_H_CPU0_SB_DQS_DN<6>")
	)
	(gr_poly
		(pts
			(xy 381.843534 -249.010678) (xy 381.796544 -248.858278) (xy 381.534924 -248.858278) (xy 381.487934 -249.010678)
			(xy 381.487934 -249.054874) (xy 381.843534 -249.054874)
		)
		(stroke
			(width 0)
			(type solid)
		)
		(fill yes)
		(layer "In11.Cu")
		(net "M_H_CPU0_SB_CA<1>")
	)
	(gr_poly
		(pts
			(xy 381.843534 -248.601738) (xy 381.843534 -248.557542) (xy 381.487934 -248.557542) (xy 381.487934 -248.601738)
			(xy 381.534924 -248.754138) (xy 381.796544 -248.754138)
		)
		(stroke
			(width 0)
			(type solid)
		)
		(fill yes)
		(layer "In11.Cu")
		(net "M_H_CPU0_SB_CA<2>")
	)
	(gr_poly
		(pts
			(xy 381.843534 -245.754906) (xy 381.796544 -245.602506) (xy 381.534924 -245.602506) (xy 381.487934 -245.754906)
			(xy 381.487934 -245.799356) (xy 381.843534 -245.799356)
		)
		(stroke
			(width 0)
			(type solid)
		)
		(fill yes)
		(layer "In11.Cu")
		(net "M_H_CPU0_SB_PAR")
	)
	(gr_poly
		(pts
			(xy 381.843534 -244.127274) (xy 381.796544 -243.974874) (xy 381.534924 -243.974874) (xy 381.487934 -244.127274)
			(xy 381.487934 -244.17147) (xy 381.843534 -244.17147)
		)
		(stroke
			(width 0)
			(type solid)
		)
		(fill yes)
		(layer "In11.Cu")
		(net "M_H_CPU0_SB_CB<4>")
	)
	(gr_poly
		(pts
			(xy 381.843534 -243.718334) (xy 381.843534 -243.674138) (xy 381.487934 -243.674138) (xy 381.487934 -243.718334)
			(xy 381.534924 -243.870734) (xy 381.796544 -243.870734)
		)
		(stroke
			(width 0)
			(type solid)
		)
		(fill yes)
		(layer "In11.Cu")
		(net "M_H_CPU0_SB_CB<7>")
	)
	(gr_poly
		(pts
			(xy 381.843534 -242.499134) (xy 381.796544 -242.346734) (xy 381.534924 -242.346734) (xy 381.487934 -242.499134)
			(xy 381.487934 -242.543584) (xy 381.843534 -242.543584)
		)
		(stroke
			(width 0)
			(type solid)
		)
		(fill yes)
		(layer "In11.Cu")
		(net "M_H_CPU0_SB_DQS_DN<9>")
	)
	(gr_poly
		(pts
			(xy 381.843534 -242.090702) (xy 381.843534 -242.046252) (xy 381.487934 -242.046252) (xy 381.487934 -242.090702)
			(xy 381.534924 -242.243102) (xy 381.796544 -242.243102)
		)
		(stroke
			(width 0)
			(type solid)
		)
		(fill yes)
		(layer "In11.Cu")
		(net "M_H_CPU0_SB_DQS_DN<4>")
	)
	(gr_poly
		(pts
			(xy 381.843534 -240.871502) (xy 381.796544 -240.719102) (xy 381.534924 -240.719102) (xy 381.487934 -240.871502)
			(xy 381.487934 -240.915952) (xy 381.843534 -240.915952)
		)
		(stroke
			(width 0)
			(type solid)
		)
		(fill yes)
		(layer "In11.Cu")
		(net "M_H_CPU0_SB_CB<2>")
	)
	(gr_poly
		(pts
			(xy 381.843534 -240.46307) (xy 381.843534 -240.41862) (xy 381.487934 -240.41862) (xy 381.487934 -240.46307)
			(xy 381.534924 -240.61547) (xy 381.796544 -240.61547)
		)
		(stroke
			(width 0)
			(type solid)
		)
		(fill yes)
		(layer "In11.Cu")
		(net "M_H_CPU0_SB_CB<1>")
	)
	(gr_poly
		(pts
			(xy 381.843534 -239.24387) (xy 381.796544 -239.09147) (xy 381.534924 -239.09147) (xy 381.487934 -239.24387)
			(xy 381.487934 -239.288066) (xy 381.843534 -239.288066)
		)
		(stroke
			(width 0)
			(type solid)
		)
		(fill yes)
		(layer "In11.Cu")
		(net "M_H_CPU0_SB_DQ<2>")
	)
	(gr_poly
		(pts
			(xy 381.843534 -238.83493) (xy 381.843534 -238.790734) (xy 381.487934 -238.790734) (xy 381.487934 -238.83493)
			(xy 381.534924 -238.98733) (xy 381.796544 -238.98733)
		)
		(stroke
			(width 0)
			(type solid)
		)
		(fill yes)
		(layer "In11.Cu")
		(net "M_H_CPU0_SB_DQ<1>")
	)
	(gr_poly
		(pts
			(xy 381.843534 -235.988098) (xy 381.796544 -235.835698) (xy 381.534924 -235.835698) (xy 381.487934 -235.988098)
			(xy 381.487934 -236.032548) (xy 381.843534 -236.032548)
		)
		(stroke
			(width 0)
			(type solid)
		)
		(fill yes)
		(layer "In11.Cu")
		(net "M_H_CPU0_SB_DQ<6>")
	)
	(gr_poly
		(pts
			(xy 381.843534 -235.579666) (xy 381.843534 -235.535216) (xy 381.487934 -235.535216) (xy 381.487934 -235.579666)
			(xy 381.534924 -235.732066) (xy 381.796544 -235.732066)
		)
		(stroke
			(width 0)
			(type solid)
		)
		(fill yes)
		(layer "In11.Cu")
		(net "M_H_CPU0_SB_DQ<5>")
	)
	(gr_poly
		(pts
			(xy 381.843534 -234.360466) (xy 381.796544 -234.208066) (xy 381.534924 -234.208066) (xy 381.487934 -234.360466)
			(xy 381.487934 -234.404916) (xy 381.843534 -234.404916)
		)
		(stroke
			(width 0)
			(type solid)
		)
		(fill yes)
		(layer "In11.Cu")
		(net "M_H_CPU0_SB_DQ<10>")
	)
	(gr_poly
		(pts
			(xy 381.843534 -233.952034) (xy 381.843534 -233.907584) (xy 381.487934 -233.907584) (xy 381.487934 -233.952034)
			(xy 381.534924 -234.104434) (xy 381.796544 -234.104434)
		)
		(stroke
			(width 0)
			(type solid)
		)
		(fill yes)
		(layer "In11.Cu")
		(net "M_H_CPU0_SB_DQ<9>")
	)
	(gr_poly
		(pts
			(xy 381.843534 -231.104694) (xy 381.796544 -230.952294) (xy 381.534924 -230.952294) (xy 381.487934 -231.104694)
			(xy 381.487934 -231.149144) (xy 381.843534 -231.149144)
		)
		(stroke
			(width 0)
			(type solid)
		)
		(fill yes)
		(layer "In11.Cu")
		(net "M_H_CPU0_SB_DQ<14>")
	)
	(gr_poly
		(pts
			(xy 381.843534 -230.696262) (xy 381.843534 -230.651812) (xy 381.487934 -230.651812) (xy 381.487934 -230.696262)
			(xy 381.534924 -230.848662) (xy 381.796544 -230.848662)
		)
		(stroke
			(width 0)
			(type solid)
		)
		(fill yes)
		(layer "In11.Cu")
		(net "M_H_CPU0_SB_DQ<13>")
	)
	(gr_poly
		(pts
			(xy 381.843534 -229.477062) (xy 381.796544 -229.324662) (xy 381.534924 -229.324662) (xy 381.487934 -229.477062)
			(xy 381.487934 -229.521512) (xy 381.843534 -229.521512)
		)
		(stroke
			(width 0)
			(type solid)
		)
		(fill yes)
		(layer "In11.Cu")
		(net "M_H_CPU0_SB_DQ<24>")
	)
	(gr_poly
		(pts
			(xy 381.843534 -229.06863) (xy 381.843534 -229.02418) (xy 381.487934 -229.02418) (xy 381.487934 -229.06863)
			(xy 381.534924 -229.22103) (xy 381.796544 -229.22103)
		)
		(stroke
			(width 0)
			(type solid)
		)
		(fill yes)
		(layer "In11.Cu")
		(net "M_H_CPU0_SB_DQ<27>")
	)
	(gr_poly
		(pts
			(xy 381.843534 -227.84943) (xy 381.796544 -227.69703) (xy 381.534924 -227.69703) (xy 381.487934 -227.84943)
			(xy 381.487934 -227.893626) (xy 381.843534 -227.893626)
		)
		(stroke
			(width 0)
			(type solid)
		)
		(fill yes)
		(layer "In11.Cu")
		(net "M_H_CPU0_SB_DQS_DP<8>")
	)
	(gr_poly
		(pts
			(xy 381.843534 -227.44049) (xy 381.843534 -227.396294) (xy 381.487934 -227.396294) (xy 381.487934 -227.44049)
			(xy 381.534924 -227.59289) (xy 381.796544 -227.59289)
		)
		(stroke
			(width 0)
			(type solid)
		)
		(fill yes)
		(layer "In11.Cu")
		(net "M_H_CPU0_SB_DQS_DP<3>")
	)
	(gr_poly
		(pts
			(xy 381.843534 -226.221798) (xy 381.796544 -226.069398) (xy 381.534924 -226.069398) (xy 381.487934 -226.221798)
			(xy 381.487934 -226.265994) (xy 381.843534 -226.265994)
		)
		(stroke
			(width 0)
			(type solid)
		)
		(fill yes)
		(layer "In11.Cu")
		(net "M_H_CPU0_SB_DQ<28>")
	)
	(gr_poly
		(pts
			(xy 381.843534 -225.812858) (xy 381.843534 -225.768662) (xy 381.487934 -225.768662) (xy 381.487934 -225.812858)
			(xy 381.534924 -225.965258) (xy 381.796544 -225.965258)
		)
		(stroke
			(width 0)
			(type solid)
		)
		(fill yes)
		(layer "In11.Cu")
		(net "M_H_CPU0_SB_DQ<31>")
	)
	(gr_poly
		(pts
			(xy 381.920496 -270.043402) (xy 382.028954 -269.926562) (xy 381.898144 -269.699994) (xy 381.742696 -269.735554)
			(xy 381.704342 -269.757652) (xy 381.882142 -270.0655)
		)
		(stroke
			(width 0)
			(type solid)
		)
		(fill yes)
		(layer "In11.Cu")
		(net "M_H_CPU0_SA_DQ<26>")
	)
	(gr_poly
		(pts
			(xy 381.924306 -268.421866) (xy 382.032764 -268.305026) (xy 381.901954 -268.078458) (xy 381.746506 -268.114018)
			(xy 381.708152 -268.136116) (xy 381.885952 -268.443964)
		)
		(stroke
			(width 0)
			(type solid)
		)
		(fill yes)
		(layer "In11.Cu")
		(net "M_H_CPU0_SA_DQ<27>")
	)
	(gr_poly
		(pts
			(xy 381.926084 -266.797028) (xy 382.034542 -266.680188) (xy 381.903732 -266.45362) (xy 381.748284 -266.48918)
			(xy 381.70993 -266.511278) (xy 381.88773 -266.819126)
		)
		(stroke
			(width 0)
			(type solid)
		)
		(fill yes)
		(layer "In11.Cu")
		(net "M_H_CPU0_SA_DQS_DN<3>")
	)
	(gr_poly
		(pts
			(xy 381.94742 -257.37947) (xy 381.90043 -257.22707) (xy 381.63881 -257.22707) (xy 381.59182 -257.37947)
			(xy 381.59182 -257.42392) (xy 381.94742 -257.42392)
		)
		(stroke
			(width 0)
			(type solid)
		)
		(fill yes)
		(layer "In11.Cu")
		(net "M_H_CPU0_ALERT_N")
	)
	(gr_poly
		(pts
			(xy 381.953516 -258.59867) (xy 381.953516 -258.554474) (xy 381.597916 -258.554474) (xy 381.597916 -258.59867)
			(xy 381.644906 -258.75107) (xy 381.906526 -258.75107)
		)
		(stroke
			(width 0)
			(type solid)
		)
		(fill yes)
		(layer "In11.Cu")
		(net "M_H_CPU0_SA_CB<5>")
	)
	(gr_poly
		(pts
			(xy 381.959358 -278.540718) (xy 381.912368 -278.388318) (xy 381.650748 -278.388318) (xy 381.603758 -278.540718)
			(xy 381.603758 -278.585168) (xy 381.959358 -278.585168)
		)
		(stroke
			(width 0)
			(type solid)
		)
		(fill yes)
		(layer "In11.Cu")
		(net "M_H_CPU0_SA_DQS_DP<6>")
	)
	(gr_poly
		(pts
			(xy 381.959358 -278.132032) (xy 381.959358 -278.087836) (xy 381.603758 -278.087836) (xy 381.603758 -278.132032)
			(xy 381.650748 -278.284432) (xy 381.912368 -278.284432)
		)
		(stroke
			(width 0)
			(type solid)
		)
		(fill yes)
		(layer "In11.Cu")
		(net "M_H_CPU0_SA_DQ<12>")
	)
	(gr_poly
		(pts
			(xy 381.959358 -275.284946) (xy 381.912368 -275.132546) (xy 381.650748 -275.132546) (xy 381.603758 -275.284946)
			(xy 381.603758 -275.329142) (xy 381.959358 -275.329142)
		)
		(stroke
			(width 0)
			(type solid)
		)
		(fill yes)
		(layer "In11.Cu")
		(net "M_H_CPU0_SA_DQ<18>")
	)
	(gr_poly
		(pts
			(xy 381.959358 -274.876514) (xy 381.959358 -274.832318) (xy 381.603758 -274.832318) (xy 381.603758 -274.876514)
			(xy 381.650748 -275.028914) (xy 381.912368 -275.028914)
		)
		(stroke
			(width 0)
			(type solid)
		)
		(fill yes)
		(layer "In11.Cu")
		(net "M_H_CPU0_SA_DQ<17>")
	)
	(gr_poly
		(pts
			(xy 381.959358 -265.110214) (xy 381.959358 -265.065764) (xy 381.603758 -265.065764) (xy 381.603758 -265.110214)
			(xy 381.650748 -265.262614) (xy 381.912368 -265.262614)
		)
		(stroke
			(width 0)
			(type solid)
		)
		(fill yes)
		(layer "In11.Cu")
		(net "M_H_CPU0_SA_DQS_DN<8>")
	)
	(gr_poly
		(pts
			(xy 381.959358 -260.634734) (xy 381.912368 -260.482334) (xy 381.650748 -260.482334) (xy 381.603758 -260.634734)
			(xy 381.603758 -260.679184) (xy 381.959358 -260.679184)
		)
		(stroke
			(width 0)
			(type solid)
		)
		(fill yes)
		(layer "In11.Cu")
		(net "M_H_CPU0_SA_DQS_DN<4>")
	)
	(gr_poly
		(pts
			(xy 381.959358 -260.22681) (xy 381.959358 -260.18236) (xy 381.603758 -260.18236) (xy 381.603758 -260.22681)
			(xy 381.650748 -260.37921) (xy 381.912368 -260.37921)
		)
		(stroke
			(width 0)
			(type solid)
		)
		(fill yes)
		(layer "In11.Cu")
		(net "M_H_CPU0_SA_DQS_DN<9>")
	)
	(gr_poly
		(pts
			(xy 381.959358 -256.971038) (xy 381.959358 -256.926588) (xy 381.603758 -256.926588) (xy 381.603758 -256.971038)
			(xy 381.650748 -257.123438) (xy 381.912368 -257.123438)
		)
		(stroke
			(width 0)
			(type solid)
		)
		(fill yes)
		(layer "In11.Cu")
		(net "M_H_CPU0_SA_CS_N<0>")
	)
	(gr_poly
		(pts
			(xy 381.959358 -255.751838) (xy 381.912368 -255.599438) (xy 381.650748 -255.599438) (xy 381.603758 -255.751838)
			(xy 381.603758 -255.796034) (xy 381.959358 -255.796034)
		)
		(stroke
			(width 0)
			(type solid)
		)
		(fill yes)
		(layer "In11.Cu")
		(net "M_H_CPU0_SA_CS_N<3>")
	)
	(gr_poly
		(pts
			(xy 381.959358 -255.343406) (xy 381.959358 -255.29921) (xy 381.603758 -255.29921) (xy 381.603758 -255.343406)
			(xy 381.650748 -255.495806) (xy 381.912368 -255.495806)
		)
		(stroke
			(width 0)
			(type solid)
		)
		(fill yes)
		(layer "In11.Cu")
		(net "M_H_CPU0_SA_CA<1>")
	)
	(gr_poly
		(pts
			(xy 381.961898 -281.387804) (xy 381.961898 -281.343608) (xy 381.606298 -281.343608) (xy 381.606298 -281.387804)
			(xy 381.653288 -281.540204) (xy 381.914908 -281.540204)
		)
		(stroke
			(width 0)
			(type solid)
		)
		(fill yes)
		(layer "In11.Cu")
		(net "M_H_CPU0_SA_DQ<8>")
	)
	(gr_poly
		(pts
			(xy 381.961898 -280.168096) (xy 381.914908 -280.015696) (xy 381.653288 -280.015696) (xy 381.606298 -280.168096)
			(xy 381.606298 -280.212546) (xy 381.961898 -280.212546)
		)
		(stroke
			(width 0)
			(type solid)
		)
		(fill yes)
		(layer "In11.Cu")
		(net "M_H_CPU0_SA_DQ<11>")
	)
	(gr_poly
		(pts
			(xy 381.961898 -279.760172) (xy 381.961898 -279.715722) (xy 381.606298 -279.715722) (xy 381.606298 -279.760172)
			(xy 381.653288 -279.912572) (xy 381.914908 -279.912572)
		)
		(stroke
			(width 0)
			(type solid)
		)
		(fill yes)
		(layer "In11.Cu")
		(net "M_H_CPU0_SA_DQS_DP<1>")
	)
	(gr_poly
		(pts
			(xy 381.961898 -276.912578) (xy 381.914908 -276.760178) (xy 381.653288 -276.760178) (xy 381.606298 -276.912578)
			(xy 381.606298 -276.957028) (xy 381.961898 -276.957028)
		)
		(stroke
			(width 0)
			(type solid)
		)
		(fill yes)
		(layer "In11.Cu")
		(net "M_H_CPU0_SA_DQ<15>")
	)
	(gr_poly
		(pts
			(xy 381.961898 -273.657314) (xy 381.914908 -273.504914) (xy 381.653288 -273.504914) (xy 381.606298 -273.657314)
			(xy 381.606298 -273.70151) (xy 381.961898 -273.70151)
		)
		(stroke
			(width 0)
			(type solid)
		)
		(fill yes)
		(layer "In11.Cu")
		(net "M_H_CPU0_SA_DQS_DN<2>")
	)
	(gr_poly
		(pts
			(xy 381.961898 -273.248882) (xy 381.961898 -273.204686) (xy 381.606298 -273.204686) (xy 381.606298 -273.248882)
			(xy 381.653288 -273.401282) (xy 381.914908 -273.401282)
		)
		(stroke
			(width 0)
			(type solid)
		)
		(fill yes)
		(layer "In11.Cu")
		(net "M_H_CPU0_SA_DQS_DN<7>")
	)
	(gr_poly
		(pts
			(xy 381.961898 -272.029174) (xy 381.914908 -271.876774) (xy 381.653288 -271.876774) (xy 381.606298 -272.029174)
			(xy 381.606298 -272.073624) (xy 381.961898 -272.073624)
		)
		(stroke
			(width 0)
			(type solid)
		)
		(fill yes)
		(layer "In11.Cu")
		(net "M_H_CPU0_SA_DQ<22>")
	)
	(gr_poly
		(pts
			(xy 381.961898 -271.62125) (xy 381.961898 -271.5768) (xy 381.606298 -271.5768) (xy 381.606298 -271.62125)
			(xy 381.653288 -271.77365) (xy 381.914908 -271.77365)
		)
		(stroke
			(width 0)
			(type solid)
		)
		(fill yes)
		(layer "In11.Cu")
		(net "M_H_CPU0_SA_DQ<21>")
	)
	(gr_poly
		(pts
			(xy 381.961898 -263.890506) (xy 381.914908 -263.738106) (xy 381.653288 -263.738106) (xy 381.606298 -263.890506)
			(xy 381.606298 -263.934956) (xy 381.961898 -263.934956)
		)
		(stroke
			(width 0)
			(type solid)
		)
		(fill yes)
		(layer "In11.Cu")
		(net "M_H_CPU0_SA_DQ<30>")
	)
	(gr_poly
		(pts
			(xy 381.961898 -263.482582) (xy 381.961898 -263.438132) (xy 381.606298 -263.438132) (xy 381.606298 -263.482582)
			(xy 381.653288 -263.634982) (xy 381.914908 -263.634982)
		)
		(stroke
			(width 0)
			(type solid)
		)
		(fill yes)
		(layer "In11.Cu")
		(net "M_H_CPU0_SA_DQ<29>")
	)
	(gr_poly
		(pts
			(xy 381.961898 -262.262874) (xy 381.914908 -262.110474) (xy 381.653288 -262.110474) (xy 381.606298 -262.262874)
			(xy 381.606298 -262.30707) (xy 381.961898 -262.30707)
		)
		(stroke
			(width 0)
			(type solid)
		)
		(fill yes)
		(layer "In11.Cu")
		(net "M_H_CPU0_SA_CB<2>")
	)
	(gr_poly
		(pts
			(xy 381.961898 -261.854442) (xy 381.961898 -261.810246) (xy 381.606298 -261.810246) (xy 381.606298 -261.854442)
			(xy 381.653288 -262.006842) (xy 381.914908 -262.006842)
		)
		(stroke
			(width 0)
			(type solid)
		)
		(fill yes)
		(layer "In11.Cu")
		(net "M_H_CPU0_SA_CB<1>")
	)
	(gr_poly
		(pts
			(xy 381.961898 -259.007102) (xy 381.914908 -258.854702) (xy 381.653288 -258.854702) (xy 381.606298 -259.007102)
			(xy 381.606298 -259.051552) (xy 381.961898 -259.051552)
		)
		(stroke
			(width 0)
			(type solid)
		)
		(fill yes)
		(layer "In11.Cu")
		(net "M_H_CPU0_SA_CB<6>")
	)
	(gr_poly
		(pts
			(xy 381.961898 -254.123698) (xy 381.914908 -253.971298) (xy 381.653288 -253.971298) (xy 381.606298 -254.123698)
			(xy 381.606298 -254.168148) (xy 381.961898 -254.168148)
		)
		(stroke
			(width 0)
			(type solid)
		)
		(fill yes)
		(layer "In11.Cu")
		(net "M_H_CPU0_SA_CA<3>")
	)
	(gr_poly
		(pts
			(xy 382.274572 -268.211554) (xy 382.312926 -268.189456) (xy 382.135126 -267.881608) (xy 382.096772 -267.903706)
			(xy 381.988314 -268.020546) (xy 382.119124 -268.247114)
		)
		(stroke
			(width 0)
			(type solid)
		)
		(fill yes)
		(layer "In11.Cu")
		(net "M_H_CPU0_SA_DQS_DP<3>")
	)
	(gr_poly
		(pts
			(xy 382.279906 -269.84833) (xy 382.31826 -269.826232) (xy 382.14046 -269.518384) (xy 382.102106 -269.540482)
			(xy 381.993648 -269.657322) (xy 382.124458 -269.88389)
		)
		(stroke
			(width 0)
			(type solid)
		)
		(fill yes)
		(layer "In11.Cu")
		(net "M_H_CPU0_SA_DQ<25>")
	)
	(gr_poly
		(pts
			(xy 382.307338 -244.53215) (xy 382.307338 -244.487954) (xy 381.951738 -244.487954) (xy 381.951738 -244.53215)
			(xy 381.998728 -244.68455) (xy 382.260348 -244.68455)
		)
		(stroke
			(width 0)
			(type solid)
		)
		(fill yes)
		(layer "In11.Cu")
		(net "M_H_CPU0_SB_CB<6>")
	)
	(gr_poly
		(pts
			(xy 382.307338 -243.313458) (xy 382.260348 -243.161058) (xy 381.998728 -243.161058) (xy 381.951738 -243.313458)
			(xy 381.951738 -243.357654) (xy 382.307338 -243.357654)
		)
		(stroke
			(width 0)
			(type solid)
		)
		(fill yes)
		(layer "In11.Cu")
		(net "M_H_CPU0_SB_CB<5>")
	)
	(gr_poly
		(pts
			(xy 382.307338 -242.904518) (xy 382.307338 -242.860322) (xy 381.951738 -242.860322) (xy 381.951738 -242.904518)
			(xy 381.998728 -243.056918) (xy 382.260348 -243.056918)
		)
		(stroke
			(width 0)
			(type solid)
		)
		(fill yes)
		(layer "In11.Cu")
		(net "M_H_CPU0_SB_DQS_DP<9>")
	)
	(gr_poly
		(pts
			(xy 382.307338 -241.685318) (xy 382.260348 -241.532918) (xy 381.998728 -241.532918) (xy 381.951738 -241.685318)
			(xy 381.951738 -241.729768) (xy 382.307338 -241.729768)
		)
		(stroke
			(width 0)
			(type solid)
		)
		(fill yes)
		(layer "In11.Cu")
		(net "M_H_CPU0_SB_DQS_DP<4>")
	)
	(gr_poly
		(pts
			(xy 382.307338 -241.276886) (xy 382.307338 -241.232436) (xy 381.951738 -241.232436) (xy 381.951738 -241.276886)
			(xy 381.998728 -241.429286) (xy 382.260348 -241.429286)
		)
		(stroke
			(width 0)
			(type solid)
		)
		(fill yes)
		(layer "In11.Cu")
		(net "M_H_CPU0_SB_CB<0>")
	)
	(gr_poly
		(pts
			(xy 382.307338 -240.057686) (xy 382.260348 -239.905286) (xy 381.998728 -239.905286) (xy 381.951738 -240.057686)
			(xy 381.951738 -240.101882) (xy 382.307338 -240.101882)
		)
		(stroke
			(width 0)
			(type solid)
		)
		(fill yes)
		(layer "In11.Cu")
		(net "M_H_CPU0_SB_CB<3>")
	)
	(gr_poly
		(pts
			(xy 382.307338 -239.648746) (xy 382.307338 -239.60455) (xy 381.951738 -239.60455) (xy 381.951738 -239.648746)
			(xy 381.998728 -239.801146) (xy 382.260348 -239.801146)
		)
		(stroke
			(width 0)
			(type solid)
		)
		(fill yes)
		(layer "In11.Cu")
		(net "M_H_CPU0_SB_DQ<0>")
	)
	(gr_poly
		(pts
			(xy 382.307338 -228.663246) (xy 382.260348 -228.510846) (xy 381.998728 -228.510846) (xy 381.951738 -228.663246)
			(xy 381.951738 -228.707696) (xy 382.307338 -228.707696)
		)
		(stroke
			(width 0)
			(type solid)
		)
		(fill yes)
		(layer "In11.Cu")
		(net "M_H_CPU0_SB_DQ<25>")
	)
	(gr_poly
		(pts
			(xy 382.307338 -228.254814) (xy 382.307338 -228.210364) (xy 381.951738 -228.210364) (xy 381.951738 -228.254814)
			(xy 381.998728 -228.407214) (xy 382.260348 -228.407214)
		)
		(stroke
			(width 0)
			(type solid)
		)
		(fill yes)
		(layer "In11.Cu")
		(net "M_H_CPU0_SB_DQS_DN<8>")
	)
	(gr_poly
		(pts
			(xy 382.307338 -227.035614) (xy 382.260348 -226.883214) (xy 381.998728 -226.883214) (xy 381.951738 -227.035614)
			(xy 381.951738 -227.07981) (xy 382.307338 -227.07981)
		)
		(stroke
			(width 0)
			(type solid)
		)
		(fill yes)
		(layer "In11.Cu")
		(net "M_H_CPU0_SB_DQS_DN<3>")
	)
	(gr_poly
		(pts
			(xy 382.307338 -226.626674) (xy 382.307338 -226.582478) (xy 381.951738 -226.582478) (xy 381.951738 -226.626674)
			(xy 381.998728 -226.779074) (xy 382.260348 -226.779074)
		)
		(stroke
			(width 0)
			(type solid)
		)
		(fill yes)
		(layer "In11.Cu")
		(net "M_H_CPU0_SB_DQ<30>")
	)
	(gr_poly
		(pts
			(xy 382.312926 -231.919018) (xy 382.265936 -231.766618) (xy 382.004316 -231.766618) (xy 381.957326 -231.919018)
			(xy 381.957326 -231.963468) (xy 382.312926 -231.963468)
		)
		(stroke
			(width 0)
			(type solid)
		)
		(fill yes)
		(layer "In11.Cu")
		(net "M_H_CPU0_SB_DQS_DP<6>")
	)
	(gr_poly
		(pts
			(xy 382.31318 -236.802422) (xy 382.26619 -236.650022) (xy 382.00457 -236.650022) (xy 381.95758 -236.802422)
			(xy 381.95758 -236.846872) (xy 382.31318 -236.846872)
		)
		(stroke
			(width 0)
			(type solid)
		)
		(fill yes)
		(layer "In11.Cu")
		(net "M_H_CPU0_SB_DQS_DP<5>")
	)
	(gr_poly
		(pts
			(xy 382.313434 -249.415554) (xy 382.313434 -249.371358) (xy 381.957834 -249.371358) (xy 381.957834 -249.415554)
			(xy 382.004824 -249.567954) (xy 382.266444 -249.567954)
		)
		(stroke
			(width 0)
			(type solid)
		)
		(fill yes)
		(layer "In11.Cu")
		(net "M_H_CPU0_SB_CA<0>")
	)
	(gr_poly
		(pts
			(xy 382.313434 -248.196354) (xy 382.266444 -248.043954) (xy 382.004824 -248.043954) (xy 381.957834 -248.196354)
			(xy 381.957834 -248.240804) (xy 382.313434 -248.240804)
		)
		(stroke
			(width 0)
			(type solid)
		)
		(fill yes)
		(layer "In11.Cu")
		(net "M_H_CPU0_SB_CA<3>")
	)
	(gr_poly
		(pts
			(xy 382.313434 -246.568722) (xy 382.266444 -246.416322) (xy 382.004824 -246.416322) (xy 381.957834 -246.568722)
			(xy 381.957834 -246.613172) (xy 382.313434 -246.613172)
		)
		(stroke
			(width 0)
			(type solid)
		)
		(fill yes)
		(layer "In11.Cu")
		(net "M_H_CPU0_SB_CA<5>")
	)
	(gr_poly
		(pts
			(xy 382.313434 -246.16029) (xy 382.313434 -246.11584) (xy 381.957834 -246.11584) (xy 381.957834 -246.16029)
			(xy 382.004824 -246.31269) (xy 382.266444 -246.31269)
		)
		(stroke
			(width 0)
			(type solid)
		)
		(fill yes)
		(layer "In11.Cu")
		(net "M_H_CPU0_SB_CA<6>")
	)
	(gr_poly
		(pts
			(xy 382.313434 -238.430054) (xy 382.266444 -238.277654) (xy 382.004824 -238.277654) (xy 381.957834 -238.430054)
			(xy 381.957834 -238.47425) (xy 382.313434 -238.47425)
		)
		(stroke
			(width 0)
			(type solid)
		)
		(fill yes)
		(layer "In11.Cu")
		(net "M_H_CPU0_SB_DQ<3>")
	)
	(gr_poly
		(pts
			(xy 382.313434 -238.021114) (xy 382.313434 -237.976918) (xy 381.957834 -237.976918) (xy 381.957834 -238.021114)
			(xy 382.004824 -238.173514) (xy 382.266444 -238.173514)
		)
		(stroke
			(width 0)
			(type solid)
		)
		(fill yes)
		(layer "In11.Cu")
		(net "M_H_CPU0_SB_DQS_DP<0>")
	)
	(gr_poly
		(pts
			(xy 382.313434 -236.393482) (xy 382.313434 -236.349286) (xy 381.957834 -236.349286) (xy 381.957834 -236.393482)
			(xy 382.004824 -236.545882) (xy 382.266444 -236.545882)
		)
		(stroke
			(width 0)
			(type solid)
		)
		(fill yes)
		(layer "In11.Cu")
		(net "M_H_CPU0_SB_DQ<4>")
	)
	(gr_poly
		(pts
			(xy 382.313434 -235.174282) (xy 382.266444 -235.021882) (xy 382.004824 -235.021882) (xy 381.957834 -235.174282)
			(xy 381.957834 -235.218732) (xy 382.313434 -235.218732)
		)
		(stroke
			(width 0)
			(type solid)
		)
		(fill yes)
		(layer "In11.Cu")
		(net "M_H_CPU0_SB_DQ<7>")
	)
	(gr_poly
		(pts
			(xy 382.313434 -234.76585) (xy 382.313434 -234.7214) (xy 381.957834 -234.7214) (xy 381.957834 -234.76585)
			(xy 382.004824 -234.91825) (xy 382.266444 -234.91825)
		)
		(stroke
			(width 0)
			(type solid)
		)
		(fill yes)
		(layer "In11.Cu")
		(net "M_H_CPU0_SB_DQ<8>")
	)
	(gr_poly
		(pts
			(xy 382.313434 -233.54665) (xy 382.266444 -233.39425) (xy 382.004824 -233.39425) (xy 381.957834 -233.54665)
			(xy 381.957834 -233.590846) (xy 382.313434 -233.590846)
		)
		(stroke
			(width 0)
			(type solid)
		)
		(fill yes)
		(layer "In11.Cu")
		(net "M_H_CPU0_SB_DQ<11>")
	)
	(gr_poly
		(pts
			(xy 382.313434 -233.13771) (xy 382.313434 -233.093514) (xy 381.957834 -233.093514) (xy 381.957834 -233.13771)
			(xy 382.004824 -233.29011) (xy 382.266444 -233.29011)
		)
		(stroke
			(width 0)
			(type solid)
		)
		(fill yes)
		(layer "In11.Cu")
		(net "M_H_CPU0_SB_DQS_DP<1>")
	)
	(gr_poly
		(pts
			(xy 382.313434 -231.510078) (xy 382.313434 -231.465882) (xy 381.957834 -231.465882) (xy 381.957834 -231.510078)
			(xy 382.004824 -231.662478) (xy 382.266444 -231.662478)
		)
		(stroke
			(width 0)
			(type solid)
		)
		(fill yes)
		(layer "In11.Cu")
		(net "M_H_CPU0_SB_DQ<12>")
	)
	(gr_poly
		(pts
			(xy 382.313434 -230.290878) (xy 382.266444 -230.138478) (xy 382.004824 -230.138478) (xy 381.957834 -230.290878)
			(xy 381.957834 -230.335328) (xy 382.313434 -230.335328)
		)
		(stroke
			(width 0)
			(type solid)
		)
		(fill yes)
		(layer "In11.Cu")
		(net "M_H_CPU0_SB_DQ<15>")
	)
	(gr_poly
		(pts
			(xy 382.313434 -229.882446) (xy 382.313434 -229.837996) (xy 381.957834 -229.837996) (xy 381.957834 -229.882446)
			(xy 382.004824 -230.034846) (xy 382.266444 -230.034846)
		)
		(stroke
			(width 0)
			(type solid)
		)
		(fill yes)
		(layer "In11.Cu")
		(net "M_H_CPU0_SB_DQ<26>")
	)
	(gr_poly
		(pts
			(xy 382.313434 -225.407474) (xy 382.266444 -225.255074) (xy 382.004824 -225.255074) (xy 381.957834 -225.407474)
			(xy 381.957834 -225.451924) (xy 382.313434 -225.451924)
		)
		(stroke
			(width 0)
			(type solid)
		)
		(fill yes)
		(layer "In11.Cu")
		(net "M_H_CPU0_SB_DQ<29>")
	)
	(gr_poly
		(pts
			(xy 382.388618 -269.22603) (xy 382.497076 -269.10919) (xy 382.366266 -268.882622) (xy 382.210818 -268.918182)
			(xy 382.172464 -268.94028) (xy 382.350264 -269.248128)
		)
		(stroke
			(width 0)
			(type solid)
		)
		(fill yes)
		(layer "In11.Cu")
		(net "M_H_CPU0_SA_DQ<27>")
	)
	(gr_poly
		(pts
			(xy 382.389634 -267.600938) (xy 382.498092 -267.484098) (xy 382.367282 -267.25753) (xy 382.211834 -267.29309)
			(xy 382.17348 -267.315188) (xy 382.35128 -267.623036)
		)
		(stroke
			(width 0)
			(type solid)
		)
		(fill yes)
		(layer "In11.Cu")
		(net "M_H_CPU0_SA_DQS_DN<3>")
	)
	(gr_poly
		(pts
			(xy 382.41478 -280.98242) (xy 382.36779 -280.83002) (xy 382.10617 -280.83002) (xy 382.05918 -280.98242)
			(xy 382.05918 -281.026616) (xy 382.41478 -281.026616)
		)
		(stroke
			(width 0)
			(type solid)
		)
		(fill yes)
		(layer "In11.Cu")
		(net "M_H_CPU0_SA_DQ<10>")
	)
	(gr_poly
		(pts
			(xy 382.41478 -280.574242) (xy 382.41478 -280.529792) (xy 382.05918 -280.529792) (xy 382.05918 -280.574242)
			(xy 382.10617 -280.726642) (xy 382.36779 -280.726642)
		)
		(stroke
			(width 0)
			(type solid)
		)
		(fill yes)
		(layer "In11.Cu")
		(net "M_H_CPU0_SA_DQ<9>")
	)
	(gr_poly
		(pts
			(xy 382.41478 -279.35428) (xy 382.36779 -279.20188) (xy 382.10617 -279.20188) (xy 382.05918 -279.35428)
			(xy 382.05918 -279.39873) (xy 382.41478 -279.39873)
		)
		(stroke
			(width 0)
			(type solid)
		)
		(fill yes)
		(layer "In11.Cu")
		(net "M_H_CPU0_SA_DQS_DN<1>")
	)
	(gr_poly
		(pts
			(xy 382.41478 -277.318216) (xy 382.41478 -277.27402) (xy 382.05918 -277.27402) (xy 382.05918 -277.318216)
			(xy 382.10617 -277.470616) (xy 382.36779 -277.470616)
		)
		(stroke
			(width 0)
			(type solid)
		)
		(fill yes)
		(layer "In11.Cu")
		(net "M_H_CPU0_SA_DQ<13>")
	)
	(gr_poly
		(pts
			(xy 382.41478 -275.690584) (xy 382.41478 -275.646388) (xy 382.05918 -275.646388) (xy 382.05918 -275.690584)
			(xy 382.10617 -275.842984) (xy 382.36779 -275.842984)
		)
		(stroke
			(width 0)
			(type solid)
		)
		(fill yes)
		(layer "In11.Cu")
		(net "M_H_CPU0_SA_DQ<16>")
	)
	(gr_poly
		(pts
			(xy 382.41478 -274.47113) (xy 382.36779 -274.31873) (xy 382.10617 -274.31873) (xy 382.05918 -274.47113)
			(xy 382.05918 -274.515326) (xy 382.41478 -274.515326)
		)
		(stroke
			(width 0)
			(type solid)
		)
		(fill yes)
		(layer "In11.Cu")
		(net "M_H_CPU0_SA_DQ<19>")
	)
	(gr_poly
		(pts
			(xy 382.41478 -274.062698) (xy 382.41478 -274.018502) (xy 382.05918 -274.018502) (xy 382.05918 -274.062698)
			(xy 382.10617 -274.215098) (xy 382.36779 -274.215098)
		)
		(stroke
			(width 0)
			(type solid)
		)
		(fill yes)
		(layer "In11.Cu")
		(net "M_H_CPU0_SA_DQS_DP<2>")
	)
	(gr_poly
		(pts
			(xy 382.41478 -272.843498) (xy 382.36779 -272.691098) (xy 382.10617 -272.691098) (xy 382.05918 -272.843498)
			(xy 382.05918 -272.887694) (xy 382.41478 -272.887694)
		)
		(stroke
			(width 0)
			(type solid)
		)
		(fill yes)
		(layer "In11.Cu")
		(net "M_H_CPU0_SA_DQS_DP<7>")
	)
	(gr_poly
		(pts
			(xy 382.41478 -272.435066) (xy 382.41478 -272.39087) (xy 382.05918 -272.39087) (xy 382.05918 -272.435066)
			(xy 382.10617 -272.587466) (xy 382.36779 -272.587466)
		)
		(stroke
			(width 0)
			(type solid)
		)
		(fill yes)
		(layer "In11.Cu")
		(net "M_H_CPU0_SA_DQ<20>")
	)
	(gr_poly
		(pts
			(xy 382.41478 -271.215358) (xy 382.36779 -271.062958) (xy 382.10617 -271.062958) (xy 382.05918 -271.215358)
			(xy 382.05918 -271.259808) (xy 382.41478 -271.259808)
		)
		(stroke
			(width 0)
			(type solid)
		)
		(fill yes)
		(layer "In11.Cu")
		(net "M_H_CPU0_SA_DQ<23>")
	)
	(gr_poly
		(pts
			(xy 382.41478 -270.807434) (xy 382.41478 -270.762984) (xy 382.05918 -270.762984) (xy 382.05918 -270.807434)
			(xy 382.10617 -270.959834) (xy 382.36779 -270.959834)
		)
		(stroke
			(width 0)
			(type solid)
		)
		(fill yes)
		(layer "In11.Cu")
		(net "M_H_CPU0_SA_DQ<24>")
	)
	(gr_poly
		(pts
			(xy 382.41478 -264.704322) (xy 382.36779 -264.551922) (xy 382.10617 -264.551922) (xy 382.05918 -264.704322)
			(xy 382.05918 -264.748772) (xy 382.41478 -264.748772)
		)
		(stroke
			(width 0)
			(type solid)
		)
		(fill yes)
		(layer "In11.Cu")
		(net "M_H_CPU0_SA_DQS_DP<8>")
	)
	(gr_poly
		(pts
			(xy 382.41478 -264.296398) (xy 382.41478 -264.251948) (xy 382.05918 -264.251948) (xy 382.05918 -264.296398)
			(xy 382.10617 -264.448798) (xy 382.36779 -264.448798)
		)
		(stroke
			(width 0)
			(type solid)
		)
		(fill yes)
		(layer "In11.Cu")
		(net "M_H_CPU0_SA_DQ<28>")
	)
	(gr_poly
		(pts
			(xy 382.41478 -263.07669) (xy 382.36779 -262.92429) (xy 382.10617 -262.92429) (xy 382.05918 -263.07669)
			(xy 382.05918 -263.120886) (xy 382.41478 -263.120886)
		)
		(stroke
			(width 0)
			(type solid)
		)
		(fill yes)
		(layer "In11.Cu")
		(net "M_H_CPU0_SA_DQ<31>")
	)
	(gr_poly
		(pts
			(xy 382.41478 -262.668258) (xy 382.41478 -262.624062) (xy 382.05918 -262.624062) (xy 382.05918 -262.668258)
			(xy 382.10617 -262.820658) (xy 382.36779 -262.820658)
		)
		(stroke
			(width 0)
			(type solid)
		)
		(fill yes)
		(layer "In11.Cu")
		(net "M_H_CPU0_SA_CB<0>")
	)
	(gr_poly
		(pts
			(xy 382.41478 -261.449058) (xy 382.36779 -261.296658) (xy 382.10617 -261.296658) (xy 382.05918 -261.449058)
			(xy 382.05918 -261.493254) (xy 382.41478 -261.493254)
		)
		(stroke
			(width 0)
			(type solid)
		)
		(fill yes)
		(layer "In11.Cu")
		(net "M_H_CPU0_SA_CB<3>")
	)
	(gr_poly
		(pts
			(xy 382.41478 -261.040626) (xy 382.41478 -260.99643) (xy 382.05918 -260.99643) (xy 382.05918 -261.040626)
			(xy 382.10617 -261.193026) (xy 382.36779 -261.193026)
		)
		(stroke
			(width 0)
			(type solid)
		)
		(fill yes)
		(layer "In11.Cu")
		(net "M_H_CPU0_SA_DQS_DP<4>")
	)
	(gr_poly
		(pts
			(xy 382.41478 -259.820918) (xy 382.36779 -259.668518) (xy 382.10617 -259.668518) (xy 382.05918 -259.820918)
			(xy 382.05918 -259.865368) (xy 382.41478 -259.865368)
		)
		(stroke
			(width 0)
			(type solid)
		)
		(fill yes)
		(layer "In11.Cu")
		(net "M_H_CPU0_SA_DQS_DP<9>")
	)
	(gr_poly
		(pts
			(xy 382.41478 -259.412994) (xy 382.41478 -259.368544) (xy 382.05918 -259.368544) (xy 382.05918 -259.412994)
			(xy 382.10617 -259.565394) (xy 382.36779 -259.565394)
		)
		(stroke
			(width 0)
			(type solid)
		)
		(fill yes)
		(layer "In11.Cu")
		(net "M_H_CPU0_SA_CB<4>")
	)
	(gr_poly
		(pts
			(xy 382.41478 -256.157222) (xy 382.41478 -256.113026) (xy 382.05918 -256.113026) (xy 382.05918 -256.157222)
			(xy 382.10617 -256.309622) (xy 382.36779 -256.309622)
		)
		(stroke
			(width 0)
			(type solid)
		)
		(fill yes)
		(layer "In11.Cu")
		(net "M_H_CPU0_SA_CS_N<2>")
	)
	(gr_poly
		(pts
			(xy 382.41478 -254.937514) (xy 382.36779 -254.785114) (xy 382.10617 -254.785114) (xy 382.05918 -254.937514)
			(xy 382.05918 -254.981964) (xy 382.41478 -254.981964)
		)
		(stroke
			(width 0)
			(type solid)
		)
		(fill yes)
		(layer "In11.Cu")
		(net "M_H_CPU0_SA_CA<0>")
	)
	(gr_poly
		(pts
			(xy 382.41478 -254.52959) (xy 382.41478 -254.48514) (xy 382.05918 -254.48514) (xy 382.05918 -254.52959)
			(xy 382.10617 -254.68199) (xy 382.36779 -254.68199)
		)
		(stroke
			(width 0)
			(type solid)
		)
		(fill yes)
		(layer "In11.Cu")
		(net "M_H_CPU0_SA_CA<2>")
	)
	(gr_poly
		(pts
			(xy 382.41732 -258.193286) (xy 382.37033 -258.040886) (xy 382.10871 -258.040886) (xy 382.06172 -258.193286)
			(xy 382.06172 -258.237736) (xy 382.41732 -258.237736)
		)
		(stroke
			(width 0)
			(type solid)
		)
		(fill yes)
		(layer "In11.Cu")
		(net "M_H_CPU0_SA_CB<7>")
	)
	(gr_poly
		(pts
			(xy 382.423162 -278.945848) (xy 382.423162 -278.901652) (xy 382.067562 -278.901652) (xy 382.067562 -278.945848)
			(xy 382.114552 -279.098248) (xy 382.376172 -279.098248)
		)
		(stroke
			(width 0)
			(type solid)
		)
		(fill yes)
		(layer "In11.Cu")
		(net "M_H_CPU0_SA_DQS_DN<6>")
	)
	(gr_poly
		(pts
			(xy 382.423162 -277.726902) (xy 382.376172 -277.574502) (xy 382.114552 -277.574502) (xy 382.067562 -277.726902)
			(xy 382.067562 -277.771098) (xy 382.423162 -277.771098)
		)
		(stroke
			(width 0)
			(type solid)
		)
		(fill yes)
		(layer "In11.Cu")
		(net "M_H_CPU0_SA_DQ<14>")
	)
	(gr_poly
		(pts
			(xy 382.423162 -256.565654) (xy 382.376172 -256.413254) (xy 382.114552 -256.413254) (xy 382.067562 -256.565654)
			(xy 382.067562 -256.610104) (xy 382.423162 -256.610104)
		)
		(stroke
			(width 0)
			(type solid)
		)
		(fill yes)
		(layer "In11.Cu")
		(net "M_H_CPU0_SA_CS_N<1>")
	)
	(gr_poly
		(pts
			(xy 382.429258 -257.784854) (xy 382.429258 -257.740404) (xy 382.073658 -257.740404) (xy 382.073658 -257.784854)
			(xy 382.120648 -257.937254) (xy 382.382268 -257.937254)
		)
		(stroke
			(width 0)
			(type solid)
		)
		(fill yes)
		(layer "In11.Cu")
		(net "M_E_CPU0_ALERT_N")
	)
	(gr_poly
		(pts
			(xy 382.744472 -282.047696) (xy 382.782826 -282.025598) (xy 382.605026 -281.71775) (xy 382.566672 -281.739848)
			(xy 382.458214 -281.856688) (xy 382.589024 -282.083256)
		)
		(stroke
			(width 0)
			(type solid)
		)
		(fill yes)
		(layer "In11.Cu")
		(net "M_H_CPU0_SA_DQ<8>")
	)
	(gr_poly
		(pts
			(xy 382.75006 -269.035022) (xy 382.788414 -269.012924) (xy 382.610614 -268.705076) (xy 382.57226 -268.727174)
			(xy 382.463802 -268.844014) (xy 382.594612 -269.070582)
		)
		(stroke
			(width 0)
			(type solid)
		)
		(fill yes)
		(layer "In11.Cu")
		(net "M_H_CPU0_SA_DQS_DP<3>")
	)
	(gr_poly
		(pts
			(xy 382.751838 -265.781028) (xy 382.790192 -265.75893) (xy 382.612392 -265.451082) (xy 382.574038 -265.47318)
			(xy 382.46558 -265.59002) (xy 382.59639 -265.816588)
		)
		(stroke
			(width 0)
			(type solid)
		)
		(fill yes)
		(layer "In11.Cu")
		(net "M_H_CPU0_SA_DQS_DN<8>")
	)
	(gr_poly
		(pts
			(xy 382.78308 -232.323894) (xy 382.78308 -232.279444) (xy 382.42748 -232.279444) (xy 382.42748 -232.323894)
			(xy 382.47447 -232.476294) (xy 382.73609 -232.476294)
		)
		(stroke
			(width 0)
			(type solid)
		)
		(fill yes)
		(layer "In11.Cu")
		(net "M_H_CPU0_SB_DQS_DN<6>")
	)
	(gr_poly
		(pts
			(xy 382.783334 -249.010678) (xy 382.736344 -248.858278) (xy 382.474724 -248.858278) (xy 382.427734 -249.010678)
			(xy 382.427734 -249.054874) (xy 382.783334 -249.054874)
		)
		(stroke
			(width 0)
			(type solid)
		)
		(fill yes)
		(layer "In11.Cu")
		(net "M_H_CPU0_SB_CA<1>")
	)
	(gr_poly
		(pts
			(xy 382.783334 -248.601738) (xy 382.783334 -248.557542) (xy 382.427734 -248.557542) (xy 382.427734 -248.601738)
			(xy 382.474724 -248.754138) (xy 382.736344 -248.754138)
		)
		(stroke
			(width 0)
			(type solid)
		)
		(fill yes)
		(layer "In11.Cu")
		(net "M_H_CPU0_SB_CA<2>")
	)
	(gr_poly
		(pts
			(xy 382.783334 -246.974106) (xy 382.783334 -246.929656) (xy 382.427734 -246.929656) (xy 382.427734 -246.974106)
			(xy 382.474724 -247.126506) (xy 382.736344 -247.126506)
		)
		(stroke
			(width 0)
			(type solid)
		)
		(fill yes)
		(layer "In11.Cu")
		(net "M_H_CPU0_SB_CA<4>")
	)
	(gr_poly
		(pts
			(xy 382.783334 -245.754906) (xy 382.736344 -245.602506) (xy 382.474724 -245.602506) (xy 382.427734 -245.754906)
			(xy 382.427734 -245.799356) (xy 382.783334 -245.799356)
		)
		(stroke
			(width 0)
			(type solid)
		)
		(fill yes)
		(layer "In11.Cu")
		(net "M_H_CPU0_SB_PAR")
	)
	(gr_poly
		(pts
			(xy 382.783334 -238.83493) (xy 382.783334 -238.790734) (xy 382.427734 -238.790734) (xy 382.427734 -238.83493)
			(xy 382.474724 -238.98733) (xy 382.736344 -238.98733)
		)
		(stroke
			(width 0)
			(type solid)
		)
		(fill yes)
		(layer "In11.Cu")
		(net "M_H_CPU0_SB_DQ<1>")
	)
	(gr_poly
		(pts
			(xy 382.783334 -237.616238) (xy 382.736344 -237.463838) (xy 382.474724 -237.463838) (xy 382.427734 -237.616238)
			(xy 382.427734 -237.660434) (xy 382.783334 -237.660434)
		)
		(stroke
			(width 0)
			(type solid)
		)
		(fill yes)
		(layer "In11.Cu")
		(net "M_H_CPU0_SB_DQS_DN<0>")
	)
	(gr_poly
		(pts
			(xy 382.783334 -237.207298) (xy 382.783334 -237.163102) (xy 382.427734 -237.163102) (xy 382.427734 -237.207298)
			(xy 382.474724 -237.359698) (xy 382.736344 -237.359698)
		)
		(stroke
			(width 0)
			(type solid)
		)
		(fill yes)
		(layer "In11.Cu")
		(net "M_H_CPU0_SB_DQS_DN<5>")
	)
	(gr_poly
		(pts
			(xy 382.783334 -235.988098) (xy 382.736344 -235.835698) (xy 382.474724 -235.835698) (xy 382.427734 -235.988098)
			(xy 382.427734 -236.032548) (xy 382.783334 -236.032548)
		)
		(stroke
			(width 0)
			(type solid)
		)
		(fill yes)
		(layer "In11.Cu")
		(net "M_H_CPU0_SB_DQ<6>")
	)
	(gr_poly
		(pts
			(xy 382.783334 -235.579666) (xy 382.783334 -235.535216) (xy 382.427734 -235.535216) (xy 382.427734 -235.579666)
			(xy 382.474724 -235.732066) (xy 382.736344 -235.732066)
		)
		(stroke
			(width 0)
			(type solid)
		)
		(fill yes)
		(layer "In11.Cu")
		(net "M_H_CPU0_SB_DQ<5>")
	)
	(gr_poly
		(pts
			(xy 382.783334 -234.360466) (xy 382.736344 -234.208066) (xy 382.474724 -234.208066) (xy 382.427734 -234.360466)
			(xy 382.427734 -234.404916) (xy 382.783334 -234.404916)
		)
		(stroke
			(width 0)
			(type solid)
		)
		(fill yes)
		(layer "In11.Cu")
		(net "M_H_CPU0_SB_DQ<10>")
	)
	(gr_poly
		(pts
			(xy 382.783334 -233.952034) (xy 382.783334 -233.907584) (xy 382.427734 -233.907584) (xy 382.427734 -233.952034)
			(xy 382.474724 -234.104434) (xy 382.736344 -234.104434)
		)
		(stroke
			(width 0)
			(type solid)
		)
		(fill yes)
		(layer "In11.Cu")
		(net "M_H_CPU0_SB_DQ<9>")
	)
	(gr_poly
		(pts
			(xy 382.783334 -232.732834) (xy 382.736344 -232.580434) (xy 382.474724 -232.580434) (xy 382.427734 -232.732834)
			(xy 382.427734 -232.77703) (xy 382.783334 -232.77703)
		)
		(stroke
			(width 0)
			(type solid)
		)
		(fill yes)
		(layer "In11.Cu")
		(net "M_H_CPU0_SB_DQS_DN<1>")
	)
	(gr_poly
		(pts
			(xy 382.783334 -231.104694) (xy 382.736344 -230.952294) (xy 382.474724 -230.952294) (xy 382.427734 -231.104694)
			(xy 382.427734 -231.149144) (xy 382.783334 -231.149144)
		)
		(stroke
			(width 0)
			(type solid)
		)
		(fill yes)
		(layer "In11.Cu")
		(net "M_H_CPU0_SB_DQ<14>")
	)
	(gr_poly
		(pts
			(xy 382.783334 -230.696262) (xy 382.783334 -230.651812) (xy 382.427734 -230.651812) (xy 382.427734 -230.696262)
			(xy 382.474724 -230.848662) (xy 382.736344 -230.848662)
		)
		(stroke
			(width 0)
			(type solid)
		)
		(fill yes)
		(layer "In11.Cu")
		(net "M_H_CPU0_SB_DQ<13>")
	)
	(gr_poly
		(pts
			(xy 382.783334 -229.477062) (xy 382.736344 -229.324662) (xy 382.474724 -229.324662) (xy 382.427734 -229.477062)
			(xy 382.427734 -229.521512) (xy 382.783334 -229.521512)
		)
		(stroke
			(width 0)
			(type solid)
		)
		(fill yes)
		(layer "In11.Cu")
		(net "M_H_CPU0_SB_DQ<24>")
	)
	(gr_poly
		(pts
			(xy 382.783334 -225.812858) (xy 382.783334 -225.768662) (xy 382.427734 -225.768662) (xy 382.427734 -225.812858)
			(xy 382.474724 -225.965258) (xy 382.736344 -225.965258)
		)
		(stroke
			(width 0)
			(type solid)
		)
		(fill yes)
		(layer "In11.Cu")
		(net "M_H_CPU0_SB_DQ<31>")
	)
	(gr_poly
		(pts
			(xy 382.791716 -244.126766) (xy 382.744726 -243.974366) (xy 382.483106 -243.974366) (xy 382.436116 -244.126766)
			(xy 382.436116 -244.171216) (xy 382.791716 -244.171216)
		)
		(stroke
			(width 0)
			(type solid)
		)
		(fill yes)
		(layer "In11.Cu")
		(net "M_H_CPU0_SB_CB<4>")
	)
	(gr_poly
		(pts
			(xy 382.791716 -243.718842) (xy 382.791716 -243.674392) (xy 382.436116 -243.674392) (xy 382.436116 -243.718842)
			(xy 382.483106 -243.871242) (xy 382.744726 -243.871242)
		)
		(stroke
			(width 0)
			(type solid)
		)
		(fill yes)
		(layer "In11.Cu")
		(net "M_H_CPU0_SB_CB<7>")
	)
	(gr_poly
		(pts
			(xy 382.791716 -242.499134) (xy 382.744726 -242.346734) (xy 382.483106 -242.346734) (xy 382.436116 -242.499134)
			(xy 382.436116 -242.54333) (xy 382.791716 -242.54333)
		)
		(stroke
			(width 0)
			(type solid)
		)
		(fill yes)
		(layer "In11.Cu")
		(net "M_H_CPU0_SB_DQS_DN<9>")
	)
	(gr_poly
		(pts
			(xy 382.791716 -242.090702) (xy 382.791716 -242.046506) (xy 382.436116 -242.046506) (xy 382.436116 -242.090702)
			(xy 382.483106 -242.243102) (xy 382.744726 -242.243102)
		)
		(stroke
			(width 0)
			(type solid)
		)
		(fill yes)
		(layer "In11.Cu")
		(net "M_H_CPU0_SB_DQS_DN<4>")
	)
	(gr_poly
		(pts
			(xy 382.791716 -240.871502) (xy 382.744726 -240.719102) (xy 382.483106 -240.719102) (xy 382.436116 -240.871502)
			(xy 382.436116 -240.915698) (xy 382.791716 -240.915698)
		)
		(stroke
			(width 0)
			(type solid)
		)
		(fill yes)
		(layer "In11.Cu")
		(net "M_H_CPU0_SB_CB<2>")
	)
	(gr_poly
		(pts
			(xy 382.791716 -240.46307) (xy 382.791716 -240.418874) (xy 382.436116 -240.418874) (xy 382.436116 -240.46307)
			(xy 382.483106 -240.61547) (xy 382.744726 -240.61547)
		)
		(stroke
			(width 0)
			(type solid)
		)
		(fill yes)
		(layer "In11.Cu")
		(net "M_H_CPU0_SB_CB<1>")
	)
	(gr_poly
		(pts
			(xy 382.791716 -239.243362) (xy 382.744726 -239.090962) (xy 382.483106 -239.090962) (xy 382.436116 -239.243362)
			(xy 382.436116 -239.287812) (xy 382.791716 -239.287812)
		)
		(stroke
			(width 0)
			(type solid)
		)
		(fill yes)
		(layer "In11.Cu")
		(net "M_H_CPU0_SB_DQ<2>")
	)
	(gr_poly
		(pts
			(xy 382.791716 -229.06863) (xy 382.791716 -229.024434) (xy 382.436116 -229.024434) (xy 382.436116 -229.06863)
			(xy 382.483106 -229.22103) (xy 382.744726 -229.22103)
		)
		(stroke
			(width 0)
			(type solid)
		)
		(fill yes)
		(layer "In11.Cu")
		(net "M_H_CPU0_SB_DQ<27>")
	)
	(gr_poly
		(pts
			(xy 382.791716 -227.848922) (xy 382.744726 -227.696522) (xy 382.483106 -227.696522) (xy 382.436116 -227.848922)
			(xy 382.436116 -227.893372) (xy 382.791716 -227.893372)
		)
		(stroke
			(width 0)
			(type solid)
		)
		(fill yes)
		(layer "In11.Cu")
		(net "M_H_CPU0_SB_DQS_DP<8>")
	)
	(gr_poly
		(pts
			(xy 382.791716 -227.440998) (xy 382.791716 -227.396548) (xy 382.436116 -227.396548) (xy 382.436116 -227.440998)
			(xy 382.483106 -227.593398) (xy 382.744726 -227.593398)
		)
		(stroke
			(width 0)
			(type solid)
		)
		(fill yes)
		(layer "In11.Cu")
		(net "M_H_CPU0_SB_DQS_DP<3>")
	)
	(gr_poly
		(pts
			(xy 382.791716 -226.22129) (xy 382.744726 -226.06889) (xy 382.483106 -226.06889) (xy 382.436116 -226.22129)
			(xy 382.436116 -226.26574) (xy 382.791716 -226.26574)
		)
		(stroke
			(width 0)
			(type solid)
		)
		(fill yes)
		(layer "In11.Cu")
		(net "M_H_CPU0_SB_DQ<28>")
	)
	(gr_poly
		(pts
			(xy 382.864106 -281.444192) (xy 382.972564 -281.327352) (xy 382.841754 -281.100784) (xy 382.686306 -281.136344)
			(xy 382.647952 -281.158442) (xy 382.825752 -281.46629)
		)
		(stroke
			(width 0)
			(type solid)
		)
		(fill yes)
		(layer "In11.Cu")
		(net "M_H_CPU0_SA_DQ<10>")
	)
	(gr_poly
		(pts
			(xy 382.864106 -265.166348) (xy 382.972564 -265.049508) (xy 382.841754 -264.82294) (xy 382.686306 -264.8585)
			(xy 382.647952 -264.880598) (xy 382.825752 -265.188446)
		)
		(stroke
			(width 0)
			(type solid)
		)
		(fill yes)
		(layer "In11.Cu")
		(net "M_H_CPU0_SA_DQS_DP<8>")
	)
	(gr_poly
		(pts
			(xy 382.865122 -268.424406) (xy 382.97358 -268.307566) (xy 382.84277 -268.080998) (xy 382.687322 -268.116558)
			(xy 382.648968 -268.138656) (xy 382.826768 -268.446504)
		)
		(stroke
			(width 0)
			(type solid)
		)
		(fill yes)
		(layer "In11.Cu")
		(net "M_H_CPU0_SA_DQS_DN<3>")
	)
	(gr_poly
		(pts
			(xy 382.893062 -280.16835) (xy 382.846072 -280.01595) (xy 382.584452 -280.01595) (xy 382.537462 -280.16835)
			(xy 382.537462 -280.2128) (xy 382.893062 -280.2128)
		)
		(stroke
			(width 0)
			(type solid)
		)
		(fill yes)
		(layer "In11.Cu")
		(net "M_H_CPU0_SA_DQ<11>")
	)
	(gr_poly
		(pts
			(xy 382.893062 -279.759664) (xy 382.893062 -279.715468) (xy 382.537462 -279.715468) (xy 382.537462 -279.759664)
			(xy 382.584452 -279.912064) (xy 382.846072 -279.912064)
		)
		(stroke
			(width 0)
			(type solid)
		)
		(fill yes)
		(layer "In11.Cu")
		(net "M_H_CPU0_SA_DQS_DP<1>")
	)
	(gr_poly
		(pts
			(xy 382.893062 -278.540718) (xy 382.846072 -278.388318) (xy 382.584452 -278.388318) (xy 382.537462 -278.540718)
			(xy 382.537462 -278.585168) (xy 382.893062 -278.585168)
		)
		(stroke
			(width 0)
			(type solid)
		)
		(fill yes)
		(layer "In11.Cu")
		(net "M_H_CPU0_SA_DQS_DP<6>")
	)
	(gr_poly
		(pts
			(xy 382.893062 -278.132032) (xy 382.893062 -278.087836) (xy 382.537462 -278.087836) (xy 382.537462 -278.132032)
			(xy 382.584452 -278.284432) (xy 382.846072 -278.284432)
		)
		(stroke
			(width 0)
			(type solid)
		)
		(fill yes)
		(layer "In11.Cu")
		(net "M_H_CPU0_SA_DQ<12>")
	)
	(gr_poly
		(pts
			(xy 382.893062 -257.37947) (xy 382.846072 -257.22707) (xy 382.584452 -257.22707) (xy 382.537462 -257.37947)
			(xy 382.537462 -257.42392) (xy 382.893062 -257.42392)
		)
		(stroke
			(width 0)
			(type solid)
		)
		(fill yes)
		(layer "In11.Cu")
		(net "M_H_CPU0_ALERT_N")
	)
	(gr_poly
		(pts
			(xy 382.893062 -256.971038) (xy 382.893062 -256.926588) (xy 382.537462 -256.926588) (xy 382.537462 -256.971038)
			(xy 382.584452 -257.123438) (xy 382.846072 -257.123438)
		)
		(stroke
			(width 0)
			(type solid)
		)
		(fill yes)
		(layer "In11.Cu")
		(net "M_H_CPU0_SA_CS_N<0>")
	)
	(gr_poly
		(pts
			(xy 382.893316 -258.59867) (xy 382.893316 -258.554474) (xy 382.537716 -258.554474) (xy 382.537716 -258.59867)
			(xy 382.584706 -258.75107) (xy 382.846326 -258.75107)
		)
		(stroke
			(width 0)
			(type solid)
		)
		(fill yes)
		(layer "In11.Cu")
		(net "M_H_CPU0_SA_CB<5>")
	)
	(gr_poly
		(pts
			(xy 382.896618 -275.284946) (xy 382.849628 -275.132546) (xy 382.588008 -275.132546) (xy 382.541018 -275.284946)
			(xy 382.541018 -275.329396) (xy 382.896618 -275.329396)
		)
		(stroke
			(width 0)
			(type solid)
		)
		(fill yes)
		(layer "In11.Cu")
		(net "M_H_CPU0_SA_DQ<18>")
	)
	(gr_poly
		(pts
			(xy 382.899158 -263.891014) (xy 382.852168 -263.738614) (xy 382.590548 -263.738614) (xy 382.543558 -263.891014)
			(xy 382.543558 -263.93521) (xy 382.899158 -263.93521)
		)
		(stroke
			(width 0)
			(type solid)
		)
		(fill yes)
		(layer "In11.Cu")
		(net "M_H_CPU0_SA_DQ<30>")
	)
	(gr_poly
		(pts
			(xy 382.899158 -263.482074) (xy 382.899158 -263.437878) (xy 382.543558 -263.437878) (xy 382.543558 -263.482074)
			(xy 382.590548 -263.634474) (xy 382.852168 -263.634474)
		)
		(stroke
			(width 0)
			(type solid)
		)
		(fill yes)
		(layer "In11.Cu")
		(net "M_H_CPU0_SA_DQ<29>")
	)
	(gr_poly
		(pts
			(xy 382.899158 -262.262874) (xy 382.852168 -262.110474) (xy 382.590548 -262.110474) (xy 382.543558 -262.262874)
			(xy 382.543558 -262.307324) (xy 382.899158 -262.307324)
		)
		(stroke
			(width 0)
			(type solid)
		)
		(fill yes)
		(layer "In11.Cu")
		(net "M_H_CPU0_SA_CB<2>")
	)
	(gr_poly
		(pts
			(xy 382.899158 -261.854442) (xy 382.899158 -261.809992) (xy 382.543558 -261.809992) (xy 382.543558 -261.854442)
			(xy 382.590548 -262.006842) (xy 382.852168 -262.006842)
		)
		(stroke
			(width 0)
			(type solid)
		)
		(fill yes)
		(layer "In11.Cu")
		(net "M_H_CPU0_SA_CB<1>")
	)
	(gr_poly
		(pts
			(xy 382.899158 -260.635242) (xy 382.852168 -260.482842) (xy 382.590548 -260.482842) (xy 382.543558 -260.635242)
			(xy 382.543558 -260.679438) (xy 382.899158 -260.679438)
		)
		(stroke
			(width 0)
			(type solid)
		)
		(fill yes)
		(layer "In11.Cu")
		(net "M_H_CPU0_SA_DQS_DN<4>")
	)
	(gr_poly
		(pts
			(xy 382.899158 -260.226302) (xy 382.899158 -260.182106) (xy 382.543558 -260.182106) (xy 382.543558 -260.226302)
			(xy 382.590548 -260.378702) (xy 382.852168 -260.378702)
		)
		(stroke
			(width 0)
			(type solid)
		)
		(fill yes)
		(layer "In11.Cu")
		(net "M_H_CPU0_SA_DQS_DN<9>")
	)
	(gr_poly
		(pts
			(xy 382.899158 -259.00761) (xy 382.852168 -258.85521) (xy 382.590548 -258.85521) (xy 382.543558 -259.00761)
			(xy 382.543558 -259.051806) (xy 382.899158 -259.051806)
		)
		(stroke
			(width 0)
			(type solid)
		)
		(fill yes)
		(layer "In11.Cu")
		(net "M_H_CPU0_SA_CB<6>")
	)
	(gr_poly
		(pts
			(xy 382.899158 -255.751838) (xy 382.852168 -255.599438) (xy 382.590548 -255.599438) (xy 382.543558 -255.751838)
			(xy 382.543558 -255.796288) (xy 382.899158 -255.796288)
		)
		(stroke
			(width 0)
			(type solid)
		)
		(fill yes)
		(layer "In11.Cu")
		(net "M_H_CPU0_SA_CS_N<3>")
	)
	(gr_poly
		(pts
			(xy 382.899158 -255.343406) (xy 382.899158 -255.298956) (xy 382.543558 -255.298956) (xy 382.543558 -255.343406)
			(xy 382.590548 -255.495806) (xy 382.852168 -255.495806)
		)
		(stroke
			(width 0)
			(type solid)
		)
		(fill yes)
		(layer "In11.Cu")
		(net "M_H_CPU0_SA_CA<1>")
	)
	(gr_poly
		(pts
			(xy 382.899158 -254.124206) (xy 382.852168 -253.971806) (xy 382.590548 -253.971806) (xy 382.543558 -254.124206)
			(xy 382.543558 -254.168402) (xy 382.899158 -254.168402)
		)
		(stroke
			(width 0)
			(type solid)
		)
		(fill yes)
		(layer "In11.Cu")
		(net "M_H_CPU0_SA_CA<3>")
	)
	(gr_poly
		(pts
			(xy 382.901698 -276.912578) (xy 382.854708 -276.760178) (xy 382.593088 -276.760178) (xy 382.546098 -276.912578)
			(xy 382.546098 -276.957028) (xy 382.901698 -276.957028)
		)
		(stroke
			(width 0)
			(type solid)
		)
		(fill yes)
		(layer "In11.Cu")
		(net "M_H_CPU0_SA_DQ<15>")
	)
	(gr_poly
		(pts
			(xy 382.901698 -273.657314) (xy 382.854708 -273.504914) (xy 382.593088 -273.504914) (xy 382.546098 -273.657314)
			(xy 382.546098 -273.70151) (xy 382.901698 -273.70151)
		)
		(stroke
			(width 0)
			(type solid)
		)
		(fill yes)
		(layer "In11.Cu")
		(net "M_H_CPU0_SA_DQS_DN<2>")
	)
	(gr_poly
		(pts
			(xy 382.901698 -273.248882) (xy 382.901698 -273.204686) (xy 382.546098 -273.204686) (xy 382.546098 -273.248882)
			(xy 382.593088 -273.401282) (xy 382.854708 -273.401282)
		)
		(stroke
			(width 0)
			(type solid)
		)
		(fill yes)
		(layer "In11.Cu")
		(net "M_H_CPU0_SA_DQS_DN<7>")
	)
	(gr_poly
		(pts
			(xy 382.901698 -272.029174) (xy 382.854708 -271.876774) (xy 382.593088 -271.876774) (xy 382.546098 -272.029174)
			(xy 382.546098 -272.073624) (xy 382.901698 -272.073624)
		)
		(stroke
			(width 0)
			(type solid)
		)
		(fill yes)
		(layer "In11.Cu")
		(net "M_H_CPU0_SA_DQ<22>")
	)
	(gr_poly
		(pts
			(xy 382.901698 -271.62125) (xy 382.901698 -271.5768) (xy 382.546098 -271.5768) (xy 382.546098 -271.62125)
			(xy 382.593088 -271.77365) (xy 382.854708 -271.77365)
		)
		(stroke
			(width 0)
			(type solid)
		)
		(fill yes)
		(layer "In11.Cu")
		(net "M_H_CPU0_SA_DQ<21>")
	)
	(gr_poly
		(pts
			(xy 382.901698 -270.401542) (xy 382.854708 -270.249142) (xy 382.593088 -270.249142) (xy 382.546098 -270.401542)
			(xy 382.546098 -270.445992) (xy 382.901698 -270.445992)
		)
		(stroke
			(width 0)
			(type solid)
		)
		(fill yes)
		(layer "In11.Cu")
		(net "M_H_CPU0_SA_DQ<26>")
	)
	(gr_poly
		(pts
			(xy 382.901698 -269.993618) (xy 382.901698 -269.949168) (xy 382.546098 -269.949168) (xy 382.546098 -269.993618)
			(xy 382.593088 -270.146018) (xy 382.854708 -270.146018)
		)
		(stroke
			(width 0)
			(type solid)
		)
		(fill yes)
		(layer "In11.Cu")
		(net "M_H_CPU0_SA_DQ<25>")
	)
	(gr_poly
		(pts
			(xy 382.902714 -274.876514) (xy 382.902714 -274.832318) (xy 382.547114 -274.832318) (xy 382.547114 -274.876514)
			(xy 382.594104 -275.028914) (xy 382.855724 -275.028914)
		)
		(stroke
			(width 0)
			(type solid)
		)
		(fill yes)
		(layer "In11.Cu")
		(net "M_H_CPU0_SA_DQ<17>")
	)
	(gr_poly
		(pts
			(xy 383.148332 -224.760028) (xy 383.109978 -224.73793) (xy 382.95453 -224.70237) (xy 382.82372 -224.928938)
			(xy 382.932178 -225.045778) (xy 382.970532 -225.067876)
		)
		(stroke
			(width 0)
			(type solid)
		)
		(fill yes)
		(layer "In11.Cu")
		(net "M_H_CPU0_SB_DQ<29>")
	)
	(gr_poly
		(pts
			(xy 383.214372 -266.583922) (xy 383.252726 -266.561824) (xy 383.074926 -266.253976) (xy 383.036572 -266.276074)
			(xy 382.928114 -266.392914) (xy 383.058924 -266.619482)
		)
		(stroke
			(width 0)
			(type solid)
		)
		(fill yes)
		(layer "In11.Cu")
		(net "M_H_CPU0_SA_DQS_DN<8>")
	)
	(gr_poly
		(pts
			(xy 383.214372 -264.956036) (xy 383.252726 -264.933938) (xy 383.074926 -264.62609) (xy 383.036572 -264.648188)
			(xy 382.928114 -264.765028) (xy 383.058924 -264.991596)
		)
		(stroke
			(width 0)
			(type solid)
		)
		(fill yes)
		(layer "In11.Cu")
		(net "M_H_CPU0_SA_DQ<28>")
	)
	(gr_poly
		(pts
			(xy 383.21869 -281.240992) (xy 383.257044 -281.218894) (xy 383.079244 -280.911046) (xy 383.04089 -280.933144)
			(xy 382.932432 -281.049984) (xy 383.063242 -281.276552)
		)
		(stroke
			(width 0)
			(type solid)
		)
		(fill yes)
		(layer "In11.Cu")
		(net "M_H_CPU0_SA_DQ<9>")
	)
	(gr_poly
		(pts
			(xy 383.220722 -282.872688) (xy 383.259076 -282.85059) (xy 383.081276 -282.542742) (xy 383.042922 -282.56484)
			(xy 382.934464 -282.68168) (xy 383.065274 -282.908248)
		)
		(stroke
			(width 0)
			(type solid)
		)
		(fill yes)
		(layer "In11.Cu")
		(net "M_H_CPU0_SA_DQ<8>")
	)
	(gr_poly
		(pts
			(xy 383.247138 -244.532658) (xy 383.247138 -244.488208) (xy 382.891538 -244.488208) (xy 382.891538 -244.532658)
			(xy 382.938528 -244.685058) (xy 383.200148 -244.685058)
		)
		(stroke
			(width 0)
			(type solid)
		)
		(fill yes)
		(layer "In11.Cu")
		(net "M_H_CPU0_SB_CB<6>")
	)
	(gr_poly
		(pts
			(xy 383.247138 -243.31295) (xy 383.200148 -243.16055) (xy 382.938528 -243.16055) (xy 382.891538 -243.31295)
			(xy 382.891538 -243.3574) (xy 383.247138 -243.3574)
		)
		(stroke
			(width 0)
			(type solid)
		)
		(fill yes)
		(layer "In11.Cu")
		(net "M_H_CPU0_SB_CB<5>")
	)
	(gr_poly
		(pts
			(xy 383.247138 -242.905026) (xy 383.247138 -242.860576) (xy 382.891538 -242.860576) (xy 382.891538 -242.905026)
			(xy 382.938528 -243.057426) (xy 383.200148 -243.057426)
		)
		(stroke
			(width 0)
			(type solid)
		)
		(fill yes)
		(layer "In11.Cu")
		(net "M_H_CPU0_SB_DQS_DP<9>")
	)
	(gr_poly
		(pts
			(xy 383.247138 -241.685318) (xy 383.200148 -241.532918) (xy 382.938528 -241.532918) (xy 382.891538 -241.685318)
			(xy 382.891538 -241.729514) (xy 383.247138 -241.729514)
		)
		(stroke
			(width 0)
			(type solid)
		)
		(fill yes)
		(layer "In11.Cu")
		(net "M_H_CPU0_SB_DQS_DP<4>")
	)
	(gr_poly
		(pts
			(xy 383.247138 -241.276886) (xy 383.247138 -241.23269) (xy 382.891538 -241.23269) (xy 382.891538 -241.276886)
			(xy 382.938528 -241.429286) (xy 383.200148 -241.429286)
		)
		(stroke
			(width 0)
			(type solid)
		)
		(fill yes)
		(layer "In11.Cu")
		(net "M_H_CPU0_SB_CB<0>")
	)
	(gr_poly
		(pts
			(xy 383.247138 -240.057178) (xy 383.200148 -239.904778) (xy 382.938528 -239.904778) (xy 382.891538 -240.057178)
			(xy 382.891538 -240.101628) (xy 383.247138 -240.101628)
		)
		(stroke
			(width 0)
			(type solid)
		)
		(fill yes)
		(layer "In11.Cu")
		(net "M_H_CPU0_SB_CB<3>")
	)
	(gr_poly
		(pts
			(xy 383.247138 -239.649254) (xy 383.247138 -239.604804) (xy 382.891538 -239.604804) (xy 382.891538 -239.649254)
			(xy 382.938528 -239.801654) (xy 383.200148 -239.801654)
		)
		(stroke
			(width 0)
			(type solid)
		)
		(fill yes)
		(layer "In11.Cu")
		(net "M_H_CPU0_SB_DQ<0>")
	)
	(gr_poly
		(pts
			(xy 383.247138 -236.393482) (xy 383.247138 -236.349286) (xy 382.891538 -236.349286) (xy 382.891538 -236.393482)
			(xy 382.938528 -236.545882) (xy 383.200148 -236.545882)
		)
		(stroke
			(width 0)
			(type solid)
		)
		(fill yes)
		(layer "In11.Cu")
		(net "M_H_CPU0_SB_DQ<4>")
	)
	(gr_poly
		(pts
			(xy 383.247138 -228.663246) (xy 383.200148 -228.510846) (xy 382.938528 -228.510846) (xy 382.891538 -228.663246)
			(xy 382.891538 -228.707442) (xy 383.247138 -228.707442)
		)
		(stroke
			(width 0)
			(type solid)
		)
		(fill yes)
		(layer "In11.Cu")
		(net "M_H_CPU0_SB_DQ<25>")
	)
	(gr_poly
		(pts
			(xy 383.247138 -228.254814) (xy 383.247138 -228.210618) (xy 382.891538 -228.210618) (xy 382.891538 -228.254814)
			(xy 382.938528 -228.407214) (xy 383.200148 -228.407214)
		)
		(stroke
			(width 0)
			(type solid)
		)
		(fill yes)
		(layer "In11.Cu")
		(net "M_H_CPU0_SB_DQS_DN<8>")
	)
	(gr_poly
		(pts
			(xy 383.247138 -227.035106) (xy 383.200148 -226.882706) (xy 382.938528 -226.882706) (xy 382.891538 -227.035106)
			(xy 382.891538 -227.079556) (xy 383.247138 -227.079556)
		)
		(stroke
			(width 0)
			(type solid)
		)
		(fill yes)
		(layer "In11.Cu")
		(net "M_H_CPU0_SB_DQS_DN<3>")
	)
	(gr_poly
		(pts
			(xy 383.247138 -226.627182) (xy 383.247138 -226.582732) (xy 382.891538 -226.582732) (xy 382.891538 -226.627182)
			(xy 382.938528 -226.779582) (xy 383.200148 -226.779582)
		)
		(stroke
			(width 0)
			(type solid)
		)
		(fill yes)
		(layer "In11.Cu")
		(net "M_H_CPU0_SB_DQ<30>")
	)
	(gr_poly
		(pts
			(xy 383.253234 -248.196354) (xy 383.206244 -248.043954) (xy 382.944624 -248.043954) (xy 382.897634 -248.196354)
			(xy 382.897634 -248.240804) (xy 383.253234 -248.240804)
		)
		(stroke
			(width 0)
			(type solid)
		)
		(fill yes)
		(layer "In11.Cu")
		(net "M_H_CPU0_SB_CA<3>")
	)
	(gr_poly
		(pts
			(xy 383.253234 -246.568722) (xy 383.206244 -246.416322) (xy 382.944624 -246.416322) (xy 382.897634 -246.568722)
			(xy 382.897634 -246.613172) (xy 383.253234 -246.613172)
		)
		(stroke
			(width 0)
			(type solid)
		)
		(fill yes)
		(layer "In11.Cu")
		(net "M_H_CPU0_SB_CA<5>")
	)
	(gr_poly
		(pts
			(xy 383.253234 -246.16029) (xy 383.253234 -246.11584) (xy 382.897634 -246.11584) (xy 382.897634 -246.16029)
			(xy 382.944624 -246.31269) (xy 383.206244 -246.31269)
		)
		(stroke
			(width 0)
			(type solid)
		)
		(fill yes)
		(layer "In11.Cu")
		(net "M_H_CPU0_SB_CA<6>")
	)
	(gr_poly
		(pts
			(xy 383.253234 -238.430054) (xy 383.206244 -238.277654) (xy 382.944624 -238.277654) (xy 382.897634 -238.430054)
			(xy 382.897634 -238.47425) (xy 383.253234 -238.47425)
		)
		(stroke
			(width 0)
			(type solid)
		)
		(fill yes)
		(layer "In11.Cu")
		(net "M_H_CPU0_SB_DQ<3>")
	)
	(gr_poly
		(pts
			(xy 383.253234 -238.021114) (xy 383.253234 -237.976918) (xy 382.897634 -237.976918) (xy 382.897634 -238.021114)
			(xy 382.944624 -238.173514) (xy 383.206244 -238.173514)
		)
		(stroke
			(width 0)
			(type solid)
		)
		(fill yes)
		(layer "In11.Cu")
		(net "M_H_CPU0_SB_DQS_DP<0>")
	)
	(gr_poly
		(pts
			(xy 383.253234 -236.802422) (xy 383.206244 -236.650022) (xy 382.944624 -236.650022) (xy 382.897634 -236.802422)
			(xy 382.897634 -236.846872) (xy 383.253234 -236.846872)
		)
		(stroke
			(width 0)
			(type solid)
		)
		(fill yes)
		(layer "In11.Cu")
		(net "M_H_CPU0_SB_DQS_DP<5>")
	)
	(gr_poly
		(pts
			(xy 383.253234 -235.174282) (xy 383.206244 -235.021882) (xy 382.944624 -235.021882) (xy 382.897634 -235.174282)
			(xy 382.897634 -235.218732) (xy 383.253234 -235.218732)
		)
		(stroke
			(width 0)
			(type solid)
		)
		(fill yes)
		(layer "In11.Cu")
		(net "M_H_CPU0_SB_DQ<7>")
	)
	(gr_poly
		(pts
			(xy 383.253234 -234.76585) (xy 383.253234 -234.7214) (xy 382.897634 -234.7214) (xy 382.897634 -234.76585)
			(xy 382.944624 -234.91825) (xy 383.206244 -234.91825)
		)
		(stroke
			(width 0)
			(type solid)
		)
		(fill yes)
		(layer "In11.Cu")
		(net "M_H_CPU0_SB_DQ<8>")
	)
	(gr_poly
		(pts
			(xy 383.253234 -233.54665) (xy 383.206244 -233.39425) (xy 382.944624 -233.39425) (xy 382.897634 -233.54665)
			(xy 382.897634 -233.590846) (xy 383.253234 -233.590846)
		)
		(stroke
			(width 0)
			(type solid)
		)
		(fill yes)
		(layer "In11.Cu")
		(net "M_H_CPU0_SB_DQ<11>")
	)
	(gr_poly
		(pts
			(xy 383.253234 -233.13771) (xy 383.253234 -233.093514) (xy 382.897634 -233.093514) (xy 382.897634 -233.13771)
			(xy 382.944624 -233.29011) (xy 383.206244 -233.29011)
		)
		(stroke
			(width 0)
			(type solid)
		)
		(fill yes)
		(layer "In11.Cu")
		(net "M_H_CPU0_SB_DQS_DP<1>")
	)
	(gr_poly
		(pts
			(xy 383.253234 -231.919018) (xy 383.206244 -231.766618) (xy 382.944624 -231.766618) (xy 382.897634 -231.919018)
			(xy 382.897634 -231.963214) (xy 383.253234 -231.963214)
		)
		(stroke
			(width 0)
			(type solid)
		)
		(fill yes)
		(layer "In11.Cu")
		(net "M_H_CPU0_SB_DQS_DP<6>")
	)
	(gr_poly
		(pts
			(xy 383.253234 -231.510078) (xy 383.253234 -231.465882) (xy 382.897634 -231.465882) (xy 382.897634 -231.510078)
			(xy 382.944624 -231.662478) (xy 383.206244 -231.662478)
		)
		(stroke
			(width 0)
			(type solid)
		)
		(fill yes)
		(layer "In11.Cu")
		(net "M_H_CPU0_SB_DQ<12>")
	)
	(gr_poly
		(pts
			(xy 383.253234 -230.290878) (xy 383.206244 -230.138478) (xy 382.944624 -230.138478) (xy 382.897634 -230.290878)
			(xy 382.897634 -230.335328) (xy 383.253234 -230.335328)
		)
		(stroke
			(width 0)
			(type solid)
		)
		(fill yes)
		(layer "In11.Cu")
		(net "M_H_CPU0_SB_DQ<15>")
	)
	(gr_poly
		(pts
			(xy 383.253234 -229.882446) (xy 383.253234 -229.837996) (xy 382.897634 -229.837996) (xy 382.897634 -229.882446)
			(xy 382.944624 -230.034846) (xy 383.206244 -230.034846)
		)
		(stroke
			(width 0)
			(type solid)
		)
		(fill yes)
		(layer "In11.Cu")
		(net "M_H_CPU0_SB_DQ<26>")
	)
	(gr_poly
		(pts
			(xy 383.326132 -225.479102) (xy 383.217674 -225.362262) (xy 383.17932 -225.340164) (xy 383.00152 -225.648012)
			(xy 383.039874 -225.67011) (xy 383.195322 -225.70567)
		)
		(stroke
			(width 0)
			(type solid)
		)
		(fill yes)
		(layer "In11.Cu")
		(net "M_H_CPU0_SB_DQ<31>")
	)
	(gr_poly
		(pts
			(xy 383.32664 -265.969242) (xy 383.435098 -265.852402) (xy 383.304288 -265.625834) (xy 383.14884 -265.661394)
			(xy 383.110486 -265.683492) (xy 383.288286 -265.99134)
		)
		(stroke
			(width 0)
			(type solid)
		)
		(fill yes)
		(layer "In11.Cu")
		(net "M_H_CPU0_SA_DQS_DP<8>")
	)
	(gr_poly
		(pts
			(xy 383.328418 -280.621232) (xy 383.436876 -280.504392) (xy 383.306066 -280.277824) (xy 383.150618 -280.313384)
			(xy 383.112264 -280.335482) (xy 383.290064 -280.64333)
		)
		(stroke
			(width 0)
			(type solid)
		)
		(fill yes)
		(layer "In11.Cu")
		(net "M_H_CPU0_SA_DQ<11>")
	)
	(gr_poly
		(pts
			(xy 383.329434 -264.34542) (xy 383.437892 -264.22858) (xy 383.307082 -264.002012) (xy 383.151634 -264.037572)
			(xy 383.11328 -264.05967) (xy 383.29108 -264.367518)
		)
		(stroke
			(width 0)
			(type solid)
		)
		(fill yes)
		(layer "In11.Cu")
		(net "M_H_CPU0_SA_DQ<30>")
	)
	(gr_poly
		(pts
			(xy 383.334006 -282.258008) (xy 383.442464 -282.141168) (xy 383.311654 -281.9146) (xy 383.156206 -281.95016)
			(xy 383.117852 -281.972258) (xy 383.295652 -282.280106)
		)
		(stroke
			(width 0)
			(type solid)
		)
		(fill yes)
		(layer "In11.Cu")
		(net "M_H_CPU0_SA_DQ<10>")
	)
	(gr_poly
		(pts
			(xy 383.35458 -277.318216) (xy 383.35458 -277.27402) (xy 382.99898 -277.27402) (xy 382.99898 -277.318216)
			(xy 383.04597 -277.470616) (xy 383.30759 -277.470616)
		)
		(stroke
			(width 0)
			(type solid)
		)
		(fill yes)
		(layer "In11.Cu")
		(net "M_H_CPU0_SA_DQ<13>")
	)
	(gr_poly
		(pts
			(xy 383.35458 -275.690584) (xy 383.35458 -275.646388) (xy 382.99898 -275.646388) (xy 382.99898 -275.690584)
			(xy 383.04597 -275.842984) (xy 383.30759 -275.842984)
		)
		(stroke
			(width 0)
			(type solid)
		)
		(fill yes)
		(layer "In11.Cu")
		(net "M_H_CPU0_SA_DQ<16>")
	)
	(gr_poly
		(pts
			(xy 383.35458 -274.47113) (xy 383.30759 -274.31873) (xy 383.04597 -274.31873) (xy 382.99898 -274.47113)
			(xy 382.99898 -274.515326) (xy 383.35458 -274.515326)
		)
		(stroke
			(width 0)
			(type solid)
		)
		(fill yes)
		(layer "In11.Cu")
		(net "M_H_CPU0_SA_DQ<19>")
	)
	(gr_poly
		(pts
			(xy 383.35458 -274.062698) (xy 383.35458 -274.018502) (xy 382.99898 -274.018502) (xy 382.99898 -274.062698)
			(xy 383.04597 -274.215098) (xy 383.30759 -274.215098)
		)
		(stroke
			(width 0)
			(type solid)
		)
		(fill yes)
		(layer "In11.Cu")
		(net "M_H_CPU0_SA_DQS_DP<2>")
	)
	(gr_poly
		(pts
			(xy 383.35458 -272.843498) (xy 383.30759 -272.691098) (xy 383.04597 -272.691098) (xy 382.99898 -272.843498)
			(xy 382.99898 -272.887694) (xy 383.35458 -272.887694)
		)
		(stroke
			(width 0)
			(type solid)
		)
		(fill yes)
		(layer "In11.Cu")
		(net "M_H_CPU0_SA_DQS_DP<7>")
	)
	(gr_poly
		(pts
			(xy 383.35458 -272.435066) (xy 383.35458 -272.39087) (xy 382.99898 -272.39087) (xy 382.99898 -272.435066)
			(xy 383.04597 -272.587466) (xy 383.30759 -272.587466)
		)
		(stroke
			(width 0)
			(type solid)
		)
		(fill yes)
		(layer "In11.Cu")
		(net "M_H_CPU0_SA_DQ<20>")
	)
	(gr_poly
		(pts
			(xy 383.35458 -271.215358) (xy 383.30759 -271.062958) (xy 383.04597 -271.062958) (xy 382.99898 -271.215358)
			(xy 382.99898 -271.259808) (xy 383.35458 -271.259808)
		)
		(stroke
			(width 0)
			(type solid)
		)
		(fill yes)
		(layer "In11.Cu")
		(net "M_H_CPU0_SA_DQ<23>")
	)
	(gr_poly
		(pts
			(xy 383.35458 -270.807434) (xy 383.35458 -270.762984) (xy 382.99898 -270.762984) (xy 382.99898 -270.807434)
			(xy 383.04597 -270.959834) (xy 383.30759 -270.959834)
		)
		(stroke
			(width 0)
			(type solid)
		)
		(fill yes)
		(layer "In11.Cu")
		(net "M_H_CPU0_SA_DQ<24>")
	)
	(gr_poly
		(pts
			(xy 383.35458 -269.587726) (xy 383.30759 -269.435326) (xy 383.04597 -269.435326) (xy 382.99898 -269.587726)
			(xy 382.99898 -269.631922) (xy 383.35458 -269.631922)
		)
		(stroke
			(width 0)
			(type solid)
		)
		(fill yes)
		(layer "In11.Cu")
		(net "M_H_CPU0_SA_DQ<27>")
	)
	(gr_poly
		(pts
			(xy 383.35458 -269.179294) (xy 383.35458 -269.135098) (xy 382.99898 -269.135098) (xy 382.99898 -269.179294)
			(xy 383.04597 -269.331694) (xy 383.30759 -269.331694)
		)
		(stroke
			(width 0)
			(type solid)
		)
		(fill yes)
		(layer "In11.Cu")
		(net "M_H_CPU0_SA_DQS_DP<3>")
	)
	(gr_poly
		(pts
			(xy 383.356866 -277.726902) (xy 383.309876 -277.574502) (xy 383.048256 -277.574502) (xy 383.001266 -277.726902)
			(xy 383.001266 -277.771098) (xy 383.356866 -277.771098)
		)
		(stroke
			(width 0)
			(type solid)
		)
		(fill yes)
		(layer "In11.Cu")
		(net "M_H_CPU0_SA_DQ<14>")
	)
	(gr_poly
		(pts
			(xy 383.356866 -259.821426) (xy 383.309876 -259.669026) (xy 383.048256 -259.669026) (xy 383.001266 -259.821426)
			(xy 383.001266 -259.865622) (xy 383.356866 -259.865622)
		)
		(stroke
			(width 0)
			(type solid)
		)
		(fill yes)
		(layer "In11.Cu")
		(net "M_H_CPU0_SA_DQS_DP<9>")
	)
	(gr_poly
		(pts
			(xy 383.356866 -259.412486) (xy 383.356866 -259.36829) (xy 383.001266 -259.36829) (xy 383.001266 -259.412486)
			(xy 383.048256 -259.564886) (xy 383.309876 -259.564886)
		)
		(stroke
			(width 0)
			(type solid)
		)
		(fill yes)
		(layer "In11.Cu")
		(net "M_H_CPU0_SA_CB<4>")
	)
	(gr_poly
		(pts
			(xy 383.362962 -278.945848) (xy 383.362962 -278.901652) (xy 383.007362 -278.901652) (xy 383.007362 -278.945848)
			(xy 383.054352 -279.098248) (xy 383.315972 -279.098248)
		)
		(stroke
			(width 0)
			(type solid)
		)
		(fill yes)
		(layer "In11.Cu")
		(net "M_H_CPU0_SA_DQS_DN<6>")
	)
	(gr_poly
		(pts
			(xy 383.362962 -263.07669) (xy 383.315972 -262.92429) (xy 383.054352 -262.92429) (xy 383.007362 -263.07669)
			(xy 383.007362 -263.12114) (xy 383.362962 -263.12114)
		)
		(stroke
			(width 0)
			(type solid)
		)
		(fill yes)
		(layer "In11.Cu")
		(net "M_H_CPU0_SA_DQ<31>")
	)
	(gr_poly
		(pts
			(xy 383.362962 -262.668258) (xy 383.362962 -262.623808) (xy 383.007362 -262.623808) (xy 383.007362 -262.668258)
			(xy 383.054352 -262.820658) (xy 383.315972 -262.820658)
		)
		(stroke
			(width 0)
			(type solid)
		)
		(fill yes)
		(layer "In11.Cu")
		(net "M_H_CPU0_SA_CB<0>")
	)
	(gr_poly
		(pts
			(xy 383.362962 -261.449058) (xy 383.315972 -261.296658) (xy 383.054352 -261.296658) (xy 383.007362 -261.449058)
			(xy 383.007362 -261.493508) (xy 383.362962 -261.493508)
		)
		(stroke
			(width 0)
			(type solid)
		)
		(fill yes)
		(layer "In11.Cu")
		(net "M_H_CPU0_SA_CB<3>")
	)
	(gr_poly
		(pts
			(xy 383.362962 -261.040626) (xy 383.362962 -260.996176) (xy 383.007362 -260.996176) (xy 383.007362 -261.040626)
			(xy 383.054352 -261.193026) (xy 383.315972 -261.193026)
		)
		(stroke
			(width 0)
			(type solid)
		)
		(fill yes)
		(layer "In11.Cu")
		(net "M_H_CPU0_SA_DQS_DP<4>")
	)
	(gr_poly
		(pts
			(xy 383.362962 -258.193286) (xy 383.315972 -258.040886) (xy 383.054352 -258.040886) (xy 383.007362 -258.193286)
			(xy 383.007362 -258.237736) (xy 383.362962 -258.237736)
		)
		(stroke
			(width 0)
			(type solid)
		)
		(fill yes)
		(layer "In11.Cu")
		(net "M_H_CPU0_SA_CB<7>")
	)
	(gr_poly
		(pts
			(xy 383.362962 -257.784854) (xy 383.362962 -257.740404) (xy 383.007362 -257.740404) (xy 383.007362 -257.784854)
			(xy 383.054352 -257.937254) (xy 383.315972 -257.937254)
		)
		(stroke
			(width 0)
			(type solid)
		)
		(fill yes)
		(layer "In11.Cu")
		(net "M_E_CPU0_ALERT_N")
	)
	(gr_poly
		(pts
			(xy 383.362962 -256.565654) (xy 383.315972 -256.413254) (xy 383.054352 -256.413254) (xy 383.007362 -256.565654)
			(xy 383.007362 -256.610104) (xy 383.362962 -256.610104)
		)
		(stroke
			(width 0)
			(type solid)
		)
		(fill yes)
		(layer "In11.Cu")
		(net "M_H_CPU0_SA_CS_N<1>")
	)
	(gr_poly
		(pts
			(xy 383.362962 -256.157222) (xy 383.362962 -256.112772) (xy 383.007362 -256.112772) (xy 383.007362 -256.157222)
			(xy 383.054352 -256.309622) (xy 383.315972 -256.309622)
		)
		(stroke
			(width 0)
			(type solid)
		)
		(fill yes)
		(layer "In11.Cu")
		(net "M_H_CPU0_SA_CS_N<2>")
	)
	(gr_poly
		(pts
			(xy 383.362962 -254.938022) (xy 383.315972 -254.785622) (xy 383.054352 -254.785622) (xy 383.007362 -254.938022)
			(xy 383.007362 -254.982218) (xy 383.362962 -254.982218)
		)
		(stroke
			(width 0)
			(type solid)
		)
		(fill yes)
		(layer "In11.Cu")
		(net "M_H_CPU0_SA_CA<0>")
	)
	(gr_poly
		(pts
			(xy 383.362962 -254.529082) (xy 383.362962 -254.484886) (xy 383.007362 -254.484886) (xy 383.007362 -254.529082)
			(xy 383.054352 -254.681482) (xy 383.315972 -254.681482)
		)
		(stroke
			(width 0)
			(type solid)
		)
		(fill yes)
		(layer "In11.Cu")
		(net "M_H_CPU0_SA_CA<2>")
	)
	(gr_poly
		(pts
			(xy 383.371344 -279.35428) (xy 383.324354 -279.20188) (xy 383.062734 -279.20188) (xy 383.015744 -279.35428)
			(xy 383.015744 -279.39873) (xy 383.371344 -279.39873)
		)
		(stroke
			(width 0)
			(type solid)
		)
		(fill yes)
		(layer "In11.Cu")
		(net "M_H_CPU0_SA_DQS_DN<1>")
	)
	(gr_poly
		(pts
			(xy 383.578862 -247.64111) (xy 383.617216 -247.619012) (xy 383.439416 -247.311164) (xy 383.401062 -247.333262)
			(xy 383.292604 -247.450102) (xy 383.423414 -247.67667)
		)
		(stroke
			(width 0)
			(type solid)
		)
		(fill yes)
		(layer "In11.Cu")
		(net "M_H_CPU0_SB_CA<4>")
	)
	(gr_poly
		(pts
			(xy 383.619248 -225.572574) (xy 383.580894 -225.550476) (xy 383.425446 -225.514916) (xy 383.294636 -225.741484)
			(xy 383.403094 -225.858324) (xy 383.441448 -225.880422)
		)
		(stroke
			(width 0)
			(type solid)
		)
		(fill yes)
		(layer "In11.Cu")
		(net "M_H_CPU0_SB_DQ<28>")
	)
	(gr_poly
		(pts
			(xy 383.687828 -280.42616) (xy 383.726182 -280.404062) (xy 383.548382 -280.096214) (xy 383.510028 -280.118312)
			(xy 383.40157 -280.235152) (xy 383.53238 -280.46172)
		)
		(stroke
			(width 0)
			(type solid)
		)
		(fill yes)
		(layer "In11.Cu")
		(net "M_H_CPU0_SA_DQS_DP<1>")
	)
	(gr_poly
		(pts
			(xy 383.68859 -282.054808) (xy 383.726944 -282.03271) (xy 383.549144 -281.724862) (xy 383.51079 -281.74696)
			(xy 383.402332 -281.8638) (xy 383.533142 -282.090368)
		)
		(stroke
			(width 0)
			(type solid)
		)
		(fill yes)
		(layer "In11.Cu")
		(net "M_H_CPU0_SA_DQ<9>")
	)
	(gr_poly
		(pts
			(xy 383.68859 -264.149332) (xy 383.726944 -264.127234) (xy 383.549144 -263.819386) (xy 383.51079 -263.841484)
			(xy 383.402332 -263.958324) (xy 383.533142 -264.184892)
		)
		(stroke
			(width 0)
			(type solid)
		)
		(fill yes)
		(layer "In11.Cu")
		(net "M_H_CPU0_SA_DQ<29>")
	)
	(gr_poly
		(pts
			(xy 383.689606 -247.023382) (xy 383.798064 -246.906542) (xy 383.667254 -246.679974) (xy 383.511806 -246.715534)
			(xy 383.473452 -246.737632) (xy 383.651252 -247.04548)
		)
		(stroke
			(width 0)
			(type solid)
		)
		(fill yes)
		(layer "In11.Cu")
		(net "M_H_CPU0_SB_CA<5>")
	)
	(gr_poly
		(pts
			(xy 383.690622 -267.40866) (xy 383.728976 -267.386562) (xy 383.551176 -267.078714) (xy 383.512822 -267.100812)
			(xy 383.404364 -267.217652) (xy 383.535174 -267.44422)
		)
		(stroke
			(width 0)
			(type solid)
		)
		(fill yes)
		(layer "In11.Cu")
		(net "M_H_CPU0_SA_DQS_DN<8>")
	)
	(gr_poly
		(pts
			(xy 383.691638 -265.781028) (xy 383.729992 -265.75893) (xy 383.552192 -265.451082) (xy 383.513838 -265.47318)
			(xy 383.40538 -265.59002) (xy 383.53619 -265.816588)
		)
		(stroke
			(width 0)
			(type solid)
		)
		(fill yes)
		(layer "In11.Cu")
		(net "M_H_CPU0_SA_DQ<28>")
	)
	(gr_poly
		(pts
			(xy 383.717038 -224.593658) (xy 383.670048 -224.441258) (xy 383.408428 -224.441258) (xy 383.361438 -224.593658)
			(xy 383.361438 -224.637854) (xy 383.717038 -224.637854)
		)
		(stroke
			(width 0)
			(type solid)
		)
		(fill yes)
		(layer "In11.Cu")
		(net "M_H_CPU0_SB_DQ<29>")
	)
	(gr_poly
		(pts
			(xy 383.723134 -245.754906) (xy 383.676144 -245.602506) (xy 383.414524 -245.602506) (xy 383.367534 -245.754906)
			(xy 383.367534 -245.799356) (xy 383.723134 -245.799356)
		)
		(stroke
			(width 0)
			(type solid)
		)
		(fill yes)
		(layer "In11.Cu")
		(net "M_H_CPU0_SB_PAR")
	)
	(gr_poly
		(pts
			(xy 383.723134 -244.127274) (xy 383.676144 -243.974874) (xy 383.414524 -243.974874) (xy 383.367534 -244.127274)
			(xy 383.367534 -244.17147) (xy 383.723134 -244.17147)
		)
		(stroke
			(width 0)
			(type solid)
		)
		(fill yes)
		(layer "In11.Cu")
		(net "M_H_CPU0_SB_CB<4>")
	)
	(gr_poly
		(pts
			(xy 383.723134 -243.718334) (xy 383.723134 -243.674138) (xy 383.367534 -243.674138) (xy 383.367534 -243.718334)
			(xy 383.414524 -243.870734) (xy 383.676144 -243.870734)
		)
		(stroke
			(width 0)
			(type solid)
		)
		(fill yes)
		(layer "In11.Cu")
		(net "M_H_CPU0_SB_CB<7>")
	)
	(gr_poly
		(pts
			(xy 383.723134 -242.499134) (xy 383.676144 -242.346734) (xy 383.414524 -242.346734) (xy 383.367534 -242.499134)
			(xy 383.367534 -242.543584) (xy 383.723134 -242.543584)
		)
		(stroke
			(width 0)
			(type solid)
		)
		(fill yes)
		(layer "In11.Cu")
		(net "M_H_CPU0_SB_DQS_DN<9>")
	)
	(gr_poly
		(pts
			(xy 383.723134 -242.090702) (xy 383.723134 -242.046252) (xy 383.367534 -242.046252) (xy 383.367534 -242.090702)
			(xy 383.414524 -242.243102) (xy 383.676144 -242.243102)
		)
		(stroke
			(width 0)
			(type solid)
		)
		(fill yes)
		(layer "In11.Cu")
		(net "M_H_CPU0_SB_DQS_DN<4>")
	)
	(gr_poly
		(pts
			(xy 383.723134 -240.871502) (xy 383.676144 -240.719102) (xy 383.414524 -240.719102) (xy 383.367534 -240.871502)
			(xy 383.367534 -240.915952) (xy 383.723134 -240.915952)
		)
		(stroke
			(width 0)
			(type solid)
		)
		(fill yes)
		(layer "In11.Cu")
		(net "M_H_CPU0_SB_CB<2>")
	)
	(gr_poly
		(pts
			(xy 383.723134 -240.46307) (xy 383.723134 -240.41862) (xy 383.367534 -240.41862) (xy 383.367534 -240.46307)
			(xy 383.414524 -240.61547) (xy 383.676144 -240.61547)
		)
		(stroke
			(width 0)
			(type solid)
		)
		(fill yes)
		(layer "In11.Cu")
		(net "M_H_CPU0_SB_CB<1>")
	)
	(gr_poly
		(pts
			(xy 383.723134 -239.24387) (xy 383.676144 -239.09147) (xy 383.414524 -239.09147) (xy 383.367534 -239.24387)
			(xy 383.367534 -239.288066) (xy 383.723134 -239.288066)
		)
		(stroke
			(width 0)
			(type solid)
		)
		(fill yes)
		(layer "In11.Cu")
		(net "M_H_CPU0_SB_DQ<2>")
	)
	(gr_poly
		(pts
			(xy 383.723134 -238.83493) (xy 383.723134 -238.790734) (xy 383.367534 -238.790734) (xy 383.367534 -238.83493)
			(xy 383.414524 -238.98733) (xy 383.676144 -238.98733)
		)
		(stroke
			(width 0)
			(type solid)
		)
		(fill yes)
		(layer "In11.Cu")
		(net "M_H_CPU0_SB_DQ<1>")
	)
	(gr_poly
		(pts
			(xy 383.723134 -237.61573) (xy 383.676144 -237.46333) (xy 383.414524 -237.46333) (xy 383.367534 -237.61573)
			(xy 383.367534 -237.66018) (xy 383.723134 -237.66018)
		)
		(stroke
			(width 0)
			(type solid)
		)
		(fill yes)
		(layer "In11.Cu")
		(net "M_H_CPU0_SB_DQS_DN<0>")
	)
	(gr_poly
		(pts
			(xy 383.723134 -235.579666) (xy 383.723134 -235.535216) (xy 383.367534 -235.535216) (xy 383.367534 -235.579666)
			(xy 383.414524 -235.732066) (xy 383.676144 -235.732066)
		)
		(stroke
			(width 0)
			(type solid)
		)
		(fill yes)
		(layer "In11.Cu")
		(net "M_H_CPU0_SB_DQ<5>")
	)
	(gr_poly
		(pts
			(xy 383.723134 -234.360466) (xy 383.676144 -234.208066) (xy 383.414524 -234.208066) (xy 383.367534 -234.360466)
			(xy 383.367534 -234.404916) (xy 383.723134 -234.404916)
		)
		(stroke
			(width 0)
			(type solid)
		)
		(fill yes)
		(layer "In11.Cu")
		(net "M_H_CPU0_SB_DQ<10>")
	)
	(gr_poly
		(pts
			(xy 383.723134 -233.952034) (xy 383.723134 -233.907584) (xy 383.367534 -233.907584) (xy 383.367534 -233.952034)
			(xy 383.414524 -234.104434) (xy 383.676144 -234.104434)
		)
		(stroke
			(width 0)
			(type solid)
		)
		(fill yes)
		(layer "In11.Cu")
		(net "M_H_CPU0_SB_DQ<9>")
	)
	(gr_poly
		(pts
			(xy 383.723134 -232.732834) (xy 383.676144 -232.580434) (xy 383.414524 -232.580434) (xy 383.367534 -232.732834)
			(xy 383.367534 -232.77703) (xy 383.723134 -232.77703)
		)
		(stroke
			(width 0)
			(type solid)
		)
		(fill yes)
		(layer "In11.Cu")
		(net "M_H_CPU0_SB_DQS_DN<1>")
	)
	(gr_poly
		(pts
			(xy 383.723134 -232.323894) (xy 383.723134 -232.279698) (xy 383.367534 -232.279698) (xy 383.367534 -232.323894)
			(xy 383.414524 -232.476294) (xy 383.676144 -232.476294)
		)
		(stroke
			(width 0)
			(type solid)
		)
		(fill yes)
		(layer "In11.Cu")
		(net "M_H_CPU0_SB_DQS_DN<6>")
	)
	(gr_poly
		(pts
			(xy 383.723134 -231.104694) (xy 383.676144 -230.952294) (xy 383.414524 -230.952294) (xy 383.367534 -231.104694)
			(xy 383.367534 -231.149144) (xy 383.723134 -231.149144)
		)
		(stroke
			(width 0)
			(type solid)
		)
		(fill yes)
		(layer "In11.Cu")
		(net "M_H_CPU0_SB_DQ<14>")
	)
	(gr_poly
		(pts
			(xy 383.723134 -230.696262) (xy 383.723134 -230.651812) (xy 383.367534 -230.651812) (xy 383.367534 -230.696262)
			(xy 383.414524 -230.848662) (xy 383.676144 -230.848662)
		)
		(stroke
			(width 0)
			(type solid)
		)
		(fill yes)
		(layer "In11.Cu")
		(net "M_H_CPU0_SB_DQ<13>")
	)
	(gr_poly
		(pts
			(xy 383.723134 -229.477062) (xy 383.676144 -229.324662) (xy 383.414524 -229.324662) (xy 383.367534 -229.477062)
			(xy 383.367534 -229.521512) (xy 383.723134 -229.521512)
		)
		(stroke
			(width 0)
			(type solid)
		)
		(fill yes)
		(layer "In11.Cu")
		(net "M_H_CPU0_SB_DQ<24>")
	)
	(gr_poly
		(pts
			(xy 383.723134 -229.06863) (xy 383.723134 -229.02418) (xy 383.367534 -229.02418) (xy 383.367534 -229.06863)
			(xy 383.414524 -229.22103) (xy 383.676144 -229.22103)
		)
		(stroke
			(width 0)
			(type solid)
		)
		(fill yes)
		(layer "In11.Cu")
		(net "M_H_CPU0_SB_DQ<27>")
	)
	(gr_poly
		(pts
			(xy 383.723134 -227.84943) (xy 383.676144 -227.69703) (xy 383.414524 -227.69703) (xy 383.367534 -227.84943)
			(xy 383.367534 -227.893626) (xy 383.723134 -227.893626)
		)
		(stroke
			(width 0)
			(type solid)
		)
		(fill yes)
		(layer "In11.Cu")
		(net "M_H_CPU0_SB_DQS_DP<8>")
	)
	(gr_poly
		(pts
			(xy 383.723134 -227.44049) (xy 383.723134 -227.396294) (xy 383.367534 -227.396294) (xy 383.367534 -227.44049)
			(xy 383.414524 -227.59289) (xy 383.676144 -227.59289)
		)
		(stroke
			(width 0)
			(type solid)
		)
		(fill yes)
		(layer "In11.Cu")
		(net "M_H_CPU0_SB_DQS_DP<3>")
	)
	(gr_poly
		(pts
			(xy 383.731516 -237.207806) (xy 383.731516 -237.163356) (xy 383.375916 -237.163356) (xy 383.375916 -237.207806)
			(xy 383.422906 -237.360206) (xy 383.684526 -237.360206)
		)
		(stroke
			(width 0)
			(type solid)
		)
		(fill yes)
		(layer "In11.Cu")
		(net "M_H_CPU0_SB_DQS_DN<5>")
	)
	(gr_poly
		(pts
			(xy 383.731516 -235.988098) (xy 383.684526 -235.835698) (xy 383.422906 -235.835698) (xy 383.375916 -235.988098)
			(xy 383.375916 -236.032294) (xy 383.731516 -236.032294)
		)
		(stroke
			(width 0)
			(type solid)
		)
		(fill yes)
		(layer "In11.Cu")
		(net "M_H_CPU0_SB_DQ<6>")
	)
	(gr_poly
		(pts
			(xy 383.797302 -263.52754) (xy 383.90576 -263.4107) (xy 383.77495 -263.184132) (xy 383.619502 -263.219692)
			(xy 383.581148 -263.24179) (xy 383.758948 -263.549638)
		)
		(stroke
			(width 0)
			(type solid)
		)
		(fill yes)
		(layer "In11.Cu")
		(net "M_H_CPU0_SA_DQ<31>")
	)
	(gr_poly
		(pts
			(xy 383.798064 -226.289108) (xy 383.689606 -226.172268) (xy 383.651252 -226.15017) (xy 383.473452 -226.458018)
			(xy 383.511806 -226.480116) (xy 383.667254 -226.515676)
		)
		(stroke
			(width 0)
			(type solid)
		)
		(fill yes)
		(layer "In11.Cu")
		(net "M_H_CPU0_SB_DQ<30>")
	)
	(gr_poly
		(pts
			(xy 383.799334 -281.43708) (xy 383.907792 -281.32024) (xy 383.776982 -281.093672) (xy 383.621534 -281.129232)
			(xy 383.58318 -281.15133) (xy 383.76098 -281.459178)
		)
		(stroke
			(width 0)
			(type solid)
		)
		(fill yes)
		(layer "In11.Cu")
		(net "M_H_CPU0_SA_DQ<11>")
	)
	(gr_poly
		(pts
			(xy 383.803652 -279.81656) (xy 383.91211 -279.69972) (xy 383.7813 -279.473152) (xy 383.625852 -279.508712)
			(xy 383.587498 -279.53081) (xy 383.765298 -279.838658)
		)
		(stroke
			(width 0)
			(type solid)
		)
		(fill yes)
		(layer "In11.Cu")
		(net "M_H_CPU0_SA_DQS_DN<1>")
	)
	(gr_poly
		(pts
			(xy 383.803906 -266.79398) (xy 383.912364 -266.67714) (xy 383.781554 -266.450572) (xy 383.626106 -266.486132)
			(xy 383.587752 -266.50823) (xy 383.765552 -266.816078)
		)
		(stroke
			(width 0)
			(type solid)
		)
		(fill yes)
		(layer "In11.Cu")
		(net "M_H_CPU0_SA_DQS_DP<8>")
	)
	(gr_poly
		(pts
			(xy 383.803906 -265.166348) (xy 383.912364 -265.049508) (xy 383.781554 -264.82294) (xy 383.626106 -264.8585)
			(xy 383.587752 -264.880598) (xy 383.765552 -265.188446)
		)
		(stroke
			(width 0)
			(type solid)
		)
		(fill yes)
		(layer "In11.Cu")
		(net "M_H_CPU0_SA_DQ<30>")
	)
	(gr_poly
		(pts
			(xy 383.832862 -283.015436) (xy 383.832862 -282.97124) (xy 383.477262 -282.97124) (xy 383.477262 -283.015436)
			(xy 383.524252 -283.167836) (xy 383.785872 -283.167836)
		)
		(stroke
			(width 0)
			(type solid)
		)
		(fill yes)
		(layer "In11.Cu")
		(net "M_H_CPU0_SA_DQ<8>")
	)
	(gr_poly
		(pts
			(xy 383.832862 -278.540718) (xy 383.785872 -278.388318) (xy 383.524252 -278.388318) (xy 383.477262 -278.540718)
			(xy 383.477262 -278.585168) (xy 383.832862 -278.585168)
		)
		(stroke
			(width 0)
			(type solid)
		)
		(fill yes)
		(layer "In11.Cu")
		(net "M_H_CPU0_SA_DQS_DP<6>")
	)
	(gr_poly
		(pts
			(xy 383.832862 -262.262874) (xy 383.785872 -262.110474) (xy 383.524252 -262.110474) (xy 383.477262 -262.262874)
			(xy 383.477262 -262.307324) (xy 383.832862 -262.307324)
		)
		(stroke
			(width 0)
			(type solid)
		)
		(fill yes)
		(layer "In11.Cu")
		(net "M_H_CPU0_SA_CB<2>")
	)
	(gr_poly
		(pts
			(xy 383.832862 -261.854442) (xy 383.832862 -261.809992) (xy 383.477262 -261.809992) (xy 383.477262 -261.854442)
			(xy 383.524252 -262.006842) (xy 383.785872 -262.006842)
		)
		(stroke
			(width 0)
			(type solid)
		)
		(fill yes)
		(layer "In11.Cu")
		(net "M_H_CPU0_SA_CB<1>")
	)
	(gr_poly
		(pts
			(xy 383.832862 -260.635242) (xy 383.785872 -260.482842) (xy 383.524252 -260.482842) (xy 383.477262 -260.635242)
			(xy 383.477262 -260.679438) (xy 383.832862 -260.679438)
		)
		(stroke
			(width 0)
			(type solid)
		)
		(fill yes)
		(layer "In11.Cu")
		(net "M_H_CPU0_SA_DQS_DN<4>")
	)
	(gr_poly
		(pts
			(xy 383.832862 -258.59867) (xy 383.832862 -258.554474) (xy 383.477262 -258.554474) (xy 383.477262 -258.59867)
			(xy 383.524252 -258.75107) (xy 383.785872 -258.75107)
		)
		(stroke
			(width 0)
			(type solid)
		)
		(fill yes)
		(layer "In11.Cu")
		(net "M_H_CPU0_SA_CB<5>")
	)
	(gr_poly
		(pts
			(xy 383.832862 -257.37947) (xy 383.785872 -257.22707) (xy 383.524252 -257.22707) (xy 383.477262 -257.37947)
			(xy 383.477262 -257.42392) (xy 383.832862 -257.42392)
		)
		(stroke
			(width 0)
			(type solid)
		)
		(fill yes)
		(layer "In11.Cu")
		(net "M_H_CPU0_ALERT_N")
	)
	(gr_poly
		(pts
			(xy 383.832862 -256.971038) (xy 383.832862 -256.926588) (xy 383.477262 -256.926588) (xy 383.477262 -256.971038)
			(xy 383.524252 -257.123438) (xy 383.785872 -257.123438)
		)
		(stroke
			(width 0)
			(type solid)
		)
		(fill yes)
		(layer "In11.Cu")
		(net "M_H_CPU0_SA_CS_N<0>")
	)
	(gr_poly
		(pts
			(xy 383.832862 -255.751838) (xy 383.785872 -255.599438) (xy 383.524252 -255.599438) (xy 383.477262 -255.751838)
			(xy 383.477262 -255.796288) (xy 383.832862 -255.796288)
		)
		(stroke
			(width 0)
			(type solid)
		)
		(fill yes)
		(layer "In11.Cu")
		(net "M_H_CPU0_SA_CS_N<3>")
	)
	(gr_poly
		(pts
			(xy 383.832862 -255.343406) (xy 383.832862 -255.298956) (xy 383.477262 -255.298956) (xy 383.477262 -255.343406)
			(xy 383.524252 -255.495806) (xy 383.785872 -255.495806)
		)
		(stroke
			(width 0)
			(type solid)
		)
		(fill yes)
		(layer "In11.Cu")
		(net "M_H_CPU0_SA_CA<1>")
	)
	(gr_poly
		(pts
			(xy 383.832862 -254.124206) (xy 383.785872 -253.971806) (xy 383.524252 -253.971806) (xy 383.477262 -254.124206)
			(xy 383.477262 -254.168402) (xy 383.832862 -254.168402)
		)
		(stroke
			(width 0)
			(type solid)
		)
		(fill yes)
		(layer "In11.Cu")
		(net "M_H_CPU0_SA_CA<3>")
	)
	(gr_poly
		(pts
			(xy 383.838958 -273.657314) (xy 383.791968 -273.504914) (xy 383.530348 -273.504914) (xy 383.483358 -273.657314)
			(xy 383.483358 -273.701764) (xy 383.838958 -273.701764)
		)
		(stroke
			(width 0)
			(type solid)
		)
		(fill yes)
		(layer "In11.Cu")
		(net "M_H_CPU0_SA_DQS_DN<2>")
	)
	(gr_poly
		(pts
			(xy 383.838958 -273.248882) (xy 383.838958 -273.204432) (xy 383.483358 -273.204432) (xy 383.483358 -273.248882)
			(xy 383.530348 -273.401282) (xy 383.791968 -273.401282)
		)
		(stroke
			(width 0)
			(type solid)
		)
		(fill yes)
		(layer "In11.Cu")
		(net "M_H_CPU0_SA_DQS_DN<7>")
	)
	(gr_poly
		(pts
			(xy 383.838958 -268.77391) (xy 383.791968 -268.62151) (xy 383.530348 -268.62151) (xy 383.483358 -268.77391)
			(xy 383.483358 -268.81836) (xy 383.838958 -268.81836)
		)
		(stroke
			(width 0)
			(type solid)
		)
		(fill yes)
		(layer "In11.Cu")
		(net "M_H_CPU0_SA_DQS_DN<3>")
	)
	(gr_poly
		(pts
			(xy 383.841244 -278.132286) (xy 383.841244 -278.08809) (xy 383.485644 -278.08809) (xy 383.485644 -278.132286)
			(xy 383.532634 -278.284686) (xy 383.794254 -278.284686)
		)
		(stroke
			(width 0)
			(type solid)
		)
		(fill yes)
		(layer "In11.Cu")
		(net "M_H_CPU0_SA_DQ<12>")
	)
	(gr_poly
		(pts
			(xy 383.841244 -276.912578) (xy 383.794254 -276.760178) (xy 383.532634 -276.760178) (xy 383.485644 -276.912578)
			(xy 383.485644 -276.957028) (xy 383.841244 -276.957028)
		)
		(stroke
			(width 0)
			(type solid)
		)
		(fill yes)
		(layer "In11.Cu")
		(net "M_H_CPU0_SA_DQ<15>")
	)
	(gr_poly
		(pts
			(xy 383.841244 -260.22681) (xy 383.841244 -260.18236) (xy 383.485644 -260.18236) (xy 383.485644 -260.22681)
			(xy 383.532634 -260.37921) (xy 383.794254 -260.37921)
		)
		(stroke
			(width 0)
			(type solid)
		)
		(fill yes)
		(layer "In11.Cu")
		(net "M_H_CPU0_SA_DQS_DN<9>")
	)
	(gr_poly
		(pts
			(xy 383.841244 -259.007102) (xy 383.794254 -258.854702) (xy 383.532634 -258.854702) (xy 383.485644 -259.007102)
			(xy 383.485644 -259.051552) (xy 383.841244 -259.051552)
		)
		(stroke
			(width 0)
			(type solid)
		)
		(fill yes)
		(layer "In11.Cu")
		(net "M_H_CPU0_SA_CB<6>")
	)
	(gr_poly
		(pts
			(xy 383.841498 -274.876768) (xy 383.841498 -274.832572) (xy 383.485898 -274.832572) (xy 383.485898 -274.876768)
			(xy 383.532888 -275.029168) (xy 383.794508 -275.029168)
		)
		(stroke
			(width 0)
			(type solid)
		)
		(fill yes)
		(layer "In11.Cu")
		(net "M_H_CPU0_SA_DQ<17>")
	)
	(gr_poly
		(pts
			(xy 383.841498 -272.029174) (xy 383.794508 -271.876774) (xy 383.532888 -271.876774) (xy 383.485898 -272.029174)
			(xy 383.485898 -272.073624) (xy 383.841498 -272.073624)
		)
		(stroke
			(width 0)
			(type solid)
		)
		(fill yes)
		(layer "In11.Cu")
		(net "M_H_CPU0_SA_DQ<22>")
	)
	(gr_poly
		(pts
			(xy 383.841498 -271.62125) (xy 383.841498 -271.5768) (xy 383.485898 -271.5768) (xy 383.485898 -271.62125)
			(xy 383.532888 -271.77365) (xy 383.794508 -271.77365)
		)
		(stroke
			(width 0)
			(type solid)
		)
		(fill yes)
		(layer "In11.Cu")
		(net "M_H_CPU0_SA_DQ<21>")
	)
	(gr_poly
		(pts
			(xy 383.841498 -270.401542) (xy 383.794508 -270.249142) (xy 383.532888 -270.249142) (xy 383.485898 -270.401542)
			(xy 383.485898 -270.445992) (xy 383.841498 -270.445992)
		)
		(stroke
			(width 0)
			(type solid)
		)
		(fill yes)
		(layer "In11.Cu")
		(net "M_H_CPU0_SA_DQ<26>")
	)
	(gr_poly
		(pts
			(xy 383.841498 -269.993618) (xy 383.841498 -269.949168) (xy 383.485898 -269.949168) (xy 383.485898 -269.993618)
			(xy 383.532888 -270.146018) (xy 383.794508 -270.146018)
		)
		(stroke
			(width 0)
			(type solid)
		)
		(fill yes)
		(layer "In11.Cu")
		(net "M_H_CPU0_SA_DQ<25>")
	)
	(gr_poly
		(pts
			(xy 384.048762 -246.827294) (xy 384.087116 -246.805196) (xy 383.909316 -246.497348) (xy 383.870962 -246.519446)
			(xy 383.762504 -246.636286) (xy 383.893314 -246.862854)
		)
		(stroke
			(width 0)
			(type solid)
		)
		(fill yes)
		(layer "In11.Cu")
		(net "M_H_CPU0_SB_CA<6>")
	)
	(gr_poly
		(pts
			(xy 384.087116 -226.390454) (xy 384.048762 -226.368356) (xy 383.893314 -226.332796) (xy 383.762504 -226.559364)
			(xy 383.870962 -226.676204) (xy 383.909316 -226.698302)
		)
		(stroke
			(width 0)
			(type solid)
		)
		(fill yes)
		(layer "In11.Cu")
		(net "M_H_CPU0_SB_DQS_DN<3>")
	)
	(gr_poly
		(pts
			(xy 384.154172 -264.956036) (xy 384.192526 -264.933938) (xy 384.014726 -264.62609) (xy 383.976372 -264.648188)
			(xy 383.867914 -264.765028) (xy 383.998724 -264.991596)
		)
		(stroke
			(width 0)
			(type solid)
		)
		(fill yes)
		(layer "In11.Cu")
		(net "M_H_CPU0_SA_DQ<29>")
	)
	(gr_poly
		(pts
			(xy 384.15849 -281.240992) (xy 384.196844 -281.218894) (xy 384.019044 -280.911046) (xy 383.98069 -280.933144)
			(xy 383.872232 -281.049984) (xy 384.003042 -281.276552)
		)
		(stroke
			(width 0)
			(type solid)
		)
		(fill yes)
		(layer "In11.Cu")
		(net "M_H_CPU0_SA_DQS_DP<1>")
	)
	(gr_poly
		(pts
			(xy 384.15849 -279.613106) (xy 384.196844 -279.591008) (xy 384.019044 -279.28316) (xy 383.98069 -279.305258)
			(xy 383.872232 -279.422098) (xy 384.003042 -279.648666)
		)
		(stroke
			(width 0)
			(type solid)
		)
		(fill yes)
		(layer "In11.Cu")
		(net "M_H_CPU0_SA_DQS_DN<6>")
	)
	(gr_poly
		(pts
			(xy 384.15849 -268.218666) (xy 384.196844 -268.196568) (xy 384.019044 -267.88872) (xy 383.98069 -267.910818)
			(xy 383.872232 -268.027658) (xy 384.003042 -268.254226)
		)
		(stroke
			(width 0)
			(type solid)
		)
		(fill yes)
		(layer "In11.Cu")
		(net "M_H_CPU0_SA_DQS_DN<8>")
	)
	(gr_poly
		(pts
			(xy 384.15849 -266.591034) (xy 384.196844 -266.568936) (xy 384.019044 -266.261088) (xy 383.98069 -266.283186)
			(xy 383.872232 -266.400026) (xy 384.003042 -266.626594)
		)
		(stroke
			(width 0)
			(type solid)
		)
		(fill yes)
		(layer "In11.Cu")
		(net "M_H_CPU0_SA_DQ<28>")
	)
	(gr_poly
		(pts
			(xy 384.159506 -246.209566) (xy 384.267964 -246.092726) (xy 384.137154 -245.866158) (xy 383.981706 -245.901718)
			(xy 383.943352 -245.923816) (xy 384.121152 -246.231664)
		)
		(stroke
			(width 0)
			(type solid)
		)
		(fill yes)
		(layer "In11.Cu")
		(net "M_H_CPU0_SB_PAR")
	)
	(gr_poly
		(pts
			(xy 384.159506 -244.58168) (xy 384.267964 -244.46484) (xy 384.137154 -244.238272) (xy 383.981706 -244.273832)
			(xy 383.943352 -244.29593) (xy 384.121152 -244.603778)
		)
		(stroke
			(width 0)
			(type solid)
		)
		(fill yes)
		(layer "In11.Cu")
		(net "M_H_CPU0_SB_CB<4>")
	)
	(gr_poly
		(pts
			(xy 384.160522 -263.339326) (xy 384.198876 -263.317228) (xy 384.021076 -263.00938) (xy 383.982722 -263.031478)
			(xy 383.874264 -263.148318) (xy 384.005074 -263.374886)
		)
		(stroke
			(width 0)
			(type solid)
		)
		(fill yes)
		(layer "In11.Cu")
		(net "M_H_CPU0_SA_CB<0>")
	)
	(gr_poly
		(pts
			(xy 384.184398 -236.801914) (xy 384.137408 -236.649514) (xy 383.875788 -236.649514) (xy 383.828798 -236.801914)
			(xy 383.828798 -236.84611) (xy 384.184398 -236.84611)
		)
		(stroke
			(width 0)
			(type solid)
		)
		(fill yes)
		(layer "In11.Cu")
		(net "M_H_CPU0_SB_DQS_DP<5>")
	)
	(gr_poly
		(pts
			(xy 384.184398 -236.39399) (xy 384.184398 -236.34954) (xy 383.828798 -236.34954) (xy 383.828798 -236.39399)
			(xy 383.875788 -236.54639) (xy 384.137408 -236.54639)
		)
		(stroke
			(width 0)
			(type solid)
		)
		(fill yes)
		(layer "In11.Cu")
		(net "M_H_CPU0_SB_DQ<4>")
	)
	(gr_poly
		(pts
			(xy 384.186938 -240.057686) (xy 384.139948 -239.905286) (xy 383.878328 -239.905286) (xy 383.831338 -240.057686)
			(xy 383.831338 -240.101882) (xy 384.186938 -240.101882)
		)
		(stroke
			(width 0)
			(type solid)
		)
		(fill yes)
		(layer "In11.Cu")
		(net "M_H_CPU0_SB_CB<3>")
	)
	(gr_poly
		(pts
			(xy 384.186938 -239.648746) (xy 384.186938 -239.60455) (xy 383.831338 -239.60455) (xy 383.831338 -239.648746)
			(xy 383.878328 -239.801146) (xy 384.139948 -239.801146)
		)
		(stroke
			(width 0)
			(type solid)
		)
		(fill yes)
		(layer "In11.Cu")
		(net "M_H_CPU0_SB_DQ<0>")
	)
	(gr_poly
		(pts
			(xy 384.186938 -235.174282) (xy 384.139948 -235.021882) (xy 383.878328 -235.021882) (xy 383.831338 -235.174282)
			(xy 383.831338 -235.218732) (xy 384.186938 -235.218732)
		)
		(stroke
			(width 0)
			(type solid)
		)
		(fill yes)
		(layer "In11.Cu")
		(net "M_H_CPU0_SB_DQ<7>")
	)
	(gr_poly
		(pts
			(xy 384.186938 -234.76585) (xy 384.186938 -234.7214) (xy 383.831338 -234.7214) (xy 383.831338 -234.76585)
			(xy 383.878328 -234.91825) (xy 384.139948 -234.91825)
		)
		(stroke
			(width 0)
			(type solid)
		)
		(fill yes)
		(layer "In11.Cu")
		(net "M_H_CPU0_SB_DQ<8>")
	)
	(gr_poly
		(pts
			(xy 384.193034 -248.196354) (xy 384.146044 -248.043954) (xy 383.884424 -248.043954) (xy 383.837434 -248.196354)
			(xy 383.837434 -248.240804) (xy 384.193034 -248.240804)
		)
		(stroke
			(width 0)
			(type solid)
		)
		(fill yes)
		(layer "In11.Cu")
		(net "M_H_CPU0_SB_CA<3>")
	)
	(gr_poly
		(pts
			(xy 384.193034 -247.787922) (xy 384.193034 -247.743472) (xy 383.837434 -247.743472) (xy 383.837434 -247.787922)
			(xy 383.884424 -247.940322) (xy 384.146044 -247.940322)
		)
		(stroke
			(width 0)
			(type solid)
		)
		(fill yes)
		(layer "In11.Cu")
		(net "M_H_CPU0_SB_CA<4>")
	)
	(gr_poly
		(pts
			(xy 384.193034 -243.313458) (xy 384.146044 -243.161058) (xy 383.884424 -243.161058) (xy 383.837434 -243.313458)
			(xy 383.837434 -243.357654) (xy 384.193034 -243.357654)
		)
		(stroke
			(width 0)
			(type solid)
		)
		(fill yes)
		(layer "In11.Cu")
		(net "M_H_CPU0_SB_CB<5>")
	)
	(gr_poly
		(pts
			(xy 384.193034 -242.904518) (xy 384.193034 -242.860322) (xy 383.837434 -242.860322) (xy 383.837434 -242.904518)
			(xy 383.884424 -243.056918) (xy 384.146044 -243.056918)
		)
		(stroke
			(width 0)
			(type solid)
		)
		(fill yes)
		(layer "In11.Cu")
		(net "M_H_CPU0_SB_DQS_DP<9>")
	)
	(gr_poly
		(pts
			(xy 384.193034 -241.685318) (xy 384.146044 -241.532918) (xy 383.884424 -241.532918) (xy 383.837434 -241.685318)
			(xy 383.837434 -241.729768) (xy 384.193034 -241.729768)
		)
		(stroke
			(width 0)
			(type solid)
		)
		(fill yes)
		(layer "In11.Cu")
		(net "M_H_CPU0_SB_DQS_DP<4>")
	)
	(gr_poly
		(pts
			(xy 384.193034 -241.276886) (xy 384.193034 -241.232436) (xy 383.837434 -241.232436) (xy 383.837434 -241.276886)
			(xy 383.884424 -241.429286) (xy 384.146044 -241.429286)
		)
		(stroke
			(width 0)
			(type solid)
		)
		(fill yes)
		(layer "In11.Cu")
		(net "M_H_CPU0_SB_CB<0>")
	)
	(gr_poly
		(pts
			(xy 384.193034 -238.430054) (xy 384.146044 -238.277654) (xy 383.884424 -238.277654) (xy 383.837434 -238.430054)
			(xy 383.837434 -238.47425) (xy 384.193034 -238.47425)
		)
		(stroke
			(width 0)
			(type solid)
		)
		(fill yes)
		(layer "In11.Cu")
		(net "M_H_CPU0_SB_DQ<3>")
	)
	(gr_poly
		(pts
			(xy 384.193034 -238.021114) (xy 384.193034 -237.976918) (xy 383.837434 -237.976918) (xy 383.837434 -238.021114)
			(xy 383.884424 -238.173514) (xy 384.146044 -238.173514)
		)
		(stroke
			(width 0)
			(type solid)
		)
		(fill yes)
		(layer "In11.Cu")
		(net "M_H_CPU0_SB_DQS_DP<0>")
	)
	(gr_poly
		(pts
			(xy 384.193034 -233.54665) (xy 384.146044 -233.39425) (xy 383.884424 -233.39425) (xy 383.837434 -233.54665)
			(xy 383.837434 -233.590846) (xy 384.193034 -233.590846)
		)
		(stroke
			(width 0)
			(type solid)
		)
		(fill yes)
		(layer "In11.Cu")
		(net "M_H_CPU0_SB_DQ<11>")
	)
	(gr_poly
		(pts
			(xy 384.193034 -233.13771) (xy 384.193034 -233.093514) (xy 383.837434 -233.093514) (xy 383.837434 -233.13771)
			(xy 383.884424 -233.29011) (xy 384.146044 -233.29011)
		)
		(stroke
			(width 0)
			(type solid)
		)
		(fill yes)
		(layer "In11.Cu")
		(net "M_H_CPU0_SB_DQS_DP<1>")
	)
	(gr_poly
		(pts
			(xy 384.193034 -231.919018) (xy 384.146044 -231.766618) (xy 383.884424 -231.766618) (xy 383.837434 -231.919018)
			(xy 383.837434 -231.963214) (xy 384.193034 -231.963214)
		)
		(stroke
			(width 0)
			(type solid)
		)
		(fill yes)
		(layer "In11.Cu")
		(net "M_H_CPU0_SB_DQS_DP<6>")
	)
	(gr_poly
		(pts
			(xy 384.193034 -231.510078) (xy 384.193034 -231.465882) (xy 383.837434 -231.465882) (xy 383.837434 -231.510078)
			(xy 383.884424 -231.662478) (xy 384.146044 -231.662478)
		)
		(stroke
			(width 0)
			(type solid)
		)
		(fill yes)
		(layer "In11.Cu")
		(net "M_H_CPU0_SB_DQ<12>")
	)
	(gr_poly
		(pts
			(xy 384.193034 -230.290878) (xy 384.146044 -230.138478) (xy 383.884424 -230.138478) (xy 383.837434 -230.290878)
			(xy 383.837434 -230.335328) (xy 384.193034 -230.335328)
		)
		(stroke
			(width 0)
			(type solid)
		)
		(fill yes)
		(layer "In11.Cu")
		(net "M_H_CPU0_SB_DQ<15>")
	)
	(gr_poly
		(pts
			(xy 384.193034 -229.882446) (xy 384.193034 -229.837996) (xy 383.837434 -229.837996) (xy 383.837434 -229.882446)
			(xy 383.884424 -230.034846) (xy 384.146044 -230.034846)
		)
		(stroke
			(width 0)
			(type solid)
		)
		(fill yes)
		(layer "In11.Cu")
		(net "M_H_CPU0_SB_DQ<26>")
	)
	(gr_poly
		(pts
			(xy 384.193034 -228.663246) (xy 384.146044 -228.510846) (xy 383.884424 -228.510846) (xy 383.837434 -228.663246)
			(xy 383.837434 -228.707696) (xy 384.193034 -228.707696)
		)
		(stroke
			(width 0)
			(type solid)
		)
		(fill yes)
		(layer "In11.Cu")
		(net "M_H_CPU0_SB_DQ<25>")
	)
	(gr_poly
		(pts
			(xy 384.193034 -228.254814) (xy 384.193034 -228.210364) (xy 383.837434 -228.210364) (xy 383.837434 -228.254814)
			(xy 383.884424 -228.407214) (xy 384.146044 -228.407214)
		)
		(stroke
			(width 0)
			(type solid)
		)
		(fill yes)
		(layer "In11.Cu")
		(net "M_H_CPU0_SB_DQS_DN<8>")
	)
	(gr_poly
		(pts
			(xy 384.193034 -225.407474) (xy 384.146044 -225.255074) (xy 383.884424 -225.255074) (xy 383.837434 -225.407474)
			(xy 383.837434 -225.451924) (xy 384.193034 -225.451924)
		)
		(stroke
			(width 0)
			(type solid)
		)
		(fill yes)
		(layer "In11.Cu")
		(net "M_H_CPU0_SB_DQ<28>")
	)
	(gr_poly
		(pts
			(xy 384.193034 -224.999042) (xy 384.193034 -224.954592) (xy 383.837434 -224.954592) (xy 383.837434 -224.999042)
			(xy 383.884424 -225.151442) (xy 384.146044 -225.151442)
		)
		(stroke
			(width 0)
			(type solid)
		)
		(fill yes)
		(layer "In11.Cu")
		(net "M_H_CPU0_SB_DQ<31>")
	)
	(gr_poly
		(pts
			(xy 384.267202 -280.6192) (xy 384.37566 -280.50236) (xy 384.24485 -280.275792) (xy 384.089402 -280.311352)
			(xy 384.051048 -280.33345) (xy 384.228848 -280.641298)
		)
		(stroke
			(width 0)
			(type solid)
		)
		(fill yes)
		(layer "In11.Cu")
		(net "M_H_CPU0_SA_DQS_DN<1>")
	)
	(gr_poly
		(pts
			(xy 384.267964 -227.102924) (xy 384.159506 -226.986084) (xy 384.121152 -226.963986) (xy 383.943352 -227.271834)
			(xy 383.981706 -227.293932) (xy 384.137154 -227.329492)
		)
		(stroke
			(width 0)
			(type solid)
		)
		(fill yes)
		(layer "In11.Cu")
		(net "M_H_CPU0_SB_DQS_DP<3>")
	)
	(gr_poly
		(pts
			(xy 384.269234 -278.995378) (xy 384.377692 -278.878538) (xy 384.246882 -278.65197) (xy 384.091434 -278.68753)
			(xy 384.05308 -278.709628) (xy 384.23088 -279.017476)
		)
		(stroke
			(width 0)
			(type solid)
		)
		(fill yes)
		(layer "In11.Cu")
		(net "M_H_CPU0_SA_DQS_DP<6>")
	)
	(gr_poly
		(pts
			(xy 384.294126 -259.820918) (xy 384.247136 -259.668518) (xy 383.985516 -259.668518) (xy 383.938526 -259.820918)
			(xy 383.938526 -259.865368) (xy 384.294126 -259.865368)
		)
		(stroke
			(width 0)
			(type solid)
		)
		(fill yes)
		(layer "In11.Cu")
		(net "M_H_CPU0_SA_DQS_DP<9>")
	)
	(gr_poly
		(pts
			(xy 384.294126 -259.412994) (xy 384.294126 -259.368544) (xy 383.938526 -259.368544) (xy 383.938526 -259.412994)
			(xy 383.985516 -259.565394) (xy 384.247136 -259.565394)
		)
		(stroke
			(width 0)
			(type solid)
		)
		(fill yes)
		(layer "In11.Cu")
		(net "M_H_CPU0_SA_CB<4>")
	)
	(gr_poly
		(pts
			(xy 384.29438 -274.47113) (xy 384.24739 -274.31873) (xy 383.98577 -274.31873) (xy 383.93878 -274.47113)
			(xy 383.93878 -274.515326) (xy 384.29438 -274.515326)
		)
		(stroke
			(width 0)
			(type solid)
		)
		(fill yes)
		(layer "In11.Cu")
		(net "M_H_CPU0_SA_DQ<19>")
	)
	(gr_poly
		(pts
			(xy 384.29438 -272.435066) (xy 384.29438 -272.39087) (xy 383.93878 -272.39087) (xy 383.93878 -272.435066)
			(xy 383.98577 -272.587466) (xy 384.24739 -272.587466)
		)
		(stroke
			(width 0)
			(type solid)
		)
		(fill yes)
		(layer "In11.Cu")
		(net "M_H_CPU0_SA_DQ<20>")
	)
	(gr_poly
		(pts
			(xy 384.29438 -271.215358) (xy 384.24739 -271.062958) (xy 383.98577 -271.062958) (xy 383.93878 -271.215358)
			(xy 383.93878 -271.259808) (xy 384.29438 -271.259808)
		)
		(stroke
			(width 0)
			(type solid)
		)
		(fill yes)
		(layer "In11.Cu")
		(net "M_H_CPU0_SA_DQ<23>")
	)
	(gr_poly
		(pts
			(xy 384.29438 -270.807434) (xy 384.29438 -270.762984) (xy 383.93878 -270.762984) (xy 383.93878 -270.807434)
			(xy 383.98577 -270.959834) (xy 384.24739 -270.959834)
		)
		(stroke
			(width 0)
			(type solid)
		)
		(fill yes)
		(layer "In11.Cu")
		(net "M_H_CPU0_SA_DQ<24>")
	)
	(gr_poly
		(pts
			(xy 384.29438 -269.587726) (xy 384.24739 -269.435326) (xy 383.98577 -269.435326) (xy 383.93878 -269.587726)
			(xy 383.93878 -269.631922) (xy 384.29438 -269.631922)
		)
		(stroke
			(width 0)
			(type solid)
		)
		(fill yes)
		(layer "In11.Cu")
		(net "M_H_CPU0_SA_DQ<27>")
	)
	(gr_poly
		(pts
			(xy 384.296666 -277.726394) (xy 384.249676 -277.573994) (xy 383.988056 -277.573994) (xy 383.941066 -277.726394)
			(xy 383.941066 -277.770844) (xy 384.296666 -277.770844)
		)
		(stroke
			(width 0)
			(type solid)
		)
		(fill yes)
		(layer "In11.Cu")
		(net "M_H_CPU0_SA_DQ<14>")
	)
	(gr_poly
		(pts
			(xy 384.296666 -277.318216) (xy 384.296666 -277.27402) (xy 383.941066 -277.27402) (xy 383.941066 -277.318216)
			(xy 383.988056 -277.470616) (xy 384.249676 -277.470616)
		)
		(stroke
			(width 0)
			(type solid)
		)
		(fill yes)
		(layer "In11.Cu")
		(net "M_H_CPU0_SA_DQ<13>")
	)
	(gr_poly
		(pts
			(xy 384.302762 -282.610052) (xy 384.255772 -282.457652) (xy 383.994152 -282.457652) (xy 383.947162 -282.610052)
			(xy 383.947162 -282.654502) (xy 384.302762 -282.654502)
		)
		(stroke
			(width 0)
			(type solid)
		)
		(fill yes)
		(layer "In11.Cu")
		(net "M_H_CPU0_SA_DQ<10>")
	)
	(gr_poly
		(pts
			(xy 384.302762 -282.20162) (xy 384.302762 -282.15717) (xy 383.947162 -282.15717) (xy 383.947162 -282.20162)
			(xy 383.994152 -282.35402) (xy 384.255772 -282.35402)
		)
		(stroke
			(width 0)
			(type solid)
		)
		(fill yes)
		(layer "In11.Cu")
		(net "M_H_CPU0_SA_DQ<9>")
	)
	(gr_poly
		(pts
			(xy 384.302762 -274.062698) (xy 384.302762 -274.018248) (xy 383.947162 -274.018248) (xy 383.947162 -274.062698)
			(xy 383.994152 -274.215098) (xy 384.255772 -274.215098)
		)
		(stroke
			(width 0)
			(type solid)
		)
		(fill yes)
		(layer "In11.Cu")
		(net "M_H_CPU0_SA_DQS_DP<2>")
	)
	(gr_poly
		(pts
			(xy 384.302762 -272.843498) (xy 384.255772 -272.691098) (xy 383.994152 -272.691098) (xy 383.947162 -272.843498)
			(xy 383.947162 -272.887948) (xy 384.302762 -272.887948)
		)
		(stroke
			(width 0)
			(type solid)
		)
		(fill yes)
		(layer "In11.Cu")
		(net "M_H_CPU0_SA_DQS_DP<7>")
	)
	(gr_poly
		(pts
			(xy 384.302762 -269.179294) (xy 384.302762 -269.134844) (xy 383.947162 -269.134844) (xy 383.947162 -269.179294)
			(xy 383.994152 -269.331694) (xy 384.255772 -269.331694)
		)
		(stroke
			(width 0)
			(type solid)
		)
		(fill yes)
		(layer "In11.Cu")
		(net "M_H_CPU0_SA_DQS_DP<3>")
	)
	(gr_poly
		(pts
			(xy 384.302762 -261.449058) (xy 384.255772 -261.296658) (xy 383.994152 -261.296658) (xy 383.947162 -261.449058)
			(xy 383.947162 -261.493508) (xy 384.302762 -261.493508)
		)
		(stroke
			(width 0)
			(type solid)
		)
		(fill yes)
		(layer "In11.Cu")
		(net "M_H_CPU0_SA_CB<3>")
	)
	(gr_poly
		(pts
			(xy 384.302762 -261.040626) (xy 384.302762 -260.996176) (xy 383.947162 -260.996176) (xy 383.947162 -261.040626)
			(xy 383.994152 -261.193026) (xy 384.255772 -261.193026)
		)
		(stroke
			(width 0)
			(type solid)
		)
		(fill yes)
		(layer "In11.Cu")
		(net "M_H_CPU0_SA_DQS_DP<4>")
	)
	(gr_poly
		(pts
			(xy 384.302762 -256.565654) (xy 384.255772 -256.413254) (xy 383.994152 -256.413254) (xy 383.947162 -256.565654)
			(xy 383.947162 -256.610104) (xy 384.302762 -256.610104)
		)
		(stroke
			(width 0)
			(type solid)
		)
		(fill yes)
		(layer "In11.Cu")
		(net "M_H_CPU0_SA_CS_N<1>")
	)
	(gr_poly
		(pts
			(xy 384.302762 -256.157222) (xy 384.302762 -256.112772) (xy 383.947162 -256.112772) (xy 383.947162 -256.157222)
			(xy 383.994152 -256.309622) (xy 384.255772 -256.309622)
		)
		(stroke
			(width 0)
			(type solid)
		)
		(fill yes)
		(layer "In11.Cu")
		(net "M_H_CPU0_SA_CS_N<2>")
	)
	(gr_poly
		(pts
			(xy 384.302762 -254.938022) (xy 384.255772 -254.785622) (xy 383.994152 -254.785622) (xy 383.947162 -254.938022)
			(xy 383.947162 -254.982218) (xy 384.302762 -254.982218)
		)
		(stroke
			(width 0)
			(type solid)
		)
		(fill yes)
		(layer "In11.Cu")
		(net "M_H_CPU0_SA_CA<0>")
	)
	(gr_poly
		(pts
			(xy 384.302762 -254.529082) (xy 384.302762 -254.484886) (xy 383.947162 -254.484886) (xy 383.947162 -254.529082)
			(xy 383.994152 -254.681482) (xy 384.255772 -254.681482)
		)
		(stroke
			(width 0)
			(type solid)
		)
		(fill yes)
		(layer "In11.Cu")
		(net "M_H_CPU0_SA_CA<2>")
	)
	(gr_poly
		(pts
			(xy 384.308858 -258.193286) (xy 384.261868 -258.040886) (xy 384.000248 -258.040886) (xy 383.953258 -258.193286)
			(xy 383.953258 -258.237482) (xy 384.308858 -258.237482)
		)
		(stroke
			(width 0)
			(type solid)
		)
		(fill yes)
		(layer "In11.Cu")
		(net "M_H_CPU0_SA_CB<7>")
	)
	(gr_poly
		(pts
			(xy 384.308858 -257.784854) (xy 384.308858 -257.740658) (xy 383.953258 -257.740658) (xy 383.953258 -257.784854)
			(xy 384.000248 -257.937254) (xy 384.261868 -257.937254)
		)
		(stroke
			(width 0)
			(type solid)
		)
		(fill yes)
		(layer "In11.Cu")
		(net "M_E_CPU0_ALERT_N")
	)
	(gr_poly
		(pts
			(xy 384.624072 -283.675328) (xy 384.662426 -283.65323) (xy 384.484626 -283.345382) (xy 384.446272 -283.36748)
			(xy 384.337814 -283.48432) (xy 384.468624 -283.710888)
		)
		(stroke
			(width 0)
			(type solid)
		)
		(fill yes)
		(layer "In11.Cu")
		(net "M_H_CPU0_SA_DQ<8>")
	)
	(gr_poly
		(pts
			(xy 384.630422 -280.430986) (xy 384.668776 -280.408888) (xy 384.490976 -280.10104) (xy 384.452622 -280.123138)
			(xy 384.344164 -280.239978) (xy 384.474974 -280.466546)
		)
		(stroke
			(width 0)
			(type solid)
		)
		(fill yes)
		(layer "In11.Cu")
		(net "M_H_CPU0_SA_DQS_DN<6>")
	)
	(gr_poly
		(pts
			(xy 384.739134 -279.809194) (xy 384.847592 -279.692354) (xy 384.716782 -279.465786) (xy 384.561334 -279.501346)
			(xy 384.52298 -279.523444) (xy 384.70078 -279.831292)
		)
		(stroke
			(width 0)
			(type solid)
		)
		(fill yes)
		(layer "In11.Cu")
		(net "M_H_CPU0_SA_DQS_DP<6>")
	)
	(gr_poly
		(pts
			(xy 384.739896 -283.065728) (xy 384.848354 -282.948888) (xy 384.717544 -282.72232) (xy 384.562096 -282.75788)
			(xy 384.523742 -282.779978) (xy 384.701542 -283.087826)
		)
		(stroke
			(width 0)
			(type solid)
		)
		(fill yes)
		(layer "In11.Cu")
		(net "M_H_CPU0_SA_DQ<10>")
	)
	(gr_poly
		(pts
			(xy 384.772662 -281.796236) (xy 384.725672 -281.643836) (xy 384.464052 -281.643836) (xy 384.417062 -281.796236)
			(xy 384.417062 -281.840686) (xy 384.772662 -281.840686)
		)
		(stroke
			(width 0)
			(type solid)
		)
		(fill yes)
		(layer "In11.Cu")
		(net "M_H_CPU0_SA_DQ<11>")
	)
	(gr_poly
		(pts
			(xy 384.772662 -281.38755) (xy 384.772662 -281.343354) (xy 384.417062 -281.343354) (xy 384.417062 -281.38755)
			(xy 384.464052 -281.53995) (xy 384.725672 -281.53995)
		)
		(stroke
			(width 0)
			(type solid)
		)
		(fill yes)
		(layer "In11.Cu")
		(net "M_H_CPU0_SA_DQS_DP<1>")
	)
	(gr_poly
		(pts
			(xy 385.093972 -284.489398) (xy 385.132326 -284.4673) (xy 384.954526 -284.159452) (xy 384.916172 -284.18155)
			(xy 384.807714 -284.29839) (xy 384.938524 -284.524958)
		)
		(stroke
			(width 0)
			(type solid)
		)
		(fill yes)
		(layer "In11.Cu")
		(net "M_H_CPU0_SA_DQ<8>")
	)
	(gr_poly
		(pts
			(xy 385.099306 -282.870656) (xy 385.13766 -282.848558) (xy 384.95986 -282.54071) (xy 384.921506 -282.562808)
			(xy 384.813048 -282.679648) (xy 384.943858 -282.906216)
		)
		(stroke
			(width 0)
			(type solid)
		)
		(fill yes)
		(layer "In11.Cu")
		(net "M_H_CPU0_SA_DQ<9>")
	)
	(gr_poly
		(pts
			(xy 385.208018 -283.876242) (xy 385.316476 -283.759402) (xy 385.185666 -283.532834) (xy 385.030218 -283.568394)
			(xy 384.991864 -283.590492) (xy 385.169664 -283.89834)
		)
		(stroke
			(width 0)
			(type solid)
		)
		(fill yes)
		(layer "In11.Cu")
		(net "M_H_CPU0_SA_DQ<10>")
	)
	(gr_poly
		(pts
			(xy 385.209034 -282.250896) (xy 385.317492 -282.134056) (xy 385.186682 -281.907488) (xy 385.031234 -281.943048)
			(xy 384.99288 -281.965146) (xy 385.17068 -282.272994)
		)
		(stroke
			(width 0)
			(type solid)
		)
		(fill yes)
		(layer "In11.Cu")
		(net "M_H_CPU0_SA_DQ<11>")
	)
	(gr_poly
		(pts
			(xy 385.242562 -280.982674) (xy 385.195572 -280.830274) (xy 384.933952 -280.830274) (xy 384.886962 -280.982674)
			(xy 384.886962 -281.02687) (xy 385.242562 -281.02687)
		)
		(stroke
			(width 0)
			(type solid)
		)
		(fill yes)
		(layer "In11.Cu")
		(net "M_H_CPU0_SA_DQS_DN<1>")
	)
	(gr_poly
		(pts
			(xy 385.242562 -280.573734) (xy 385.242562 -280.529538) (xy 384.886962 -280.529538) (xy 384.886962 -280.573734)
			(xy 384.933952 -280.726134) (xy 385.195572 -280.726134)
		)
		(stroke
			(width 0)
			(type solid)
		)
		(fill yes)
		(layer "In11.Cu")
		(net "M_H_CPU0_SA_DQS_DN<6>")
	)
	(gr_poly
		(pts
			(xy 385.56946 -283.685234) (xy 385.607814 -283.663136) (xy 385.430014 -283.355288) (xy 385.39166 -283.377386)
			(xy 385.283202 -283.494226) (xy 385.414012 -283.720794)
		)
		(stroke
			(width 0)
			(type solid)
		)
		(fill yes)
		(layer "In11.Cu")
		(net "M_H_CPU0_SA_DQ<9>")
	)
	(gr_poly
		(pts
			(xy 385.678172 -283.062934) (xy 385.78663 -282.946094) (xy 385.65582 -282.719526) (xy 385.500372 -282.755086)
			(xy 385.462018 -282.777184) (xy 385.639818 -283.085032)
		)
		(stroke
			(width 0)
			(type solid)
		)
		(fill yes)
		(layer "In11.Cu")
		(net "M_H_CPU0_SA_DQ<11>")
	)
	(gr_poly
		(pts
			(xy 385.678934 -281.43708) (xy 385.787392 -281.32024) (xy 385.656582 -281.093672) (xy 385.501134 -281.129232)
			(xy 385.46278 -281.15133) (xy 385.64058 -281.459178)
		)
		(stroke
			(width 0)
			(type solid)
		)
		(fill yes)
		(layer "In11.Cu")
		(net "M_H_CPU0_SA_DQS_DN<1>")
	)
	(gr_poly
		(pts
			(xy 385.712462 -280.168604) (xy 385.665472 -280.016204) (xy 385.403852 -280.016204) (xy 385.356862 -280.168604)
			(xy 385.356862 -280.2128) (xy 385.712462 -280.2128)
		)
		(stroke
			(width 0)
			(type solid)
		)
		(fill yes)
		(layer "In11.Cu")
		(net "M_H_CPU0_SA_DQS_DP<6>")
	)
	(gr_poly
		(pts
			(xy 386.033772 -284.489398) (xy 386.072126 -284.4673) (xy 385.894326 -284.159452) (xy 385.855972 -284.18155)
			(xy 385.747514 -284.29839) (xy 385.878324 -284.524958)
		)
		(stroke
			(width 0)
			(type solid)
		)
		(fill yes)
		(layer "In11.Cu")
		(net "M_H_CPU0_SA_DQ<9>")
	)
	(gr_poly
		(pts
			(xy 386.147818 -283.876242) (xy 386.256276 -283.759402) (xy 386.125466 -283.532834) (xy 385.970018 -283.568394)
			(xy 385.931664 -283.590492) (xy 386.109464 -283.89834)
		)
		(stroke
			(width 0)
			(type solid)
		)
		(fill yes)
		(layer "In11.Cu")
		(net "M_H_CPU0_SA_DQ<11>")
	)
	(gr_poly
		(pts
			(xy 386.148072 -280.621232) (xy 386.25653 -280.504392) (xy 386.12572 -280.277824) (xy 385.970272 -280.313384)
			(xy 385.931918 -280.335482) (xy 386.109718 -280.64333)
		)
		(stroke
			(width 0)
			(type solid)
		)
		(fill yes)
		(layer "In11.Cu")
		(net "M_H_CPU0_SA_DQS_DP<6>")
	)
	(gr_poly
		(pts
			(xy 386.148834 -282.250896) (xy 386.257292 -282.134056) (xy 386.126482 -281.907488) (xy 385.971034 -281.943048)
			(xy 385.93268 -281.965146) (xy 386.11048 -282.272994)
		)
		(stroke
			(width 0)
			(type solid)
		)
		(fill yes)
		(layer "In11.Cu")
		(net "M_H_CPU0_SA_DQS_DN<1>")
	)
	(gr_poly
		(pts
			(xy 29.542486 -166.656004) (xy 29.542486 -162.998404) (xy 29.491686 -162.947604) (xy 25.834086 -162.947604)
			(xy 25.783286 -162.998404) (xy 25.783286 -166.656004) (xy 25.834086 -166.706804) (xy 29.491686 -166.706804)
		)
		(stroke
			(width 0)
			(type solid)
		)
		(fill yes)
		(layer "In11.Cu")
		(net "GND")
	)
	(gr_poly
		(pts
			(xy 30.154118 -335.06537) (xy 30.154118 -330.49591) (xy 29.138118 -329.47991) (xy 18.368518 -329.47991)
			(xy 17.126458 -330.72197) (xy 17.126458 -335.63179) (xy 17.827498 -336.33283) (xy 28.886658 -336.33283)
		)
		(stroke
			(width 0)
			(type solid)
		)
		(fill yes)
		(layer "In11.Cu")
		(net "P12V_S3_AUX_CPU1_NVDIMM")
	)
	(gr_poly
		(pts
			(xy 33.94075 -131.462272) (xy 33.94075 -127.804672) (xy 33.88995 -127.753872) (xy 30.23235 -127.753872)
			(xy 30.18155 -127.804672) (xy 30.18155 -131.462272) (xy 30.23235 -131.513072) (xy 33.88995 -131.513072)
		)
		(stroke
			(width 0)
			(type solid)
		)
		(fill yes)
		(layer "In11.Cu")
		(net "GND")
	)
	(gr_poly
		(pts
			(xy 217.33256 -26.947368) (xy 217.33256 -25.212548) (xy 216.7382 -24.618188) (xy 213.22538 -24.618188)
			(xy 213.03488 -24.808688) (xy 213.03488 -27.396948) (xy 213.26856 -27.630628) (xy 216.6493 -27.630628)
		)
		(stroke
			(width 0)
			(type solid)
		)
		(fill yes)
		(layer "In11.Cu")
		(net "GND")
	)
	(gr_poly
		(pts
			(xy 249.511312 -89.374472) (xy 249.511312 -86.478872) (xy 249.333512 -86.301072) (xy 245.904512 -86.301072)
			(xy 245.752112 -86.453472) (xy 245.752112 -89.653872) (xy 245.929912 -89.831672) (xy 249.054112 -89.831672)
		)
		(stroke
			(width 0)
			(type solid)
		)
		(fill yes)
		(layer "In11.Cu")
		(net "GND")
	)
	(gr_poly
		(pts
			(xy 326.70242 -32.253428) (xy 326.70242 -31.360872) (xy 323.875908 -28.53436) (xy 323.57822 -28.53436)
			(xy 321.00901 -31.10357) (xy 321.00901 -31.812484) (xy 323.807074 -34.610548) (xy 324.3453 -34.610548)
		)
		(stroke
			(width 0)
			(type solid)
		)
		(fill yes)
		(layer "In11.Cu")
		(net "GND")
	)
	(gr_poly
		(pts
			(xy 337.936586 -70.187058) (xy 337.936586 -67.25412) (xy 337.568032 -66.885566) (xy 333.806038 -66.885566)
			(xy 333.422244 -67.26936) (xy 333.422244 -70.586092) (xy 333.54518 -70.709028) (xy 337.414616 -70.709028)
		)
		(stroke
			(width 0)
			(type solid)
		)
		(fill yes)
		(layer "In11.Cu")
		(net "GND")
	)
	(gr_poly
		(pts
			(xy 427.559216 -138.21791) (xy 427.559216 -134.61111) (xy 427.508416 -134.56031) (xy 423.901616 -134.56031)
			(xy 423.850816 -134.61111) (xy 423.850816 -138.21791) (xy 423.901616 -138.26871) (xy 427.508416 -138.26871)
		)
		(stroke
			(width 0)
			(type solid)
		)
		(fill yes)
		(layer "In11.Cu")
		(net "GND")
	)
	(gr_poly
		(pts
			(xy 49.318164 -395.461744) (xy 49.220628 -395.364208)
			(arc
				(start 47.639732 -395.364208)
				(mid 47.552191 -395.414241)
				(end 47.550832 -395.515084)
			)
			(arc
				(start 47.550832 -395.515084)
				(mid 47.585919 -395.60178)
				(end 47.598838 -395.694408)
			)
			(xy 47.5996 -395.744192) (xy 49.035716 -395.744192)
		)
		(stroke
			(width 0)
			(type solid)
		)
		(fill yes)
		(layer "In11.Cu")
		(net "P3V3_AUX")
	)
	(gr_poly
		(pts
			(xy 230.38054 -434.93182) (xy 230.38054 -427.00194) (xy 230.38816 -426.99432) (xy 230.38816 -423.3037)
			(xy 233.04246 -420.6494) (xy 270.34236 -420.6494) (xy 275.54936 -415.4424) (xy 279.79624 -415.4424)
			(xy 280.19756 -415.04108) (xy 280.19756 -408.29992) (xy 279.96896 -408.07132) (xy 239.84458 -408.07132)
			(xy 233.0704 -414.8455) (xy 207.34528 -414.8455) (xy 206.49184 -415.69894) (xy 206.49184 -435.39156)
			(xy 207.63484 -436.53456) (xy 228.7778 -436.53456)
		)
		(stroke
			(width 0)
			(type solid)
		)
		(fill yes)
		(layer "In11.Cu")
		(net "P12V_PSU")
	)
	(gr_poly
		(pts
			(arc
				(start 150.249128 -39.517828)
				(mid 150.54834 -39.354789)
				(end 150.847552 -39.517828)
			)
			(xy 151.54148 -39.517828) (xy 151.7142 -39.345108) (xy 151.7142 -35.761168) (xy 151.47036 -35.517328)
			(xy 148.971 -35.517328) (xy 148.7424 -35.745928) (xy 148.7424 -39.268908) (xy 148.99132 -39.517828)
		)
		(stroke
			(width 0)
			(type solid)
		)
		(fill yes)
		(layer "In11.Cu")
		(net "GND")
	)
	(gr_poly
		(pts
			(arc
				(start 292.333426 -162.139884)
				(mid 292.00475 -162.139884)
				(end 292.333426 -162.139884)
			)
		)
		(stroke
			(width 0)
			(type solid)
		)
		(fill yes)
		(layer "In11.Cu")
		(net "GND")
	)
	(gr_poly
		(pts
			(arc
				(start 294.489886 -163.135564)
				(mid 294.16121 -163.135564)
				(end 294.489886 -163.135564)
			)
		)
		(stroke
			(width 0)
			(type solid)
		)
		(fill yes)
		(layer "In11.Cu")
		(net "GND")
	)
	(gr_poly
		(pts
			(arc
				(start 294.781986 -162.106864)
				(mid 294.45331 -162.106864)
				(end 294.781986 -162.106864)
			)
		)
		(stroke
			(width 0)
			(type solid)
		)
		(fill yes)
		(layer "In11.Cu")
		(net "GND")
	)
	(gr_poly
		(pts
			(arc
				(start 296.511726 -161.596324)
				(mid 296.18305 -161.596324)
				(end 296.511726 -161.596324)
			)
		)
		(stroke
			(width 0)
			(type solid)
		)
		(fill yes)
		(layer "In11.Cu")
		(net "GND")
	)
	(gr_poly
		(pts
			(arc
				(start 296.938446 -163.102544)
				(mid 296.60977 -163.102544)
				(end 296.938446 -163.102544)
			)
		)
		(stroke
			(width 0)
			(type solid)
		)
		(fill yes)
		(layer "In11.Cu")
		(net "GND")
	)
	(gr_poly
		(pts
			(arc
				(start 298.960286 -161.563304)
				(mid 298.63161 -161.563304)
				(end 298.960286 -161.563304)
			)
		)
		(stroke
			(width 0)
			(type solid)
		)
		(fill yes)
		(layer "In11.Cu")
		(net "GND")
	)
	(gr_poly
		(pts
			(arc
				(start 299.950886 -163.122864)
				(mid 299.62221 -163.122864)
				(end 299.950886 -163.122864)
			)
		)
		(stroke
			(width 0)
			(type solid)
		)
		(fill yes)
		(layer "In11.Cu")
		(net "GND")
	)
	(gr_poly
		(pts
			(arc
				(start 302.399446 -163.089844)
				(mid 302.07077 -163.089844)
				(end 302.399446 -163.089844)
			)
		)
		(stroke
			(width 0)
			(type solid)
		)
		(fill yes)
		(layer "In11.Cu")
		(net "GND")
	)
	(gr_poly
		(pts
			(arc
				(start 369.603528 -182.463948)
				(mid 369.251484 -182.463948)
				(end 369.603528 -182.463948)
			)
		)
		(stroke
			(width 0)
			(type solid)
		)
		(fill yes)
		(layer "In11.Cu")
		(net "GND")
	)
	(gr_poly
		(pts
			(arc
				(start 371.838728 -181.226968)
				(mid 371.486684 -181.226968)
				(end 371.838728 -181.226968)
			)
		)
		(stroke
			(width 0)
			(type solid)
		)
		(fill yes)
		(layer "In11.Cu")
		(net "GND")
	)
	(gr_poly
		(pts
			(arc
				(start 372.654576 -184.655968)
				(mid 372.302532 -184.655968)
				(end 372.654576 -184.655968)
			)
		)
		(stroke
			(width 0)
			(type solid)
		)
		(fill yes)
		(layer "In11.Cu")
		(net "GND")
	)
	(gr_poly
		(pts
			(arc
				(start 373.467376 -181.353968)
				(mid 373.115332 -181.353968)
				(end 373.467376 -181.353968)
			)
		)
		(stroke
			(width 0)
			(type solid)
		)
		(fill yes)
		(layer "In11.Cu")
		(net "GND")
	)
	(gr_poly
		(pts
			(arc
				(start 374.810528 -185.900568)
				(mid 374.458484 -185.900568)
				(end 374.810528 -185.900568)
			)
		)
		(stroke
			(width 0)
			(type solid)
		)
		(fill yes)
		(layer "In11.Cu")
		(net "GND")
	)
	(gr_poly
		(pts
			(arc
				(start 375.623328 -182.598568)
				(mid 375.271284 -182.598568)
				(end 375.623328 -182.598568)
			)
		)
		(stroke
			(width 0)
			(type solid)
		)
		(fill yes)
		(layer "In11.Cu")
		(net "GND")
	)
	(gr_poly
		(pts
			(arc
				(start 339.513418 -73.85177)
				(mid 339.147658 -73.85177)
				(end 339.513418 -73.85177)
			)
		)
		(stroke
			(width 0)
			(type solid)
		)
		(fill yes)
		(layer "In11.Cu")
		(net "GND")
	)
	(gr_poly
		(pts
			(arc
				(start 340.772242 -73.85177)
				(mid 340.406482 -73.85177)
				(end 340.772242 -73.85177)
			)
		)
		(stroke
			(width 0)
			(type solid)
		)
		(fill yes)
		(layer "In11.Cu")
		(net "GND")
	)
	(gr_poly
		(pts
			(xy 245.06174 -251.739908) (xy 245.06174 -247.261888) (xy 244.59692 -246.797068) (xy 240.55578 -246.797068)
			(xy 240.2205 -247.132348) (xy 240.2205 -249.273568) (xy 240.806222 -249.273568) (xy 240.810293 -249.217946)
			(xy 240.822419 -249.163509) (xy 240.842342 -249.111418) (xy 240.869638 -249.062783) (xy 240.903724 -249.01864)
			(xy 240.943873 -248.979931) (xy 240.989231 -248.94748) (xy 241.038831 -248.921979) (xy 241.091615 -248.903972)
			(xy 241.146458 -248.893842) (xy 241.202192 -248.891805) (xy 241.257629 -248.897905) (xy 241.311586 -248.912011)
			(xy 241.362915 -248.933823) (xy 241.410521 -248.962877) (xy 241.453389 -248.998552) (xy 241.490606 -249.040089)
			(xy 241.521379 -249.086602) (xy 241.545051 -249.137099) (xy 241.561119 -249.190506) (xy 241.569239 -249.245682)
			(xy 241.569748 -249.273568) (xy 241.569239 -249.301454) (xy 241.561119 -249.35663) (xy 241.545051 -249.410037)
			(xy 241.521379 -249.460534) (xy 241.490606 -249.507047) (xy 241.453389 -249.548584) (xy 241.410521 -249.584259)
			(xy 241.362915 -249.613313) (xy 241.311586 -249.635125) (xy 241.257629 -249.649231) (xy 241.202192 -249.655331)
			(xy 241.146458 -249.653294) (xy 241.091615 -249.643164) (xy 241.038831 -249.625157) (xy 240.989231 -249.599656)
			(xy 240.943873 -249.567205) (xy 240.903724 -249.528496) (xy 240.869638 -249.484353) (xy 240.842342 -249.435718)
			(xy 240.822419 -249.383627) (xy 240.810293 -249.32919) (xy 240.806222 -249.273568) (xy 240.2205 -249.273568)
			(xy 240.2205 -251.922788) (xy 240.4872 -252.189488) (xy 244.61216 -252.189488)
		)
		(stroke
			(width 0)
			(type solid)
		)
		(fill yes)
		(layer "In11.Cu")
		(net "GND")
	)
	(gr_poly
		(pts
			(xy 361.21848 -366.080548) (xy 361.21848 -364.635542) (xy 360.69905 -364.116112)
			(arc
				(start 360.597196 -364.116112)
				(mid 360.525175 -364.14605)
				(end 360.495596 -364.21822)
			)
			(arc
				(start 360.495596 -364.223046)
				(mid 360.435649 -364.519402)
				(end 360.265218 -364.769146)
			)
			(arc
				(start 360.265218 -364.769146)
				(mid 360.234677 -364.841251)
				(end 360.264456 -364.913672)
			)
			(arc
				(start 360.398568 -365.047784)
				(mid 360.528023 -365.234812)
				(end 360.583226 -365.455454)
			)
			(arc
				(start 360.583226 -365.455454)
				(mid 360.791673 -365.590639)
				(end 360.872532 -365.825532)
			)
			(arc
				(start 360.872532 -365.825532)
				(mid 360.802641 -366.045711)
				(end 360.618532 -366.185196)
			)
			(xy 360.584496 -366.197134) (xy 360.584496 -366.360202) (xy 360.761788 -366.53724)
		)
		(stroke
			(width 0)
			(type solid)
		)
		(fill yes)
		(layer "In11.Cu")
		(net "PVCCIN_CPU0_VREF")
	)
	(gr_poly
		(pts
			(xy 107.10545 -353.728782) (xy 107.11495 -353.719478) (xy 107.13557 -353.702684) (xy 107.146598 -353.695254)
			(xy 107.169712 -353.680268) (xy 107.169712 -353.602036) (xy 103.552498 -353.602036) (xy 103.540353 -353.601845)
			(xy 103.516182 -353.599423) (xy 103.504238 -353.59721) (xy 103.477568 -353.59213) (xy 103.422704 -353.647248)
			(xy 104.272715 -354.497132) (xy 105.004868 -354.497132) (xy 105.008939 -354.44151) (xy 105.021065 -354.387073)
			(xy 105.040988 -354.334982) (xy 105.068284 -354.286347) (xy 105.10237 -354.242204) (xy 105.142519 -354.203495)
			(xy 105.187877 -354.171044) (xy 105.237477 -354.145543) (xy 105.290261 -354.127536) (xy 105.345104 -354.117406)
			(xy 105.400838 -354.115369) (xy 105.456275 -354.121469) (xy 105.510232 -354.135575) (xy 105.561561 -354.157387)
			(xy 105.609167 -354.186441) (xy 105.652035 -354.222116) (xy 105.689252 -354.263653) (xy 105.720025 -354.310166)
			(xy 105.743697 -354.360663) (xy 105.759765 -354.41407) (xy 105.767885 -354.469246) (xy 105.768394 -354.497132)
			(xy 105.767885 -354.525018) (xy 105.759765 -354.580194) (xy 105.743697 -354.633601) (xy 105.720025 -354.684098)
			(xy 105.689252 -354.730611) (xy 105.652035 -354.772148) (xy 105.609167 -354.807823) (xy 105.561561 -354.836877)
			(xy 105.510232 -354.858689) (xy 105.456275 -354.872795) (xy 105.400838 -354.878895) (xy 105.345104 -354.876858)
			(xy 105.290261 -354.866728) (xy 105.237477 -354.848721) (xy 105.187877 -354.82322) (xy 105.142519 -354.790769)
			(xy 105.10237 -354.75206) (xy 105.068284 -354.707917) (xy 105.040988 -354.659282) (xy 105.021065 -354.607191)
			(xy 105.008939 -354.552754) (xy 105.004868 -354.497132) (xy 104.272715 -354.497132) (xy 105.125266 -355.349556)
			(xy 105.484422 -355.349556)
		)
		(stroke
			(width 0)
			(type solid)
		)
		(fill yes)
		(layer "In11.Cu")
		(net "GND")
	)
	(gr_poly
		(pts
			(xy 10.35558 -100.975668)
			(arc
				(start 10.35558 -100.736908)
				(mid 10.269496 -100.495608)
				(end 10.35558 -100.254308)
			)
			(arc
				(start 10.35558 -100.03917)
				(mid 10.302076 -99.949675)
				(end 10.197846 -99.954334)
			)
			(arc
				(start 10.197846 -99.954334)
				(mid 10.09724 -100.001603)
				(end 9.98728 -100.017834)
			)
			(arc
				(start 9.98728 -100.017834)
				(mid 9.605772 -99.636326)
				(end 9.98728 -99.254818)
			)
			(arc
				(start 9.98728 -99.254818)
				(mid 10.097231 -99.271082)
				(end 10.197846 -99.318318)
			)
			(arc
				(start 10.197846 -99.318318)
				(mid 10.302135 -99.323088)
				(end 10.35558 -99.233482)
			)
			(xy 10.35558 -98.755962)
			(arc
				(start 10.315702 -98.747072)
				(mid 10.017245 -98.374708)
				(end 10.315702 -98.002344)
			)
			(xy 10.35558 -97.993454) (xy 10.35558 -97.711768) (xy 9.72566 -97.081848) (xy 6.02742 -97.081848)
			(xy 5.44576 -97.663508) (xy 5.44576 -100.912168) (xy 5.91312 -101.379528) (xy 9.95172 -101.379528)
		)
		(stroke
			(width 0)
			(type solid)
		)
		(fill yes)
		(layer "In11.Cu")
		(net "GND")
	)
	(gr_poly
		(pts
			(xy 66.843656 -180.084222) (xy 66.870441 -180.058198) (xy 66.929075 -180.011943) (xy 66.992725 -179.972875)
			(xy 67.060513 -179.941534) (xy 67.131507 -179.918351) (xy 67.168014 -179.910486) (xy 67.183254 -179.907438)
			(xy 67.265804 -179.824888) (xy 70.1802 -179.824888) (xy 70.903846 -179.101242) (xy 70.903846 -178.909218)
			(xy 70.903366 -178.89457) (xy 70.895054 -178.866478) (xy 70.879108 -178.841903) (xy 70.856841 -178.822865)
			(xy 70.830085 -178.810933) (xy 70.801043 -178.807088) (xy 70.786498 -178.808888) (xy 70.751106 -178.814116)
			(xy 70.679778 -178.819708) (xy 70.644004 -178.820064) (xy 70.601729 -178.819591) (xy 70.51754 -178.81179)
			(xy 70.434429 -178.796254) (xy 70.353107 -178.773116) (xy 70.274267 -178.742574) (xy 70.19858 -178.704887)
			(xy 70.126695 -178.660377) (xy 70.059222 -178.609425) (xy 69.996739 -178.552464) (xy 69.939778 -178.489981)
			(xy 69.888825 -178.422509) (xy 69.844315 -178.350623) (xy 69.806628 -178.274937) (xy 69.776085 -178.196097)
			(xy 69.752947 -178.114774) (xy 69.737411 -178.031664) (xy 69.729609 -177.947475) (xy 69.729609 -177.862925)
			(xy 69.737411 -177.778736) (xy 69.752947 -177.695626) (xy 69.776085 -177.614303) (xy 69.806628 -177.535463)
			(xy 69.844315 -177.459777) (xy 69.888825 -177.387891) (xy 69.939778 -177.320419) (xy 69.996739 -177.257936)
			(xy 70.059222 -177.200975) (xy 70.126695 -177.150023) (xy 70.19858 -177.105513) (xy 70.274267 -177.067826)
			(xy 70.353107 -177.037284) (xy 70.434429 -177.014146) (xy 70.51754 -176.99861) (xy 70.601729 -176.990809)
			(xy 70.644004 -176.990248) (xy 70.679778 -176.990593) (xy 70.751108 -176.996186) (xy 70.786498 -177.001424)
			(xy 70.801039 -177.003212) (xy 70.830069 -176.999346) (xy 70.856812 -176.987407) (xy 70.879071 -176.968375)
			(xy 70.89502 -176.943813) (xy 70.90335 -176.915737) (xy 70.903846 -176.901094) (xy 70.903846 -174.414688)
			(xy 70.394576 -173.905672) (xy 68.992242 -173.905672) (xy 66.14922 -171.06265) (xy 61.143134 -171.06265)
			(xy 61.110114 -171.09567) (xy 61.061854 -171.09567) (xy 60.661804 -171.49572) (xy 60.661804 -177.947504)
			(xy 67.755004 -177.947504) (xy 67.755004 -177.862808) (xy 67.763055 -177.778494) (xy 67.779084 -177.695328)
			(xy 67.802945 -177.614061) (xy 67.834424 -177.535431) (xy 67.873235 -177.46015) (xy 67.919025 -177.388898)
			(xy 67.971381 -177.322322) (xy 68.029829 -177.261024) (xy 68.093839 -177.205559) (xy 68.162831 -177.15643)
			(xy 68.236181 -177.114081) (xy 68.313224 -177.078897) (xy 68.393263 -177.051195) (xy 68.475572 -177.031227)
			(xy 68.559407 -177.019174) (xy 68.644008 -177.015144) (xy 68.728609 -177.019174) (xy 68.812444 -177.031227)
			(xy 68.894753 -177.051195) (xy 68.974792 -177.078897) (xy 69.051835 -177.114081) (xy 69.125185 -177.15643)
			(xy 69.194177 -177.205559) (xy 69.258187 -177.261024) (xy 69.316635 -177.322322) (xy 69.368991 -177.388898)
			(xy 69.414781 -177.46015) (xy 69.453592 -177.535431) (xy 69.485071 -177.614061) (xy 69.508932 -177.695328)
			(xy 69.524961 -177.778494) (xy 69.533012 -177.862808) (xy 69.533516 -177.905156) (xy 69.533012 -177.947504)
			(xy 69.524961 -178.031818) (xy 69.508932 -178.114984) (xy 69.485071 -178.196251) (xy 69.453592 -178.274881)
			(xy 69.414781 -178.350162) (xy 69.368991 -178.421414) (xy 69.316635 -178.48799) (xy 69.258187 -178.549288)
			(xy 69.194177 -178.604753) (xy 69.125185 -178.653882) (xy 69.051835 -178.696231) (xy 68.974792 -178.731415)
			(xy 68.894753 -178.759117) (xy 68.812444 -178.779085) (xy 68.728609 -178.791138) (xy 68.644008 -178.795169)
			(xy 68.559407 -178.791138) (xy 68.475572 -178.779085) (xy 68.393263 -178.759117) (xy 68.313224 -178.731415)
			(xy 68.236181 -178.696231) (xy 68.162831 -178.653882) (xy 68.093839 -178.604753) (xy 68.029829 -178.549288)
			(xy 67.971381 -178.48799) (xy 67.919025 -178.421414) (xy 67.873235 -178.350162) (xy 67.834424 -178.274881)
			(xy 67.802945 -178.196251) (xy 67.779084 -178.114984) (xy 67.763055 -178.031818) (xy 67.755004 -177.947504)
			(xy 60.661804 -177.947504) (xy 60.661804 -180.67401) (xy 61.148468 -181.160674) (xy 65.767204 -181.160674)
		)
		(stroke
			(width 0)
			(type solid)
		)
		(fill yes)
		(layer "In11.Cu")
		(net "PVCCFA_EHV_CPU1")
	)
	(gr_poly
		(pts
			(xy 409.22956 -156.088588) (xy 409.22956 -148.760688) (xy 408.62758 -148.158708) (xy 400.4818 -148.158708)
			(xy 399.31594 -149.324568) (xy 399.31594 -150.339552) (xy 399.642589 -150.339552) (xy 399.646611 -150.253832)
			(xy 399.658642 -150.168864) (xy 399.678578 -150.085397) (xy 399.706241 -150.004163) (xy 399.74139 -149.925877)
			(xy 399.783716 -149.851226) (xy 399.832845 -149.780867) (xy 399.888348 -149.715417) (xy 399.949735 -149.655453)
			(xy 400.016468 -149.6015) (xy 400.08796 -149.554033) (xy 400.163582 -149.513469) (xy 400.242671 -149.480165)
			(xy 400.324531 -149.454413) (xy 400.408442 -149.43644) (xy 400.493668 -149.426404) (xy 400.57946 -149.424392)
			(xy 400.665062 -149.430423) (xy 400.749724 -149.444443) (xy 400.832701 -149.466329) (xy 400.913264 -149.49589)
			(xy 400.990704 -149.532864) (xy 401.064343 -149.576928) (xy 401.133531 -149.627694) (xy 401.197662 -149.684715)
			(xy 401.256171 -149.747491) (xy 401.308544 -149.815471) (xy 401.354322 -149.888056) (xy 401.393102 -149.964608)
			(xy 401.424543 -150.044456) (xy 401.448369 -150.126897) (xy 401.46437 -150.211207) (xy 401.472405 -150.296645)
			(xy 401.472908 -150.339552) (xy 401.472405 -150.382459) (xy 401.46437 -150.467897) (xy 401.448369 -150.552207)
			(xy 401.424543 -150.634648) (xy 401.393102 -150.714496) (xy 401.354322 -150.791048) (xy 401.308544 -150.863633)
			(xy 401.256171 -150.931613) (xy 401.197662 -150.994389) (xy 401.133531 -151.05141) (xy 401.064343 -151.102176)
			(xy 400.990704 -151.14624) (xy 400.913264 -151.183214) (xy 400.832701 -151.212775) (xy 400.749724 -151.234661)
			(xy 400.665062 -151.248681) (xy 400.57946 -151.254712) (xy 400.493668 -151.2527) (xy 400.408442 -151.242664)
			(xy 400.324531 -151.224691) (xy 400.242671 -151.198939) (xy 400.163582 -151.165635) (xy 400.08796 -151.125071)
			(xy 400.016468 -151.077604) (xy 399.949735 -151.023651) (xy 399.888348 -150.963687) (xy 399.832845 -150.898237)
			(xy 399.783716 -150.827878) (xy 399.74139 -150.753227) (xy 399.706241 -150.674941) (xy 399.678578 -150.593707)
			(xy 399.658642 -150.51024) (xy 399.646611 -150.425272) (xy 399.642589 -150.339552) (xy 399.31594 -150.339552)
			(xy 399.31594 -152.381896) (xy 399.668996 -152.381896) (xy 399.668996 -152.2972) (xy 399.677047 -152.212886)
			(xy 399.693076 -152.12972) (xy 399.716937 -152.048453) (xy 399.748416 -151.969823) (xy 399.787227 -151.894542)
			(xy 399.833017 -151.82329) (xy 399.885373 -151.756714) (xy 399.943821 -151.695416) (xy 400.007831 -151.639951)
			(xy 400.076823 -151.590822) (xy 400.150173 -151.548473) (xy 400.227216 -151.513289) (xy 400.307255 -151.485587)
			(xy 400.389564 -151.465619) (xy 400.473399 -151.453566) (xy 400.558 -151.449536) (xy 400.642601 -151.453566)
			(xy 400.726436 -151.465619) (xy 400.808745 -151.485587) (xy 400.888784 -151.513289) (xy 400.965827 -151.548473)
			(xy 401.039177 -151.590822) (xy 401.108169 -151.639951) (xy 401.172179 -151.695416) (xy 401.230627 -151.756714)
			(xy 401.282983 -151.82329) (xy 401.328773 -151.894542) (xy 401.367584 -151.969823) (xy 401.399063 -152.048453)
			(xy 401.422924 -152.12972) (xy 401.438953 -152.212886) (xy 401.447004 -152.2972) (xy 401.447508 -152.339548)
			(xy 401.447004 -152.381896) (xy 401.438953 -152.46621) (xy 401.422924 -152.549376) (xy 401.399063 -152.630643)
			(xy 401.367584 -152.709273) (xy 401.328773 -152.784554) (xy 401.282983 -152.855806) (xy 401.230627 -152.922382)
			(xy 401.172179 -152.98368) (xy 401.108169 -153.039145) (xy 401.039177 -153.088274) (xy 400.965827 -153.130623)
			(xy 400.888784 -153.165807) (xy 400.808745 -153.193509) (xy 400.726436 -153.213477) (xy 400.642601 -153.22553)
			(xy 400.558 -153.229561) (xy 400.473399 -153.22553) (xy 400.389564 -153.213477) (xy 400.307255 -153.193509)
			(xy 400.227216 -153.165807) (xy 400.150173 -153.130623) (xy 400.076823 -153.088274) (xy 400.007831 -153.039145)
			(xy 399.943821 -152.98368) (xy 399.885373 -152.922382) (xy 399.833017 -152.855806) (xy 399.787227 -152.784554)
			(xy 399.748416 -152.709273) (xy 399.716937 -152.630643) (xy 399.693076 -152.549376) (xy 399.677047 -152.46621)
			(xy 399.668996 -152.381896) (xy 399.31594 -152.381896) (xy 399.31594 -156.131768) (xy 399.515838 -156.331666)
			(xy 399.526776 -156.341811) (xy 399.553089 -156.355838) (xy 399.582331 -156.361675) (xy 399.612012 -156.358822)
			(xy 399.639608 -156.347525) (xy 399.662768 -156.328743) (xy 399.679521 -156.304076) (xy 399.684494 -156.29001)
			(xy 399.697296 -156.250582) (xy 399.729071 -156.174009) (xy 399.76764 -156.100624) (xy 399.812689 -156.031028)
			(xy 399.863847 -155.965791) (xy 399.920696 -155.905449) (xy 399.98277 -155.850495) (xy 400.049559 -155.801381)
			(xy 400.120516 -155.758509) (xy 400.19506 -155.722229) (xy 400.27258 -155.692841) (xy 400.35244 -155.670583)
			(xy 400.433985 -155.65564) (xy 400.516548 -155.648133) (xy 400.558 -155.647644) (xy 400.601441 -155.648157)
			(xy 400.687931 -155.656394) (xy 400.773251 -155.672794) (xy 400.856631 -155.697208) (xy 400.937322 -155.729418)
			(xy 401.014595 -155.769133) (xy 401.087755 -155.815995) (xy 401.156142 -155.869581) (xy 401.219141 -155.92941)
			(xy 401.276185 -155.994943) (xy 401.326758 -156.065588) (xy 401.370406 -156.14071) (xy 401.406735 -156.219631)
			(xy 401.435418 -156.301641) (xy 401.456197 -156.386001) (xy 401.468885 -156.471952) (xy 401.471638 -156.515308)
			(xy 401.474178 -156.563568) (xy 408.75458 -156.563568)
		)
		(stroke
			(width 0)
			(type solid)
		)
		(fill yes)
		(layer "In11.Cu")
		(net "PVCCFA_EHV_CPU0")
	)
	(gr_poly
		(pts
			(xy 198.43496 -113.538762) (xy 198.434485 -113.5241) (xy 198.426171 -113.495981) (xy 198.41021 -113.471384)
			(xy 198.387918 -113.452334) (xy 198.361132 -113.440404) (xy 198.332061 -113.436575) (xy 198.3031 -113.441165)
			(xy 198.289672 -113.447068) (xy 198.263848 -113.458844) (xy 198.209585 -113.475481) (xy 198.153458 -113.483899)
			(xy 198.12508 -113.484406) (xy 198.09783 -113.483919) (xy 198.043885 -113.47616) (xy 197.991592 -113.460803)
			(xy 197.942018 -113.438161) (xy 197.89617 -113.408694) (xy 197.854983 -113.373003) (xy 197.819294 -113.331814)
			(xy 197.789829 -113.285964) (xy 197.76719 -113.236389) (xy 197.751836 -113.184096) (xy 197.74408 -113.13015)
			(xy 197.74408 -113.07565) (xy 197.751836 -113.021704) (xy 197.76719 -112.969411) (xy 197.789829 -112.919836)
			(xy 197.819294 -112.873986) (xy 197.854983 -112.832797) (xy 197.89617 -112.797106) (xy 197.942018 -112.767639)
			(xy 197.991592 -112.744997) (xy 198.043885 -112.72964) (xy 198.09783 -112.721881) (xy 198.12508 -112.72139)
			(xy 198.153458 -112.72191) (xy 198.209586 -112.730317) (xy 198.26385 -112.746949) (xy 198.289672 -112.758728)
			(xy 198.303113 -112.7646) (xy 198.332072 -112.769183) (xy 198.361141 -112.765354) (xy 198.387926 -112.75343)
			(xy 198.410222 -112.73439) (xy 198.426195 -112.709804) (xy 198.43453 -112.681694) (xy 198.43496 -112.667034)
			(xy 198.43496 -112.560862) (xy 198.434485 -112.5462) (xy 198.426171 -112.518081) (xy 198.41021 -112.493484)
			(xy 198.387918 -112.474434) (xy 198.361132 -112.462504) (xy 198.332061 -112.458675) (xy 198.3031 -112.463265)
			(xy 198.289672 -112.469168) (xy 198.263848 -112.480944) (xy 198.209585 -112.497581) (xy 198.153458 -112.505999)
			(xy 198.12508 -112.506506) (xy 198.09783 -112.506019) (xy 198.043885 -112.49826) (xy 197.991592 -112.482903)
			(xy 197.942018 -112.460261) (xy 197.89617 -112.430794) (xy 197.854983 -112.395103) (xy 197.819294 -112.353914)
			(xy 197.789829 -112.308064) (xy 197.76719 -112.258489) (xy 197.751836 -112.206196) (xy 197.74408 -112.15225)
			(xy 197.74408 -112.09775) (xy 197.751836 -112.043804) (xy 197.76719 -111.991511) (xy 197.789829 -111.941936)
			(xy 197.819294 -111.896086) (xy 197.854983 -111.854897) (xy 197.89617 -111.819206) (xy 197.942018 -111.789739)
			(xy 197.991592 -111.767097) (xy 198.043885 -111.75174) (xy 198.09783 -111.743981) (xy 198.12508 -111.74349)
			(xy 198.153458 -111.74401) (xy 198.209586 -111.752417) (xy 198.26385 -111.769049) (xy 198.289672 -111.780828)
			(xy 198.303113 -111.7867) (xy 198.332072 -111.791283) (xy 198.361141 -111.787454) (xy 198.387926 -111.77553)
			(xy 198.410222 -111.75649) (xy 198.426195 -111.731904) (xy 198.43453 -111.703794) (xy 198.43496 -111.689134)
			(xy 198.43496 -110.922308) (xy 193.381376 -110.922308) (xy 193.367067 -110.922795) (xy 193.339573 -110.930735)
			(xy 193.315358 -110.945985) (xy 193.296319 -110.967351) (xy 193.283949 -110.993157) (xy 193.279219 -111.021381)
			(xy 193.282497 -111.04981) (xy 193.293529 -111.076216) (xy 193.302128 -111.087662) (xy 193.316963 -111.106715)
			(xy 193.341899 -111.148068) (xy 193.361012 -111.192414) (xy 193.373951 -111.238937) (xy 193.380479 -111.286783)
			(xy 193.380868 -111.310928) (xy 193.38035 -111.338136) (xy 193.372067 -111.391917) (xy 193.355696 -111.443812)
			(xy 193.331621 -111.492611) (xy 193.3004 -111.537179) (xy 193.262762 -111.576478) (xy 193.219583 -111.609593)
			(xy 193.195956 -111.623094) (xy 193.16954 -111.637572) (xy 193.16954 -112.048544) (xy 193.213228 -112.05464)
			(xy 193.240149 -112.058967) (xy 193.292471 -112.074307) (xy 193.342077 -112.09694) (xy 193.387955 -112.126404)
			(xy 193.429171 -112.1621) (xy 193.464887 -112.203299) (xy 193.494373 -112.249164) (xy 193.517029 -112.298758)
			(xy 193.532395 -112.351073) (xy 193.540156 -112.405043) (xy 193.540155 -112.459568) (xy 193.532392 -112.513537)
			(xy 193.517025 -112.565852) (xy 193.494367 -112.615446) (xy 193.46488 -112.661309) (xy 193.429164 -112.702508)
			(xy 193.387946 -112.738202) (xy 193.342067 -112.767665) (xy 193.292461 -112.790297) (xy 193.240138 -112.805636)
			(xy 193.213228 -112.810036) (xy 193.16954 -112.816132) (xy 193.16954 -113.514632) (xy 196.46341 -113.514632)
			(xy 196.467481 -113.45901) (xy 196.479607 -113.404573) (xy 196.49953 -113.352482) (xy 196.526826 -113.303847)
			(xy 196.560912 -113.259704) (xy 196.601061 -113.220995) (xy 196.646419 -113.188544) (xy 196.696019 -113.163043)
			(xy 196.748803 -113.145036) (xy 196.803646 -113.134906) (xy 196.85938 -113.132869) (xy 196.914817 -113.138969)
			(xy 196.968774 -113.153075) (xy 197.020103 -113.174887) (xy 197.067709 -113.203941) (xy 197.110577 -113.239616)
			(xy 197.147794 -113.281153) (xy 197.178567 -113.327666) (xy 197.202239 -113.378163) (xy 197.218307 -113.43157)
			(xy 197.226427 -113.486746) (xy 197.226936 -113.514632) (xy 197.226427 -113.542518) (xy 197.218307 -113.597694)
			(xy 197.202239 -113.651101) (xy 197.178567 -113.701598) (xy 197.147794 -113.748111) (xy 197.110577 -113.789648)
			(xy 197.067709 -113.825323) (xy 197.020103 -113.854377) (xy 196.968774 -113.876189) (xy 196.914817 -113.890295)
			(xy 196.85938 -113.896395) (xy 196.803646 -113.894358) (xy 196.748803 -113.884228) (xy 196.696019 -113.866221)
			(xy 196.646419 -113.84072) (xy 196.601061 -113.808269) (xy 196.560912 -113.76956) (xy 196.526826 -113.725417)
			(xy 196.49953 -113.676782) (xy 196.479607 -113.624691) (xy 196.467481 -113.570254) (xy 196.46341 -113.514632)
			(xy 193.16954 -113.514632) (xy 193.16954 -114.303048) (xy 198.43496 -114.303048)
		)
		(stroke
			(width 0)
			(type solid)
		)
		(fill yes)
		(layer "In11.Cu")
		(net "GND")
	)
	(gr_poly
		(pts
			(xy 244.863112 -103.31577) (xy 244.878187 -103.315212) (xy 244.907019 -103.306395) (xy 244.932032 -103.289559)
			(xy 244.951053 -103.266165) (xy 244.962432 -103.238244) (xy 244.965182 -103.208219) (xy 244.96268 -103.193342)
			(xy 244.95891 -103.174131) (xy 244.954838 -103.135193) (xy 244.954552 -103.115618) (xy 244.955038 -103.088367)
			(xy 244.962794 -103.034419) (xy 244.978149 -102.982124) (xy 245.000791 -102.932547) (xy 245.030257 -102.886697)
			(xy 245.065948 -102.845506) (xy 245.107139 -102.809815) (xy 245.152989 -102.780349) (xy 245.202566 -102.757707)
			(xy 245.254861 -102.742352) (xy 245.308809 -102.734596) (xy 245.363311 -102.734596) (xy 245.417259 -102.742352)
			(xy 245.469554 -102.757707) (xy 245.519131 -102.780349) (xy 245.564981 -102.809815) (xy 245.606172 -102.845506)
			(xy 245.641863 -102.886697) (xy 245.671329 -102.932547) (xy 245.693971 -102.982124) (xy 245.709326 -103.034419)
			(xy 245.717082 -103.088367) (xy 245.717568 -103.115618) (xy 245.717302 -103.135194) (xy 245.713228 -103.174134)
			(xy 245.70944 -103.193342) (xy 245.706876 -103.20822) (xy 245.709579 -103.238273) (xy 245.720949 -103.266224)
			(xy 245.739992 -103.28963) (xy 245.765045 -103.306448) (xy 245.79392 -103.315209) (xy 245.809008 -103.31577)
			(xy 251.776484 -103.31577) (xy 251.778516 -103.315516) (xy 251.807726 -103.3145) (xy 251.836936 -103.315516)
			(xy 251.838968 -103.31577) (xy 252.260608 -103.31577) (xy 252.981206 -102.595172) (xy 252.981206 -102.195122)
			(xy 252.687582 -101.901498) (xy 249.512074 -101.901498) (xy 249.458734 -101.954838) (xy 247.644158 -101.954838)
			(xy 244.57533 -98.88601) (xy 241.640106 -98.88601) (xy 241.133122 -99.392994) (xy 241.133122 -100.113592)
			(xy 241.306604 -100.287074) (xy 242.56568 -100.287074) (xy 242.569751 -100.231452) (xy 242.581877 -100.177015)
			(xy 242.6018 -100.124924) (xy 242.629096 -100.076289) (xy 242.663182 -100.032146) (xy 242.703331 -99.993437)
			(xy 242.748689 -99.960986) (xy 242.798289 -99.935485) (xy 242.851073 -99.917478) (xy 242.905916 -99.907348)
			(xy 242.96165 -99.905311) (xy 243.017087 -99.911411) (xy 243.071044 -99.925517) (xy 243.122373 -99.947329)
			(xy 243.169979 -99.976383) (xy 243.212847 -100.012058) (xy 243.250064 -100.053595) (xy 243.280837 -100.100108)
			(xy 243.293588 -100.127308) (xy 244.437406 -100.127308) (xy 244.441477 -100.071686) (xy 244.453603 -100.017249)
			(xy 244.473526 -99.965158) (xy 244.500822 -99.916523) (xy 244.534908 -99.87238) (xy 244.575057 -99.833671)
			(xy 244.620415 -99.80122) (xy 244.670015 -99.775719) (xy 244.722799 -99.757712) (xy 244.777642 -99.747582)
			(xy 244.833376 -99.745545) (xy 244.888813 -99.751645) (xy 244.94277 -99.765751) (xy 244.994099 -99.787563)
			(xy 245.041705 -99.816617) (xy 245.084573 -99.852292) (xy 245.12179 -99.893829) (xy 245.152563 -99.940342)
			(xy 245.176235 -99.990839) (xy 245.192303 -100.044246) (xy 245.200423 -100.099422) (xy 245.200932 -100.127308)
			(xy 245.200423 -100.155194) (xy 245.192303 -100.21037) (xy 245.176235 -100.263777) (xy 245.152563 -100.314274)
			(xy 245.12179 -100.360787) (xy 245.084573 -100.402324) (xy 245.041705 -100.437999) (xy 244.994099 -100.467053)
			(xy 244.94277 -100.488865) (xy 244.888813 -100.502971) (xy 244.833376 -100.509071) (xy 244.777642 -100.507034)
			(xy 244.722799 -100.496904) (xy 244.670015 -100.478897) (xy 244.620415 -100.453396) (xy 244.575057 -100.420945)
			(xy 244.534908 -100.382236) (xy 244.500822 -100.338093) (xy 244.473526 -100.289458) (xy 244.453603 -100.237367)
			(xy 244.441477 -100.18293) (xy 244.437406 -100.127308) (xy 243.293588 -100.127308) (xy 243.304509 -100.150605)
			(xy 243.320577 -100.204012) (xy 243.328697 -100.259188) (xy 243.329206 -100.287074) (xy 243.328697 -100.31496)
			(xy 243.320577 -100.370136) (xy 243.304509 -100.423543) (xy 243.280837 -100.47404) (xy 243.250064 -100.520553)
			(xy 243.212847 -100.56209) (xy 243.169979 -100.597765) (xy 243.122373 -100.626819) (xy 243.071044 -100.648631)
			(xy 243.017087 -100.662737) (xy 242.96165 -100.668837) (xy 242.905916 -100.6668) (xy 242.851073 -100.65667)
			(xy 242.798289 -100.638663) (xy 242.748689 -100.613162) (xy 242.703331 -100.580711) (xy 242.663182 -100.542002)
			(xy 242.629096 -100.497859) (xy 242.6018 -100.449224) (xy 242.581877 -100.397133) (xy 242.569751 -100.342696)
			(xy 242.56568 -100.287074) (xy 241.306604 -100.287074) (xy 242.188238 -101.168708) (xy 244.437406 -101.168708)
			(xy 244.441477 -101.113086) (xy 244.453603 -101.058649) (xy 244.473526 -101.006558) (xy 244.500822 -100.957923)
			(xy 244.534908 -100.91378) (xy 244.575057 -100.875071) (xy 244.620415 -100.84262) (xy 244.670015 -100.817119)
			(xy 244.722799 -100.799112) (xy 244.777642 -100.788982) (xy 244.833376 -100.786945) (xy 244.888813 -100.793045)
			(xy 244.94277 -100.807151) (xy 244.994099 -100.828963) (xy 245.041705 -100.858017) (xy 245.084573 -100.893692)
			(xy 245.12179 -100.935229) (xy 245.152563 -100.981742) (xy 245.176235 -101.032239) (xy 245.192303 -101.085646)
			(xy 245.200423 -101.140822) (xy 245.200932 -101.168708) (xy 245.200423 -101.196594) (xy 245.192303 -101.25177)
			(xy 245.176235 -101.305177) (xy 245.152563 -101.355674) (xy 245.12179 -101.402187) (xy 245.084573 -101.443724)
			(xy 245.041705 -101.479399) (xy 244.994099 -101.508453) (xy 244.94277 -101.530265) (xy 244.888813 -101.544371)
			(xy 244.833376 -101.550471) (xy 244.777642 -101.548434) (xy 244.722799 -101.538304) (xy 244.670015 -101.520297)
			(xy 244.620415 -101.494796) (xy 244.575057 -101.462345) (xy 244.534908 -101.423636) (xy 244.500822 -101.379493)
			(xy 244.473526 -101.330858) (xy 244.453603 -101.278767) (xy 244.441477 -101.22433) (xy 244.437406 -101.168708)
			(xy 242.188238 -101.168708) (xy 244.3353 -103.31577)
		)
		(stroke
			(width 0)
			(type solid)
		)
		(fill yes)
		(layer "In11.Cu")
		(net "P3V3_AUX_CLK_GEN_VDDA25M_CK440")
	)
	(gr_poly
		(pts
			(xy 236.60608 -128.107948) (xy 237.82528 -128.107948) (xy 238.20628 -127.726948) (xy 238.20628 -123.567952)
			(xy 238.182305 -123.553098) (xy 238.138608 -123.517441) (xy 238.100636 -123.475741) (xy 238.069214 -123.428906)
			(xy 238.045028 -123.377957) (xy 238.028604 -123.324003) (xy 238.020301 -123.268219) (xy 238.020298 -123.21182)
			(xy 238.028596 -123.156035) (xy 238.045014 -123.102079) (xy 238.069195 -123.051128) (xy 238.100612 -123.00429)
			(xy 238.13858 -122.962586) (xy 238.182273 -122.926925) (xy 238.20628 -122.912124) (xy 238.20628 -119.827548)
			(xy 237.52048 -119.141748) (xy 235.41228 -119.141748) (xy 234.75188 -119.802148) (xy 234.75188 -124.51842)
			(xy 234.752317 -124.531738) (xy 234.759214 -124.557465) (xy 234.772534 -124.580532) (xy 234.791368 -124.599366)
			(xy 234.814435 -124.612686) (xy 234.840162 -124.619583) (xy 234.85348 -124.62002) (xy 234.853734 -124.62002)
			(xy 234.881647 -124.620475) (xy 234.936859 -124.628722) (xy 234.990223 -124.645117) (xy 235.040542 -124.669291)
			(xy 235.08669 -124.700704) (xy 235.10748 -124.719334) (xy 235.118976 -124.729243) (xy 235.14629 -124.742433)
			(xy 235.176276 -124.747009) (xy 235.206281 -124.742565) (xy 235.233654 -124.729495) (xy 235.245148 -124.719588)
			(xy 235.265892 -124.701253) (xy 235.311781 -124.670282) (xy 235.361744 -124.646436) (xy 235.414683 -124.630236)
			(xy 235.469435 -124.62204) (xy 235.497116 -124.621544) (xy 235.524456 -124.622024) (xy 235.578549 -124.630013)
			(xy 235.630895 -124.645816) (xy 235.680372 -124.669095) (xy 235.725918 -124.699351) (xy 235.746544 -124.717302)
			(xy 235.757995 -124.726927) (xy 235.785039 -124.739674) (xy 235.814616 -124.744048) (xy 235.844193 -124.739674)
			(xy 235.871237 -124.726927) (xy 235.882688 -124.717302) (xy 235.903322 -124.699359) (xy 235.948859 -124.669089)
			(xy 235.998334 -124.645804) (xy 236.050681 -124.630002) (xy 236.104776 -124.622024) (xy 236.132116 -124.621544)
			(xy 236.158011 -124.62199) (xy 236.209303 -124.629166) (xy 236.259106 -124.643377) (xy 236.306461 -124.664349)
			(xy 236.350454 -124.691678) (xy 236.390238 -124.724838) (xy 236.425045 -124.763188) (xy 236.439964 -124.784358)
			(xy 236.448864 -124.796409) (xy 236.472224 -124.815143) (xy 236.50001 -124.826303) (xy 236.529839 -124.828932)
			(xy 236.559149 -124.822803) (xy 236.572552 -124.816108) (xy 236.60005 -124.801882) (xy 236.658591 -124.78174)
			(xy 236.719652 -124.77153) (xy 236.750606 -124.770896) (xy 236.777223 -124.771349) (xy 236.829916 -124.778926)
			(xy 236.880993 -124.793924) (xy 236.929417 -124.81604) (xy 236.974199 -124.844822) (xy 237.01443 -124.879684)
			(xy 237.04929 -124.919917) (xy 237.07807 -124.964701) (xy 237.100183 -125.013125) (xy 237.115179 -125.064204)
			(xy 237.122753 -125.116897) (xy 237.123224 -125.143514) (xy 237.122678 -125.172395) (xy 237.113756 -125.229464)
			(xy 237.096126 -125.284471) (xy 237.070214 -125.336095) (xy 237.053882 -125.359922) (xy 237.045652 -125.372391)
			(xy 237.036106 -125.400686) (xy 237.035135 -125.430532) (xy 237.042822 -125.459388) (xy 237.058513 -125.484795)
			(xy 237.069376 -125.49505) (xy 237.088806 -125.512827) (xy 237.122969 -125.552907) (xy 237.151153 -125.597393)
			(xy 237.172798 -125.645403) (xy 237.187475 -125.69598) (xy 237.19489 -125.748118) (xy 237.19536 -125.77445)
			(xy 237.194911 -125.801071) (xy 237.187341 -125.853773) (xy 237.172348 -125.90486) (xy 237.150236 -125.953294)
			(xy 237.121457 -125.998088) (xy 237.086595 -126.03833) (xy 237.046362 -126.073202) (xy 237.001575 -126.101992)
			(xy 236.953147 -126.124115) (xy 236.902063 -126.139121) (xy 236.849363 -126.146705) (xy 236.822742 -126.147068)
			(xy 236.794363 -126.146532) (xy 236.738261 -126.137921) (xy 236.684112 -126.120907) (xy 236.633168 -126.095882)
			(xy 236.586605 -126.063426) (xy 236.545498 -126.024287) (xy 236.510799 -125.979371) (xy 236.496606 -125.95479)
			(xy 236.489242 -125.942401) (xy 236.468881 -125.92202) (xy 236.443636 -125.908142) (xy 236.415518 -125.901875)
			(xy 236.386769 -125.903716) (xy 236.35968 -125.91352) (xy 236.336411 -125.930505) (xy 236.327188 -125.941582)
			(xy 236.309019 -125.964234) (xy 236.266984 -126.004293) (xy 236.219361 -126.037516) (xy 236.167252 -126.063135)
			(xy 236.111861 -126.080557) (xy 236.054469 -126.089381) (xy 236.025436 -126.089918) (xy 235.998181 -126.089458)
			(xy 235.944226 -126.081705) (xy 235.891923 -126.066352) (xy 235.842338 -126.043712) (xy 235.796479 -126.014245)
			(xy 235.755281 -125.978551) (xy 235.719583 -125.937358) (xy 235.69011 -125.891503) (xy 235.667464 -125.84192)
			(xy 235.652105 -125.789619) (xy 235.644346 -125.735665) (xy 235.643928 -125.70841) (xy 235.644419 -125.680753)
			(xy 235.652402 -125.626017) (xy 235.668204 -125.573007) (xy 235.691491 -125.522833) (xy 235.721778 -125.476547)
			(xy 235.758429 -125.435117) (xy 235.800677 -125.399413) (xy 235.847637 -125.37018) (xy 235.872782 -125.358652)
			(xy 235.881955 -125.354122) (xy 235.89598 -125.339252) (xy 235.903084 -125.320086) (xy 235.902139 -125.299667)
			(xy 235.893295 -125.281239) (xy 235.88599 -125.27407) (xy 235.882688 -125.271022) (xy 235.871237 -125.261397)
			(xy 235.844193 -125.24865) (xy 235.814616 -125.244276) (xy 235.785039 -125.24865) (xy 235.757995 -125.261397)
			(xy 235.746544 -125.271022) (xy 235.725913 -125.288971) (xy 235.680377 -125.31925) (xy 235.630904 -125.342544)
			(xy 235.578555 -125.358354) (xy 235.524458 -125.366338) (xy 235.497116 -125.36678) (xy 235.469257 -125.366261)
			(xy 235.414161 -125.357964) (xy 235.360916 -125.341553) (xy 235.31071 -125.317393) (xy 235.264662 -125.286024)
			(xy 235.243878 -125.267466) (xy 235.232382 -125.257564) (xy 235.205072 -125.244385) (xy 235.175093 -125.23982)
			(xy 235.145097 -125.244272) (xy 235.117737 -125.257347) (xy 235.10621 -125.267212) (xy 235.085434 -125.28559)
			(xy 235.03946 -125.316624) (xy 234.989392 -125.340494) (xy 234.936337 -125.356673) (xy 234.881469 -125.364803)
			(xy 234.853734 -125.365256) (xy 234.85348 -125.365256) (xy 234.840161 -125.365693) (xy 234.814431 -125.37259)
			(xy 234.791361 -125.385908) (xy 234.772523 -125.404742) (xy 234.759199 -125.427809) (xy 234.752296 -125.453537)
			(xy 234.75188 -125.466856) (xy 234.75188 -126.812548) (xy 234.765088 -126.825756) (xy 236.410256 -126.825756)
			(xy 236.414232 -126.77143) (xy 236.426075 -126.718261) (xy 236.445534 -126.667384) (xy 236.472194 -126.619882)
			(xy 236.505485 -126.576768) (xy 236.544699 -126.538961) (xy 236.589001 -126.507266) (xy 236.637444 -126.48236)
			(xy 236.688998 -126.464772) (xy 236.742564 -126.454878) (xy 236.796999 -126.452888) (xy 236.851144 -126.458846)
			(xy 236.903844 -126.472624) (xy 236.953977 -126.493928) (xy 237.000473 -126.522304) (xy 237.042343 -126.557148)
			(xy 237.078692 -126.597717) (xy 237.108748 -126.643146) (xy 237.131869 -126.692467) (xy 237.147562 -126.744629)
			(xy 237.155493 -126.79852) (xy 237.15599 -126.825756) (xy 237.155493 -126.852992) (xy 237.147562 -126.906883)
			(xy 237.131869 -126.959045) (xy 237.108748 -127.008366) (xy 237.078692 -127.053795) (xy 237.042343 -127.094364)
			(xy 237.000473 -127.129208) (xy 236.953977 -127.157584) (xy 236.903844 -127.178888) (xy 236.851144 -127.192666)
			(xy 236.796999 -127.198624) (xy 236.742564 -127.196634) (xy 236.688998 -127.18674) (xy 236.637444 -127.169152)
			(xy 236.589001 -127.144246) (xy 236.544699 -127.112551) (xy 236.505485 -127.074744) (xy 236.472194 -127.03163)
			(xy 236.445534 -126.984128) (xy 236.426075 -126.933251) (xy 236.414232 -126.880082) (xy 236.410256 -126.825756)
			(xy 234.765088 -126.825756) (xy 235.664248 -127.724916) (xy 235.675363 -127.735235) (xy 235.702147 -127.749431)
			(xy 235.731916 -127.755148) (xy 235.762053 -127.751884) (xy 235.789908 -127.739927) (xy 235.813033 -127.720327)
			(xy 235.821728 -127.707898) (xy 235.836831 -127.685106) (xy 235.872522 -127.643688) (xy 235.913759 -127.607787)
			(xy 235.959698 -127.57814) (xy 236.009398 -127.555352) (xy 236.061841 -127.539891) (xy 236.115955 -127.532072)
			(xy 236.143292 -127.531622) (xy 236.170544 -127.532085) (xy 236.224495 -127.539841) (xy 236.276792 -127.555197)
			(xy 236.326371 -127.577839) (xy 236.372223 -127.607307) (xy 236.413414 -127.643001) (xy 236.449106 -127.684195)
			(xy 236.478571 -127.730048) (xy 236.501211 -127.779629) (xy 236.516564 -127.831927) (xy 236.524317 -127.885878)
			(xy 236.5248 -127.91313) (xy 236.524407 -127.938762) (xy 236.517579 -127.989568) (xy 236.503997 -128.038998)
			(xy 236.49432 -128.062736) (xy 236.490256 -128.072134) (xy 236.490256 -128.133348) (xy 236.58068 -128.133348)
		)
		(stroke
			(width 0)
			(type solid)
		)
		(fill yes)
		(layer "In11.Cu")
		(net "P3V3_DB2000_VDDR")
	)
	(gr_poly
		(pts
			(xy 409.455366 -165.563042) (xy 409.464968 -165.552825) (xy 409.478672 -165.528374) (xy 409.485218 -165.501121)
			(xy 409.484116 -165.473114) (xy 409.475447 -165.44646) (xy 409.459864 -165.423162) (xy 409.449524 -165.41369)
			(xy 409.428885 -165.395489) (xy 409.392543 -165.354167) (xy 409.362521 -165.30805) (xy 409.339443 -165.258094)
			(xy 409.323787 -165.20534) (xy 409.315879 -165.150882) (xy 409.315412 -165.123368) (xy 409.315907 -165.095699)
			(xy 409.323905 -165.040942) (xy 409.339729 -164.987914) (xy 409.363046 -164.937729) (xy 409.393368 -164.891437)
			(xy 409.430058 -164.850011) (xy 409.472348 -164.81432) (xy 409.51935 -164.785111) (xy 409.54452 -164.77361)
			(xy 409.575 -164.760402) (xy 409.575 -159.458914) (xy 409.54452 -159.445706) (xy 409.519352 -159.434201)
			(xy 409.472347 -159.404997) (xy 409.430056 -159.369309) (xy 409.393365 -159.327883) (xy 409.363045 -159.281591)
			(xy 409.339732 -159.231404) (xy 409.323915 -159.178375) (xy 409.315927 -159.123617) (xy 409.315412 -159.095948)
			(xy 409.315929 -159.067208) (xy 409.324546 -159.010376) (xy 409.341591 -158.955481) (xy 409.366679 -158.903765)
			(xy 409.399242 -158.856397) (xy 409.418536 -158.83509) (xy 409.428618 -158.823557) (xy 409.441978 -158.796007)
			(xy 409.446577 -158.765735) (xy 409.441999 -158.73546) (xy 409.428658 -158.707901) (xy 409.418536 -158.696406)
			(xy 409.399262 -158.67508) (xy 409.36669 -158.62772) (xy 409.341591 -158.576008) (xy 409.324533 -158.521117)
			(xy 409.315903 -158.464288) (xy 409.315412 -158.435548) (xy 409.315908 -158.40788) (xy 409.323909 -158.353125)
			(xy 409.339734 -158.300099) (xy 409.363053 -158.249916) (xy 409.393376 -158.203627) (xy 409.430067 -158.162203)
			(xy 409.472356 -158.126513) (xy 409.519357 -158.097307) (xy 409.54452 -158.08579) (xy 409.575 -158.072582)
			(xy 409.575 -157.599888) (xy 408.97048 -156.995368) (xy 401.363942 -156.995368) (xy 401.343218 -157.032919)
			(xy 401.295757 -157.104366) (xy 401.241816 -157.171056) (xy 401.181868 -157.232404) (xy 401.11644 -157.28787)
			(xy 401.046107 -157.336966) (xy 400.971487 -157.379263) (xy 400.893234 -157.414388) (xy 400.812036 -157.442032)
			(xy 400.728608 -157.461953) (xy 400.64368 -157.473977) (xy 400.558 -157.477996) (xy 400.47232 -157.473977)
			(xy 400.387392 -157.461953) (xy 400.303964 -157.442032) (xy 400.222766 -157.414388) (xy 400.144513 -157.379263)
			(xy 400.069893 -157.336966) (xy 399.99956 -157.28787) (xy 399.934132 -157.232404) (xy 399.874184 -157.171056)
			(xy 399.820243 -157.104366) (xy 399.772782 -157.032919) (xy 399.752058 -156.995368) (xy 398.36852 -156.995368)
			(xy 397.80718 -157.556708) (xy 397.80718 -158.604896) (xy 399.668996 -158.604896) (xy 399.668996 -158.5202)
			(xy 399.677047 -158.435886) (xy 399.693076 -158.35272) (xy 399.716937 -158.271453) (xy 399.748416 -158.192823)
			(xy 399.787227 -158.117542) (xy 399.833017 -158.04629) (xy 399.885373 -157.979714) (xy 399.943821 -157.918416)
			(xy 400.007831 -157.862951) (xy 400.076823 -157.813822) (xy 400.150173 -157.771473) (xy 400.227216 -157.736289)
			(xy 400.307255 -157.708587) (xy 400.389564 -157.688619) (xy 400.473399 -157.676566) (xy 400.558 -157.672536)
			(xy 400.642601 -157.676566) (xy 400.726436 -157.688619) (xy 400.808745 -157.708587) (xy 400.888784 -157.736289)
			(xy 400.965827 -157.771473) (xy 401.039177 -157.813822) (xy 401.108169 -157.862951) (xy 401.172179 -157.918416)
			(xy 401.230627 -157.979714) (xy 401.282983 -158.04629) (xy 401.328773 -158.117542) (xy 401.367584 -158.192823)
			(xy 401.399063 -158.271453) (xy 401.422924 -158.35272) (xy 401.438953 -158.435886) (xy 401.447004 -158.5202)
			(xy 401.447508 -158.562548) (xy 401.447004 -158.604896) (xy 401.438953 -158.68921) (xy 401.422924 -158.772376)
			(xy 401.399063 -158.853643) (xy 401.367584 -158.932273) (xy 401.328773 -159.007554) (xy 401.282983 -159.078806)
			(xy 401.230627 -159.145382) (xy 401.172179 -159.20668) (xy 401.108169 -159.262145) (xy 401.039177 -159.311274)
			(xy 400.965827 -159.353623) (xy 400.888784 -159.388807) (xy 400.808745 -159.416509) (xy 400.726436 -159.436477)
			(xy 400.642601 -159.44853) (xy 400.558 -159.452561) (xy 400.473399 -159.44853) (xy 400.389564 -159.436477)
			(xy 400.307255 -159.416509) (xy 400.227216 -159.388807) (xy 400.150173 -159.353623) (xy 400.076823 -159.311274)
			(xy 400.007831 -159.262145) (xy 399.943821 -159.20668) (xy 399.885373 -159.145382) (xy 399.833017 -159.078806)
			(xy 399.787227 -159.007554) (xy 399.748416 -158.932273) (xy 399.716937 -158.853643) (xy 399.693076 -158.772376)
			(xy 399.677047 -158.68921) (xy 399.668996 -158.604896) (xy 397.80718 -158.604896) (xy 397.80718 -162.785552)
			(xy 399.642589 -162.785552) (xy 399.646611 -162.699832) (xy 399.658642 -162.614864) (xy 399.678578 -162.531397)
			(xy 399.706241 -162.450163) (xy 399.74139 -162.371877) (xy 399.783716 -162.297226) (xy 399.832845 -162.226867)
			(xy 399.888348 -162.161417) (xy 399.949735 -162.101453) (xy 400.016468 -162.0475) (xy 400.08796 -162.000033)
			(xy 400.163582 -161.959469) (xy 400.242671 -161.926165) (xy 400.324531 -161.900413) (xy 400.408442 -161.88244)
			(xy 400.493668 -161.872404) (xy 400.57946 -161.870392) (xy 400.665062 -161.876423) (xy 400.749724 -161.890443)
			(xy 400.832701 -161.912329) (xy 400.913264 -161.94189) (xy 400.990704 -161.978864) (xy 401.064343 -162.022928)
			(xy 401.133531 -162.073694) (xy 401.197662 -162.130715) (xy 401.256171 -162.193491) (xy 401.308544 -162.261471)
			(xy 401.354322 -162.334056) (xy 401.393102 -162.410608) (xy 401.424543 -162.490456) (xy 401.448369 -162.572897)
			(xy 401.46437 -162.657207) (xy 401.472405 -162.742645) (xy 401.472908 -162.785552) (xy 401.472405 -162.828459)
			(xy 401.46437 -162.913897) (xy 401.448369 -162.998207) (xy 401.424543 -163.080648) (xy 401.393102 -163.160496)
			(xy 401.354322 -163.237048) (xy 401.308544 -163.309633) (xy 401.256171 -163.377613) (xy 401.197662 -163.440389)
			(xy 401.133531 -163.49741) (xy 401.064343 -163.548176) (xy 400.990704 -163.59224) (xy 400.913264 -163.629214)
			(xy 400.832701 -163.658775) (xy 400.749724 -163.680661) (xy 400.665062 -163.694681) (xy 400.57946 -163.700712)
			(xy 400.493668 -163.6987) (xy 400.408442 -163.688664) (xy 400.324531 -163.670691) (xy 400.242671 -163.644939)
			(xy 400.163582 -163.611635) (xy 400.08796 -163.571071) (xy 400.016468 -163.523604) (xy 399.949735 -163.469651)
			(xy 399.888348 -163.409687) (xy 399.832845 -163.344237) (xy 399.783716 -163.273878) (xy 399.74139 -163.199227)
			(xy 399.706241 -163.120941) (xy 399.678578 -163.039707) (xy 399.658642 -162.95624) (xy 399.646611 -162.871272)
			(xy 399.642589 -162.785552) (xy 397.80718 -162.785552) (xy 397.80718 -164.827896) (xy 399.668996 -164.827896)
			(xy 399.668996 -164.7432) (xy 399.677047 -164.658886) (xy 399.693076 -164.57572) (xy 399.716937 -164.494453)
			(xy 399.748416 -164.415823) (xy 399.787227 -164.340542) (xy 399.833017 -164.26929) (xy 399.885373 -164.202714)
			(xy 399.943821 -164.141416) (xy 400.007831 -164.085951) (xy 400.076823 -164.036822) (xy 400.150173 -163.994473)
			(xy 400.227216 -163.959289) (xy 400.307255 -163.931587) (xy 400.389564 -163.911619) (xy 400.473399 -163.899566)
			(xy 400.558 -163.895536) (xy 400.642601 -163.899566) (xy 400.726436 -163.911619) (xy 400.808745 -163.931587)
			(xy 400.888784 -163.959289) (xy 400.965827 -163.994473) (xy 401.039177 -164.036822) (xy 401.108169 -164.085951)
			(xy 401.172179 -164.141416) (xy 401.230627 -164.202714) (xy 401.282983 -164.26929) (xy 401.328773 -164.340542)
			(xy 401.367584 -164.415823) (xy 401.399063 -164.494453) (xy 401.422924 -164.57572) (xy 401.438953 -164.658886)
			(xy 401.447004 -164.7432) (xy 401.447508 -164.785548) (xy 401.447004 -164.827896) (xy 401.438953 -164.91221)
			(xy 401.422924 -164.995376) (xy 401.399063 -165.076643) (xy 401.367584 -165.155273) (xy 401.328773 -165.230554)
			(xy 401.282983 -165.301806) (xy 401.230627 -165.368382) (xy 401.172179 -165.42968) (xy 401.108169 -165.485145)
			(xy 401.039177 -165.534274) (xy 400.965827 -165.576623) (xy 400.888784 -165.611807) (xy 400.808745 -165.639509)
			(xy 400.726436 -165.659477) (xy 400.642601 -165.67153) (xy 400.558 -165.675561) (xy 400.473399 -165.67153)
			(xy 400.389564 -165.659477) (xy 400.307255 -165.639509) (xy 400.227216 -165.611807) (xy 400.150173 -165.576623)
			(xy 400.076823 -165.534274) (xy 400.007831 -165.485145) (xy 399.943821 -165.42968) (xy 399.885373 -165.368382)
			(xy 399.833017 -165.301806) (xy 399.787227 -165.230554) (xy 399.748416 -165.155273) (xy 399.716937 -165.076643)
			(xy 399.693076 -164.995376) (xy 399.677047 -164.91221) (xy 399.668996 -164.827896) (xy 397.80718 -164.827896)
			(xy 397.80718 -164.965888) (xy 399.01622 -166.174928) (xy 408.84348 -166.174928)
		)
		(stroke
			(width 0)
			(type solid)
		)
		(fill yes)
		(layer "In11.Cu")
		(net "PVCCD_HV_CPU0")
	)
	(gr_poly
		(pts
			(xy 70.037706 -172.687488) (xy 70.051862 -172.687036) (xy 70.079091 -172.67928) (xy 70.103139 -172.664338)
			(xy 70.122154 -172.643363) (xy 70.134671 -172.617969) (xy 70.139727 -172.590112) (xy 70.136932 -172.561939)
			(xy 70.126501 -172.535619) (xy 70.109237 -172.51318) (xy 70.098158 -172.504354) (xy 70.064249 -172.478525)
			(xy 70.000873 -172.421512) (xy 69.943073 -172.358852) (xy 69.891349 -172.29109) (xy 69.84615 -172.218813)
			(xy 69.807868 -172.142645) (xy 69.776833 -172.063248) (xy 69.753316 -171.98131) (xy 69.737519 -171.89754)
			(xy 69.72958 -171.812663) (xy 69.729096 -171.77004) (xy 69.729584 -171.727764) (xy 69.737386 -171.643572)
			(xy 69.752922 -171.560459) (xy 69.776061 -171.479135) (xy 69.806605 -171.400292) (xy 69.844293 -171.324604)
			(xy 69.888804 -171.252716) (xy 69.939758 -171.185242) (xy 69.996721 -171.122757) (xy 70.059206 -171.065794)
			(xy 70.12668 -171.01484) (xy 70.198568 -170.970329) (xy 70.274256 -170.932641) (xy 70.353099 -170.902097)
			(xy 70.434423 -170.878958) (xy 70.517536 -170.863422) (xy 70.601728 -170.85562) (xy 70.68628 -170.85562)
			(xy 70.770472 -170.863422) (xy 70.853585 -170.878958) (xy 70.934909 -170.902097) (xy 71.013752 -170.932641)
			(xy 71.08944 -170.970329) (xy 71.161328 -171.01484) (xy 71.228802 -171.065794) (xy 71.291287 -171.122757)
			(xy 71.34825 -171.185242) (xy 71.399204 -171.252716) (xy 71.443715 -171.324604) (xy 71.481403 -171.400292)
			(xy 71.511947 -171.479135) (xy 71.535086 -171.560459) (xy 71.550622 -171.643572) (xy 71.558424 -171.727764)
			(xy 71.558912 -171.77004) (xy 71.558425 -171.812664) (xy 71.550501 -171.897544) (xy 71.534715 -171.981318)
			(xy 71.511204 -172.063261) (xy 71.480172 -172.142661) (xy 71.441889 -172.21883) (xy 71.396686 -172.291107)
			(xy 71.344956 -172.358867) (xy 71.287147 -172.42152) (xy 71.22376 -172.478524) (xy 71.18985 -172.504354)
			(xy 71.17877 -172.513158) (xy 71.161557 -172.535608) (xy 71.151167 -172.561919) (xy 71.148395 -172.590072)
			(xy 71.153456 -172.617904) (xy 71.165961 -172.643279) (xy 71.184949 -172.664249) (xy 71.208963 -172.679202)
			(xy 71.236158 -172.686992) (xy 71.250302 -172.687488) (xy 73.30186 -172.687488) (xy 75.946 -170.043348)
			(xy 75.946 -168.906444) (xy 75.95108 -168.884346) (xy 75.95108 -163.167568) (xy 75.08494 -162.301428)
			(xy 75.050396 -162.32378) (xy 75.027134 -162.338272) (xy 74.977336 -162.36116) (xy 74.924776 -162.376688)
			(xy 74.870535 -162.384535) (xy 74.843132 -162.384994) (xy 74.815878 -162.384533) (xy 74.761924 -162.376779)
			(xy 74.709623 -162.361426) (xy 74.66004 -162.338785) (xy 74.614184 -162.309318) (xy 74.572989 -162.273624)
			(xy 74.537293 -162.23243) (xy 74.507823 -162.186576) (xy 74.48518 -162.136993) (xy 74.469824 -162.084693)
			(xy 74.462068 -162.03074) (xy 74.461624 -162.003486) (xy 74.462099 -161.976084) (xy 74.469944 -161.921844)
			(xy 74.485469 -161.869286) (xy 74.508356 -161.81949) (xy 74.522838 -161.796222) (xy 74.54519 -161.761678)
			(xy 74.257408 -161.473896) (xy 74.236326 -161.473642) (xy 74.200691 -161.473145) (xy 74.129868 -161.465171)
			(xy 74.060382 -161.449322) (xy 73.993106 -161.425797) (xy 73.928886 -161.39489) (xy 73.868528 -161.35699)
			(xy 73.81279 -161.312573) (xy 73.787254 -161.287714) (xy 73.335388 -160.835848) (xy 72.17918 -160.835848)
			(xy 70.910704 -162.104324) (xy 68.974716 -162.104324) (xy 67.903852 -161.03346) (xy 63.270638 -161.03346)
			(xy 63.123572 -161.180526) (xy 63.123572 -164.634926) (xy 69.007995 -164.634926) (xy 69.012017 -164.549206)
			(xy 69.024048 -164.464238) (xy 69.043984 -164.380771) (xy 69.071647 -164.299537) (xy 69.106796 -164.221251)
			(xy 69.149122 -164.1466) (xy 69.198251 -164.076241) (xy 69.253754 -164.010791) (xy 69.315141 -163.950827)
			(xy 69.381874 -163.896874) (xy 69.453366 -163.849407) (xy 69.528988 -163.808843) (xy 69.608077 -163.775539)
			(xy 69.689937 -163.749787) (xy 69.773848 -163.731814) (xy 69.859074 -163.721778) (xy 69.944866 -163.719766)
			(xy 70.030468 -163.725797) (xy 70.11513 -163.739817) (xy 70.198107 -163.761703) (xy 70.27867 -163.791264)
			(xy 70.35611 -163.828238) (xy 70.429749 -163.872302) (xy 70.498937 -163.923068) (xy 70.563068 -163.980089)
			(xy 70.621577 -164.042865) (xy 70.67395 -164.110845) (xy 70.719728 -164.18343) (xy 70.758508 -164.259982)
			(xy 70.789949 -164.33983) (xy 70.813775 -164.422271) (xy 70.829776 -164.506581) (xy 70.837811 -164.592019)
			(xy 70.838314 -164.634926) (xy 70.837811 -164.677833) (xy 70.829776 -164.763271) (xy 70.813775 -164.847581)
			(xy 70.789949 -164.930022) (xy 70.758508 -165.00987) (xy 70.719728 -165.086422) (xy 70.67395 -165.159007)
			(xy 70.621577 -165.226987) (xy 70.563068 -165.289763) (xy 70.498937 -165.346784) (xy 70.429749 -165.39755)
			(xy 70.35611 -165.441614) (xy 70.27867 -165.478588) (xy 70.198107 -165.508149) (xy 70.11513 -165.530035)
			(xy 70.030468 -165.544055) (xy 69.944866 -165.550086) (xy 69.859074 -165.548074) (xy 69.773848 -165.538038)
			(xy 69.689937 -165.520065) (xy 69.608077 -165.494313) (xy 69.528988 -165.461009) (xy 69.453366 -165.420445)
			(xy 69.381874 -165.372978) (xy 69.315141 -165.319025) (xy 69.253754 -165.259061) (xy 69.198251 -165.193611)
			(xy 69.149122 -165.123252) (xy 69.106796 -165.048601) (xy 69.071647 -164.970315) (xy 69.043984 -164.889081)
			(xy 69.024048 -164.805614) (xy 69.012017 -164.720646) (xy 69.007995 -164.634926) (xy 63.123572 -164.634926)
			(xy 63.123572 -166.67727) (xy 69.034402 -166.67727) (xy 69.034402 -166.592574) (xy 69.042453 -166.50826)
			(xy 69.058482 -166.425094) (xy 69.082343 -166.343827) (xy 69.113822 -166.265197) (xy 69.152633 -166.189916)
			(xy 69.198423 -166.118664) (xy 69.250779 -166.052088) (xy 69.309227 -165.99079) (xy 69.373237 -165.935325)
			(xy 69.442229 -165.886196) (xy 69.515579 -165.843847) (xy 69.592622 -165.808663) (xy 69.672661 -165.780961)
			(xy 69.75497 -165.760993) (xy 69.838805 -165.74894) (xy 69.923406 -165.74491) (xy 70.008007 -165.74894)
			(xy 70.091842 -165.760993) (xy 70.174151 -165.780961) (xy 70.25419 -165.808663) (xy 70.331233 -165.843847)
			(xy 70.404583 -165.886196) (xy 70.473575 -165.935325) (xy 70.537585 -165.99079) (xy 70.596033 -166.052088)
			(xy 70.648389 -166.118664) (xy 70.694179 -166.189916) (xy 70.73299 -166.265197) (xy 70.764469 -166.343827)
			(xy 70.78833 -166.425094) (xy 70.804359 -166.50826) (xy 70.81241 -166.592574) (xy 70.812914 -166.634922)
			(xy 70.81241 -166.67727) (xy 70.804359 -166.761584) (xy 70.78833 -166.84475) (xy 70.764469 -166.926017)
			(xy 70.73299 -167.004647) (xy 70.694179 -167.079928) (xy 70.648389 -167.15118) (xy 70.596033 -167.217756)
			(xy 70.537585 -167.279054) (xy 70.473575 -167.334519) (xy 70.404583 -167.383648) (xy 70.331233 -167.425997)
			(xy 70.25419 -167.461181) (xy 70.174151 -167.488883) (xy 70.091842 -167.508851) (xy 70.008007 -167.520904)
			(xy 69.923406 -167.524935) (xy 69.838805 -167.520904) (xy 69.75497 -167.508851) (xy 69.672661 -167.488883)
			(xy 69.592622 -167.461181) (xy 69.515579 -167.425997) (xy 69.442229 -167.383648) (xy 69.373237 -167.334519)
			(xy 69.309227 -167.279054) (xy 69.250779 -167.217756) (xy 69.198423 -167.15118) (xy 69.152633 -167.079928)
			(xy 69.113822 -167.004647) (xy 69.082343 -166.926017) (xy 69.058482 -166.84475) (xy 69.042453 -166.761584)
			(xy 69.034402 -166.67727) (xy 63.123572 -166.67727) (xy 63.123572 -169.185844) (xy 63.284608 -169.34688)
			(xy 64.9986 -169.34688) (xy 67.585336 -171.933616) (xy 67.59545 -171.943089) (xy 67.619569 -171.956709)
			(xy 67.646464 -171.963337) (xy 67.67415 -171.962486) (xy 67.700586 -171.954217) (xy 67.723823 -171.939141)
			(xy 67.742148 -171.918369) (xy 67.754208 -171.893433) (xy 67.759114 -171.866171) (xy 67.75831 -171.852336)
			(xy 67.756521 -171.831809) (xy 67.754615 -171.790644) (xy 67.7545 -171.77004) (xy 67.755004 -171.727692)
			(xy 67.763055 -171.643378) (xy 67.779084 -171.560212) (xy 67.802945 -171.478945) (xy 67.834424 -171.400315)
			(xy 67.873235 -171.325034) (xy 67.919025 -171.253782) (xy 67.971381 -171.187206) (xy 68.029829 -171.125908)
			(xy 68.093839 -171.070443) (xy 68.162831 -171.021314) (xy 68.236181 -170.978965) (xy 68.313224 -170.943781)
			(xy 68.393263 -170.916079) (xy 68.475572 -170.896111) (xy 68.559407 -170.884058) (xy 68.644008 -170.880028)
			(xy 68.728609 -170.884058) (xy 68.812444 -170.896111) (xy 68.894753 -170.916079) (xy 68.974792 -170.943781)
			(xy 69.051835 -170.978965) (xy 69.125185 -171.021314) (xy 69.194177 -171.070443) (xy 69.258187 -171.125908)
			(xy 69.316635 -171.187206) (xy 69.368991 -171.253782) (xy 69.414781 -171.325034) (xy 69.453592 -171.400315)
			(xy 69.485071 -171.478945) (xy 69.508932 -171.560212) (xy 69.524961 -171.643378) (xy 69.533012 -171.727692)
			(xy 69.533516 -171.77004) (xy 69.53301 -171.813061) (xy 69.524698 -171.898701) (xy 69.508156 -171.983138)
			(xy 69.483538 -172.065583) (xy 69.451074 -172.145266) (xy 69.411068 -172.221441) (xy 69.363894 -172.293399)
			(xy 69.309992 -172.360464) (xy 69.249866 -172.422012) (xy 69.184078 -172.477467) (xy 69.14896 -172.502322)
			(xy 69.13744 -172.510875) (xy 69.119309 -172.533095) (xy 69.108071 -172.55948) (xy 69.104615 -172.587949)
			(xy 69.109211 -172.616257) (xy 69.121499 -172.64217) (xy 69.140507 -172.663644) (xy 69.164738 -172.678985)
			(xy 69.192279 -172.686982) (xy 69.206618 -172.687488)
		)
		(stroke
			(width 0)
			(type solid)
		)
		(fill yes)
		(layer "In11.Cu")
		(net "PVCCD_HV_CPU1")
	)
	(gr_poly
		(pts
			(xy 0.654812 -17.86255)
			(arc
				(start 0.66675 -17.85493)
				(mid 0.827347 -17.756522)
				(end 0.991362 -17.663922)
			)
			(xy 1.017524 -17.61998)
			(arc
				(start 1.017524 -13.780008)
				(mid 1.305283 -13.085295)
				(end 1.999996 -12.797536)
			)
			(arc
				(start 11.102594 -12.797536)
				(mid 13.236139 -11.913635)
				(end 14.11986 -9.780016)
			)
			(xy 14.11986 -3.945382)
			(arc
				(start 14.10081 -3.90779)
				(mid 13.825764 -3.583504)
				(end 13.726922 -3.16992)
			)
			(arc
				(start 13.726922 -3.16992)
				(mid 13.825371 -2.757062)
				(end 14.09954 -2.433066)
			)
			(xy 14.11986 -2.392934) (xy 14.11986 -1.016) (xy 80.684116 -1.016) (xy 80.684116 -2.39141)
			(arc
				(start 80.704944 -2.43205)
				(mid 81.07796 -3.169158)
				(end 80.704944 -3.906266)
			)
			(xy 80.684116 -3.946906)
			(arc
				(start 80.684116 -9.780016)
				(mid 81.568091 -11.91374)
				(end 83.70189 -12.797536)
			)
			(arc
				(start 124.102622 -12.797536)
				(mid 126.236167 -11.913635)
				(end 127.119888 -9.780016)
			)
			(arc
				(start 127.119888 -9.223756)
				(mid 127.113727 -9.202804)
				(end 127.099314 -9.186418)
			)
			(arc
				(start 127.099314 -9.186418)
				(mid 126.839825 -8.890054)
				(end 126.728982 -8.512048)
			)
			(xy 126.700534 -8.46963) (xy 126.687326 -8.463026)
			(arc
				(start 126.66345 -8.457184)
				(mid 126.627619 -8.471973)
				(end 126.61265 -8.50773)
			)
			(arc
				(start 126.61265 -9.780016)
				(mid 125.877331 -11.555233)
				(end 124.102114 -12.290552)
			)
			(arc
				(start 83.70189 -12.290552)
				(mid 81.926673 -11.555233)
				(end 81.191354 -9.780016)
			)
			(xy 81.191354 -1.28524) (xy 81.19364 -1.28524)
			(arc
				(start 81.19364 -0.999998)
				(mid 81.049612 -0.652282)
				(end 80.701896 -0.508254)
			)
			(arc
				(start 14.10208 -0.508254)
				(mid 13.754364 -0.652282)
				(end 13.610336 -0.999998)
			)
			(xy 13.610336 -1.28524) (xy 13.612622 -1.28524)
			(arc
				(start 13.612622 -9.780016)
				(mid 12.877303 -11.555233)
				(end 11.102086 -12.290552)
			)
			(arc
				(start 1.999996 -12.290552)
				(mid 0.946792 -12.726804)
				(end 0.51054 -13.780008)
			)
			(arc
				(start 0.51054 -17.769332)
				(mid 0.517626 -17.795211)
				(end 0.536956 -17.813782)
			)
			(xy 0.62738 -17.863566)
		)
		(stroke
			(width 0)
			(type solid)
		)
		(fill yes)
		(layer "In11.Cu")
		(net "GND")
	)
	(gr_poly
		(pts
			(xy 71.27748 -161.031428) (xy 71.27748 -147.714208) (xy 70.501002 -146.93773) (xy 70.466025 -146.965507)
			(xy 70.391587 -147.014879) (xy 70.312695 -147.056768) (xy 70.230099 -147.090776) (xy 70.144584 -147.116579)
			(xy 70.056962 -147.133931) (xy 69.968067 -147.142669) (xy 69.923406 -147.143216) (xy 69.881129 -147.142743)
			(xy 69.796934 -147.134942) (xy 69.713819 -147.119405) (xy 69.632492 -147.096266) (xy 69.553647 -147.065722)
			(xy 69.477956 -147.028033) (xy 69.406066 -146.983521) (xy 69.33859 -146.932565) (xy 69.276103 -146.875601)
			(xy 69.219138 -146.813115) (xy 69.168183 -146.745639) (xy 69.12367 -146.673749) (xy 69.08598 -146.598059)
			(xy 69.055436 -146.519214) (xy 69.032296 -146.437887) (xy 69.016759 -146.354772) (xy 69.008957 -146.270577)
			(xy 69.008957 -146.186023) (xy 69.016759 -146.101828) (xy 69.032296 -146.018713) (xy 69.055436 -145.937386)
			(xy 69.08598 -145.858541) (xy 69.12367 -145.782851) (xy 69.168183 -145.710961) (xy 69.219138 -145.643485)
			(xy 69.276103 -145.580999) (xy 69.33859 -145.524035) (xy 69.406066 -145.473079) (xy 69.477956 -145.428567)
			(xy 69.553647 -145.390878) (xy 69.632492 -145.360334) (xy 69.713819 -145.337195) (xy 69.796934 -145.321658)
			(xy 69.881129 -145.313857) (xy 69.923406 -145.3134) (xy 69.942351 -145.313477) (xy 69.980209 -145.315001)
			(xy 69.999098 -145.316448) (xy 70.013097 -145.317152) (xy 70.040595 -145.31177) (xy 70.065598 -145.299123)
			(xy 70.086228 -145.280163) (xy 70.100934 -145.256312) (xy 70.10861 -145.229365) (xy 70.10908 -145.215356)
			(xy 70.10908 -144.490948) (xy 68.382896 -142.764764) (xy 63.241936 -142.764764) (xy 63.123572 -142.883128)
			(xy 63.123572 -148.270652) (xy 69.034402 -148.270652) (xy 69.034402 -148.185956) (xy 69.042453 -148.101642)
			(xy 69.058482 -148.018476) (xy 69.082343 -147.937209) (xy 69.113822 -147.858579) (xy 69.152633 -147.783298)
			(xy 69.198423 -147.712046) (xy 69.250779 -147.64547) (xy 69.309227 -147.584172) (xy 69.373237 -147.528707)
			(xy 69.442229 -147.479578) (xy 69.515579 -147.437229) (xy 69.592622 -147.402045) (xy 69.672661 -147.374343)
			(xy 69.75497 -147.354375) (xy 69.838805 -147.342322) (xy 69.923406 -147.338292) (xy 70.008007 -147.342322)
			(xy 70.091842 -147.354375) (xy 70.174151 -147.374343) (xy 70.25419 -147.402045) (xy 70.331233 -147.437229)
			(xy 70.404583 -147.479578) (xy 70.473575 -147.528707) (xy 70.537585 -147.584172) (xy 70.596033 -147.64547)
			(xy 70.648389 -147.712046) (xy 70.694179 -147.783298) (xy 70.73299 -147.858579) (xy 70.764469 -147.937209)
			(xy 70.78833 -148.018476) (xy 70.804359 -148.101642) (xy 70.81241 -148.185956) (xy 70.812914 -148.228304)
			(xy 70.81241 -148.270652) (xy 70.804359 -148.354966) (xy 70.78833 -148.438132) (xy 70.764469 -148.519399)
			(xy 70.73299 -148.598029) (xy 70.694179 -148.67331) (xy 70.648389 -148.744562) (xy 70.596033 -148.811138)
			(xy 70.537585 -148.872436) (xy 70.473575 -148.927901) (xy 70.404583 -148.97703) (xy 70.331233 -149.019379)
			(xy 70.25419 -149.054563) (xy 70.174151 -149.082265) (xy 70.091842 -149.102233) (xy 70.008007 -149.114286)
			(xy 69.923406 -149.118317) (xy 69.838805 -149.114286) (xy 69.75497 -149.102233) (xy 69.672661 -149.082265)
			(xy 69.592622 -149.054563) (xy 69.515579 -149.019379) (xy 69.442229 -148.97703) (xy 69.373237 -148.927901)
			(xy 69.309227 -148.872436) (xy 69.250779 -148.811138) (xy 69.198423 -148.744562) (xy 69.152633 -148.67331)
			(xy 69.113822 -148.598029) (xy 69.082343 -148.519399) (xy 69.058482 -148.438132) (xy 69.042453 -148.354966)
			(xy 69.034402 -148.270652) (xy 63.123572 -148.270652) (xy 63.123572 -152.364694) (xy 69.007995 -152.364694)
			(xy 69.012017 -152.278974) (xy 69.024048 -152.194006) (xy 69.043984 -152.110539) (xy 69.071647 -152.029305)
			(xy 69.106796 -151.951019) (xy 69.149122 -151.876368) (xy 69.198251 -151.806009) (xy 69.253754 -151.740559)
			(xy 69.315141 -151.680595) (xy 69.381874 -151.626642) (xy 69.453366 -151.579175) (xy 69.528988 -151.538611)
			(xy 69.608077 -151.505307) (xy 69.689937 -151.479555) (xy 69.773848 -151.461582) (xy 69.859074 -151.451546)
			(xy 69.944866 -151.449534) (xy 70.030468 -151.455565) (xy 70.11513 -151.469585) (xy 70.198107 -151.491471)
			(xy 70.27867 -151.521032) (xy 70.35611 -151.558006) (xy 70.429749 -151.60207) (xy 70.498937 -151.652836)
			(xy 70.563068 -151.709857) (xy 70.621577 -151.772633) (xy 70.67395 -151.840613) (xy 70.719728 -151.913198)
			(xy 70.758508 -151.98975) (xy 70.789949 -152.069598) (xy 70.813775 -152.152039) (xy 70.829776 -152.236349)
			(xy 70.837811 -152.321787) (xy 70.838314 -152.364694) (xy 70.837811 -152.407601) (xy 70.829776 -152.493039)
			(xy 70.813775 -152.577349) (xy 70.789949 -152.65979) (xy 70.758508 -152.739638) (xy 70.719728 -152.81619)
			(xy 70.67395 -152.888775) (xy 70.621577 -152.956755) (xy 70.563068 -153.019531) (xy 70.498937 -153.076552)
			(xy 70.429749 -153.127318) (xy 70.35611 -153.171382) (xy 70.27867 -153.208356) (xy 70.198107 -153.237917)
			(xy 70.11513 -153.259803) (xy 70.030468 -153.273823) (xy 69.944866 -153.279854) (xy 69.859074 -153.277842)
			(xy 69.773848 -153.267806) (xy 69.689937 -153.249833) (xy 69.608077 -153.224081) (xy 69.528988 -153.190777)
			(xy 69.453366 -153.150213) (xy 69.381874 -153.102746) (xy 69.315141 -153.048793) (xy 69.253754 -152.988829)
			(xy 69.198251 -152.923379) (xy 69.149122 -152.85302) (xy 69.106796 -152.778369) (xy 69.071647 -152.700083)
			(xy 69.043984 -152.618849) (xy 69.024048 -152.535382) (xy 69.012017 -152.450414) (xy 69.007995 -152.364694)
			(xy 63.123572 -152.364694) (xy 63.123572 -154.407038) (xy 69.034402 -154.407038) (xy 69.034402 -154.322342)
			(xy 69.042453 -154.238028) (xy 69.058482 -154.154862) (xy 69.082343 -154.073595) (xy 69.113822 -153.994965)
			(xy 69.152633 -153.919684) (xy 69.198423 -153.848432) (xy 69.250779 -153.781856) (xy 69.309227 -153.720558)
			(xy 69.373237 -153.665093) (xy 69.442229 -153.615964) (xy 69.515579 -153.573615) (xy 69.592622 -153.538431)
			(xy 69.672661 -153.510729) (xy 69.75497 -153.490761) (xy 69.838805 -153.478708) (xy 69.923406 -153.474678)
			(xy 70.008007 -153.478708) (xy 70.091842 -153.490761) (xy 70.174151 -153.510729) (xy 70.25419 -153.538431)
			(xy 70.331233 -153.573615) (xy 70.404583 -153.615964) (xy 70.473575 -153.665093) (xy 70.537585 -153.720558)
			(xy 70.596033 -153.781856) (xy 70.648389 -153.848432) (xy 70.694179 -153.919684) (xy 70.73299 -153.994965)
			(xy 70.764469 -154.073595) (xy 70.78833 -154.154862) (xy 70.804359 -154.238028) (xy 70.81241 -154.322342)
			(xy 70.812914 -154.36469) (xy 70.81241 -154.407038) (xy 70.804359 -154.491352) (xy 70.78833 -154.574518)
			(xy 70.764469 -154.655785) (xy 70.73299 -154.734415) (xy 70.694179 -154.809696) (xy 70.648389 -154.880948)
			(xy 70.596033 -154.947524) (xy 70.537585 -155.008822) (xy 70.473575 -155.064287) (xy 70.404583 -155.113416)
			(xy 70.331233 -155.155765) (xy 70.25419 -155.190949) (xy 70.174151 -155.218651) (xy 70.091842 -155.238619)
			(xy 70.008007 -155.250672) (xy 69.923406 -155.254703) (xy 69.838805 -155.250672) (xy 69.75497 -155.238619)
			(xy 69.672661 -155.218651) (xy 69.592622 -155.190949) (xy 69.515579 -155.155765) (xy 69.442229 -155.113416)
			(xy 69.373237 -155.064287) (xy 69.309227 -155.008822) (xy 69.250779 -154.947524) (xy 69.198423 -154.880948)
			(xy 69.152633 -154.809696) (xy 69.113822 -154.734415) (xy 69.082343 -154.655785) (xy 69.058482 -154.574518)
			(xy 69.042453 -154.491352) (xy 69.034402 -154.407038) (xy 63.123572 -154.407038) (xy 63.123572 -158.49981)
			(xy 69.007995 -158.49981) (xy 69.012017 -158.41409) (xy 69.024048 -158.329122) (xy 69.043984 -158.245655)
			(xy 69.071647 -158.164421) (xy 69.106796 -158.086135) (xy 69.149122 -158.011484) (xy 69.198251 -157.941125)
			(xy 69.253754 -157.875675) (xy 69.315141 -157.815711) (xy 69.381874 -157.761758) (xy 69.453366 -157.714291)
			(xy 69.528988 -157.673727) (xy 69.608077 -157.640423) (xy 69.689937 -157.614671) (xy 69.773848 -157.596698)
			(xy 69.859074 -157.586662) (xy 69.944866 -157.58465) (xy 70.030468 -157.590681) (xy 70.11513 -157.604701)
			(xy 70.198107 -157.626587) (xy 70.27867 -157.656148) (xy 70.35611 -157.693122) (xy 70.429749 -157.737186)
			(xy 70.498937 -157.787952) (xy 70.563068 -157.844973) (xy 70.621577 -157.907749) (xy 70.67395 -157.975729)
			(xy 70.719728 -158.048314) (xy 70.758508 -158.124866) (xy 70.789949 -158.204714) (xy 70.813775 -158.287155)
			(xy 70.829776 -158.371465) (xy 70.837811 -158.456903) (xy 70.838314 -158.49981) (xy 70.837811 -158.542717)
			(xy 70.829776 -158.628155) (xy 70.813775 -158.712465) (xy 70.789949 -158.794906) (xy 70.758508 -158.874754)
			(xy 70.719728 -158.951306) (xy 70.67395 -159.023891) (xy 70.621577 -159.091871) (xy 70.563068 -159.154647)
			(xy 70.498937 -159.211668) (xy 70.429749 -159.262434) (xy 70.35611 -159.306498) (xy 70.27867 -159.343472)
			(xy 70.198107 -159.373033) (xy 70.11513 -159.394919) (xy 70.030468 -159.408939) (xy 69.944866 -159.41497)
			(xy 69.859074 -159.412958) (xy 69.773848 -159.402922) (xy 69.689937 -159.384949) (xy 69.608077 -159.359197)
			(xy 69.528988 -159.325893) (xy 69.453366 -159.285329) (xy 69.381874 -159.237862) (xy 69.315141 -159.183909)
			(xy 69.253754 -159.123945) (xy 69.198251 -159.058495) (xy 69.149122 -158.988136) (xy 69.106796 -158.913485)
			(xy 69.071647 -158.835199) (xy 69.043984 -158.753965) (xy 69.024048 -158.670498) (xy 69.012017 -158.58553)
			(xy 69.007995 -158.49981) (xy 63.123572 -158.49981) (xy 63.123572 -160.542154) (xy 69.034402 -160.542154)
			(xy 69.034402 -160.457458) (xy 69.042453 -160.373144) (xy 69.058482 -160.289978) (xy 69.082343 -160.208711)
			(xy 69.113822 -160.130081) (xy 69.152633 -160.0548) (xy 69.198423 -159.983548) (xy 69.250779 -159.916972)
			(xy 69.309227 -159.855674) (xy 69.373237 -159.800209) (xy 69.442229 -159.75108) (xy 69.515579 -159.708731)
			(xy 69.592622 -159.673547) (xy 69.672661 -159.645845) (xy 69.75497 -159.625877) (xy 69.838805 -159.613824)
			(xy 69.923406 -159.609794) (xy 70.008007 -159.613824) (xy 70.091842 -159.625877) (xy 70.174151 -159.645845)
			(xy 70.25419 -159.673547) (xy 70.331233 -159.708731) (xy 70.404583 -159.75108) (xy 70.473575 -159.800209)
			(xy 70.537585 -159.855674) (xy 70.596033 -159.916972) (xy 70.648389 -159.983548) (xy 70.694179 -160.0548)
			(xy 70.73299 -160.130081) (xy 70.764469 -160.208711) (xy 70.78833 -160.289978) (xy 70.804359 -160.373144)
			(xy 70.81241 -160.457458) (xy 70.812914 -160.499806) (xy 70.81241 -160.542154) (xy 70.804359 -160.626468)
			(xy 70.78833 -160.709634) (xy 70.764469 -160.790901) (xy 70.73299 -160.869531) (xy 70.694179 -160.944812)
			(xy 70.648389 -161.016064) (xy 70.596033 -161.08264) (xy 70.537585 -161.143938) (xy 70.473575 -161.199403)
			(xy 70.404583 -161.248532) (xy 70.331233 -161.290881) (xy 70.25419 -161.326065) (xy 70.174151 -161.353767)
			(xy 70.091842 -161.373735) (xy 70.008007 -161.385788) (xy 69.923406 -161.389819) (xy 69.838805 -161.385788)
			(xy 69.75497 -161.373735) (xy 69.672661 -161.353767) (xy 69.592622 -161.326065) (xy 69.515579 -161.290881)
			(xy 69.442229 -161.248532) (xy 69.373237 -161.199403) (xy 69.309227 -161.143938) (xy 69.250779 -161.08264)
			(xy 69.198423 -161.016064) (xy 69.152633 -160.944812) (xy 69.113822 -160.869531) (xy 69.082343 -160.790901)
			(xy 69.058482 -160.709634) (xy 69.042453 -160.626468) (xy 69.034402 -160.542154) (xy 63.123572 -160.542154)
			(xy 63.123572 -160.549844) (xy 63.284608 -160.71088) (xy 68.419472 -160.71088) (xy 69.32168 -161.613088)
			(xy 70.69582 -161.613088)
		)
		(stroke
			(width 0)
			(type solid)
		)
		(fill yes)
		(layer "In11.Cu")
		(net "PVCCINFAON_CPU1")
	)
	(gr_poly
		(pts
			(xy 437.936894 -11.683746) (xy 440.603132 -11.683746) (xy 440.617947 -11.683236) (xy 440.646329 -11.674729)
			(xy 440.671079 -11.65844) (xy 440.690117 -11.635737) (xy 440.701845 -11.608527) (xy 440.705276 -11.579097)
			(xy 440.700122 -11.549919) (xy 440.686817 -11.523445) (xy 440.677046 -11.512296) (xy 440.657551 -11.490931)
			(xy 440.624582 -11.443411) (xy 440.599171 -11.391457) (xy 440.581901 -11.336259) (xy 440.573168 -11.279086)
			(xy 440.572652 -11.250168) (xy 440.573126 -11.222799) (xy 440.580955 -11.168624) (xy 440.596447 -11.116124)
			(xy 440.619285 -11.066378) (xy 440.648998 -11.020407) (xy 440.666632 -10.99947) (xy 440.675862 -10.988142)
			(xy 440.688026 -10.961586) (xy 440.69219 -10.932676) (xy 440.688013 -10.903767) (xy 440.675835 -10.877217)
			(xy 440.666632 -10.865866) (xy 440.648991 -10.844935) (xy 440.619266 -10.798968) (xy 440.596426 -10.749221)
			(xy 440.580939 -10.696717) (xy 440.573124 -10.642538) (xy 440.572652 -10.615168) (xy 440.573138 -10.587917)
			(xy 440.580894 -10.533969) (xy 440.596249 -10.481674) (xy 440.618891 -10.432097) (xy 440.648357 -10.386247)
			(xy 440.684048 -10.345056) (xy 440.725239 -10.309365) (xy 440.771089 -10.279899) (xy 440.820666 -10.257257)
			(xy 440.872961 -10.241902) (xy 440.926909 -10.234146) (xy 440.981411 -10.234146) (xy 441.035359 -10.241902)
			(xy 441.087654 -10.257257) (xy 441.137231 -10.279899) (xy 441.183081 -10.309365) (xy 441.224272 -10.345056)
			(xy 441.259963 -10.386247) (xy 441.289429 -10.432097) (xy 441.312071 -10.481674) (xy 441.327426 -10.533969)
			(xy 441.335182 -10.587917) (xy 441.335668 -10.615168) (xy 441.335191 -10.642536) (xy 441.327358 -10.696709)
			(xy 441.311863 -10.749206) (xy 441.289023 -10.79895) (xy 441.259308 -10.844918) (xy 441.241688 -10.865866)
			(xy 441.232448 -10.877194) (xy 441.220263 -10.903754) (xy 441.216083 -10.932676) (xy 441.220249 -10.961599)
			(xy 441.232421 -10.988165) (xy 441.241688 -10.99947) (xy 441.259332 -11.020401) (xy 441.289063 -11.066366)
			(xy 441.311911 -11.116112) (xy 441.327405 -11.168616) (xy 441.335228 -11.222797) (xy 441.335668 -11.250168)
			(xy 441.335135 -11.279086) (xy 441.326407 -11.336261) (xy 441.309145 -11.391461) (xy 441.283746 -11.443422)
			(xy 441.250793 -11.490953) (xy 441.231274 -11.512296) (xy 441.22146 -11.523413) (xy 441.208134 -11.549891)
			(xy 441.202969 -11.579079) (xy 441.2064 -11.608522) (xy 441.218137 -11.635741) (xy 441.237193 -11.658445)
			(xy 441.261965 -11.674724) (xy 441.290367 -11.683208) (xy 441.305188 -11.683746) (xy 452.98487 -11.683746)
			(xy 453.81418 -10.854436) (xy 453.81418 -8.52043) (xy 453.384412 -8.090662) (xy 445.522604 -8.090662)
			(xy 444.724028 -7.292086) (xy 440.365896 -7.292086) (xy 440.35218 -7.320534) (xy 440.339243 -7.345844)
			(xy 440.307008 -7.392659) (xy 440.268185 -7.434174) (xy 440.223633 -7.469471) (xy 440.174338 -7.497769)
			(xy 440.12139 -7.518441) (xy 440.065962 -7.53103) (xy 440.00928 -7.535257) (xy 439.952598 -7.53103)
			(xy 439.89717 -7.518441) (xy 439.844222 -7.497769) (xy 439.794927 -7.469471) (xy 439.750375 -7.434174)
			(xy 439.711552 -7.392659) (xy 439.679317 -7.345844) (xy 439.66638 -7.320534) (xy 439.652664 -7.292086)
			(xy 439.476896 -7.292086) (xy 439.46318 -7.320534) (xy 439.450243 -7.345844) (xy 439.418008 -7.392659)
			(xy 439.379185 -7.434174) (xy 439.334633 -7.469471) (xy 439.285338 -7.497769) (xy 439.23239 -7.518441)
			(xy 439.176962 -7.53103) (xy 439.12028 -7.535257) (xy 439.063598 -7.53103) (xy 439.00817 -7.518441)
			(xy 438.955222 -7.497769) (xy 438.905927 -7.469471) (xy 438.861375 -7.434174) (xy 438.822552 -7.392659)
			(xy 438.790317 -7.345844) (xy 438.77738 -7.320534) (xy 438.763664 -7.292086) (xy 438.587896 -7.292086)
			(xy 438.57418 -7.320534) (xy 438.561243 -7.345844) (xy 438.529008 -7.392659) (xy 438.490185 -7.434174)
			(xy 438.445633 -7.469471) (xy 438.396338 -7.497769) (xy 438.34339 -7.518441) (xy 438.287962 -7.53103)
			(xy 438.23128 -7.535257) (xy 438.174598 -7.53103) (xy 438.11917 -7.518441) (xy 438.066222 -7.497769)
			(xy 438.016927 -7.469471) (xy 437.972375 -7.434174) (xy 437.933552 -7.392659) (xy 437.901317 -7.345844)
			(xy 437.88838 -7.320534) (xy 437.874664 -7.292086) (xy 435.418738 -7.292086) (xy 434.036978 -8.673846)
			(xy 434.036978 -8.727948) (xy 443.539372 -8.727948) (xy 443.539849 -8.700578) (xy 443.547661 -8.646399)
			(xy 443.563147 -8.593895) (xy 443.585987 -8.544148) (xy 443.615711 -8.498181) (xy 443.633352 -8.47725)
			(xy 443.642538 -8.465886) (xy 443.654715 -8.439341) (xy 443.658895 -8.410436) (xy 443.654736 -8.381529)
			(xy 443.642578 -8.354975) (xy 443.633352 -8.343646) (xy 443.615729 -8.322701) (xy 443.586013 -8.276732)
			(xy 443.563173 -8.226988) (xy 443.547678 -8.17449) (xy 443.539847 -8.120316) (xy 443.539372 -8.092948)
			(xy 443.539858 -8.065697) (xy 443.547614 -8.011749) (xy 443.562969 -7.959454) (xy 443.585611 -7.909877)
			(xy 443.615077 -7.864027) (xy 443.650768 -7.822836) (xy 443.691959 -7.787145) (xy 443.737809 -7.757679)
			(xy 443.787386 -7.735037) (xy 443.839681 -7.719682) (xy 443.893629 -7.711926) (xy 443.948131 -7.711926)
			(xy 444.002079 -7.719682) (xy 444.054374 -7.735037) (xy 444.103951 -7.757679) (xy 444.149801 -7.787145)
			(xy 444.190992 -7.822836) (xy 444.226683 -7.864027) (xy 444.256149 -7.909877) (xy 444.278791 -7.959454)
			(xy 444.294146 -8.011749) (xy 444.301902 -8.065697) (xy 444.302388 -8.092948) (xy 444.301894 -8.120317)
			(xy 444.294084 -8.174495) (xy 444.278601 -8.226998) (xy 444.255766 -8.276746) (xy 444.226047 -8.322714)
			(xy 444.208408 -8.343646) (xy 444.199124 -8.354938) (xy 444.186952 -8.381509) (xy 444.182788 -8.410436)
			(xy 444.186972 -8.439361) (xy 444.199164 -8.465923) (xy 444.208408 -8.47725) (xy 444.226038 -8.498189)
			(xy 444.255751 -8.54416) (xy 444.278589 -8.593906) (xy 444.294082 -8.646405) (xy 444.301913 -8.700579)
			(xy 444.302388 -8.727948) (xy 444.301967 -8.753495) (xy 444.295163 -8.804135) (xy 444.281657 -8.853412)
			(xy 444.261691 -8.900443) (xy 444.235622 -8.944387) (xy 444.220092 -8.964676) (xy 444.211 -8.976959)
			(xy 444.199976 -9.005447) (xy 444.197856 -9.035921) (xy 444.204832 -9.065662) (xy 444.220279 -9.092016)
			(xy 444.242821 -9.112632) (xy 444.256414 -9.119616) (xy 444.280602 -9.131507) (xy 444.325621 -9.161142)
			(xy 444.366022 -9.196818) (xy 444.400999 -9.237826) (xy 444.429856 -9.283348) (xy 444.452019 -9.332478)
			(xy 444.467047 -9.384239) (xy 444.47464 -9.437599) (xy 444.475108 -9.464548) (xy 444.475108 -9.467088)
			(xy 444.475521 -9.481546) (xy 444.483456 -9.509348) (xy 444.498865 -9.533811) (xy 444.520512 -9.552975)
			(xy 444.546663 -9.565305) (xy 444.575221 -9.569811) (xy 444.603897 -9.566134) (xy 444.617348 -9.560814)
			(xy 444.641592 -9.550672) (xy 444.692173 -9.536408) (xy 444.744233 -9.529229) (xy 444.77051 -9.52881)
			(xy 444.79776 -9.529289) (xy 444.851705 -9.537046) (xy 444.903997 -9.552402) (xy 444.953572 -9.575043)
			(xy 444.967397 -9.583928) (xy 449.172582 -9.583928) (xy 449.176653 -9.528306) (xy 449.188779 -9.473869)
			(xy 449.208702 -9.421778) (xy 449.235998 -9.373143) (xy 449.270084 -9.329) (xy 449.310233 -9.290291)
			(xy 449.355591 -9.25784) (xy 449.405191 -9.232339) (xy 449.457975 -9.214332) (xy 449.512818 -9.204202)
			(xy 449.568552 -9.202165) (xy 449.623989 -9.208265) (xy 449.677946 -9.222371) (xy 449.729275 -9.244183)
			(xy 449.776881 -9.273237) (xy 449.819749 -9.308912) (xy 449.856966 -9.350449) (xy 449.887739 -9.396962)
			(xy 449.911411 -9.447459) (xy 449.927479 -9.500866) (xy 449.935599 -9.556042) (xy 449.936108 -9.583928)
			(xy 449.935599 -9.611814) (xy 449.927479 -9.66699) (xy 449.911411 -9.720397) (xy 449.887739 -9.770894)
			(xy 449.856966 -9.817407) (xy 449.819749 -9.858944) (xy 449.776881 -9.894619) (xy 449.729275 -9.923673)
			(xy 449.677946 -9.945485) (xy 449.623989 -9.959591) (xy 449.568552 -9.965691) (xy 449.512818 -9.963654)
			(xy 449.457975 -9.953524) (xy 449.405191 -9.935517) (xy 449.355591 -9.910016) (xy 449.310233 -9.877565)
			(xy 449.270084 -9.838856) (xy 449.235998 -9.794713) (xy 449.208702 -9.746078) (xy 449.188779 -9.693987)
			(xy 449.176653 -9.63955) (xy 449.172582 -9.583928) (xy 444.967397 -9.583928) (xy 444.99942 -9.604509)
			(xy 445.040608 -9.6402) (xy 445.076297 -9.681389) (xy 445.105762 -9.727237) (xy 445.128402 -9.776813)
			(xy 445.143756 -9.829105) (xy 445.151512 -9.883051) (xy 445.151512 -9.937551) (xy 445.143756 -9.991496)
			(xy 445.128401 -10.043789) (xy 445.105761 -10.093364) (xy 445.076297 -10.139213) (xy 445.040607 -10.180401)
			(xy 444.999419 -10.216092) (xy 444.953571 -10.245557) (xy 444.903996 -10.268198) (xy 444.851704 -10.283554)
			(xy 444.797759 -10.291311) (xy 444.743259 -10.291312) (xy 444.689313 -10.283558) (xy 444.63702 -10.268205)
			(xy 444.587444 -10.245566) (xy 444.541595 -10.216102) (xy 444.500405 -10.180414) (xy 444.464714 -10.139226)
			(xy 444.435247 -10.093379) (xy 444.412605 -10.043805) (xy 444.397248 -9.991513) (xy 444.38949 -9.937568)
			(xy 444.389002 -9.910318) (xy 444.389002 -9.907778) (xy 444.388602 -9.89332) (xy 444.38066 -9.865521)
			(xy 444.365247 -9.841061) (xy 444.343598 -9.821899) (xy 444.317448 -9.80957) (xy 444.28889 -9.805062)
			(xy 444.260214 -9.808735) (xy 444.246762 -9.814052) (xy 444.222516 -9.824189) (xy 444.171936 -9.838455)
			(xy 444.119877 -9.845636) (xy 444.0936 -9.846056) (xy 444.066351 -9.845522) (xy 444.012407 -9.837767)
			(xy 443.960116 -9.822414) (xy 443.910542 -9.799777) (xy 443.864694 -9.770315) (xy 443.823505 -9.734629)
			(xy 443.787814 -9.693444) (xy 443.758346 -9.6476) (xy 443.735702 -9.598029) (xy 443.720343 -9.54574)
			(xy 443.712581 -9.491797) (xy 443.712092 -9.464548) (xy 443.712515 -9.439001) (xy 443.719319 -9.388362)
			(xy 443.732825 -9.339085) (xy 443.752791 -9.292053) (xy 443.778858 -9.248109) (xy 443.794388 -9.22782)
			(xy 443.803492 -9.215545) (xy 443.814519 -9.187053) (xy 443.816638 -9.156576) (xy 443.809661 -9.126833)
			(xy 443.794209 -9.100478) (xy 443.771662 -9.079862) (xy 443.758066 -9.07288) (xy 443.733895 -9.060955)
			(xy 443.688873 -9.031328) (xy 443.648469 -8.995659) (xy 443.613489 -8.954657) (xy 443.584628 -8.909139)
			(xy 443.562463 -8.860012) (xy 443.547434 -8.808254) (xy 443.53984 -8.754896) (xy 443.539372 -8.727948)
			(xy 434.036978 -8.727948) (xy 434.036978 -9.439148) (xy 435.106062 -9.439148) (xy 435.110133 -9.383526)
			(xy 435.122259 -9.329089) (xy 435.142182 -9.276998) (xy 435.169478 -9.228363) (xy 435.203564 -9.18422)
			(xy 435.243713 -9.145511) (xy 435.289071 -9.11306) (xy 435.338671 -9.087559) (xy 435.391455 -9.069552)
			(xy 435.446298 -9.059422) (xy 435.502032 -9.057385) (xy 435.557469 -9.063485) (xy 435.611426 -9.077591)
			(xy 435.662755 -9.099403) (xy 435.710361 -9.128457) (xy 435.753229 -9.164132) (xy 435.790446 -9.205669)
			(xy 435.821219 -9.252182) (xy 435.844891 -9.302679) (xy 435.860959 -9.356086) (xy 435.869079 -9.411262)
			(xy 435.869588 -9.439148) (xy 435.869079 -9.467034) (xy 435.860959 -9.52221) (xy 435.844891 -9.575617)
			(xy 435.821219 -9.626114) (xy 435.790446 -9.672627) (xy 435.753229 -9.714164) (xy 435.710361 -9.749839)
			(xy 435.662755 -9.778893) (xy 435.611426 -9.800705) (xy 435.557469 -9.814811) (xy 435.502032 -9.820911)
			(xy 435.446298 -9.818874) (xy 435.391455 -9.808744) (xy 435.338671 -9.790737) (xy 435.289071 -9.765236)
			(xy 435.243713 -9.732785) (xy 435.203564 -9.694076) (xy 435.169478 -9.649933) (xy 435.142182 -9.601298)
			(xy 435.122259 -9.549207) (xy 435.110133 -9.49477) (xy 435.106062 -9.439148) (xy 434.036978 -9.439148)
			(xy 434.036978 -12.973558) (xy 434.15966 -13.09624) (xy 436.5244 -13.09624)
		)
		(stroke
			(width 0)
			(type solid)
		)
		(fill yes)
		(layer "In11.Cu")
		(net "P3V3_OCP_SFF")
	)
	(gr_poly
		(pts
			(arc
				(start 256.800096 -36.291012)
				(mid 258.932727 -35.407647)
				(end 259.816092 -33.275016)
			)
			(xy 259.817616 -32.293306) (xy 259.817616 -32.275018)
			(arc
				(start 259.817616 -13.780008)
				(mid 260.105375 -13.085295)
				(end 260.800088 -12.797536)
			)
			(arc
				(start 385.601972 -12.797536)
				(mid 387.735681 -11.913725)
				(end 388.619492 -9.780016)
			)
			(xy 388.619492 -3.928364)
			(arc
				(start 388.614158 -3.917442)
				(mid 388.329377 -3.590886)
				(end 388.226808 -3.16992)
			)
			(arc
				(start 388.226808 -3.16992)
				(mid 388.275543 -2.875216)
				(end 388.416546 -2.611882)
			)
			(arc
				(start 388.416546 -2.611882)
				(mid 388.501545 -2.513276)
				(end 388.59968 -2.427732)
			)
			(xy 388.619492 -2.388108) (xy 388.619492 -1.016) (xy 455.184256 -1.016) (xy 455.184256 -2.375154)
			(arc
				(start 455.205338 -2.416048)
				(mid 455.573689 -3.012402)
				(end 455.41184 -3.69443)
			)
			(arc
				(start 455.41184 -3.69443)
				(mid 455.315091 -3.810755)
				(end 455.200512 -3.909568)
			)
			(xy 455.184256 -3.941318)
			(arc
				(start 455.184256 -9.780016)
				(mid 456.068231 -11.91374)
				(end 458.20203 -12.797536)
			)
			(arc
				(start 469.799924 -12.797536)
				(mid 470.494637 -13.085295)
				(end 470.782396 -13.780008)
			)
			(xy 470.782396 -17.620234)
			(arc
				(start 470.808558 -17.664176)
				(mid 470.972568 -17.756784)
				(end 471.13317 -17.855184)
			)
			(arc
				(start 471.13317 -17.855184)
				(mid 471.158695 -17.863037)
				(end 471.184732 -17.856962)
			)
			(arc
				(start 471.262964 -17.814036)
				(mid 471.282207 -17.795414)
				(end 471.28938 -17.769586)
			)
			(arc
				(start 471.28938 -13.780008)
				(mid 470.853128 -12.726804)
				(end 469.799924 -12.290552)
			)
			(arc
				(start 458.20203 -12.290552)
				(mid 456.426813 -11.555233)
				(end 455.691494 -9.780016)
			)
			(xy 455.691494 -1.30556) (xy 455.69378 -1.30556)
			(arc
				(start 455.69378 -0.999998)
				(mid 455.549752 -0.652282)
				(end 455.202036 -0.508254)
			)
			(arc
				(start 388.601966 -0.508254)
				(mid 388.25425 -0.652282)
				(end 388.110222 -0.999998)
			)
			(xy 388.110222 -1.30556) (xy 388.112508 -1.30556)
			(arc
				(start 388.112508 -9.780016)
				(mid 387.377189 -11.555233)
				(end 385.601972 -12.290552)
			)
			(arc
				(start 260.800088 -12.290552)
				(mid 259.746884 -12.726804)
				(end 259.310632 -13.780008)
			)
			(arc
				(start 259.310632 -32.275018)
				(mid 259.308727 -32.775015)
				(end 259.308092 -33.275016)
			)
			(arc
				(start 259.308092 -33.275016)
				(mid 258.573517 -35.048437)
				(end 256.800096 -35.783012)
			)
			(arc
				(start 225.300032 -35.783012)
				(mid 223.526611 -35.048437)
				(end 222.792036 -33.275016)
			)
			(arc
				(start 222.792036 -33.275016)
				(mid 222.790131 -32.775019)
				(end 222.789496 -32.275018)
			)
			(arc
				(start 222.789496 -13.780008)
				(mid 222.353244 -12.726804)
				(end 221.30004 -12.290552)
			)
			(arc
				(start 196.701918 -12.290552)
				(mid 194.926701 -11.555233)
				(end 194.191382 -9.780016)
			)
			(xy 194.191382 -6.53796) (xy 194.193668 -6.53796)
			(arc
				(start 194.193668 -6.279896)
				(mid 194.04964 -5.93218)
				(end 193.701924 -5.788152)
			)
			(arc
				(start 127.102108 -5.788152)
				(mid 126.754392 -5.93218)
				(end 126.610364 -6.279896)
			)
			(xy 126.610364 -6.53796) (xy 126.61265 -6.53796)
			(arc
				(start 126.61265 -7.744206)
				(mid 126.627618 -7.779963)
				(end 126.66345 -7.794752)
			)
			(arc
				(start 126.687326 -7.78891)
				(mid 126.774244 -7.75555)
				(end 126.86665 -7.744206)
			)
			(arc
				(start 126.86665 -7.744206)
				(mid 126.931475 -7.749794)
				(end 126.994412 -7.766304)
			)
			(arc
				(start 126.994412 -7.766304)
				(mid 127.020815 -7.768359)
				(end 127.044704 -7.756906)
			)
			(arc
				(start 127.044704 -7.756906)
				(mid 127.071589 -7.734537)
				(end 127.099314 -7.713218)
			)
			(xy 127.119888 -7.672832) (xy 127.119888 -6.295898) (xy 193.684144 -6.295898) (xy 193.684144 -7.673086)
			(arc
				(start 193.704718 -7.713472)
				(mid 194.076604 -8.449818)
				(end 193.704718 -9.186164)
			)
			(xy 193.684144 -9.22655)
			(arc
				(start 193.684144 -9.780016)
				(mid 194.568119 -11.91374)
				(end 196.701918 -12.797536)
			)
			(arc
				(start 221.30004 -12.797536)
				(mid 221.994753 -13.085295)
				(end 222.282512 -13.780008)
			)
			(xy 222.282512 -32.275018)
			(arc
				(start 222.284036 -33.275016)
				(mid 223.167401 -35.407647)
				(end 225.300032 -36.291012)
			)
		)
		(stroke
			(width 0)
			(type solid)
		)
		(fill yes)
		(layer "In11.Cu")
		(net "GND")
	)
	(gr_poly
		(pts
			(xy 310.297322 -192.7606) (xy 310.312285 -192.760114) (xy 310.340948 -192.751523) (xy 310.365893 -192.734997)
			(xy 310.384982 -192.711953) (xy 310.396575 -192.684368) (xy 310.39968 -192.654607) (xy 310.39403 -192.625222)
			(xy 310.387492 -192.611756) (xy 310.373658 -192.584228) (xy 310.354082 -192.525814) (xy 310.344156 -192.465013)
			(xy 310.34355 -192.43421) (xy 310.344036 -192.406959) (xy 310.351792 -192.353011) (xy 310.367147 -192.300716)
			(xy 310.389789 -192.251139) (xy 310.419255 -192.205289) (xy 310.454946 -192.164098) (xy 310.496137 -192.128407)
			(xy 310.541987 -192.098941) (xy 310.591564 -192.076299) (xy 310.643859 -192.060944) (xy 310.697807 -192.053188)
			(xy 310.752309 -192.053188) (xy 310.806257 -192.060944) (xy 310.858552 -192.076299) (xy 310.908129 -192.098941)
			(xy 310.953979 -192.128407) (xy 310.99517 -192.164098) (xy 311.030861 -192.205289) (xy 311.060327 -192.251139)
			(xy 311.082969 -192.300716) (xy 311.098324 -192.353011) (xy 311.10608 -192.406959) (xy 311.106566 -192.43421)
			(xy 311.105953 -192.465012) (xy 311.096015 -192.525809) (xy 311.076446 -192.584223) (xy 311.062624 -192.611756)
			(xy 311.056137 -192.625243) (xy 311.050495 -192.654618) (xy 311.0536 -192.684369) (xy 311.065186 -192.711947)
			(xy 311.08426 -192.734989) (xy 311.109189 -192.751521) (xy 311.137837 -192.760127) (xy 311.152794 -192.7606)
			(xy 311.510934 -192.7606) (xy 311.526392 -192.760064) (xy 311.555893 -192.750825) (xy 311.581273 -192.733174)
			(xy 311.600202 -192.708732) (xy 311.610943 -192.679743) (xy 311.61228 -192.664334) (xy 311.614307 -192.6354)
			(xy 311.626015 -192.578595) (xy 311.646185 -192.524216) (xy 311.674354 -192.473516) (xy 311.709872 -192.427665)
			(xy 311.751922 -192.387717) (xy 311.799533 -192.354595) (xy 311.851609 -192.32906) (xy 311.90695 -192.311702)
			(xy 311.96428 -192.30292) (xy 311.99328 -192.302384) (xy 312.019364 -192.302809) (xy 312.071044 -192.309916)
			(xy 312.121274 -192.324) (xy 312.169116 -192.344798) (xy 312.213677 -192.371922) (xy 312.254125 -192.404867)
			(xy 312.289706 -192.443016) (xy 312.319756 -192.485659) (xy 312.332116 -192.508632) (xy 312.338743 -192.520599)
			(xy 312.357229 -192.540747) (xy 312.380406 -192.555255) (xy 312.406607 -192.563079) (xy 312.433945 -192.563654)
			(xy 312.460452 -192.556939) (xy 312.484219 -192.543419) (xy 312.494168 -192.534032) (xy 336.3722 -168.656)
			(xy 336.3722 -150.0124) (xy 333.3242 -146.9644) (xy 289.4584 -146.9644) (xy 288.7726 -147.6502) (xy 288.7726 -148.561044)
			(xy 288.773093 -148.575374) (xy 288.78106 -148.602903) (xy 288.796357 -148.627139) (xy 288.81778 -148.646176)
			(xy 288.843646 -148.658518) (xy 288.871921 -148.663195) (xy 288.900383 -148.659839) (xy 288.926795 -148.648714)
			(xy 288.938208 -148.640038) (xy 288.958698 -148.623915) (xy 289.003247 -148.596823) (xy 289.05107 -148.57605)
			(xy 289.101276 -148.561982) (xy 289.15293 -148.554883) (xy 289.179 -148.55444) (xy 289.206248 -148.554926)
			(xy 289.260189 -148.562682) (xy 289.312477 -148.578035) (xy 289.362048 -148.600673) (xy 289.407892 -148.630136)
			(xy 289.449077 -148.665823) (xy 289.484764 -148.707008) (xy 289.514227 -148.752852) (xy 289.536865 -148.802423)
			(xy 289.552218 -148.854711) (xy 289.559974 -148.908652) (xy 289.559974 -148.961348) (xy 292.5986 -148.961348)
			(xy 292.602671 -148.905726) (xy 292.614797 -148.851289) (xy 292.63472 -148.799198) (xy 292.662016 -148.750563)
			(xy 292.696102 -148.70642) (xy 292.736251 -148.667711) (xy 292.781609 -148.63526) (xy 292.831209 -148.609759)
			(xy 292.883993 -148.591752) (xy 292.938836 -148.581622) (xy 292.99457 -148.579585) (xy 293.050007 -148.585685)
			(xy 293.103964 -148.599791) (xy 293.155293 -148.621603) (xy 293.202899 -148.650657) (xy 293.245767 -148.686332)
			(xy 293.282984 -148.727869) (xy 293.313757 -148.774382) (xy 293.329961 -148.808948) (xy 293.826182 -148.808948)
			(xy 293.830253 -148.753326) (xy 293.842379 -148.698889) (xy 293.862302 -148.646798) (xy 293.889598 -148.598163)
			(xy 293.923684 -148.55402) (xy 293.963833 -148.515311) (xy 294.009191 -148.48286) (xy 294.058791 -148.457359)
			(xy 294.111575 -148.439352) (xy 294.166418 -148.429222) (xy 294.222152 -148.427185) (xy 294.277589 -148.433285)
			(xy 294.331546 -148.447391) (xy 294.382875 -148.469203) (xy 294.430481 -148.498257) (xy 294.439726 -148.505951)
			(xy 297.385703 -148.505951) (xy 297.385703 -148.451449) (xy 297.39346 -148.397501) (xy 297.408816 -148.345207)
			(xy 297.431459 -148.29563) (xy 297.460927 -148.249781) (xy 297.496621 -148.208592) (xy 297.537813 -148.172903)
			(xy 297.583665 -148.14344) (xy 297.633244 -148.120802) (xy 297.68554 -148.105452) (xy 297.739489 -148.0977)
			(xy 297.76674 -148.09724) (xy 297.793004 -148.097656) (xy 297.845037 -148.104855) (xy 297.89559 -148.119125)
			(xy 297.943708 -148.140197) (xy 297.988479 -148.16767) (xy 298.029057 -148.201027) (xy 298.064674 -148.239636)
			(xy 298.094658 -148.282766) (xy 298.11844 -148.329603) (xy 298.12742 -148.354288) (xy 298.132607 -148.367872)
			(xy 298.149459 -148.391554) (xy 298.1723 -148.409529) (xy 298.19928 -148.420343) (xy 298.228213 -148.423119)
			(xy 298.256757 -148.417631) (xy 298.269914 -148.411438) (xy 298.297124 -148.398058) (xy 298.354729 -148.379137)
			(xy 298.414603 -148.369581) (xy 298.44492 -148.36902) (xy 298.472172 -148.369451) (xy 298.526122 -148.377211)
			(xy 298.578418 -148.392569) (xy 298.627996 -148.415213) (xy 298.673848 -148.444682) (xy 298.715038 -148.480376)
			(xy 298.75073 -148.521568) (xy 298.755858 -148.529548) (xy 299.668182 -148.529548) (xy 299.672253 -148.473926)
			(xy 299.684379 -148.419489) (xy 299.704302 -148.367398) (xy 299.731598 -148.318763) (xy 299.765684 -148.27462)
			(xy 299.805833 -148.235911) (xy 299.851191 -148.20346) (xy 299.900791 -148.177959) (xy 299.953575 -148.159952)
			(xy 300.008418 -148.149822) (xy 300.064152 -148.147785) (xy 300.119589 -148.153885) (xy 300.173546 -148.167991)
			(xy 300.224875 -148.189803) (xy 300.272481 -148.218857) (xy 300.315349 -148.254532) (xy 300.352566 -148.296069)
			(xy 300.383339 -148.342582) (xy 300.407011 -148.393079) (xy 300.423079 -148.446486) (xy 300.431199 -148.501662)
			(xy 300.431708 -148.529548) (xy 300.431199 -148.557434) (xy 300.423079 -148.61261) (xy 300.407011 -148.666017)
			(xy 300.383339 -148.716514) (xy 300.352566 -148.763027) (xy 300.315349 -148.804564) (xy 300.272481 -148.840239)
			(xy 300.224875 -148.869293) (xy 300.173546 -148.891105) (xy 300.119589 -148.905211) (xy 300.064152 -148.911311)
			(xy 300.008418 -148.909274) (xy 299.953575 -148.899144) (xy 299.900791 -148.881137) (xy 299.851191 -148.855636)
			(xy 299.805833 -148.823185) (xy 299.765684 -148.784476) (xy 299.731598 -148.740333) (xy 299.704302 -148.691698)
			(xy 299.684379 -148.639607) (xy 299.672253 -148.58517) (xy 299.668182 -148.529548) (xy 298.755858 -148.529548)
			(xy 298.780197 -148.567421) (xy 298.802838 -148.617001) (xy 298.818194 -148.669298) (xy 298.82595 -148.723248)
			(xy 298.82595 -148.777752) (xy 298.818194 -148.831702) (xy 298.802838 -148.883999) (xy 298.780197 -148.933579)
			(xy 298.75073 -148.979432) (xy 298.715038 -149.020624) (xy 298.673848 -149.056318) (xy 298.627996 -149.085787)
			(xy 298.578418 -149.108431) (xy 298.526122 -149.123789) (xy 298.472172 -149.131549) (xy 298.44492 -149.132036)
			(xy 298.418657 -149.131583) (xy 298.366625 -149.124391) (xy 298.316072 -149.110128) (xy 298.267954 -149.089062)
			(xy 298.223182 -149.061593) (xy 298.182604 -149.02824) (xy 298.146985 -148.989635) (xy 298.117002 -148.946507)
			(xy 298.09322 -148.899672) (xy 298.08424 -148.874988) (xy 298.078993 -148.861425) (xy 298.06216 -148.83773)
			(xy 298.039331 -148.819739) (xy 298.012357 -148.808911) (xy 297.983426 -148.806124) (xy 297.954881 -148.811602)
			(xy 297.941746 -148.817838) (xy 297.914542 -148.83123) (xy 297.856934 -148.850147) (xy 297.797057 -148.859698)
			(xy 297.76674 -148.860256) (xy 297.739489 -148.8597) (xy 297.68554 -148.851948) (xy 297.633244 -148.836598)
			(xy 297.583665 -148.81396) (xy 297.537813 -148.784497) (xy 297.496621 -148.748808) (xy 297.460927 -148.707619)
			(xy 297.431459 -148.66177) (xy 297.408816 -148.612193) (xy 297.39346 -148.559899) (xy 297.385703 -148.505951)
			(xy 294.439726 -148.505951) (xy 294.473349 -148.533932) (xy 294.510566 -148.575469) (xy 294.541339 -148.621982)
			(xy 294.565011 -148.672479) (xy 294.581079 -148.725886) (xy 294.589199 -148.781062) (xy 294.589708 -148.808948)
			(xy 294.589199 -148.836834) (xy 294.581079 -148.89201) (xy 294.565011 -148.945417) (xy 294.541339 -148.995914)
			(xy 294.510566 -149.042427) (xy 294.473349 -149.083964) (xy 294.430481 -149.119639) (xy 294.382875 -149.148693)
			(xy 294.331546 -149.170505) (xy 294.277589 -149.184611) (xy 294.222152 -149.190711) (xy 294.166418 -149.188674)
			(xy 294.111575 -149.178544) (xy 294.058791 -149.160537) (xy 294.009191 -149.135036) (xy 293.963833 -149.102585)
			(xy 293.923684 -149.063876) (xy 293.889598 -149.019733) (xy 293.862302 -148.971098) (xy 293.842379 -148.919007)
			(xy 293.830253 -148.86457) (xy 293.826182 -148.808948) (xy 293.329961 -148.808948) (xy 293.337429 -148.824879)
			(xy 293.353497 -148.878286) (xy 293.361617 -148.933462) (xy 293.362126 -148.961348) (xy 293.361617 -148.989234)
			(xy 293.353497 -149.04441) (xy 293.337429 -149.097817) (xy 293.313757 -149.148314) (xy 293.282984 -149.194827)
			(xy 293.245767 -149.236364) (xy 293.202899 -149.272039) (xy 293.155293 -149.301093) (xy 293.103964 -149.322905)
			(xy 293.050007 -149.337011) (xy 292.99457 -149.343111) (xy 292.938836 -149.341074) (xy 292.883993 -149.330944)
			(xy 292.831209 -149.312937) (xy 292.781609 -149.287436) (xy 292.736251 -149.254985) (xy 292.696102 -149.216276)
			(xy 292.662016 -149.172133) (xy 292.63472 -149.123498) (xy 292.614797 -149.071407) (xy 292.602671 -149.01697)
			(xy 292.5986 -148.961348) (xy 289.559974 -148.961348) (xy 289.559974 -148.963148) (xy 289.552218 -149.017089)
			(xy 289.536865 -149.069377) (xy 289.514227 -149.118948) (xy 289.484764 -149.164792) (xy 289.449077 -149.205977)
			(xy 289.407892 -149.241664) (xy 289.362048 -149.271127) (xy 289.312477 -149.293765) (xy 289.260189 -149.309118)
			(xy 289.206248 -149.316874) (xy 289.179 -149.317456) (xy 289.152929 -149.317031) (xy 289.101274 -149.309929)
			(xy 289.051068 -149.295858) (xy 289.003246 -149.275079) (xy 288.9587 -149.247981) (xy 288.938208 -149.231858)
			(xy 288.926766 -149.223209) (xy 288.900357 -149.212052) (xy 288.871888 -149.208673) (xy 288.843601 -149.213337)
			(xy 288.817724 -149.225678) (xy 288.796295 -149.244723) (xy 288.781002 -149.268973) (xy 288.77305 -149.296517)
			(xy 288.7726 -149.310852) (xy 288.7726 -149.533356) (xy 304.17084 -149.533356) (xy 304.174911 -149.477734)
			(xy 304.187037 -149.423297) (xy 304.20696 -149.371206) (xy 304.234256 -149.322571) (xy 304.268342 -149.278428)
			(xy 304.308491 -149.239719) (xy 304.353849 -149.207268) (xy 304.403449 -149.181767) (xy 304.456233 -149.16376)
			(xy 304.511076 -149.15363) (xy 304.56681 -149.151593) (xy 304.622247 -149.157693) (xy 304.676204 -149.171799)
			(xy 304.727533 -149.193611) (xy 304.775139 -149.222665) (xy 304.818007 -149.25834) (xy 304.855224 -149.299877)
			(xy 304.885997 -149.34639) (xy 304.909669 -149.396887) (xy 304.925737 -149.450294) (xy 304.933857 -149.50547)
			(xy 304.934366 -149.533356) (xy 304.933857 -149.561242) (xy 304.925737 -149.616418) (xy 304.909669 -149.669825)
			(xy 304.885997 -149.720322) (xy 304.855224 -149.766835) (xy 304.818007 -149.808372) (xy 304.775139 -149.844047)
			(xy 304.727533 -149.873101) (xy 304.676204 -149.894913) (xy 304.622247 -149.909019) (xy 304.56681 -149.915119)
			(xy 304.511076 -149.913082) (xy 304.456233 -149.902952) (xy 304.403449 -149.884945) (xy 304.353849 -149.859444)
			(xy 304.308491 -149.826993) (xy 304.268342 -149.788284) (xy 304.234256 -149.744141) (xy 304.20696 -149.695506)
			(xy 304.187037 -149.643415) (xy 304.174911 -149.588978) (xy 304.17084 -149.533356) (xy 288.7726 -149.533356)
			(xy 288.7726 -150.392638) (xy 289.9316 -150.392638) (xy 289.935671 -150.337016) (xy 289.947797 -150.282579)
			(xy 289.96772 -150.230488) (xy 289.995016 -150.181853) (xy 290.029102 -150.13771) (xy 290.069251 -150.099001)
			(xy 290.114609 -150.06655) (xy 290.164209 -150.041049) (xy 290.216993 -150.023042) (xy 290.271836 -150.012912)
			(xy 290.32757 -150.010875) (xy 290.383007 -150.016975) (xy 290.436964 -150.031081) (xy 290.488293 -150.052893)
			(xy 290.535899 -150.081947) (xy 290.578767 -150.117622) (xy 290.615984 -150.159159) (xy 290.646757 -150.205672)
			(xy 290.670429 -150.256169) (xy 290.686497 -150.309576) (xy 290.694617 -150.364752) (xy 290.695126 -150.392638)
			(xy 290.694617 -150.420524) (xy 290.686497 -150.4757) (xy 290.670429 -150.529107) (xy 290.646757 -150.579604)
			(xy 290.615984 -150.626117) (xy 290.578767 -150.667654) (xy 290.535899 -150.703329) (xy 290.488293 -150.732383)
			(xy 290.436964 -150.754195) (xy 290.383007 -150.768301) (xy 290.32757 -150.774401) (xy 290.271836 -150.772364)
			(xy 290.216993 -150.762234) (xy 290.164209 -150.744227) (xy 290.114609 -150.718726) (xy 290.069251 -150.686275)
			(xy 290.029102 -150.647566) (xy 289.995016 -150.603423) (xy 289.96772 -150.554788) (xy 289.947797 -150.502697)
			(xy 289.935671 -150.44826) (xy 289.9316 -150.392638) (xy 288.7726 -150.392638) (xy 288.7726 -151.0792)
			(xy 289.433 -151.7396) (xy 298.138342 -151.7396) (xy 298.15283 -151.739084) (xy 298.180637 -151.730933)
			(xy 298.205036 -151.7153) (xy 298.224061 -151.693444) (xy 298.236182 -151.667124) (xy 298.240421 -151.638459)
			(xy 298.236439 -151.609757) (xy 298.224556 -151.583329) (xy 298.215558 -151.57196) (xy 298.198297 -151.551111)
			(xy 298.169219 -151.50546) (xy 298.146886 -151.456158) (xy 298.131745 -151.404193) (xy 298.124102 -151.350611)
			(xy 298.12361 -151.323548) (xy 298.124071 -151.296271) (xy 298.131831 -151.242271) (xy 298.147201 -151.189926)
			(xy 298.169866 -151.140302) (xy 298.199366 -151.094411) (xy 298.235099 -151.053188) (xy 298.255436 -151.035004)
			(xy 298.265753 -151.025475) (xy 298.281167 -151.002009) (xy 298.289609 -150.975234) (xy 298.290442 -150.947171)
			(xy 298.283603 -150.919942) (xy 298.269609 -150.895603) (xy 298.249517 -150.875993) (xy 298.237402 -150.868888)
			(xy 298.211938 -150.854455) (xy 298.165371 -150.818995) (xy 298.124768 -150.776838) (xy 298.091082 -150.728972)
			(xy 298.065103 -150.676522) (xy 298.047443 -150.620719) (xy 298.038515 -150.562874) (xy 298.038012 -150.533608)
			(xy 298.038498 -150.506357) (xy 298.046254 -150.452409) (xy 298.061609 -150.400114) (xy 298.084251 -150.350537)
			(xy 298.113717 -150.304687) (xy 298.149408 -150.263496) (xy 298.190599 -150.227805) (xy 298.236449 -150.198339)
			(xy 298.286026 -150.175697) (xy 298.338321 -150.160342) (xy 298.392269 -150.152586) (xy 298.446771 -150.152586)
			(xy 298.500719 -150.160342) (xy 298.553014 -150.175697) (xy 298.602591 -150.198339) (xy 298.648441 -150.227805)
			(xy 298.689632 -150.263496) (xy 298.725323 -150.304687) (xy 298.754789 -150.350537) (xy 298.777431 -150.400114)
			(xy 298.792786 -150.452409) (xy 298.800542 -150.506357) (xy 298.801028 -150.533608) (xy 298.800563 -150.560883)
			(xy 298.792795 -150.614878) (xy 298.777418 -150.667216) (xy 298.754745 -150.716831) (xy 298.725238 -150.762713)
			(xy 298.6895 -150.803926) (xy 298.669202 -150.822152) (xy 298.658883 -150.831685) (xy 298.643467 -150.855157)
			(xy 298.635021 -150.881939) (xy 298.634181 -150.910008) (xy 298.641012 -150.937247) (xy 298.654998 -150.961599)
			(xy 298.675083 -150.981225) (xy 298.687236 -150.988268) (xy 298.712696 -151.002704) (xy 298.759253 -151.038167)
			(xy 298.799846 -151.080327) (xy 298.833521 -151.128193) (xy 298.859489 -151.180643) (xy 298.87714 -151.236443)
			(xy 298.886058 -151.294285) (xy 298.886626 -151.323548) (xy 298.88615 -151.35061) (xy 298.878495 -151.40419)
			(xy 298.863343 -151.45615) (xy 298.841001 -151.505447) (xy 298.811916 -151.551092) (xy 298.794678 -151.57196)
			(xy 298.785647 -151.583307) (xy 298.773755 -151.609743) (xy 298.769769 -151.638454) (xy 298.77401 -151.667129)
			(xy 298.786136 -151.693458) (xy 298.805171 -151.715319) (xy 298.829581 -151.730952) (xy 298.857401 -151.739098)
			(xy 298.871894 -151.7396) (xy 303.9364 -151.7396) (xy 304.206148 -152.009348) (xy 306.698902 -152.009348)
			(xy 306.702973 -151.953726) (xy 306.715099 -151.899289) (xy 306.735022 -151.847198) (xy 306.762318 -151.798563)
			(xy 306.796404 -151.75442) (xy 306.836553 -151.715711) (xy 306.881911 -151.68326) (xy 306.931511 -151.657759)
			(xy 306.984295 -151.639752) (xy 307.039138 -151.629622) (xy 307.094872 -151.627585) (xy 307.150309 -151.633685)
			(xy 307.204266 -151.647791) (xy 307.255595 -151.669603) (xy 307.303201 -151.698657) (xy 307.346069 -151.734332)
			(xy 307.383286 -151.775869) (xy 307.414059 -151.822382) (xy 307.437731 -151.872879) (xy 307.453799 -151.926286)
			(xy 307.461919 -151.981462) (xy 307.462428 -152.009348) (xy 307.461919 -152.037234) (xy 307.453799 -152.09241)
			(xy 307.437731 -152.145817) (xy 307.414059 -152.196314) (xy 307.403319 -152.212548) (xy 307.973982 -152.212548)
			(xy 307.978053 -152.156926) (xy 307.990179 -152.102489) (xy 308.010102 -152.050398) (xy 308.037398 -152.001763)
			(xy 308.071484 -151.95762) (xy 308.111633 -151.918911) (xy 308.156991 -151.88646) (xy 308.206591 -151.860959)
			(xy 308.259375 -151.842952) (xy 308.314218 -151.832822) (xy 308.369952 -151.830785) (xy 308.425389 -151.836885)
			(xy 308.479346 -151.850991) (xy 308.530675 -151.872803) (xy 308.578281 -151.901857) (xy 308.621149 -151.937532)
			(xy 308.658366 -151.979069) (xy 308.689139 -152.025582) (xy 308.712811 -152.076079) (xy 308.728879 -152.129486)
			(xy 308.736999 -152.184662) (xy 308.737508 -152.212548) (xy 308.736999 -152.240434) (xy 308.728879 -152.29561)
			(xy 308.712811 -152.349017) (xy 308.689139 -152.399514) (xy 308.658366 -152.446027) (xy 308.621149 -152.487564)
			(xy 308.578281 -152.523239) (xy 308.530675 -152.552293) (xy 308.479346 -152.574105) (xy 308.425389 -152.588211)
			(xy 308.369952 -152.594311) (xy 308.314218 -152.592274) (xy 308.259375 -152.582144) (xy 308.206591 -152.564137)
			(xy 308.156991 -152.538636) (xy 308.111633 -152.506185) (xy 308.071484 -152.467476) (xy 308.037398 -152.423333)
			(xy 308.010102 -152.374698) (xy 307.990179 -152.322607) (xy 307.978053 -152.26817) (xy 307.973982 -152.212548)
			(xy 307.403319 -152.212548) (xy 307.383286 -152.242827) (xy 307.346069 -152.284364) (xy 307.303201 -152.320039)
			(xy 307.255595 -152.349093) (xy 307.204266 -152.370905) (xy 307.150309 -152.385011) (xy 307.094872 -152.391111)
			(xy 307.039138 -152.389074) (xy 306.984295 -152.378944) (xy 306.931511 -152.360937) (xy 306.881911 -152.335436)
			(xy 306.836553 -152.302985) (xy 306.796404 -152.264276) (xy 306.762318 -152.220133) (xy 306.735022 -152.171498)
			(xy 306.715099 -152.119407) (xy 306.702973 -152.06497) (xy 306.698902 -152.009348) (xy 304.206148 -152.009348)
			(xy 306.2986 -154.1018) (xy 328.2188 -154.1018) (xy 331.8002 -157.6832) (xy 331.8002 -166.7764) (xy 331.8256 -166.8018)
			(xy 331.8256 -168.2242) (xy 328.9046 -171.1452) (xy 324.358 -171.1452) (xy 308.1782 -187.325) (xy 308.1782 -189.158978)
			(xy 309.400381 -189.158978) (xy 309.400381 -189.074422) (xy 309.408183 -188.990228) (xy 309.423721 -188.907113)
			(xy 309.446861 -188.825786) (xy 309.477407 -188.746941) (xy 309.515098 -188.671251) (xy 309.559611 -188.599362)
			(xy 309.610569 -188.531886) (xy 309.667535 -188.469401) (xy 309.730023 -188.412438) (xy 309.797501 -188.361484)
			(xy 309.869393 -188.316974) (xy 309.945085 -188.279288) (xy 310.023931 -188.248746) (xy 310.10526 -188.22561)
			(xy 310.188376 -188.210077) (xy 310.27257 -188.202279) (xy 310.314848 -188.201808) (xy 311.559448 -188.201808)
			(xy 311.601723 -188.202266) (xy 311.685913 -188.210072) (xy 311.769024 -188.225612) (xy 311.850346 -188.248754)
			(xy 311.929187 -188.279301) (xy 312.004872 -188.316991) (xy 312.076757 -188.361504) (xy 312.144229 -188.412459)
			(xy 312.206711 -188.469423) (xy 312.263671 -188.531908) (xy 312.314623 -188.599382) (xy 312.359132 -188.67127)
			(xy 312.396819 -188.746957) (xy 312.427361 -188.825799) (xy 312.450499 -188.907123) (xy 312.466035 -188.990234)
			(xy 312.473836 -189.074424) (xy 312.473836 -189.158976) (xy 312.466035 -189.243166) (xy 312.450499 -189.326277)
			(xy 312.427361 -189.407601) (xy 312.396819 -189.486443) (xy 312.359132 -189.56213) (xy 312.314623 -189.634018)
			(xy 312.263671 -189.701492) (xy 312.206711 -189.763977) (xy 312.144229 -189.820941) (xy 312.076757 -189.871896)
			(xy 312.004872 -189.916409) (xy 311.929187 -189.954099) (xy 311.850346 -189.984646) (xy 311.769024 -190.007788)
			(xy 311.685913 -190.023328) (xy 311.601723 -190.031134) (xy 311.559448 -190.031624) (xy 310.314848 -190.031624)
			(xy 310.27257 -190.031121) (xy 310.188376 -190.023323) (xy 310.10526 -190.00779) (xy 310.023931 -189.984654)
			(xy 309.945085 -189.954112) (xy 309.869393 -189.916426) (xy 309.797501 -189.871916) (xy 309.730023 -189.820962)
			(xy 309.667535 -189.763999) (xy 309.610569 -189.701514) (xy 309.559611 -189.634038) (xy 309.515098 -189.562149)
			(xy 309.477407 -189.486459) (xy 309.446861 -189.407614) (xy 309.423721 -189.326287) (xy 309.408183 -189.243172)
			(xy 309.400381 -189.158978) (xy 308.1782 -189.158978) (xy 308.1782 -192.4304) (xy 308.5084 -192.7606)
		)
		(stroke
			(width 0)
			(type solid)
		)
		(fill yes)
		(layer "In11.Cu")
		(net "P3V3_AUX")
	)
	(gr_poly
		(pts
			(xy 269.595092 -436.8673) (xy 269.609436 -436.866811) (xy 269.636992 -436.858835) (xy 269.661242 -436.843509)
			(xy 269.680273 -436.822043) (xy 269.692583 -436.796132) (xy 269.697201 -436.767819) (xy 269.693761 -436.739338)
			(xy 269.682537 -436.712938) (xy 269.664413 -436.690702) (xy 269.640819 -436.674383) (xy 269.62735 -436.669434)
			(xy 269.543581 -436.641008) (xy 269.378489 -436.577411) (xy 269.216515 -436.506245) (xy 269.058006 -436.427664)
			(xy 268.903302 -436.341834) (xy 268.752734 -436.248941) (xy 268.606623 -436.149182) (xy 268.465283 -436.042772)
			(xy 268.329017 -435.929938) (xy 268.198116 -435.810921) (xy 268.07286 -435.685977) (xy 267.953518 -435.555373)
			(xy 267.840344 -435.419388) (xy 267.733582 -435.278314) (xy 267.633459 -435.132453) (xy 267.540191 -434.982116)
			(xy 267.453976 -434.827626) (xy 267.375 -434.669314) (xy 267.303431 -434.507518) (xy 267.239422 -434.342585)
			(xy 267.183112 -434.174867) (xy 267.134619 -434.004724) (xy 267.094049 -433.832521) (xy 267.061487 -433.658625)
			(xy 267.037004 -433.483409) (xy 267.020652 -433.307248) (xy 267.012465 -433.130519) (xy 267.011912 -433.04206)
			(xy 267.012407 -432.95502) (xy 267.02033 -432.781121) (xy 267.03616 -432.607763) (xy 267.059864 -432.435305)
			(xy 267.091393 -432.264105) (xy 267.130681 -432.094517) (xy 267.177647 -431.926892) (xy 267.232194 -431.76158)
			(xy 267.294208 -431.598921) (xy 267.363561 -431.439253) (xy 267.44011 -431.282908) (xy 267.523696 -431.130208)
			(xy 267.614145 -430.981471) (xy 267.711269 -430.837005) (xy 267.814869 -430.69711) (xy 267.924728 -430.562074)
			(xy 268.04062 -430.432179) (xy 268.162304 -430.307693) (xy 268.289527 -430.188875) (xy 268.422027 -430.07597)
			(xy 268.559528 -429.969213) (xy 268.701746 -429.868825) (xy 268.848385 -429.775014) (xy 268.999142 -429.687974)
			(xy 269.153705 -429.607886) (xy 269.311752 -429.534916) (xy 269.472957 -429.469215) (xy 269.636986 -429.410919)
			(xy 269.803497 -429.36015) (xy 269.972147 -429.317012) (xy 270.142585 -429.281594) (xy 270.314459 -429.253971)
			(xy 270.487412 -429.234199) (xy 270.661086 -429.222319) (xy 270.83512 -429.218357) (xy 271.009154 -429.222319)
			(xy 271.182828 -429.234199) (xy 271.355781 -429.253971) (xy 271.527655 -429.281594) (xy 271.698093 -429.317012)
			(xy 271.866743 -429.36015) (xy 272.033254 -429.410919) (xy 272.197283 -429.469215) (xy 272.358488 -429.534916)
			(xy 272.516535 -429.607886) (xy 272.671098 -429.687974) (xy 272.821855 -429.775014) (xy 272.968494 -429.868825)
			(xy 273.110712 -429.969213) (xy 273.248213 -430.07597) (xy 273.380713 -430.188875) (xy 273.507936 -430.307693)
			(xy 273.62962 -430.432179) (xy 273.745512 -430.562074) (xy 273.855371 -430.69711) (xy 273.958971 -430.837005)
			(xy 274.056095 -430.981471) (xy 274.146544 -431.130208) (xy 274.23013 -431.282908) (xy 274.306679 -431.439253)
			(xy 274.376032 -431.598921) (xy 274.438046 -431.76158) (xy 274.492593 -431.926892) (xy 274.539559 -432.094517)
			(xy 274.578847 -432.264105) (xy 274.610376 -432.435305) (xy 274.63408 -432.607763) (xy 274.64991 -432.781121)
			(xy 274.657833 -432.95502) (xy 274.658328 -433.04206) (xy 274.657823 -433.130521) (xy 274.649641 -433.307252)
			(xy 274.633292 -433.483417) (xy 274.608812 -433.658636) (xy 274.576253 -433.832535) (xy 274.535684 -434.004742)
			(xy 274.487193 -434.174888) (xy 274.430884 -434.342609) (xy 274.366876 -434.507546) (xy 274.295307 -434.669345)
			(xy 274.21633 -434.82766) (xy 274.130114 -434.982153) (xy 274.036844 -435.132492) (xy 273.93672 -435.278356)
			(xy 273.829955 -435.419432) (xy 273.716779 -435.555418) (xy 273.597434 -435.686023) (xy 273.472175 -435.810968)
			(xy 273.34127 -435.929985) (xy 273.205 -436.042819) (xy 273.063656 -436.149229) (xy 272.917541 -436.248986)
			(xy 272.766968 -436.341878) (xy 272.61226 -436.427705) (xy 272.453746 -436.506284) (xy 272.291768 -436.577446)
			(xy 272.126671 -436.64104) (xy 272.04289 -436.669434) (xy 272.029461 -436.674457) (xy 272.005897 -436.69077)
			(xy 271.987798 -436.712992) (xy 271.97659 -436.739369) (xy 271.973157 -436.767822) (xy 271.977769 -436.796108)
			(xy 271.990064 -436.821996) (xy 272.009072 -436.843446) (xy 272.033293 -436.858765) (xy 272.060819 -436.866747)
			(xy 272.075148 -436.8673) (xy 272.795238 -436.8673) (xy 275.273516 -434.389276) (xy 275.273516 -430.893728)
			(xy 275.273956 -430.868748) (xy 275.281727 -430.819397) (xy 275.297129 -430.771872) (xy 275.319782 -430.727344)
			(xy 275.349128 -430.686912) (xy 275.36648 -430.668938) (xy 278.600408 -427.43501) (xy 278.618397 -427.417662)
			(xy 278.658815 -427.388271) (xy 278.703333 -427.365566) (xy 278.750855 -427.350105) (xy 278.800211 -427.34227)
			(xy 278.825198 -427.341792) (xy 292.085014 -427.341792) (xy 293.12108 -426.30598) (xy 293.12108 -414.080198)
			(xy 293.120535 -414.065109) (xy 293.111725 -414.036244) (xy 293.094873 -414.011208) (xy 293.071447 -413.992182)
			(xy 293.043487 -413.980823) (xy 293.013429 -413.97812) (xy 292.983892 -413.984309) (xy 292.957447 -413.99885)
			(xy 292.946582 -414.009332) (xy 292.928562 -414.027236) (xy 292.888605 -414.058603) (xy 292.844838 -414.084389)
			(xy 292.798036 -414.104138) (xy 292.749026 -414.1175) (xy 292.698677 -414.12424) (xy 292.673278 -414.124648)
			(xy 292.646025 -414.124161) (xy 292.592074 -414.116401) (xy 292.539776 -414.101042) (xy 292.490197 -414.078397)
			(xy 292.444344 -414.048927) (xy 292.403152 -414.013232) (xy 292.367459 -413.972038) (xy 292.337992 -413.926184)
			(xy 292.31535 -413.876603) (xy 292.299995 -413.824305) (xy 292.292238 -413.770353) (xy 292.292238 -413.715847)
			(xy 292.299995 -413.661895) (xy 292.31535 -413.609597) (xy 292.337992 -413.560016) (xy 292.367459 -413.514162)
			(xy 292.403152 -413.472968) (xy 292.444344 -413.437273) (xy 292.490197 -413.407803) (xy 292.539776 -413.385158)
			(xy 292.592074 -413.369799) (xy 292.646025 -413.362039) (xy 292.673278 -413.361632) (xy 292.698677 -413.362049)
			(xy 292.749027 -413.368786) (xy 292.798038 -413.382145) (xy 292.844843 -413.401889) (xy 292.888614 -413.427669)
			(xy 292.928577 -413.459028) (xy 292.946582 -413.476948) (xy 292.957492 -413.487393) (xy 292.983935 -413.501957)
			(xy 293.013478 -413.508165) (xy 293.043547 -413.505474) (xy 293.071518 -413.49412) (xy 293.094955 -413.475093)
			(xy 293.111814 -413.45005) (xy 293.120625 -413.421176) (xy 293.12108 -413.406082) (xy 293.12108 -413.35706)
			(xy 292.12794 -412.36392) (xy 281.280108 -412.36392) (xy 281.280108 -412.86684) (xy 283.38272 -412.86684)
			(xy 283.383206 -412.839589) (xy 283.390962 -412.785641) (xy 283.406317 -412.733346) (xy 283.428959 -412.683769)
			(xy 283.458425 -412.637919) (xy 283.494116 -412.596728) (xy 283.535307 -412.561037) (xy 283.581157 -412.531571)
			(xy 283.630734 -412.508929) (xy 283.683029 -412.493574) (xy 283.736977 -412.485818) (xy 283.791479 -412.485818)
			(xy 283.845427 -412.493574) (xy 283.897722 -412.508929) (xy 283.947299 -412.531571) (xy 283.993149 -412.561037)
			(xy 284.03434 -412.596728) (xy 284.070031 -412.637919) (xy 284.099497 -412.683769) (xy 284.122139 -412.733346)
			(xy 284.137494 -412.785641) (xy 284.14525 -412.839589) (xy 284.145736 -412.86684) (xy 284.145275 -412.893992)
			(xy 284.137557 -412.947746) (xy 284.122299 -412.999863) (xy 284.099807 -413.049292) (xy 284.070536 -413.095033)
			(xy 284.035077 -413.136163) (xy 284.014926 -413.154368) (xy 284.005015 -413.16352) (xy 283.990064 -413.185966)
			(xy 283.981518 -413.211546) (xy 283.979973 -413.238471) (xy 283.985538 -413.26486) (xy 283.997824 -413.288869)
			(xy 284.015972 -413.308819) (xy 284.027118 -413.31642) (xy 284.049827 -413.331576) (xy 284.091135 -413.367269)
			(xy 284.126935 -413.408486) (xy 284.156496 -413.454384) (xy 284.179214 -413.504026) (xy 284.194625 -413.556399)
			(xy 284.202415 -413.610433) (xy 284.202886 -413.63773) (xy 284.2024 -413.664981) (xy 284.194644 -413.718929)
			(xy 284.179289 -413.771224) (xy 284.156647 -413.820801) (xy 284.127181 -413.866651) (xy 284.09149 -413.907842)
			(xy 284.050299 -413.943533) (xy 284.004449 -413.972999) (xy 283.954872 -413.995641) (xy 283.902577 -414.010996)
			(xy 283.848629 -414.018752) (xy 283.794127 -414.018752) (xy 283.740179 -414.010996) (xy 283.687884 -413.995641)
			(xy 283.638307 -413.972999) (xy 283.592457 -413.943533) (xy 283.551266 -413.907842) (xy 283.515575 -413.866651)
			(xy 283.486109 -413.820801) (xy 283.463467 -413.771224) (xy 283.448112 -413.718929) (xy 283.440356 -413.664981)
			(xy 283.43987 -413.63773) (xy 283.440377 -413.610579) (xy 283.448085 -413.556827) (xy 283.463334 -413.504711)
			(xy 283.485817 -413.455282) (xy 283.51508 -413.40954) (xy 283.550532 -413.368408) (xy 283.57068 -413.350202)
			(xy 283.580515 -413.340975) (xy 283.595467 -413.318547) (xy 283.604019 -413.292985) (xy 283.605574 -413.266076)
			(xy 283.600023 -413.239699) (xy 283.587754 -413.215698) (xy 283.569625 -413.195752) (xy 283.558488 -413.18815)
			(xy 283.535767 -413.173012) (xy 283.494458 -413.137316) (xy 283.458659 -413.096096) (xy 283.4291 -413.050195)
			(xy 283.406384 -413.00055) (xy 283.390975 -412.948175) (xy 283.383189 -412.894138) (xy 283.38272 -412.86684)
			(xy 281.280108 -412.86684) (xy 281.280108 -413.50565) (xy 282.402532 -413.50565) (xy 282.406603 -413.450028)
			(xy 282.418729 -413.395591) (xy 282.438652 -413.3435) (xy 282.465948 -413.294865) (xy 282.500034 -413.250722)
			(xy 282.540183 -413.212013) (xy 282.585541 -413.179562) (xy 282.635141 -413.154061) (xy 282.687925 -413.136054)
			(xy 282.742768 -413.125924) (xy 282.798502 -413.123887) (xy 282.853939 -413.129987) (xy 282.907896 -413.144093)
			(xy 282.959225 -413.165905) (xy 283.006831 -413.194959) (xy 283.049699 -413.230634) (xy 283.086916 -413.272171)
			(xy 283.117689 -413.318684) (xy 283.141361 -413.369181) (xy 283.157429 -413.422588) (xy 283.165549 -413.477764)
			(xy 283.166058 -413.50565) (xy 283.165549 -413.533536) (xy 283.157429 -413.588712) (xy 283.141361 -413.642119)
			(xy 283.117689 -413.692616) (xy 283.086916 -413.739129) (xy 283.049699 -413.780666) (xy 283.006831 -413.816341)
			(xy 282.959225 -413.845395) (xy 282.907896 -413.867207) (xy 282.853939 -413.881313) (xy 282.798502 -413.887413)
			(xy 282.742768 -413.885376) (xy 282.687925 -413.875246) (xy 282.635141 -413.857239) (xy 282.585541 -413.831738)
			(xy 282.540183 -413.799287) (xy 282.500034 -413.760578) (xy 282.465948 -413.716435) (xy 282.438652 -413.6678)
			(xy 282.418729 -413.615709) (xy 282.406603 -413.561272) (xy 282.402532 -413.50565) (xy 281.280108 -413.50565)
			(xy 281.280108 -414.36798) (xy 282.571442 -414.36798) (xy 282.575513 -414.312358) (xy 282.587639 -414.257921)
			(xy 282.607562 -414.20583) (xy 282.634858 -414.157195) (xy 282.668944 -414.113052) (xy 282.709093 -414.074343)
			(xy 282.754451 -414.041892) (xy 282.804051 -414.016391) (xy 282.856835 -413.998384) (xy 282.911678 -413.988254)
			(xy 282.967412 -413.986217) (xy 283.022849 -413.992317) (xy 283.076806 -414.006423) (xy 283.128135 -414.028235)
			(xy 283.175741 -414.057289) (xy 283.218609 -414.092964) (xy 283.255826 -414.134501) (xy 283.286599 -414.181014)
			(xy 283.310271 -414.231511) (xy 283.326339 -414.284918) (xy 283.334459 -414.340094) (xy 283.334968 -414.36798)
			(xy 283.334459 -414.395866) (xy 283.326339 -414.451042) (xy 283.310271 -414.504449) (xy 283.286599 -414.554946)
			(xy 283.255826 -414.601459) (xy 283.218609 -414.642996) (xy 283.175741 -414.678671) (xy 283.128135 -414.707725)
			(xy 283.076806 -414.729537) (xy 283.022849 -414.743643) (xy 282.967412 -414.749743) (xy 282.911678 -414.747706)
			(xy 282.856835 -414.737576) (xy 282.804051 -414.719569) (xy 282.754451 -414.694068) (xy 282.709093 -414.661617)
			(xy 282.668944 -414.622908) (xy 282.634858 -414.578765) (xy 282.607562 -414.53013) (xy 282.587639 -414.478039)
			(xy 282.575513 -414.423602) (xy 282.571442 -414.36798) (xy 281.280108 -414.36798) (xy 281.280108 -415.46018)
			(xy 281.279643 -415.485168) (xy 281.271817 -415.534527) (xy 281.256355 -415.58205) (xy 281.233639 -415.626565)
			(xy 281.20423 -415.666971) (xy 281.18689 -415.68497) (xy 279.98801 -416.88385) (xy 280.663902 -416.88385)
			(xy 280.667973 -416.828228) (xy 280.680099 -416.773791) (xy 280.700022 -416.7217) (xy 280.727318 -416.673065)
			(xy 280.761404 -416.628922) (xy 280.801553 -416.590213) (xy 280.846911 -416.557762) (xy 280.896511 -416.532261)
			(xy 280.949295 -416.514254) (xy 281.004138 -416.504124) (xy 281.059872 -416.502087) (xy 281.115309 -416.508187)
			(xy 281.169266 -416.522293) (xy 281.220595 -416.544105) (xy 281.268201 -416.573159) (xy 281.311069 -416.608834)
			(xy 281.348286 -416.650371) (xy 281.379059 -416.696884) (xy 281.402731 -416.747381) (xy 281.418799 -416.800788)
			(xy 281.426919 -416.855964) (xy 281.427428 -416.88385) (xy 281.426919 -416.911736) (xy 281.418799 -416.966912)
			(xy 281.402731 -417.020319) (xy 281.379059 -417.070816) (xy 281.348286 -417.117329) (xy 281.311069 -417.158866)
			(xy 281.268201 -417.194541) (xy 281.220595 -417.223595) (xy 281.169266 -417.245407) (xy 281.115309 -417.259513)
			(xy 281.059872 -417.265613) (xy 281.004138 -417.263576) (xy 280.949295 -417.253446) (xy 280.896511 -417.235439)
			(xy 280.846911 -417.209938) (xy 280.801553 -417.177487) (xy 280.761404 -417.138778) (xy 280.727318 -417.094635)
			(xy 280.700022 -417.046) (xy 280.680099 -416.993909) (xy 280.667973 -416.939472) (xy 280.663902 -416.88385)
			(xy 279.98801 -416.88385) (xy 279.84577 -417.02609) (xy 279.82778 -417.043437) (xy 279.787362 -417.072825)
			(xy 279.742844 -417.095527) (xy 279.695322 -417.110984) (xy 279.645966 -417.118816) (xy 279.62098 -417.119308)
			(xy 277.715472 -417.119308) (xy 277.09495 -417.73983) (xy 277.076944 -417.75716) (xy 277.036531 -417.786552)
			(xy 276.992017 -417.809261) (xy 276.944498 -417.824727) (xy 276.895146 -417.832569) (xy 276.87016 -417.833048)
			(xy 275.757386 -417.833048) (xy 275.621242 -417.968938) (xy 275.610696 -417.980321) (xy 275.596424 -418.007859)
			(xy 275.591064 -418.038408) (xy 275.59511 -418.069159) (xy 275.608188 -418.097282) (xy 275.618194 -418.109146)
			(xy 275.636781 -418.130337) (xy 275.668159 -418.177159) (xy 275.692316 -418.228085) (xy 275.708726 -418.282009)
			(xy 275.717033 -418.337758) (xy 275.717508 -418.36594) (xy 275.71699 -418.394244) (xy 275.708619 -418.45023)
			(xy 275.692068 -418.504365) (xy 275.667698 -418.55546) (xy 275.636047 -418.602393) (xy 275.597807 -418.644133)
			(xy 275.55382 -418.679765) (xy 275.50505 -418.708506) (xy 275.452569 -418.729725) (xy 275.425154 -418.73678)
			(xy 275.411184 -418.740336) (xy 272.13687 -422.01465) (xy 272.118879 -422.031994) (xy 272.078459 -422.061377)
			(xy 272.03394 -422.084074) (xy 271.986419 -422.099529) (xy 271.937065 -422.107358) (xy 271.91208 -422.107868)
			(xy 243.166392 -422.107868) (xy 243.096542 -422.177464) (xy 243.140738 -422.22166) (xy 243.151914 -422.22547)
			(xy 243.176577 -422.234476) (xy 243.223365 -422.258299) (xy 243.266448 -422.288308) (xy 243.305014 -422.323935)
			(xy 243.338336 -422.364511) (xy 243.365784 -422.409268) (xy 243.386842 -422.457364) (xy 243.401113 -422.507892)
			(xy 243.408326 -422.559898) (xy 243.408708 -422.58615) (xy 243.408189 -422.614558) (xy 243.39977 -422.670747)
			(xy 243.383112 -422.725065) (xy 243.358582 -422.776313) (xy 243.326723 -422.823356) (xy 243.288239 -422.865154)
			(xy 243.243983 -422.900782) (xy 243.219732 -422.915588) (xy 243.2077 -422.923181) (xy 243.188072 -422.943761)
			(xy 243.174877 -422.968954) (xy 243.169137 -422.996808) (xy 243.171298 -423.025165) (xy 243.181191 -423.051828)
			(xy 243.198051 -423.074731) (xy 243.209064 -423.083736) (xy 243.231804 -423.101929) (xy 243.272023 -423.144043)
			(xy 243.305378 -423.191778) (xy 243.331094 -423.244026) (xy 243.342679 -423.28084) (xy 282.347922 -423.28084)
			(xy 282.351993 -423.225218) (xy 282.364119 -423.170781) (xy 282.384042 -423.11869) (xy 282.411338 -423.070055)
			(xy 282.445424 -423.025912) (xy 282.485573 -422.987203) (xy 282.530931 -422.954752) (xy 282.580531 -422.929251)
			(xy 282.633315 -422.911244) (xy 282.688158 -422.901114) (xy 282.743892 -422.899077) (xy 282.799329 -422.905177)
			(xy 282.853286 -422.919283) (xy 282.904615 -422.941095) (xy 282.952221 -422.970149) (xy 282.995089 -423.005824)
			(xy 283.032306 -423.047361) (xy 283.063079 -423.093874) (xy 283.086751 -423.144371) (xy 283.102819 -423.197778)
			(xy 283.110939 -423.252954) (xy 283.111448 -423.28084) (xy 283.110939 -423.308726) (xy 283.102819 -423.363902)
			(xy 283.086751 -423.417309) (xy 283.063079 -423.467806) (xy 283.032306 -423.514319) (xy 282.995089 -423.555856)
			(xy 282.952221 -423.591531) (xy 282.904615 -423.620585) (xy 282.853286 -423.642397) (xy 282.799329 -423.656503)
			(xy 282.743892 -423.662603) (xy 282.688158 -423.660566) (xy 282.633315 -423.650436) (xy 282.580531 -423.632429)
			(xy 282.530931 -423.606928) (xy 282.485573 -423.574477) (xy 282.445424 -423.535768) (xy 282.411338 -423.491625)
			(xy 282.384042 -423.44299) (xy 282.364119 -423.390899) (xy 282.351993 -423.336462) (xy 282.347922 -423.28084)
			(xy 243.342679 -423.28084) (xy 243.348575 -423.299574) (xy 243.357414 -423.357133) (xy 243.357908 -423.38625)
			(xy 243.357422 -423.413501) (xy 243.349666 -423.467449) (xy 243.334311 -423.519744) (xy 243.311669 -423.569321)
			(xy 243.282203 -423.615171) (xy 243.246512 -423.656362) (xy 243.205321 -423.692053) (xy 243.159471 -423.721519)
			(xy 243.109894 -423.744161) (xy 243.057599 -423.759516) (xy 243.003651 -423.767272) (xy 242.949149 -423.767272)
			(xy 242.895201 -423.759516) (xy 242.842906 -423.744161) (xy 242.793329 -423.721519) (xy 242.747479 -423.692053)
			(xy 242.706288 -423.656362) (xy 242.670597 -423.615171) (xy 242.641131 -423.569321) (xy 242.618489 -423.519744)
			(xy 242.603134 -423.467449) (xy 242.595378 -423.413501) (xy 242.594892 -423.38625) (xy 242.595411 -423.357842)
			(xy 242.60383 -423.301653) (xy 242.620488 -423.247335) (xy 242.645018 -423.196087) (xy 242.676877 -423.149044)
			(xy 242.715361 -423.107246) (xy 242.759617 -423.071618) (xy 242.783868 -423.056812) (xy 242.7959 -423.049219)
			(xy 242.815528 -423.028639) (xy 242.828723 -423.003446) (xy 242.834463 -422.975592) (xy 242.832302 -422.947235)
			(xy 242.822409 -422.920572) (xy 242.805549 -422.897669) (xy 242.794536 -422.888664) (xy 242.773622 -422.872018)
			(xy 242.73621 -422.833841) (xy 242.704493 -422.790816) (xy 242.691412 -422.767506) (xy 242.684631 -422.755806)
			(xy 242.666006 -422.736211) (xy 242.642886 -422.722202) (xy 242.616895 -422.714765) (xy 242.589864 -422.714422)
			(xy 242.563693 -422.721199) (xy 242.540225 -422.734617) (xy 242.530376 -422.743884) (xy 241.05108 -424.22318)
			(xy 241.05108 -425.152148) (xy 276.956434 -425.152148) (xy 276.956435 -425.097638) (xy 276.964194 -425.043684)
			(xy 276.979553 -424.991382) (xy 277.002198 -424.941799) (xy 277.03167 -424.895943) (xy 277.067367 -424.854749)
			(xy 277.108565 -424.819054) (xy 277.154422 -424.789585) (xy 277.204007 -424.766943) (xy 277.25631 -424.751588)
			(xy 277.310265 -424.743834) (xy 277.33752 -424.743372) (xy 277.360289 -424.743721) (xy 277.405495 -424.749201)
			(xy 277.42769 -424.754294) (xy 277.441172 -424.757127) (xy 277.468696 -424.756194) (xy 277.494973 -424.747948)
			(xy 277.518097 -424.732989) (xy 277.536389 -424.7124) (xy 277.548522 -424.687677) (xy 277.553617 -424.660612)
			(xy 277.552912 -424.646852) (xy 277.551642 -424.61434) (xy 277.552112 -424.587083) (xy 277.559865 -424.533123)
			(xy 277.575219 -424.480815) (xy 277.597861 -424.431226) (xy 277.62733 -424.385363) (xy 277.663026 -424.344162)
			(xy 277.704223 -424.30846) (xy 277.750082 -424.278985) (xy 277.799668 -424.256336) (xy 277.851974 -424.240976)
			(xy 277.905933 -424.233216) (xy 277.960447 -424.233214) (xy 278.014407 -424.240971) (xy 278.066713 -424.256329)
			(xy 278.116301 -424.278975) (xy 278.162161 -424.308448) (xy 278.20336 -424.344147) (xy 278.239058 -424.385347)
			(xy 278.26853 -424.431208) (xy 278.291174 -424.480797) (xy 278.306531 -424.533103) (xy 278.314286 -424.587063)
			(xy 278.314284 -424.641577) (xy 278.306522 -424.695536) (xy 278.29116 -424.747841) (xy 278.268511 -424.797427)
			(xy 278.239034 -424.843285) (xy 278.203331 -424.884481) (xy 278.162129 -424.920176) (xy 278.116266 -424.949644)
			(xy 278.066675 -424.972285) (xy 278.014367 -424.987637) (xy 277.960407 -424.995389) (xy 277.93315 -424.995848)
			(xy 277.910382 -424.995486) (xy 277.865175 -424.990015) (xy 277.84298 -424.984926) (xy 277.829492 -424.982146)
			(xy 277.80198 -424.983087) (xy 277.775716 -424.991331) (xy 277.752601 -425.006283) (xy 277.734312 -425.026857)
			(xy 277.722173 -425.051564) (xy 277.717063 -425.078614) (xy 277.717758 -425.092368) (xy 277.719028 -425.12488)
			(xy 277.718566 -425.152135) (xy 277.710812 -425.20609) (xy 277.695457 -425.258393) (xy 277.672815 -425.307978)
			(xy 277.643346 -425.353835) (xy 277.607651 -425.395033) (xy 277.566457 -425.43073) (xy 277.520601 -425.460202)
			(xy 277.471018 -425.482847) (xy 277.418716 -425.498206) (xy 277.364762 -425.505965) (xy 277.310252 -425.505966)
			(xy 277.256297 -425.498209) (xy 277.203995 -425.482852) (xy 277.154411 -425.460208) (xy 277.108554 -425.430738)
			(xy 277.067358 -425.395042) (xy 277.031662 -425.353846) (xy 277.002192 -425.307989) (xy 276.979548 -425.258405)
			(xy 276.964191 -425.206103) (xy 276.956434 -425.152148) (xy 241.05108 -425.152148) (xy 241.05108 -426.7708)
			(xy 281.131262 -426.7708) (xy 281.135333 -426.715178) (xy 281.147459 -426.660741) (xy 281.167382 -426.60865)
			(xy 281.194678 -426.560015) (xy 281.228764 -426.515872) (xy 281.268913 -426.477163) (xy 281.314271 -426.444712)
			(xy 281.363871 -426.419211) (xy 281.416655 -426.401204) (xy 281.471498 -426.391074) (xy 281.527232 -426.389037)
			(xy 281.582669 -426.395137) (xy 281.636626 -426.409243) (xy 281.687955 -426.431055) (xy 281.735561 -426.460109)
			(xy 281.778429 -426.495784) (xy 281.815646 -426.537321) (xy 281.846419 -426.583834) (xy 281.870091 -426.634331)
			(xy 281.886159 -426.687738) (xy 281.894279 -426.742914) (xy 281.894788 -426.7708) (xy 281.894279 -426.798686)
			(xy 281.886159 -426.853862) (xy 281.870091 -426.907269) (xy 281.846419 -426.957766) (xy 281.815646 -427.004279)
			(xy 281.778429 -427.045816) (xy 281.735561 -427.081491) (xy 281.687955 -427.110545) (xy 281.636626 -427.132357)
			(xy 281.582669 -427.146463) (xy 281.527232 -427.152563) (xy 281.471498 -427.150526) (xy 281.416655 -427.140396)
			(xy 281.363871 -427.122389) (xy 281.314271 -427.096888) (xy 281.268913 -427.064437) (xy 281.228764 -427.025728)
			(xy 281.194678 -426.981585) (xy 281.167382 -426.93295) (xy 281.147459 -426.880859) (xy 281.135333 -426.826422)
			(xy 281.131262 -426.7708) (xy 241.05108 -426.7708) (xy 241.05108 -436.13324) (xy 241.78514 -436.8673)
		)
		(stroke
			(width 0)
			(type solid)
		)
		(fill yes)
		(layer "In11.Cu")
		(net "GND")
	)
	(gr_poly
		(pts
			(xy 102.964234 -265.270488) (xy 102.967028 -265.254994) (xy 102.971964 -265.230465) (xy 102.988247 -265.183157)
			(xy 103.011477 -265.138845) (xy 103.041122 -265.098541) (xy 103.076505 -265.063168) (xy 103.116816 -265.033533)
			(xy 103.161134 -265.010314) (xy 103.208447 -264.994043) (xy 103.232966 -264.989056) (xy 103.24846 -264.986262)
			(xy 103.512874 -264.721848) (xy 103.488998 -264.68705) (xy 103.47537 -264.666317) (xy 103.453812 -264.621631)
			(xy 103.439168 -264.574227) (xy 103.431766 -264.525167) (xy 103.43134 -264.50036) (xy 103.431852 -264.474395)
			(xy 103.439981 -264.423104) (xy 103.456034 -264.373717) (xy 103.479613 -264.327448) (xy 103.51014 -264.285437)
			(xy 103.546863 -264.248718) (xy 103.588877 -264.218196) (xy 103.635148 -264.194621) (xy 103.684537 -264.178574)
			(xy 103.735829 -264.17045) (xy 103.761794 -264.169906) (xy 103.786603 -264.17033) (xy 103.835668 -264.17771)
			(xy 103.883076 -264.192351) (xy 103.927758 -264.213923) (xy 103.948484 -264.227564) (xy 103.983282 -264.25144)
			(xy 105.047796 -263.186926) (xy 105.047796 -261.570978) (xy 105.03027 -261.553198) (xy 105.020437 -261.543218)
			(xy 104.996553 -261.528592) (xy 104.969597 -261.520993) (xy 104.941591 -261.520993) (xy 104.914635 -261.528592)
			(xy 104.890751 -261.543218) (xy 104.880918 -261.553198) (xy 104.862008 -261.572894) (xy 104.818912 -261.606416)
			(xy 104.770889 -261.63239) (xy 104.719247 -261.65011) (xy 104.665393 -261.659091) (xy 104.638094 -261.659624)
			(xy 104.612129 -261.659114) (xy 104.56084 -261.65099) (xy 104.511452 -261.634942) (xy 104.465184 -261.611366)
			(xy 104.423172 -261.580843) (xy 104.386453 -261.544123) (xy 104.35593 -261.502111) (xy 104.332355 -261.455842)
			(xy 104.316309 -261.406454) (xy 104.308185 -261.355165) (xy 104.308185 -261.303235) (xy 104.316309 -261.251946)
			(xy 104.332355 -261.202558) (xy 104.35593 -261.156289) (xy 104.386453 -261.114277) (xy 104.423172 -261.077557)
			(xy 104.465184 -261.047034) (xy 104.511452 -261.023458) (xy 104.56084 -261.00741) (xy 104.612129 -260.999286)
			(xy 104.638094 -260.998716) (xy 104.665392 -260.999278) (xy 104.719244 -261.008255) (xy 104.770887 -261.025967)
			(xy 104.818914 -261.05193) (xy 104.862018 -261.085438) (xy 104.880918 -261.105142) (xy 104.890751 -261.115122)
			(xy 104.914635 -261.129748) (xy 104.941591 -261.137347) (xy 104.969597 -261.137347) (xy 104.996553 -261.129748)
			(xy 105.020437 -261.115122) (xy 105.03027 -261.105142) (xy 105.047796 -261.087362) (xy 105.047796 -257.192526)
			(xy 104.615996 -256.760726) (xy 103.117396 -256.760726) (xy 102.682548 -257.195574) (xy 102.680516 -257.2131)
			(xy 102.677246 -257.237514) (xy 102.664408 -257.285069) (xy 102.644652 -257.33019) (xy 102.618416 -257.371878)
			(xy 102.586282 -257.409208) (xy 102.548961 -257.441355) (xy 102.507282 -257.467604) (xy 102.462167 -257.487374)
			(xy 102.414617 -257.500227) (xy 102.390194 -257.503422) (xy 102.372668 -257.505454) (xy 102.121208 -257.756914)
			(xy 102.14737 -257.791966) (xy 102.162726 -257.813469) (xy 102.187119 -257.860337) (xy 102.203737 -257.910491)
			(xy 102.212156 -257.962652) (xy 102.212648 -257.98907) (xy 102.212167 -258.015041) (xy 102.204046 -258.066343)
			(xy 102.187999 -258.115743) (xy 102.164421 -258.162025) (xy 102.133892 -258.204047) (xy 102.097166 -258.240777)
			(xy 102.055145 -258.271308) (xy 102.008865 -258.29489) (xy 101.959466 -258.31094) (xy 101.908165 -258.319066)
			(xy 101.882194 -258.319524) (xy 101.860459 -258.319178) (xy 101.817364 -258.313473) (xy 101.775391 -258.302164)
			(xy 101.755194 -258.294124) (xy 101.740968 -258.288809) (xy 101.710758 -258.285881) (xy 101.681018 -258.291942)
			(xy 101.654362 -258.306457) (xy 101.633134 -258.328151) (xy 101.625654 -258.341368) (xy 101.617178 -258.357619)
			(xy 101.598883 -258.389383) (xy 101.589078 -258.404868) (xy 101.581359 -258.417927) (xy 101.573198 -258.447125)
			(xy 101.573973 -258.477433) (xy 101.583615 -258.506177) (xy 101.601274 -258.530821) (xy 101.612954 -258.540504)
			(xy 101.632759 -258.556261) (xy 101.667802 -258.592775) (xy 101.696877 -258.634199) (xy 101.719304 -258.679567)
			(xy 101.734561 -258.727821) (xy 101.742292 -258.777836) (xy 101.742748 -258.80314) (xy 101.742236 -258.829105)
			(xy 101.742236 -258.829107) (xy 102.021895 -258.829107) (xy 102.021895 -258.777173) (xy 102.03002 -258.725878)
			(xy 102.046068 -258.676485) (xy 102.069646 -258.630211) (xy 102.100172 -258.588195) (xy 102.136895 -258.551472)
			(xy 102.178911 -258.520946) (xy 102.225185 -258.497368) (xy 102.274578 -258.48132) (xy 102.325873 -258.473195)
			(xy 102.377807 -258.473195) (xy 102.429102 -258.48132) (xy 102.478495 -258.497368) (xy 102.524769 -258.520946)
			(xy 102.566785 -258.551472) (xy 102.603508 -258.588195) (xy 102.634034 -258.630211) (xy 102.657612 -258.676485)
			(xy 102.67366 -258.725878) (xy 102.681785 -258.777173) (xy 102.682294 -258.80314) (xy 102.681785 -258.829107)
			(xy 102.67366 -258.880402) (xy 102.657612 -258.929795) (xy 102.634034 -258.976069) (xy 102.603508 -259.018085)
			(xy 102.566785 -259.054808) (xy 102.524769 -259.085334) (xy 102.478495 -259.108912) (xy 102.429102 -259.12496)
			(xy 102.377807 -259.133085) (xy 102.325873 -259.133085) (xy 102.274578 -259.12496) (xy 102.225185 -259.108912)
			(xy 102.178911 -259.085334) (xy 102.136895 -259.054808) (xy 102.100172 -259.018085) (xy 102.069646 -258.976069)
			(xy 102.046068 -258.929795) (xy 102.03002 -258.880402) (xy 102.021895 -258.829107) (xy 101.742236 -258.829107)
			(xy 101.734106 -258.880395) (xy 101.718054 -258.929782) (xy 101.694474 -258.97605) (xy 101.663947 -259.018059)
			(xy 101.627224 -259.054777) (xy 101.58521 -259.085298) (xy 101.538939 -259.108872) (xy 101.48955 -259.124917)
			(xy 101.438259 -259.133039) (xy 101.412294 -259.133594) (xy 101.390559 -259.133248) (xy 101.347464 -259.127543)
			(xy 101.305491 -259.116232) (xy 101.285294 -259.108194) (xy 101.27107 -259.102876) (xy 101.240862 -259.099946)
			(xy 101.211123 -259.106009) (xy 101.184472 -259.12053) (xy 101.163256 -259.142233) (xy 101.155754 -259.155438)
			(xy 101.147271 -259.171623) (xy 101.128975 -259.203259) (xy 101.119178 -259.218684) (xy 101.111468 -259.231745)
			(xy 101.10332 -259.260942) (xy 101.104098 -259.291245) (xy 101.113734 -259.319986) (xy 101.131381 -259.344633)
			(xy 101.143054 -259.35432) (xy 101.162859 -259.370078) (xy 101.1979 -259.406591) (xy 101.226972 -259.448016)
			(xy 101.249397 -259.493384) (xy 101.264652 -259.541638) (xy 101.27238 -259.591652) (xy 101.272848 -259.616956)
			(xy 101.272343 -259.642923) (xy 101.552249 -259.642923) (xy 101.552249 -259.590989) (xy 101.560374 -259.539694)
			(xy 101.576422 -259.490301) (xy 101.6 -259.444027) (xy 101.630526 -259.402011) (xy 101.667249 -259.365288)
			(xy 101.709265 -259.334762) (xy 101.755539 -259.311184) (xy 101.804932 -259.295136) (xy 101.856227 -259.287011)
			(xy 101.908161 -259.287011) (xy 101.959456 -259.295136) (xy 102.008849 -259.311184) (xy 102.055123 -259.334762)
			(xy 102.097139 -259.365288) (xy 102.133862 -259.402011) (xy 102.164388 -259.444027) (xy 102.187966 -259.490301)
			(xy 102.204014 -259.539694) (xy 102.212139 -259.590989) (xy 102.212648 -259.616956) (xy 102.212139 -259.642923)
			(xy 102.204014 -259.694218) (xy 102.194849 -259.722425) (xy 102.536499 -259.722425) (xy 102.536499 -259.670491)
			(xy 102.544624 -259.619196) (xy 102.560672 -259.569803) (xy 102.58425 -259.523529) (xy 102.614776 -259.481513)
			(xy 102.651499 -259.44479) (xy 102.693515 -259.414264) (xy 102.739789 -259.390686) (xy 102.789182 -259.374638)
			(xy 102.840477 -259.366513) (xy 102.892411 -259.366513) (xy 102.943706 -259.374638) (xy 102.993099 -259.390686)
			(xy 103.039373 -259.414264) (xy 103.081389 -259.44479) (xy 103.118112 -259.481513) (xy 103.148638 -259.523529)
			(xy 103.172216 -259.569803) (xy 103.188264 -259.619196) (xy 103.196389 -259.670491) (xy 103.196898 -259.696458)
			(xy 103.196389 -259.722425) (xy 103.188264 -259.77372) (xy 103.172216 -259.823113) (xy 103.148638 -259.869387)
			(xy 103.118112 -259.911403) (xy 103.081389 -259.948126) (xy 103.039373 -259.978652) (xy 102.993099 -260.00223)
			(xy 102.943706 -260.018278) (xy 102.892411 -260.026403) (xy 102.840477 -260.026403) (xy 102.789182 -260.018278)
			(xy 102.739789 -260.00223) (xy 102.693515 -259.978652) (xy 102.651499 -259.948126) (xy 102.614776 -259.911403)
			(xy 102.58425 -259.869387) (xy 102.560672 -259.823113) (xy 102.544624 -259.77372) (xy 102.536499 -259.722425)
			(xy 102.194849 -259.722425) (xy 102.187966 -259.743611) (xy 102.164388 -259.789885) (xy 102.133862 -259.831901)
			(xy 102.097139 -259.868624) (xy 102.055123 -259.89915) (xy 102.008849 -259.922728) (xy 101.959456 -259.938776)
			(xy 101.908161 -259.946901) (xy 101.856227 -259.946901) (xy 101.804932 -259.938776) (xy 101.755539 -259.922728)
			(xy 101.709265 -259.89915) (xy 101.667249 -259.868624) (xy 101.630526 -259.831901) (xy 101.6 -259.789885)
			(xy 101.576422 -259.743611) (xy 101.560374 -259.694218) (xy 101.552249 -259.642923) (xy 101.272343 -259.642923)
			(xy 101.272326 -259.643813) (xy 101.26364 -259.696819) (xy 101.246491 -259.747721) (xy 101.221331 -259.795177)
			(xy 101.188822 -259.837936) (xy 101.149822 -259.87487) (xy 101.105359 -259.905006) (xy 101.056605 -259.927549)
			(xy 101.004846 -259.941905) (xy 100.978208 -259.945378) (xy 100.932996 -259.950458) (xy 100.932996 -260.456739)
			(xy 101.082603 -260.456739) (xy 101.082603 -260.404805) (xy 101.090728 -260.35351) (xy 101.106776 -260.304117)
			(xy 101.130354 -260.257843) (xy 101.16088 -260.215827) (xy 101.197603 -260.179104) (xy 101.239619 -260.148578)
			(xy 101.285893 -260.125) (xy 101.335286 -260.108952) (xy 101.386581 -260.100827) (xy 101.438515 -260.100827)
			(xy 101.48981 -260.108952) (xy 101.539203 -260.125) (xy 101.585477 -260.148578) (xy 101.627493 -260.179104)
			(xy 101.664216 -260.215827) (xy 101.694742 -260.257843) (xy 101.71832 -260.304117) (xy 101.734368 -260.35351)
			(xy 101.742493 -260.404805) (xy 101.743002 -260.430772) (xy 101.742493 -260.456739) (xy 101.742487 -260.456774)
			(xy 102.022301 -260.456774) (xy 102.022301 -260.404826) (xy 102.030428 -260.353518) (xy 102.046482 -260.304113)
			(xy 102.070068 -260.257828) (xy 102.100605 -260.215804) (xy 102.13734 -260.179074) (xy 102.179369 -260.148543)
			(xy 102.225658 -260.124964) (xy 102.275065 -260.108917) (xy 102.326374 -260.100797) (xy 102.352348 -260.100318)
			(xy 102.379433 -260.10093) (xy 102.432877 -260.109757) (xy 102.484166 -260.127184) (xy 102.531926 -260.152744)
			(xy 102.574877 -260.185751) (xy 102.611869 -260.225323) (xy 102.64191 -260.270398) (xy 102.664197 -260.31977)
			(xy 102.678132 -260.372115) (xy 102.681278 -260.399022) (xy 102.683079 -260.413169) (xy 102.693479 -260.439712)
			(xy 102.71082 -260.462338) (xy 102.733745 -260.479281) (xy 102.760465 -260.489217) (xy 102.788891 -260.491369)
			(xy 102.802944 -260.488938) (xy 102.819398 -260.485756) (xy 102.852735 -260.48232) (xy 102.869492 -260.48208)
			(xy 102.895464 -260.482494) (xy 102.94677 -260.490619) (xy 102.996172 -260.50667) (xy 103.042456 -260.530252)
			(xy 103.084481 -260.560783) (xy 103.121211 -260.597513) (xy 103.151744 -260.639537) (xy 103.175327 -260.68582)
			(xy 103.191379 -260.735222) (xy 103.199505 -260.786528) (xy 103.199505 -260.838472) (xy 103.191379 -260.889778)
			(xy 103.175327 -260.93918) (xy 103.151744 -260.985463) (xy 103.121211 -261.027487) (xy 103.084481 -261.064217)
			(xy 103.042456 -261.094748) (xy 102.996172 -261.11833) (xy 102.94677 -261.134381) (xy 102.895464 -261.142506)
			(xy 102.869492 -261.142988) (xy 102.842406 -261.142426) (xy 102.788959 -261.133589) (xy 102.73767 -261.116154)
			(xy 102.68991 -261.090587) (xy 102.64696 -261.057574) (xy 102.609969 -261.017997) (xy 102.579929 -260.972917)
			(xy 102.557643 -260.923542) (xy 102.543708 -260.871192) (xy 102.540562 -260.844284) (xy 102.53871 -260.830146)
			(xy 102.528317 -260.80361) (xy 102.510986 -260.780987) (xy 102.488071 -260.764043) (xy 102.461362 -260.754103)
			(xy 102.432946 -260.751943) (xy 102.418896 -260.754368) (xy 102.402444 -260.757559) (xy 102.369105 -260.760989)
			(xy 102.352348 -260.761226) (xy 102.326374 -260.760803) (xy 102.275065 -260.752683) (xy 102.225658 -260.736636)
			(xy 102.179369 -260.713057) (xy 102.13734 -260.682526) (xy 102.100605 -260.645796) (xy 102.070068 -260.603772)
			(xy 102.046482 -260.557487) (xy 102.030428 -260.508082) (xy 102.022301 -260.456774) (xy 101.742487 -260.456774)
			(xy 101.734368 -260.508034) (xy 101.71832 -260.557427) (xy 101.694742 -260.603701) (xy 101.664216 -260.645717)
			(xy 101.627493 -260.68244) (xy 101.585477 -260.712966) (xy 101.539203 -260.736544) (xy 101.48981 -260.752592)
			(xy 101.438515 -260.760717) (xy 101.386581 -260.760717) (xy 101.335286 -260.752592) (xy 101.285893 -260.736544)
			(xy 101.239619 -260.712966) (xy 101.197603 -260.68244) (xy 101.16088 -260.645717) (xy 101.130354 -260.603701)
			(xy 101.106776 -260.557427) (xy 101.090728 -260.508034) (xy 101.082603 -260.456739) (xy 100.932996 -260.456739)
			(xy 100.932996 -260.91134) (xy 100.978208 -260.91642) (xy 101.003443 -260.919643) (xy 101.05257 -260.932845)
			(xy 101.099093 -260.953423) (xy 101.141911 -260.98089) (xy 101.180012 -261.014597) (xy 101.212495 -261.053746)
			(xy 101.238593 -261.097412) (xy 101.257687 -261.144563) (xy 101.269327 -261.194084) (xy 101.273237 -261.244805)
			(xy 101.271231 -261.270809) (xy 101.552249 -261.270809) (xy 101.552249 -261.218875) (xy 101.560374 -261.16758)
			(xy 101.576422 -261.118187) (xy 101.6 -261.071913) (xy 101.630526 -261.029897) (xy 101.667249 -260.993174)
			(xy 101.709265 -260.962648) (xy 101.755539 -260.93907) (xy 101.804932 -260.923022) (xy 101.856227 -260.914897)
			(xy 101.908161 -260.914897) (xy 101.959456 -260.923022) (xy 102.008849 -260.93907) (xy 102.055123 -260.962648)
			(xy 102.097139 -260.993174) (xy 102.133862 -261.029897) (xy 102.164388 -261.071913) (xy 102.187966 -261.118187)
			(xy 102.204014 -261.16758) (xy 102.212139 -261.218875) (xy 102.212648 -261.244842) (xy 102.212139 -261.270809)
			(xy 102.204014 -261.322104) (xy 102.187966 -261.371497) (xy 102.164388 -261.417771) (xy 102.133862 -261.459787)
			(xy 102.097139 -261.49651) (xy 102.055123 -261.527036) (xy 102.008849 -261.550614) (xy 101.959456 -261.566662)
			(xy 101.908161 -261.574787) (xy 101.856227 -261.574787) (xy 101.804932 -261.566662) (xy 101.755539 -261.550614)
			(xy 101.709265 -261.527036) (xy 101.667249 -261.49651) (xy 101.630526 -261.459787) (xy 101.6 -261.417771)
			(xy 101.576422 -261.371497) (xy 101.560374 -261.322104) (xy 101.552249 -261.270809) (xy 101.271231 -261.270809)
			(xy 101.269325 -261.295525) (xy 101.257684 -261.345045) (xy 101.238588 -261.392196) (xy 101.21249 -261.435862)
			(xy 101.180006 -261.47501) (xy 101.141904 -261.508715) (xy 101.099085 -261.536181) (xy 101.052562 -261.556758)
			(xy 101.003434 -261.569959) (xy 100.978208 -261.573264) (xy 100.932996 -261.578344) (xy 100.932996 -262.084625)
			(xy 101.082603 -262.084625) (xy 101.082603 -262.032691) (xy 101.090728 -261.981396) (xy 101.106776 -261.932003)
			(xy 101.130354 -261.885729) (xy 101.16088 -261.843713) (xy 101.197603 -261.80699) (xy 101.239619 -261.776464)
			(xy 101.285893 -261.752886) (xy 101.335286 -261.736838) (xy 101.386581 -261.728713) (xy 101.438515 -261.728713)
			(xy 101.48981 -261.736838) (xy 101.539203 -261.752886) (xy 101.585477 -261.776464) (xy 101.627493 -261.80699)
			(xy 101.664216 -261.843713) (xy 101.694742 -261.885729) (xy 101.71832 -261.932003) (xy 101.734368 -261.981396)
			(xy 101.742493 -262.032691) (xy 101.743002 -262.058658) (xy 101.742493 -262.084625) (xy 102.022403 -262.084625)
			(xy 102.022403 -262.032691) (xy 102.030528 -261.981396) (xy 102.046576 -261.932003) (xy 102.070154 -261.885729)
			(xy 102.10068 -261.843713) (xy 102.137403 -261.80699) (xy 102.179419 -261.776464) (xy 102.225693 -261.752886)
			(xy 102.275086 -261.736838) (xy 102.326381 -261.728713) (xy 102.378315 -261.728713) (xy 102.42961 -261.736838)
			(xy 102.479003 -261.752886) (xy 102.525277 -261.776464) (xy 102.567293 -261.80699) (xy 102.604016 -261.843713)
			(xy 102.634542 -261.885729) (xy 102.65812 -261.932003) (xy 102.674168 -261.981396) (xy 102.682293 -262.032691)
			(xy 102.682802 -262.058658) (xy 102.682293 -262.084625) (xy 102.674168 -262.13592) (xy 102.65812 -262.185313)
			(xy 102.634542 -262.231587) (xy 102.604016 -262.273603) (xy 102.567293 -262.310326) (xy 102.525277 -262.340852)
			(xy 102.479003 -262.36443) (xy 102.42961 -262.380478) (xy 102.378315 -262.388603) (xy 102.326381 -262.388603)
			(xy 102.275086 -262.380478) (xy 102.225693 -262.36443) (xy 102.179419 -262.340852) (xy 102.137403 -262.310326)
			(xy 102.10068 -262.273603) (xy 102.070154 -262.231587) (xy 102.046576 -262.185313) (xy 102.030528 -262.13592)
			(xy 102.022403 -262.084625) (xy 101.742493 -262.084625) (xy 101.734368 -262.13592) (xy 101.71832 -262.185313)
			(xy 101.694742 -262.231587) (xy 101.664216 -262.273603) (xy 101.627493 -262.310326) (xy 101.585477 -262.340852)
			(xy 101.539203 -262.36443) (xy 101.48981 -262.380478) (xy 101.438515 -262.388603) (xy 101.386581 -262.388603)
			(xy 101.335286 -262.380478) (xy 101.285893 -262.36443) (xy 101.239619 -262.340852) (xy 101.197603 -262.310326)
			(xy 101.16088 -262.273603) (xy 101.130354 -262.231587) (xy 101.106776 -262.185313) (xy 101.090728 -262.13592)
			(xy 101.082603 -262.084625) (xy 100.932996 -262.084625) (xy 100.932996 -262.538972) (xy 100.978208 -262.544052)
			(xy 101.003448 -262.547275) (xy 101.052586 -262.560479) (xy 101.099119 -262.58106) (xy 101.141946 -262.608531)
			(xy 101.180056 -262.642244) (xy 101.212547 -262.681401) (xy 101.226552 -262.704834) (xy 103.384096 -262.704834)
			(xy 103.38452 -262.680281) (xy 103.391763 -262.631713) (xy 103.40611 -262.584751) (xy 103.427246 -262.540427)
			(xy 103.454705 -262.499717) (xy 103.470964 -262.481314) (xy 103.480735 -262.469799) (xy 103.493754 -262.442572)
			(xy 103.49823 -262.412725) (xy 103.493769 -262.382877) (xy 103.480763 -262.355642) (xy 103.470964 -262.344154)
			(xy 103.454719 -262.325738) (xy 103.427247 -262.285038) (xy 103.406105 -262.240718) (xy 103.391759 -262.193755)
			(xy 103.384526 -262.145187) (xy 103.384096 -262.120634) (xy 103.384605 -262.094667) (xy 103.39273 -262.043372)
			(xy 103.408778 -261.993979) (xy 103.432356 -261.947705) (xy 103.462882 -261.905689) (xy 103.499605 -261.868966)
			(xy 103.541621 -261.83844) (xy 103.587895 -261.814862) (xy 103.637288 -261.798814) (xy 103.688583 -261.790689)
			(xy 103.740517 -261.790689) (xy 103.791812 -261.798814) (xy 103.841205 -261.814862) (xy 103.887479 -261.83844)
			(xy 103.929495 -261.868966) (xy 103.966218 -261.905689) (xy 103.996744 -261.947705) (xy 104.020322 -261.993979)
			(xy 104.03637 -262.043372) (xy 104.044495 -262.094667) (xy 104.045004 -262.120634) (xy 104.044561 -262.145186)
			(xy 104.037322 -262.193753) (xy 104.022979 -262.240715) (xy 104.001848 -262.285039) (xy 103.974393 -262.32575)
			(xy 103.958136 -262.344154) (xy 103.948298 -262.355617) (xy 103.935287 -262.382863) (xy 103.930824 -262.412725)
			(xy 103.935302 -262.442585) (xy 103.948327 -262.469825) (xy 103.958136 -262.481314) (xy 103.974413 -262.499703)
			(xy 104.001881 -262.540411) (xy 104.023017 -262.584737) (xy 104.037355 -262.631706) (xy 104.044579 -262.68028)
			(xy 104.045004 -262.704834) (xy 104.044495 -262.730801) (xy 104.03637 -262.782096) (xy 104.020322 -262.831489)
			(xy 103.996744 -262.877763) (xy 103.966218 -262.919779) (xy 103.929495 -262.956502) (xy 103.887479 -262.987028)
			(xy 103.841205 -263.010606) (xy 103.791812 -263.026654) (xy 103.740517 -263.034779) (xy 103.688583 -263.034779)
			(xy 103.637288 -263.026654) (xy 103.587895 -263.010606) (xy 103.541621 -262.987028) (xy 103.499605 -262.956502)
			(xy 103.462882 -262.919779) (xy 103.432356 -262.877763) (xy 103.408778 -262.831489) (xy 103.39273 -262.782096)
			(xy 103.384605 -262.730801) (xy 103.384096 -262.704834) (xy 101.226552 -262.704834) (xy 101.23865 -262.725075)
			(xy 101.257749 -262.772236) (xy 101.269393 -262.821767) (xy 101.273305 -262.872497) (xy 101.269394 -262.923228)
			(xy 101.257751 -262.972759) (xy 101.238653 -263.01992) (xy 101.21255 -263.063595) (xy 101.18006 -263.102752)
			(xy 101.141951 -263.136465) (xy 101.099124 -263.163938) (xy 101.052591 -263.184519) (xy 101.003453 -263.197724)
			(xy 100.978208 -263.200896) (xy 100.932996 -263.205976) (xy 100.932996 -263.712511) (xy 101.082349 -263.712511)
			(xy 101.082349 -263.660577) (xy 101.090474 -263.609282) (xy 101.106522 -263.559889) (xy 101.1301 -263.513615)
			(xy 101.160626 -263.471599) (xy 101.197349 -263.434876) (xy 101.239365 -263.40435) (xy 101.285639 -263.380772)
			(xy 101.335032 -263.364724) (xy 101.386327 -263.356599) (xy 101.438261 -263.356599) (xy 101.489556 -263.364724)
			(xy 101.538949 -263.380772) (xy 101.585223 -263.40435) (xy 101.627239 -263.434876) (xy 101.663962 -263.471599)
			(xy 101.694488 -263.513615) (xy 101.718066 -263.559889) (xy 101.734114 -263.609282) (xy 101.742239 -263.660577)
			(xy 101.742748 -263.686544) (xy 101.742239 -263.712511) (xy 102.022403 -263.712511) (xy 102.022403 -263.660577)
			(xy 102.030528 -263.609282) (xy 102.046576 -263.559889) (xy 102.070154 -263.513615) (xy 102.10068 -263.471599)
			(xy 102.137403 -263.434876) (xy 102.179419 -263.40435) (xy 102.225693 -263.380772) (xy 102.275086 -263.364724)
			(xy 102.326381 -263.356599) (xy 102.378315 -263.356599) (xy 102.42961 -263.364724) (xy 102.479003 -263.380772)
			(xy 102.525277 -263.40435) (xy 102.567293 -263.434876) (xy 102.604016 -263.471599) (xy 102.634542 -263.513615)
			(xy 102.65812 -263.559889) (xy 102.674168 -263.609282) (xy 102.682293 -263.660577) (xy 102.682802 -263.686544)
			(xy 102.682293 -263.712511) (xy 102.674168 -263.763806) (xy 102.65812 -263.813199) (xy 102.634542 -263.859473)
			(xy 102.604016 -263.901489) (xy 102.567293 -263.938212) (xy 102.525277 -263.968738) (xy 102.479003 -263.992316)
			(xy 102.42961 -264.008364) (xy 102.378315 -264.016489) (xy 102.326381 -264.016489) (xy 102.275086 -264.008364)
			(xy 102.225693 -263.992316) (xy 102.179419 -263.968738) (xy 102.137403 -263.938212) (xy 102.10068 -263.901489)
			(xy 102.070154 -263.859473) (xy 102.046576 -263.813199) (xy 102.030528 -263.763806) (xy 102.022403 -263.712511)
			(xy 101.742239 -263.712511) (xy 101.734114 -263.763806) (xy 101.718066 -263.813199) (xy 101.694488 -263.859473)
			(xy 101.663962 -263.901489) (xy 101.627239 -263.938212) (xy 101.585223 -263.968738) (xy 101.538949 -263.992316)
			(xy 101.489556 -264.008364) (xy 101.438261 -264.016489) (xy 101.386327 -264.016489) (xy 101.335032 -264.008364)
			(xy 101.285639 -263.992316) (xy 101.239365 -263.968738) (xy 101.197349 -263.938212) (xy 101.160626 -263.901489)
			(xy 101.1301 -263.859473) (xy 101.106522 -263.813199) (xy 101.090474 -263.763806) (xy 101.082349 -263.712511)
			(xy 100.932996 -263.712511) (xy 100.932996 -264.166858) (xy 100.978208 -264.171938) (xy 101.003449 -264.175161)
			(xy 101.052589 -264.188365) (xy 101.099124 -264.208947) (xy 101.141954 -264.236419) (xy 101.180065 -264.270133)
			(xy 101.212557 -264.309291) (xy 101.238662 -264.352968) (xy 101.257762 -264.40013) (xy 101.269406 -264.449663)
			(xy 101.273319 -264.500396) (xy 101.269408 -264.551128) (xy 101.257765 -264.600662) (xy 101.238666 -264.647824)
			(xy 101.212562 -264.691502) (xy 101.180071 -264.730661) (xy 101.14196 -264.764375) (xy 101.099132 -264.791849)
			(xy 101.052597 -264.812432) (xy 101.003458 -264.825637) (xy 100.978208 -264.828782) (xy 100.932996 -264.833862)
			(xy 100.932996 -265.574526) (xy 101.085396 -265.726926) (xy 102.507796 -265.726926)
		)
		(stroke
			(width 0)
			(type solid)
		)
		(fill yes)
		(layer "In11.Cu")
		(net "PVCCFA_EHV_CPU1")
	)
	(gr_poly
		(pts
			(xy 225.68916 -399.03908) (xy 228.79304 -399.03908) (xy 230.44404 -400.69008) (xy 238.73714 -400.69008)
			(xy 239.0394 -400.38782) (xy 239.0394 -396.84452) (xy 239.47882 -396.4051) (xy 278.94788 -396.4051)
			(xy 279.23236 -396.12062) (xy 279.23236 -395.48816) (xy 279.199863 -395.460026) (xy 279.139858 -395.398475)
			(xy 279.08607 -395.331424) (xy 279.039 -395.259497) (xy 278.999087 -395.183365) (xy 278.966704 -395.103738)
			(xy 278.942152 -395.021359) (xy 278.92566 -394.936996) (xy 278.917383 -394.851436) (xy 278.916892 -394.808456)
			(xy 278.917398 -394.765476) (xy 278.925668 -394.679916) (xy 278.942154 -394.595553) (xy 278.966704 -394.513175)
			(xy 278.999087 -394.43355) (xy 279.039003 -394.35742) (xy 279.086078 -394.285498) (xy 279.139873 -394.218453)
			(xy 279.199886 -394.156911) (xy 279.23236 -394.128752) (xy 279.23236 -390.67486) (xy 278.67102 -390.11352)
			(xy 231.65308 -390.11352) (xy 229.1715 -392.5951) (xy 186.75858 -392.5951) (xy 185.1533 -394.20038)
			(xy 185.1533 -394.8085) (xy 243.179528 -394.8085) (xy 243.183558 -394.723892) (xy 243.195613 -394.640051)
			(xy 243.215583 -394.557735) (xy 243.243287 -394.47769) (xy 243.278475 -394.400641) (xy 243.320827 -394.327286)
			(xy 243.36996 -394.258289) (xy 243.42543 -394.194274) (xy 243.486733 -394.135823) (xy 243.553315 -394.083463)
			(xy 243.624573 -394.03767) (xy 243.699861 -393.998857) (xy 243.778498 -393.967377) (xy 243.859771 -393.943515)
			(xy 243.942944 -393.927486) (xy 244.027264 -393.919435) (xy 244.069616 -393.918948) (xy 244.11084 -393.919417)
			(xy 244.192933 -393.927053) (xy 244.273968 -393.94225) (xy 244.35325 -393.964876) (xy 244.430099 -393.994739)
			(xy 244.503857 -394.031582) (xy 244.573891 -394.075088) (xy 244.639601 -394.124886) (xy 244.670326 -394.152374)
			(xy 244.677558 -394.158461) (xy 244.695171 -394.165287) (xy 244.714061 -394.165287) (xy 244.731674 -394.158461)
			(xy 244.738906 -394.152374) (xy 244.769639 -394.124894) (xy 244.835341 -394.075085) (xy 244.905371 -394.03157)
			(xy 244.979128 -393.994723) (xy 245.055977 -393.964858) (xy 245.13526 -393.942233) (xy 245.216297 -393.927041)
			(xy 245.298392 -393.919413) (xy 245.339616 -393.918948) (xy 245.381408 -393.919476) (xy 245.464624 -393.927312)
			(xy 245.546738 -393.942923) (xy 245.627024 -393.96617) (xy 245.704775 -393.996849) (xy 245.779303 -394.034689)
			(xy 245.849951 -394.079356) (xy 245.916096 -394.130456) (xy 245.977154 -394.187537) (xy 246.032585 -394.250097)
			(xy 246.081902 -394.317582) (xy 246.124667 -394.389397) (xy 246.143018 -394.426948) (xy 246.170089 -394.428781)
			(xy 246.223268 -394.43954) (xy 246.274197 -394.458246) (xy 246.321697 -394.484466) (xy 246.364667 -394.51759)
			(xy 246.402111 -394.556853) (xy 246.433163 -394.601345) (xy 246.457102 -394.650034) (xy 246.473374 -394.701792)
			(xy 246.481601 -394.75542) (xy 246.482108 -394.782548) (xy 246.481601 -394.8085) (xy 249.114543 -394.8085)
			(xy 249.118574 -394.723896) (xy 249.130628 -394.640058) (xy 249.150596 -394.557746) (xy 249.178298 -394.477704)
			(xy 249.213483 -394.400658) (xy 249.255833 -394.327305) (xy 249.304963 -394.25831) (xy 249.360429 -394.194298)
			(xy 249.421729 -394.135847) (xy 249.488307 -394.083488) (xy 249.55956 -394.037695) (xy 249.634844 -393.998882)
			(xy 249.713476 -393.967401) (xy 249.794745 -393.943537) (xy 249.877914 -393.927506) (xy 249.96223 -393.919453)
			(xy 250.00458 -393.918948) (xy 250.045803 -393.919439) (xy 250.127896 -393.927072) (xy 250.20893 -393.942266)
			(xy 250.288212 -393.964889) (xy 250.365061 -393.994749) (xy 250.438819 -394.031588) (xy 250.508854 -394.075092)
			(xy 250.574564 -394.124887) (xy 250.60529 -394.152374) (xy 250.612522 -394.158461) (xy 250.630135 -394.165287)
			(xy 250.649025 -394.165287) (xy 250.666638 -394.158461) (xy 250.67387 -394.152374) (xy 250.704576 -394.124863)
			(xy 250.770283 -394.075057) (xy 250.840317 -394.031545) (xy 250.914078 -393.994701) (xy 250.990931 -393.96484)
			(xy 251.070218 -393.942219) (xy 251.151257 -393.927032) (xy 251.233355 -393.91941) (xy 251.27458 -393.918948)
			(xy 251.316356 -393.919458) (xy 251.399539 -393.927298) (xy 251.481621 -393.942901) (xy 251.561879 -393.966129)
			(xy 251.639606 -393.996779) (xy 251.714118 -394.03458) (xy 251.784758 -394.079199) (xy 251.850904 -394.130243)
			(xy 251.911974 -394.187264) (xy 251.96743 -394.249758) (xy 252.016784 -394.317175) (xy 252.059601 -394.388922)
			(xy 252.077982 -394.42644) (xy 252.086364 -394.42644) (xy 252.114351 -394.426946) (xy 252.169636 -394.435698)
			(xy 252.222871 -394.452992) (xy 252.272744 -394.478402) (xy 252.318028 -394.511302) (xy 252.357606 -394.550881)
			(xy 252.390505 -394.596166) (xy 252.415913 -394.646041) (xy 252.433205 -394.699276) (xy 252.441955 -394.754561)
			(xy 252.442472 -394.782548) (xy 252.441992 -394.8085) (xy 255.049428 -394.8085) (xy 255.053459 -394.723891)
			(xy 255.065514 -394.640048) (xy 255.085484 -394.55773) (xy 255.11319 -394.477684) (xy 255.148379 -394.400634)
			(xy 255.190732 -394.327277) (xy 255.239868 -394.258279) (xy 255.295339 -394.194265) (xy 255.356645 -394.135813)
			(xy 255.423229 -394.083453) (xy 255.494489 -394.03766) (xy 255.56978 -393.998849) (xy 255.648419 -393.96737)
			(xy 255.729694 -393.943509) (xy 255.812869 -393.927482) (xy 255.897191 -393.919434) (xy 255.939544 -393.918948)
			(xy 255.980768 -393.919399) (xy 256.062862 -393.927038) (xy 256.143897 -393.942237) (xy 256.223179 -393.964866)
			(xy 256.300029 -393.994731) (xy 256.373786 -394.031576) (xy 256.44382 -394.075085) (xy 256.509529 -394.124885)
			(xy 256.540254 -394.152374) (xy 256.547486 -394.158461) (xy 256.565099 -394.165287) (xy 256.583989 -394.165287)
			(xy 256.601602 -394.158461) (xy 256.608834 -394.152374) (xy 256.639555 -394.12488) (xy 256.70526 -394.075073)
			(xy 256.775292 -394.031559) (xy 256.849049 -393.994713) (xy 256.925901 -393.96485) (xy 257.005185 -393.942227)
			(xy 257.086223 -393.927037) (xy 257.168319 -393.919412) (xy 257.209544 -393.918948) (xy 257.251493 -393.919491)
			(xy 257.335018 -393.927401) (xy 257.417428 -393.943137) (xy 257.497991 -393.96656) (xy 257.575991 -393.997462)
			(xy 257.650737 -394.035568) (xy 257.721565 -394.08054) (xy 257.787845 -394.131979) (xy 257.848989 -394.189427)
			(xy 257.904455 -394.252376) (xy 257.95375 -394.320266) (xy 257.996436 -394.392494) (xy 258.014724 -394.43025)
			(xy 258.027542 -394.428485) (xy 258.053348 -394.426578) (xy 258.066286 -394.42644) (xy 258.067048 -394.42644)
			(xy 258.093699 -394.426845) (xy 258.146403 -394.434796) (xy 258.197335 -394.450512) (xy 258.245356 -394.473643)
			(xy 258.289393 -394.503673) (xy 258.328463 -394.539929) (xy 258.361693 -394.581604) (xy 258.388341 -394.627765)
			(xy 258.407813 -394.677383) (xy 258.419673 -394.729348) (xy 258.423656 -394.7825) (xy 258.421708 -394.8085)
			(xy 260.984428 -394.8085) (xy 260.988458 -394.723893) (xy 261.000513 -394.640052) (xy 261.020483 -394.557736)
			(xy 261.048186 -394.477692) (xy 261.083374 -394.400643) (xy 261.125725 -394.327288) (xy 261.174858 -394.258291)
			(xy 261.230327 -394.194277) (xy 261.29163 -394.135826) (xy 261.358212 -394.083466) (xy 261.429469 -394.037672)
			(xy 261.504756 -393.99886) (xy 261.583392 -393.967379) (xy 261.664664 -393.943516) (xy 261.747837 -393.927487)
			(xy 261.832156 -393.919436) (xy 261.874508 -393.918948) (xy 261.915732 -393.919422) (xy 261.997825 -393.927057)
			(xy 262.078859 -393.942253) (xy 262.158141 -393.964879) (xy 262.234991 -393.994741) (xy 262.308749 -394.031583)
			(xy 262.378783 -394.075089) (xy 262.444493 -394.124886) (xy 262.475218 -394.152374) (xy 262.48245 -394.158461)
			(xy 262.500063 -394.165287) (xy 262.518953 -394.165287) (xy 262.536566 -394.158461) (xy 262.543798 -394.152374)
			(xy 262.574534 -394.124897) (xy 262.640236 -394.075089) (xy 262.710266 -394.031574) (xy 262.784021 -393.994725)
			(xy 262.86087 -393.96486) (xy 262.940153 -393.942234) (xy 263.021189 -393.927042) (xy 263.103284 -393.919413)
			(xy 263.144508 -393.918948) (xy 263.18635 -393.919404) (xy 263.269665 -393.927258) (xy 263.351874 -393.942906)
			(xy 263.432248 -393.966208) (xy 263.510078 -393.996959) (xy 263.584674 -394.034887) (xy 263.655376 -394.079656)
			(xy 263.721559 -394.130869) (xy 263.782638 -394.188075) (xy 263.838071 -394.250766) (xy 263.887369 -394.318389)
			(xy 263.930095 -394.390344) (xy 263.948418 -394.427964) (xy 263.981692 -394.42644) (xy 264.008347 -394.426817)
			(xy 264.061062 -394.434761) (xy 264.112004 -394.450474) (xy 264.160035 -394.473603) (xy 264.204083 -394.503633)
			(xy 264.243162 -394.539893) (xy 264.276401 -394.581572) (xy 264.303057 -394.62774) (xy 264.322533 -394.677365)
			(xy 264.334396 -394.729339) (xy 264.33838 -394.7825) (xy 264.336432 -394.8085) (xy 266.919443 -394.8085)
			(xy 266.923474 -394.723896) (xy 266.935527 -394.640059) (xy 266.955496 -394.557747) (xy 266.983198 -394.477706)
			(xy 267.018382 -394.40066) (xy 267.060731 -394.327308) (xy 267.109861 -394.258313) (xy 267.165326 -394.194301)
			(xy 267.226625 -394.13585) (xy 267.293203 -394.083491) (xy 267.364456 -394.037698) (xy 267.439739 -393.998885)
			(xy 267.51837 -393.967403) (xy 267.599638 -393.943538) (xy 267.682807 -393.927507) (xy 267.767122 -393.919453)
			(xy 267.809472 -393.918948) (xy 267.850695 -393.919444) (xy 267.932787 -393.927077) (xy 268.013822 -393.942269)
			(xy 268.093103 -393.964892) (xy 268.169953 -393.994751) (xy 268.243711 -394.03159) (xy 268.313746 -394.075093)
			(xy 268.379456 -394.124888) (xy 268.410182 -394.152374) (xy 268.417414 -394.158461) (xy 268.435027 -394.165287)
			(xy 268.453917 -394.165287) (xy 268.47153 -394.158461) (xy 268.478762 -394.152374) (xy 268.509471 -394.124866)
			(xy 268.575178 -394.07506) (xy 268.645212 -394.031548) (xy 268.718971 -393.994703) (xy 268.795824 -393.964842)
			(xy 268.87511 -393.942221) (xy 268.95615 -393.927033) (xy 269.038247 -393.91941) (xy 269.079472 -393.918948)
			(xy 269.121265 -393.919428) (xy 269.204483 -393.927269) (xy 269.286598 -393.942885) (xy 269.366885 -393.966137)
			(xy 269.444636 -393.996821) (xy 269.519164 -394.034666) (xy 269.589812 -394.079337) (xy 269.655956 -394.130441)
			(xy 269.717013 -394.187526) (xy 269.772444 -394.250089) (xy 269.821759 -394.317577) (xy 269.864524 -394.389396)
			(xy 269.882874 -394.426948) (xy 269.909949 -394.428731) (xy 269.963129 -394.439499) (xy 270.014058 -394.458212)
			(xy 270.061558 -394.484438) (xy 270.104527 -394.517569) (xy 270.141971 -394.556837) (xy 270.173021 -394.601333)
			(xy 270.19696 -394.650026) (xy 270.213231 -394.701787) (xy 270.221458 -394.755419) (xy 270.221964 -394.782548)
			(xy 270.221496 -394.8085) (xy 272.854328 -394.8085) (xy 272.858359 -394.723891) (xy 272.870414 -394.640048)
			(xy 272.890384 -394.557731) (xy 272.918089 -394.477686) (xy 272.953277 -394.400636) (xy 272.995631 -394.32728)
			(xy 273.044766 -394.258282) (xy 273.100237 -394.194267) (xy 273.161542 -394.135816) (xy 273.228125 -394.083456)
			(xy 273.299385 -394.037663) (xy 273.374675 -393.998851) (xy 273.453313 -393.967372) (xy 273.534587 -393.943511)
			(xy 273.617762 -393.927483) (xy 273.702084 -393.919434) (xy 273.744436 -393.918948) (xy 273.78566 -393.919404)
			(xy 273.867754 -393.927042) (xy 273.948789 -393.942241) (xy 274.028071 -393.964869) (xy 274.10492 -393.994734)
			(xy 274.178678 -394.031578) (xy 274.248712 -394.075086) (xy 274.314421 -394.124886) (xy 274.345146 -394.152374)
			(xy 274.352378 -394.158461) (xy 274.369991 -394.165287) (xy 274.388881 -394.165287) (xy 274.406494 -394.158461)
			(xy 274.413726 -394.152374) (xy 274.44445 -394.124884) (xy 274.510154 -394.075076) (xy 274.580186 -394.031562)
			(xy 274.653943 -393.994716) (xy 274.730794 -393.964852) (xy 274.810078 -393.942228) (xy 274.891116 -393.927038)
			(xy 274.973211 -393.919412) (xy 275.014436 -393.918948) (xy 275.056229 -393.919459) (xy 275.139445 -393.927297)
			(xy 275.221559 -393.942909) (xy 275.301846 -393.966158) (xy 275.379596 -393.996839) (xy 275.454125 -394.034681)
			(xy 275.524773 -394.079349) (xy 275.590918 -394.130451) (xy 275.651975 -394.187533) (xy 275.707406 -394.250094)
			(xy 275.756722 -394.31758) (xy 275.799488 -394.389397) (xy 275.817838 -394.426948) (xy 275.844911 -394.428763)
			(xy 275.898089 -394.439526) (xy 275.949019 -394.458234) (xy 275.996518 -394.484456) (xy 276.039488 -394.517583)
			(xy 276.076932 -394.556848) (xy 276.107984 -394.601341) (xy 276.131922 -394.650031) (xy 276.148194 -394.70179)
			(xy 276.156421 -394.75542) (xy 276.156928 -394.782548) (xy 276.156404 -394.808503) (xy 276.148874 -394.859865)
			(xy 276.133965 -394.909589) (xy 276.111994 -394.956621) (xy 276.083427 -394.999964) (xy 276.048869 -395.038699)
			(xy 276.009052 -395.072006) (xy 275.964821 -395.099179) (xy 275.917114 -395.11964) (xy 275.86694 -395.132958)
			(xy 275.841206 -395.13637) (xy 275.825747 -395.174161) (xy 275.788816 -395.246988) (xy 275.745365 -395.316123)
			(xy 275.695761 -395.380985) (xy 275.64042 -395.441027) (xy 275.579808 -395.495744) (xy 275.514437 -395.544676)
			(xy 275.444856 -395.587409) (xy 275.371651 -395.623585) (xy 275.295438 -395.652899) (xy 275.216859 -395.675104)
			(xy 275.136576 -395.690013) (xy 275.055264 -395.6975) (xy 275.014436 -395.697964) (xy 274.973213 -395.69746)
			(xy 274.891121 -395.689828) (xy 274.810087 -395.674636) (xy 274.730806 -395.652015) (xy 274.653956 -395.622157)
			(xy 274.580198 -395.585319) (xy 274.510163 -395.541817) (xy 274.444452 -395.492024) (xy 274.413726 -395.464538)
			(xy 274.406494 -395.458451) (xy 274.388881 -395.451625) (xy 274.369991 -395.451625) (xy 274.352378 -395.458451)
			(xy 274.345146 -395.464538) (xy 274.314435 -395.492044) (xy 274.248729 -395.54185) (xy 274.178695 -395.585362)
			(xy 274.104936 -395.622207) (xy 274.028083 -395.652068) (xy 273.948797 -395.67469) (xy 273.867758 -395.689878)
			(xy 273.785661 -395.697501) (xy 273.744436 -395.697964) (xy 273.702084 -395.697566) (xy 273.617762 -395.689517)
			(xy 273.534587 -395.673489) (xy 273.453313 -395.649628) (xy 273.374675 -395.618149) (xy 273.299385 -395.579337)
			(xy 273.228125 -395.533544) (xy 273.161542 -395.481184) (xy 273.100237 -395.422733) (xy 273.044766 -395.358718)
			(xy 272.995631 -395.28972) (xy 272.953277 -395.216364) (xy 272.918089 -395.139314) (xy 272.890384 -395.059269)
			(xy 272.870414 -394.976952) (xy 272.858359 -394.893109) (xy 272.854328 -394.8085) (xy 270.221496 -394.8085)
			(xy 270.221496 -394.808506) (xy 270.213964 -394.859873) (xy 270.199053 -394.909601) (xy 270.177077 -394.956636)
			(xy 270.148504 -394.999982) (xy 270.113939 -395.038718) (xy 270.074115 -395.072025) (xy 270.029876 -395.099194)
			(xy 269.98216 -395.119651) (xy 269.93198 -395.132962) (xy 269.906242 -395.13637) (xy 269.890753 -395.174148)
			(xy 269.853824 -395.246974) (xy 269.810375 -395.316109) (xy 269.760773 -395.38097) (xy 269.705435 -395.441012)
			(xy 269.644826 -395.49573) (xy 269.579457 -395.544662) (xy 269.509879 -395.587396) (xy 269.436676 -395.623574)
			(xy 269.360466 -395.652889) (xy 269.28189 -395.675096) (xy 269.201609 -395.690008) (xy 269.120299 -395.697499)
			(xy 269.079472 -395.697964) (xy 269.038248 -395.6975) (xy 268.956155 -395.689862) (xy 268.87512 -395.674665)
			(xy 268.795838 -395.652037) (xy 268.718989 -395.622174) (xy 268.645231 -395.585331) (xy 268.575197 -395.541824)
			(xy 268.509487 -395.492026) (xy 268.478762 -395.464538) (xy 268.47153 -395.458451) (xy 268.453917 -395.451625)
			(xy 268.435027 -395.451625) (xy 268.417414 -395.458451) (xy 268.410182 -395.464538) (xy 268.379456 -395.492026)
			(xy 268.313752 -395.541834) (xy 268.243721 -395.585348) (xy 268.169964 -395.622194) (xy 268.093113 -395.652058)
			(xy 268.013829 -395.674682) (xy 267.932792 -395.689873) (xy 267.850696 -395.6975) (xy 267.809472 -395.697964)
			(xy 267.767122 -395.697547) (xy 267.682807 -395.689493) (xy 267.599638 -395.673462) (xy 267.51837 -395.649597)
			(xy 267.439739 -395.618115) (xy 267.364456 -395.579302) (xy 267.293203 -395.533509) (xy 267.226625 -395.48115)
			(xy 267.165326 -395.422699) (xy 267.109861 -395.358687) (xy 267.060731 -395.289692) (xy 267.018382 -395.21634)
			(xy 266.983198 -395.139294) (xy 266.955496 -395.059253) (xy 266.935527 -394.976941) (xy 266.923474 -394.893104)
			(xy 266.919443 -394.8085) (xy 264.336432 -394.8085) (xy 264.334396 -394.835661) (xy 264.322533 -394.887635)
			(xy 264.303057 -394.93726) (xy 264.276401 -394.983428) (xy 264.243162 -395.025107) (xy 264.204083 -395.061367)
			(xy 264.160035 -395.091397) (xy 264.112004 -395.114526) (xy 264.061062 -395.130239) (xy 264.008347 -395.138183)
			(xy 263.981692 -395.138656) (xy 263.970516 -395.138402) (xy 263.954928 -395.17605) (xy 263.917915 -395.248648)
			(xy 263.874417 -395.317555) (xy 263.824797 -395.382194) (xy 263.769471 -395.442023) (xy 263.708905 -395.496539)
			(xy 263.643605 -395.545287) (xy 263.57412 -395.587856) (xy 263.501032 -395.623891) (xy 263.424953 -395.653088)
			(xy 263.346523 -395.675203) (xy 263.266399 -395.69005) (xy 263.185252 -395.697505) (xy 263.144508 -395.697964)
			(xy 263.103285 -395.697477) (xy 263.021192 -395.689843) (xy 262.940158 -395.674649) (xy 262.860876 -395.652025)
			(xy 262.784027 -395.622164) (xy 262.710269 -395.585324) (xy 262.640234 -395.54182) (xy 262.574524 -395.492025)
			(xy 262.543798 -395.464538) (xy 262.536566 -395.458451) (xy 262.518953 -395.451625) (xy 262.500063 -395.451625)
			(xy 262.48245 -395.458451) (xy 262.475218 -395.464538) (xy 262.444477 -395.492009) (xy 262.378775 -395.541818)
			(xy 262.308747 -395.585333) (xy 262.234992 -395.622182) (xy 262.158144 -395.652048) (xy 262.078861 -395.674675)
			(xy 261.997826 -395.689868) (xy 261.915732 -395.697498) (xy 261.874508 -395.697964) (xy 261.832156 -395.697564)
			(xy 261.747837 -395.689513) (xy 261.664664 -395.673484) (xy 261.583392 -395.649621) (xy 261.504756 -395.61814)
			(xy 261.429469 -395.579328) (xy 261.358212 -395.533534) (xy 261.29163 -395.481174) (xy 261.230327 -395.422723)
			(xy 261.174858 -395.358709) (xy 261.125725 -395.289712) (xy 261.083374 -395.216357) (xy 261.048186 -395.139308)
			(xy 261.020483 -395.059264) (xy 261.000513 -394.976948) (xy 260.988458 -394.893107) (xy 260.984428 -394.8085)
			(xy 258.421708 -394.8085) (xy 258.419673 -394.835652) (xy 258.407813 -394.887617) (xy 258.388341 -394.937235)
			(xy 258.361693 -394.983396) (xy 258.328463 -395.025071) (xy 258.289393 -395.061327) (xy 258.245356 -395.091357)
			(xy 258.197335 -395.114488) (xy 258.146403 -395.130204) (xy 258.093699 -395.138155) (xy 258.067048 -395.138656)
			(xy 258.03606 -395.137386) (xy 258.020546 -395.175113) (xy 257.983557 -395.247826) (xy 257.940067 -395.316846)
			(xy 257.89044 -395.381595) (xy 257.835094 -395.441529) (xy 257.774494 -395.496144) (xy 257.709147 -395.544982)
			(xy 257.639604 -395.587632) (xy 257.566448 -395.623736) (xy 257.490294 -395.65299) (xy 257.411782 -395.67515)
			(xy 257.331571 -395.690029) (xy 257.250334 -395.697502) (xy 257.209544 -395.697964) (xy 257.168321 -395.697455)
			(xy 257.08623 -395.689824) (xy 257.005196 -395.674633) (xy 256.925914 -395.652012) (xy 256.849065 -395.622155)
			(xy 256.775306 -395.585317) (xy 256.705271 -395.541816) (xy 256.63956 -395.492023) (xy 256.608834 -395.464538)
			(xy 256.601602 -395.458451) (xy 256.583989 -395.451625) (xy 256.565099 -395.451625) (xy 256.547486 -395.458451)
			(xy 256.540254 -395.464538) (xy 256.50954 -395.49204) (xy 256.443834 -395.541846) (xy 256.373801 -395.585359)
			(xy 256.300042 -395.622204) (xy 256.22319 -395.652066) (xy 256.143904 -395.674688) (xy 256.062865 -395.689877)
			(xy 255.980769 -395.697501) (xy 255.939544 -395.697964) (xy 255.897191 -395.697566) (xy 255.812869 -395.689518)
			(xy 255.729694 -395.673491) (xy 255.648419 -395.64963) (xy 255.56978 -395.618151) (xy 255.494489 -395.57934)
			(xy 255.423229 -395.533547) (xy 255.356645 -395.481187) (xy 255.295339 -395.422735) (xy 255.239868 -395.358721)
			(xy 255.190732 -395.289723) (xy 255.148379 -395.216366) (xy 255.11319 -395.139316) (xy 255.085484 -395.05927)
			(xy 255.065514 -394.976952) (xy 255.053459 -394.893109) (xy 255.049428 -394.8085) (xy 252.441992 -394.8085)
			(xy 252.441968 -394.809821) (xy 252.433657 -394.863731) (xy 252.417221 -394.915743) (xy 252.393046 -394.964639)
			(xy 252.361695 -395.009276) (xy 252.323904 -395.04861) (xy 252.280556 -395.081721) (xy 252.232666 -395.107832)
			(xy 252.181353 -395.126335) (xy 252.127819 -395.136795) (xy 252.100588 -395.138402) (xy 252.085024 -395.17606)
			(xy 252.048009 -395.248659) (xy 252.004509 -395.317566) (xy 251.954887 -395.382206) (xy 251.89956 -395.442034)
			(xy 251.838991 -395.496551) (xy 251.773689 -395.545298) (xy 251.704202 -395.587866) (xy 251.631111 -395.623899)
			(xy 251.555031 -395.653095) (xy 251.476599 -395.675208) (xy 251.396473 -395.690054) (xy 251.315325 -395.697507)
			(xy 251.27458 -395.697964) (xy 251.233356 -395.697495) (xy 251.151263 -395.689858) (xy 251.070228 -395.674661)
			(xy 250.990947 -395.652035) (xy 250.914097 -395.622172) (xy 250.840339 -395.58533) (xy 250.770305 -395.541823)
			(xy 250.704595 -395.492026) (xy 250.67387 -395.464538) (xy 250.666638 -395.458451) (xy 250.649025 -395.451625)
			(xy 250.630135 -395.451625) (xy 250.612522 -395.458451) (xy 250.60529 -395.464538) (xy 250.574561 -395.492023)
			(xy 250.508857 -395.54183) (xy 250.438827 -395.585344) (xy 250.36507 -395.622192) (xy 250.28822 -395.652056)
			(xy 250.208936 -395.67468) (xy 250.127899 -395.689872) (xy 250.045804 -395.697499) (xy 250.00458 -395.697964)
			(xy 249.96223 -395.697547) (xy 249.877914 -395.689494) (xy 249.794745 -395.673463) (xy 249.713476 -395.649599)
			(xy 249.634844 -395.618118) (xy 249.55956 -395.579305) (xy 249.488307 -395.533512) (xy 249.421729 -395.481153)
			(xy 249.360429 -395.422702) (xy 249.304963 -395.35869) (xy 249.255833 -395.289695) (xy 249.213483 -395.216342)
			(xy 249.178298 -395.139296) (xy 249.150596 -395.059254) (xy 249.130628 -394.976942) (xy 249.118574 -394.893104)
			(xy 249.114543 -394.8085) (xy 246.481601 -394.8085) (xy 246.481601 -394.808504) (xy 246.474071 -394.859867)
			(xy 246.459161 -394.909593) (xy 246.437189 -394.956626) (xy 246.40862 -394.999969) (xy 246.374059 -395.038705)
			(xy 246.334241 -395.072012) (xy 246.290007 -395.099183) (xy 246.242297 -395.119644) (xy 246.192121 -395.132959)
			(xy 246.166386 -395.13637) (xy 246.15086 -395.174132) (xy 246.113933 -395.246957) (xy 246.070488 -395.316091)
			(xy 246.020888 -395.380952) (xy 245.965553 -395.440994) (xy 245.904948 -395.495712) (xy 245.839582 -395.544645)
			(xy 245.770007 -395.587381) (xy 245.696808 -395.62356) (xy 245.620601 -395.652878) (xy 245.542028 -395.675088)
			(xy 245.461749 -395.690002) (xy 245.380442 -395.697497) (xy 245.339616 -395.697964) (xy 245.298393 -395.697472)
			(xy 245.216301 -395.689839) (xy 245.135266 -395.674645) (xy 245.055985 -395.652022) (xy 244.979135 -395.622162)
			(xy 244.905377 -395.585323) (xy 244.835342 -395.541819) (xy 244.769632 -395.492024) (xy 244.738906 -395.464538)
			(xy 244.731674 -395.458451) (xy 244.714061 -395.451625) (xy 244.695171 -395.451625) (xy 244.677558 -395.458451)
			(xy 244.670326 -395.464538) (xy 244.639624 -395.492053) (xy 244.573916 -395.541859) (xy 244.503881 -395.58537)
			(xy 244.43012 -395.622214) (xy 244.353266 -395.652074) (xy 244.273979 -395.674694) (xy 244.192939 -395.68988)
			(xy 244.110841 -395.697502) (xy 244.069616 -395.697964) (xy 244.027264 -395.697565) (xy 243.942944 -395.689514)
			(xy 243.859771 -395.673485) (xy 243.778498 -395.649623) (xy 243.699861 -395.618143) (xy 243.624573 -395.57933)
			(xy 243.553315 -395.533537) (xy 243.486733 -395.481177) (xy 243.42543 -395.422726) (xy 243.36996 -395.358711)
			(xy 243.320827 -395.289714) (xy 243.278475 -395.216359) (xy 243.243287 -395.13931) (xy 243.215583 -395.059265)
			(xy 243.195613 -394.976949) (xy 243.183558 -394.893108) (xy 243.179528 -394.8085) (xy 185.1533 -394.8085)
			(xy 185.1533 -396.92834) (xy 185.94324 -397.71828) (xy 185.94324 -400.42338) (xy 186.17692 -400.65706)
			(xy 192.0748 -400.65706) (xy 194.3481 -398.38376) (xy 196.56552 -398.38376) (xy 198.86168 -400.67992)
			(xy 202.5904 -400.67992) (xy 204.30998 -398.96034) (xy 207.31226 -398.96034) (xy 209.02168 -400.66976)
			(xy 213.26348 -400.66976) (xy 215.05164 -398.8816) (xy 217.97518 -398.8816) (xy 219.79636 -400.70278)
			(xy 224.02546 -400.70278)
		)
		(stroke
			(width 0)
			(type solid)
		)
		(fill yes)
		(layer "In11.Cu")
		(net "P12V_AUX")
	)
	(gr_poly
		(pts
			(arc
				(start 194.443604 -441.479432)
				(mid 194.479525 -441.464553)
				(end 194.494404 -441.428632)
			)
			(arc
				(start 194.494404 -441.17006)
				(mid 194.790421 -440.455411)
				(end 195.50507 -440.159394)
			)
			(arc
				(start 276.314916 -440.159394)
				(mid 277.029565 -440.455411)
				(end 277.325582 -441.17006)
			)
			(arc
				(start 277.325582 -441.428632)
				(mid 277.340461 -441.464553)
				(end 277.376382 -441.479432)
			)
			(arc
				(start 463.300064 -441.479432)
				(mid 464.353268 -441.04318)
				(end 464.78952 -439.989976)
			)
			(arc
				(start 464.78952 -409.528264)
				(mid 464.980687 -408.567674)
				(end 465.52485 -407.753312)
			)
			(arc
				(start 467.353396 -405.924766)
				(mid 467.676179 -405.441593)
				(end 467.789514 -404.871682)
			)
			(arc
				(start 467.789514 -82.82813)
				(mid 467.980666 -81.867526)
				(end 468.524844 -81.053178)
			)
			(arc
				(start 470.853262 -78.72476)
				(mid 471.176045 -78.241587)
				(end 471.28938 -77.671676)
			)
			(arc
				(start 471.28938 -26.830528)
				(mid 471.282359 -26.804504)
				(end 471.262964 -26.785824)
			)
			(arc
				(start 471.184732 -26.742898)
				(mid 471.158691 -26.736707)
				(end 471.13317 -26.744676)
			)
			(arc
				(start 471.13317 -26.744676)
				(mid 470.972573 -26.843084)
				(end 470.808558 -26.935684)
			)
			(arc
				(start 470.808558 -26.935684)
				(mid 470.789062 -26.95436)
				(end 470.781888 -26.980388)
			)
			(arc
				(start 470.781888 -77.672184)
				(mid 470.707176 -78.047677)
				(end 470.494614 -78.366112)
			)
			(arc
				(start 468.166196 -80.69453)
				(mid 467.512084 -81.673433)
				(end 467.282276 -82.82813)
			)
			(arc
				(start 467.282276 -84.884006)
				(mid 467.286177 -84.903529)
				(end 467.297262 -84.920074)
			)
			(arc
				(start 467.514686 -85.137752)
				(mid 467.525797 -85.154286)
				(end 467.529672 -85.17382)
			)
			(arc
				(start 467.529672 -116.867686)
				(mid 467.525771 -116.887209)
				(end 467.514686 -116.903754)
			)
			(arc
				(start 467.297262 -117.121432)
				(mid 467.286151 -117.137966)
				(end 467.282276 -117.1575)
			)
			(arc
				(start 467.282276 -358.935274)
				(mid 467.28295 -358.943778)
				(end 467.28507 -358.952038)
			)
			(arc
				(start 467.28507 -358.952038)
				(mid 467.514132 -359.845086)
				(end 467.59114 -360.76382)
			)
			(arc
				(start 467.59114 -360.76382)
				(mid 467.514124 -361.682553)
				(end 467.28507 -362.575602)
			)
			(arc
				(start 467.28507 -362.575602)
				(mid 467.282984 -362.583868)
				(end 467.282276 -362.592366)
			)
			(arc
				(start 467.282276 -404.871936)
				(mid 467.207495 -405.247595)
				(end 466.994748 -405.566118)
			)
			(arc
				(start 465.166202 -407.394664)
				(mid 464.5119 -408.373524)
				(end 464.282028 -409.528264)
			)
			(arc
				(start 464.282028 -439.989976)
				(mid 463.994417 -440.684329)
				(end 463.300064 -440.97194)
			)
			(xy 410.917898 -440.97194)
			(arc
				(start 410.910024 -440.974734)
				(mid 410.831038 -440.993945)
				(end 410.750004 -441.000388)
			)
			(arc
				(start 410.750004 -441.000388)
				(mid 410.668968 -440.993957)
				(end 410.589984 -440.974734)
			)
			(xy 410.58211 -440.97194) (xy 406.917906 -440.97194)
			(arc
				(start 406.910032 -440.974734)
				(mid 406.831046 -440.993945)
				(end 406.750012 -441.000388)
			)
			(arc
				(start 406.750012 -441.000388)
				(mid 406.668976 -440.993957)
				(end 406.589992 -440.974734)
			)
			(xy 406.582118 -440.97194) (xy 402.917914 -440.97194)
			(arc
				(start 402.91004 -440.974734)
				(mid 402.831054 -440.993945)
				(end 402.75002 -441.000388)
			)
			(arc
				(start 402.75002 -441.000388)
				(mid 402.668984 -440.993957)
				(end 402.59 -440.974734)
			)
			(xy 402.582126 -440.97194) (xy 398.917922 -440.97194)
			(arc
				(start 398.910048 -440.974734)
				(mid 398.831062 -440.993945)
				(end 398.750028 -441.000388)
			)
			(arc
				(start 398.750028 -441.000388)
				(mid 398.668992 -440.993957)
				(end 398.590008 -440.974734)
			)
			(xy 398.582134 -440.97194) (xy 393.917932 -440.97194)
			(arc
				(start 393.910058 -440.974734)
				(mid 393.831072 -440.993945)
				(end 393.750038 -441.000388)
			)
			(arc
				(start 393.750038 -441.000388)
				(mid 393.669002 -440.993957)
				(end 393.590018 -440.974734)
			)
			(xy 393.582144 -440.97194) (xy 389.91794 -440.97194)
			(arc
				(start 389.910066 -440.974734)
				(mid 389.83108 -440.993945)
				(end 389.750046 -441.000388)
			)
			(arc
				(start 389.750046 -441.000388)
				(mid 389.66901 -440.993957)
				(end 389.590026 -440.974734)
			)
			(xy 389.582152 -440.97194) (xy 385.917948 -440.97194)
			(arc
				(start 385.910074 -440.974734)
				(mid 385.831088 -440.993945)
				(end 385.750054 -441.000388)
			)
			(arc
				(start 385.750054 -441.000388)
				(mid 385.669018 -440.993957)
				(end 385.590034 -440.974734)
			)
			(xy 385.58216 -440.97194) (xy 381.917956 -440.97194)
			(arc
				(start 381.910082 -440.974734)
				(mid 381.831096 -440.993945)
				(end 381.750062 -441.000388)
			)
			(arc
				(start 381.750062 -441.000388)
				(mid 381.669026 -440.993957)
				(end 381.590042 -440.974734)
			)
			(xy 381.582168 -440.97194) (xy 343.817956 -440.97194)
			(arc
				(start 343.810082 -440.974734)
				(mid 343.731096 -440.993945)
				(end 343.650062 -441.000388)
			)
			(arc
				(start 343.650062 -441.000388)
				(mid 343.569026 -440.993957)
				(end 343.490042 -440.974734)
			)
			(xy 343.482168 -440.97194) (xy 339.817964 -440.97194)
			(arc
				(start 339.81009 -440.974734)
				(mid 339.731104 -440.993945)
				(end 339.65007 -441.000388)
			)
			(arc
				(start 339.65007 -441.000388)
				(mid 339.569034 -440.993957)
				(end 339.49005 -440.974734)
			)
			(xy 339.482176 -440.97194) (xy 335.817972 -440.97194)
			(arc
				(start 335.810098 -440.974734)
				(mid 335.731112 -440.993945)
				(end 335.650078 -441.000388)
			)
			(arc
				(start 335.650078 -441.000388)
				(mid 335.569042 -440.993957)
				(end 335.490058 -440.974734)
			)
			(xy 335.482184 -440.97194) (xy 331.81798 -440.97194)
			(arc
				(start 331.810106 -440.974734)
				(mid 331.73112 -440.993945)
				(end 331.650086 -441.000388)
			)
			(arc
				(start 331.650086 -441.000388)
				(mid 331.56905 -440.993957)
				(end 331.490066 -440.974734)
			)
			(xy 331.482192 -440.97194) (xy 326.81799 -440.97194)
			(arc
				(start 326.810116 -440.974734)
				(mid 326.73113 -440.993945)
				(end 326.650096 -441.000388)
			)
			(arc
				(start 326.650096 -441.000388)
				(mid 326.56906 -440.993957)
				(end 326.490076 -440.974734)
			)
			(xy 326.482202 -440.97194) (xy 322.817998 -440.97194)
			(arc
				(start 322.810124 -440.974734)
				(mid 322.731138 -440.993945)
				(end 322.650104 -441.000388)
			)
			(arc
				(start 322.650104 -441.000388)
				(mid 322.569068 -440.993957)
				(end 322.490084 -440.974734)
			)
			(xy 322.48221 -440.97194) (xy 318.818006 -440.97194)
			(arc
				(start 318.810132 -440.974734)
				(mid 318.731146 -440.993945)
				(end 318.650112 -441.000388)
			)
			(arc
				(start 318.650112 -441.000388)
				(mid 318.569076 -440.993957)
				(end 318.490092 -440.974734)
			)
			(xy 318.482218 -440.97194) (xy 314.818014 -440.97194)
			(arc
				(start 314.81014 -440.974734)
				(mid 314.731154 -440.993945)
				(end 314.65012 -441.000388)
			)
			(arc
				(start 314.65012 -441.000388)
				(mid 314.569084 -440.993957)
				(end 314.4901 -440.974734)
			)
			(xy 314.482226 -440.97194)
			(arc
				(start 277.82012 -440.97194)
				(mid 277.31587 -440.028787)
				(end 276.314916 -439.652156)
			)
			(arc
				(start 195.50507 -439.652156)
				(mid 194.504157 -440.028834)
				(end 193.999866 -440.97194)
			)
			(xy 154.917902 -440.97194)
			(arc
				(start 154.910028 -440.974734)
				(mid 154.831042 -440.993945)
				(end 154.750008 -441.000388)
			)
			(arc
				(start 154.750008 -441.000388)
				(mid 154.668972 -440.993957)
				(end 154.589988 -440.974734)
			)
			(xy 154.582114 -440.97194) (xy 150.91791 -440.97194)
			(arc
				(start 150.910036 -440.974734)
				(mid 150.83105 -440.993945)
				(end 150.750016 -441.000388)
			)
			(arc
				(start 150.750016 -441.000388)
				(mid 150.66898 -440.993957)
				(end 150.589996 -440.974734)
			)
			(xy 150.582122 -440.97194) (xy 146.917918 -440.97194)
			(arc
				(start 146.910044 -440.974734)
				(mid 146.831058 -440.993945)
				(end 146.750024 -441.000388)
			)
			(arc
				(start 146.750024 -441.000388)
				(mid 146.668988 -440.993957)
				(end 146.590004 -440.974734)
			)
			(xy 146.58213 -440.97194) (xy 142.917926 -440.97194)
			(arc
				(start 142.910052 -440.974734)
				(mid 142.831066 -440.993945)
				(end 142.750032 -441.000388)
			)
			(arc
				(start 142.750032 -441.000388)
				(mid 142.668996 -440.993957)
				(end 142.590012 -440.974734)
			)
			(xy 142.582138 -440.97194) (xy 137.917936 -440.97194)
			(arc
				(start 137.910062 -440.974734)
				(mid 137.831076 -440.993945)
				(end 137.750042 -441.000388)
			)
			(arc
				(start 137.750042 -441.000388)
				(mid 137.669006 -440.993957)
				(end 137.590022 -440.974734)
			)
			(xy 137.582148 -440.97194) (xy 133.917944 -440.97194)
			(arc
				(start 133.91007 -440.974734)
				(mid 133.831084 -440.993945)
				(end 133.75005 -441.000388)
			)
			(arc
				(start 133.75005 -441.000388)
				(mid 133.669014 -440.993957)
				(end 133.59003 -440.974734)
			)
			(xy 133.582156 -440.97194) (xy 129.917952 -440.97194)
			(arc
				(start 129.910078 -440.974734)
				(mid 129.831092 -440.993945)
				(end 129.750058 -441.000388)
			)
			(arc
				(start 129.750058 -441.000388)
				(mid 129.669022 -440.993957)
				(end 129.590038 -440.974734)
			)
			(xy 129.582164 -440.97194) (xy 125.91796 -440.97194)
			(arc
				(start 125.910086 -440.974734)
				(mid 125.8311 -440.993945)
				(end 125.750066 -441.000388)
			)
			(arc
				(start 125.750066 -441.000388)
				(mid 125.66903 -440.993957)
				(end 125.590046 -440.974734)
			)
			(xy 125.582172 -440.97194) (xy 87.81796 -440.97194)
			(arc
				(start 87.810086 -440.974734)
				(mid 87.7311 -440.993945)
				(end 87.650066 -441.000388)
			)
			(arc
				(start 87.650066 -441.000388)
				(mid 87.56903 -440.993957)
				(end 87.490046 -440.974734)
			)
			(xy 87.482172 -440.97194) (xy 83.817968 -440.97194)
			(arc
				(start 83.810094 -440.974734)
				(mid 83.731108 -440.993945)
				(end 83.650074 -441.000388)
			)
			(arc
				(start 83.650074 -441.000388)
				(mid 83.569038 -440.993957)
				(end 83.490054 -440.974734)
			)
			(xy 83.48218 -440.97194) (xy 79.817976 -440.97194)
			(arc
				(start 79.810102 -440.974734)
				(mid 79.731116 -440.993945)
				(end 79.650082 -441.000388)
			)
			(arc
				(start 79.650082 -441.000388)
				(mid 79.569046 -440.993957)
				(end 79.490062 -440.974734)
			)
			(xy 79.482188 -440.97194) (xy 75.817984 -440.97194)
			(arc
				(start 75.81011 -440.974734)
				(mid 75.731124 -440.993945)
				(end 75.65009 -441.000388)
			)
			(arc
				(start 75.65009 -441.000388)
				(mid 75.569054 -440.993957)
				(end 75.49007 -440.974734)
			)
			(xy 75.482196 -440.97194) (xy 70.817994 -440.97194)
			(arc
				(start 70.81012 -440.974734)
				(mid 70.731134 -440.993945)
				(end 70.6501 -441.000388)
			)
			(arc
				(start 70.6501 -441.000388)
				(mid 70.569064 -440.993957)
				(end 70.49008 -440.974734)
			)
			(xy 70.482206 -440.97194) (xy 66.818002 -440.97194)
			(arc
				(start 66.810128 -440.974734)
				(mid 66.731142 -440.993945)
				(end 66.650108 -441.000388)
			)
			(arc
				(start 66.650108 -441.000388)
				(mid 66.569072 -440.993957)
				(end 66.490088 -440.974734)
			)
			(xy 66.482214 -440.97194) (xy 62.81801 -440.97194)
			(arc
				(start 62.810136 -440.974734)
				(mid 62.73115 -440.993945)
				(end 62.650116 -441.000388)
			)
			(arc
				(start 62.650116 -441.000388)
				(mid 62.56908 -440.993957)
				(end 62.490096 -440.974734)
			)
			(xy 62.482222 -440.97194) (xy 58.818018 -440.97194)
			(arc
				(start 58.810144 -440.974734)
				(mid 58.731158 -440.993945)
				(end 58.650124 -441.000388)
			)
			(arc
				(start 58.650124 -441.000388)
				(mid 58.569088 -440.993957)
				(end 58.490104 -440.974734)
			)
			(xy 58.48223 -440.97194)
			(arc
				(start 8.50011 -440.97194)
				(mid 7.805667 -440.684345)
				(end 7.517892 -439.989976)
			)
			(arc
				(start 7.517892 -409.528264)
				(mid 7.287997 -408.373534)
				(end 6.633718 -407.394664)
			)
			(arc
				(start 3.305302 -404.066248)
				(mid 3.092701 -403.747829)
				(end 3.018028 -403.37232)
			)
			(arc
				(start 3.018028 -81.32826)
				(mid 2.788133 -80.17353)
				(end 2.133854 -79.19466)
			)
			(arc
				(start 1.305306 -78.366112)
				(mid 1.092705 -78.047693)
				(end 1.018032 -77.672184)
			)
			(arc
				(start 1.018032 -42.244772)
				(mid 1.013298 -42.223357)
				(end 0.999998 -42.20591)
			)
			(arc
				(start 0.999998 -42.20591)
				(mid 0.873253 -41.933622)
				(end 0.999998 -41.661334)
			)
			(arc
				(start 0.999998 -41.661334)
				(mid 1.013327 -41.6439)
				(end 1.018032 -41.622472)
			)
			(arc
				(start 1.018032 -41.222422)
				(mid 1.013298 -41.201007)
				(end 0.999998 -41.18356)
			)
			(arc
				(start 0.999998 -41.18356)
				(mid 0.873253 -40.911272)
				(end 0.999998 -40.638984)
			)
			(arc
				(start 0.999998 -40.638984)
				(mid 1.013327 -40.62155)
				(end 1.018032 -40.600122)
			)
			(arc
				(start 1.018032 -40.167814)
				(mid 1.012748 -40.145255)
				(end 0.997966 -40.127428)
			)
			(arc
				(start 0.997966 -40.127428)
				(mid 0.84779 -39.824152)
				(end 0.997966 -39.520876)
			)
			(arc
				(start 0.997966 -39.520876)
				(mid 1.012704 -39.503027)
				(end 1.018032 -39.48049)
			)
			(arc
				(start 1.018032 -39.099998)
				(mid 1.013298 -39.078583)
				(end 0.999998 -39.061136)
			)
			(arc
				(start 0.999998 -39.061136)
				(mid 0.873253 -38.788848)
				(end 0.999998 -38.51656)
			)
			(arc
				(start 0.999998 -38.51656)
				(mid 1.013327 -38.499126)
				(end 1.018032 -38.477698)
			)
			(arc
				(start 1.018032 -38.110414)
				(mid 1.011311 -38.085415)
				(end 0.99314 -38.06698)
			)
			(arc
				(start 0.99314 -38.06698)
				(mid 0.807128 -37.73932)
				(end 0.99314 -37.41166)
			)
			(arc
				(start 0.99314 -37.41166)
				(mid 1.011304 -37.393221)
				(end 1.018032 -37.368226)
			)
			(arc
				(start 1.018032 -37.067236)
				(mid 1.011311 -37.042237)
				(end 0.99314 -37.023802)
			)
			(arc
				(start 0.99314 -37.023802)
				(mid 0.807128 -36.696142)
				(end 0.99314 -36.368482)
			)
			(arc
				(start 0.99314 -36.368482)
				(mid 1.011304 -36.350043)
				(end 1.018032 -36.325048)
			)
			(arc
				(start 1.018032 -35.987228)
				(mid 1.011311 -35.962229)
				(end 0.99314 -35.943794)
			)
			(arc
				(start 0.99314 -35.943794)
				(mid 0.807128 -35.616134)
				(end 0.99314 -35.288474)
			)
			(arc
				(start 0.99314 -35.288474)
				(mid 1.011304 -35.270035)
				(end 1.018032 -35.24504)
			)
			(arc
				(start 1.018032 -26.980642)
				(mid 1.010858 -26.954615)
				(end 0.991362 -26.935938)
			)
			(arc
				(start 0.991362 -26.935938)
				(mid 0.827352 -26.84333)
				(end 0.66675 -26.74493)
			)
			(xy 0.654812 -26.73731) (xy 0.62738 -26.736294)
			(arc
				(start 0.536956 -26.786078)
				(mid 0.517713 -26.8047)
				(end 0.51054 -26.830528)
			)
			(arc
				(start 0.51054 -77.671676)
				(mid 0.623884 -78.241583)
				(end 0.946658 -78.72476)
			)
			(arc
				(start 1.775206 -79.553308)
				(mid 2.319424 -80.367648)
				(end 2.510536 -81.32826)
			)
			(arc
				(start 2.510536 -403.371812)
				(mid 2.62388 -403.941719)
				(end 2.946654 -404.424896)
			)
			(arc
				(start 6.27507 -407.753312)
				(mid 6.819424 -408.567623)
				(end 7.010654 -409.528264)
			)
			(arc
				(start 7.010654 -439.989976)
				(mid 7.446906 -441.04318)
				(end 8.50011 -441.479432)
			)
		)
		(stroke
			(width 0)
			(type solid)
		)
		(fill yes)
		(layer "In11.Cu")
		(net "GND")
	)
	(gr_poly
		(pts
			(xy 350.932496 -265.726926) (xy 350.947615 -265.726389) (xy 350.976535 -265.717563) (xy 351.001601 -265.700654)
			(xy 351.020616 -265.677145) (xy 351.031911 -265.649097) (xy 351.034497 -265.618971) (xy 351.028146 -265.589409)
			(xy 351.013415 -265.563004) (xy 351.002854 -265.552174) (xy 350.984096 -265.533335) (xy 350.95224 -265.490777)
			(xy 350.927603 -265.443672) (xy 350.910818 -265.393231) (xy 350.902318 -265.340756) (xy 350.901762 -265.314176)
			(xy 350.902271 -265.288209) (xy 350.910396 -265.236914) (xy 350.926444 -265.187521) (xy 350.950022 -265.141247)
			(xy 350.980548 -265.099231) (xy 351.017271 -265.062508) (xy 351.059287 -265.031982) (xy 351.105561 -265.008404)
			(xy 351.154954 -264.992356) (xy 351.206249 -264.984231) (xy 351.258183 -264.984231) (xy 351.309478 -264.992356)
			(xy 351.358871 -265.008404) (xy 351.405145 -265.031982) (xy 351.447161 -265.062508) (xy 351.483884 -265.099231)
			(xy 351.51441 -265.141247) (xy 351.537988 -265.187521) (xy 351.554036 -265.236914) (xy 351.562161 -265.288209)
			(xy 351.56267 -265.314176) (xy 351.562142 -265.340758) (xy 351.55364 -265.393236) (xy 351.536851 -265.443679)
			(xy 351.512208 -265.490785) (xy 351.480345 -265.533342) (xy 351.461578 -265.552174) (xy 351.451085 -265.56304)
			(xy 351.436415 -265.589427) (xy 351.430102 -265.61895) (xy 351.432701 -265.649029) (xy 351.443982 -265.677033)
			(xy 351.46296 -265.700513) (xy 351.487976 -265.717416) (xy 351.516841 -265.726264) (xy 351.531936 -265.726926)
			(xy 351.872296 -265.726926) (xy 351.887415 -265.726389) (xy 351.916335 -265.717563) (xy 351.941401 -265.700654)
			(xy 351.960416 -265.677145) (xy 351.971711 -265.649097) (xy 351.974297 -265.618971) (xy 351.967946 -265.589409)
			(xy 351.953215 -265.563004) (xy 351.942654 -265.552174) (xy 351.923896 -265.533335) (xy 351.89204 -265.490777)
			(xy 351.867403 -265.443672) (xy 351.850618 -265.393231) (xy 351.842118 -265.340756) (xy 351.841562 -265.314176)
			(xy 351.842071 -265.288209) (xy 351.850196 -265.236914) (xy 351.866244 -265.187521) (xy 351.889822 -265.141247)
			(xy 351.920348 -265.099231) (xy 351.957071 -265.062508) (xy 351.999087 -265.031982) (xy 352.045361 -265.008404)
			(xy 352.094754 -264.992356) (xy 352.146049 -264.984231) (xy 352.197983 -264.984231) (xy 352.249278 -264.992356)
			(xy 352.298671 -265.008404) (xy 352.344945 -265.031982) (xy 352.386961 -265.062508) (xy 352.423684 -265.099231)
			(xy 352.45421 -265.141247) (xy 352.477788 -265.187521) (xy 352.493836 -265.236914) (xy 352.501961 -265.288209)
			(xy 352.50247 -265.314176) (xy 352.501942 -265.340758) (xy 352.49344 -265.393236) (xy 352.476651 -265.443679)
			(xy 352.452008 -265.490785) (xy 352.420145 -265.533342) (xy 352.401378 -265.552174) (xy 352.390885 -265.56304)
			(xy 352.376215 -265.589427) (xy 352.369902 -265.61895) (xy 352.372501 -265.649029) (xy 352.383782 -265.677033)
			(xy 352.40276 -265.700513) (xy 352.427776 -265.717416) (xy 352.456641 -265.726264) (xy 352.471736 -265.726926)
			(xy 352.509582 -265.726926) (xy 352.802444 -265.434064) (xy 352.794062 -265.405362) (xy 352.788109 -265.383037)
			(xy 352.781731 -265.337277) (xy 352.781362 -265.314176) (xy 352.781865 -265.288324) (xy 352.789924 -265.237253)
			(xy 352.805841 -265.188061) (xy 352.829228 -265.141949) (xy 352.859514 -265.100044) (xy 352.895958 -265.063369)
			(xy 352.937671 -265.03282) (xy 352.960432 -265.020552) (xy 352.987864 -265.006328) (xy 352.987864 -264.856468)
			(xy 352.987399 -264.842664) (xy 352.97999 -264.816069) (xy 352.965723 -264.792434) (xy 352.945642 -264.773488)
			(xy 352.921218 -264.760619) (xy 352.894237 -264.754768) (xy 352.866676 -264.756363) (xy 352.840551 -264.765289)
			(xy 352.82886 -264.772648) (xy 352.808098 -264.786384) (xy 352.763314 -264.808124) (xy 352.715773 -264.822889)
			(xy 352.666553 -264.830346) (xy 352.641662 -264.830814) (xy 352.6157 -264.830302) (xy 352.564416 -264.822174)
			(xy 352.515034 -264.806124) (xy 352.468771 -264.782547) (xy 352.426765 -264.752024) (xy 352.390052 -264.715306)
			(xy 352.359533 -264.673296) (xy 352.335962 -264.627031) (xy 352.319917 -264.577647) (xy 352.311795 -264.526362)
			(xy 352.311795 -264.474438) (xy 352.319917 -264.423153) (xy 352.335962 -264.373769) (xy 352.359533 -264.327504)
			(xy 352.390052 -264.285494) (xy 352.426765 -264.248776) (xy 352.468771 -264.218253) (xy 352.515034 -264.194676)
			(xy 352.564416 -264.178626) (xy 352.6157 -264.170498) (xy 352.641662 -264.169906) (xy 352.666552 -264.170362)
			(xy 352.715767 -264.177839) (xy 352.763303 -264.192615) (xy 352.808085 -264.214356) (xy 352.82886 -264.228072)
			(xy 352.840518 -264.235498) (xy 352.866663 -264.244428) (xy 352.894246 -264.246024) (xy 352.921247 -264.240169)
			(xy 352.945691 -264.22729) (xy 352.965788 -264.208332) (xy 352.980069 -264.18468) (xy 352.987488 -264.158066)
			(xy 352.987864 -264.144252) (xy 352.987864 -261.570978) (xy 352.970084 -261.552944) (xy 352.960251 -261.542964)
			(xy 352.936367 -261.528338) (xy 352.909411 -261.520739) (xy 352.881405 -261.520739) (xy 352.854449 -261.528338)
			(xy 352.830565 -261.542964) (xy 352.820732 -261.552944) (xy 352.801821 -261.572639) (xy 352.758724 -261.606158)
			(xy 352.710701 -261.63213) (xy 352.659059 -261.649849) (xy 352.605206 -261.658832) (xy 352.577908 -261.65937)
			(xy 352.551937 -261.658888) (xy 352.500634 -261.650763) (xy 352.451234 -261.634713) (xy 352.404953 -261.611133)
			(xy 352.362931 -261.580603) (xy 352.326202 -261.543875) (xy 352.295671 -261.501853) (xy 352.27209 -261.455573)
			(xy 352.256039 -261.406173) (xy 352.247913 -261.354871) (xy 352.247913 -261.302929) (xy 352.256039 -261.251627)
			(xy 352.27209 -261.202227) (xy 352.295671 -261.155947) (xy 352.326202 -261.113925) (xy 352.362931 -261.077197)
			(xy 352.404953 -261.046667) (xy 352.451234 -261.023087) (xy 352.500634 -261.007037) (xy 352.551937 -260.998912)
			(xy 352.577908 -260.998462) (xy 352.605205 -260.999025) (xy 352.659055 -261.008005) (xy 352.710695 -261.02572)
			(xy 352.758718 -261.051687) (xy 352.801817 -261.085199) (xy 352.820732 -261.104888) (xy 352.830565 -261.114868)
			(xy 352.854449 -261.129494) (xy 352.881405 -261.137093) (xy 352.909411 -261.137093) (xy 352.936367 -261.129494)
			(xy 352.960251 -261.114868) (xy 352.970084 -261.104888) (xy 352.987864 -261.086854) (xy 352.987864 -257.192526)
			(xy 352.556064 -256.760726) (xy 351.057464 -256.760726) (xy 350.622616 -257.195574) (xy 350.620584 -257.2131)
			(xy 350.617314 -257.237514) (xy 350.604476 -257.285066) (xy 350.584719 -257.330185) (xy 350.558482 -257.37187)
			(xy 350.526347 -257.409198) (xy 350.489026 -257.441341) (xy 350.447346 -257.467587) (xy 350.402231 -257.487353)
			(xy 350.354681 -257.500201) (xy 350.330262 -257.503422) (xy 350.312736 -257.505454) (xy 350.061276 -257.756914)
			(xy 350.087438 -257.791966) (xy 350.102791 -257.81347) (xy 350.127179 -257.860339) (xy 350.143794 -257.910493)
			(xy 350.152211 -257.962653) (xy 350.152716 -257.98907) (xy 350.152235 -258.01504) (xy 350.144114 -258.06634)
			(xy 350.128066 -258.115738) (xy 350.104487 -258.162017) (xy 350.073959 -258.204038) (xy 350.037231 -258.240764)
			(xy 349.995211 -258.271292) (xy 349.948931 -258.294869) (xy 349.899532 -258.310916) (xy 349.848232 -258.319036)
			(xy 349.822262 -258.319524) (xy 349.800527 -258.319176) (xy 349.757434 -258.313467) (xy 349.715462 -258.302154)
			(xy 349.695262 -258.294124) (xy 349.681033 -258.288798) (xy 349.65081 -258.285852) (xy 349.621053 -258.291901)
			(xy 349.594379 -258.306411) (xy 349.573133 -258.328108) (xy 349.565722 -258.341368) (xy 349.557246 -258.357619)
			(xy 349.53895 -258.389382) (xy 349.529146 -258.404868) (xy 349.521429 -258.417927) (xy 349.513271 -258.447126)
			(xy 349.514045 -258.477434) (xy 349.523685 -258.506178) (xy 349.54134 -258.530824) (xy 349.553022 -258.540504)
			(xy 349.572829 -258.55626) (xy 349.607875 -258.592772) (xy 349.636952 -258.634196) (xy 349.659382 -258.679564)
			(xy 349.67464 -258.727819) (xy 349.682372 -258.777835) (xy 349.682816 -258.80314) (xy 349.682304 -258.829104)
			(xy 349.682304 -258.829107) (xy 349.961963 -258.829107) (xy 349.961963 -258.777173) (xy 349.970088 -258.725878)
			(xy 349.986136 -258.676485) (xy 350.009714 -258.630211) (xy 350.04024 -258.588195) (xy 350.076963 -258.551472)
			(xy 350.118979 -258.520946) (xy 350.165253 -258.497368) (xy 350.214646 -258.48132) (xy 350.265941 -258.473195)
			(xy 350.317875 -258.473195) (xy 350.36917 -258.48132) (xy 350.418563 -258.497368) (xy 350.464837 -258.520946)
			(xy 350.506853 -258.551472) (xy 350.543576 -258.588195) (xy 350.574102 -258.630211) (xy 350.59768 -258.676485)
			(xy 350.613728 -258.725878) (xy 350.621853 -258.777173) (xy 350.622362 -258.80314) (xy 350.621853 -258.829107)
			(xy 350.613728 -258.880402) (xy 350.59768 -258.929795) (xy 350.574102 -258.976069) (xy 350.543576 -259.018085)
			(xy 350.506853 -259.054808) (xy 350.464837 -259.085334) (xy 350.418563 -259.108912) (xy 350.36917 -259.12496)
			(xy 350.317875 -259.133085) (xy 350.265941 -259.133085) (xy 350.214646 -259.12496) (xy 350.165253 -259.108912)
			(xy 350.118979 -259.085334) (xy 350.076963 -259.054808) (xy 350.04024 -259.018085) (xy 350.009714 -258.976069)
			(xy 349.986136 -258.929795) (xy 349.970088 -258.880402) (xy 349.961963 -258.829107) (xy 349.682304 -258.829107)
			(xy 349.674174 -258.880392) (xy 349.658122 -258.929777) (xy 349.634541 -258.976042) (xy 349.604013 -259.01805)
			(xy 349.56729 -259.054764) (xy 349.525276 -259.085282) (xy 349.479005 -259.108851) (xy 349.429616 -259.124892)
			(xy 349.378326 -259.13301) (xy 349.352362 -259.133594) (xy 349.330627 -259.133246) (xy 349.287534 -259.127537)
			(xy 349.245563 -259.116223) (xy 349.225362 -259.108194) (xy 349.211135 -259.102865) (xy 349.180914 -259.099917)
			(xy 349.151159 -259.105968) (xy 349.124489 -259.120485) (xy 349.103255 -259.142189) (xy 349.095822 -259.155438)
			(xy 349.087339 -259.171623) (xy 349.069045 -259.20326) (xy 349.059246 -259.218684) (xy 349.051538 -259.231746)
			(xy 349.043392 -259.260943) (xy 349.04417 -259.291246) (xy 349.053804 -259.319987) (xy 349.071446 -259.344637)
			(xy 349.083122 -259.35432) (xy 349.102928 -259.370077) (xy 349.137973 -259.406589) (xy 349.167048 -259.448013)
			(xy 349.189475 -259.493381) (xy 349.204731 -259.541636) (xy 349.21246 -259.591652) (xy 349.212916 -259.616956)
			(xy 349.212411 -259.642923) (xy 349.492317 -259.642923) (xy 349.492317 -259.590989) (xy 349.500442 -259.539694)
			(xy 349.51649 -259.490301) (xy 349.540068 -259.444027) (xy 349.570594 -259.402011) (xy 349.607317 -259.365288)
			(xy 349.649333 -259.334762) (xy 349.695607 -259.311184) (xy 349.745 -259.295136) (xy 349.796295 -259.287011)
			(xy 349.848229 -259.287011) (xy 349.899524 -259.295136) (xy 349.948917 -259.311184) (xy 349.995191 -259.334762)
			(xy 350.037207 -259.365288) (xy 350.07393 -259.402011) (xy 350.104456 -259.444027) (xy 350.128034 -259.490301)
			(xy 350.144082 -259.539694) (xy 350.152207 -259.590989) (xy 350.152716 -259.616956) (xy 350.152207 -259.642923)
			(xy 350.144082 -259.694218) (xy 350.134917 -259.722425) (xy 350.476567 -259.722425) (xy 350.476567 -259.670491)
			(xy 350.484692 -259.619196) (xy 350.50074 -259.569803) (xy 350.524318 -259.523529) (xy 350.554844 -259.481513)
			(xy 350.591567 -259.44479) (xy 350.633583 -259.414264) (xy 350.679857 -259.390686) (xy 350.72925 -259.374638)
			(xy 350.780545 -259.366513) (xy 350.832479 -259.366513) (xy 350.883774 -259.374638) (xy 350.933167 -259.390686)
			(xy 350.979441 -259.414264) (xy 351.021457 -259.44479) (xy 351.05818 -259.481513) (xy 351.088706 -259.523529)
			(xy 351.112284 -259.569803) (xy 351.128332 -259.619196) (xy 351.136457 -259.670491) (xy 351.136966 -259.696458)
			(xy 351.136457 -259.722425) (xy 351.128332 -259.77372) (xy 351.112284 -259.823113) (xy 351.088706 -259.869387)
			(xy 351.05818 -259.911403) (xy 351.021457 -259.948126) (xy 350.979441 -259.978652) (xy 350.933167 -260.00223)
			(xy 350.883774 -260.018278) (xy 350.832479 -260.026403) (xy 350.780545 -260.026403) (xy 350.72925 -260.018278)
			(xy 350.679857 -260.00223) (xy 350.633583 -259.978652) (xy 350.591567 -259.948126) (xy 350.554844 -259.911403)
			(xy 350.524318 -259.869387) (xy 350.50074 -259.823113) (xy 350.484692 -259.77372) (xy 350.476567 -259.722425)
			(xy 350.134917 -259.722425) (xy 350.128034 -259.743611) (xy 350.104456 -259.789885) (xy 350.07393 -259.831901)
			(xy 350.037207 -259.868624) (xy 349.995191 -259.89915) (xy 349.948917 -259.922728) (xy 349.899524 -259.938776)
			(xy 349.848229 -259.946901) (xy 349.796295 -259.946901) (xy 349.745 -259.938776) (xy 349.695607 -259.922728)
			(xy 349.649333 -259.89915) (xy 349.607317 -259.868624) (xy 349.570594 -259.831901) (xy 349.540068 -259.789885)
			(xy 349.51649 -259.743611) (xy 349.500442 -259.694218) (xy 349.492317 -259.642923) (xy 349.212411 -259.642923)
			(xy 349.212394 -259.643815) (xy 349.203709 -259.696825) (xy 349.186561 -259.747731) (xy 349.161402 -259.795192)
			(xy 349.128895 -259.837956) (xy 349.089897 -259.874897) (xy 349.045435 -259.905041) (xy 348.996681 -259.927594)
			(xy 348.944921 -259.94196) (xy 348.918276 -259.945378) (xy 348.873064 -259.950458) (xy 348.873064 -260.456739)
			(xy 349.022671 -260.456739) (xy 349.022671 -260.404805) (xy 349.030796 -260.35351) (xy 349.046844 -260.304117)
			(xy 349.070422 -260.257843) (xy 349.100948 -260.215827) (xy 349.137671 -260.179104) (xy 349.179687 -260.148578)
			(xy 349.225961 -260.125) (xy 349.275354 -260.108952) (xy 349.326649 -260.100827) (xy 349.378583 -260.100827)
			(xy 349.429878 -260.108952) (xy 349.479271 -260.125) (xy 349.525545 -260.148578) (xy 349.567561 -260.179104)
			(xy 349.604284 -260.215827) (xy 349.63481 -260.257843) (xy 349.658388 -260.304117) (xy 349.674436 -260.35351)
			(xy 349.682561 -260.404805) (xy 349.68307 -260.430772) (xy 349.682561 -260.456739) (xy 349.682556 -260.456772)
			(xy 349.962401 -260.456772) (xy 349.962401 -260.404828) (xy 349.970527 -260.353523) (xy 349.986579 -260.304121)
			(xy 350.010162 -260.257838) (xy 350.040695 -260.215815) (xy 350.077427 -260.179085) (xy 350.119452 -260.148554)
			(xy 350.165735 -260.124973) (xy 350.215138 -260.108923) (xy 350.266444 -260.1008) (xy 350.292416 -260.100318)
			(xy 350.319503 -260.100867) (xy 350.37295 -260.109705) (xy 350.42424 -260.127142) (xy 350.472 -260.15271)
			(xy 350.51495 -260.185726) (xy 350.551941 -260.225304) (xy 350.581981 -260.270385) (xy 350.604267 -260.319763)
			(xy 350.6182 -260.372113) (xy 350.621346 -260.399022) (xy 350.623184 -260.413163) (xy 350.63358 -260.4397)
			(xy 350.650914 -260.462323) (xy 350.673831 -260.479266) (xy 350.700543 -260.489205) (xy 350.728962 -260.491364)
			(xy 350.743012 -260.488938) (xy 350.759467 -260.485761) (xy 350.792803 -260.482322) (xy 350.80956 -260.48208)
			(xy 350.835534 -260.482492) (xy 350.886843 -260.490613) (xy 350.93625 -260.506661) (xy 350.982538 -260.530241)
			(xy 351.024567 -260.560772) (xy 351.061302 -260.597502) (xy 351.091838 -260.639528) (xy 351.115424 -260.685813)
			(xy 351.131478 -260.735218) (xy 351.139605 -260.786526) (xy 351.139605 -260.838474) (xy 351.131478 -260.889782)
			(xy 351.115424 -260.939187) (xy 351.091838 -260.985472) (xy 351.061302 -261.027498) (xy 351.024567 -261.064228)
			(xy 350.982538 -261.094759) (xy 350.93625 -261.118339) (xy 350.886843 -261.134387) (xy 350.835534 -261.142508)
			(xy 350.80956 -261.142988) (xy 350.782473 -261.142455) (xy 350.729025 -261.133614) (xy 350.677735 -261.116174)
			(xy 350.629975 -261.090603) (xy 350.587026 -261.057585) (xy 350.550035 -261.018006) (xy 350.519996 -260.972923)
			(xy 350.49771 -260.923545) (xy 350.483776 -260.871193) (xy 350.48063 -260.844284) (xy 350.478815 -260.830139)
			(xy 350.468417 -260.803598) (xy 350.45108 -260.780972) (xy 350.428157 -260.764028) (xy 350.40144 -260.754092)
			(xy 350.373016 -260.751938) (xy 350.358964 -260.754368) (xy 350.34251 -260.757548) (xy 350.309173 -260.760986)
			(xy 350.292416 -260.761226) (xy 350.266444 -260.7608) (xy 350.215138 -260.752677) (xy 350.165735 -260.736627)
			(xy 350.119452 -260.713046) (xy 350.077427 -260.682515) (xy 350.040695 -260.645785) (xy 350.010162 -260.603762)
			(xy 349.986579 -260.557479) (xy 349.970527 -260.508077) (xy 349.962401 -260.456772) (xy 349.682556 -260.456772)
			(xy 349.674436 -260.508034) (xy 349.658388 -260.557427) (xy 349.63481 -260.603701) (xy 349.604284 -260.645717)
			(xy 349.567561 -260.68244) (xy 349.525545 -260.712966) (xy 349.479271 -260.736544) (xy 349.429878 -260.752592)
			(xy 349.378583 -260.760717) (xy 349.326649 -260.760717) (xy 349.275354 -260.752592) (xy 349.225961 -260.736544)
			(xy 349.179687 -260.712966) (xy 349.137671 -260.68244) (xy 349.100948 -260.645717) (xy 349.070422 -260.603701)
			(xy 349.046844 -260.557427) (xy 349.030796 -260.508034) (xy 349.022671 -260.456739) (xy 348.873064 -260.456739)
			(xy 348.873064 -260.91134) (xy 348.918276 -260.91642) (xy 348.943512 -260.919641) (xy 348.992644 -260.93284)
			(xy 349.039171 -260.953415) (xy 349.081993 -260.980881) (xy 349.120098 -261.014587) (xy 349.152585 -261.053737)
			(xy 349.178685 -261.097405) (xy 349.197781 -261.144558) (xy 349.209423 -261.194082) (xy 349.213334 -261.244805)
			(xy 349.211328 -261.270809) (xy 349.492317 -261.270809) (xy 349.492317 -261.218875) (xy 349.500442 -261.16758)
			(xy 349.51649 -261.118187) (xy 349.540068 -261.071913) (xy 349.570594 -261.029897) (xy 349.607317 -260.993174)
			(xy 349.649333 -260.962648) (xy 349.695607 -260.93907) (xy 349.745 -260.923022) (xy 349.796295 -260.914897)
			(xy 349.848229 -260.914897) (xy 349.899524 -260.923022) (xy 349.948917 -260.93907) (xy 349.995191 -260.962648)
			(xy 350.037207 -260.993174) (xy 350.07393 -261.029897) (xy 350.104456 -261.071913) (xy 350.128034 -261.118187)
			(xy 350.144082 -261.16758) (xy 350.152207 -261.218875) (xy 350.152716 -261.244842) (xy 350.152207 -261.270809)
			(xy 350.144082 -261.322104) (xy 350.128034 -261.371497) (xy 350.104456 -261.417771) (xy 350.07393 -261.459787)
			(xy 350.037207 -261.49651) (xy 349.995191 -261.527036) (xy 349.948917 -261.550614) (xy 349.899524 -261.566662)
			(xy 349.848229 -261.574787) (xy 349.796295 -261.574787) (xy 349.745 -261.566662) (xy 349.695607 -261.550614)
			(xy 349.649333 -261.527036) (xy 349.607317 -261.49651) (xy 349.570594 -261.459787) (xy 349.540068 -261.417771)
			(xy 349.51649 -261.371497) (xy 349.500442 -261.322104) (xy 349.492317 -261.270809) (xy 349.211328 -261.270809)
			(xy 349.209421 -261.295527) (xy 349.197779 -261.345051) (xy 349.178681 -261.392203) (xy 349.152579 -261.43587)
			(xy 349.120092 -261.47502) (xy 349.081986 -261.508725) (xy 349.039163 -261.536189) (xy 348.992635 -261.556763)
			(xy 348.943503 -261.569961) (xy 348.918276 -261.573264) (xy 348.873064 -261.578344) (xy 348.873064 -262.084625)
			(xy 349.022671 -262.084625) (xy 349.022671 -262.032691) (xy 349.030796 -261.981396) (xy 349.046844 -261.932003)
			(xy 349.070422 -261.885729) (xy 349.100948 -261.843713) (xy 349.137671 -261.80699) (xy 349.179687 -261.776464)
			(xy 349.225961 -261.752886) (xy 349.275354 -261.736838) (xy 349.326649 -261.728713) (xy 349.378583 -261.728713)
			(xy 349.429878 -261.736838) (xy 349.479271 -261.752886) (xy 349.525545 -261.776464) (xy 349.567561 -261.80699)
			(xy 349.604284 -261.843713) (xy 349.63481 -261.885729) (xy 349.658388 -261.932003) (xy 349.674436 -261.981396)
			(xy 349.682561 -262.032691) (xy 349.68307 -262.058658) (xy 349.682561 -262.084625) (xy 349.962471 -262.084625)
			(xy 349.962471 -262.032691) (xy 349.970596 -261.981396) (xy 349.986644 -261.932003) (xy 350.010222 -261.885729)
			(xy 350.040748 -261.843713) (xy 350.077471 -261.80699) (xy 350.119487 -261.776464) (xy 350.165761 -261.752886)
			(xy 350.215154 -261.736838) (xy 350.266449 -261.728713) (xy 350.318383 -261.728713) (xy 350.369678 -261.736838)
			(xy 350.419071 -261.752886) (xy 350.465345 -261.776464) (xy 350.507361 -261.80699) (xy 350.544084 -261.843713)
			(xy 350.57461 -261.885729) (xy 350.598188 -261.932003) (xy 350.614236 -261.981396) (xy 350.622361 -262.032691)
			(xy 350.62287 -262.058658) (xy 350.622361 -262.084625) (xy 350.614236 -262.13592) (xy 350.598188 -262.185313)
			(xy 350.57461 -262.231587) (xy 350.544084 -262.273603) (xy 350.507361 -262.310326) (xy 350.465345 -262.340852)
			(xy 350.419071 -262.36443) (xy 350.369678 -262.380478) (xy 350.318383 -262.388603) (xy 350.266449 -262.388603)
			(xy 350.215154 -262.380478) (xy 350.165761 -262.36443) (xy 350.119487 -262.340852) (xy 350.077471 -262.310326)
			(xy 350.040748 -262.273603) (xy 350.010222 -262.231587) (xy 349.986644 -262.185313) (xy 349.970596 -262.13592)
			(xy 349.962471 -262.084625) (xy 349.682561 -262.084625) (xy 349.674436 -262.13592) (xy 349.658388 -262.185313)
			(xy 349.63481 -262.231587) (xy 349.604284 -262.273603) (xy 349.567561 -262.310326) (xy 349.525545 -262.340852)
			(xy 349.479271 -262.36443) (xy 349.429878 -262.380478) (xy 349.378583 -262.388603) (xy 349.326649 -262.388603)
			(xy 349.275354 -262.380478) (xy 349.225961 -262.36443) (xy 349.179687 -262.340852) (xy 349.137671 -262.310326)
			(xy 349.100948 -262.273603) (xy 349.070422 -262.231587) (xy 349.046844 -262.185313) (xy 349.030796 -262.13592)
			(xy 349.022671 -262.084625) (xy 348.873064 -262.084625) (xy 348.873064 -262.538972) (xy 348.918276 -262.544052)
			(xy 348.943518 -262.547273) (xy 348.992659 -262.560473) (xy 349.039196 -262.581052) (xy 349.082028 -262.608522)
			(xy 349.120142 -262.642234) (xy 349.152636 -262.681392) (xy 349.166496 -262.70458) (xy 351.32391 -262.70458)
			(xy 351.324358 -262.680028) (xy 351.331595 -262.631461) (xy 351.345936 -262.584499) (xy 351.367067 -262.540175)
			(xy 351.394521 -262.499464) (xy 351.410778 -262.48106) (xy 351.420601 -262.469586) (xy 351.433612 -262.442343)
			(xy 351.438076 -262.412485) (xy 351.433603 -262.382628) (xy 351.420584 -262.355389) (xy 351.410778 -262.3439)
			(xy 351.394494 -262.325518) (xy 351.36703 -262.284807) (xy 351.345897 -262.240478) (xy 351.33156 -262.193509)
			(xy 351.324336 -262.144935) (xy 351.32391 -262.12038) (xy 351.324419 -262.094413) (xy 351.332544 -262.043118)
			(xy 351.348592 -261.993725) (xy 351.37217 -261.947451) (xy 351.402696 -261.905435) (xy 351.439419 -261.868712)
			(xy 351.481435 -261.838186) (xy 351.527709 -261.814608) (xy 351.577102 -261.79856) (xy 351.628397 -261.790435)
			(xy 351.680331 -261.790435) (xy 351.731626 -261.79856) (xy 351.781019 -261.814608) (xy 351.827293 -261.838186)
			(xy 351.869309 -261.868712) (xy 351.906032 -261.905435) (xy 351.936558 -261.947451) (xy 351.960136 -261.993725)
			(xy 351.976184 -262.043118) (xy 351.984309 -262.094413) (xy 351.984818 -262.12038) (xy 351.984399 -262.144933)
			(xy 351.977154 -262.193501) (xy 351.962805 -262.240463) (xy 351.941669 -262.284787) (xy 351.914209 -262.325497)
			(xy 351.89795 -262.3439) (xy 351.888164 -262.355403) (xy 351.875145 -262.382635) (xy 351.870671 -262.412485)
			(xy 351.875136 -262.442337) (xy 351.888147 -262.469572) (xy 351.89795 -262.48106) (xy 351.914204 -262.499468)
			(xy 351.941674 -262.540171) (xy 351.962815 -262.584493) (xy 351.977158 -262.631457) (xy 351.984389 -262.680027)
			(xy 351.984818 -262.70458) (xy 351.984309 -262.730547) (xy 351.976184 -262.781842) (xy 351.960136 -262.831235)
			(xy 351.936558 -262.877509) (xy 351.906032 -262.919525) (xy 351.869309 -262.956248) (xy 351.827293 -262.986774)
			(xy 351.781019 -263.010352) (xy 351.731626 -263.0264) (xy 351.680331 -263.034525) (xy 351.628397 -263.034525)
			(xy 351.577102 -263.0264) (xy 351.527709 -263.010352) (xy 351.481435 -262.986774) (xy 351.439419 -262.956248)
			(xy 351.402696 -262.919525) (xy 351.37217 -262.877509) (xy 351.348592 -262.831235) (xy 351.332544 -262.781842)
			(xy 351.324419 -262.730547) (xy 351.32391 -262.70458) (xy 349.166496 -262.70458) (xy 349.178743 -262.725068)
			(xy 349.197844 -262.77223) (xy 349.209489 -262.821764) (xy 349.213402 -262.872497) (xy 349.20949 -262.92323)
			(xy 349.197846 -262.972764) (xy 349.178745 -263.019927) (xy 349.152639 -263.063604) (xy 349.120146 -263.102762)
			(xy 349.082033 -263.136475) (xy 349.039201 -263.163946) (xy 348.992665 -263.184525) (xy 348.943523 -263.197726)
			(xy 348.918276 -263.200896) (xy 348.873064 -263.205976) (xy 348.873064 -263.712511) (xy 349.022417 -263.712511)
			(xy 349.022417 -263.660577) (xy 349.030542 -263.609282) (xy 349.04659 -263.559889) (xy 349.070168 -263.513615)
			(xy 349.100694 -263.471599) (xy 349.137417 -263.434876) (xy 349.179433 -263.40435) (xy 349.225707 -263.380772)
			(xy 349.2751 -263.364724) (xy 349.326395 -263.356599) (xy 349.378329 -263.356599) (xy 349.429624 -263.364724)
			(xy 349.479017 -263.380772) (xy 349.525291 -263.40435) (xy 349.567307 -263.434876) (xy 349.60403 -263.471599)
			(xy 349.634556 -263.513615) (xy 349.658134 -263.559889) (xy 349.674182 -263.609282) (xy 349.682307 -263.660577)
			(xy 349.682816 -263.686544) (xy 349.682307 -263.712511) (xy 349.962471 -263.712511) (xy 349.962471 -263.660577)
			(xy 349.970596 -263.609282) (xy 349.986644 -263.559889) (xy 350.010222 -263.513615) (xy 350.040748 -263.471599)
			(xy 350.077471 -263.434876) (xy 350.119487 -263.40435) (xy 350.165761 -263.380772) (xy 350.215154 -263.364724)
			(xy 350.266449 -263.356599) (xy 350.318383 -263.356599) (xy 350.369678 -263.364724) (xy 350.419071 -263.380772)
			(xy 350.465345 -263.40435) (xy 350.507361 -263.434876) (xy 350.544084 -263.471599) (xy 350.57461 -263.513615)
			(xy 350.598188 -263.559889) (xy 350.614236 -263.609282) (xy 350.622361 -263.660577) (xy 350.62287 -263.686544)
			(xy 350.622361 -263.712511) (xy 350.614236 -263.763806) (xy 350.598188 -263.813199) (xy 350.57461 -263.859473)
			(xy 350.544084 -263.901489) (xy 350.507361 -263.938212) (xy 350.465345 -263.968738) (xy 350.419071 -263.992316)
			(xy 350.369678 -264.008364) (xy 350.318383 -264.016489) (xy 350.266449 -264.016489) (xy 350.215154 -264.008364)
			(xy 350.165761 -263.992316) (xy 350.119487 -263.968738) (xy 350.077471 -263.938212) (xy 350.040748 -263.901489)
			(xy 350.010222 -263.859473) (xy 349.986644 -263.813199) (xy 349.970596 -263.763806) (xy 349.962471 -263.712511)
			(xy 349.682307 -263.712511) (xy 349.674182 -263.763806) (xy 349.658134 -263.813199) (xy 349.634556 -263.859473)
			(xy 349.60403 -263.901489) (xy 349.567307 -263.938212) (xy 349.525291 -263.968738) (xy 349.479017 -263.992316)
			(xy 349.429624 -264.008364) (xy 349.378329 -264.016489) (xy 349.326395 -264.016489) (xy 349.2751 -264.008364)
			(xy 349.225707 -263.992316) (xy 349.179433 -263.968738) (xy 349.137417 -263.938212) (xy 349.100694 -263.901489)
			(xy 349.070168 -263.859473) (xy 349.04659 -263.813199) (xy 349.030542 -263.763806) (xy 349.022417 -263.712511)
			(xy 348.873064 -263.712511) (xy 348.873064 -264.166858) (xy 348.918276 -264.171938) (xy 348.943519 -264.175159)
			(xy 348.992663 -264.188359) (xy 349.039202 -264.208939) (xy 349.082035 -264.23641) (xy 349.120151 -264.270124)
			(xy 349.152647 -264.309282) (xy 349.178754 -264.35296) (xy 349.197857 -264.400125) (xy 349.209502 -264.44966)
			(xy 349.213416 -264.500396) (xy 349.211417 -264.526327) (xy 351.371917 -264.526327) (xy 351.371917 -264.474393)
			(xy 351.380042 -264.423098) (xy 351.39609 -264.373705) (xy 351.419668 -264.327431) (xy 351.450194 -264.285415)
			(xy 351.486917 -264.248692) (xy 351.528933 -264.218166) (xy 351.575207 -264.194588) (xy 351.6246 -264.17854)
			(xy 351.675895 -264.170415) (xy 351.727829 -264.170415) (xy 351.779124 -264.17854) (xy 351.828517 -264.194588)
			(xy 351.874791 -264.218166) (xy 351.916807 -264.248692) (xy 351.95353 -264.285415) (xy 351.984056 -264.327431)
			(xy 352.007634 -264.373705) (xy 352.023682 -264.423098) (xy 352.031807 -264.474393) (xy 352.032316 -264.50036)
			(xy 352.031807 -264.526327) (xy 352.023682 -264.577622) (xy 352.007634 -264.627015) (xy 351.984056 -264.673289)
			(xy 351.95353 -264.715305) (xy 351.916807 -264.752028) (xy 351.874791 -264.782554) (xy 351.828517 -264.806132)
			(xy 351.779124 -264.82218) (xy 351.727829 -264.830305) (xy 351.675895 -264.830305) (xy 351.6246 -264.82218)
			(xy 351.575207 -264.806132) (xy 351.528933 -264.782554) (xy 351.486917 -264.752028) (xy 351.450194 -264.715305)
			(xy 351.419668 -264.673289) (xy 351.39609 -264.627015) (xy 351.380042 -264.577622) (xy 351.371917 -264.526327)
			(xy 349.211417 -264.526327) (xy 349.209504 -264.551131) (xy 349.19786 -264.600667) (xy 349.178758 -264.647832)
			(xy 349.152652 -264.691511) (xy 349.120157 -264.73067) (xy 349.082042 -264.764385) (xy 349.039209 -264.791857)
			(xy 348.992671 -264.812438) (xy 348.943527 -264.82564) (xy 348.918276 -264.828782) (xy 348.873064 -264.833862)
			(xy 348.873064 -265.574526) (xy 349.025464 -265.726926)
		)
		(stroke
			(width 0)
			(type solid)
		)
		(fill yes)
		(layer "In11.Cu")
		(net "PVCCFA_EHV_CPU0")
	)
	(gr_poly
		(pts
			(xy 359.264458 -366.7125) (xy 359.274799 -366.711966) (xy 359.293773 -366.703725) (xy 359.30797 -366.688679)
			(xy 359.315096 -366.669259) (xy 359.315004 -366.658906) (xy 359.313988 -366.623346) (xy 359.313988 -366.11433)
			(xy 359.313544 -366.101204) (xy 359.306776 -366.075837) (xy 359.29376 -366.053036) (xy 359.275355 -366.034312)
			(xy 359.252783 -366.020905) (xy 359.227536 -366.013702) (xy 359.21442 -366.012984) (xy 359.186093 -366.011806)
			(xy 359.130236 -366.002113) (xy 359.103168 -365.99368) (xy 359.088153 -365.989335) (xy 359.056914 -365.988984)
			(xy 359.027027 -365.998083) (xy 359.001283 -366.015782) (xy 358.982085 -366.040428) (xy 358.976168 -366.054894)
			(xy 358.962262 -366.090937) (xy 358.928182 -366.160274) (xy 358.887268 -366.225811) (xy 358.839939 -366.286877)
			(xy 358.78668 -366.342846) (xy 358.728037 -366.393146) (xy 358.66461 -366.43726) (xy 358.597049 -366.474737)
			(xy 358.526046 -366.505194) (xy 358.452328 -366.528318) (xy 358.37665 -366.543872) (xy 358.299788 -366.551697)
			(xy 358.261158 -366.552226) (xy 358.221225 -366.551701) (xy 358.141797 -366.543349) (xy 358.063677 -366.52674)
			(xy 357.987722 -366.502058) (xy 357.914762 -366.469571) (xy 357.845597 -366.429636) (xy 357.780985 -366.38269)
			(xy 357.721634 -366.329249) (xy 357.668195 -366.269896) (xy 357.621251 -366.205283) (xy 357.581318 -366.136117)
			(xy 357.548834 -366.063156) (xy 357.524153 -365.987199) (xy 357.507547 -365.909079) (xy 357.499198 -365.829651)
			(xy 357.49865 -365.789718) (xy 357.499171 -365.749087) (xy 357.507811 -365.668285) (xy 357.524993 -365.58886)
			(xy 357.550524 -365.511713) (xy 357.584114 -365.437718) (xy 357.625382 -365.367714) (xy 357.67386 -365.302496)
			(xy 357.728998 -365.242802) (xy 357.759254 -365.215678) (xy 357.769169 -365.206431) (xy 357.784141 -365.18384)
			(xy 357.792633 -365.158102) (xy 357.794046 -365.131037) (xy 357.78828 -365.104556) (xy 357.775742 -365.080528)
			(xy 357.757319 -365.060651) (xy 357.746046 -365.053118) (xy 357.713529 -365.032257) (xy 357.652448 -364.984946)
			(xy 357.596466 -364.931699) (xy 357.546156 -364.873063) (xy 357.502034 -364.809641) (xy 357.464552 -364.742081)
			(xy 357.434095 -364.671076) (xy 357.410976 -364.597356) (xy 357.39543 -364.521675) (xy 357.387619 -364.44481)
			(xy 357.387144 -364.40618) (xy 357.38771 -364.364382) (xy 357.396854 -364.281286) (xy 357.415029 -364.199689)
			(xy 357.442018 -364.120568) (xy 357.477498 -364.044874) (xy 357.521041 -363.973513) (xy 357.546148 -363.94009)
			(xy 357.517074 -363.91301) (xy 357.464111 -363.853777) (xy 357.417597 -363.789356) (xy 357.378036 -363.720447)
			(xy 357.345857 -363.647797) (xy 357.32141 -363.572193) (xy 357.304959 -363.494457) (xy 357.296683 -363.415431)
			(xy 357.296212 -363.375702) (xy 357.296717 -363.335767) (xy 357.305065 -363.256336) (xy 357.321671 -363.178212)
			(xy 357.346352 -363.102252) (xy 357.378838 -363.029288) (xy 357.418773 -362.96012) (xy 357.46572 -362.895504)
			(xy 357.519163 -362.836151) (xy 357.578518 -362.782709) (xy 357.643135 -362.735764) (xy 357.712304 -362.69583)
			(xy 357.785269 -362.663346) (xy 357.861229 -362.638666) (xy 357.939354 -362.622062) (xy 358.018785 -362.613716)
			(xy 358.05872 -362.613194) (xy 358.101503 -362.613794) (xy 358.18653 -362.623374) (xy 358.26995 -362.642412)
			(xy 358.350715 -362.670667) (xy 358.42781 -362.707786) (xy 358.464358 -362.730034) (xy 358.4775 -362.737637)
			(xy 358.506799 -362.74554) (xy 358.537127 -362.744502) (xy 358.565817 -362.734612) (xy 358.590344 -362.716743)
			(xy 358.60855 -362.692465) (xy 358.618835 -362.663915) (xy 358.620292 -362.633604) (xy 358.617012 -362.618782)
			(xy 358.605893 -362.572394) (xy 358.593923 -362.477756) (xy 358.593136 -362.43006) (xy 358.593643 -362.390127)
			(xy 358.601995 -362.3107) (xy 358.618604 -362.23258) (xy 358.643288 -362.156625) (xy 358.675776 -362.083666)
			(xy 358.715713 -362.014503) (xy 358.76266 -361.949893) (xy 358.816104 -361.890544) (xy 358.875458 -361.837107)
			(xy 358.940073 -361.790167) (xy 359.009241 -361.750238) (xy 359.082204 -361.717758) (xy 359.158162 -361.693083)
			(xy 359.236283 -361.676482) (xy 359.315711 -361.668138) (xy 359.355644 -361.667552) (xy 359.392709 -361.667995)
			(xy 359.46649 -361.67519) (xy 359.539224 -361.689508) (xy 359.610227 -361.710814) (xy 359.644696 -361.724448)
			(xy 359.956608 -361.412536) (xy 359.975545 -361.394326) (xy 360.017746 -361.363039) (xy 360.064053 -361.338229)
			(xy 360.113479 -361.320425) (xy 360.16497 -361.310007) (xy 360.21743 -361.307197) (xy 360.243628 -361.309158)
			(xy 360.442256 -361.11053) (xy 360.440249 -361.084328) (xy 360.44301 -361.031852) (xy 360.453404 -360.980342)
			(xy 360.471208 -360.930901) (xy 360.496039 -360.88459) (xy 360.527367 -360.8424) (xy 360.545634 -360.82351)
			(xy 360.772202 -360.596434) (xy 360.773756 -360.569381) (xy 360.783571 -360.516092) (xy 360.79176 -360.490262)
			(xy 360.7943 -360.482388) (xy 360.7943 -360.422698) (xy 360.774337 -360.405566) (xy 360.739152 -360.366459)
			(xy 360.710048 -360.322639) (xy 360.687648 -360.275041) (xy 360.672431 -360.224685) (xy 360.664721 -360.172648)
			(xy 360.664252 -360.146346) (xy 360.664252 -360.077512) (xy 360.664764 -360.050863) (xy 360.67269 -359.998156)
			(xy 360.688309 -359.947196) (xy 360.71128 -359.899101) (xy 360.7411 -359.854924) (xy 360.75874 -359.834942)
			(xy 360.742853 -359.814518) (xy 360.716154 -359.770196) (xy 360.695693 -359.722671) (xy 360.681845 -359.672815)
			(xy 360.674866 -359.621546) (xy 360.674412 -359.595674) (xy 360.6749 -359.568425) (xy 360.68266 -359.514481)
			(xy 360.698017 -359.46219) (xy 360.72066 -359.412618) (xy 360.750127 -359.366772) (xy 360.785819 -359.325587)
			(xy 360.827009 -359.2899) (xy 360.872858 -359.260438) (xy 360.922433 -359.237801) (xy 360.974726 -359.22245)
			(xy 361.02867 -359.214697) (xy 361.05592 -359.214166) (xy 361.083508 -359.214654) (xy 361.138109 -359.222598)
			(xy 361.190998 -359.238319) (xy 361.241074 -359.261489) (xy 361.264454 -359.276142) (xy 362.781088 -357.759254)
			(xy 362.781088 -354.541582) (xy 361.443016 -353.20351) (xy 361.443016 -352.949256) (xy 360.704892 -352.949256)
			(xy 360.679939 -352.948628) (xy 360.630995 -352.93887) (xy 360.584888 -352.919768) (xy 360.543383 -352.892054)
			(xy 360.525314 -352.874834) (xy 360.444796 -352.794316) (xy 360.423968 -352.794316) (xy 360.396693 -352.793885)
			(xy 360.342691 -352.786182) (xy 360.290337 -352.770866) (xy 360.240697 -352.748251) (xy 360.194785 -352.718796)
			(xy 360.153535 -352.683102) (xy 360.11779 -352.641897) (xy 360.088278 -352.596021) (xy 360.0656 -352.54641)
			(xy 360.050219 -352.494075) (xy 360.042449 -352.440082) (xy 360.041952 -352.412808) (xy 360.042437 -352.385555)
			(xy 360.050193 -352.331605) (xy 360.065547 -352.279307) (xy 360.088187 -352.229726) (xy 360.117652 -352.183872)
			(xy 360.153343 -352.142677) (xy 360.194533 -352.106981) (xy 360.240384 -352.07751) (xy 360.289962 -352.054863)
			(xy 360.342258 -352.039503) (xy 360.396207 -352.031741) (xy 360.42346 -352.0313) (xy 360.452409 -352.031841)
			(xy 360.509641 -352.040596) (xy 360.564893 -352.057897) (xy 360.616898 -352.083346) (xy 360.664462 -352.116359)
			(xy 360.706492 -352.156178) (xy 360.742025 -352.20189) (xy 360.770245 -352.252444) (xy 360.790504 -352.306682)
			(xy 360.802337 -352.363358) (xy 360.80446 -352.392234) (xy 360.806746 -352.436176) (xy 360.811064 -352.44024)
			(xy 361.573318 -352.44024) (xy 361.573318 -352.255074) (xy 361.43311 -352.11512) (xy 361.409648 -352.117859)
			(xy 361.362497 -352.12078) (xy 361.338876 -352.120962) (xy 361.298943 -352.120456) (xy 361.219514 -352.112105)
			(xy 361.141394 -352.095497) (xy 361.065437 -352.070814) (xy 360.992477 -352.038327) (xy 360.923312 -351.998391)
			(xy 360.858701 -351.951444) (xy 360.799351 -351.898) (xy 360.745912 -351.838645) (xy 360.698971 -351.774029)
			(xy 360.659041 -351.704861) (xy 360.626561 -351.631898) (xy 360.601885 -351.555939) (xy 360.585284 -351.477817)
			(xy 360.57694 -351.398387) (xy 360.576368 -351.358454) (xy 360.576368 -351.357946) (xy 360.57657 -351.334516)
			(xy 360.579491 -351.287747) (xy 360.58221 -351.264474) (xy 360.396028 -351.078038) (xy 360.164126 -350.847406)
			(xy 360.196892 -350.76892) (xy 360.166666 -350.723708) (xy 360.149648 -350.723708) (xy 359.707688 -351.165668)
			(xy 359.707688 -351.173542) (xy 359.72733 -351.191698) (xy 359.761844 -351.232562) (xy 359.790309 -351.277848)
			(xy 359.812166 -351.326667) (xy 359.826987 -351.378062) (xy 359.83448 -351.431024) (xy 359.834942 -351.457768)
			(xy 359.834456 -351.485019) (xy 359.8267 -351.538967) (xy 359.811345 -351.591262) (xy 359.788703 -351.640839)
			(xy 359.759237 -351.686689) (xy 359.723546 -351.72788) (xy 359.682355 -351.763571) (xy 359.636505 -351.793037)
			(xy 359.586928 -351.815679) (xy 359.534633 -351.831034) (xy 359.480685 -351.83879) (xy 359.426183 -351.83879)
			(xy 359.372235 -351.831034) (xy 359.31994 -351.815679) (xy 359.270363 -351.793037) (xy 359.224513 -351.763571)
			(xy 359.183322 -351.72788) (xy 359.147631 -351.686689) (xy 359.118165 -351.640839) (xy 359.095523 -351.591262)
			(xy 359.080168 -351.538967) (xy 359.072412 -351.485019) (xy 359.071926 -351.457768) (xy 359.072399 -351.431027)
			(xy 359.079911 -351.378073) (xy 359.094743 -351.326688) (xy 359.116603 -351.277875) (xy 359.145064 -351.232593)
			(xy 359.179568 -351.191728) (xy 359.19918 -351.173542) (xy 359.19918 -351.060258) (xy 359.199786 -351.035273)
			(xy 359.209518 -350.986259) (xy 359.228622 -350.940084) (xy 359.256362 -350.89852) (xy 359.273602 -350.880426)
			(xy 359.82783 -350.326198) (xy 359.588562 -350.087184) (xy 359.405174 -350.087184) (xy 359.340404 -350.022668)
			(xy 358.365806 -350.022668) (xy 358.34701 -349.9739) (xy 358.342993 -349.964544) (xy 358.328968 -349.949808)
			(xy 358.310314 -349.94169) (xy 358.289972 -349.94147) (xy 358.271147 -349.949183) (xy 358.263698 -349.95612)
			(xy 357.505 -350.714818) (xy 357.505 -351.225612) (xy 357.523242 -351.243651) (xy 357.55521 -351.283775)
			(xy 357.581508 -351.327825) (xy 357.601661 -351.375003) (xy 357.615305 -351.424459) (xy 357.622192 -351.475297)
			(xy 357.622602 -351.500948) (xy 357.622116 -351.528199) (xy 357.61436 -351.582147) (xy 357.599005 -351.634442)
			(xy 357.576363 -351.684019) (xy 357.546897 -351.729869) (xy 357.511206 -351.77106) (xy 357.470015 -351.806751)
			(xy 357.424165 -351.836217) (xy 357.374588 -351.858859) (xy 357.322293 -351.874214) (xy 357.268345 -351.88197)
			(xy 357.213843 -351.88197) (xy 357.159895 -351.874214) (xy 357.1076 -351.858859) (xy 357.058023 -351.836217)
			(xy 357.012173 -351.806751) (xy 356.970982 -351.77106) (xy 356.935291 -351.729869) (xy 356.905825 -351.684019)
			(xy 356.883183 -351.634442) (xy 356.867828 -351.582147) (xy 356.860072 -351.528199) (xy 356.859586 -351.500948)
			(xy 356.860114 -351.473141) (xy 356.868233 -351.418121) (xy 356.88425 -351.364861) (xy 356.907823 -351.314488)
			(xy 356.938456 -351.268068) (xy 356.975499 -351.226584) (xy 356.996492 -351.20834) (xy 356.996492 -350.609408)
			(xy 356.997102 -350.584424) (xy 357.00684 -350.535413) (xy 357.025945 -350.489241) (xy 357.053683 -350.447678)
			(xy 357.070914 -350.429576) (xy 357.434642 -350.065848) (xy 357.443995 -350.055885) (xy 357.45751 -350.032146)
			(xy 357.464241 -350.005671) (xy 357.463705 -349.97836) (xy 357.45594 -349.95217) (xy 357.441504 -349.928979)
			(xy 357.421431 -349.910451) (xy 357.409496 -349.903796) (xy 357.290624 -350.022668) (xy 356.479348 -350.022668)
			(xy 356.479348 -351.454974) (xy 356.478817 -351.478376) (xy 356.470254 -351.524388) (xy 356.46233 -351.546414)
			(xy 356.458957 -351.571989) (xy 356.443201 -351.621101) (xy 356.417865 -351.666028) (xy 356.40137 -351.68586)
			(xy 356.401878 -351.707704) (xy 356.401392 -351.734955) (xy 356.393636 -351.788903) (xy 356.378281 -351.841198)
			(xy 356.355639 -351.890775) (xy 356.326173 -351.936625) (xy 356.290482 -351.977816) (xy 356.249291 -352.013507)
			(xy 356.203441 -352.042973) (xy 356.153864 -352.065615) (xy 356.101569 -352.08097) (xy 356.047621 -352.088726)
			(xy 355.993119 -352.088726) (xy 355.939171 -352.08097) (xy 355.886876 -352.065615) (xy 355.837299 -352.042973)
			(xy 355.791449 -352.013507) (xy 355.750258 -351.977816) (xy 355.714567 -351.936625) (xy 355.685101 -351.890775)
			(xy 355.662459 -351.841198) (xy 355.647104 -351.788903) (xy 355.639348 -351.734955) (xy 355.638862 -351.707704)
			(xy 355.639379 -351.679367) (xy 355.647762 -351.623315) (xy 355.664345 -351.56912) (xy 355.688761 -351.517975)
			(xy 355.720475 -351.471004) (xy 355.758789 -351.429241) (xy 355.802858 -351.393605) (xy 355.851715 -351.364881)
			(xy 355.904283 -351.343699) (xy 355.931724 -351.33661) (xy 355.97084 -351.327212) (xy 355.97084 -349.892366)
			(xy 355.519228 -349.892366) (xy 355.519228 -350.383602) (xy 355.538847 -350.40177) (xy 355.573314 -350.442649)
			(xy 355.601735 -350.487942) (xy 355.623551 -350.536759) (xy 355.638336 -350.588145) (xy 355.645799 -350.641093)
			(xy 355.646228 -350.667828) (xy 355.645742 -350.695079) (xy 355.637986 -350.749027) (xy 355.622631 -350.801322)
			(xy 355.599989 -350.850899) (xy 355.570523 -350.896749) (xy 355.534832 -350.93794) (xy 355.493641 -350.973631)
			(xy 355.447791 -351.003097) (xy 355.398214 -351.025739) (xy 355.345919 -351.041094) (xy 355.291971 -351.04885)
			(xy 355.237469 -351.04885) (xy 355.183521 -351.041094) (xy 355.131226 -351.025739) (xy 355.081649 -351.003097)
			(xy 355.035799 -350.973631) (xy 354.994608 -350.93794) (xy 354.958917 -350.896749) (xy 354.929451 -350.850899)
			(xy 354.906809 -350.801322) (xy 354.891454 -350.749027) (xy 354.883698 -350.695079) (xy 354.883212 -350.667828)
			(xy 354.883659 -350.641093) (xy 354.89112 -350.588145) (xy 354.905899 -350.536758) (xy 354.927708 -350.487937)
			(xy 354.956119 -350.442638) (xy 354.990575 -350.40175) (xy 355.010212 -350.383602) (xy 355.010212 -349.892366)
			(xy 354.508308 -349.892366) (xy 354.508308 -350.999044) (xy 354.842826 -351.333816) (xy 354.860049 -351.351926)
			(xy 354.887791 -351.393486) (xy 354.906903 -351.439655) (xy 354.91665 -351.488664) (xy 354.917248 -351.513648)
			(xy 354.917248 -351.686622) (xy 354.936893 -351.704777) (xy 354.971413 -351.745639) (xy 354.999883 -351.790924)
			(xy 355.021745 -351.839744) (xy 355.03657 -351.891139) (xy 355.044067 -351.944103) (xy 355.044502 -351.970848)
			(xy 355.044016 -351.998099) (xy 355.03626 -352.052047) (xy 355.020905 -352.104342) (xy 354.998263 -352.153919)
			(xy 354.968797 -352.199769) (xy 354.933106 -352.24096) (xy 354.891915 -352.276651) (xy 354.846065 -352.306117)
			(xy 354.796488 -352.328759) (xy 354.744193 -352.344114) (xy 354.690245 -352.35187) (xy 354.635743 -352.35187)
			(xy 354.581795 -352.344114) (xy 354.5295 -352.328759) (xy 354.479923 -352.306117) (xy 354.434073 -352.276651)
			(xy 354.392882 -352.24096) (xy 354.357191 -352.199769) (xy 354.327725 -352.153919) (xy 354.305083 -352.104342)
			(xy 354.289728 -352.052047) (xy 354.281972 -351.998099) (xy 354.281486 -351.970848) (xy 354.282046 -351.940795)
			(xy 354.291468 -351.881432) (xy 354.310087 -351.824282) (xy 354.337441 -351.770761) (xy 354.372853 -351.722194)
			(xy 354.393754 -351.700592) (xy 354.40874 -351.68586) (xy 354.40874 -351.619058) (xy 354.073968 -351.284286)
			(xy 354.056713 -351.26619) (xy 354.028906 -351.224644) (xy 354.009735 -351.178473) (xy 353.999937 -351.12945)
			(xy 353.999292 -351.104454) (xy 353.999292 -349.891096) (xy 353.677728 -349.891096) (xy 353.677728 -350.021144)
			(xy 351.915476 -350.021144) (xy 351.915476 -351.674176) (xy 351.949512 -351.708466) (xy 351.942884 -351.683201)
			(xy 351.935746 -351.631458) (xy 351.935288 -351.605342) (xy 351.935288 -351.605088) (xy 351.935775 -351.577837)
			(xy 351.943532 -351.523891) (xy 351.958889 -351.471597) (xy 351.98153 -351.422021) (xy 352.010997 -351.376172)
			(xy 352.046688 -351.334983) (xy 352.087878 -351.299292) (xy 352.133728 -351.269827) (xy 352.183305 -351.247186)
			(xy 352.235598 -351.231831) (xy 352.289545 -351.224074) (xy 352.316796 -351.22358) (xy 352.342702 -351.224014)
			(xy 352.394037 -351.231029) (xy 352.44395 -351.244931) (xy 352.49152 -351.265463) (xy 352.535872 -351.292246)
			(xy 352.556318 -351.308162) (xy 352.588068 -351.319338) (xy 352.625152 -351.303336) (xy 352.65216 -351.275367)
			(xy 352.710952 -351.224483) (xy 352.774617 -351.179845) (xy 352.842492 -351.141915) (xy 352.913875 -351.111088)
			(xy 352.988023 -351.087683) (xy 353.064168 -351.071943) (xy 353.141519 -351.064032) (xy 353.180396 -351.06356)
			(xy 353.220331 -351.064082) (xy 353.299763 -351.072431) (xy 353.377887 -351.089035) (xy 353.453847 -351.113716)
			(xy 353.526812 -351.1462) (xy 353.595982 -351.186134) (xy 353.660599 -351.233079) (xy 353.719954 -351.28652)
			(xy 353.773399 -351.345873) (xy 353.820347 -351.410488) (xy 353.860283 -351.479656) (xy 353.892772 -351.552619)
			(xy 353.917455 -351.628578) (xy 353.934064 -351.706702) (xy 353.942416 -351.786133) (xy 353.942904 -351.826068)
			(xy 353.942387 -351.865207) (xy 353.934333 -351.943071) (xy 353.918346 -352.0197) (xy 353.894595 -352.094289)
			(xy 353.86333 -352.166053) (xy 353.824879 -352.234238) (xy 353.779647 -352.298126) (xy 353.728109 -352.357046)
			(xy 353.699826 -352.384106) (xy 353.690218 -352.393628) (xy 353.675958 -352.416604) (xy 353.668227 -352.442518)
			(xy 353.667569 -352.469551) (xy 353.674028 -352.49581) (xy 353.687152 -352.519453) (xy 353.706022 -352.538824)
			(xy 353.729313 -352.552563) (xy 353.755394 -352.559707) (xy 353.768914 -352.560128) (xy 357.27386 -352.560128)
			(xy 357.285798 -352.572066) (xy 357.641398 -352.216466) (xy 357.659507 -352.199242) (xy 357.701067 -352.171498)
			(xy 357.747236 -352.152384) (xy 357.796245 -352.142633) (xy 357.82123 -352.142044) (xy 358.607868 -352.142044)
			(xy 358.626024 -352.122401) (xy 358.666887 -352.087888) (xy 358.712173 -352.059423) (xy 358.760993 -352.037568)
			(xy 358.812388 -352.022749) (xy 358.86535 -352.015259) (xy 358.892094 -352.01479) (xy 358.919347 -352.015253)
			(xy 358.973299 -352.023009) (xy 359.025598 -352.038365) (xy 359.075179 -352.061007) (xy 359.121033 -352.090475)
			(xy 359.162227 -352.126169) (xy 359.197921 -352.167362) (xy 359.22739 -352.213216) (xy 359.250033 -352.262796)
			(xy 359.265389 -352.315095) (xy 359.273147 -352.369047) (xy 359.273147 -352.423553) (xy 359.265389 -352.477505)
			(xy 359.250033 -352.529804) (xy 359.22739 -352.579384) (xy 359.197921 -352.625238) (xy 359.162227 -352.666431)
			(xy 359.121033 -352.702125) (xy 359.075179 -352.731593) (xy 359.025598 -352.754235) (xy 358.973299 -352.769591)
			(xy 358.919347 -352.777347) (xy 358.892094 -352.777806) (xy 358.865352 -352.777335) (xy 358.812396 -352.769826)
			(xy 358.761007 -352.754998) (xy 358.712191 -352.733141) (xy 358.666905 -352.704684) (xy 358.626034 -352.670183)
			(xy 358.607868 -352.650552) (xy 357.92664 -352.650552) (xy 357.485442 -353.09175) (xy 357.479252 -353.097854)
			(xy 357.466159 -353.109295) (xy 357.45928 -353.11461) (xy 357.45928 -353.290632) (xy 357.589328 -353.290632)
			(xy 357.589328 -353.5553) (xy 357.627428 -353.593146) (xy 357.627428 -354.24745) (xy 357.655368 -354.275644)
			(xy 358.420924 -353.510342) (xy 358.420924 -353.489006) (xy 358.421353 -353.46173) (xy 358.429051 -353.407726)
			(xy 358.444364 -353.35537) (xy 358.466978 -353.305728) (xy 358.496433 -353.259813) (xy 358.532127 -353.218563)
			(xy 358.573333 -353.182817) (xy 358.619211 -353.153305) (xy 358.668825 -353.13063) (xy 358.721162 -353.115252)
			(xy 358.775157 -353.107486) (xy 358.802432 -353.10699) (xy 358.829695 -353.107456) (xy 358.883665 -353.115224)
			(xy 358.93598 -353.130595) (xy 358.985573 -353.153258) (xy 359.031434 -353.182751) (xy 359.07263 -353.218472)
			(xy 359.108321 -353.259695) (xy 359.137779 -353.305578) (xy 359.160405 -353.355189) (xy 359.175737 -353.407515)
			(xy 359.183464 -353.461491) (xy 359.183428 -353.516017) (xy 359.175629 -353.569982) (xy 359.160227 -353.622288)
			(xy 359.137535 -353.671868) (xy 359.123131 -353.694238) (xy 360.057952 -353.694238) (xy 360.062023 -353.638616)
			(xy 360.074149 -353.584179) (xy 360.094072 -353.532088) (xy 360.121368 -353.483453) (xy 360.155454 -353.43931)
			(xy 360.195603 -353.400601) (xy 360.240961 -353.36815) (xy 360.290561 -353.342649) (xy 360.343345 -353.324642)
			(xy 360.398188 -353.314512) (xy 360.453922 -353.312475) (xy 360.509359 -353.318575) (xy 360.563316 -353.332681)
			(xy 360.614645 -353.354493) (xy 360.662251 -353.383547) (xy 360.705119 -353.419222) (xy 360.742336 -353.460759)
			(xy 360.773109 -353.507272) (xy 360.796781 -353.557769) (xy 360.812849 -353.611176) (xy 360.820969 -353.666352)
			(xy 360.821478 -353.694238) (xy 360.820969 -353.722124) (xy 360.812849 -353.7773) (xy 360.796781 -353.830707)
			(xy 360.773109 -353.881204) (xy 360.742336 -353.927717) (xy 360.705119 -353.969254) (xy 360.662251 -354.004929)
			(xy 360.614645 -354.033983) (xy 360.563316 -354.055795) (xy 360.509359 -354.069901) (xy 360.453922 -354.076001)
			(xy 360.398188 -354.073964) (xy 360.343345 -354.063834) (xy 360.290561 -354.045827) (xy 360.240961 -354.020326)
			(xy 360.195603 -353.987875) (xy 360.155454 -353.949166) (xy 360.121368 -353.905023) (xy 360.094072 -353.856388)
			(xy 360.074149 -353.804297) (xy 360.062023 -353.74986) (xy 360.057952 -353.694238) (xy 359.123131 -353.694238)
			(xy 359.108016 -353.717712) (xy 359.07227 -353.758887) (xy 359.031027 -353.794554) (xy 358.985126 -353.823985)
			(xy 358.935503 -353.846582) (xy 358.883168 -353.861884) (xy 358.829188 -353.86958) (xy 358.801924 -353.870006)
			(xy 358.780588 -353.870006) (xy 357.972106 -354.678742) (xy 358.043145 -354.749608) (xy 359.185462 -354.749608)
			(xy 359.189533 -354.693986) (xy 359.201659 -354.639549) (xy 359.221582 -354.587458) (xy 359.248878 -354.538823)
			(xy 359.282964 -354.49468) (xy 359.323113 -354.455971) (xy 359.368471 -354.42352) (xy 359.418071 -354.398019)
			(xy 359.470855 -354.380012) (xy 359.525698 -354.369882) (xy 359.581432 -354.367845) (xy 359.636869 -354.373945)
			(xy 359.690826 -354.388051) (xy 359.742155 -354.409863) (xy 359.789761 -354.438917) (xy 359.832629 -354.474592)
			(xy 359.869846 -354.516129) (xy 359.900619 -354.562642) (xy 359.924291 -354.613139) (xy 359.940359 -354.666546)
			(xy 359.948479 -354.721722) (xy 359.948988 -354.749608) (xy 359.948479 -354.777494) (xy 359.940359 -354.83267)
			(xy 359.924291 -354.886077) (xy 359.900619 -354.936574) (xy 359.883157 -354.962968) (xy 360.296712 -354.962968)
			(xy 360.300783 -354.907346) (xy 360.312909 -354.852909) (xy 360.332832 -354.800818) (xy 360.360128 -354.752183)
			(xy 360.394214 -354.70804) (xy 360.434363 -354.669331) (xy 360.479721 -354.63688) (xy 360.529321 -354.611379)
			(xy 360.582105 -354.593372) (xy 360.636948 -354.583242) (xy 360.692682 -354.581205) (xy 360.748119 -354.587305)
			(xy 360.802076 -354.601411) (xy 360.853405 -354.623223) (xy 360.901011 -354.652277) (xy 360.943879 -354.687952)
			(xy 360.981096 -354.729489) (xy 360.987685 -354.739448) (xy 361.378752 -354.739448) (xy 361.382823 -354.683826)
			(xy 361.394949 -354.629389) (xy 361.414872 -354.577298) (xy 361.442168 -354.528663) (xy 361.476254 -354.48452)
			(xy 361.516403 -354.445811) (xy 361.561761 -354.41336) (xy 361.611361 -354.387859) (xy 361.664145 -354.369852)
			(xy 361.718988 -354.359722) (xy 361.774722 -354.357685) (xy 361.830159 -354.363785) (xy 361.884116 -354.377891)
			(xy 361.935445 -354.399703) (xy 361.983051 -354.428757) (xy 362.025919 -354.464432) (xy 362.063136 -354.505969)
			(xy 362.093909 -354.552482) (xy 362.117581 -354.602979) (xy 362.133649 -354.656386) (xy 362.141769 -354.711562)
			(xy 362.142278 -354.739448) (xy 362.141769 -354.767334) (xy 362.133649 -354.82251) (xy 362.117581 -354.875917)
			(xy 362.093909 -354.926414) (xy 362.063136 -354.972927) (xy 362.025919 -355.014464) (xy 361.983051 -355.050139)
			(xy 361.935445 -355.079193) (xy 361.884116 -355.101005) (xy 361.830159 -355.115111) (xy 361.774722 -355.121211)
			(xy 361.718988 -355.119174) (xy 361.664145 -355.109044) (xy 361.611361 -355.091037) (xy 361.561761 -355.065536)
			(xy 361.516403 -355.033085) (xy 361.476254 -354.994376) (xy 361.442168 -354.950233) (xy 361.414872 -354.901598)
			(xy 361.394949 -354.849507) (xy 361.382823 -354.79507) (xy 361.378752 -354.739448) (xy 360.987685 -354.739448)
			(xy 361.011869 -354.776002) (xy 361.035541 -354.826499) (xy 361.051609 -354.879906) (xy 361.059729 -354.935082)
			(xy 361.060238 -354.962968) (xy 361.059729 -354.990854) (xy 361.051609 -355.04603) (xy 361.035541 -355.099437)
			(xy 361.011869 -355.149934) (xy 360.981096 -355.196447) (xy 360.943879 -355.237984) (xy 360.901011 -355.273659)
			(xy 360.853405 -355.302713) (xy 360.802076 -355.324525) (xy 360.748119 -355.338631) (xy 360.692682 -355.344731)
			(xy 360.636948 -355.342694) (xy 360.582105 -355.332564) (xy 360.529321 -355.314557) (xy 360.479721 -355.289056)
			(xy 360.434363 -355.256605) (xy 360.394214 -355.217896) (xy 360.360128 -355.173753) (xy 360.332832 -355.125118)
			(xy 360.312909 -355.073027) (xy 360.300783 -355.01859) (xy 360.296712 -354.962968) (xy 359.883157 -354.962968)
			(xy 359.869846 -354.983087) (xy 359.832629 -355.024624) (xy 359.789761 -355.060299) (xy 359.742155 -355.089353)
			(xy 359.690826 -355.111165) (xy 359.636869 -355.125271) (xy 359.581432 -355.131371) (xy 359.525698 -355.129334)
			(xy 359.470855 -355.119204) (xy 359.418071 -355.101197) (xy 359.368471 -355.075696) (xy 359.323113 -355.043245)
			(xy 359.282964 -355.004536) (xy 359.248878 -354.960393) (xy 359.221582 -354.911758) (xy 359.201659 -354.859667)
			(xy 359.189533 -354.80523) (xy 359.185462 -354.749608) (xy 358.043145 -354.749608) (xy 358.076246 -354.782628)
			(xy 358.375204 -354.782628) (xy 358.375204 -356.156514) (xy 358.86593 -356.156514) (xy 358.870001 -356.100892)
			(xy 358.882127 -356.046455) (xy 358.90205 -355.994364) (xy 358.929346 -355.945729) (xy 358.963432 -355.901586)
			(xy 359.003581 -355.862877) (xy 359.048939 -355.830426) (xy 359.098539 -355.804925) (xy 359.151323 -355.786918)
			(xy 359.206166 -355.776788) (xy 359.2619 -355.774751) (xy 359.317337 -355.780851) (xy 359.371294 -355.794957)
			(xy 359.422623 -355.816769) (xy 359.470229 -355.845823) (xy 359.513097 -355.881498) (xy 359.550314 -355.923035)
			(xy 359.581087 -355.969548) (xy 359.604759 -356.020045) (xy 359.620827 -356.073452) (xy 359.628947 -356.128628)
			(xy 359.629456 -356.156514) (xy 359.628947 -356.1844) (xy 359.620827 -356.239576) (xy 359.604759 -356.292983)
			(xy 359.581087 -356.34348) (xy 359.550314 -356.389993) (xy 359.513097 -356.43153) (xy 359.470229 -356.467205)
			(xy 359.422623 -356.496259) (xy 359.371294 -356.518071) (xy 359.317337 -356.532177) (xy 359.2619 -356.538277)
			(xy 359.206166 -356.53624) (xy 359.151323 -356.52611) (xy 359.098539 -356.508103) (xy 359.048939 -356.482602)
			(xy 359.003581 -356.450151) (xy 358.963432 -356.411442) (xy 358.929346 -356.367299) (xy 358.90205 -356.318664)
			(xy 358.882127 -356.266573) (xy 358.870001 -356.212136) (xy 358.86593 -356.156514) (xy 358.375204 -356.156514)
			(xy 358.375204 -356.42042) (xy 358.248712 -356.546912) (xy 361.125006 -356.546912) (xy 361.129077 -356.49129)
			(xy 361.141203 -356.436853) (xy 361.161126 -356.384762) (xy 361.188422 -356.336127) (xy 361.222508 -356.291984)
			(xy 361.262657 -356.253275) (xy 361.308015 -356.220824) (xy 361.357615 -356.195323) (xy 361.410399 -356.177316)
			(xy 361.465242 -356.167186) (xy 361.520976 -356.165149) (xy 361.576413 -356.171249) (xy 361.63037 -356.185355)
			(xy 361.681699 -356.207167) (xy 361.729305 -356.236221) (xy 361.772173 -356.271896) (xy 361.80939 -356.313433)
			(xy 361.840163 -356.359946) (xy 361.863835 -356.410443) (xy 361.879903 -356.46385) (xy 361.888023 -356.519026)
			(xy 361.888532 -356.546912) (xy 361.888023 -356.574798) (xy 361.879903 -356.629974) (xy 361.863835 -356.683381)
			(xy 361.840163 -356.733878) (xy 361.80939 -356.780391) (xy 361.772173 -356.821928) (xy 361.729305 -356.857603)
			(xy 361.681699 -356.886657) (xy 361.63037 -356.908469) (xy 361.576413 -356.922575) (xy 361.520976 -356.928675)
			(xy 361.465242 -356.926638) (xy 361.410399 -356.916508) (xy 361.357615 -356.898501) (xy 361.308015 -356.873)
			(xy 361.262657 -356.840549) (xy 361.222508 -356.80184) (xy 361.188422 -356.757697) (xy 361.161126 -356.709062)
			(xy 361.141203 -356.656971) (xy 361.129077 -356.602534) (xy 361.125006 -356.546912) (xy 358.248712 -356.546912)
			(xy 357.852218 -356.943406) (xy 358.041192 -356.943406) (xy 358.045263 -356.887784) (xy 358.057389 -356.833347)
			(xy 358.077312 -356.781256) (xy 358.104608 -356.732621) (xy 358.138694 -356.688478) (xy 358.178843 -356.649769)
			(xy 358.224201 -356.617318) (xy 358.273801 -356.591817) (xy 358.326585 -356.57381) (xy 358.381428 -356.56368)
			(xy 358.437162 -356.561643) (xy 358.492599 -356.567743) (xy 358.546556 -356.581849) (xy 358.597885 -356.603661)
			(xy 358.645491 -356.632715) (xy 358.688359 -356.66839) (xy 358.725576 -356.709927) (xy 358.756349 -356.75644)
			(xy 358.780021 -356.806937) (xy 358.796089 -356.860344) (xy 358.804209 -356.91552) (xy 358.804718 -356.943406)
			(xy 358.804209 -356.971292) (xy 358.796089 -357.026468) (xy 358.780021 -357.079875) (xy 358.756349 -357.130372)
			(xy 358.725576 -357.176885) (xy 358.688359 -357.218422) (xy 358.645491 -357.254097) (xy 358.597885 -357.283151)
			(xy 358.546556 -357.304963) (xy 358.492599 -357.319069) (xy 358.437162 -357.325169) (xy 358.381428 -357.323132)
			(xy 358.326585 -357.313002) (xy 358.273801 -357.294995) (xy 358.224201 -357.269494) (xy 358.178843 -357.237043)
			(xy 358.138694 -357.198334) (xy 358.104608 -357.154191) (xy 358.077312 -357.105556) (xy 358.057389 -357.053465)
			(xy 358.045263 -356.999028) (xy 358.041192 -356.943406) (xy 357.852218 -356.943406) (xy 357.234236 -357.561388)
			(xy 360.900216 -357.561388) (xy 360.904287 -357.505766) (xy 360.916413 -357.451329) (xy 360.936336 -357.399238)
			(xy 360.963632 -357.350603) (xy 360.997718 -357.30646) (xy 361.037867 -357.267751) (xy 361.083225 -357.2353)
			(xy 361.132825 -357.209799) (xy 361.185609 -357.191792) (xy 361.240452 -357.181662) (xy 361.296186 -357.179625)
			(xy 361.351623 -357.185725) (xy 361.40558 -357.199831) (xy 361.456909 -357.221643) (xy 361.504515 -357.250697)
			(xy 361.547383 -357.286372) (xy 361.5846 -357.327909) (xy 361.615373 -357.374422) (xy 361.639045 -357.424919)
			(xy 361.655113 -357.478326) (xy 361.663233 -357.533502) (xy 361.663742 -357.561388) (xy 361.663233 -357.589274)
			(xy 361.655113 -357.64445) (xy 361.639045 -357.697857) (xy 361.615373 -357.748354) (xy 361.5846 -357.794867)
			(xy 361.547383 -357.836404) (xy 361.504515 -357.872079) (xy 361.456909 -357.901133) (xy 361.40558 -357.922945)
			(xy 361.351623 -357.937051) (xy 361.296186 -357.943151) (xy 361.240452 -357.941114) (xy 361.185609 -357.930984)
			(xy 361.132825 -357.912977) (xy 361.083225 -357.887476) (xy 361.037867 -357.855025) (xy 360.997718 -357.816316)
			(xy 360.963632 -357.772173) (xy 360.936336 -357.723538) (xy 360.916413 -357.671447) (xy 360.904287 -357.61701)
			(xy 360.900216 -357.561388) (xy 357.234236 -357.561388) (xy 356.417372 -358.378252) (xy 356.417372 -358.848406)
			(xy 358.041192 -358.848406) (xy 358.045263 -358.792784) (xy 358.057389 -358.738347) (xy 358.077312 -358.686256)
			(xy 358.104608 -358.637621) (xy 358.138694 -358.593478) (xy 358.178843 -358.554769) (xy 358.224201 -358.522318)
			(xy 358.273801 -358.496817) (xy 358.326585 -358.47881) (xy 358.381428 -358.46868) (xy 358.437162 -358.466643)
			(xy 358.492599 -358.472743) (xy 358.546556 -358.486849) (xy 358.597885 -358.508661) (xy 358.645491 -358.537715)
			(xy 358.688359 -358.57339) (xy 358.691258 -358.576626) (xy 360.646216 -358.576626) (xy 360.650287 -358.521004)
			(xy 360.662413 -358.466567) (xy 360.682336 -358.414476) (xy 360.709632 -358.365841) (xy 360.743718 -358.321698)
			(xy 360.783867 -358.282989) (xy 360.829225 -358.250538) (xy 360.878825 -358.225037) (xy 360.931609 -358.20703)
			(xy 360.986452 -358.1969) (xy 361.042186 -358.194863) (xy 361.097623 -358.200963) (xy 361.15158 -358.215069)
			(xy 361.202909 -358.236881) (xy 361.250515 -358.265935) (xy 361.293383 -358.30161) (xy 361.3306 -358.343147)
			(xy 361.361373 -358.38966) (xy 361.385045 -358.440157) (xy 361.401113 -358.493564) (xy 361.409233 -358.54874)
			(xy 361.409742 -358.576626) (xy 361.409233 -358.604512) (xy 361.401113 -358.659688) (xy 361.385045 -358.713095)
			(xy 361.361373 -358.763592) (xy 361.3306 -358.810105) (xy 361.293383 -358.851642) (xy 361.250515 -358.887317)
			(xy 361.202909 -358.916371) (xy 361.15158 -358.938183) (xy 361.097623 -358.952289) (xy 361.042186 -358.958389)
			(xy 360.986452 -358.956352) (xy 360.931609 -358.946222) (xy 360.878825 -358.928215) (xy 360.829225 -358.902714)
			(xy 360.783867 -358.870263) (xy 360.743718 -358.831554) (xy 360.709632 -358.787411) (xy 360.682336 -358.738776)
			(xy 360.662413 -358.686685) (xy 360.650287 -358.632248) (xy 360.646216 -358.576626) (xy 358.691258 -358.576626)
			(xy 358.725576 -358.614927) (xy 358.756349 -358.66144) (xy 358.780021 -358.711937) (xy 358.796089 -358.765344)
			(xy 358.804209 -358.82052) (xy 358.804718 -358.848406) (xy 358.804209 -358.876292) (xy 358.796089 -358.931468)
			(xy 358.780021 -358.984875) (xy 358.756349 -359.035372) (xy 358.725576 -359.081885) (xy 358.688359 -359.123422)
			(xy 358.645491 -359.159097) (xy 358.597885 -359.188151) (xy 358.546556 -359.209963) (xy 358.492599 -359.224069)
			(xy 358.437162 -359.230169) (xy 358.381428 -359.228132) (xy 358.326585 -359.218002) (xy 358.273801 -359.199995)
			(xy 358.224201 -359.174494) (xy 358.178843 -359.142043) (xy 358.138694 -359.103334) (xy 358.104608 -359.059191)
			(xy 358.077312 -359.010556) (xy 358.057389 -358.958465) (xy 358.045263 -358.904028) (xy 358.041192 -358.848406)
			(xy 356.417372 -358.848406) (xy 356.417372 -360.199432) (xy 356.462584 -360.244644) (xy 356.476383 -360.243219)
			(xy 356.504084 -360.241692) (xy 356.517956 -360.241596) (xy 356.521766 -360.241596) (xy 356.552556 -360.242269)
			(xy 356.613646 -360.250086) (xy 356.673357 -360.265178) (xy 356.730825 -360.287326) (xy 356.78522 -360.31621)
			(xy 356.835756 -360.351413) (xy 356.881701 -360.392427) (xy 356.922393 -360.438658) (xy 356.957243 -360.489438)
			(xy 356.985747 -360.544033) (xy 357.007493 -360.601654) (xy 357.022168 -360.661469) (xy 357.029558 -360.722612)
			(xy 357.03002 -360.753406) (xy 358.041192 -360.753406) (xy 358.045263 -360.697784) (xy 358.057389 -360.643347)
			(xy 358.077312 -360.591256) (xy 358.104608 -360.542621) (xy 358.138694 -360.498478) (xy 358.178843 -360.459769)
			(xy 358.224201 -360.427318) (xy 358.273801 -360.401817) (xy 358.326585 -360.38381) (xy 358.381428 -360.37368)
			(xy 358.437162 -360.371643) (xy 358.492599 -360.377743) (xy 358.546556 -360.391849) (xy 358.597885 -360.413661)
			(xy 358.645491 -360.442715) (xy 358.688359 -360.47839) (xy 358.725576 -360.519927) (xy 358.756349 -360.56644)
			(xy 358.780021 -360.616937) (xy 358.796089 -360.670344) (xy 358.804209 -360.72552) (xy 358.804718 -360.753406)
			(xy 358.804209 -360.781292) (xy 358.796089 -360.836468) (xy 358.780021 -360.889875) (xy 358.756349 -360.940372)
			(xy 358.725576 -360.986885) (xy 358.688359 -361.028422) (xy 358.645491 -361.064097) (xy 358.597885 -361.093151)
			(xy 358.546556 -361.114963) (xy 358.492599 -361.129069) (xy 358.437162 -361.135169) (xy 358.381428 -361.133132)
			(xy 358.326585 -361.123002) (xy 358.273801 -361.104995) (xy 358.224201 -361.079494) (xy 358.178843 -361.047043)
			(xy 358.138694 -361.008334) (xy 358.104608 -360.964191) (xy 358.077312 -360.915556) (xy 358.057389 -360.863465)
			(xy 358.045263 -360.809028) (xy 358.041192 -360.753406) (xy 357.03002 -360.753406) (xy 357.029571 -360.784317)
			(xy 357.022117 -360.845688) (xy 357.007317 -360.905712) (xy 356.985388 -360.963514) (xy 356.95665 -361.01825)
			(xy 356.921521 -361.069122) (xy 356.880516 -361.115387) (xy 356.834231 -361.156371) (xy 356.783343 -361.191475)
			(xy 356.728593 -361.220187) (xy 356.670781 -361.242089) (xy 356.610749 -361.25686) (xy 356.549375 -361.264286)
			(xy 356.518464 -361.264708) (xy 356.51821 -361.264708) (xy 356.51821 -361.264962) (xy 356.506828 -361.264901)
			(xy 356.484086 -361.263885) (xy 356.472744 -361.26293) (xy 356.462155 -361.262515) (xy 356.442095 -361.269274)
			(xy 356.426456 -361.283539) (xy 356.417885 -361.302893) (xy 356.417372 -361.313476) (xy 356.417372 -363.784642)
			(xy 356.447456 -363.808709) (xy 356.503133 -363.861964) (xy 356.55316 -363.92056) (xy 356.597027 -363.983898)
			(xy 356.634287 -364.051335) (xy 356.664561 -364.122184) (xy 356.687542 -364.195723) (xy 356.702994 -364.271204)
			(xy 356.71076 -364.347857) (xy 356.710762 -364.424903) (xy 356.703 -364.501557) (xy 356.687552 -364.577039)
			(xy 356.664575 -364.650579) (xy 356.634304 -364.721429) (xy 356.597048 -364.788868) (xy 356.553184 -364.852209)
			(xy 356.50316 -364.910807) (xy 356.447486 -364.964066) (xy 356.417372 -364.988094) (xy 356.417372 -365.433864)
			(xy 357.695754 -366.7125)
		)
		(stroke
			(width 0)
			(type solid)
		)
		(fill yes)
		(layer "In11.Cu")
		(net "PVCCIN_CPU0_VREF")
	)
	(gr_poly
		(pts
			(xy 122.705114 -270.273272) (xy 122.701304 -270.247618) (xy 122.699519 -270.235186) (xy 122.697614 -270.210139)
			(xy 122.697494 -270.19758) (xy 122.697997 -270.171359) (xy 122.706279 -270.119575) (xy 122.722633 -270.069748)
			(xy 122.746647 -270.023127) (xy 122.77772 -269.980883) (xy 122.796046 -269.962122) (xy 122.796046 -269.793466)
			(xy 122.795591 -269.779714) (xy 122.788249 -269.753207) (xy 122.774105 -269.729617) (xy 122.754184 -269.710652)
			(xy 122.729928 -269.697685) (xy 122.703093 -269.691654) (xy 122.675621 -269.692997) (xy 122.662442 -269.696946)
			(xy 122.637017 -269.704908) (xy 122.584432 -269.713464) (xy 122.557794 -269.713964) (xy 122.531826 -269.713454)
			(xy 122.48053 -269.705329) (xy 122.431137 -269.689279) (xy 122.384863 -269.665701) (xy 122.342846 -269.635173)
			(xy 122.306123 -269.598449) (xy 122.275596 -269.556432) (xy 122.252018 -269.510157) (xy 122.23597 -269.460764)
			(xy 122.227845 -269.409468) (xy 122.227845 -269.357532) (xy 122.23597 -269.306236) (xy 122.252018 -269.256843)
			(xy 122.275596 -269.210568) (xy 122.306123 -269.168551) (xy 122.342846 -269.131827) (xy 122.384863 -269.101299)
			(xy 122.431137 -269.077721) (xy 122.48053 -269.061671) (xy 122.531826 -269.053546) (xy 122.557794 -269.053056)
			(xy 122.584432 -269.053563) (xy 122.637017 -269.062112) (xy 122.662442 -269.070074) (xy 122.67564 -269.073986)
			(xy 122.703122 -269.075379) (xy 122.729976 -269.069378) (xy 122.754251 -269.056421) (xy 122.774181 -269.037448)
			(xy 122.788317 -269.01384) (xy 122.795631 -268.987313) (xy 122.796046 -268.973554) (xy 122.796046 -268.805406)
			(xy 122.777673 -268.78664) (xy 122.74651 -268.744368) (xy 122.722425 -268.6977) (xy 122.706024 -268.64781)
			(xy 122.697719 -268.595954) (xy 122.69772 -268.543437) (xy 122.706026 -268.491582) (xy 122.722429 -268.441692)
			(xy 122.746515 -268.395025) (xy 122.777678 -268.352754) (xy 122.796046 -268.333982) (xy 122.796046 -267.177266)
			(xy 122.777713 -267.158508) (xy 122.746623 -267.116269) (xy 122.722596 -267.069649) (xy 122.706234 -267.019819)
			(xy 122.697948 -266.968029) (xy 122.697948 -266.915582) (xy 122.706231 -266.863792) (xy 122.722591 -266.813962)
			(xy 122.746617 -266.767341) (xy 122.777706 -266.7251) (xy 122.796046 -266.70635) (xy 122.796046 -266.538202)
			(xy 122.795583 -266.524456) (xy 122.78823 -266.497965) (xy 122.774084 -266.474391) (xy 122.754166 -266.455439)
			(xy 122.729919 -266.442482) (xy 122.703095 -266.436454) (xy 122.675634 -266.437794) (xy 122.662442 -266.441682)
			(xy 122.637016 -266.449643) (xy 122.584432 -266.458198) (xy 122.557794 -266.4587) (xy 122.531823 -266.45819)
			(xy 122.480522 -266.450064) (xy 122.431123 -266.434013) (xy 122.384844 -266.410431) (xy 122.342823 -266.379901)
			(xy 122.306096 -266.343172) (xy 122.275566 -266.301151) (xy 122.251985 -266.254871) (xy 122.235935 -266.205472)
			(xy 122.227809 -266.154171) (xy 122.227809 -266.102229) (xy 122.235935 -266.050928) (xy 122.251985 -266.001529)
			(xy 122.275566 -265.955249) (xy 122.306096 -265.913228) (xy 122.342823 -265.876499) (xy 122.384844 -265.845969)
			(xy 122.431123 -265.822387) (xy 122.480522 -265.806336) (xy 122.531823 -265.79821) (xy 122.557794 -265.797792)
			(xy 122.584432 -265.7983) (xy 122.637017 -265.806849) (xy 122.662442 -265.81481) (xy 122.675642 -265.818721)
			(xy 122.703126 -265.820113) (xy 122.729983 -265.814112) (xy 122.754261 -265.801155) (xy 122.774196 -265.782184)
			(xy 122.788338 -265.758577) (xy 122.795661 -265.73205) (xy 122.796046 -265.71829) (xy 122.796046 -265.549634)
			(xy 122.777716 -265.530877) (xy 122.746631 -265.488638) (xy 122.722608 -265.442019) (xy 122.706251 -265.392191)
			(xy 122.697969 -265.340405) (xy 122.697972 -265.287961) (xy 122.706259 -265.236176) (xy 122.722621 -265.18635)
			(xy 122.746648 -265.139734) (xy 122.777738 -265.097498) (xy 122.796046 -265.078718) (xy 122.796046 -264.910316)
			(xy 122.795584 -264.896569) (xy 122.788234 -264.870074) (xy 122.774088 -264.846496) (xy 122.75417 -264.827542)
			(xy 122.729921 -264.814582) (xy 122.703094 -264.808554) (xy 122.675631 -264.809895) (xy 122.662442 -264.813796)
			(xy 122.637016 -264.821757) (xy 122.584432 -264.830311) (xy 122.557794 -264.830814) (xy 122.53183 -264.830304)
			(xy 122.480542 -264.82218) (xy 122.431156 -264.806133) (xy 122.384889 -264.782558) (xy 122.342879 -264.752035)
			(xy 122.306161 -264.715317) (xy 122.275639 -264.673306) (xy 122.252065 -264.627038) (xy 122.236018 -264.577652)
			(xy 122.227895 -264.526364) (xy 122.227895 -264.474436) (xy 122.236018 -264.423148) (xy 122.252065 -264.373762)
			(xy 122.275639 -264.327494) (xy 122.306161 -264.285483) (xy 122.342879 -264.248765) (xy 122.384889 -264.218242)
			(xy 122.431156 -264.194667) (xy 122.480542 -264.17862) (xy 122.53183 -264.170496) (xy 122.557794 -264.169906)
			(xy 122.584432 -264.170414) (xy 122.637017 -264.178963) (xy 122.662442 -264.186924) (xy 122.675643 -264.190834)
			(xy 122.703128 -264.192226) (xy 122.729986 -264.186225) (xy 122.754265 -264.173269) (xy 122.774202 -264.154298)
			(xy 122.788347 -264.130692) (xy 122.795672 -264.104164) (xy 122.796046 -264.090404) (xy 122.796046 -263.922256)
			(xy 122.777669 -263.90349) (xy 122.746499 -263.861216) (xy 122.722406 -263.814546) (xy 122.705998 -263.764652)
			(xy 122.697687 -263.712792) (xy 122.697682 -263.66027) (xy 122.705983 -263.608408) (xy 122.722382 -263.558511)
			(xy 122.746466 -263.511836) (xy 122.777628 -263.469557) (xy 122.796046 -263.450832) (xy 122.796046 -263.28243)
			(xy 122.795586 -263.268681) (xy 122.788238 -263.242183) (xy 122.774093 -263.218602) (xy 122.754174 -263.199645)
			(xy 122.729923 -263.186683) (xy 122.703094 -263.180654) (xy 122.675628 -263.181995) (xy 122.662442 -263.18591)
			(xy 122.63707 -263.193821) (xy 122.584619 -263.202371) (xy 122.558048 -263.202928) (xy 122.532078 -263.202449)
			(xy 122.480777 -263.19433) (xy 122.431378 -263.178286) (xy 122.385098 -263.154711) (xy 122.343075 -263.124185)
			(xy 122.306346 -263.087461) (xy 122.275814 -263.045443) (xy 122.252232 -262.999166) (xy 122.236181 -262.949769)
			(xy 122.228055 -262.89847) (xy 122.228055 -262.84653) (xy 122.236181 -262.795231) (xy 122.252232 -262.745834)
			(xy 122.275814 -262.699557) (xy 122.306346 -262.657539) (xy 122.343075 -262.620815) (xy 122.385098 -262.590289)
			(xy 122.431378 -262.566714) (xy 122.480777 -262.55067) (xy 122.532078 -262.542551) (xy 122.558048 -262.54202)
			(xy 122.584619 -262.542572) (xy 122.63707 -262.551127) (xy 122.662442 -262.559038) (xy 122.675643 -262.562948)
			(xy 122.703129 -262.564339) (xy 122.729988 -262.558339) (xy 122.754269 -262.545383) (xy 122.774207 -262.526412)
			(xy 122.788355 -262.502806) (xy 122.795684 -262.476279) (xy 122.796046 -262.462518) (xy 122.796046 -262.29437)
			(xy 122.777676 -262.275604) (xy 122.746519 -262.233333) (xy 122.722439 -262.186666) (xy 122.706043 -262.136779)
			(xy 122.697743 -262.084927) (xy 122.697748 -262.032414) (xy 122.706057 -261.980563) (xy 122.722462 -261.930679)
			(xy 122.74655 -261.884017) (xy 122.777714 -261.841752) (xy 122.796046 -261.822946) (xy 122.796046 -261.654798)
			(xy 122.795582 -261.641052) (xy 122.788229 -261.614562) (xy 122.774082 -261.590989) (xy 122.754165 -261.572039)
			(xy 122.729918 -261.559081) (xy 122.703095 -261.553054) (xy 122.675635 -261.554394) (xy 122.662442 -261.558278)
			(xy 122.637016 -261.566239) (xy 122.584432 -261.574794) (xy 122.557794 -261.575296) (xy 122.531824 -261.574786)
			(xy 122.480523 -261.56666) (xy 122.431125 -261.550609) (xy 122.384846 -261.527028) (xy 122.342826 -261.496498)
			(xy 122.306099 -261.45977) (xy 122.275569 -261.417749) (xy 122.251989 -261.37147) (xy 122.235939 -261.322071)
			(xy 122.227813 -261.27077) (xy 122.227813 -261.21883) (xy 122.235939 -261.167529) (xy 122.251989 -261.11813)
			(xy 122.275569 -261.071851) (xy 122.306099 -261.02983) (xy 122.342826 -260.993102) (xy 122.384846 -260.962572)
			(xy 122.431125 -260.938991) (xy 122.480523 -260.92294) (xy 122.531824 -260.914814) (xy 122.557794 -260.914388)
			(xy 122.586139 -260.914942) (xy 122.642004 -260.924568) (xy 122.695399 -260.943607) (xy 122.720354 -260.95706)
			(xy 122.731784 -260.963664) (xy 122.796046 -260.963664) (xy 122.796046 -260.8834) (xy 122.582686 -260.67004)
			(xy 122.315986 -260.67004) (xy 122.297451 -260.687056) (xy 122.256188 -260.715845) (xy 122.211034 -260.738041)
			(xy 122.163036 -260.75313) (xy 122.113305 -260.760763) (xy 122.062991 -260.760763) (xy 122.01326 -260.75313)
			(xy 121.965262 -260.738041) (xy 121.920108 -260.715845) (xy 121.878845 -260.687056) (xy 121.86031 -260.67004)
			(xy 119.397526 -260.67004) (xy 118.796757 -261.270809) (xy 121.288049 -261.270809) (xy 121.288049 -261.218875)
			(xy 121.296174 -261.16758) (xy 121.312222 -261.118187) (xy 121.3358 -261.071913) (xy 121.366326 -261.029897)
			(xy 121.403049 -260.993174) (xy 121.445065 -260.962648) (xy 121.491339 -260.93907) (xy 121.540732 -260.923022)
			(xy 121.592027 -260.914897) (xy 121.643961 -260.914897) (xy 121.695256 -260.923022) (xy 121.744649 -260.93907)
			(xy 121.790923 -260.962648) (xy 121.832939 -260.993174) (xy 121.869662 -261.029897) (xy 121.900188 -261.071913)
			(xy 121.923766 -261.118187) (xy 121.939814 -261.16758) (xy 121.947939 -261.218875) (xy 121.948448 -261.244842)
			(xy 121.947939 -261.270809) (xy 121.939814 -261.322104) (xy 121.923766 -261.371497) (xy 121.900188 -261.417771)
			(xy 121.869662 -261.459787) (xy 121.832939 -261.49651) (xy 121.790923 -261.527036) (xy 121.744649 -261.550614)
			(xy 121.695256 -261.566662) (xy 121.643961 -261.574787) (xy 121.592027 -261.574787) (xy 121.540732 -261.566662)
			(xy 121.491339 -261.550614) (xy 121.445065 -261.527036) (xy 121.403049 -261.49651) (xy 121.366326 -261.459787)
			(xy 121.3358 -261.417771) (xy 121.312222 -261.371497) (xy 121.296174 -261.322104) (xy 121.288049 -261.270809)
			(xy 118.796757 -261.270809) (xy 118.562374 -261.505192) (xy 118.548864 -261.525807) (xy 118.516709 -261.56316)
			(xy 118.479362 -261.595322) (xy 118.458742 -261.608824) (xy 118.203726 -261.86384) (xy 118.203726 -262.084625)
			(xy 121.758203 -262.084625) (xy 121.758203 -262.032691) (xy 121.766328 -261.981396) (xy 121.782376 -261.932003)
			(xy 121.805954 -261.885729) (xy 121.83648 -261.843713) (xy 121.873203 -261.80699) (xy 121.915219 -261.776464)
			(xy 121.961493 -261.752886) (xy 122.010886 -261.736838) (xy 122.062181 -261.728713) (xy 122.114115 -261.728713)
			(xy 122.16541 -261.736838) (xy 122.214803 -261.752886) (xy 122.261077 -261.776464) (xy 122.303093 -261.80699)
			(xy 122.339816 -261.843713) (xy 122.370342 -261.885729) (xy 122.39392 -261.932003) (xy 122.409968 -261.981396)
			(xy 122.418093 -262.032691) (xy 122.418602 -262.058658) (xy 122.418093 -262.084625) (xy 122.409968 -262.13592)
			(xy 122.39392 -262.185313) (xy 122.370342 -262.231587) (xy 122.339816 -262.273603) (xy 122.303093 -262.310326)
			(xy 122.261077 -262.340852) (xy 122.214803 -262.36443) (xy 122.16541 -262.380478) (xy 122.114115 -262.388603)
			(xy 122.062181 -262.388603) (xy 122.010886 -262.380478) (xy 121.961493 -262.36443) (xy 121.915219 -262.340852)
			(xy 121.873203 -262.310326) (xy 121.83648 -262.273603) (xy 121.805954 -262.231587) (xy 121.782376 -262.185313)
			(xy 121.766328 -262.13592) (xy 121.758203 -262.084625) (xy 118.203726 -262.084625) (xy 118.203726 -263.391963)
			(xy 118.382543 -263.391963) (xy 118.382543 -263.340029) (xy 118.390668 -263.288734) (xy 118.406716 -263.239341)
			(xy 118.430294 -263.193067) (xy 118.46082 -263.151051) (xy 118.497543 -263.114328) (xy 118.539559 -263.083802)
			(xy 118.585833 -263.060224) (xy 118.635226 -263.044176) (xy 118.686521 -263.036051) (xy 118.738455 -263.036051)
			(xy 118.78975 -263.044176) (xy 118.839143 -263.060224) (xy 118.885417 -263.083802) (xy 118.927433 -263.114328)
			(xy 118.964156 -263.151051) (xy 118.994682 -263.193067) (xy 119.01826 -263.239341) (xy 119.034308 -263.288734)
			(xy 119.036658 -263.30357) (xy 119.375633 -263.30357) (xy 119.375633 -263.25163) (xy 119.383759 -263.200328)
			(xy 119.39981 -263.15093) (xy 119.423392 -263.104651) (xy 119.453923 -263.062631) (xy 119.490653 -263.025905)
			(xy 119.532675 -262.995377) (xy 119.578956 -262.971799) (xy 119.628356 -262.955752) (xy 119.679658 -262.947631)
			(xy 119.705628 -262.94715) (xy 119.732142 -262.947677) (xy 119.784486 -262.956165) (xy 119.834799 -262.972918)
			(xy 119.858536 -262.984742) (xy 119.872252 -262.991257) (xy 119.902084 -262.996822) (xy 119.932234 -262.993381)
			(xy 119.960044 -262.981237) (xy 119.983062 -262.961461) (xy 119.991632 -262.948928) (xy 120.0069 -262.925775)
			(xy 120.043972 -262.884529) (xy 120.087412 -262.850053) (xy 120.135998 -262.823315) (xy 120.188368 -262.805066)
			(xy 120.243049 -262.795818) (xy 120.270778 -262.795258) (xy 120.296749 -262.795715) (xy 120.348053 -262.803838)
			(xy 120.397454 -262.819886) (xy 120.443737 -262.843466) (xy 120.48576 -262.873995) (xy 120.510208 -262.898441)
			(xy 121.288049 -262.898441) (xy 121.288049 -262.846507) (xy 121.296174 -262.795212) (xy 121.312222 -262.745819)
			(xy 121.3358 -262.699545) (xy 121.366326 -262.657529) (xy 121.403049 -262.620806) (xy 121.445065 -262.59028)
			(xy 121.491339 -262.566702) (xy 121.540732 -262.550654) (xy 121.592027 -262.542529) (xy 121.643961 -262.542529)
			(xy 121.695256 -262.550654) (xy 121.744649 -262.566702) (xy 121.790923 -262.59028) (xy 121.832939 -262.620806)
			(xy 121.869662 -262.657529) (xy 121.900188 -262.699545) (xy 121.923766 -262.745819) (xy 121.939814 -262.795212)
			(xy 121.947939 -262.846507) (xy 121.948448 -262.872474) (xy 121.947939 -262.898441) (xy 121.939814 -262.949736)
			(xy 121.923766 -262.999129) (xy 121.900188 -263.045403) (xy 121.869662 -263.087419) (xy 121.832939 -263.124142)
			(xy 121.790923 -263.154668) (xy 121.744649 -263.178246) (xy 121.695256 -263.194294) (xy 121.643961 -263.202419)
			(xy 121.592027 -263.202419) (xy 121.540732 -263.194294) (xy 121.491339 -263.178246) (xy 121.445065 -263.154668)
			(xy 121.403049 -263.124142) (xy 121.366326 -263.087419) (xy 121.3358 -263.045403) (xy 121.312222 -262.999129)
			(xy 121.296174 -262.949736) (xy 121.288049 -262.898441) (xy 120.510208 -262.898441) (xy 120.522491 -262.910723)
			(xy 120.553023 -262.952745) (xy 120.576605 -262.999025) (xy 120.592657 -263.048426) (xy 120.600783 -263.099729)
			(xy 120.600783 -263.151671) (xy 120.592657 -263.202974) (xy 120.576605 -263.252375) (xy 120.553023 -263.298655)
			(xy 120.522491 -263.340677) (xy 120.48576 -263.377405) (xy 120.443737 -263.407934) (xy 120.397454 -263.431514)
			(xy 120.348053 -263.447562) (xy 120.296749 -263.455685) (xy 120.270778 -263.456166) (xy 120.244264 -263.455646)
			(xy 120.191919 -263.447157) (xy 120.141607 -263.430401) (xy 120.11787 -263.418574) (xy 120.104153 -263.41206)
			(xy 120.074322 -263.406492) (xy 120.044171 -263.409932) (xy 120.01636 -263.422076) (xy 119.993343 -263.441854)
			(xy 119.984774 -263.454388) (xy 119.969475 -263.47752) (xy 119.932412 -263.51877) (xy 119.88898 -263.553251)
			(xy 119.840399 -263.579994) (xy 119.788034 -263.598247) (xy 119.733356 -263.607497) (xy 119.705628 -263.608058)
			(xy 119.679658 -263.607569) (xy 119.628356 -263.599448) (xy 119.578956 -263.583401) (xy 119.532675 -263.559823)
			(xy 119.490653 -263.529295) (xy 119.453923 -263.492569) (xy 119.423392 -263.450549) (xy 119.39981 -263.40427)
			(xy 119.383759 -263.354872) (xy 119.375633 -263.30357) (xy 119.036658 -263.30357) (xy 119.042433 -263.340029)
			(xy 119.042942 -263.365996) (xy 119.042433 -263.391963) (xy 119.034308 -263.443258) (xy 119.01826 -263.492651)
			(xy 118.994682 -263.538925) (xy 118.964156 -263.580941) (xy 118.927433 -263.617664) (xy 118.885417 -263.64819)
			(xy 118.839143 -263.671768) (xy 118.78975 -263.687816) (xy 118.738455 -263.695941) (xy 118.686521 -263.695941)
			(xy 118.635226 -263.687816) (xy 118.585833 -263.671768) (xy 118.539559 -263.64819) (xy 118.497543 -263.617664)
			(xy 118.46082 -263.580941) (xy 118.430294 -263.538925) (xy 118.406716 -263.492651) (xy 118.390668 -263.443258)
			(xy 118.382543 -263.391963) (xy 118.203726 -263.391963) (xy 118.203726 -263.712511) (xy 121.758203 -263.712511)
			(xy 121.758203 -263.660577) (xy 121.766328 -263.609282) (xy 121.782376 -263.559889) (xy 121.805954 -263.513615)
			(xy 121.83648 -263.471599) (xy 121.873203 -263.434876) (xy 121.915219 -263.40435) (xy 121.961493 -263.380772)
			(xy 122.010886 -263.364724) (xy 122.062181 -263.356599) (xy 122.114115 -263.356599) (xy 122.16541 -263.364724)
			(xy 122.214803 -263.380772) (xy 122.261077 -263.40435) (xy 122.303093 -263.434876) (xy 122.339816 -263.471599)
			(xy 122.370342 -263.513615) (xy 122.39392 -263.559889) (xy 122.409968 -263.609282) (xy 122.418093 -263.660577)
			(xy 122.418602 -263.686544) (xy 122.418093 -263.712511) (xy 122.409968 -263.763806) (xy 122.39392 -263.813199)
			(xy 122.370342 -263.859473) (xy 122.339816 -263.901489) (xy 122.303093 -263.938212) (xy 122.261077 -263.968738)
			(xy 122.214803 -263.992316) (xy 122.16541 -264.008364) (xy 122.114115 -264.016489) (xy 122.062181 -264.016489)
			(xy 122.010886 -264.008364) (xy 121.961493 -263.992316) (xy 121.915219 -263.968738) (xy 121.873203 -263.938212)
			(xy 121.83648 -263.901489) (xy 121.805954 -263.859473) (xy 121.782376 -263.813199) (xy 121.766328 -263.763806)
			(xy 121.758203 -263.712511) (xy 118.203726 -263.712511) (xy 118.203726 -264.526327) (xy 118.468649 -264.526327)
			(xy 118.468649 -264.474393) (xy 118.476774 -264.423098) (xy 118.492822 -264.373705) (xy 118.5164 -264.327431)
			(xy 118.546926 -264.285415) (xy 118.583649 -264.248692) (xy 118.625665 -264.218166) (xy 118.671939 -264.194588)
			(xy 118.721332 -264.17854) (xy 118.772627 -264.170415) (xy 118.824561 -264.170415) (xy 118.875856 -264.17854)
			(xy 118.925249 -264.194588) (xy 118.971523 -264.218166) (xy 119.013539 -264.248692) (xy 119.050262 -264.285415)
			(xy 119.080788 -264.327431) (xy 119.104366 -264.373705) (xy 119.120414 -264.423098) (xy 119.128539 -264.474393)
			(xy 119.129048 -264.50036) (xy 119.128539 -264.526327) (xy 119.408449 -264.526327) (xy 119.408449 -264.474393)
			(xy 119.416574 -264.423098) (xy 119.432622 -264.373705) (xy 119.4562 -264.327431) (xy 119.486726 -264.285415)
			(xy 119.523449 -264.248692) (xy 119.565465 -264.218166) (xy 119.611739 -264.194588) (xy 119.661132 -264.17854)
			(xy 119.712427 -264.170415) (xy 119.764361 -264.170415) (xy 119.815656 -264.17854) (xy 119.865049 -264.194588)
			(xy 119.911323 -264.218166) (xy 119.953339 -264.248692) (xy 119.990062 -264.285415) (xy 120.020588 -264.327431)
			(xy 120.044166 -264.373705) (xy 120.060214 -264.423098) (xy 120.068339 -264.474393) (xy 120.068848 -264.50036)
			(xy 120.068339 -264.526327) (xy 120.348249 -264.526327) (xy 120.348249 -264.474393) (xy 120.356374 -264.423098)
			(xy 120.372422 -264.373705) (xy 120.396 -264.327431) (xy 120.426526 -264.285415) (xy 120.463249 -264.248692)
			(xy 120.505265 -264.218166) (xy 120.551539 -264.194588) (xy 120.600932 -264.17854) (xy 120.652227 -264.170415)
			(xy 120.704161 -264.170415) (xy 120.755456 -264.17854) (xy 120.804849 -264.194588) (xy 120.851123 -264.218166)
			(xy 120.893139 -264.248692) (xy 120.929862 -264.285415) (xy 120.960388 -264.327431) (xy 120.983966 -264.373705)
			(xy 121.000014 -264.423098) (xy 121.008139 -264.474393) (xy 121.008648 -264.50036) (xy 121.008139 -264.526327)
			(xy 121.288049 -264.526327) (xy 121.288049 -264.474393) (xy 121.296174 -264.423098) (xy 121.312222 -264.373705)
			(xy 121.3358 -264.327431) (xy 121.366326 -264.285415) (xy 121.403049 -264.248692) (xy 121.445065 -264.218166)
			(xy 121.491339 -264.194588) (xy 121.540732 -264.17854) (xy 121.592027 -264.170415) (xy 121.643961 -264.170415)
			(xy 121.695256 -264.17854) (xy 121.744649 -264.194588) (xy 121.790923 -264.218166) (xy 121.832939 -264.248692)
			(xy 121.869662 -264.285415) (xy 121.900188 -264.327431) (xy 121.923766 -264.373705) (xy 121.939814 -264.423098)
			(xy 121.947939 -264.474393) (xy 121.948448 -264.50036) (xy 121.947939 -264.526327) (xy 121.939814 -264.577622)
			(xy 121.923766 -264.627015) (xy 121.900188 -264.673289) (xy 121.869662 -264.715305) (xy 121.832939 -264.752028)
			(xy 121.790923 -264.782554) (xy 121.744649 -264.806132) (xy 121.695256 -264.82218) (xy 121.643961 -264.830305)
			(xy 121.592027 -264.830305) (xy 121.540732 -264.82218) (xy 121.491339 -264.806132) (xy 121.445065 -264.782554)
			(xy 121.403049 -264.752028) (xy 121.366326 -264.715305) (xy 121.3358 -264.673289) (xy 121.312222 -264.627015)
			(xy 121.296174 -264.577622) (xy 121.288049 -264.526327) (xy 121.008139 -264.526327) (xy 121.000014 -264.577622)
			(xy 120.983966 -264.627015) (xy 120.960388 -264.673289) (xy 120.929862 -264.715305) (xy 120.893139 -264.752028)
			(xy 120.851123 -264.782554) (xy 120.804849 -264.806132) (xy 120.755456 -264.82218) (xy 120.704161 -264.830305)
			(xy 120.652227 -264.830305) (xy 120.600932 -264.82218) (xy 120.551539 -264.806132) (xy 120.505265 -264.782554)
			(xy 120.463249 -264.752028) (xy 120.426526 -264.715305) (xy 120.396 -264.673289) (xy 120.372422 -264.627015)
			(xy 120.356374 -264.577622) (xy 120.348249 -264.526327) (xy 120.068339 -264.526327) (xy 120.060214 -264.577622)
			(xy 120.044166 -264.627015) (xy 120.020588 -264.673289) (xy 119.990062 -264.715305) (xy 119.953339 -264.752028)
			(xy 119.911323 -264.782554) (xy 119.865049 -264.806132) (xy 119.815656 -264.82218) (xy 119.764361 -264.830305)
			(xy 119.712427 -264.830305) (xy 119.661132 -264.82218) (xy 119.611739 -264.806132) (xy 119.565465 -264.782554)
			(xy 119.523449 -264.752028) (xy 119.486726 -264.715305) (xy 119.4562 -264.673289) (xy 119.432622 -264.627015)
			(xy 119.416574 -264.577622) (xy 119.408449 -264.526327) (xy 119.128539 -264.526327) (xy 119.120414 -264.577622)
			(xy 119.104366 -264.627015) (xy 119.080788 -264.673289) (xy 119.050262 -264.715305) (xy 119.013539 -264.752028)
			(xy 118.971523 -264.782554) (xy 118.925249 -264.806132) (xy 118.875856 -264.82218) (xy 118.824561 -264.830305)
			(xy 118.772627 -264.830305) (xy 118.721332 -264.82218) (xy 118.671939 -264.806132) (xy 118.625665 -264.782554)
			(xy 118.583649 -264.752028) (xy 118.546926 -264.715305) (xy 118.5164 -264.673289) (xy 118.492822 -264.627015)
			(xy 118.476774 -264.577622) (xy 118.468649 -264.526327) (xy 118.203726 -264.526327) (xy 118.203726 -264.882884)
			(xy 118.20417 -264.896676) (xy 118.211534 -264.923259) (xy 118.225754 -264.946894) (xy 118.24579 -264.965852)
			(xy 118.270175 -264.978746) (xy 118.297123 -264.984631) (xy 118.310914 -264.98423) (xy 118.328694 -264.983722)
			(xy 118.354665 -264.984204) (xy 118.405969 -264.992329) (xy 118.45537 -265.00838) (xy 118.501652 -265.031961)
			(xy 118.543675 -265.062492) (xy 118.580404 -265.099221) (xy 118.610936 -265.141243) (xy 118.634518 -265.187524)
			(xy 118.650569 -265.236925) (xy 118.658695 -265.288229) (xy 118.658695 -265.340143) (xy 118.938803 -265.340143)
			(xy 118.938803 -265.288209) (xy 118.946928 -265.236914) (xy 118.962976 -265.187521) (xy 118.986554 -265.141247)
			(xy 119.01708 -265.099231) (xy 119.053803 -265.062508) (xy 119.095819 -265.031982) (xy 119.142093 -265.008404)
			(xy 119.191486 -264.992356) (xy 119.242781 -264.984231) (xy 119.294715 -264.984231) (xy 119.34601 -264.992356)
			(xy 119.395403 -265.008404) (xy 119.441677 -265.031982) (xy 119.483693 -265.062508) (xy 119.520416 -265.099231)
			(xy 119.550942 -265.141247) (xy 119.57452 -265.187521) (xy 119.590568 -265.236914) (xy 119.598693 -265.288209)
			(xy 119.599202 -265.314176) (xy 119.598693 -265.340143) (xy 119.878603 -265.340143) (xy 119.878603 -265.288209)
			(xy 119.886728 -265.236914) (xy 119.902776 -265.187521) (xy 119.926354 -265.141247) (xy 119.95688 -265.099231)
			(xy 119.993603 -265.062508) (xy 120.035619 -265.031982) (xy 120.081893 -265.008404) (xy 120.131286 -264.992356)
			(xy 120.182581 -264.984231) (xy 120.234515 -264.984231) (xy 120.28581 -264.992356) (xy 120.335203 -265.008404)
			(xy 120.381477 -265.031982) (xy 120.423493 -265.062508) (xy 120.460216 -265.099231) (xy 120.490742 -265.141247)
			(xy 120.51432 -265.187521) (xy 120.530368 -265.236914) (xy 120.538493 -265.288209) (xy 120.539002 -265.314176)
			(xy 120.538493 -265.340143) (xy 121.758203 -265.340143) (xy 121.758203 -265.288209) (xy 121.766328 -265.236914)
			(xy 121.782376 -265.187521) (xy 121.805954 -265.141247) (xy 121.83648 -265.099231) (xy 121.873203 -265.062508)
			(xy 121.915219 -265.031982) (xy 121.961493 -265.008404) (xy 122.010886 -264.992356) (xy 122.062181 -264.984231)
			(xy 122.114115 -264.984231) (xy 122.16541 -264.992356) (xy 122.214803 -265.008404) (xy 122.261077 -265.031982)
			(xy 122.303093 -265.062508) (xy 122.339816 -265.099231) (xy 122.370342 -265.141247) (xy 122.39392 -265.187521)
			(xy 122.409968 -265.236914) (xy 122.418093 -265.288209) (xy 122.418602 -265.314176) (xy 122.418093 -265.340143)
			(xy 122.409968 -265.391438) (xy 122.39392 -265.440831) (xy 122.370342 -265.487105) (xy 122.339816 -265.529121)
			(xy 122.303093 -265.565844) (xy 122.261077 -265.59637) (xy 122.214803 -265.619948) (xy 122.16541 -265.635996)
			(xy 122.114115 -265.644121) (xy 122.062181 -265.644121) (xy 122.010886 -265.635996) (xy 121.961493 -265.619948)
			(xy 121.915219 -265.59637) (xy 121.873203 -265.565844) (xy 121.83648 -265.529121) (xy 121.805954 -265.487105)
			(xy 121.782376 -265.440831) (xy 121.766328 -265.391438) (xy 121.758203 -265.340143) (xy 120.538493 -265.340143)
			(xy 120.530368 -265.391438) (xy 120.51432 -265.440831) (xy 120.490742 -265.487105) (xy 120.460216 -265.529121)
			(xy 120.423493 -265.565844) (xy 120.381477 -265.59637) (xy 120.335203 -265.619948) (xy 120.28581 -265.635996)
			(xy 120.234515 -265.644121) (xy 120.182581 -265.644121) (xy 120.131286 -265.635996) (xy 120.081893 -265.619948)
			(xy 120.035619 -265.59637) (xy 119.993603 -265.565844) (xy 119.95688 -265.529121) (xy 119.926354 -265.487105)
			(xy 119.902776 -265.440831) (xy 119.886728 -265.391438) (xy 119.878603 -265.340143) (xy 119.598693 -265.340143)
			(xy 119.590568 -265.391438) (xy 119.57452 -265.440831) (xy 119.550942 -265.487105) (xy 119.520416 -265.529121)
			(xy 119.483693 -265.565844) (xy 119.441677 -265.59637) (xy 119.395403 -265.619948) (xy 119.34601 -265.635996)
			(xy 119.294715 -265.644121) (xy 119.242781 -265.644121) (xy 119.191486 -265.635996) (xy 119.142093 -265.619948)
			(xy 119.095819 -265.59637) (xy 119.053803 -265.565844) (xy 119.01708 -265.529121) (xy 118.986554 -265.487105)
			(xy 118.962976 -265.440831) (xy 118.946928 -265.391438) (xy 118.938803 -265.340143) (xy 118.658695 -265.340143)
			(xy 118.658695 -265.340171) (xy 118.650569 -265.391475) (xy 118.634518 -265.440876) (xy 118.610936 -265.487157)
			(xy 118.580404 -265.529179) (xy 118.543675 -265.565908) (xy 118.501652 -265.596439) (xy 118.45537 -265.62002)
			(xy 118.405969 -265.636071) (xy 118.354665 -265.644196) (xy 118.328694 -265.64463) (xy 118.310914 -265.644122)
			(xy 118.297135 -265.64383) (xy 118.270229 -265.649743) (xy 118.245883 -265.662635) (xy 118.225869 -265.681566)
			(xy 118.211645 -265.705158) (xy 118.204246 -265.731694) (xy 118.203726 -265.745468) (xy 118.203726 -266.154467)
			(xy 118.468649 -266.154467) (xy 118.468649 -266.102533) (xy 118.476774 -266.051238) (xy 118.492822 -266.001845)
			(xy 118.5164 -265.955571) (xy 118.546926 -265.913555) (xy 118.583649 -265.876832) (xy 118.625665 -265.846306)
			(xy 118.671939 -265.822728) (xy 118.721332 -265.80668) (xy 118.772627 -265.798555) (xy 118.824561 -265.798555)
			(xy 118.875856 -265.80668) (xy 118.925249 -265.822728) (xy 118.971523 -265.846306) (xy 119.013539 -265.876832)
			(xy 119.050262 -265.913555) (xy 119.080788 -265.955571) (xy 119.104366 -266.001845) (xy 119.120414 -266.051238)
			(xy 119.128539 -266.102533) (xy 119.129048 -266.1285) (xy 119.128544 -266.154213) (xy 119.408449 -266.154213)
			(xy 119.408449 -266.102279) (xy 119.416574 -266.050984) (xy 119.432622 -266.001591) (xy 119.4562 -265.955317)
			(xy 119.486726 -265.913301) (xy 119.523449 -265.876578) (xy 119.565465 -265.846052) (xy 119.611739 -265.822474)
			(xy 119.661132 -265.806426) (xy 119.712427 -265.798301) (xy 119.764361 -265.798301) (xy 119.815656 -265.806426)
			(xy 119.865049 -265.822474) (xy 119.911323 -265.846052) (xy 119.953339 -265.876578) (xy 119.990062 -265.913301)
			(xy 120.020588 -265.955317) (xy 120.044166 -266.001591) (xy 120.060214 -266.050984) (xy 120.068339 -266.102279)
			(xy 120.068848 -266.128246) (xy 120.068339 -266.154213) (xy 120.348249 -266.154213) (xy 120.348249 -266.102279)
			(xy 120.356374 -266.050984) (xy 120.372422 -266.001591) (xy 120.396 -265.955317) (xy 120.426526 -265.913301)
			(xy 120.463249 -265.876578) (xy 120.505265 -265.846052) (xy 120.551539 -265.822474) (xy 120.600932 -265.806426)
			(xy 120.652227 -265.798301) (xy 120.704161 -265.798301) (xy 120.755456 -265.806426) (xy 120.804849 -265.822474)
			(xy 120.851123 -265.846052) (xy 120.893139 -265.876578) (xy 120.929862 -265.913301) (xy 120.960388 -265.955317)
			(xy 120.983966 -266.001591) (xy 121.000014 -266.050984) (xy 121.008139 -266.102279) (xy 121.008648 -266.128246)
			(xy 121.008139 -266.154213) (xy 121.000014 -266.205508) (xy 120.983966 -266.254901) (xy 120.960388 -266.301175)
			(xy 120.929862 -266.343191) (xy 120.893139 -266.379914) (xy 120.851123 -266.41044) (xy 120.804849 -266.434018)
			(xy 120.755456 -266.450066) (xy 120.704161 -266.458191) (xy 120.652227 -266.458191) (xy 120.600932 -266.450066)
			(xy 120.551539 -266.434018) (xy 120.505265 -266.41044) (xy 120.463249 -266.379914) (xy 120.426526 -266.343191)
			(xy 120.396 -266.301175) (xy 120.372422 -266.254901) (xy 120.356374 -266.205508) (xy 120.348249 -266.154213)
			(xy 120.068339 -266.154213) (xy 120.060214 -266.205508) (xy 120.044166 -266.254901) (xy 120.020588 -266.301175)
			(xy 119.990062 -266.343191) (xy 119.953339 -266.379914) (xy 119.911323 -266.41044) (xy 119.865049 -266.434018)
			(xy 119.815656 -266.450066) (xy 119.764361 -266.458191) (xy 119.712427 -266.458191) (xy 119.661132 -266.450066)
			(xy 119.611739 -266.434018) (xy 119.565465 -266.41044) (xy 119.523449 -266.379914) (xy 119.486726 -266.343191)
			(xy 119.4562 -266.301175) (xy 119.432622 -266.254901) (xy 119.416574 -266.205508) (xy 119.408449 -266.154213)
			(xy 119.128544 -266.154213) (xy 119.128539 -266.154467) (xy 119.120414 -266.205762) (xy 119.104366 -266.255155)
			(xy 119.080788 -266.301429) (xy 119.050262 -266.343445) (xy 119.013539 -266.380168) (xy 118.971523 -266.410694)
			(xy 118.925249 -266.434272) (xy 118.875856 -266.45032) (xy 118.824561 -266.458445) (xy 118.772627 -266.458445)
			(xy 118.721332 -266.45032) (xy 118.671939 -266.434272) (xy 118.625665 -266.410694) (xy 118.583649 -266.380168)
			(xy 118.546926 -266.343445) (xy 118.5164 -266.301429) (xy 118.492822 -266.255155) (xy 118.476774 -266.205762)
			(xy 118.468649 -266.154467) (xy 118.203726 -266.154467) (xy 118.203726 -266.510262) (xy 118.204141 -266.524047)
			(xy 118.211445 -266.550629) (xy 118.22561 -266.574279) (xy 118.245599 -266.593264) (xy 118.269947 -266.606192)
			(xy 118.29687 -266.612118) (xy 118.31066 -266.611862) (xy 118.32844 -266.611354) (xy 118.354405 -266.611866)
			(xy 118.405693 -266.619995) (xy 118.45508 -266.636047) (xy 118.501347 -266.659626) (xy 118.543356 -266.690153)
			(xy 118.580073 -266.726874) (xy 118.610595 -266.768887) (xy 118.634168 -266.815157) (xy 118.650214 -266.864545)
			(xy 118.658337 -266.915835) (xy 118.658337 -266.967765) (xy 118.658335 -266.967775) (xy 121.758203 -266.967775)
			(xy 121.758203 -266.915841) (xy 121.766328 -266.864546) (xy 121.782376 -266.815153) (xy 121.805954 -266.768879)
			(xy 121.83648 -266.726863) (xy 121.873203 -266.69014) (xy 121.915219 -266.659614) (xy 121.961493 -266.636036)
			(xy 122.010886 -266.619988) (xy 122.062181 -266.611863) (xy 122.114115 -266.611863) (xy 122.16541 -266.619988)
			(xy 122.214803 -266.636036) (xy 122.261077 -266.659614) (xy 122.303093 -266.69014) (xy 122.339816 -266.726863)
			(xy 122.370342 -266.768879) (xy 122.39392 -266.815153) (xy 122.409968 -266.864546) (xy 122.418093 -266.915841)
			(xy 122.418602 -266.941808) (xy 122.418093 -266.967775) (xy 122.409968 -267.01907) (xy 122.39392 -267.068463)
			(xy 122.370342 -267.114737) (xy 122.339816 -267.156753) (xy 122.303093 -267.193476) (xy 122.261077 -267.224002)
			(xy 122.214803 -267.24758) (xy 122.16541 -267.263628) (xy 122.114115 -267.271753) (xy 122.062181 -267.271753)
			(xy 122.010886 -267.263628) (xy 121.961493 -267.24758) (xy 121.915219 -267.224002) (xy 121.873203 -267.193476)
			(xy 121.83648 -267.156753) (xy 121.805954 -267.114737) (xy 121.782376 -267.068463) (xy 121.766328 -267.01907)
			(xy 121.758203 -266.967775) (xy 118.658335 -266.967775) (xy 118.650214 -267.019055) (xy 118.634168 -267.068443)
			(xy 118.610595 -267.114713) (xy 118.580073 -267.156726) (xy 118.543356 -267.193447) (xy 118.501347 -267.223974)
			(xy 118.45508 -267.247553) (xy 118.405693 -267.263605) (xy 118.354405 -267.271734) (xy 118.32844 -267.272262)
			(xy 118.31066 -267.271754) (xy 118.296879 -267.271496) (xy 118.269984 -267.277475) (xy 118.245665 -267.290424)
			(xy 118.225691 -267.3094) (xy 118.211514 -267.333025) (xy 118.204166 -267.359578) (xy 118.203726 -267.373354)
			(xy 118.203726 -267.781845) (xy 119.408449 -267.781845) (xy 119.408449 -267.729911) (xy 119.416574 -267.678616)
			(xy 119.432622 -267.629223) (xy 119.4562 -267.582949) (xy 119.486726 -267.540933) (xy 119.523449 -267.50421)
			(xy 119.565465 -267.473684) (xy 119.611739 -267.450106) (xy 119.661132 -267.434058) (xy 119.712427 -267.425933)
			(xy 119.764361 -267.425933) (xy 119.815656 -267.434058) (xy 119.865049 -267.450106) (xy 119.911323 -267.473684)
			(xy 119.953339 -267.50421) (xy 119.990062 -267.540933) (xy 120.020588 -267.582949) (xy 120.044166 -267.629223)
			(xy 120.060214 -267.678616) (xy 120.068339 -267.729911) (xy 120.068848 -267.755878) (xy 120.068339 -267.781845)
			(xy 120.060214 -267.83314) (xy 120.044166 -267.882533) (xy 120.020588 -267.928807) (xy 119.990062 -267.970823)
			(xy 119.953339 -268.007546) (xy 119.911323 -268.038072) (xy 119.865049 -268.06165) (xy 119.815656 -268.077698)
			(xy 119.764361 -268.085823) (xy 119.712427 -268.085823) (xy 119.661132 -268.077698) (xy 119.611739 -268.06165)
			(xy 119.565465 -268.038072) (xy 119.523449 -268.007546) (xy 119.486726 -267.970823) (xy 119.4562 -267.928807)
			(xy 119.432622 -267.882533) (xy 119.416574 -267.83314) (xy 119.408449 -267.781845) (xy 118.203726 -267.781845)
			(xy 118.203726 -268.138402) (xy 118.204173 -268.152193) (xy 118.21154 -268.178771) (xy 118.225761 -268.202402)
			(xy 118.245796 -268.221356) (xy 118.270178 -268.234247) (xy 118.297124 -268.240131) (xy 118.310914 -268.239748)
			(xy 118.328948 -268.23924) (xy 118.354913 -268.239753) (xy 118.406203 -268.247883) (xy 118.45559 -268.263936)
			(xy 118.501859 -268.287517) (xy 118.543869 -268.318045) (xy 118.580586 -268.354768) (xy 118.611108 -268.396782)
			(xy 118.634682 -268.443054) (xy 118.650728 -268.492443) (xy 118.658851 -268.543735) (xy 118.658851 -268.595665)
			(xy 118.650728 -268.646957) (xy 118.634682 -268.696346) (xy 118.611108 -268.742618) (xy 118.580586 -268.784632)
			(xy 118.543869 -268.821355) (xy 118.501859 -268.851883) (xy 118.45559 -268.875464) (xy 118.406203 -268.891517)
			(xy 118.354913 -268.899647) (xy 118.328948 -268.900148) (xy 118.310914 -268.89964) (xy 118.297131 -268.899348)
			(xy 118.270217 -268.90526) (xy 118.245861 -268.91815) (xy 118.225834 -268.937078) (xy 118.211594 -268.96067)
			(xy 118.204175 -268.987209) (xy 118.203726 -269.000986) (xy 118.203726 -269.409477) (xy 120.348249 -269.409477)
			(xy 120.348249 -269.357543) (xy 120.356374 -269.306248) (xy 120.372422 -269.256855) (xy 120.396 -269.210581)
			(xy 120.426526 -269.168565) (xy 120.463249 -269.131842) (xy 120.505265 -269.101316) (xy 120.551539 -269.077738)
			(xy 120.600932 -269.06169) (xy 120.652227 -269.053565) (xy 120.704161 -269.053565) (xy 120.755456 -269.06169)
			(xy 120.804849 -269.077738) (xy 120.851123 -269.101316) (xy 120.893139 -269.131842) (xy 120.929862 -269.168565)
			(xy 120.960388 -269.210581) (xy 120.983966 -269.256855) (xy 121.000014 -269.306248) (xy 121.008139 -269.357543)
			(xy 121.008648 -269.38351) (xy 121.008139 -269.409477) (xy 121.000014 -269.460772) (xy 120.983966 -269.510165)
			(xy 120.960388 -269.556439) (xy 120.929862 -269.598455) (xy 120.893139 -269.635178) (xy 120.851123 -269.665704)
			(xy 120.804849 -269.689282) (xy 120.755456 -269.70533) (xy 120.704161 -269.713455) (xy 120.652227 -269.713455)
			(xy 120.600932 -269.70533) (xy 120.551539 -269.689282) (xy 120.505265 -269.665704) (xy 120.463249 -269.635178)
			(xy 120.426526 -269.598455) (xy 120.396 -269.556439) (xy 120.372422 -269.510165) (xy 120.356374 -269.460772)
			(xy 120.348249 -269.409477) (xy 118.203726 -269.409477) (xy 118.203726 -269.766288) (xy 118.204171 -269.78008)
			(xy 118.211535 -269.806661) (xy 118.225756 -269.830296) (xy 118.245791 -269.849253) (xy 118.270175 -269.862146)
			(xy 118.297123 -269.868031) (xy 118.310914 -269.867634) (xy 118.328948 -269.867126) (xy 118.354913 -269.867639)
			(xy 118.406204 -269.875769) (xy 118.455591 -269.891822) (xy 118.50186 -269.915402) (xy 118.543871 -269.945928)
			(xy 118.58059 -269.982651) (xy 118.611113 -270.024664) (xy 118.634689 -270.070935) (xy 118.650738 -270.120324)
			(xy 118.658863 -270.171615) (xy 118.659402 -270.19758) (xy 118.659124 -270.216094) (xy 118.65492 -270.252885)
			(xy 118.65102 -270.270986) (xy 118.644924 -270.298418) (xy 118.953026 -270.60652) (xy 122.371866 -270.60652)
		)
		(stroke
			(width 0)
			(type solid)
		)
		(fill yes)
		(layer "In11.Cu")
		(net "PVCCINFAON_CPU1")
	)
	(gr_poly
		(pts
			(xy 370.637054 -270.201136) (xy 370.63807 -270.181578) (xy 370.639828 -270.155577) (xy 370.6505 -270.10457)
			(xy 370.669038 -270.055867) (xy 370.694986 -270.010675) (xy 370.727699 -269.97011) (xy 370.766369 -269.935178)
			(xy 370.810039 -269.906743) (xy 370.857628 -269.885508) (xy 370.882672 -269.878302) (xy 370.920264 -269.868396)
			(xy 370.920264 -269.672816) (xy 370.919832 -269.659206) (xy 370.91264 -269.632953) (xy 370.898763 -269.609535)
			(xy 370.879189 -269.59062) (xy 370.85531 -269.577552) (xy 370.828827 -269.571262) (xy 370.801623 -269.572198)
			(xy 370.775634 -269.580292) (xy 370.752709 -269.594969) (xy 370.743226 -269.604744) (xy 370.724286 -269.624933)
			(xy 370.680902 -269.65931) (xy 370.632393 -269.685971) (xy 370.580117 -269.704169) (xy 370.525538 -269.713393)
			(xy 370.497862 -269.713964) (xy 370.471896 -269.713452) (xy 370.420604 -269.705323) (xy 370.371215 -269.68927)
			(xy 370.324945 -269.66569) (xy 370.282933 -269.635162) (xy 370.246214 -269.598438) (xy 370.21569 -269.556423)
			(xy 370.192115 -269.51015) (xy 370.176069 -269.460759) (xy 370.167945 -269.409466) (xy 370.167945 -269.357534)
			(xy 370.176069 -269.306241) (xy 370.192115 -269.25685) (xy 370.21569 -269.210577) (xy 370.246214 -269.168562)
			(xy 370.282933 -269.131838) (xy 370.324945 -269.10131) (xy 370.371215 -269.07773) (xy 370.420604 -269.061677)
			(xy 370.471896 -269.053548) (xy 370.497862 -269.053056) (xy 370.52554 -269.053616) (xy 370.580123 -269.062839)
			(xy 370.632403 -269.081034) (xy 370.680918 -269.107691) (xy 370.724309 -269.142064) (xy 370.743226 -269.162276)
			(xy 370.75267 -269.172098) (xy 370.77561 -269.186781) (xy 370.801615 -269.194879) (xy 370.828836 -269.195814)
			(xy 370.855335 -269.18952) (xy 370.879229 -269.176446) (xy 370.898816 -269.15752) (xy 370.912704 -269.13409)
			(xy 370.919905 -269.107822) (xy 370.920264 -269.094204) (xy 370.920264 -268.899132) (xy 370.882672 -268.888972)
			(xy 370.858173 -268.881952) (xy 370.811531 -268.861418) (xy 370.768595 -268.833966) (xy 370.730383 -268.800248)
			(xy 370.6978 -268.761062) (xy 370.671621 -268.717339) (xy 370.652465 -268.670115) (xy 370.640787 -268.620509)
			(xy 370.636863 -268.569698) (xy 370.640787 -268.518888) (xy 370.652466 -268.469282) (xy 370.671622 -268.422058)
			(xy 370.697802 -268.378335) (xy 370.730385 -268.33915) (xy 370.768597 -268.305432) (xy 370.811534 -268.277981)
			(xy 370.858176 -268.257447) (xy 370.882672 -268.250416) (xy 370.920264 -268.240256) (xy 370.920264 -267.270992)
			(xy 370.882672 -267.261086) (xy 370.858183 -267.254054) (xy 370.811563 -267.233502) (xy 370.768649 -267.206038)
			(xy 370.730459 -267.172314) (xy 370.697897 -267.133129) (xy 370.671734 -267.08941) (xy 370.65259 -267.042194)
			(xy 370.640919 -266.9926) (xy 370.636998 -266.941802) (xy 370.640919 -266.891004) (xy 370.652589 -266.84141)
			(xy 370.671732 -266.794194) (xy 370.697894 -266.750475) (xy 370.730456 -266.711289) (xy 370.768646 -266.677564)
			(xy 370.811559 -266.6501) (xy 370.858179 -266.629547) (xy 370.882672 -266.62253) (xy 370.920264 -266.612624)
			(xy 370.920264 -266.417552) (xy 370.919824 -266.403948) (xy 370.912622 -266.377711) (xy 370.898742 -266.354309)
			(xy 370.879172 -266.335408) (xy 370.855303 -266.322349) (xy 370.828831 -266.316063) (xy 370.801639 -266.316995)
			(xy 370.77566 -266.32508) (xy 370.752741 -266.339742) (xy 370.743226 -266.34948) (xy 370.724285 -266.369667)
			(xy 370.6809 -266.40404) (xy 370.632391 -266.430698) (xy 370.580115 -266.448894) (xy 370.525538 -266.458118)
			(xy 370.497862 -266.4587) (xy 370.471893 -266.458188) (xy 370.420596 -266.450058) (xy 370.371201 -266.434003)
			(xy 370.324926 -266.41042) (xy 370.28291 -266.379889) (xy 370.246186 -266.343161) (xy 370.21566 -266.301141)
			(xy 370.192082 -266.254864) (xy 370.176034 -266.205467) (xy 370.167909 -266.154169) (xy 370.167909 -266.102231)
			(xy 370.176034 -266.050933) (xy 370.192082 -266.001536) (xy 370.21566 -265.955259) (xy 370.246186 -265.913239)
			(xy 370.28291 -265.876511) (xy 370.324926 -265.84598) (xy 370.371201 -265.822397) (xy 370.420596 -265.806342)
			(xy 370.471893 -265.798212) (xy 370.497862 -265.797792) (xy 370.52554 -265.798352) (xy 370.580121 -265.807576)
			(xy 370.632401 -265.825772) (xy 370.680914 -265.852432) (xy 370.724302 -265.886807) (xy 370.743226 -265.907012)
			(xy 370.752672 -265.916831) (xy 370.775614 -265.93151) (xy 370.80162 -265.939604) (xy 370.82884 -265.940537)
			(xy 370.85534 -265.934244) (xy 370.879234 -265.921172) (xy 370.898824 -265.90225) (xy 370.912717 -265.878823)
			(xy 370.919925 -265.852558) (xy 370.920264 -265.83894) (xy 370.920264 -265.64336) (xy 370.882672 -265.633454)
			(xy 370.858185 -265.626422) (xy 370.81157 -265.605871) (xy 370.768661 -265.578408) (xy 370.730476 -265.544687)
			(xy 370.697917 -265.505504) (xy 370.671758 -265.461789) (xy 370.652617 -265.414577) (xy 370.640949 -265.364987)
			(xy 370.637029 -265.314194) (xy 370.64095 -265.263401) (xy 370.652621 -265.213811) (xy 370.671763 -265.1666)
			(xy 370.697924 -265.122886) (xy 370.730484 -265.083704) (xy 370.768671 -265.049984) (xy 370.811581 -265.022524)
			(xy 370.858197 -265.001974) (xy 370.882672 -264.994898) (xy 370.920264 -264.984992) (xy 370.920264 -264.789666)
			(xy 370.919826 -264.776061) (xy 370.912626 -264.74982) (xy 370.898747 -264.726415) (xy 370.879176 -264.70751)
			(xy 370.855304 -264.69445) (xy 370.82883 -264.688163) (xy 370.801635 -264.689095) (xy 370.775654 -264.697182)
			(xy 370.752734 -264.711848) (xy 370.743226 -264.721594) (xy 370.724285 -264.74178) (xy 370.680899 -264.776152)
			(xy 370.63239 -264.802809) (xy 370.580115 -264.821004) (xy 370.525538 -264.830227) (xy 370.497862 -264.830814)
			(xy 370.4719 -264.830302) (xy 370.420616 -264.822174) (xy 370.371234 -264.806124) (xy 370.324971 -264.782547)
			(xy 370.282965 -264.752024) (xy 370.246252 -264.715306) (xy 370.215733 -264.673296) (xy 370.192162 -264.627031)
			(xy 370.176117 -264.577647) (xy 370.167995 -264.526362) (xy 370.167995 -264.474438) (xy 370.176117 -264.423153)
			(xy 370.192162 -264.373769) (xy 370.215733 -264.327504) (xy 370.246252 -264.285494) (xy 370.282965 -264.248776)
			(xy 370.324971 -264.218253) (xy 370.371234 -264.194676) (xy 370.420616 -264.178626) (xy 370.4719 -264.170498)
			(xy 370.497862 -264.169906) (xy 370.52554 -264.170466) (xy 370.580121 -264.17969) (xy 370.6324 -264.197887)
			(xy 370.680912 -264.224547) (xy 370.724299 -264.258924) (xy 370.743226 -264.279126) (xy 370.752667 -264.288951)
			(xy 370.775603 -264.303641) (xy 370.801608 -264.311743) (xy 370.828829 -264.31268) (xy 370.855329 -264.306386)
			(xy 370.879222 -264.293309) (xy 370.898806 -264.274379) (xy 370.912687 -264.250944) (xy 370.919878 -264.224673)
			(xy 370.920264 -264.211054) (xy 370.920264 -264.015982) (xy 370.882672 -264.005822) (xy 370.858169 -263.998802)
			(xy 370.811519 -263.978267) (xy 370.768576 -263.950813) (xy 370.730357 -263.917091) (xy 370.697768 -263.877901)
			(xy 370.671583 -263.834172) (xy 370.652423 -263.786942) (xy 370.640741 -263.737329) (xy 370.636815 -263.686511)
			(xy 370.640737 -263.635693) (xy 370.652416 -263.58608) (xy 370.671573 -263.538848) (xy 370.697755 -263.495118)
			(xy 370.730341 -263.455926) (xy 370.768558 -263.422201) (xy 370.811499 -263.394744) (xy 370.858147 -263.374206)
			(xy 370.882672 -263.367266) (xy 370.920264 -263.357106) (xy 370.920264 -263.162034) (xy 370.919834 -263.148422)
			(xy 370.912645 -263.122165) (xy 370.898769 -263.098743) (xy 370.879193 -263.079823) (xy 370.855313 -263.066753)
			(xy 370.828826 -263.060462) (xy 370.801618 -263.061398) (xy 370.775626 -263.069495) (xy 370.7527 -263.084176)
			(xy 370.743226 -263.093962) (xy 370.724291 -263.114104) (xy 370.680935 -263.148398) (xy 370.632475 -263.174994)
			(xy 370.580262 -263.193149) (xy 370.525755 -263.202357) (xy 370.498116 -263.202928) (xy 370.472148 -263.202446)
			(xy 370.420851 -263.194324) (xy 370.371456 -263.178277) (xy 370.32518 -263.1547) (xy 370.283162 -263.124174)
			(xy 370.246437 -263.08745) (xy 370.215908 -263.045434) (xy 370.192329 -262.999159) (xy 370.17628 -262.949765)
			(xy 370.168155 -262.898468) (xy 370.168155 -262.846532) (xy 370.17628 -262.795235) (xy 370.192329 -262.745841)
			(xy 370.215908 -262.699566) (xy 370.246437 -262.65755) (xy 370.283162 -262.620826) (xy 370.32518 -262.5903)
			(xy 370.371456 -262.566723) (xy 370.420851 -262.550676) (xy 370.472148 -262.542554) (xy 370.498116 -262.54202)
			(xy 370.525755 -262.542582) (xy 370.58026 -262.551793) (xy 370.632469 -262.569954) (xy 370.680923 -262.596559)
			(xy 370.724269 -262.630864) (xy 370.743226 -262.650986) (xy 370.75267 -262.660807) (xy 370.775611 -262.675489)
			(xy 370.801616 -262.683586) (xy 370.828837 -262.68452) (xy 370.855337 -262.678227) (xy 370.87923 -262.665153)
			(xy 370.898818 -262.646228) (xy 370.912708 -262.622799) (xy 370.919911 -262.596532) (xy 370.920264 -262.582914)
			(xy 370.920264 -262.388096) (xy 370.882672 -262.377936) (xy 370.858175 -262.370916) (xy 370.811539 -262.350383)
			(xy 370.768608 -262.322933) (xy 370.730401 -262.289217) (xy 370.697823 -262.250035) (xy 370.671648 -262.206315)
			(xy 370.652495 -262.159095) (xy 370.64082 -262.109494) (xy 370.636898 -262.058689) (xy 370.640823 -262.007884)
			(xy 370.652502 -261.958284) (xy 370.671658 -261.911065) (xy 370.697836 -261.867348) (xy 370.730416 -261.828167)
			(xy 370.768626 -261.794454) (xy 370.811558 -261.767007) (xy 370.858196 -261.746477) (xy 370.882672 -261.73938)
			(xy 370.920264 -261.72922) (xy 370.920264 -261.534148) (xy 370.919824 -261.520545) (xy 370.912621 -261.494308)
			(xy 370.898741 -261.470908) (xy 370.879171 -261.452007) (xy 370.855302 -261.438949) (xy 370.828831 -261.432663)
			(xy 370.80164 -261.433595) (xy 370.775662 -261.441679) (xy 370.752743 -261.45634) (xy 370.743226 -261.466076)
			(xy 370.724285 -261.486263) (xy 370.6809 -261.520637) (xy 370.632391 -261.547295) (xy 370.580116 -261.565491)
			(xy 370.525538 -261.574715) (xy 370.497862 -261.575296) (xy 370.471893 -261.574784) (xy 370.420596 -261.566654)
			(xy 370.371203 -261.5506) (xy 370.324928 -261.527017) (xy 370.282912 -261.496486) (xy 370.246189 -261.459759)
			(xy 370.215663 -261.417739) (xy 370.192086 -261.371462) (xy 370.176037 -261.322067) (xy 370.167913 -261.270769)
			(xy 370.167913 -261.218831) (xy 370.176037 -261.167534) (xy 370.192086 -261.118138) (xy 370.215663 -261.071861)
			(xy 370.246189 -261.029841) (xy 370.282912 -260.993114) (xy 370.324928 -260.962583) (xy 370.371203 -260.939)
			(xy 370.420596 -260.922946) (xy 370.471893 -260.914816) (xy 370.497862 -260.914388) (xy 370.52257 -260.914846)
			(xy 370.571437 -260.9222) (xy 370.618663 -260.93675) (xy 370.663196 -260.958172) (xy 370.704041 -260.985987)
			(xy 370.740288 -261.019575) (xy 370.771129 -261.058187) (xy 370.795875 -261.100962) (xy 370.813974 -261.146945)
			(xy 370.819934 -261.170928) (xy 370.829078 -261.210552) (xy 370.920264 -261.210552) (xy 370.920264 -260.951726)
			(xy 370.497354 -260.528816) (xy 370.486983 -260.519109) (xy 370.462155 -260.505328) (xy 370.434496 -260.498902)
			(xy 370.406137 -260.500327) (xy 370.379261 -260.509492) (xy 370.35594 -260.525692) (xy 370.33797 -260.547679)
			(xy 370.332 -260.560566) (xy 370.32214 -260.582575) (xy 370.296975 -260.623715) (xy 370.266092 -260.660756)
			(xy 370.230149 -260.692909) (xy 370.18991 -260.71949) (xy 370.146232 -260.739935) (xy 370.100044 -260.753807)
			(xy 370.052329 -260.760811) (xy 370.028216 -260.761226) (xy 370.002247 -260.760744) (xy 369.950947 -260.752621)
			(xy 369.90155 -260.736572) (xy 369.855273 -260.712993) (xy 369.813254 -260.682464) (xy 369.776528 -260.645737)
			(xy 369.746001 -260.603717) (xy 369.722423 -260.557439) (xy 369.706376 -260.508041) (xy 369.698255 -260.456741)
			(xy 369.697762 -260.430772) (xy 369.698129 -260.408723) (xy 369.703994 -260.365017) (xy 369.709446 -260.34365)
			(xy 369.712606 -260.330645) (xy 369.712757 -260.303891) (xy 369.705949 -260.278016) (xy 369.692651 -260.2548)
			(xy 369.673776 -260.235838) (xy 369.650622 -260.222432) (xy 369.62478 -260.215504) (xy 369.611402 -260.215126)
			(xy 367.679224 -260.215126) (xy 366.623541 -261.270809) (xy 369.228117 -261.270809) (xy 369.228117 -261.218875)
			(xy 369.236242 -261.16758) (xy 369.25229 -261.118187) (xy 369.275868 -261.071913) (xy 369.306394 -261.029897)
			(xy 369.343117 -260.993174) (xy 369.385133 -260.962648) (xy 369.431407 -260.93907) (xy 369.4808 -260.923022)
			(xy 369.532095 -260.914897) (xy 369.584029 -260.914897) (xy 369.635324 -260.923022) (xy 369.684717 -260.93907)
			(xy 369.730991 -260.962648) (xy 369.773007 -260.993174) (xy 369.80973 -261.029897) (xy 369.840256 -261.071913)
			(xy 369.863834 -261.118187) (xy 369.879882 -261.16758) (xy 369.888007 -261.218875) (xy 369.888516 -261.244842)
			(xy 369.888007 -261.270809) (xy 369.879882 -261.322104) (xy 369.863834 -261.371497) (xy 369.840256 -261.417771)
			(xy 369.80973 -261.459787) (xy 369.773007 -261.49651) (xy 369.730991 -261.527036) (xy 369.684717 -261.550614)
			(xy 369.635324 -261.566662) (xy 369.584029 -261.574787) (xy 369.532095 -261.574787) (xy 369.4808 -261.566662)
			(xy 369.431407 -261.550614) (xy 369.385133 -261.527036) (xy 369.343117 -261.49651) (xy 369.306394 -261.459787)
			(xy 369.275868 -261.417771) (xy 369.25229 -261.371497) (xy 369.236242 -261.322104) (xy 369.228117 -261.270809)
			(xy 366.623541 -261.270809) (xy 366.553242 -261.341108) (xy 366.551464 -261.359396) (xy 366.54846 -261.386047)
			(xy 366.534943 -261.437946) (xy 366.513235 -261.486986) (xy 366.483904 -261.531885) (xy 366.447719 -261.571468)
			(xy 366.427004 -261.588504) (xy 366.427004 -262.084625) (xy 369.698271 -262.084625) (xy 369.698271 -262.032691)
			(xy 369.706396 -261.981396) (xy 369.722444 -261.932003) (xy 369.746022 -261.885729) (xy 369.776548 -261.843713)
			(xy 369.813271 -261.80699) (xy 369.855287 -261.776464) (xy 369.901561 -261.752886) (xy 369.950954 -261.736838)
			(xy 370.002249 -261.728713) (xy 370.054183 -261.728713) (xy 370.105478 -261.736838) (xy 370.154871 -261.752886)
			(xy 370.201145 -261.776464) (xy 370.243161 -261.80699) (xy 370.279884 -261.843713) (xy 370.31041 -261.885729)
			(xy 370.333988 -261.932003) (xy 370.350036 -261.981396) (xy 370.358161 -262.032691) (xy 370.35867 -262.058658)
			(xy 370.358161 -262.084625) (xy 370.350036 -262.13592) (xy 370.333988 -262.185313) (xy 370.31041 -262.231587)
			(xy 370.279884 -262.273603) (xy 370.243161 -262.310326) (xy 370.201145 -262.340852) (xy 370.154871 -262.36443)
			(xy 370.105478 -262.380478) (xy 370.054183 -262.388603) (xy 370.002249 -262.388603) (xy 369.950954 -262.380478)
			(xy 369.901561 -262.36443) (xy 369.855287 -262.340852) (xy 369.813271 -262.310326) (xy 369.776548 -262.273603)
			(xy 369.746022 -262.231587) (xy 369.722444 -262.185313) (xy 369.706396 -262.13592) (xy 369.698271 -262.084625)
			(xy 366.427004 -262.084625) (xy 366.427004 -262.964422) (xy 366.427435 -262.978077) (xy 366.434662 -263.004412)
			(xy 366.44862 -263.027885) (xy 366.468306 -263.046811) (xy 366.492309 -263.059835) (xy 366.518909 -263.066021)
			(xy 366.546196 -263.064926) (xy 366.559338 -263.061196) (xy 366.583717 -263.053938) (xy 366.633982 -263.046154)
			(xy 366.659414 -263.045702) (xy 366.685384 -263.046212) (xy 366.736684 -263.05434) (xy 366.786081 -263.070392)
			(xy 366.832359 -263.093973) (xy 366.874379 -263.124504) (xy 366.911105 -263.161232) (xy 366.941634 -263.203252)
			(xy 366.965214 -263.249532) (xy 366.981264 -263.29893) (xy 366.981998 -263.303567) (xy 367.315759 -263.303567)
			(xy 367.315759 -263.251633) (xy 367.323883 -263.200339) (xy 367.339932 -263.150948) (xy 367.363509 -263.104675)
			(xy 367.394034 -263.062659) (xy 367.430756 -263.025937) (xy 367.472771 -262.995411) (xy 367.519044 -262.971833)
			(xy 367.568435 -262.955784) (xy 367.619729 -262.94766) (xy 367.645696 -262.94715) (xy 367.672209 -262.947689)
			(xy 367.724554 -262.956172) (xy 367.774866 -262.97292) (xy 367.798604 -262.984742) (xy 367.812288 -262.99133)
			(xy 367.842135 -262.996881) (xy 367.872296 -262.993424) (xy 367.900112 -262.981263) (xy 367.923131 -262.96147)
			(xy 367.9317 -262.948928) (xy 367.946989 -262.92579) (xy 367.984057 -262.884544) (xy 368.027492 -262.850066)
			(xy 368.076075 -262.823326) (xy 368.12844 -262.805073) (xy 368.183118 -262.795821) (xy 368.210846 -262.795258)
			(xy 368.236812 -262.795747) (xy 368.288103 -262.803877) (xy 368.337491 -262.81993) (xy 368.383761 -262.843511)
			(xy 368.425772 -262.87404) (xy 368.45017 -262.898441) (xy 369.228117 -262.898441) (xy 369.228117 -262.846507)
			(xy 369.236242 -262.795212) (xy 369.25229 -262.745819) (xy 369.275868 -262.699545) (xy 369.306394 -262.657529)
			(xy 369.343117 -262.620806) (xy 369.385133 -262.59028) (xy 369.431407 -262.566702) (xy 369.4808 -262.550654)
			(xy 369.532095 -262.542529) (xy 369.584029 -262.542529) (xy 369.635324 -262.550654) (xy 369.684717 -262.566702)
			(xy 369.730991 -262.59028) (xy 369.773007 -262.620806) (xy 369.80973 -262.657529) (xy 369.840256 -262.699545)
			(xy 369.863834 -262.745819) (xy 369.879882 -262.795212) (xy 369.888007 -262.846507) (xy 369.888516 -262.872474)
			(xy 369.888007 -262.898441) (xy 369.879882 -262.949736) (xy 369.863834 -262.999129) (xy 369.840256 -263.045403)
			(xy 369.80973 -263.087419) (xy 369.773007 -263.124142) (xy 369.730991 -263.154668) (xy 369.684717 -263.178246)
			(xy 369.635324 -263.194294) (xy 369.584029 -263.202419) (xy 369.532095 -263.202419) (xy 369.4808 -263.194294)
			(xy 369.431407 -263.178246) (xy 369.385133 -263.154668) (xy 369.343117 -263.124142) (xy 369.306394 -263.087419)
			(xy 369.275868 -263.045403) (xy 369.25229 -262.999129) (xy 369.236242 -262.949736) (xy 369.228117 -262.898441)
			(xy 368.45017 -262.898441) (xy 368.46249 -262.910763) (xy 368.493013 -262.952779) (xy 368.516587 -262.999051)
			(xy 368.532634 -263.048442) (xy 368.540757 -263.099734) (xy 368.540757 -263.151666) (xy 368.532634 -263.202958)
			(xy 368.516587 -263.252349) (xy 368.493013 -263.298621) (xy 368.46249 -263.340637) (xy 368.425772 -263.37736)
			(xy 368.383761 -263.407889) (xy 368.337491 -263.43147) (xy 368.288103 -263.447523) (xy 368.236812 -263.455653)
			(xy 368.210846 -263.456166) (xy 368.184331 -263.455659) (xy 368.131986 -263.447164) (xy 368.081674 -263.430403)
			(xy 368.057938 -263.418574) (xy 368.044236 -263.412025) (xy 368.014398 -263.406464) (xy 367.984242 -263.409912)
			(xy 367.956428 -263.422064) (xy 367.933411 -263.44185) (xy 367.924842 -263.454388) (xy 367.909498 -263.477488)
			(xy 367.872444 -263.51874) (xy 367.829021 -263.553224) (xy 367.780449 -263.579972) (xy 367.728092 -263.598232)
			(xy 367.673421 -263.607492) (xy 367.645696 -263.608058) (xy 367.619729 -263.60754) (xy 367.568435 -263.599416)
			(xy 367.519044 -263.583367) (xy 367.472771 -263.559789) (xy 367.430756 -263.529263) (xy 367.394034 -263.492541)
			(xy 367.363509 -263.450525) (xy 367.339932 -263.404252) (xy 367.323883 -263.354861) (xy 367.315759 -263.303567)
			(xy 366.981998 -263.303567) (xy 366.989389 -263.35023) (xy 366.989389 -263.40217) (xy 366.981264 -263.45347)
			(xy 366.965214 -263.502868) (xy 366.941634 -263.549148) (xy 366.911105 -263.591168) (xy 366.874379 -263.627896)
			(xy 366.83236 -263.658427) (xy 366.786081 -263.682008) (xy 366.736684 -263.69806) (xy 366.685384 -263.706188)
			(xy 366.659414 -263.70661) (xy 366.633983 -263.70614) (xy 366.583721 -263.698356) (xy 366.559338 -263.691116)
			(xy 366.546194 -263.687406) (xy 366.518915 -263.686339) (xy 366.492328 -263.692538) (xy 366.468333 -263.705558)
			(xy 366.461095 -263.712511) (xy 369.698271 -263.712511) (xy 369.698271 -263.660577) (xy 369.706396 -263.609282)
			(xy 369.722444 -263.559889) (xy 369.746022 -263.513615) (xy 369.776548 -263.471599) (xy 369.813271 -263.434876)
			(xy 369.855287 -263.40435) (xy 369.901561 -263.380772) (xy 369.950954 -263.364724) (xy 370.002249 -263.356599)
			(xy 370.054183 -263.356599) (xy 370.105478 -263.364724) (xy 370.154871 -263.380772) (xy 370.201145 -263.40435)
			(xy 370.243161 -263.434876) (xy 370.279884 -263.471599) (xy 370.31041 -263.513615) (xy 370.333988 -263.559889)
			(xy 370.350036 -263.609282) (xy 370.358161 -263.660577) (xy 370.35867 -263.686544) (xy 370.358161 -263.712511)
			(xy 370.350036 -263.763806) (xy 370.333988 -263.813199) (xy 370.31041 -263.859473) (xy 370.279884 -263.901489)
			(xy 370.243161 -263.938212) (xy 370.201145 -263.968738) (xy 370.154871 -263.992316) (xy 370.105478 -264.008364)
			(xy 370.054183 -264.016489) (xy 370.002249 -264.016489) (xy 369.950954 -264.008364) (xy 369.901561 -263.992316)
			(xy 369.855287 -263.968738) (xy 369.813271 -263.938212) (xy 369.776548 -263.901489) (xy 369.746022 -263.859473)
			(xy 369.722444 -263.813199) (xy 369.706396 -263.763806) (xy 369.698271 -263.712511) (xy 366.461095 -263.712511)
			(xy 366.448645 -263.724471) (xy 366.434671 -263.747924) (xy 366.42741 -263.77424) (xy 366.427004 -263.78789)
			(xy 366.427004 -264.122916) (xy 366.427595 -264.137992) (xy 366.436488 -264.166805) (xy 366.453403 -264.191768)
			(xy 366.476869 -264.210706) (xy 366.504841 -264.22197) (xy 366.534883 -264.224577) (xy 366.564377 -264.218302)
			(xy 366.57788 -264.211562) (xy 366.602639 -264.198479) (xy 366.655467 -264.179913) (xy 366.710665 -264.170501)
			(xy 366.738662 -264.169906) (xy 366.764636 -264.170386) (xy 366.815946 -264.178507) (xy 366.865354 -264.194556)
			(xy 366.911642 -264.218136) (xy 366.953672 -264.248668) (xy 366.990407 -264.285399) (xy 367.020944 -264.327425)
			(xy 367.04453 -264.373711) (xy 367.060584 -264.423117) (xy 367.068711 -264.474426) (xy 367.068711 -264.526327)
			(xy 367.348517 -264.526327) (xy 367.348517 -264.474393) (xy 367.356642 -264.423098) (xy 367.37269 -264.373705)
			(xy 367.396268 -264.327431) (xy 367.426794 -264.285415) (xy 367.463517 -264.248692) (xy 367.505533 -264.218166)
			(xy 367.551807 -264.194588) (xy 367.6012 -264.17854) (xy 367.652495 -264.170415) (xy 367.704429 -264.170415)
			(xy 367.755724 -264.17854) (xy 367.805117 -264.194588) (xy 367.851391 -264.218166) (xy 367.893407 -264.248692)
			(xy 367.93013 -264.285415) (xy 367.960656 -264.327431) (xy 367.984234 -264.373705) (xy 368.000282 -264.423098)
			(xy 368.008407 -264.474393) (xy 368.008916 -264.50036) (xy 368.008407 -264.526327) (xy 368.288317 -264.526327)
			(xy 368.288317 -264.474393) (xy 368.296442 -264.423098) (xy 368.31249 -264.373705) (xy 368.336068 -264.327431)
			(xy 368.366594 -264.285415) (xy 368.403317 -264.248692) (xy 368.445333 -264.218166) (xy 368.491607 -264.194588)
			(xy 368.541 -264.17854) (xy 368.592295 -264.170415) (xy 368.644229 -264.170415) (xy 368.695524 -264.17854)
			(xy 368.744917 -264.194588) (xy 368.791191 -264.218166) (xy 368.833207 -264.248692) (xy 368.86993 -264.285415)
			(xy 368.900456 -264.327431) (xy 368.924034 -264.373705) (xy 368.940082 -264.423098) (xy 368.948207 -264.474393)
			(xy 368.948716 -264.50036) (xy 368.948207 -264.526327) (xy 369.228117 -264.526327) (xy 369.228117 -264.474393)
			(xy 369.236242 -264.423098) (xy 369.25229 -264.373705) (xy 369.275868 -264.327431) (xy 369.306394 -264.285415)
			(xy 369.343117 -264.248692) (xy 369.385133 -264.218166) (xy 369.431407 -264.194588) (xy 369.4808 -264.17854)
			(xy 369.532095 -264.170415) (xy 369.584029 -264.170415) (xy 369.635324 -264.17854) (xy 369.684717 -264.194588)
			(xy 369.730991 -264.218166) (xy 369.773007 -264.248692) (xy 369.80973 -264.285415) (xy 369.840256 -264.327431)
			(xy 369.863834 -264.373705) (xy 369.879882 -264.423098) (xy 369.888007 -264.474393) (xy 369.888516 -264.50036)
			(xy 369.888007 -264.526327) (xy 369.879882 -264.577622) (xy 369.863834 -264.627015) (xy 369.840256 -264.673289)
			(xy 369.80973 -264.715305) (xy 369.773007 -264.752028) (xy 369.730991 -264.782554) (xy 369.684717 -264.806132)
			(xy 369.635324 -264.82218) (xy 369.584029 -264.830305) (xy 369.532095 -264.830305) (xy 369.4808 -264.82218)
			(xy 369.431407 -264.806132) (xy 369.385133 -264.782554) (xy 369.343117 -264.752028) (xy 369.306394 -264.715305)
			(xy 369.275868 -264.673289) (xy 369.25229 -264.627015) (xy 369.236242 -264.577622) (xy 369.228117 -264.526327)
			(xy 368.948207 -264.526327) (xy 368.940082 -264.577622) (xy 368.924034 -264.627015) (xy 368.900456 -264.673289)
			(xy 368.86993 -264.715305) (xy 368.833207 -264.752028) (xy 368.791191 -264.782554) (xy 368.744917 -264.806132)
			(xy 368.695524 -264.82218) (xy 368.644229 -264.830305) (xy 368.592295 -264.830305) (xy 368.541 -264.82218)
			(xy 368.491607 -264.806132) (xy 368.445333 -264.782554) (xy 368.403317 -264.752028) (xy 368.366594 -264.715305)
			(xy 368.336068 -264.673289) (xy 368.31249 -264.627015) (xy 368.296442 -264.577622) (xy 368.288317 -264.526327)
			(xy 368.008407 -264.526327) (xy 368.000282 -264.577622) (xy 367.984234 -264.627015) (xy 367.960656 -264.673289)
			(xy 367.93013 -264.715305) (xy 367.893407 -264.752028) (xy 367.851391 -264.782554) (xy 367.805117 -264.806132)
			(xy 367.755724 -264.82218) (xy 367.704429 -264.830305) (xy 367.652495 -264.830305) (xy 367.6012 -264.82218)
			(xy 367.551807 -264.806132) (xy 367.505533 -264.782554) (xy 367.463517 -264.752028) (xy 367.426794 -264.715305)
			(xy 367.396268 -264.673289) (xy 367.37269 -264.627015) (xy 367.356642 -264.577622) (xy 367.348517 -264.526327)
			(xy 367.068711 -264.526327) (xy 367.068711 -264.526374) (xy 367.060584 -264.577683) (xy 367.04453 -264.627089)
			(xy 367.020944 -264.673375) (xy 366.990407 -264.715401) (xy 366.953672 -264.752132) (xy 366.911642 -264.782664)
			(xy 366.865354 -264.806244) (xy 366.815946 -264.822293) (xy 366.764636 -264.830414) (xy 366.738662 -264.830814)
			(xy 366.710661 -264.830252) (xy 366.655454 -264.820855) (xy 366.602627 -264.80227) (xy 366.57788 -264.789158)
			(xy 366.564419 -264.782316) (xy 366.534903 -264.776026) (xy 366.504836 -264.778634) (xy 366.476843 -264.789911)
			(xy 366.453366 -264.808875) (xy 366.436454 -264.83387) (xy 366.427581 -264.862715) (xy 366.427004 -264.877804)
			(xy 366.427004 -265.024108) (xy 366.448986 -265.036646) (xy 366.489199 -265.067365) (xy 366.524257 -265.103856)
			(xy 366.553342 -265.145265) (xy 366.575773 -265.190625) (xy 366.591026 -265.238875) (xy 366.598743 -265.288887)
			(xy 366.598745 -265.33949) (xy 366.598644 -265.340143) (xy 366.878871 -265.340143) (xy 366.878871 -265.288209)
			(xy 366.886996 -265.236914) (xy 366.903044 -265.187521) (xy 366.926622 -265.141247) (xy 366.957148 -265.099231)
			(xy 366.993871 -265.062508) (xy 367.035887 -265.031982) (xy 367.082161 -265.008404) (xy 367.131554 -264.992356)
			(xy 367.182849 -264.984231) (xy 367.234783 -264.984231) (xy 367.286078 -264.992356) (xy 367.335471 -265.008404)
			(xy 367.381745 -265.031982) (xy 367.423761 -265.062508) (xy 367.460484 -265.099231) (xy 367.49101 -265.141247)
			(xy 367.514588 -265.187521) (xy 367.530636 -265.236914) (xy 367.538761 -265.288209) (xy 367.53927 -265.314176)
			(xy 367.538761 -265.340143) (xy 367.818671 -265.340143) (xy 367.818671 -265.288209) (xy 367.826796 -265.236914)
			(xy 367.842844 -265.187521) (xy 367.866422 -265.141247) (xy 367.896948 -265.099231) (xy 367.933671 -265.062508)
			(xy 367.975687 -265.031982) (xy 368.021961 -265.008404) (xy 368.071354 -264.992356) (xy 368.122649 -264.984231)
			(xy 368.174583 -264.984231) (xy 368.225878 -264.992356) (xy 368.275271 -265.008404) (xy 368.321545 -265.031982)
			(xy 368.363561 -265.062508) (xy 368.400284 -265.099231) (xy 368.43081 -265.141247) (xy 368.454388 -265.187521)
			(xy 368.470436 -265.236914) (xy 368.478561 -265.288209) (xy 368.47907 -265.314176) (xy 368.478561 -265.340143)
			(xy 369.698271 -265.340143) (xy 369.698271 -265.288209) (xy 369.706396 -265.236914) (xy 369.722444 -265.187521)
			(xy 369.746022 -265.141247) (xy 369.776548 -265.099231) (xy 369.813271 -265.062508) (xy 369.855287 -265.031982)
			(xy 369.901561 -265.008404) (xy 369.950954 -264.992356) (xy 370.002249 -264.984231) (xy 370.054183 -264.984231)
			(xy 370.105478 -264.992356) (xy 370.154871 -265.008404) (xy 370.201145 -265.031982) (xy 370.243161 -265.062508)
			(xy 370.279884 -265.099231) (xy 370.31041 -265.141247) (xy 370.333988 -265.187521) (xy 370.350036 -265.236914)
			(xy 370.358161 -265.288209) (xy 370.35867 -265.314176) (xy 370.358161 -265.340143) (xy 370.350036 -265.391438)
			(xy 370.333988 -265.440831) (xy 370.31041 -265.487105) (xy 370.279884 -265.529121) (xy 370.243161 -265.565844)
			(xy 370.201145 -265.59637) (xy 370.154871 -265.619948) (xy 370.105478 -265.635996) (xy 370.054183 -265.644121)
			(xy 370.002249 -265.644121) (xy 369.950954 -265.635996) (xy 369.901561 -265.619948) (xy 369.855287 -265.59637)
			(xy 369.813271 -265.565844) (xy 369.776548 -265.529121) (xy 369.746022 -265.487105) (xy 369.722444 -265.440831)
			(xy 369.706396 -265.391438) (xy 369.698271 -265.340143) (xy 368.478561 -265.340143) (xy 368.470436 -265.391438)
			(xy 368.454388 -265.440831) (xy 368.43081 -265.487105) (xy 368.400284 -265.529121) (xy 368.363561 -265.565844)
			(xy 368.321545 -265.59637) (xy 368.275271 -265.619948) (xy 368.225878 -265.635996) (xy 368.174583 -265.644121)
			(xy 368.122649 -265.644121) (xy 368.071354 -265.635996) (xy 368.021961 -265.619948) (xy 367.975687 -265.59637)
			(xy 367.933671 -265.565844) (xy 367.896948 -265.529121) (xy 367.866422 -265.487105) (xy 367.842844 -265.440831)
			(xy 367.826796 -265.391438) (xy 367.818671 -265.340143) (xy 367.538761 -265.340143) (xy 367.530636 -265.391438)
			(xy 367.514588 -265.440831) (xy 367.49101 -265.487105) (xy 367.460484 -265.529121) (xy 367.423761 -265.565844)
			(xy 367.381745 -265.59637) (xy 367.335471 -265.619948) (xy 367.286078 -265.635996) (xy 367.234783 -265.644121)
			(xy 367.182849 -265.644121) (xy 367.131554 -265.635996) (xy 367.082161 -265.619948) (xy 367.035887 -265.59637)
			(xy 366.993871 -265.565844) (xy 366.957148 -265.529121) (xy 366.926622 -265.487105) (xy 366.903044 -265.440831)
			(xy 366.886996 -265.391438) (xy 366.878871 -265.340143) (xy 366.598644 -265.340143) (xy 366.591031 -265.389502)
			(xy 366.575782 -265.437753) (xy 366.553354 -265.483115) (xy 366.524272 -265.524527) (xy 366.489216 -265.56102)
			(xy 366.449005 -265.591742) (xy 366.427004 -265.604244) (xy 366.427004 -265.751056) (xy 366.427588 -265.766138)
			(xy 366.43647 -265.794968) (xy 366.453384 -265.819947) (xy 366.476856 -265.838898) (xy 366.504839 -265.850169)
			(xy 366.534893 -265.852776) (xy 366.564399 -265.846493) (xy 366.57788 -265.839702) (xy 366.60264 -265.826621)
			(xy 366.655467 -265.808058) (xy 366.710665 -265.798648) (xy 366.738662 -265.798046) (xy 366.764633 -265.798526)
			(xy 366.815937 -265.806646) (xy 366.865339 -265.822693) (xy 366.911621 -265.84627) (xy 366.953646 -265.876798)
			(xy 366.990377 -265.913525) (xy 367.02091 -265.955546) (xy 367.044493 -266.001826) (xy 367.060545 -266.051226)
			(xy 367.068671 -266.102529) (xy 367.068671 -266.154213) (xy 367.348517 -266.154213) (xy 367.348517 -266.102279)
			(xy 367.356642 -266.050984) (xy 367.37269 -266.001591) (xy 367.396268 -265.955317) (xy 367.426794 -265.913301)
			(xy 367.463517 -265.876578) (xy 367.505533 -265.846052) (xy 367.551807 -265.822474) (xy 367.6012 -265.806426)
			(xy 367.652495 -265.798301) (xy 367.704429 -265.798301) (xy 367.755724 -265.806426) (xy 367.805117 -265.822474)
			(xy 367.851391 -265.846052) (xy 367.893407 -265.876578) (xy 367.93013 -265.913301) (xy 367.960656 -265.955317)
			(xy 367.984234 -266.001591) (xy 368.000282 -266.050984) (xy 368.008407 -266.102279) (xy 368.008916 -266.128246)
			(xy 368.008407 -266.154213) (xy 368.288317 -266.154213) (xy 368.288317 -266.102279) (xy 368.296442 -266.050984)
			(xy 368.31249 -266.001591) (xy 368.336068 -265.955317) (xy 368.366594 -265.913301) (xy 368.403317 -265.876578)
			(xy 368.445333 -265.846052) (xy 368.491607 -265.822474) (xy 368.541 -265.806426) (xy 368.592295 -265.798301)
			(xy 368.644229 -265.798301) (xy 368.695524 -265.806426) (xy 368.744917 -265.822474) (xy 368.791191 -265.846052)
			(xy 368.833207 -265.876578) (xy 368.86993 -265.913301) (xy 368.900456 -265.955317) (xy 368.924034 -266.001591)
			(xy 368.940082 -266.050984) (xy 368.948207 -266.102279) (xy 368.948716 -266.128246) (xy 368.948207 -266.154213)
			(xy 368.940082 -266.205508) (xy 368.924034 -266.254901) (xy 368.900456 -266.301175) (xy 368.86993 -266.343191)
			(xy 368.833207 -266.379914) (xy 368.791191 -266.41044) (xy 368.744917 -266.434018) (xy 368.695524 -266.450066)
			(xy 368.644229 -266.458191) (xy 368.592295 -266.458191) (xy 368.541 -266.450066) (xy 368.491607 -266.434018)
			(xy 368.445333 -266.41044) (xy 368.403317 -266.379914) (xy 368.366594 -266.343191) (xy 368.336068 -266.301175)
			(xy 368.31249 -266.254901) (xy 368.296442 -266.205508) (xy 368.288317 -266.154213) (xy 368.008407 -266.154213)
			(xy 368.000282 -266.205508) (xy 367.984234 -266.254901) (xy 367.960656 -266.301175) (xy 367.93013 -266.343191)
			(xy 367.893407 -266.379914) (xy 367.851391 -266.41044) (xy 367.805117 -266.434018) (xy 367.755724 -266.450066)
			(xy 367.704429 -266.458191) (xy 367.652495 -266.458191) (xy 367.6012 -266.450066) (xy 367.551807 -266.434018)
			(xy 367.505533 -266.41044) (xy 367.463517 -266.379914) (xy 367.426794 -266.343191) (xy 367.396268 -266.301175)
			(xy 367.37269 -266.254901) (xy 367.356642 -266.205508) (xy 367.348517 -266.154213) (xy 367.068671 -266.154213)
			(xy 367.068671 -266.154471) (xy 367.060545 -266.205774) (xy 367.044493 -266.255174) (xy 367.02091 -266.301454)
			(xy 366.990377 -266.343475) (xy 366.953646 -266.380202) (xy 366.911621 -266.41073) (xy 366.865339 -266.434307)
			(xy 366.815937 -266.450354) (xy 366.764633 -266.458474) (xy 366.738662 -266.458954) (xy 366.710661 -266.458393)
			(xy 366.655453 -266.448997) (xy 366.602625 -266.430414) (xy 366.57788 -266.417298) (xy 366.564421 -266.410455)
			(xy 366.534907 -266.404162) (xy 366.504843 -266.406769) (xy 366.476853 -266.418047) (xy 366.45338 -266.437013)
			(xy 366.436474 -266.46201) (xy 366.427611 -266.490856) (xy 366.427004 -266.505944) (xy 366.427004 -266.65174)
			(xy 366.448957 -266.664299) (xy 366.489109 -266.695047) (xy 366.52411 -266.731551) (xy 366.553145 -266.772959)
			(xy 366.575534 -266.818306) (xy 366.590757 -266.866534) (xy 366.598458 -266.916517) (xy 366.598458 -266.96709)
			(xy 366.598352 -266.967775) (xy 369.698271 -266.967775) (xy 369.698271 -266.915841) (xy 369.706396 -266.864546)
			(xy 369.722444 -266.815153) (xy 369.746022 -266.768879) (xy 369.776548 -266.726863) (xy 369.813271 -266.69014)
			(xy 369.855287 -266.659614) (xy 369.901561 -266.636036) (xy 369.950954 -266.619988) (xy 370.002249 -266.611863)
			(xy 370.054183 -266.611863) (xy 370.105478 -266.619988) (xy 370.154871 -266.636036) (xy 370.201145 -266.659614)
			(xy 370.243161 -266.69014) (xy 370.279884 -266.726863) (xy 370.31041 -266.768879) (xy 370.333988 -266.815153)
			(xy 370.350036 -266.864546) (xy 370.358161 -266.915841) (xy 370.35867 -266.941808) (xy 370.358161 -266.967775)
			(xy 370.350036 -267.01907) (xy 370.333988 -267.068463) (xy 370.31041 -267.114737) (xy 370.279884 -267.156753)
			(xy 370.243161 -267.193476) (xy 370.201145 -267.224002) (xy 370.154871 -267.24758) (xy 370.105478 -267.263628)
			(xy 370.054183 -267.271753) (xy 370.002249 -267.271753) (xy 369.950954 -267.263628) (xy 369.901561 -267.24758)
			(xy 369.855287 -267.224002) (xy 369.813271 -267.193476) (xy 369.776548 -267.156753) (xy 369.746022 -267.114737)
			(xy 369.722444 -267.068463) (xy 369.706396 -267.01907) (xy 369.698271 -266.967775) (xy 366.598352 -266.967775)
			(xy 366.590756 -267.017074) (xy 366.575532 -267.065301) (xy 366.553141 -267.110647) (xy 366.524106 -267.152055)
			(xy 366.489103 -267.188558) (xy 366.44895 -267.219305) (xy 366.427004 -267.231876) (xy 366.427004 -267.781845)
			(xy 367.348517 -267.781845) (xy 367.348517 -267.729911) (xy 367.356642 -267.678616) (xy 367.37269 -267.629223)
			(xy 367.396268 -267.582949) (xy 367.426794 -267.540933) (xy 367.463517 -267.50421) (xy 367.505533 -267.473684)
			(xy 367.551807 -267.450106) (xy 367.6012 -267.434058) (xy 367.652495 -267.425933) (xy 367.704429 -267.425933)
			(xy 367.755724 -267.434058) (xy 367.805117 -267.450106) (xy 367.851391 -267.473684) (xy 367.893407 -267.50421)
			(xy 367.93013 -267.540933) (xy 367.960656 -267.582949) (xy 367.984234 -267.629223) (xy 368.000282 -267.678616)
			(xy 368.008407 -267.729911) (xy 368.008916 -267.755878) (xy 368.008407 -267.781845) (xy 368.000282 -267.83314)
			(xy 367.984234 -267.882533) (xy 367.960656 -267.928807) (xy 367.93013 -267.970823) (xy 367.893407 -268.007546)
			(xy 367.851391 -268.038072) (xy 367.805117 -268.06165) (xy 367.755724 -268.077698) (xy 367.704429 -268.085823)
			(xy 367.652495 -268.085823) (xy 367.6012 -268.077698) (xy 367.551807 -268.06165) (xy 367.505533 -268.038072)
			(xy 367.463517 -268.007546) (xy 367.426794 -267.970823) (xy 367.396268 -267.928807) (xy 367.37269 -267.882533)
			(xy 367.356642 -267.83314) (xy 367.348517 -267.781845) (xy 366.427004 -267.781845) (xy 366.427004 -268.279372)
			(xy 366.449011 -268.291915) (xy 366.489272 -268.322652) (xy 366.524373 -268.35917) (xy 366.553494 -268.400614)
			(xy 366.575953 -268.446016) (xy 366.591224 -268.494311) (xy 366.59895 -268.544371) (xy 366.598951 -268.595023)
			(xy 366.591225 -268.645083) (xy 366.575955 -268.693379) (xy 366.553497 -268.738781) (xy 366.524377 -268.780226)
			(xy 366.489276 -268.816744) (xy 366.449016 -268.847482) (xy 366.427004 -268.860016) (xy 366.427004 -269.409477)
			(xy 368.288317 -269.409477) (xy 368.288317 -269.357543) (xy 368.296442 -269.306248) (xy 368.31249 -269.256855)
			(xy 368.336068 -269.210581) (xy 368.366594 -269.168565) (xy 368.403317 -269.131842) (xy 368.445333 -269.101316)
			(xy 368.491607 -269.077738) (xy 368.541 -269.06169) (xy 368.592295 -269.053565) (xy 368.644229 -269.053565)
			(xy 368.695524 -269.06169) (xy 368.744917 -269.077738) (xy 368.791191 -269.101316) (xy 368.833207 -269.131842)
			(xy 368.86993 -269.168565) (xy 368.900456 -269.210581) (xy 368.924034 -269.256855) (xy 368.940082 -269.306248)
			(xy 368.948207 -269.357543) (xy 368.948716 -269.38351) (xy 368.948207 -269.409477) (xy 368.940082 -269.460772)
			(xy 368.924034 -269.510165) (xy 368.900456 -269.556439) (xy 368.86993 -269.598455) (xy 368.833207 -269.635178)
			(xy 368.791191 -269.665704) (xy 368.744917 -269.689282) (xy 368.695524 -269.70533) (xy 368.644229 -269.713455)
			(xy 368.592295 -269.713455) (xy 368.541 -269.70533) (xy 368.491607 -269.689282) (xy 368.445333 -269.665704)
			(xy 368.403317 -269.635178) (xy 368.366594 -269.598455) (xy 368.336068 -269.556439) (xy 368.31249 -269.510165)
			(xy 368.296442 -269.460772) (xy 368.288317 -269.409477) (xy 366.427004 -269.409477) (xy 366.427004 -269.907258)
			(xy 366.449006 -269.919807) (xy 366.489255 -269.950552) (xy 366.524348 -269.987073) (xy 366.553464 -270.028516)
			(xy 366.575923 -270.073912) (xy 366.5912 -270.122202) (xy 366.598938 -270.172256) (xy 366.59947 -270.19758)
			(xy 366.598984 -270.223475) (xy 366.590942 -270.274636) (xy 366.583468 -270.299434) (xy 366.573816 -270.328898)
			(xy 366.924844 -270.679926) (xy 370.158264 -270.679926)
		)
		(stroke
			(width 0)
			(type solid)
		)
		(fill yes)
		(layer "In11.Cu")
		(net "PVCCINFAON_CPU0")
	)
	(gr_poly
		(pts
			(xy 115.25758 -364.574328) (xy 115.25758 -364.469426) (xy 115.233401 -364.456614) (xy 115.18865 -364.425124)
			(xy 115.148842 -364.387579) (xy 115.114791 -364.344745) (xy 115.100608 -364.321344) (xy 115.093205 -364.309637)
			(xy 115.073298 -364.290396) (xy 115.04895 -364.277215) (xy 115.021956 -364.271065) (xy 114.994302 -364.2724)
			(xy 114.968024 -364.281119) (xy 114.945059 -364.296583) (xy 114.927096 -364.317651) (xy 114.920776 -364.32998)
			(xy 114.90894 -364.35442) (xy 114.879383 -364.399974) (xy 114.843672 -364.440882) (xy 114.802526 -364.476319)
			(xy 114.756775 -364.50557) (xy 114.707342 -364.528045) (xy 114.655224 -364.54329) (xy 114.601471 -364.550999)
			(xy 114.57432 -364.551468) (xy 114.547069 -364.551006) (xy 114.493122 -364.543252) (xy 114.440827 -364.5279)
			(xy 114.391249 -364.505261) (xy 114.345399 -364.475796) (xy 114.304208 -364.440106) (xy 114.268516 -364.398917)
			(xy 114.239049 -364.353068) (xy 114.216407 -364.303492) (xy 114.201052 -364.251198) (xy 114.193295 -364.197251)
			(xy 114.193295 -364.142749) (xy 114.201052 -364.088802) (xy 114.216407 -364.036508) (xy 114.239049 -363.986932)
			(xy 114.268516 -363.941083) (xy 114.304208 -363.899894) (xy 114.345399 -363.864204) (xy 114.391249 -363.834739)
			(xy 114.440827 -363.8121) (xy 114.493122 -363.796748) (xy 114.547069 -363.788994) (xy 114.57432 -363.788452)
			(xy 114.602768 -363.788979) (xy 114.659032 -363.797428) (xy 114.713419 -363.814137) (xy 114.764722 -363.838734)
			(xy 114.811805 -363.870675) (xy 114.853625 -363.909253) (xy 114.889254 -363.953611) (xy 114.904012 -363.977936)
			(xy 114.911414 -363.989656) (xy 114.931327 -364.008922) (xy 114.955687 -364.022124) (xy 114.9827 -364.02829)
			(xy 115.010376 -364.026965) (xy 115.036676 -364.018246) (xy 115.059663 -364.002777) (xy 115.077644 -363.981696)
			(xy 115.083844 -363.9693) (xy 115.094949 -363.946338) (xy 115.122357 -363.903322) (xy 115.155245 -363.864336)
			(xy 115.193028 -363.830072) (xy 115.235034 -363.801141) (xy 115.25758 -363.789214) (xy 115.25758 -363.76229)
			(xy 115.245236 -363.723448) (xy 115.227943 -363.643799) (xy 115.219246 -363.562759) (xy 115.218718 -363.522006)
			(xy 115.219207 -363.48255) (xy 115.227328 -363.404058) (xy 115.243495 -363.32682) (xy 115.25504 -363.289088)
			(xy 115.25758 -363.281468) (xy 115.25758 -356.145338) (xy 115.045744 -355.933756) (xy 113.250218 -355.933756)
			(xy 113.225223 -355.933116) (xy 113.176203 -355.923311) (xy 113.130036 -355.904133) (xy 113.088497 -355.876319)
			(xy 113.070386 -355.85908) (xy 112.65154 -355.440234) (xy 112.630204 -355.440234) (xy 112.602927 -355.439806)
			(xy 112.54892 -355.432107) (xy 112.49656 -355.416795) (xy 112.446915 -355.394181) (xy 112.400996 -355.364728)
			(xy 112.359741 -355.329034) (xy 112.32399 -355.287828) (xy 112.294473 -355.241951) (xy 112.27179 -355.192337)
			(xy 112.256406 -355.139999) (xy 112.248632 -355.086002) (xy 112.248188 -355.058726) (xy 112.24865 -355.031472)
			(xy 112.256404 -354.977518) (xy 112.271757 -354.925217) (xy 112.294398 -354.875633) (xy 112.323865 -354.829776)
			(xy 112.359559 -354.78858) (xy 112.400752 -354.752883) (xy 112.446607 -354.723413) (xy 112.496189 -354.700768)
			(xy 112.548489 -354.68541) (xy 112.602442 -354.677652) (xy 112.629696 -354.677218) (xy 112.658532 -354.677724)
			(xy 112.715553 -354.686365) (xy 112.770623 -354.703494) (xy 112.822485 -354.728721) (xy 112.869955 -354.761472)
			(xy 112.891316 -354.78085) (xy 112.901951 -354.790218) (xy 112.927125 -354.803212) (xy 112.954901 -354.808786)
			(xy 112.983139 -354.80651) (xy 113.009664 -354.79656) (xy 113.032432 -354.779701) (xy 113.049688 -354.757234)
			(xy 113.060104 -354.730888) (xy 113.062004 -354.716842) (xy 113.066132 -354.678954) (xy 113.081003 -354.604199)
			(xy 113.10326 -354.531302) (xy 113.132682 -354.46099) (xy 113.168974 -354.393966) (xy 113.211775 -354.330898)
			(xy 113.260656 -354.272417) (xy 113.287556 -354.245418) (xy 113.297113 -354.23542) (xy 113.31096 -354.211491)
			(xy 113.317878 -354.184724) (xy 113.317359 -354.157082) (xy 113.309442 -354.130593) (xy 113.294707 -354.107201)
			(xy 113.284762 -354.09759) (xy 113.255659 -354.070507) (xy 113.202641 -354.011262) (xy 113.156077 -353.94682)
			(xy 113.116474 -353.877882) (xy 113.084262 -353.805196) (xy 113.05979 -353.729552) (xy 113.043325 -353.651772)
			(xy 113.035045 -353.5727) (xy 113.034572 -353.532948) (xy 113.035097 -353.492319) (xy 113.043743 -353.411521)
			(xy 113.060932 -353.332101) (xy 113.086469 -353.254959) (xy 113.120064 -353.180969) (xy 113.161336 -353.110972)
			(xy 113.209817 -353.04576) (xy 113.264958 -352.986074) (xy 113.295176 -352.958908) (xy 113.305243 -352.949563)
			(xy 113.320417 -352.926681) (xy 113.328945 -352.900582) (xy 113.330212 -352.873155) (xy 113.324126 -352.846382)
			(xy 113.311125 -352.822198) (xy 113.292151 -352.802352) (xy 113.268576 -352.788279) (xy 113.242103 -352.780996)
			(xy 113.228374 -352.7806) (xy 113.147856 -352.7806) (xy 113.117376 -352.81108) (xy 113.117376 -352.832416)
			(xy 113.116946 -352.859691) (xy 113.109245 -352.913692) (xy 113.09393 -352.966046) (xy 113.071315 -353.015685)
			(xy 113.041859 -353.061597) (xy 113.006165 -353.102845) (xy 112.964959 -353.138588) (xy 112.919083 -353.168098)
			(xy 112.869471 -353.190772) (xy 112.817135 -353.206149) (xy 112.763142 -353.213914) (xy 112.735868 -353.214432)
			(xy 112.708603 -353.213966) (xy 112.65463 -353.206198) (xy 112.602312 -353.190826) (xy 112.552716 -353.168161)
			(xy 112.506852 -353.138667) (xy 112.465654 -353.102944) (xy 112.429961 -353.061719) (xy 112.400501 -353.015832)
			(xy 112.377874 -352.966219) (xy 112.362541 -352.91389) (xy 112.354814 -352.859911) (xy 112.35485 -352.805382)
			(xy 112.362649 -352.751413) (xy 112.378052 -352.699104) (xy 112.400745 -352.649521) (xy 112.430266 -352.603674)
			(xy 112.466014 -352.562497) (xy 112.507259 -352.526828) (xy 112.553163 -352.497395) (xy 112.602789 -352.474797)
			(xy 112.655127 -352.459494) (xy 112.709111 -352.451798) (xy 112.736376 -352.451416) (xy 112.757712 -352.451416)
			(xy 112.862614 -352.346514) (xy 112.880722 -352.329288) (xy 112.922281 -352.301541) (xy 112.968451 -352.282427)
			(xy 113.017461 -352.272677) (xy 113.042446 -352.272092) (xy 113.5888 -352.272092) (xy 113.603802 -352.27156)
			(xy 113.632513 -352.262853) (xy 113.657463 -352.246188) (xy 113.676502 -352.223) (xy 113.687993 -352.195284)
			(xy 113.690946 -352.165427) (xy 113.685106 -352.135998) (xy 113.670978 -352.109529) (xy 113.660682 -352.09861)
			(xy 113.633504 -352.071432) (xy 112.547908 -350.98609) (xy 111.99114 -350.429322) (xy 111.768128 -350.652588)
			(xy 111.768128 -351.173542) (xy 111.787745 -351.191711) (xy 111.822208 -351.232591) (xy 111.850623 -351.277884)
			(xy 111.872435 -351.326702) (xy 111.887214 -351.378088) (xy 111.894672 -351.431034) (xy 111.895128 -351.457768)
			(xy 111.894642 -351.485019) (xy 111.886886 -351.538967) (xy 111.871531 -351.591262) (xy 111.848889 -351.640839)
			(xy 111.819423 -351.686689) (xy 111.783732 -351.72788) (xy 111.742541 -351.763571) (xy 111.696691 -351.793037)
			(xy 111.647114 -351.815679) (xy 111.594819 -351.831034) (xy 111.540871 -351.83879) (xy 111.486369 -351.83879)
			(xy 111.432421 -351.831034) (xy 111.380126 -351.815679) (xy 111.330549 -351.793037) (xy 111.284699 -351.763571)
			(xy 111.243508 -351.72788) (xy 111.207817 -351.686689) (xy 111.178351 -351.640839) (xy 111.155709 -351.591262)
			(xy 111.140354 -351.538967) (xy 111.132598 -351.485019) (xy 111.132112 -351.457768) (xy 111.132563 -351.431034)
			(xy 111.140031 -351.378091) (xy 111.154817 -351.326709) (xy 111.176631 -351.277894) (xy 111.205046 -351.232602)
			(xy 111.239504 -351.19172) (xy 111.259112 -351.173542) (xy 111.259112 -350.547178) (xy 111.260128 -350.52635)
			(xy 111.26085 -350.512322) (xy 111.255476 -350.484763) (xy 111.242798 -350.45971) (xy 111.223776 -350.439058)
			(xy 111.199847 -350.424368) (xy 111.172822 -350.416751) (xy 111.158782 -350.416368) (xy 109.712252 -350.416368)
			(xy 109.555788 -350.573086) (xy 109.555788 -351.216722) (xy 109.575403 -351.234892) (xy 109.609863 -351.275774)
			(xy 109.638277 -351.321067) (xy 109.660087 -351.369884) (xy 109.674867 -351.421269) (xy 109.682326 -351.474214)
			(xy 109.682788 -351.500948) (xy 109.682302 -351.528199) (xy 109.674546 -351.582147) (xy 109.659191 -351.634442)
			(xy 109.636549 -351.684019) (xy 109.607083 -351.729869) (xy 109.571392 -351.77106) (xy 109.530201 -351.806751)
			(xy 109.484351 -351.836217) (xy 109.434774 -351.858859) (xy 109.382479 -351.874214) (xy 109.328531 -351.88197)
			(xy 109.274029 -351.88197) (xy 109.220081 -351.874214) (xy 109.167786 -351.858859) (xy 109.118209 -351.836217)
			(xy 109.072359 -351.806751) (xy 109.031168 -351.77106) (xy 108.995477 -351.729869) (xy 108.966011 -351.684019)
			(xy 108.943369 -351.634442) (xy 108.928014 -351.582147) (xy 108.920258 -351.528199) (xy 108.919772 -351.500948)
			(xy 108.920224 -351.474215) (xy 108.927695 -351.421272) (xy 108.942481 -351.369891) (xy 108.964295 -351.321076)
			(xy 108.992709 -351.275784) (xy 109.027166 -351.234902) (xy 109.046772 -351.216722) (xy 109.046772 -350.467676)
			(xy 109.047026 -350.467168) (xy 109.047026 -350.416368) (xy 108.539788 -350.416368) (xy 108.539788 -351.216722)
			(xy 108.559403 -351.234892) (xy 108.593863 -351.275774) (xy 108.622277 -351.321067) (xy 108.644087 -351.369884)
			(xy 108.658867 -351.421269) (xy 108.666326 -351.474214) (xy 108.666788 -351.500948) (xy 108.666302 -351.528199)
			(xy 108.658546 -351.582147) (xy 108.643191 -351.634442) (xy 108.620549 -351.684019) (xy 108.591083 -351.729869)
			(xy 108.555392 -351.77106) (xy 108.514201 -351.806751) (xy 108.468351 -351.836217) (xy 108.418774 -351.858859)
			(xy 108.366479 -351.874214) (xy 108.312531 -351.88197) (xy 108.258029 -351.88197) (xy 108.204081 -351.874214)
			(xy 108.151786 -351.858859) (xy 108.102209 -351.836217) (xy 108.056359 -351.806751) (xy 108.015168 -351.77106)
			(xy 107.979477 -351.729869) (xy 107.950011 -351.684019) (xy 107.927369 -351.634442) (xy 107.912014 -351.582147)
			(xy 107.904258 -351.528199) (xy 107.903772 -351.500948) (xy 107.904224 -351.474215) (xy 107.911695 -351.421272)
			(xy 107.926481 -351.369891) (xy 107.948295 -351.321076) (xy 107.976709 -351.275784) (xy 108.011166 -351.234902)
			(xy 108.030772 -351.216722) (xy 108.030772 -350.416368) (xy 107.523788 -350.416368) (xy 107.523788 -351.216722)
			(xy 107.543403 -351.234892) (xy 107.577863 -351.275774) (xy 107.606277 -351.321067) (xy 107.628087 -351.369884)
			(xy 107.642867 -351.421269) (xy 107.650326 -351.474214) (xy 107.650788 -351.500948) (xy 107.650302 -351.528199)
			(xy 107.642546 -351.582147) (xy 107.627191 -351.634442) (xy 107.604549 -351.684019) (xy 107.575083 -351.729869)
			(xy 107.539392 -351.77106) (xy 107.498201 -351.806751) (xy 107.452351 -351.836217) (xy 107.402774 -351.858859)
			(xy 107.350479 -351.874214) (xy 107.296531 -351.88197) (xy 107.242029 -351.88197) (xy 107.188081 -351.874214)
			(xy 107.135786 -351.858859) (xy 107.086209 -351.836217) (xy 107.040359 -351.806751) (xy 106.999168 -351.77106)
			(xy 106.963477 -351.729869) (xy 106.934011 -351.684019) (xy 106.911369 -351.634442) (xy 106.896014 -351.582147)
			(xy 106.888258 -351.528199) (xy 106.887772 -351.500948) (xy 106.888224 -351.474215) (xy 106.895695 -351.421272)
			(xy 106.910481 -351.369891) (xy 106.932295 -351.321076) (xy 106.960709 -351.275784) (xy 106.995166 -351.234902)
			(xy 107.014772 -351.216722) (xy 107.014772 -350.416368) (xy 106.507788 -350.416368) (xy 106.507788 -351.216722)
			(xy 106.527403 -351.234892) (xy 106.561863 -351.275774) (xy 106.590277 -351.321067) (xy 106.612087 -351.369884)
			(xy 106.626867 -351.421269) (xy 106.634326 -351.474214) (xy 106.634788 -351.500948) (xy 106.634302 -351.528199)
			(xy 106.626546 -351.582147) (xy 106.611191 -351.634442) (xy 106.588549 -351.684019) (xy 106.559083 -351.729869)
			(xy 106.523392 -351.77106) (xy 106.482201 -351.806751) (xy 106.436351 -351.836217) (xy 106.386774 -351.858859)
			(xy 106.334479 -351.874214) (xy 106.280531 -351.88197) (xy 106.226029 -351.88197) (xy 106.172081 -351.874214)
			(xy 106.119786 -351.858859) (xy 106.070209 -351.836217) (xy 106.024359 -351.806751) (xy 105.983168 -351.77106)
			(xy 105.947477 -351.729869) (xy 105.918011 -351.684019) (xy 105.895369 -351.634442) (xy 105.880014 -351.582147)
			(xy 105.872258 -351.528199) (xy 105.871772 -351.500948) (xy 105.872224 -351.474215) (xy 105.879695 -351.421272)
			(xy 105.894481 -351.369891) (xy 105.916295 -351.321076) (xy 105.944709 -351.275784) (xy 105.979166 -351.234902)
			(xy 105.998772 -351.216722) (xy 105.998772 -350.307402) (xy 105.58272 -349.891096) (xy 103.892858 -349.891096)
			(xy 103.25608 -350.527874) (xy 103.25608 -351.700592) (xy 103.994964 -351.700592) (xy 103.999035 -351.64497)
			(xy 104.011161 -351.590533) (xy 104.031084 -351.538442) (xy 104.05838 -351.489807) (xy 104.092466 -351.445664)
			(xy 104.132615 -351.406955) (xy 104.177973 -351.374504) (xy 104.227573 -351.349003) (xy 104.280357 -351.330996)
			(xy 104.3352 -351.320866) (xy 104.390934 -351.318829) (xy 104.446371 -351.324929) (xy 104.500328 -351.339035)
			(xy 104.551657 -351.360847) (xy 104.599263 -351.389901) (xy 104.642131 -351.425576) (xy 104.679348 -351.467113)
			(xy 104.710121 -351.513626) (xy 104.733793 -351.564123) (xy 104.749861 -351.61753) (xy 104.757981 -351.672706)
			(xy 104.75849 -351.700592) (xy 104.757981 -351.728478) (xy 104.749861 -351.783654) (xy 104.733793 -351.837061)
			(xy 104.721086 -351.864168) (xy 104.858564 -351.864168) (xy 104.862635 -351.808546) (xy 104.874761 -351.754109)
			(xy 104.894684 -351.702018) (xy 104.92198 -351.653383) (xy 104.956066 -351.60924) (xy 104.996215 -351.570531)
			(xy 105.041573 -351.53808) (xy 105.091173 -351.512579) (xy 105.143957 -351.494572) (xy 105.1988 -351.484442)
			(xy 105.254534 -351.482405) (xy 105.309971 -351.488505) (xy 105.363928 -351.502611) (xy 105.415257 -351.524423)
			(xy 105.462863 -351.553477) (xy 105.505731 -351.589152) (xy 105.542948 -351.630689) (xy 105.573721 -351.677202)
			(xy 105.597393 -351.727699) (xy 105.613461 -351.781106) (xy 105.621581 -351.836282) (xy 105.62209 -351.864168)
			(xy 105.621581 -351.892054) (xy 105.613461 -351.94723) (xy 105.597393 -352.000637) (xy 105.573721 -352.051134)
			(xy 105.542948 -352.097647) (xy 105.505731 -352.139184) (xy 105.462863 -352.174859) (xy 105.415257 -352.203913)
			(xy 105.363928 -352.225725) (xy 105.309971 -352.239831) (xy 105.254534 -352.245931) (xy 105.1988 -352.243894)
			(xy 105.143957 -352.233764) (xy 105.091173 -352.215757) (xy 105.041573 -352.190256) (xy 104.996215 -352.157805)
			(xy 104.956066 -352.119096) (xy 104.92198 -352.074953) (xy 104.894684 -352.026318) (xy 104.874761 -351.974227)
			(xy 104.862635 -351.91979) (xy 104.858564 -351.864168) (xy 104.721086 -351.864168) (xy 104.710121 -351.887558)
			(xy 104.679348 -351.934071) (xy 104.642131 -351.975608) (xy 104.599263 -352.011283) (xy 104.551657 -352.040337)
			(xy 104.500328 -352.062149) (xy 104.446371 -352.076255) (xy 104.390934 -352.082355) (xy 104.3352 -352.080318)
			(xy 104.280357 -352.070188) (xy 104.227573 -352.052181) (xy 104.177973 -352.02668) (xy 104.132615 -351.994229)
			(xy 104.092466 -351.95552) (xy 104.05838 -351.911377) (xy 104.031084 -351.862742) (xy 104.011161 -351.810651)
			(xy 103.999035 -351.756214) (xy 103.994964 -351.700592) (xy 103.25608 -351.700592) (xy 103.25608 -352.152458)
			(xy 103.805736 -352.70186) (xy 109.104176 -352.70186) (xy 109.589824 -352.216466) (xy 109.607934 -352.199244)
			(xy 109.649494 -352.171504) (xy 109.695664 -352.152395) (xy 109.744672 -352.142649) (xy 109.769656 -352.142044)
			(xy 110.657894 -352.142044) (xy 110.676048 -352.122398) (xy 110.71691 -352.087876) (xy 110.762195 -352.059403)
			(xy 110.811014 -352.037538) (xy 110.86241 -352.022709) (xy 110.915374 -352.015209) (xy 110.94212 -352.01479)
			(xy 110.96937 -352.015277) (xy 111.023316 -352.023036) (xy 111.075609 -352.038393) (xy 111.125184 -352.061035)
			(xy 111.171032 -352.090502) (xy 111.21222 -352.126194) (xy 111.24791 -352.167384) (xy 111.277374 -352.213234)
			(xy 111.300014 -352.26281) (xy 111.315368 -352.315103) (xy 111.323124 -352.36905) (xy 111.323124 -352.42355)
			(xy 111.315368 -352.477497) (xy 111.300014 -352.52979) (xy 111.277374 -352.579366) (xy 111.24791 -352.625216)
			(xy 111.21222 -352.666406) (xy 111.171032 -352.702098) (xy 111.125184 -352.731565) (xy 111.075609 -352.754207)
			(xy 111.023316 -352.769564) (xy 110.96937 -352.777323) (xy 110.94212 -352.777806) (xy 110.915377 -352.777337)
			(xy 110.862419 -352.769831) (xy 110.811028 -352.755006) (xy 110.76221 -352.733151) (xy 110.716921 -352.704695)
			(xy 110.676047 -352.670195) (xy 110.657894 -352.650552) (xy 109.875066 -352.650552) (xy 109.558074 -352.967544)
			(xy 109.558074 -353.434142) (xy 109.778292 -353.65436) (xy 110.337092 -353.65436) (xy 110.48111 -353.510342)
			(xy 110.48111 -353.489006) (xy 110.481539 -353.46173) (xy 110.489237 -353.407725) (xy 110.50455 -353.355368)
			(xy 110.527164 -353.305725) (xy 110.556618 -353.25981) (xy 110.592312 -353.218558) (xy 110.633518 -353.182811)
			(xy 110.679396 -353.153298) (xy 110.72901 -353.13062) (xy 110.781348 -353.115241) (xy 110.835343 -353.107473)
			(xy 110.862618 -353.10699) (xy 110.889868 -353.107477) (xy 110.943814 -353.115236) (xy 110.996107 -353.130592)
			(xy 111.045682 -353.153234) (xy 111.09153 -353.182701) (xy 111.132719 -353.218393) (xy 111.168408 -353.259582)
			(xy 111.197873 -353.305432) (xy 111.220513 -353.355008) (xy 111.235868 -353.407301) (xy 111.243624 -353.461248)
			(xy 111.244126 -353.488498) (xy 111.243625 -353.516619) (xy 111.235368 -353.572252) (xy 111.219034 -353.62607)
			(xy 111.194976 -353.676906) (xy 111.163715 -353.72366) (xy 111.125929 -353.765319) (xy 111.082437 -353.800978)
			(xy 111.03418 -353.829866) (xy 110.982206 -353.851357) (xy 110.92764 -353.864984) (xy 110.899702 -353.868228)
			(xy 110.881668 -353.870006) (xy 110.609634 -354.14204) (xy 111.725708 -354.14204) (xy 111.729779 -354.086418)
			(xy 111.741905 -354.031981) (xy 111.761828 -353.97989) (xy 111.789124 -353.931255) (xy 111.82321 -353.887112)
			(xy 111.863359 -353.848403) (xy 111.908717 -353.815952) (xy 111.958317 -353.790451) (xy 112.011101 -353.772444)
			(xy 112.065944 -353.762314) (xy 112.121678 -353.760277) (xy 112.177115 -353.766377) (xy 112.231072 -353.780483)
			(xy 112.282401 -353.802295) (xy 112.330007 -353.831349) (xy 112.372875 -353.867024) (xy 112.410092 -353.908561)
			(xy 112.440865 -353.955074) (xy 112.464537 -354.005571) (xy 112.480605 -354.058978) (xy 112.488725 -354.114154)
			(xy 112.489234 -354.14204) (xy 112.488725 -354.169926) (xy 112.480605 -354.225102) (xy 112.464537 -354.278509)
			(xy 112.440865 -354.329006) (xy 112.410092 -354.375519) (xy 112.372875 -354.417056) (xy 112.330007 -354.452731)
			(xy 112.282401 -354.481785) (xy 112.231072 -354.503597) (xy 112.177115 -354.517703) (xy 112.121678 -354.523803)
			(xy 112.065944 -354.521766) (xy 112.011101 -354.511636) (xy 111.958317 -354.493629) (xy 111.908717 -354.468128)
			(xy 111.863359 -354.435677) (xy 111.82321 -354.396968) (xy 111.789124 -354.352825) (xy 111.761828 -354.30419)
			(xy 111.741905 -354.252099) (xy 111.729779 -354.197662) (xy 111.725708 -354.14204) (xy 110.609634 -354.14204)
			(xy 110.003844 -354.74783) (xy 110.003844 -354.9904) (xy 111.263176 -354.9904) (xy 111.275352 -354.966834)
			(xy 111.305243 -354.923015) (xy 111.340913 -354.883755) (xy 111.381674 -354.849812) (xy 111.426742 -354.821838)
			(xy 111.475248 -354.800373) (xy 111.526259 -354.78583) (xy 111.578792 -354.778488) (xy 111.605314 -354.778056)
			(xy 111.632567 -354.778543) (xy 111.686518 -354.786302) (xy 111.738816 -354.801659) (xy 111.788397 -354.824304)
			(xy 111.83425 -354.853773) (xy 111.875442 -354.889468) (xy 111.911135 -354.930662) (xy 111.940603 -354.976516)
			(xy 111.963245 -355.026097) (xy 111.978601 -355.078395) (xy 111.986358 -355.132347) (xy 111.986358 -355.186853)
			(xy 111.978601 -355.240805) (xy 111.963245 -355.293103) (xy 111.940603 -355.342684) (xy 111.911135 -355.388538)
			(xy 111.875442 -355.429732) (xy 111.83425 -355.465427) (xy 111.788397 -355.494896) (xy 111.738816 -355.517541)
			(xy 111.686518 -355.532898) (xy 111.632567 -355.540657) (xy 111.605314 -355.541072) (xy 111.577125 -355.540567)
			(xy 111.521361 -355.532273) (xy 111.467424 -355.515865) (xy 111.441738 -355.504242) (xy 111.431324 -355.499416)
			(xy 110.003844 -355.499416) (xy 110.003844 -355.681788) (xy 109.876844 -355.808788) (xy 109.24794 -355.808788)
			(xy 108.905802 -356.150926) (xy 110.986314 -356.150926) (xy 110.990385 -356.095304) (xy 111.002511 -356.040867)
			(xy 111.022434 -355.988776) (xy 111.04973 -355.940141) (xy 111.083816 -355.895998) (xy 111.123965 -355.857289)
			(xy 111.169323 -355.824838) (xy 111.218923 -355.799337) (xy 111.271707 -355.78133) (xy 111.32655 -355.7712)
			(xy 111.382284 -355.769163) (xy 111.437721 -355.775263) (xy 111.491678 -355.789369) (xy 111.543007 -355.811181)
			(xy 111.590613 -355.840235) (xy 111.633481 -355.87591) (xy 111.670698 -355.917447) (xy 111.701471 -355.96396)
			(xy 111.725143 -356.014457) (xy 111.741211 -356.067864) (xy 111.749331 -356.12304) (xy 111.74984 -356.150926)
			(xy 111.749331 -356.178812) (xy 111.741211 -356.233988) (xy 111.725143 -356.287395) (xy 111.701471 -356.337892)
			(xy 111.670698 -356.384405) (xy 111.633481 -356.425942) (xy 111.590613 -356.461617) (xy 111.543007 -356.490671)
			(xy 111.491678 -356.512483) (xy 111.437721 -356.526589) (xy 111.382284 -356.532689) (xy 111.32655 -356.530652)
			(xy 111.271707 -356.520522) (xy 111.218923 -356.502515) (xy 111.169323 -356.477014) (xy 111.123965 -356.444563)
			(xy 111.083816 -356.405854) (xy 111.04973 -356.361711) (xy 111.022434 -356.313076) (xy 111.002511 -356.260985)
			(xy 110.990385 -356.206548) (xy 110.986314 -356.150926) (xy 108.905802 -356.150926) (xy 108.64723 -356.409498)
			(xy 108.637045 -356.420484) (xy 108.622982 -356.446919) (xy 108.617181 -356.476295) (xy 108.62014 -356.506092)
			(xy 108.631605 -356.533753) (xy 108.650592 -356.556906) (xy 108.675472 -356.573566) (xy 108.689648 -356.578408)
			(xy 108.715377 -356.586738) (xy 108.764364 -356.609644) (xy 108.809626 -356.63924) (xy 108.850253 -356.674931)
			(xy 108.885433 -356.716003) (xy 108.914459 -356.761632) (xy 108.93675 -356.810903) (xy 108.951858 -356.862828)
			(xy 108.959481 -356.916367) (xy 108.959904 -356.943406) (xy 110.101378 -356.943406) (xy 110.105449 -356.887784)
			(xy 110.117575 -356.833347) (xy 110.137498 -356.781256) (xy 110.164794 -356.732621) (xy 110.19888 -356.688478)
			(xy 110.239029 -356.649769) (xy 110.284387 -356.617318) (xy 110.333987 -356.591817) (xy 110.386771 -356.57381)
			(xy 110.441614 -356.56368) (xy 110.497348 -356.561643) (xy 110.552785 -356.567743) (xy 110.554717 -356.568248)
			(xy 113.183922 -356.568248) (xy 113.187993 -356.512626) (xy 113.200119 -356.458189) (xy 113.220042 -356.406098)
			(xy 113.247338 -356.357463) (xy 113.281424 -356.31332) (xy 113.321573 -356.274611) (xy 113.366931 -356.24216)
			(xy 113.416531 -356.216659) (xy 113.469315 -356.198652) (xy 113.524158 -356.188522) (xy 113.579892 -356.186485)
			(xy 113.635329 -356.192585) (xy 113.689286 -356.206691) (xy 113.740615 -356.228503) (xy 113.788221 -356.257557)
			(xy 113.831089 -356.293232) (xy 113.868306 -356.334769) (xy 113.899079 -356.381282) (xy 113.922751 -356.431779)
			(xy 113.938819 -356.485186) (xy 113.946939 -356.540362) (xy 113.947448 -356.568248) (xy 113.946939 -356.596134)
			(xy 113.938819 -356.65131) (xy 113.922751 -356.704717) (xy 113.899079 -356.755214) (xy 113.868306 -356.801727)
			(xy 113.831089 -356.843264) (xy 113.788221 -356.878939) (xy 113.740615 -356.907993) (xy 113.689286 -356.929805)
			(xy 113.635329 -356.943911) (xy 113.579892 -356.950011) (xy 113.524158 -356.947974) (xy 113.469315 -356.937844)
			(xy 113.416531 -356.919837) (xy 113.366931 -356.894336) (xy 113.321573 -356.861885) (xy 113.281424 -356.823176)
			(xy 113.247338 -356.779033) (xy 113.220042 -356.730398) (xy 113.200119 -356.678307) (xy 113.187993 -356.62387)
			(xy 113.183922 -356.568248) (xy 110.554717 -356.568248) (xy 110.606742 -356.581849) (xy 110.658071 -356.603661)
			(xy 110.705677 -356.632715) (xy 110.748545 -356.66839) (xy 110.785762 -356.709927) (xy 110.816535 -356.75644)
			(xy 110.840207 -356.806937) (xy 110.856275 -356.860344) (xy 110.864395 -356.91552) (xy 110.864904 -356.943406)
			(xy 110.864395 -356.971292) (xy 110.856275 -357.026468) (xy 110.840207 -357.079875) (xy 110.816535 -357.130372)
			(xy 110.785762 -357.176885) (xy 110.748545 -357.218422) (xy 110.705677 -357.254097) (xy 110.658071 -357.283151)
			(xy 110.606742 -357.304963) (xy 110.552785 -357.319069) (xy 110.497348 -357.325169) (xy 110.441614 -357.323132)
			(xy 110.386771 -357.313002) (xy 110.333987 -357.294995) (xy 110.284387 -357.269494) (xy 110.239029 -357.237043)
			(xy 110.19888 -357.198334) (xy 110.164794 -357.154191) (xy 110.137498 -357.105556) (xy 110.117575 -357.053465)
			(xy 110.105449 -356.999028) (xy 110.101378 -356.943406) (xy 108.959904 -356.943406) (xy 108.959418 -356.970657)
			(xy 108.951661 -357.024604) (xy 108.936305 -357.076898) (xy 108.913663 -357.126474) (xy 108.884197 -357.172323)
			(xy 108.848505 -357.213512) (xy 108.807315 -357.249203) (xy 108.761465 -357.278668) (xy 108.711888 -357.301308)
			(xy 108.659594 -357.316663) (xy 108.605647 -357.324419) (xy 108.578396 -357.324914) (xy 108.552479 -357.324476)
			(xy 108.501122 -357.317462) (xy 108.476034 -357.310944) (xy 108.463033 -357.30776) (xy 108.436276 -357.307561)
			(xy 108.410386 -357.314318) (xy 108.38714 -357.327569) (xy 108.368134 -357.346403) (xy 108.354672 -357.369528)
			(xy 108.34768 -357.395356) (xy 108.347256 -357.408734) (xy 108.347256 -357.561388) (xy 112.960402 -357.561388)
			(xy 112.964473 -357.505766) (xy 112.976599 -357.451329) (xy 112.996522 -357.399238) (xy 113.023818 -357.350603)
			(xy 113.057904 -357.30646) (xy 113.098053 -357.267751) (xy 113.143411 -357.2353) (xy 113.193011 -357.209799)
			(xy 113.245795 -357.191792) (xy 113.300638 -357.181662) (xy 113.356372 -357.179625) (xy 113.411809 -357.185725)
			(xy 113.465766 -357.199831) (xy 113.517095 -357.221643) (xy 113.564701 -357.250697) (xy 113.607569 -357.286372)
			(xy 113.644786 -357.327909) (xy 113.675559 -357.374422) (xy 113.699231 -357.424919) (xy 113.715299 -357.478326)
			(xy 113.723419 -357.533502) (xy 113.723928 -357.561388) (xy 113.723419 -357.589274) (xy 113.715299 -357.64445)
			(xy 113.699231 -357.697857) (xy 113.675559 -357.748354) (xy 113.644786 -357.794867) (xy 113.607569 -357.836404)
			(xy 113.564701 -357.872079) (xy 113.517095 -357.901133) (xy 113.465766 -357.922945) (xy 113.411809 -357.937051)
			(xy 113.356372 -357.943151) (xy 113.300638 -357.941114) (xy 113.245795 -357.930984) (xy 113.193011 -357.912977)
			(xy 113.143411 -357.887476) (xy 113.098053 -357.855025) (xy 113.057904 -357.816316) (xy 113.023818 -357.772173)
			(xy 112.996522 -357.723538) (xy 112.976599 -357.671447) (xy 112.964473 -357.61701) (xy 112.960402 -357.561388)
			(xy 108.347256 -357.561388) (xy 108.347256 -358.848406) (xy 110.101378 -358.848406) (xy 110.105449 -358.792784)
			(xy 110.117575 -358.738347) (xy 110.137498 -358.686256) (xy 110.164794 -358.637621) (xy 110.19888 -358.593478)
			(xy 110.239029 -358.554769) (xy 110.284387 -358.522318) (xy 110.333987 -358.496817) (xy 110.386771 -358.47881)
			(xy 110.441614 -358.46868) (xy 110.497348 -358.466643) (xy 110.552785 -358.472743) (xy 110.606742 -358.486849)
			(xy 110.658071 -358.508661) (xy 110.705677 -358.537715) (xy 110.748545 -358.57339) (xy 110.751444 -358.576626)
			(xy 112.706402 -358.576626) (xy 112.710473 -358.521004) (xy 112.722599 -358.466567) (xy 112.742522 -358.414476)
			(xy 112.769818 -358.365841) (xy 112.803904 -358.321698) (xy 112.844053 -358.282989) (xy 112.889411 -358.250538)
			(xy 112.939011 -358.225037) (xy 112.991795 -358.20703) (xy 113.046638 -358.1969) (xy 113.102372 -358.194863)
			(xy 113.157809 -358.200963) (xy 113.211766 -358.215069) (xy 113.263095 -358.236881) (xy 113.310701 -358.265935)
			(xy 113.353569 -358.30161) (xy 113.390786 -358.343147) (xy 113.421559 -358.38966) (xy 113.445231 -358.440157)
			(xy 113.461299 -358.493564) (xy 113.469419 -358.54874) (xy 113.469928 -358.576626) (xy 113.469419 -358.604512)
			(xy 113.461299 -358.659688) (xy 113.445231 -358.713095) (xy 113.421559 -358.763592) (xy 113.390786 -358.810105)
			(xy 113.353569 -358.851642) (xy 113.310701 -358.887317) (xy 113.263095 -358.916371) (xy 113.211766 -358.938183)
			(xy 113.157809 -358.952289) (xy 113.102372 -358.958389) (xy 113.046638 -358.956352) (xy 112.991795 -358.946222)
			(xy 112.939011 -358.928215) (xy 112.889411 -358.902714) (xy 112.844053 -358.870263) (xy 112.803904 -358.831554)
			(xy 112.769818 -358.787411) (xy 112.742522 -358.738776) (xy 112.722599 -358.686685) (xy 112.710473 -358.632248)
			(xy 112.706402 -358.576626) (xy 110.751444 -358.576626) (xy 110.785762 -358.614927) (xy 110.816535 -358.66144)
			(xy 110.840207 -358.711937) (xy 110.856275 -358.765344) (xy 110.864395 -358.82052) (xy 110.864904 -358.848406)
			(xy 110.864395 -358.876292) (xy 110.856275 -358.931468) (xy 110.840207 -358.984875) (xy 110.816535 -359.035372)
			(xy 110.785762 -359.081885) (xy 110.748545 -359.123422) (xy 110.705677 -359.159097) (xy 110.658071 -359.188151)
			(xy 110.606742 -359.209963) (xy 110.552785 -359.224069) (xy 110.497348 -359.230169) (xy 110.441614 -359.228132)
			(xy 110.386771 -359.218002) (xy 110.333987 -359.199995) (xy 110.284387 -359.174494) (xy 110.239029 -359.142043)
			(xy 110.19888 -359.103334) (xy 110.164794 -359.059191) (xy 110.137498 -359.010556) (xy 110.117575 -358.958465)
			(xy 110.105449 -358.904028) (xy 110.101378 -358.848406) (xy 108.347256 -358.848406) (xy 108.347256 -359.595674)
			(xy 112.734088 -359.595674) (xy 112.738159 -359.540052) (xy 112.750285 -359.485615) (xy 112.770208 -359.433524)
			(xy 112.797504 -359.384889) (xy 112.83159 -359.340746) (xy 112.871739 -359.302037) (xy 112.917097 -359.269586)
			(xy 112.966697 -359.244085) (xy 113.019481 -359.226078) (xy 113.074324 -359.215948) (xy 113.130058 -359.213911)
			(xy 113.185495 -359.220011) (xy 113.239452 -359.234117) (xy 113.290781 -359.255929) (xy 113.338387 -359.284983)
			(xy 113.381255 -359.320658) (xy 113.418472 -359.362195) (xy 113.449245 -359.408708) (xy 113.472917 -359.459205)
			(xy 113.488985 -359.512612) (xy 113.497105 -359.567788) (xy 113.497614 -359.595674) (xy 113.497105 -359.62356)
			(xy 113.488985 -359.678736) (xy 113.472917 -359.732143) (xy 113.449245 -359.78264) (xy 113.418472 -359.829153)
			(xy 113.381255 -359.87069) (xy 113.338387 -359.906365) (xy 113.290781 -359.935419) (xy 113.239452 -359.957231)
			(xy 113.185495 -359.971337) (xy 113.130058 -359.977437) (xy 113.074324 -359.9754) (xy 113.019481 -359.96527)
			(xy 112.966697 -359.947263) (xy 112.917097 -359.921762) (xy 112.871739 -359.889311) (xy 112.83159 -359.850602)
			(xy 112.797504 -359.806459) (xy 112.770208 -359.757824) (xy 112.750285 -359.705733) (xy 112.738159 -359.651296)
			(xy 112.734088 -359.595674) (xy 108.347256 -359.595674) (xy 108.347256 -360.25328) (xy 108.478066 -360.38409)
			(xy 108.504736 -360.37901) (xy 108.522903 -360.375668) (xy 108.559671 -360.372105) (xy 108.578142 -360.371898)
			(xy 108.581444 -360.371898) (xy 108.608553 -360.37259) (xy 108.662171 -360.380697) (xy 108.714101 -360.396314)
			(xy 108.763297 -360.419127) (xy 108.808766 -360.448676) (xy 108.849594 -360.484366) (xy 108.884956 -360.525477)
			(xy 108.91414 -360.571181) (xy 108.936559 -360.620558) (xy 108.951761 -360.672611) (xy 108.959439 -360.726292)
			(xy 108.959904 -360.753406) (xy 110.101378 -360.753406) (xy 110.105449 -360.697784) (xy 110.117575 -360.643347)
			(xy 110.137498 -360.591256) (xy 110.164794 -360.542621) (xy 110.19888 -360.498478) (xy 110.239029 -360.459769)
			(xy 110.284387 -360.427318) (xy 110.333987 -360.401817) (xy 110.386771 -360.38381) (xy 110.441614 -360.37368)
			(xy 110.497348 -360.371643) (xy 110.552785 -360.377743) (xy 110.606742 -360.391849) (xy 110.658071 -360.413661)
			(xy 110.705677 -360.442715) (xy 110.748545 -360.47839) (xy 110.785762 -360.519927) (xy 110.816535 -360.56644)
			(xy 110.837621 -360.61142) (xy 112.831624 -360.61142) (xy 112.835695 -360.555798) (xy 112.847821 -360.501361)
			(xy 112.867744 -360.44927) (xy 112.89504 -360.400635) (xy 112.929126 -360.356492) (xy 112.969275 -360.317783)
			(xy 113.014633 -360.285332) (xy 113.064233 -360.259831) (xy 113.117017 -360.241824) (xy 113.17186 -360.231694)
			(xy 113.227594 -360.229657) (xy 113.283031 -360.235757) (xy 113.336988 -360.249863) (xy 113.388317 -360.271675)
			(xy 113.435923 -360.300729) (xy 113.478791 -360.336404) (xy 113.516008 -360.377941) (xy 113.546781 -360.424454)
			(xy 113.570453 -360.474951) (xy 113.586521 -360.528358) (xy 113.594641 -360.583534) (xy 113.59515 -360.61142)
			(xy 113.594641 -360.639306) (xy 113.586521 -360.694482) (xy 113.570453 -360.747889) (xy 113.546781 -360.798386)
			(xy 113.516008 -360.844899) (xy 113.478791 -360.886436) (xy 113.435923 -360.922111) (xy 113.388317 -360.951165)
			(xy 113.336988 -360.972977) (xy 113.283031 -360.987083) (xy 113.227594 -360.993183) (xy 113.17186 -360.991146)
			(xy 113.117017 -360.981016) (xy 113.064233 -360.963009) (xy 113.014633 -360.937508) (xy 112.969275 -360.905057)
			(xy 112.929126 -360.866348) (xy 112.89504 -360.822205) (xy 112.867744 -360.77357) (xy 112.847821 -360.721479)
			(xy 112.835695 -360.667042) (xy 112.831624 -360.61142) (xy 110.837621 -360.61142) (xy 110.840207 -360.616937)
			(xy 110.856275 -360.670344) (xy 110.864395 -360.72552) (xy 110.864904 -360.753406) (xy 110.864395 -360.781292)
			(xy 110.856275 -360.836468) (xy 110.840207 -360.889875) (xy 110.816535 -360.940372) (xy 110.785762 -360.986885)
			(xy 110.748545 -361.028422) (xy 110.705677 -361.064097) (xy 110.658071 -361.093151) (xy 110.606742 -361.114963)
			(xy 110.552785 -361.129069) (xy 110.497348 -361.135169) (xy 110.441614 -361.133132) (xy 110.386771 -361.123002)
			(xy 110.333987 -361.104995) (xy 110.284387 -361.079494) (xy 110.239029 -361.047043) (xy 110.19888 -361.008334)
			(xy 110.164794 -360.964191) (xy 110.137498 -360.915556) (xy 110.117575 -360.863465) (xy 110.105449 -360.809028)
			(xy 110.101378 -360.753406) (xy 108.959904 -360.753406) (xy 108.959418 -360.780657) (xy 108.951661 -360.834604)
			(xy 108.936305 -360.886898) (xy 108.913663 -360.936474) (xy 108.884197 -360.982323) (xy 108.848505 -361.023512)
			(xy 108.807315 -361.059203) (xy 108.761465 -361.088668) (xy 108.711888 -361.111308) (xy 108.659594 -361.126663)
			(xy 108.605647 -361.134419) (xy 108.578396 -361.134914) (xy 108.554778 -361.134543) (xy 108.507907 -361.128681)
			(xy 108.484924 -361.12323) (xy 108.478574 -361.121706) (xy 108.476796 -361.121198) (xy 108.474002 -361.120436)
			(xy 108.45891 -361.117144) (xy 108.428078 -361.118796) (xy 108.399145 -361.129575) (xy 108.37475 -361.1485)
			(xy 108.357115 -361.173844) (xy 108.347851 -361.203297) (xy 108.347256 -361.218734) (xy 108.347256 -361.462828)
			(xy 108.429044 -361.544616) (xy 112.355882 -361.544616) (xy 112.359953 -361.488994) (xy 112.372079 -361.434557)
			(xy 112.392002 -361.382466) (xy 112.419298 -361.333831) (xy 112.453384 -361.289688) (xy 112.493533 -361.250979)
			(xy 112.538891 -361.218528) (xy 112.588491 -361.193027) (xy 112.641275 -361.17502) (xy 112.696118 -361.16489)
			(xy 112.751852 -361.162853) (xy 112.807289 -361.168953) (xy 112.861246 -361.183059) (xy 112.912575 -361.204871)
			(xy 112.960181 -361.233925) (xy 113.003049 -361.2696) (xy 113.040266 -361.311137) (xy 113.071039 -361.35765)
			(xy 113.094711 -361.408147) (xy 113.110779 -361.461554) (xy 113.118899 -361.51673) (xy 113.119408 -361.544616)
			(xy 113.118899 -361.572502) (xy 113.110779 -361.627678) (xy 113.094711 -361.681085) (xy 113.071039 -361.731582)
			(xy 113.040266 -361.778095) (xy 113.003049 -361.819632) (xy 112.960181 -361.855307) (xy 112.912575 -361.884361)
			(xy 112.861246 -361.906173) (xy 112.807289 -361.920279) (xy 112.751852 -361.926379) (xy 112.696118 -361.924342)
			(xy 112.641275 -361.914212) (xy 112.588491 -361.896205) (xy 112.538891 -361.870704) (xy 112.493533 -361.838253)
			(xy 112.453384 -361.799544) (xy 112.419298 -361.755401) (xy 112.392002 -361.706766) (xy 112.372079 -361.654675)
			(xy 112.359953 -361.600238) (xy 112.355882 -361.544616) (xy 108.429044 -361.544616) (xy 109.314488 -362.43006)
			(xy 111.033812 -362.43006) (xy 111.037883 -362.374438) (xy 111.050009 -362.320001) (xy 111.069932 -362.26791)
			(xy 111.097228 -362.219275) (xy 111.131314 -362.175132) (xy 111.171463 -362.136423) (xy 111.216821 -362.103972)
			(xy 111.266421 -362.078471) (xy 111.319205 -362.060464) (xy 111.374048 -362.050334) (xy 111.429782 -362.048297)
			(xy 111.485219 -362.054397) (xy 111.539176 -362.068503) (xy 111.590505 -362.090315) (xy 111.638111 -362.119369)
			(xy 111.680979 -362.155044) (xy 111.718196 -362.196581) (xy 111.748969 -362.243094) (xy 111.772641 -362.293591)
			(xy 111.788709 -362.346998) (xy 111.796829 -362.402174) (xy 111.797338 -362.43006) (xy 111.796829 -362.457946)
			(xy 111.788709 -362.513122) (xy 111.772641 -362.566529) (xy 111.748969 -362.617026) (xy 111.718196 -362.663539)
			(xy 111.680979 -362.705076) (xy 111.638111 -362.740751) (xy 111.590505 -362.769805) (xy 111.539176 -362.791617)
			(xy 111.485219 -362.805723) (xy 111.429782 -362.811823) (xy 111.374048 -362.809786) (xy 111.319205 -362.799656)
			(xy 111.266421 -362.781649) (xy 111.216821 -362.756148) (xy 111.171463 -362.723697) (xy 111.131314 -362.684988)
			(xy 111.097228 -362.640845) (xy 111.069932 -362.59221) (xy 111.050009 -362.540119) (xy 111.037883 -362.485682)
			(xy 111.033812 -362.43006) (xy 109.314488 -362.43006) (xy 109.45622 -362.571792) (xy 109.45622 -362.718604)
			(xy 109.456732 -362.733094) (xy 109.464875 -362.760908) (xy 109.480506 -362.785312) (xy 109.502363 -362.804342)
			(xy 109.528687 -362.816464) (xy 109.557357 -362.820702) (xy 109.586062 -362.816713) (xy 109.61249 -362.80482)
			(xy 109.62386 -362.79582) (xy 109.653444 -362.771185) (xy 109.716729 -362.727339) (xy 109.784111 -362.690096)
			(xy 109.854905 -362.659836) (xy 109.928389 -362.636868) (xy 110.003814 -362.621424) (xy 110.080411 -362.613663)
			(xy 110.118906 -362.613194) (xy 110.15884 -362.613717) (xy 110.23827 -362.622066) (xy 110.316392 -362.638672)
			(xy 110.39235 -362.663353) (xy 110.465312 -362.695838) (xy 110.534479 -362.735773) (xy 110.599093 -362.782718)
			(xy 110.658446 -362.83616) (xy 110.711887 -362.895513) (xy 110.758832 -362.960128) (xy 110.798765 -363.029295)
			(xy 110.83125 -363.102258) (xy 110.85593 -363.178216) (xy 110.872535 -363.256338) (xy 110.879794 -363.32541)
			(xy 112.722658 -363.32541) (xy 112.726729 -363.269788) (xy 112.738855 -363.215351) (xy 112.758778 -363.16326)
			(xy 112.786074 -363.114625) (xy 112.82016 -363.070482) (xy 112.860309 -363.031773) (xy 112.905667 -362.999322)
			(xy 112.955267 -362.973821) (xy 113.008051 -362.955814) (xy 113.062894 -362.945684) (xy 113.118628 -362.943647)
			(xy 113.174065 -362.949747) (xy 113.228022 -362.963853) (xy 113.279351 -362.985665) (xy 113.326957 -363.014719)
			(xy 113.369825 -363.050394) (xy 113.407042 -363.091931) (xy 113.437815 -363.138444) (xy 113.461487 -363.188941)
			(xy 113.477555 -363.242348) (xy 113.485675 -363.297524) (xy 113.486184 -363.32541) (xy 113.485675 -363.353296)
			(xy 113.477555 -363.408472) (xy 113.461487 -363.461879) (xy 113.437815 -363.512376) (xy 113.407042 -363.558889)
			(xy 113.369825 -363.600426) (xy 113.326957 -363.636101) (xy 113.279351 -363.665155) (xy 113.228022 -363.686967)
			(xy 113.174065 -363.701073) (xy 113.118628 -363.707173) (xy 113.062894 -363.705136) (xy 113.008051 -363.695006)
			(xy 112.955267 -363.676999) (xy 112.905667 -363.651498) (xy 112.860309 -363.619047) (xy 112.82016 -363.580338)
			(xy 112.786074 -363.536195) (xy 112.758778 -363.48756) (xy 112.738855 -363.435469) (xy 112.726729 -363.381032)
			(xy 112.722658 -363.32541) (xy 110.879794 -363.32541) (xy 110.880883 -363.335768) (xy 110.881414 -363.375702)
			(xy 110.880849 -363.417501) (xy 110.871706 -363.500597) (xy 110.853532 -363.582194) (xy 110.826543 -363.661315)
			(xy 110.791064 -363.73701) (xy 110.747519 -363.808371) (xy 110.72241 -363.841792) (xy 110.751479 -363.868875)
			(xy 110.804432 -363.928111) (xy 110.850935 -363.992534) (xy 110.890486 -364.061444) (xy 110.922655 -364.134094)
			(xy 110.947092 -364.209697) (xy 110.951688 -364.231428) (xy 111.419638 -364.231428) (xy 111.423709 -364.175806)
			(xy 111.435835 -364.121369) (xy 111.455758 -364.069278) (xy 111.483054 -364.020643) (xy 111.51714 -363.9765)
			(xy 111.557289 -363.937791) (xy 111.602647 -363.90534) (xy 111.652247 -363.879839) (xy 111.705031 -363.861832)
			(xy 111.759874 -363.851702) (xy 111.815608 -363.849665) (xy 111.871045 -363.855765) (xy 111.925002 -363.869871)
			(xy 111.976331 -363.891683) (xy 112.023937 -363.920737) (xy 112.066805 -363.956412) (xy 112.104022 -363.997949)
			(xy 112.134795 -364.044462) (xy 112.158467 -364.094959) (xy 112.174535 -364.148366) (xy 112.182655 -364.203542)
			(xy 112.183164 -364.231428) (xy 112.182655 -364.259314) (xy 112.174535 -364.31449) (xy 112.158467 -364.367897)
			(xy 112.134795 -364.418394) (xy 112.104022 -364.464907) (xy 112.066805 -364.506444) (xy 112.023937 -364.542119)
			(xy 111.976331 -364.571173) (xy 111.925002 -364.592985) (xy 111.871045 -364.607091) (xy 111.815608 -364.613191)
			(xy 111.759874 -364.611154) (xy 111.705031 -364.601024) (xy 111.652247 -364.583017) (xy 111.602647 -364.557516)
			(xy 111.557289 -364.525065) (xy 111.51714 -364.486356) (xy 111.483054 -364.442213) (xy 111.455758 -364.393578)
			(xy 111.435835 -364.341487) (xy 111.423709 -364.28705) (xy 111.419638 -364.231428) (xy 110.951688 -364.231428)
			(xy 110.963533 -364.287431) (xy 110.971799 -364.366453) (xy 110.972346 -364.40618) (xy 110.971076 -364.451392)
			(xy 110.970722 -364.465233) (xy 110.976566 -364.492283) (xy 110.989462 -364.51677) (xy 111.008461 -364.536893)
			(xy 111.032167 -364.551173) (xy 111.058838 -364.558561) (xy 111.072676 -364.559088) (xy 111.099986 -364.559468)
			(xy 111.15407 -364.567083) (xy 111.206515 -364.582333) (xy 111.25625 -364.604905) (xy 111.302257 -364.63434)
			(xy 111.343597 -364.670034) (xy 111.379424 -364.711258) (xy 111.409006 -364.757171) (xy 111.431739 -364.806832)
			(xy 111.447157 -364.859228) (xy 111.454946 -364.913287) (xy 111.455454 -364.940596) (xy 111.45495 -364.968757)
			(xy 111.446673 -365.024468) (xy 111.430299 -365.078358) (xy 111.406182 -365.129256) (xy 111.390938 -365.15294)
			(xy 111.383696 -365.164619) (xy 111.375106 -365.19071) (xy 111.373784 -365.218148) (xy 111.379824 -365.244945)
			(xy 111.392789 -365.269161) (xy 111.411742 -365.289045) (xy 111.435309 -365.303157) (xy 111.461785 -365.310475)
			(xy 111.47552 -365.310928) (xy 114.52098 -365.310928)
		)
		(stroke
			(width 0)
			(type solid)
		)
		(fill yes)
		(layer "In11.Cu")
		(net "PVCCIN_CPU1_VREF")
	)
	(gr_poly
		(pts
			(xy 465.316316 -395.996414) (xy 466.959696 -394.353034) (xy 466.959696 -379.017784) (xy 465.741258 -377.799346)
			(xy 462.17205 -377.799346) (xy 462.157056 -377.799873) (xy 462.128361 -377.808577) (xy 462.103434 -377.825247)
			(xy 462.084431 -377.848443) (xy 462.072992 -377.876163) (xy 462.070106 -377.90601) (xy 462.076022 -377.935407)
			(xy 462.090228 -377.961815) (xy 462.100422 -377.972828) (xy 462.10601 -377.97867) (xy 462.126088 -377.99955)
			(xy 462.160136 -378.046409) (xy 462.186435 -378.098017) (xy 462.204338 -378.153104) (xy 462.213402 -378.210313)
			(xy 462.21396 -378.239274) (xy 462.21396 -381.305816) (xy 462.215484 -381.311912) (xy 462.220809 -381.334591)
			(xy 462.226547 -381.380822) (xy 462.226914 -381.404114) (xy 462.226428 -381.431365) (xy 462.218672 -381.485313)
			(xy 462.203317 -381.537608) (xy 462.193523 -381.559054) (xy 463.166712 -381.559054) (xy 463.170783 -381.503432)
			(xy 463.182909 -381.448995) (xy 463.202832 -381.396904) (xy 463.230128 -381.348269) (xy 463.264214 -381.304126)
			(xy 463.304363 -381.265417) (xy 463.349721 -381.232966) (xy 463.399321 -381.207465) (xy 463.452105 -381.189458)
			(xy 463.506948 -381.179328) (xy 463.562682 -381.177291) (xy 463.618119 -381.183391) (xy 463.672076 -381.197497)
			(xy 463.689681 -381.204978) (xy 464.315048 -381.204978) (xy 464.315541 -381.17613) (xy 464.324227 -381.119091)
			(xy 464.341412 -381.064014) (xy 464.366703 -381.012157) (xy 464.399522 -380.964704) (xy 464.418934 -380.943358)
			(xy 464.429105 -380.931769) (xy 464.442652 -380.904088) (xy 464.447314 -380.873626) (xy 464.442667 -380.843161)
			(xy 464.429135 -380.815473) (xy 464.418934 -380.803912) (xy 464.399513 -380.782577) (xy 464.366716 -380.735113)
			(xy 464.341441 -380.683251) (xy 464.324264 -380.628174) (xy 464.315577 -380.571139) (xy 464.315048 -380.542292)
			(xy 464.31557 -380.515043) (xy 464.323327 -380.461098) (xy 464.338681 -380.408807) (xy 464.361319 -380.359233)
			(xy 464.390782 -380.313384) (xy 464.42647 -380.272195) (xy 464.467656 -380.236504) (xy 464.513501 -380.207037)
			(xy 464.563073 -380.184393) (xy 464.615363 -380.169034) (xy 464.669307 -380.161273) (xy 464.696556 -380.160784)
			(xy 464.725296 -380.161278) (xy 464.782124 -380.169908) (xy 464.837015 -380.186966) (xy 464.888727 -380.212064)
			(xy 464.936088 -380.244635) (xy 464.957414 -380.263908) (xy 464.968948 -380.27398) (xy 464.996494 -380.287322)
			(xy 465.026756 -380.291907) (xy 465.057018 -380.287322) (xy 465.084564 -380.27398) (xy 465.096098 -380.263908)
			(xy 465.117398 -380.244606) (xy 465.164768 -380.212045) (xy 465.216486 -380.186959) (xy 465.271383 -380.169916)
			(xy 465.328215 -380.161301) (xy 465.356956 -380.160784) (xy 465.384207 -380.161296) (xy 465.438156 -380.169047)
			(xy 465.490453 -380.184397) (xy 465.540032 -380.207034) (xy 465.585885 -380.236496) (xy 465.627078 -380.272185)
			(xy 465.662772 -380.313373) (xy 465.692241 -380.359222) (xy 465.714885 -380.408799) (xy 465.730242 -380.461093)
			(xy 465.738 -380.515041) (xy 465.738464 -380.542292) (xy 465.737949 -380.571139) (xy 465.729268 -380.628177)
			(xy 465.712088 -380.683254) (xy 465.686802 -380.735112) (xy 465.653988 -380.782565) (xy 465.634578 -380.803912)
			(xy 465.624387 -380.815468) (xy 465.610927 -380.843173) (xy 465.606307 -380.873626) (xy 465.610943 -380.904076)
			(xy 465.624416 -380.931774) (xy 465.634578 -380.943358) (xy 465.653987 -380.964704) (xy 465.686785 -381.012165)
			(xy 465.712063 -381.064025) (xy 465.729243 -381.119099) (xy 465.737933 -381.176132) (xy 465.738464 -381.204978)
			(xy 465.738024 -381.232232) (xy 465.730269 -381.286186) (xy 465.714913 -381.338487) (xy 465.69227 -381.38807)
			(xy 465.662801 -381.433926) (xy 465.627104 -381.47512) (xy 465.585908 -381.510814) (xy 465.540051 -381.540281)
			(xy 465.490467 -381.562921) (xy 465.438165 -381.578274) (xy 465.38421 -381.586026) (xy 465.356956 -381.586486)
			(xy 465.328217 -381.585966) (xy 465.271391 -381.577339) (xy 465.216501 -381.560287) (xy 465.164789 -381.535195)
			(xy 465.117426 -381.502631) (xy 465.096098 -381.483362) (xy 465.084564 -381.47329) (xy 465.057018 -381.459948)
			(xy 465.026756 -381.455363) (xy 464.996494 -381.459948) (xy 464.968948 -381.47329) (xy 464.957414 -381.483362)
			(xy 464.936105 -381.502654) (xy 464.888738 -381.535217) (xy 464.837022 -381.560305) (xy 464.782127 -381.577351)
			(xy 464.725296 -381.585968) (xy 464.696556 -381.586486) (xy 464.669303 -381.586063) (xy 464.615352 -381.5783)
			(xy 464.563054 -381.562938) (xy 464.513475 -381.54029) (xy 464.467624 -381.510817) (xy 464.426434 -381.475119)
			(xy 464.390743 -381.433923) (xy 464.361278 -381.388067) (xy 464.338639 -381.338484) (xy 464.323286 -381.286184)
			(xy 464.315532 -381.232231) (xy 464.315048 -381.204978) (xy 463.689681 -381.204978) (xy 463.723405 -381.219309)
			(xy 463.771011 -381.248363) (xy 463.813879 -381.284038) (xy 463.851096 -381.325575) (xy 463.881869 -381.372088)
			(xy 463.905541 -381.422585) (xy 463.921609 -381.475992) (xy 463.929729 -381.531168) (xy 463.930238 -381.559054)
			(xy 463.929729 -381.58694) (xy 463.921609 -381.642116) (xy 463.905541 -381.695523) (xy 463.881869 -381.74602)
			(xy 463.851096 -381.792533) (xy 463.813879 -381.83407) (xy 463.771011 -381.869745) (xy 463.723405 -381.898799)
			(xy 463.672076 -381.920611) (xy 463.618119 -381.934717) (xy 463.562682 -381.940817) (xy 463.506948 -381.93878)
			(xy 463.452105 -381.92865) (xy 463.399321 -381.910643) (xy 463.349721 -381.885142) (xy 463.304363 -381.852691)
			(xy 463.264214 -381.813982) (xy 463.230128 -381.769839) (xy 463.202832 -381.721204) (xy 463.182909 -381.669113)
			(xy 463.170783 -381.614676) (xy 463.166712 -381.559054) (xy 462.193523 -381.559054) (xy 462.180675 -381.587185)
			(xy 462.151209 -381.633035) (xy 462.115518 -381.674226) (xy 462.074327 -381.709917) (xy 462.028477 -381.739383)
			(xy 461.9789 -381.762025) (xy 461.926605 -381.77738) (xy 461.872657 -381.785136) (xy 461.818155 -381.785136)
			(xy 461.764207 -381.77738) (xy 461.711912 -381.762025) (xy 461.662335 -381.739383) (xy 461.616485 -381.709917)
			(xy 461.575294 -381.674226) (xy 461.539603 -381.633035) (xy 461.510137 -381.587185) (xy 461.487495 -381.537608)
			(xy 461.47214 -381.485313) (xy 461.464384 -381.431365) (xy 461.463898 -381.404114) (xy 461.464281 -381.380823)
			(xy 461.470018 -381.334593) (xy 461.475328 -381.311912) (xy 461.476852 -381.305816) (xy 461.476852 -378.391928)
			(xy 460.884016 -377.799346) (xy 440.58459 -377.799346) (xy 440.569594 -377.799879) (xy 440.540892 -377.808587)
			(xy 440.515953 -377.825249) (xy 440.496923 -377.848432) (xy 440.485441 -377.87614) (xy 440.482494 -377.905988)
			(xy 440.488336 -377.935407) (xy 440.502465 -377.961863) (xy 440.512708 -377.972828) (xy 441.833254 -379.29312)
			(xy 454.16216 -379.29312) (xy 454.190134 -379.293695) (xy 454.245387 -379.302494) (xy 454.298587 -379.31982)
			(xy 454.348425 -379.345245) (xy 454.393678 -379.378147) (xy 454.413874 -379.397514) (xy 454.685908 -379.669548)
			(xy 460.297782 -379.669548) (xy 460.301853 -379.613926) (xy 460.313979 -379.559489) (xy 460.333902 -379.507398)
			(xy 460.361198 -379.458763) (xy 460.395284 -379.41462) (xy 460.435433 -379.375911) (xy 460.480791 -379.34346)
			(xy 460.530391 -379.317959) (xy 460.583175 -379.299952) (xy 460.638018 -379.289822) (xy 460.693752 -379.287785)
			(xy 460.749189 -379.293885) (xy 460.803146 -379.307991) (xy 460.854475 -379.329803) (xy 460.902081 -379.358857)
			(xy 460.944949 -379.394532) (xy 460.982166 -379.436069) (xy 461.012939 -379.482582) (xy 461.036611 -379.533079)
			(xy 461.052679 -379.586486) (xy 461.060799 -379.641662) (xy 461.061308 -379.669548) (xy 461.060799 -379.697434)
			(xy 461.052679 -379.75261) (xy 461.036611 -379.806017) (xy 461.012939 -379.856514) (xy 460.982166 -379.903027)
			(xy 460.944949 -379.944564) (xy 460.902081 -379.980239) (xy 460.854475 -380.009293) (xy 460.803146 -380.031105)
			(xy 460.749189 -380.045211) (xy 460.693752 -380.051311) (xy 460.638018 -380.049274) (xy 460.583175 -380.039144)
			(xy 460.530391 -380.021137) (xy 460.480791 -379.995636) (xy 460.435433 -379.963185) (xy 460.395284 -379.924476)
			(xy 460.361198 -379.880333) (xy 460.333902 -379.831698) (xy 460.313979 -379.779607) (xy 460.301853 -379.72517)
			(xy 460.297782 -379.669548) (xy 454.685908 -379.669548) (xy 456.324208 -381.307848) (xy 456.343582 -381.328024)
			(xy 456.376432 -381.373295) (xy 456.401801 -381.423145) (xy 456.419064 -381.476348) (xy 456.427799 -381.531595)
			(xy 456.428348 -381.559562) (xy 456.428348 -382.32842) (xy 456.932282 -382.32842) (xy 456.936353 -382.272798)
			(xy 456.948479 -382.218361) (xy 456.968402 -382.16627) (xy 456.995698 -382.117635) (xy 457.029784 -382.073492)
			(xy 457.069933 -382.034783) (xy 457.115291 -382.002332) (xy 457.164891 -381.976831) (xy 457.217675 -381.958824)
			(xy 457.272518 -381.948694) (xy 457.328252 -381.946657) (xy 457.383689 -381.952757) (xy 457.437646 -381.966863)
			(xy 457.488975 -381.988675) (xy 457.536581 -382.017729) (xy 457.579449 -382.053404) (xy 457.616666 -382.094941)
			(xy 457.647439 -382.141454) (xy 457.671111 -382.191951) (xy 457.687179 -382.245358) (xy 457.695299 -382.300534)
			(xy 457.695808 -382.32842) (xy 457.695299 -382.356306) (xy 457.687179 -382.411482) (xy 457.678163 -382.44145)
			(xy 458.634082 -382.44145) (xy 458.638153 -382.385828) (xy 458.650279 -382.331391) (xy 458.670202 -382.2793)
			(xy 458.697498 -382.230665) (xy 458.731584 -382.186522) (xy 458.771733 -382.147813) (xy 458.817091 -382.115362)
			(xy 458.866691 -382.089861) (xy 458.919475 -382.071854) (xy 458.974318 -382.061724) (xy 459.030052 -382.059687)
			(xy 459.085489 -382.065787) (xy 459.139446 -382.079893) (xy 459.190775 -382.101705) (xy 459.238381 -382.130759)
			(xy 459.281249 -382.166434) (xy 459.318466 -382.207971) (xy 459.349239 -382.254484) (xy 459.372911 -382.304981)
			(xy 459.388979 -382.358388) (xy 459.389017 -382.358646) (xy 459.737458 -382.358646) (xy 459.741529 -382.303024)
			(xy 459.753655 -382.248587) (xy 459.773578 -382.196496) (xy 459.800874 -382.147861) (xy 459.83496 -382.103718)
			(xy 459.875109 -382.065009) (xy 459.920467 -382.032558) (xy 459.970067 -382.007057) (xy 460.022851 -381.98905)
			(xy 460.077694 -381.97892) (xy 460.133428 -381.976883) (xy 460.188865 -381.982983) (xy 460.242822 -381.997089)
			(xy 460.294151 -382.018901) (xy 460.341757 -382.047955) (xy 460.384625 -382.08363) (xy 460.421842 -382.125167)
			(xy 460.452615 -382.17168) (xy 460.476287 -382.222177) (xy 460.492355 -382.275584) (xy 460.500475 -382.33076)
			(xy 460.500984 -382.358646) (xy 460.500475 -382.386532) (xy 460.492355 -382.441708) (xy 460.476287 -382.495115)
			(xy 460.452615 -382.545612) (xy 460.421842 -382.592125) (xy 460.384625 -382.633662) (xy 460.341757 -382.669337)
			(xy 460.294151 -382.698391) (xy 460.242822 -382.720203) (xy 460.188865 -382.734309) (xy 460.133428 -382.740409)
			(xy 460.077694 -382.738372) (xy 460.022851 -382.728242) (xy 459.970067 -382.710235) (xy 459.920467 -382.684734)
			(xy 459.875109 -382.652283) (xy 459.83496 -382.613574) (xy 459.800874 -382.569431) (xy 459.773578 -382.520796)
			(xy 459.753655 -382.468705) (xy 459.741529 -382.414268) (xy 459.737458 -382.358646) (xy 459.389017 -382.358646)
			(xy 459.397099 -382.413564) (xy 459.397608 -382.44145) (xy 459.397099 -382.469336) (xy 459.388979 -382.524512)
			(xy 459.372911 -382.577919) (xy 459.349239 -382.628416) (xy 459.318466 -382.674929) (xy 459.281249 -382.716466)
			(xy 459.238381 -382.752141) (xy 459.190775 -382.781195) (xy 459.139446 -382.803007) (xy 459.085489 -382.817113)
			(xy 459.030052 -382.823213) (xy 458.974318 -382.821176) (xy 458.919475 -382.811046) (xy 458.866691 -382.793039)
			(xy 458.817091 -382.767538) (xy 458.771733 -382.735087) (xy 458.731584 -382.696378) (xy 458.697498 -382.652235)
			(xy 458.670202 -382.6036) (xy 458.650279 -382.551509) (xy 458.638153 -382.497072) (xy 458.634082 -382.44145)
			(xy 457.678163 -382.44145) (xy 457.671111 -382.464889) (xy 457.647439 -382.515386) (xy 457.616666 -382.561899)
			(xy 457.579449 -382.603436) (xy 457.536581 -382.639111) (xy 457.488975 -382.668165) (xy 457.437646 -382.689977)
			(xy 457.383689 -382.704083) (xy 457.328252 -382.710183) (xy 457.272518 -382.708146) (xy 457.217675 -382.698016)
			(xy 457.164891 -382.680009) (xy 457.115291 -382.654508) (xy 457.069933 -382.622057) (xy 457.029784 -382.583348)
			(xy 456.995698 -382.539205) (xy 456.968402 -382.49057) (xy 456.948479 -382.438479) (xy 456.936353 -382.384042)
			(xy 456.932282 -382.32842) (xy 456.428348 -382.32842) (xy 456.428348 -383.004314) (xy 460.372458 -383.004314)
			(xy 460.376529 -382.948692) (xy 460.388655 -382.894255) (xy 460.408578 -382.842164) (xy 460.435874 -382.793529)
			(xy 460.46996 -382.749386) (xy 460.510109 -382.710677) (xy 460.555467 -382.678226) (xy 460.605067 -382.652725)
			(xy 460.657851 -382.634718) (xy 460.712694 -382.624588) (xy 460.768428 -382.622551) (xy 460.823865 -382.628651)
			(xy 460.877822 -382.642757) (xy 460.929151 -382.664569) (xy 460.976757 -382.693623) (xy 461.019625 -382.729298)
			(xy 461.056842 -382.770835) (xy 461.087615 -382.817348) (xy 461.111287 -382.867845) (xy 461.127355 -382.921252)
			(xy 461.135475 -382.976428) (xy 461.135984 -383.004314) (xy 461.135475 -383.0322) (xy 461.127355 -383.087376)
			(xy 461.111287 -383.140783) (xy 461.087615 -383.19128) (xy 461.056842 -383.237793) (xy 461.019625 -383.27933)
			(xy 460.976757 -383.315005) (xy 460.929151 -383.344059) (xy 460.877822 -383.365871) (xy 460.823865 -383.379977)
			(xy 460.768428 -383.386077) (xy 460.712694 -383.38404) (xy 460.657851 -383.37391) (xy 460.605067 -383.355903)
			(xy 460.555467 -383.330402) (xy 460.510109 -383.297951) (xy 460.46996 -383.259242) (xy 460.435874 -383.215099)
			(xy 460.408578 -383.166464) (xy 460.388655 -383.114373) (xy 460.376529 -383.059936) (xy 460.372458 -383.004314)
			(xy 456.428348 -383.004314) (xy 456.428348 -387.143752) (xy 456.431396 -387.152134) (xy 456.441905 -387.183354)
			(xy 456.453275 -387.248233) (xy 456.454002 -387.281166) (xy 456.453516 -387.308417) (xy 456.44576 -387.362365)
			(xy 456.430405 -387.41466) (xy 456.407763 -387.464237) (xy 456.378297 -387.510087) (xy 456.342606 -387.551278)
			(xy 456.301415 -387.586969) (xy 456.255565 -387.616435) (xy 456.205988 -387.639077) (xy 456.153693 -387.654432)
			(xy 456.099745 -387.662188) (xy 456.045243 -387.662188) (xy 455.991295 -387.654432) (xy 455.939 -387.639077)
			(xy 455.889423 -387.616435) (xy 455.843573 -387.586969) (xy 455.802382 -387.551278) (xy 455.766691 -387.510087)
			(xy 455.737225 -387.464237) (xy 455.714583 -387.41466) (xy 455.699228 -387.362365) (xy 455.691472 -387.308417)
			(xy 455.690986 -387.281166) (xy 455.691696 -387.248231) (xy 455.703057 -387.183347) (xy 455.713592 -387.152134)
			(xy 455.71664 -387.143752) (xy 455.71664 -381.707136) (xy 454.014586 -380.005336) (xy 441.68568 -380.005336)
			(xy 441.657704 -380.004764) (xy 441.602447 -379.995972) (xy 441.549242 -379.978653) (xy 441.499396 -379.953233)
			(xy 441.454135 -379.920338) (xy 441.433966 -379.900942) (xy 439.33237 -377.799346) (xy 433.923694 -377.799346)
			(xy 433.908708 -377.814332) (xy 433.196492 -378.526548) (xy 438.052462 -378.526548) (xy 438.056533 -378.470926)
			(xy 438.068659 -378.416489) (xy 438.088582 -378.364398) (xy 438.115878 -378.315763) (xy 438.149964 -378.27162)
			(xy 438.190113 -378.232911) (xy 438.235471 -378.20046) (xy 438.285071 -378.174959) (xy 438.337855 -378.156952)
			(xy 438.392698 -378.146822) (xy 438.448432 -378.144785) (xy 438.503869 -378.150885) (xy 438.557826 -378.164991)
			(xy 438.609155 -378.186803) (xy 438.656761 -378.215857) (xy 438.699629 -378.251532) (xy 438.736846 -378.293069)
			(xy 438.767619 -378.339582) (xy 438.791291 -378.390079) (xy 438.807359 -378.443486) (xy 438.815479 -378.498662)
			(xy 438.815988 -378.526548) (xy 438.815479 -378.554434) (xy 438.807359 -378.60961) (xy 438.791291 -378.663017)
			(xy 438.767619 -378.713514) (xy 438.736846 -378.760027) (xy 438.699629 -378.801564) (xy 438.656761 -378.837239)
			(xy 438.609155 -378.866293) (xy 438.557826 -378.888105) (xy 438.503869 -378.902211) (xy 438.448432 -378.908311)
			(xy 438.392698 -378.906274) (xy 438.337855 -378.896144) (xy 438.285071 -378.878137) (xy 438.235471 -378.852636)
			(xy 438.190113 -378.820185) (xy 438.149964 -378.781476) (xy 438.115878 -378.737333) (xy 438.088582 -378.688698)
			(xy 438.068659 -378.636607) (xy 438.056533 -378.58217) (xy 438.052462 -378.526548) (xy 433.196492 -378.526548)
			(xy 432.645058 -379.077982) (xy 432.645058 -380.05258) (xy 438.059828 -380.05258) (xy 438.063899 -379.996958)
			(xy 438.076025 -379.942521) (xy 438.095948 -379.89043) (xy 438.123244 -379.841795) (xy 438.15733 -379.797652)
			(xy 438.197479 -379.758943) (xy 438.242837 -379.726492) (xy 438.292437 -379.700991) (xy 438.345221 -379.682984)
			(xy 438.400064 -379.672854) (xy 438.455798 -379.670817) (xy 438.511235 -379.676917) (xy 438.565192 -379.691023)
			(xy 438.616521 -379.712835) (xy 438.664127 -379.741889) (xy 438.706995 -379.777564) (xy 438.744212 -379.819101)
			(xy 438.774985 -379.865614) (xy 438.798657 -379.916111) (xy 438.814725 -379.969518) (xy 438.822845 -380.024694)
			(xy 438.823354 -380.05258) (xy 438.822845 -380.080466) (xy 438.814725 -380.135642) (xy 438.798657 -380.189049)
			(xy 438.774985 -380.239546) (xy 438.744212 -380.286059) (xy 438.706995 -380.327596) (xy 438.664127 -380.363271)
			(xy 438.616521 -380.392325) (xy 438.565192 -380.414137) (xy 438.511235 -380.428243) (xy 438.455798 -380.434343)
			(xy 438.400064 -380.432306) (xy 438.345221 -380.422176) (xy 438.292437 -380.404169) (xy 438.242837 -380.378668)
			(xy 438.197479 -380.346217) (xy 438.15733 -380.307508) (xy 438.123244 -380.263365) (xy 438.095948 -380.21473)
			(xy 438.076025 -380.162639) (xy 438.063899 -380.108202) (xy 438.059828 -380.05258) (xy 432.645058 -380.05258)
			(xy 432.645058 -380.807468) (xy 432.645509 -380.820935) (xy 432.652627 -380.846914) (xy 432.666297 -380.870124)
			(xy 432.685564 -380.888948) (xy 432.709086 -380.902072) (xy 432.735224 -380.908584) (xy 432.762155 -380.908027)
			(xy 432.788001 -380.900442) (xy 432.799744 -380.893828) (xy 432.822391 -380.880439) (xy 432.870583 -380.859333)
			(xy 432.921218 -380.845052) (xy 432.973336 -380.837866) (xy 432.999642 -380.83744) (xy 433.026888 -380.837929)
			(xy 433.080824 -380.845689) (xy 433.133107 -380.861046) (xy 433.182673 -380.883687) (xy 433.228512 -380.913151)
			(xy 433.269692 -380.948838) (xy 433.305375 -380.990021) (xy 433.334833 -381.035864) (xy 433.357468 -381.085432)
			(xy 433.37282 -381.137717) (xy 433.380574 -381.191654) (xy 433.380574 -381.246146) (xy 433.37282 -381.300083)
			(xy 433.357468 -381.352368) (xy 433.334833 -381.401936) (xy 433.305375 -381.447779) (xy 433.269692 -381.488962)
			(xy 433.228512 -381.524649) (xy 433.182673 -381.554113) (xy 433.133107 -381.576754) (xy 433.080824 -381.592111)
			(xy 433.026888 -381.599871) (xy 432.999642 -381.600456) (xy 432.973336 -381.600032) (xy 432.921219 -381.592841)
			(xy 432.870583 -381.578561) (xy 432.822388 -381.557463) (xy 432.799744 -381.544068) (xy 432.788042 -381.537389)
			(xy 432.762191 -381.529824) (xy 432.735261 -381.529284) (xy 432.709128 -381.535809) (xy 432.685612 -381.548943)
			(xy 432.666351 -381.567772) (xy 432.652686 -381.590983) (xy 432.64557 -381.616962) (xy 432.645058 -381.630428)
			(xy 432.645058 -382.524553) (xy 437.679785 -382.524553) (xy 437.679785 -382.470047) (xy 437.687543 -382.416096)
			(xy 437.7029 -382.363799) (xy 437.725544 -382.31422) (xy 437.755014 -382.268368) (xy 437.79071 -382.227177)
			(xy 437.831905 -382.191487) (xy 437.87776 -382.162022) (xy 437.927342 -382.139384) (xy 437.979641 -382.124033)
			(xy 438.033593 -382.116282) (xy 438.060846 -382.115822) (xy 438.090076 -382.11638) (xy 438.147851 -382.125317)
			(xy 438.203586 -382.142959) (xy 438.25598 -382.168894) (xy 438.303805 -382.202516) (xy 438.345945 -382.243038)
			(xy 438.364122 -382.265936) (xy 438.37256 -382.276333) (xy 438.393764 -382.29267) (xy 438.418483 -382.302943)
			(xy 438.445021 -382.306448) (xy 438.471559 -382.302943) (xy 438.496278 -382.29267) (xy 438.517482 -382.276333)
			(xy 438.52592 -382.265936) (xy 438.544107 -382.243043) (xy 438.586231 -382.2025) (xy 438.634051 -382.168863)
			(xy 438.686444 -382.14292) (xy 438.742184 -382.125279) (xy 438.799964 -382.116353) (xy 438.829196 -382.115822)
			(xy 438.856451 -382.116225) (xy 438.910407 -382.123982) (xy 438.962709 -382.139339) (xy 439.012294 -382.161983)
			(xy 439.058151 -382.191453) (xy 439.099348 -382.227149) (xy 439.135045 -382.268346) (xy 439.164515 -382.314203)
			(xy 439.18716 -382.363787) (xy 439.202517 -382.416089) (xy 439.210275 -382.470045) (xy 439.210275 -382.524555)
			(xy 439.202517 -382.578511) (xy 439.18716 -382.630813) (xy 439.164515 -382.680397) (xy 439.135045 -382.726254)
			(xy 439.099348 -382.767451) (xy 439.058151 -382.803147) (xy 439.012294 -382.832617) (xy 438.962709 -382.855261)
			(xy 438.910407 -382.870618) (xy 438.856451 -382.878375) (xy 438.829196 -382.878838) (xy 438.799966 -382.878266)
			(xy 438.742192 -382.869334) (xy 438.686456 -382.851696) (xy 438.634062 -382.825763) (xy 438.586236 -382.792143)
			(xy 438.544097 -382.751622) (xy 438.52592 -382.728724) (xy 438.517509 -382.718283) (xy 438.496323 -382.701865)
			(xy 438.471591 -382.691536) (xy 438.445021 -382.688012) (xy 438.418451 -382.691536) (xy 438.393719 -382.701865)
			(xy 438.372533 -382.718283) (xy 438.364122 -382.728724) (xy 438.345962 -382.751639) (xy 438.303829 -382.792173)
			(xy 438.256003 -382.825801) (xy 438.203604 -382.851735) (xy 438.14786 -382.869367) (xy 438.090079 -382.878283)
			(xy 438.060846 -382.878838) (xy 438.033593 -382.878318) (xy 437.979641 -382.870567) (xy 437.927342 -382.855216)
			(xy 437.87776 -382.832578) (xy 437.831905 -382.803113) (xy 437.79071 -382.767423) (xy 437.755014 -382.726232)
			(xy 437.725544 -382.68038) (xy 437.7029 -382.630801) (xy 437.687543 -382.578504) (xy 437.679785 -382.524553)
			(xy 432.645058 -382.524553) (xy 432.645058 -382.903853) (xy 442.76693 -382.903853) (xy 442.76693 -382.849347)
			(xy 442.774686 -382.795396) (xy 442.790041 -382.743098) (xy 442.812682 -382.693518) (xy 442.842148 -382.647664)
			(xy 442.87784 -382.606469) (xy 442.91903 -382.570773) (xy 442.964881 -382.541302) (xy 443.014459 -382.518656)
			(xy 443.066755 -382.503295) (xy 443.120705 -382.495533) (xy 443.147958 -382.495044) (xy 443.176875 -382.495576)
			(xy 443.234046 -382.5043) (xy 443.289245 -382.521554) (xy 443.341207 -382.546943) (xy 443.388742 -382.579885)
			(xy 443.430758 -382.619625) (xy 443.448948 -382.64211) (xy 443.458845 -382.653915) (xy 443.484169 -382.671434)
			(xy 443.513562 -382.68061) (xy 443.544354 -382.68061) (xy 443.573747 -382.671434) (xy 443.599071 -382.653915)
			(xy 443.608968 -382.64211) (xy 443.62718 -382.619644) (xy 443.669195 -382.579907) (xy 443.716725 -382.546966)
			(xy 443.768683 -382.521574) (xy 443.823877 -382.504314) (xy 443.881043 -382.495581) (xy 443.909958 -382.495044)
			(xy 443.937209 -382.4956) (xy 443.991158 -382.503351) (xy 444.043454 -382.518702) (xy 444.093034 -382.541339)
			(xy 444.138886 -382.570802) (xy 444.180079 -382.606492) (xy 444.215772 -382.64768) (xy 444.245241 -382.69353)
			(xy 444.267883 -382.743106) (xy 444.28324 -382.795401) (xy 444.290997 -382.849349) (xy 444.290997 -382.903851)
			(xy 444.28324 -382.957799) (xy 444.267883 -383.010094) (xy 444.245241 -383.05967) (xy 444.215772 -383.10552)
			(xy 444.180079 -383.146708) (xy 444.138886 -383.182398) (xy 444.093034 -383.211861) (xy 444.043454 -383.234498)
			(xy 443.991158 -383.249849) (xy 443.937209 -383.2576) (xy 443.909958 -383.25806) (xy 443.881042 -383.257515)
			(xy 443.823871 -383.248794) (xy 443.768672 -383.231542) (xy 443.71671 -383.206156) (xy 443.669176 -383.173216)
			(xy 443.627158 -383.133478) (xy 443.608968 -383.110994) (xy 443.599071 -383.099189) (xy 443.573747 -383.08167)
			(xy 443.544354 -383.072494) (xy 443.513562 -383.072494) (xy 443.484169 -383.08167) (xy 443.458845 -383.099189)
			(xy 443.448948 -383.110994) (xy 443.430728 -383.133453) (xy 443.388715 -383.17319) (xy 443.341186 -383.206132)
			(xy 443.28923 -383.231525) (xy 443.234038 -383.248786) (xy 443.176872 -383.257522) (xy 443.147958 -383.25806)
			(xy 443.120705 -383.257667) (xy 443.066755 -383.249905) (xy 443.014459 -383.234544) (xy 442.964881 -383.211898)
			(xy 442.91903 -383.182427) (xy 442.87784 -383.146731) (xy 442.842148 -383.105536) (xy 442.812682 -383.059682)
			(xy 442.790041 -383.010102) (xy 442.774686 -382.957804) (xy 442.76693 -382.903853) (xy 432.645058 -382.903853)
			(xy 432.645058 -384.569253) (xy 437.679785 -384.569253) (xy 437.679785 -384.514747) (xy 437.687543 -384.460796)
			(xy 437.7029 -384.408499) (xy 437.725544 -384.35892) (xy 437.755014 -384.313068) (xy 437.79071 -384.271877)
			(xy 437.831905 -384.236187) (xy 437.87776 -384.206722) (xy 437.927342 -384.184084) (xy 437.979641 -384.168733)
			(xy 438.033593 -384.160982) (xy 438.060846 -384.160522) (xy 438.090076 -384.16108) (xy 438.147851 -384.170017)
			(xy 438.203586 -384.187659) (xy 438.25598 -384.213594) (xy 438.303805 -384.247216) (xy 438.345945 -384.287738)
			(xy 438.364122 -384.310636) (xy 438.37256 -384.321033) (xy 438.393764 -384.33737) (xy 438.418483 -384.347643)
			(xy 438.445021 -384.351148) (xy 438.471559 -384.347643) (xy 438.496278 -384.33737) (xy 438.517482 -384.321033)
			(xy 438.52592 -384.310636) (xy 438.544107 -384.287743) (xy 438.586231 -384.2472) (xy 438.634051 -384.213563)
			(xy 438.686444 -384.18762) (xy 438.742184 -384.169979) (xy 438.799964 -384.161053) (xy 438.829196 -384.160522)
			(xy 438.856451 -384.160925) (xy 438.910407 -384.168682) (xy 438.962709 -384.184039) (xy 439.012294 -384.206683)
			(xy 439.058151 -384.236153) (xy 439.099348 -384.271849) (xy 439.135045 -384.313046) (xy 439.164515 -384.358903)
			(xy 439.18716 -384.408487) (xy 439.202517 -384.460789) (xy 439.210275 -384.514745) (xy 439.210275 -384.569255)
			(xy 439.202517 -384.623211) (xy 439.18716 -384.675513) (xy 439.164515 -384.725097) (xy 439.135045 -384.770954)
			(xy 439.099348 -384.812151) (xy 439.058151 -384.847847) (xy 439.012294 -384.877317) (xy 438.962709 -384.899961)
			(xy 438.910407 -384.915318) (xy 438.856451 -384.923075) (xy 438.829196 -384.923538) (xy 438.799966 -384.922966)
			(xy 438.742192 -384.914034) (xy 438.686456 -384.896396) (xy 438.634062 -384.870463) (xy 438.586236 -384.836843)
			(xy 438.544097 -384.796322) (xy 438.52592 -384.773424) (xy 438.517509 -384.762983) (xy 438.496323 -384.746565)
			(xy 438.471591 -384.736236) (xy 438.445021 -384.732712) (xy 438.418451 -384.736236) (xy 438.393719 -384.746565)
			(xy 438.372533 -384.762983) (xy 438.364122 -384.773424) (xy 438.345962 -384.796339) (xy 438.303829 -384.836873)
			(xy 438.256003 -384.870501) (xy 438.203604 -384.896435) (xy 438.14786 -384.914067) (xy 438.090079 -384.922983)
			(xy 438.060846 -384.923538) (xy 438.033593 -384.923018) (xy 437.979641 -384.915267) (xy 437.927342 -384.899916)
			(xy 437.87776 -384.877278) (xy 437.831905 -384.847813) (xy 437.79071 -384.812123) (xy 437.755014 -384.770932)
			(xy 437.725544 -384.72508) (xy 437.7029 -384.675501) (xy 437.687543 -384.623204) (xy 437.679785 -384.569253)
			(xy 432.645058 -384.569253) (xy 432.645058 -385.760468) (xy 432.645509 -385.773935) (xy 432.652627 -385.799914)
			(xy 432.666297 -385.823124) (xy 432.685564 -385.841948) (xy 432.709086 -385.855072) (xy 432.735224 -385.861584)
			(xy 432.762155 -385.861027) (xy 432.788001 -385.853442) (xy 432.799744 -385.846828) (xy 432.822391 -385.833439)
			(xy 432.870583 -385.812333) (xy 432.921218 -385.798052) (xy 432.973336 -385.790866) (xy 432.999642 -385.79044)
			(xy 433.026888 -385.790929) (xy 433.080824 -385.798689) (xy 433.133107 -385.814046) (xy 433.182673 -385.836687)
			(xy 433.228512 -385.866151) (xy 433.269692 -385.901838) (xy 433.305375 -385.943021) (xy 433.334833 -385.988864)
			(xy 433.357468 -386.038432) (xy 433.37282 -386.090717) (xy 433.380574 -386.144654) (xy 433.380574 -386.199146)
			(xy 433.37282 -386.253083) (xy 433.357468 -386.305368) (xy 433.337608 -386.348858) (xy 438.101609 -386.348858)
			(xy 438.101609 -386.294342) (xy 438.109368 -386.240381) (xy 438.124728 -386.188074) (xy 438.147376 -386.138485)
			(xy 438.176851 -386.092624) (xy 438.212554 -386.051425) (xy 438.253756 -386.015727) (xy 438.29962 -385.986257)
			(xy 438.349211 -385.963614) (xy 438.40152 -385.94826) (xy 438.455482 -385.940506) (xy 438.48274 -385.940046)
			(xy 438.511656 -385.94059) (xy 438.568827 -385.949311) (xy 438.624026 -385.966563) (xy 438.675988 -385.991949)
			(xy 438.723523 -386.024889) (xy 438.76554 -386.064628) (xy 438.78373 -386.087112) (xy 438.793627 -386.098917)
			(xy 438.818951 -386.116436) (xy 438.848344 -386.125612) (xy 438.879136 -386.125612) (xy 438.908529 -386.116436)
			(xy 438.933853 -386.098917) (xy 438.94375 -386.087112) (xy 438.960503 -386.066329) (xy 438.998857 -386.029199)
			(xy 439.042011 -385.997777) (xy 439.089125 -385.972678) (xy 439.139277 -385.954392) (xy 439.191488 -385.943275)
			(xy 439.24474 -385.939545) (xy 439.297992 -385.943275) (xy 439.350203 -385.954392) (xy 439.400355 -385.972678)
			(xy 439.447469 -385.997777) (xy 439.490623 -386.029199) (xy 439.528977 -386.066329) (xy 439.54573 -386.087112)
			(xy 439.555627 -386.098917) (xy 439.580951 -386.116436) (xy 439.610344 -386.125612) (xy 439.641136 -386.125612)
			(xy 439.670529 -386.116436) (xy 439.695853 -386.098917) (xy 439.70575 -386.087112) (xy 439.722503 -386.066329)
			(xy 439.760857 -386.029199) (xy 439.804011 -385.997777) (xy 439.851125 -385.972678) (xy 439.901277 -385.954392)
			(xy 439.953488 -385.943275) (xy 440.00674 -385.939545) (xy 440.059992 -385.943275) (xy 440.112203 -385.954392)
			(xy 440.162355 -385.972678) (xy 440.209469 -385.997777) (xy 440.252623 -386.029199) (xy 440.290977 -386.066329)
			(xy 440.30773 -386.087112) (xy 440.317627 -386.098917) (xy 440.342951 -386.116436) (xy 440.372344 -386.125612)
			(xy 440.403136 -386.125612) (xy 440.432529 -386.116436) (xy 440.457853 -386.098917) (xy 440.46775 -386.087112)
			(xy 440.485972 -386.064655) (xy 440.527985 -386.024918) (xy 440.575513 -385.991975) (xy 440.627469 -385.966582)
			(xy 440.682661 -385.94932) (xy 440.739826 -385.940585) (xy 440.76874 -385.940046) (xy 440.795986 -385.940627)
			(xy 440.849923 -385.948387) (xy 440.902206 -385.963744) (xy 440.951773 -385.986384) (xy 440.997612 -386.015848)
			(xy 441.038793 -386.051535) (xy 441.074476 -386.09272) (xy 441.103935 -386.138563) (xy 441.12657 -386.188131)
			(xy 441.141921 -386.240416) (xy 441.149676 -386.294354) (xy 441.149676 -386.348846) (xy 441.141921 -386.402784)
			(xy 441.12657 -386.455069) (xy 441.103935 -386.504637) (xy 441.074476 -386.55048) (xy 441.038793 -386.591665)
			(xy 440.997612 -386.627352) (xy 440.951773 -386.656816) (xy 440.902206 -386.679456) (xy 440.849923 -386.694813)
			(xy 440.795986 -386.702573) (xy 440.76874 -386.703062) (xy 440.739823 -386.702529) (xy 440.682652 -386.693805)
			(xy 440.627453 -386.676551) (xy 440.575491 -386.651162) (xy 440.527957 -386.618221) (xy 440.48594 -386.578481)
			(xy 440.46775 -386.555996) (xy 440.457853 -386.544191) (xy 440.432529 -386.526672) (xy 440.403136 -386.517496)
			(xy 440.372344 -386.517496) (xy 440.342951 -386.526672) (xy 440.317627 -386.544191) (xy 440.30773 -386.555996)
			(xy 440.290977 -386.576779) (xy 440.252623 -386.613909) (xy 440.209469 -386.645331) (xy 440.162355 -386.67043)
			(xy 440.112203 -386.688716) (xy 440.059992 -386.699833) (xy 440.00674 -386.703563) (xy 439.953488 -386.699833)
			(xy 439.901277 -386.688716) (xy 439.851125 -386.67043) (xy 439.804011 -386.645331) (xy 439.760857 -386.613909)
			(xy 439.722503 -386.576779) (xy 439.70575 -386.555996) (xy 439.695853 -386.544191) (xy 439.670529 -386.526672)
			(xy 439.641136 -386.517496) (xy 439.610344 -386.517496) (xy 439.580951 -386.526672) (xy 439.555627 -386.544191)
			(xy 439.54573 -386.555996) (xy 439.528977 -386.576779) (xy 439.490623 -386.613909) (xy 439.447469 -386.645331)
			(xy 439.400355 -386.67043) (xy 439.350203 -386.688716) (xy 439.297992 -386.699833) (xy 439.24474 -386.703563)
			(xy 439.191488 -386.699833) (xy 439.139277 -386.688716) (xy 439.089125 -386.67043) (xy 439.042011 -386.645331)
			(xy 438.998857 -386.613909) (xy 438.960503 -386.576779) (xy 438.94375 -386.555996) (xy 438.933853 -386.544191)
			(xy 438.908529 -386.526672) (xy 438.879136 -386.517496) (xy 438.848344 -386.517496) (xy 438.818951 -386.526672)
			(xy 438.793627 -386.544191) (xy 438.78373 -386.555996) (xy 438.765521 -386.578464) (xy 438.723505 -386.618201)
			(xy 438.675974 -386.651142) (xy 438.624016 -386.676533) (xy 438.568822 -386.693792) (xy 438.511655 -386.702525)
			(xy 438.48274 -386.703062) (xy 438.455482 -386.702694) (xy 438.40152 -386.69494) (xy 438.349211 -386.679586)
			(xy 438.29962 -386.656943) (xy 438.253756 -386.627473) (xy 438.212554 -386.591775) (xy 438.176851 -386.550576)
			(xy 438.147376 -386.504715) (xy 438.124728 -386.455126) (xy 438.109368 -386.402819) (xy 438.101609 -386.348858)
			(xy 433.337608 -386.348858) (xy 433.334833 -386.354936) (xy 433.305375 -386.400779) (xy 433.269692 -386.441962)
			(xy 433.228512 -386.477649) (xy 433.182673 -386.507113) (xy 433.133107 -386.529754) (xy 433.080824 -386.545111)
			(xy 433.026888 -386.552871) (xy 432.999642 -386.553456) (xy 432.973336 -386.553032) (xy 432.921219 -386.545841)
			(xy 432.870583 -386.531561) (xy 432.822388 -386.510463) (xy 432.799744 -386.497068) (xy 432.788042 -386.490389)
			(xy 432.762191 -386.482824) (xy 432.735261 -386.482284) (xy 432.709128 -386.488809) (xy 432.685612 -386.501943)
			(xy 432.666351 -386.520772) (xy 432.652686 -386.543983) (xy 432.64557 -386.569962) (xy 432.645058 -386.583428)
			(xy 432.645058 -387.371153) (xy 442.672159 -387.371153) (xy 442.672159 -387.316647) (xy 442.679917 -387.262695)
			(xy 442.695273 -387.210396) (xy 442.717917 -387.160816) (xy 442.747386 -387.114962) (xy 442.783081 -387.07377)
			(xy 442.824275 -387.038076) (xy 442.87013 -387.008609) (xy 442.919711 -386.985968) (xy 442.972011 -386.970613)
			(xy 443.025963 -386.962858) (xy 443.053216 -386.962396) (xy 443.082132 -386.962938) (xy 443.139304 -386.971657)
			(xy 443.194504 -386.988908) (xy 443.246467 -387.014295) (xy 443.294001 -387.047236) (xy 443.336017 -387.086977)
			(xy 443.354206 -387.109462) (xy 443.364103 -387.121267) (xy 443.389427 -387.138786) (xy 443.41882 -387.147962)
			(xy 443.449612 -387.147962) (xy 443.479005 -387.138786) (xy 443.504329 -387.121267) (xy 443.514226 -387.109462)
			(xy 443.532393 -387.086958) (xy 443.574419 -387.047226) (xy 443.621959 -387.01429) (xy 443.673925 -386.988906)
			(xy 443.729126 -386.971654) (xy 443.786299 -386.962929) (xy 443.815216 -386.962396) (xy 443.842467 -386.962875)
			(xy 443.896413 -386.970633) (xy 443.948707 -386.98599) (xy 443.998282 -387.008632) (xy 444.044131 -387.038099)
			(xy 444.08532 -387.073791) (xy 444.12101 -387.114981) (xy 444.150475 -387.160832) (xy 444.173116 -387.210408)
			(xy 444.18847 -387.262702) (xy 444.196226 -387.316649) (xy 444.196226 -387.371151) (xy 444.18847 -387.425098)
			(xy 444.173116 -387.477392) (xy 444.150475 -387.526968) (xy 444.12101 -387.572819) (xy 444.08532 -387.614009)
			(xy 444.044131 -387.649701) (xy 443.998282 -387.679168) (xy 443.948707 -387.70181) (xy 443.896413 -387.717167)
			(xy 443.842467 -387.724925) (xy 443.815216 -387.725412) (xy 443.786298 -387.724916) (xy 443.729124 -387.716187)
			(xy 443.673923 -387.698927) (xy 443.621961 -387.673531) (xy 443.574428 -387.640582) (xy 443.532414 -387.600835)
			(xy 443.514226 -387.578346) (xy 443.504329 -387.566541) (xy 443.479005 -387.549022) (xy 443.449612 -387.539846)
			(xy 443.41882 -387.539846) (xy 443.389427 -387.549022) (xy 443.364103 -387.566541) (xy 443.354206 -387.578346)
			(xy 443.336023 -387.600836) (xy 443.294 -387.640569) (xy 443.246463 -387.673506) (xy 443.194501 -387.698893)
			(xy 443.139302 -387.716148) (xy 443.082132 -387.724877) (xy 443.053216 -387.725412) (xy 443.025963 -387.724942)
			(xy 442.972011 -387.717187) (xy 442.919711 -387.701832) (xy 442.87013 -387.679191) (xy 442.824275 -387.649724)
			(xy 442.783081 -387.61403) (xy 442.747386 -387.572838) (xy 442.717917 -387.526984) (xy 442.695273 -387.477404)
			(xy 442.679917 -387.425105) (xy 442.672159 -387.371153) (xy 432.645058 -387.371153) (xy 432.645058 -388.760253)
			(xy 438.101685 -388.760253) (xy 438.101685 -388.705747) (xy 438.109443 -388.651797) (xy 438.1248 -388.5995)
			(xy 438.147443 -388.549921) (xy 438.176913 -388.50407) (xy 438.212608 -388.46288) (xy 438.253802 -388.427189)
			(xy 438.299657 -388.397724) (xy 438.349238 -388.375086) (xy 438.401536 -388.359734) (xy 438.455487 -388.351983)
			(xy 438.48274 -388.351522) (xy 438.511656 -388.352075) (xy 438.568826 -388.360796) (xy 438.624024 -388.378046)
			(xy 438.675986 -388.403431) (xy 438.723521 -388.436369) (xy 438.765539 -388.476105) (xy 438.78373 -388.498588)
			(xy 438.793627 -388.510393) (xy 438.818951 -388.527912) (xy 438.848344 -388.537088) (xy 438.879136 -388.537088)
			(xy 438.908529 -388.527912) (xy 438.933853 -388.510393) (xy 438.94375 -388.498588) (xy 438.960503 -388.477805)
			(xy 438.998857 -388.440675) (xy 439.042011 -388.409253) (xy 439.089125 -388.384154) (xy 439.139277 -388.365868)
			(xy 439.191488 -388.354751) (xy 439.24474 -388.351021) (xy 439.297992 -388.354751) (xy 439.350203 -388.365868)
			(xy 439.400355 -388.384154) (xy 439.447469 -388.409253) (xy 439.490623 -388.440675) (xy 439.528977 -388.477805)
			(xy 439.54573 -388.498588) (xy 439.555627 -388.510393) (xy 439.580951 -388.527912) (xy 439.610344 -388.537088)
			(xy 439.641136 -388.537088) (xy 439.670529 -388.527912) (xy 439.695853 -388.510393) (xy 439.70575 -388.498588)
			(xy 439.722503 -388.477805) (xy 439.760857 -388.440675) (xy 439.804011 -388.409253) (xy 439.851125 -388.384154)
			(xy 439.901277 -388.365868) (xy 439.953488 -388.354751) (xy 440.00674 -388.351021) (xy 440.059992 -388.354751)
			(xy 440.112203 -388.365868) (xy 440.162355 -388.384154) (xy 440.209469 -388.409253) (xy 440.252623 -388.440675)
			(xy 440.290977 -388.477805) (xy 440.30773 -388.498588) (xy 440.317627 -388.510393) (xy 440.342951 -388.527912)
			(xy 440.372344 -388.537088) (xy 440.403136 -388.537088) (xy 440.432529 -388.527912) (xy 440.457853 -388.510393)
			(xy 440.46775 -388.498588) (xy 440.485966 -388.476126) (xy 440.527981 -388.43639) (xy 440.575511 -388.403449)
			(xy 440.627467 -388.378057) (xy 440.68266 -388.360796) (xy 440.739826 -388.352061) (xy 440.76874 -388.351522)
			(xy 440.795992 -388.351951) (xy 440.849939 -388.359712) (xy 440.902233 -388.375072) (xy 440.951809 -388.397717)
			(xy 440.997658 -388.427187) (xy 441.038847 -388.462881) (xy 441.074537 -388.504074) (xy 441.104002 -388.549926)
			(xy 441.126642 -388.599504) (xy 441.141996 -388.6518) (xy 441.149752 -388.705748) (xy 441.149752 -388.760252)
			(xy 441.141996 -388.8142) (xy 441.126642 -388.866496) (xy 441.104002 -388.916074) (xy 441.074537 -388.961926)
			(xy 441.038847 -389.003119) (xy 440.997658 -389.038813) (xy 440.951809 -389.068283) (xy 440.902233 -389.090928)
			(xy 440.849939 -389.106288) (xy 440.795992 -389.114049) (xy 440.76874 -389.114538) (xy 440.739823 -389.114015)
			(xy 440.682651 -389.10529) (xy 440.627451 -389.088035) (xy 440.575489 -389.062644) (xy 440.527955 -389.0297)
			(xy 440.485939 -388.989958) (xy 440.46775 -388.967472) (xy 440.457853 -388.955667) (xy 440.432529 -388.938148)
			(xy 440.403136 -388.928972) (xy 440.372344 -388.928972) (xy 440.342951 -388.938148) (xy 440.317627 -388.955667)
			(xy 440.30773 -388.967472) (xy 440.290977 -388.988255) (xy 440.252623 -389.025385) (xy 440.209469 -389.056807)
			(xy 440.162355 -389.081906) (xy 440.112203 -389.100192) (xy 440.059992 -389.111309) (xy 440.00674 -389.115039)
			(xy 439.953488 -389.111309) (xy 439.901277 -389.100192) (xy 439.851125 -389.081906) (xy 439.804011 -389.056807)
			(xy 439.760857 -389.025385) (xy 439.722503 -388.988255) (xy 439.70575 -388.967472) (xy 439.695853 -388.955667)
			(xy 439.670529 -388.938148) (xy 439.641136 -388.928972) (xy 439.610344 -388.928972) (xy 439.580951 -388.938148)
			(xy 439.555627 -388.955667) (xy 439.54573 -388.967472) (xy 439.528977 -388.988255) (xy 439.490623 -389.025385)
			(xy 439.447469 -389.056807) (xy 439.400355 -389.081906) (xy 439.350203 -389.100192) (xy 439.297992 -389.111309)
			(xy 439.24474 -389.115039) (xy 439.191488 -389.111309) (xy 439.139277 -389.100192) (xy 439.089125 -389.081906)
			(xy 439.042011 -389.056807) (xy 438.998857 -389.025385) (xy 438.960503 -388.988255) (xy 438.94375 -388.967472)
			(xy 438.933853 -388.955667) (xy 438.908529 -388.938148) (xy 438.879136 -388.928972) (xy 438.848344 -388.928972)
			(xy 438.818951 -388.938148) (xy 438.793627 -388.955667) (xy 438.78373 -388.967472) (xy 438.765515 -388.989935)
			(xy 438.723501 -389.029673) (xy 438.675971 -389.062615) (xy 438.624015 -389.088007) (xy 438.568821 -389.105268)
			(xy 438.511655 -389.114001) (xy 438.48274 -389.114538) (xy 438.455487 -389.114017) (xy 438.401536 -389.106266)
			(xy 438.349238 -389.090914) (xy 438.299657 -389.068276) (xy 438.253802 -389.038811) (xy 438.212608 -389.00312)
			(xy 438.176913 -388.96193) (xy 438.147443 -388.916079) (xy 438.1248 -388.8665) (xy 438.109443 -388.814203)
			(xy 438.101685 -388.760253) (xy 432.645058 -388.760253) (xy 432.645058 -391.094468) (xy 432.645509 -391.107935)
			(xy 432.652627 -391.133914) (xy 432.666297 -391.157124) (xy 432.685564 -391.175948) (xy 432.709086 -391.189072)
			(xy 432.735224 -391.195584) (xy 432.762155 -391.195027) (xy 432.788001 -391.187442) (xy 432.799744 -391.180828)
			(xy 432.822391 -391.167439) (xy 432.870583 -391.146333) (xy 432.921218 -391.132052) (xy 432.973336 -391.124866)
			(xy 432.999642 -391.12444) (xy 433.026888 -391.124929) (xy 433.080824 -391.132689) (xy 433.133107 -391.148046)
			(xy 433.182673 -391.170687) (xy 433.228512 -391.200151) (xy 433.269692 -391.235838) (xy 433.305375 -391.277021)
			(xy 433.334833 -391.322864) (xy 433.357468 -391.372432) (xy 433.37282 -391.424717) (xy 433.380574 -391.478654)
			(xy 433.380574 -391.533146) (xy 433.37282 -391.587083) (xy 433.357468 -391.639368) (xy 433.334833 -391.688936)
			(xy 433.305375 -391.734779) (xy 433.269692 -391.775962) (xy 433.228512 -391.811649) (xy 433.182673 -391.841113)
			(xy 433.133107 -391.863754) (xy 433.080824 -391.879111) (xy 433.026888 -391.886871) (xy 432.999642 -391.887456)
			(xy 432.973336 -391.887032) (xy 432.921219 -391.879841) (xy 432.870583 -391.865561) (xy 432.822388 -391.844463)
			(xy 432.799744 -391.831068) (xy 432.788042 -391.824389) (xy 432.762191 -391.816824) (xy 432.735261 -391.816284)
			(xy 432.709128 -391.822809) (xy 432.685612 -391.835943) (xy 432.666351 -391.854772) (xy 432.652686 -391.877983)
			(xy 432.64557 -391.903962) (xy 432.645058 -391.917428) (xy 432.645058 -393.67079) (xy 432.65979 -393.685776)
			(xy 434.970428 -395.996414) (xy 434.985414 -396.011146) (xy 465.30133 -396.011146)
		)
		(stroke
			(width 0)
			(type solid)
		)
		(fill yes)
		(layer "In11.Cu")
		(net "GND")
	)
	(gr_poly
		(pts
			(xy 24.947372 -398.21231) (xy 24.94964 -398.187407) (xy 24.959881 -398.138462) (xy 24.976434 -398.091277)
			(xy 24.999017 -398.046661) (xy 25.027241 -398.005383) (xy 25.043638 -397.986504) (xy 25.053028 -397.975302)
			(xy 25.065563 -397.948908) (xy 25.07012 -397.920047) (xy 25.066325 -397.891075) (xy 25.05449 -397.864361)
			(xy 25.045416 -397.8529) (xy 25.028403 -397.832116) (xy 24.999769 -397.786673) (xy 24.977793 -397.737663)
			(xy 24.962911 -397.686054) (xy 24.955416 -397.632868) (xy 24.954992 -397.606012) (xy 24.954992 -396.742412)
			(xy 24.955444 -396.715016) (xy 24.963244 -396.660784) (xy 24.978727 -396.608227) (xy 25.001576 -396.558428)
			(xy 25.031318 -396.512414) (xy 25.048972 -396.49146) (xy 25.058106 -396.48011) (xy 25.070188 -396.453614)
			(xy 25.074324 -396.424789) (xy 25.070181 -396.395964) (xy 25.058094 -396.369471) (xy 25.048972 -396.35811)
			(xy 25.031331 -396.337178) (xy 25.001605 -396.291211) (xy 24.978763 -396.241465) (xy 24.963272 -396.188962)
			(xy 24.955453 -396.134782) (xy 24.954992 -396.107412) (xy 24.955478 -396.080161) (xy 24.963234 -396.026213)
			(xy 24.978589 -395.973918) (xy 25.001231 -395.924341) (xy 25.030697 -395.878491) (xy 25.066388 -395.8373)
			(xy 25.107579 -395.801609) (xy 25.153429 -395.772143) (xy 25.203006 -395.749501) (xy 25.255301 -395.734146)
			(xy 25.309249 -395.72639) (xy 25.363751 -395.72639) (xy 25.417699 -395.734146) (xy 25.469994 -395.749501)
			(xy 25.519571 -395.772143) (xy 25.565421 -395.801609) (xy 25.606612 -395.8373) (xy 25.642303 -395.878491)
			(xy 25.671769 -395.924341) (xy 25.694411 -395.973918) (xy 25.709766 -396.026213) (xy 25.717522 -396.080161)
			(xy 25.718008 -396.107412) (xy 25.717535 -396.134782) (xy 25.70971 -396.188959) (xy 25.694222 -396.241462)
			(xy 25.671389 -396.291212) (xy 25.64168 -396.337189) (xy 25.624028 -396.35811) (xy 25.614793 -396.36941)
			(xy 25.604929 -396.390876) (xy 28.256228 -396.390876) (xy 28.260299 -396.335254) (xy 28.272425 -396.280817)
			(xy 28.292348 -396.228726) (xy 28.319644 -396.180091) (xy 28.35373 -396.135948) (xy 28.393879 -396.097239)
			(xy 28.439237 -396.064788) (xy 28.488837 -396.039287) (xy 28.541621 -396.02128) (xy 28.596464 -396.01115)
			(xy 28.652198 -396.009113) (xy 28.707635 -396.015213) (xy 28.761592 -396.029319) (xy 28.812921 -396.051131)
			(xy 28.860527 -396.080185) (xy 28.903395 -396.11586) (xy 28.940612 -396.157397) (xy 28.971385 -396.20391)
			(xy 28.995057 -396.254407) (xy 29.001115 -396.274544) (xy 35.204398 -396.274544) (xy 35.208469 -396.218922)
			(xy 35.220595 -396.164485) (xy 35.240518 -396.112394) (xy 35.267814 -396.063759) (xy 35.3019 -396.019616)
			(xy 35.342049 -395.980907) (xy 35.387407 -395.948456) (xy 35.437007 -395.922955) (xy 35.489791 -395.904948)
			(xy 35.544634 -395.894818) (xy 35.600368 -395.892781) (xy 35.655805 -395.898881) (xy 35.709762 -395.912987)
			(xy 35.761091 -395.934799) (xy 35.808697 -395.963853) (xy 35.851565 -395.999528) (xy 35.888782 -396.041065)
			(xy 35.919555 -396.087578) (xy 35.943227 -396.138075) (xy 35.959295 -396.191482) (xy 35.967415 -396.246658)
			(xy 35.967924 -396.274544) (xy 35.967415 -396.30243) (xy 35.959295 -396.357606) (xy 35.943227 -396.411013)
			(xy 35.919555 -396.46151) (xy 35.888782 -396.508023) (xy 35.851565 -396.54956) (xy 35.808697 -396.585235)
			(xy 35.761091 -396.614289) (xy 35.709762 -396.636101) (xy 35.655805 -396.650207) (xy 35.600368 -396.656307)
			(xy 35.544634 -396.65427) (xy 35.489791 -396.64414) (xy 35.437007 -396.626133) (xy 35.387407 -396.600632)
			(xy 35.342049 -396.568181) (xy 35.3019 -396.529472) (xy 35.267814 -396.485329) (xy 35.240518 -396.436694)
			(xy 35.220595 -396.384603) (xy 35.208469 -396.330166) (xy 35.204398 -396.274544) (xy 29.001115 -396.274544)
			(xy 29.011125 -396.307814) (xy 29.019245 -396.36299) (xy 29.019754 -396.390876) (xy 29.019245 -396.418762)
			(xy 29.011125 -396.473938) (xy 28.995057 -396.527345) (xy 28.971385 -396.577842) (xy 28.940612 -396.624355)
			(xy 28.903395 -396.665892) (xy 28.860527 -396.701567) (xy 28.812921 -396.730621) (xy 28.761592 -396.752433)
			(xy 28.707635 -396.766539) (xy 28.652198 -396.772639) (xy 28.596464 -396.770602) (xy 28.541621 -396.760472)
			(xy 28.488837 -396.742465) (xy 28.439237 -396.716964) (xy 28.393879 -396.684513) (xy 28.35373 -396.645804)
			(xy 28.319644 -396.601661) (xy 28.292348 -396.553026) (xy 28.272425 -396.500935) (xy 28.260299 -396.446498)
			(xy 28.256228 -396.390876) (xy 25.604929 -396.390876) (xy 25.602612 -396.395917) (xy 25.598436 -396.424789)
			(xy 25.602606 -396.453661) (xy 25.61478 -396.480171) (xy 25.624028 -396.49146) (xy 25.641673 -396.512419)
			(xy 25.671402 -396.55844) (xy 25.694246 -396.608238) (xy 25.709736 -396.660791) (xy 25.717553 -396.715018)
			(xy 25.718008 -396.742412) (xy 25.718008 -397.606012) (xy 25.717537 -397.633912) (xy 25.709438 -397.689121)
			(xy 25.693386 -397.742562) (xy 25.669722 -397.793095) (xy 25.638952 -397.839644) (xy 25.620726 -397.860774)
			(xy 25.611327 -397.871974) (xy 25.598778 -397.898369) (xy 25.594214 -397.927236) (xy 25.598006 -397.956215)
			(xy 25.609846 -397.982936) (xy 25.618948 -397.994378) (xy 25.637858 -398.017608) (xy 25.668962 -398.068795)
			(xy 25.691697 -398.124209) (xy 25.705506 -398.182492) (xy 25.708356 -398.21231) (xy 25.711912 -398.2593)
			(xy 28.21686 -398.2593) (xy 28.543758 -397.932402) (xy 28.553744 -397.921754) (xy 28.567715 -397.896137)
			(xy 28.57388 -397.867616) (xy 28.571736 -397.838516) (xy 28.561458 -397.811206) (xy 28.543884 -397.787913)
			(xy 28.520444 -397.770534) (xy 28.506928 -397.765016) (xy 28.479809 -397.754488) (xy 28.428868 -397.7264)
			(xy 28.38278 -397.690905) (xy 28.342615 -397.648826) (xy 28.309303 -397.601137) (xy 28.283616 -397.548944)
			(xy 28.266149 -397.493457) (xy 28.257307 -397.435962) (xy 28.256738 -397.406876) (xy 28.257203 -397.379625)
			(xy 28.264963 -397.32568) (xy 28.280322 -397.273387) (xy 28.302966 -397.223813) (xy 28.332435 -397.177966)
			(xy 28.36813 -397.13678) (xy 28.409322 -397.101093) (xy 28.455175 -397.071632) (xy 28.504753 -397.048997)
			(xy 28.557048 -397.033648) (xy 28.610995 -397.025898) (xy 28.638246 -397.025368) (xy 28.667334 -397.025912)
			(xy 28.724837 -397.034741) (xy 28.780331 -397.052201) (xy 28.83253 -397.077888) (xy 28.880221 -397.111206)
			(xy 28.922298 -397.151381) (xy 28.957784 -397.197481) (xy 28.985856 -397.248437) (xy 28.996386 -397.275558)
			(xy 29.001825 -397.289131) (xy 29.01918 -397.312651) (xy 29.042489 -397.330288) (xy 29.06984 -397.340597)
			(xy 29.098992 -397.342733) (xy 29.127553 -397.336521) (xy 29.153184 -397.32247) (xy 29.163772 -397.312388)
			(xy 29.70784 -396.76832) (xy 32.671004 -396.76832) (xy 32.690485 -396.750106) (xy 32.733619 -396.71874)
			(xy 32.780701 -396.693687) (xy 32.830812 -396.675435) (xy 32.882978 -396.664339) (xy 32.93618 -396.660616)
			(xy 32.989382 -396.664339) (xy 33.041548 -396.675435) (xy 33.091659 -396.693687) (xy 33.138741 -396.71874)
			(xy 33.181875 -396.750106) (xy 33.201356 -396.76832) (xy 36.09086 -396.76832) (xy 36.907216 -395.951964)
			(xy 45.503592 -395.951964) (xy 45.503592 -393.954) (xy 45.504103 -393.929016) (xy 45.511953 -393.879668)
			(xy 45.527412 -393.83215) (xy 45.550103 -393.78763) (xy 45.579467 -393.7472) (xy 45.59681 -393.72921)
			(xy 46.73981 -392.58621) (xy 46.761733 -392.565355) (xy 46.811856 -392.531474) (xy 46.839378 -392.5189)
			(xy 46.852345 -392.512778) (xy 46.87448 -392.494569) (xy 46.890689 -392.47093) (xy 46.899701 -392.443721)
			(xy 46.900805 -392.41508) (xy 46.893916 -392.387258) (xy 46.88713 -392.374628) (xy 46.874934 -392.352746)
			(xy 46.855743 -392.30647) (xy 46.842765 -392.258083) (xy 46.836222 -392.208415) (xy 46.835822 -392.183366)
			(xy 46.836308 -392.156115) (xy 46.844064 -392.102167) (xy 46.859419 -392.049872) (xy 46.882061 -392.000295)
			(xy 46.911527 -391.954445) (xy 46.947218 -391.913254) (xy 46.988409 -391.877563) (xy 47.034259 -391.848097)
			(xy 47.083836 -391.825455) (xy 47.136131 -391.8101) (xy 47.190079 -391.802344) (xy 47.244581 -391.802344)
			(xy 47.298529 -391.8101) (xy 47.350824 -391.825455) (xy 47.400401 -391.848097) (xy 47.446251 -391.877563)
			(xy 47.487442 -391.913254) (xy 47.523133 -391.954445) (xy 47.534929 -391.9728) (xy 93.242382 -391.9728)
			(xy 93.246453 -391.917178) (xy 93.258579 -391.862741) (xy 93.278502 -391.81065) (xy 93.305798 -391.762015)
			(xy 93.339884 -391.717872) (xy 93.380033 -391.679163) (xy 93.425391 -391.646712) (xy 93.474991 -391.621211)
			(xy 93.527775 -391.603204) (xy 93.582618 -391.593074) (xy 93.638352 -391.591037) (xy 93.693789 -391.597137)
			(xy 93.747746 -391.611243) (xy 93.799075 -391.633055) (xy 93.846681 -391.662109) (xy 93.889549 -391.697784)
			(xy 93.926766 -391.739321) (xy 93.957539 -391.785834) (xy 93.981211 -391.836331) (xy 93.997279 -391.889738)
			(xy 94.005399 -391.944914) (xy 94.005908 -391.9728) (xy 94.005399 -392.000686) (xy 93.997279 -392.055862)
			(xy 93.981211 -392.109269) (xy 93.957539 -392.159766) (xy 93.926766 -392.206279) (xy 93.889549 -392.247816)
			(xy 93.846681 -392.283491) (xy 93.799075 -392.312545) (xy 93.747746 -392.334357) (xy 93.693789 -392.348463)
			(xy 93.638352 -392.354563) (xy 93.582618 -392.352526) (xy 93.527775 -392.342396) (xy 93.474991 -392.324389)
			(xy 93.425391 -392.298888) (xy 93.380033 -392.266437) (xy 93.339884 -392.227728) (xy 93.305798 -392.183585)
			(xy 93.278502 -392.13495) (xy 93.258579 -392.082859) (xy 93.246453 -392.028422) (xy 93.242382 -391.9728)
			(xy 47.534929 -391.9728) (xy 47.552599 -392.000295) (xy 47.575241 -392.049872) (xy 47.590596 -392.102167)
			(xy 47.598352 -392.156115) (xy 47.598838 -392.183366) (xy 47.5983 -392.2117) (xy 47.589875 -392.267739)
			(xy 47.573249 -392.321915) (xy 47.5615 -392.347704) (xy 47.555632 -392.361142) (xy 47.551056 -392.390092)
			(xy 47.554889 -392.41915) (xy 47.566816 -392.445924) (xy 47.585854 -392.468209) (xy 47.610436 -392.48417)
			(xy 47.638539 -392.492495) (xy 47.653194 -392.492992) (xy 47.6758 -392.492992) (xy 47.700784 -392.493503)
			(xy 47.750132 -392.501353) (xy 47.79765 -392.516812) (xy 47.84217 -392.539503) (xy 47.8826 -392.568867)
			(xy 47.90059 -392.58621) (xy 49.102772 -393.788392) (xy 49.911 -393.788392) (xy 49.935984 -393.788903)
			(xy 49.985332 -393.796753) (xy 50.03285 -393.812212) (xy 50.07737 -393.834903) (xy 50.1178 -393.864267)
			(xy 50.13579 -393.88161) (xy 50.601372 -394.347192) (xy 95.372428 -394.347192) (xy 95.693992 -394.025628)
			(xy 95.693992 -392.996674) (xy 95.68174 -392.977535) (xy 95.661369 -392.936912) (xy 95.653352 -392.915648)
			(xy 95.649347 -392.906037) (xy 95.635093 -392.890889) (xy 95.616 -392.882638) (xy 95.5952 -392.882638)
			(xy 95.576107 -392.890889) (xy 95.561853 -392.906037) (xy 95.557848 -392.915648) (xy 95.547382 -392.942885)
			(xy 95.519372 -392.99407) (xy 95.483894 -393.040392) (xy 95.441776 -393.080772) (xy 95.394001 -393.114267)
			(xy 95.341682 -393.140097) (xy 95.286041 -393.15766) (xy 95.228374 -393.166544) (xy 95.1992 -393.167108)
			(xy 95.171949 -393.166622) (xy 95.118001 -393.158866) (xy 95.065706 -393.143511) (xy 95.016129 -393.120869)
			(xy 94.970279 -393.091403) (xy 94.929088 -393.055712) (xy 94.893397 -393.014521) (xy 94.863931 -392.968671)
			(xy 94.841289 -392.919094) (xy 94.825934 -392.866799) (xy 94.818178 -392.812851) (xy 94.818178 -392.758349)
			(xy 94.825934 -392.704401) (xy 94.841289 -392.652106) (xy 94.863931 -392.602529) (xy 94.893397 -392.556679)
			(xy 94.929088 -392.515488) (xy 94.970279 -392.479797) (xy 95.016129 -392.450331) (xy 95.065706 -392.427689)
			(xy 95.118001 -392.412334) (xy 95.171949 -392.404578) (xy 95.1992 -392.404092) (xy 95.226457 -392.404578)
			(xy 95.280417 -392.412336) (xy 95.332724 -392.427694) (xy 95.382312 -392.450339) (xy 95.428174 -392.479811)
			(xy 95.469374 -392.515509) (xy 95.505075 -392.556708) (xy 95.520256 -392.579352) (xy 95.528537 -392.591279)
			(xy 95.550473 -392.610283) (xy 95.576873 -392.622338) (xy 95.6056 -392.626468) (xy 95.634327 -392.622338)
			(xy 95.660727 -392.610283) (xy 95.682663 -392.591279) (xy 95.690944 -392.579352) (xy 95.706097 -392.556688)
			(xy 95.741809 -392.515496) (xy 95.783016 -392.479801) (xy 95.828882 -392.45033) (xy 95.878473 -392.427683)
			(xy 95.93078 -392.412319) (xy 95.984741 -392.404551) (xy 96.012 -392.404092) (xy 96.03769 -392.404511)
			(xy 96.088605 -392.411407) (xy 96.138134 -392.425074) (xy 96.18538 -392.445265) (xy 96.229489 -392.471615)
			(xy 96.269663 -392.503646) (xy 96.305174 -392.540779) (xy 96.32061 -392.561318) (xy 96.330106 -392.573507)
			(xy 96.35487 -392.591961) (xy 96.384019 -392.602168) (xy 96.414886 -392.603192) (xy 96.444648 -392.59494)
			(xy 96.470581 -392.578168) (xy 96.480884 -392.566652) (xy 96.499122 -392.545582) (xy 96.540663 -392.508438)
			(xy 96.587164 -392.477729) (xy 96.637635 -392.454107) (xy 96.691004 -392.438075) (xy 96.746137 -392.429973)
			(xy 96.774 -392.429492) (xy 96.802377 -392.430013) (xy 96.858505 -392.438423) (xy 96.912767 -392.455058)
			(xy 96.938592 -392.46683) (xy 96.952032 -392.472699) (xy 96.980987 -392.477276) (xy 97.01005 -392.473445)
			(xy 97.036829 -392.461519) (xy 97.059121 -392.442482) (xy 97.07509 -392.417899) (xy 97.083423 -392.389793)
			(xy 97.08388 -392.375136) (xy 97.08388 -391.94486) (xy 96.75241 -391.61339) (xy 96.735054 -391.595406)
			(xy 96.705649 -391.554994) (xy 96.682936 -391.510476) (xy 96.667475 -391.46295) (xy 96.659648 -391.413589)
			(xy 96.659192 -391.3886) (xy 96.659192 -391.269728) (xy 96.651826 -391.257536) (xy 96.636876 -391.23208)
			(xy 96.614143 -391.177599) (xy 96.600053 -391.120271) (xy 96.596962 -391.090912) (xy 96.595113 -391.075911)
			(xy 96.583829 -391.047889) (xy 96.564854 -391.024383) (xy 96.539842 -391.007443) (xy 96.510973 -390.998545)
			(xy 96.49587 -390.997948) (xy 95.2246 -390.997948) (xy 95.219266 -390.998964) (xy 95.196735 -391.003443)
			(xy 95.15105 -391.008281) (xy 95.12808 -391.008616) (xy 57.64276 -391.008616) (xy 57.619791 -391.008276)
			(xy 57.574106 -391.00344) (xy 57.551574 -390.998964) (xy 57.54624 -390.997948) (xy 53.90388 -390.997948)
			(xy 48.18888 -385.282948) (xy 43.143932 -385.282948) (xy 43.12954 -385.2834) (xy 43.10188 -385.291351)
			(xy 43.077543 -385.306714) (xy 43.058467 -385.328265) (xy 43.046173 -385.354287) (xy 43.04164 -385.382708)
			(xy 43.045228 -385.411264) (xy 43.05046 -385.42468) (xy 43.060275 -385.448608) (xy 43.074089 -385.498448)
			(xy 43.081042 -385.549696) (xy 43.081448 -385.575556) (xy 43.080945 -385.604356) (xy 43.072321 -385.661305)
			(xy 43.055217 -385.716305) (xy 43.043094 -385.742434) (xy 43.036817 -385.756576) (xy 43.032219 -385.787159)
			(xy 43.036972 -385.817718) (xy 43.050641 -385.845459) (xy 43.071978 -385.867847) (xy 43.085258 -385.875784)
			(xy 43.110422 -385.890306) (xy 43.156427 -385.925788) (xy 43.196513 -385.967841) (xy 43.229752 -386.015492)
			(xy 43.255374 -386.067635) (xy 43.272785 -386.123063) (xy 43.281582 -386.180491) (xy 43.282108 -386.20954)
			(xy 43.281622 -386.236791) (xy 43.273866 -386.290739) (xy 43.258511 -386.343034) (xy 43.235869 -386.392611)
			(xy 43.206403 -386.438461) (xy 43.170712 -386.479652) (xy 43.129521 -386.515343) (xy 43.083671 -386.544809)
			(xy 43.034094 -386.567451) (xy 42.981799 -386.582806) (xy 42.927851 -386.590562) (xy 42.873349 -386.590562)
			(xy 42.819401 -386.582806) (xy 42.767106 -386.567451) (xy 42.717529 -386.544809) (xy 42.671679 -386.515343)
			(xy 42.630488 -386.479652) (xy 42.594797 -386.438461) (xy 42.565331 -386.392611) (xy 42.542689 -386.343034)
			(xy 42.527334 -386.290739) (xy 42.519578 -386.236791) (xy 42.519092 -386.20954) (xy 42.519675 -386.179236)
			(xy 42.529245 -386.119388) (xy 42.538142 -386.090414) (xy 42.541999 -386.077233) (xy 42.543307 -386.049811)
			(xy 42.537262 -386.023033) (xy 42.5243 -385.998833) (xy 42.505359 -385.978961) (xy 42.481807 -385.964855)
			(xy 42.455348 -385.957535) (xy 42.441622 -385.957064) (xy 42.094658 -385.957064) (xy 42.080931 -385.957519)
			(xy 42.054472 -385.964844) (xy 42.030921 -385.978953) (xy 42.011981 -385.998827) (xy 41.999019 -386.023029)
			(xy 41.992974 -386.049809) (xy 41.994282 -386.077232) (xy 41.998138 -386.090414) (xy 42.007046 -386.119386)
			(xy 42.016615 -386.179235) (xy 42.017188 -386.20954) (xy 42.016702 -386.236791) (xy 42.008946 -386.290739)
			(xy 41.993591 -386.343034) (xy 41.970949 -386.392611) (xy 41.941483 -386.438461) (xy 41.905792 -386.479652)
			(xy 41.864601 -386.515343) (xy 41.818751 -386.544809) (xy 41.769174 -386.567451) (xy 41.716879 -386.582806)
			(xy 41.662931 -386.590562) (xy 41.608429 -386.590562) (xy 41.554481 -386.582806) (xy 41.502186 -386.567451)
			(xy 41.452609 -386.544809) (xy 41.406759 -386.515343) (xy 41.365568 -386.479652) (xy 41.329877 -386.438461)
			(xy 41.300411 -386.392611) (xy 41.277769 -386.343034) (xy 41.262414 -386.290739) (xy 41.254658 -386.236791)
			(xy 41.254172 -386.20954) (xy 41.254721 -386.180495) (xy 41.263539 -386.123077) (xy 41.280961 -386.067661)
			(xy 41.306585 -386.015527) (xy 41.339817 -385.967881) (xy 41.37989 -385.925825) (xy 41.425877 -385.890333)
			(xy 41.451022 -385.875784) (xy 41.464284 -385.867815) (xy 41.485621 -385.84543) (xy 41.4993 -385.817695)
			(xy 41.504072 -385.787141) (xy 41.499503 -385.756555) (xy 41.493186 -385.742434) (xy 41.48108 -385.716299)
			(xy 41.463987 -385.661297) (xy 41.455339 -385.604354) (xy 41.454832 -385.575556) (xy 41.455245 -385.549697)
			(xy 41.462196 -385.498448) (xy 41.476006 -385.448608) (xy 41.48582 -385.42468) (xy 41.491038 -385.411276)
			(xy 41.494568 -385.382744) (xy 41.490003 -385.354359) (xy 41.477704 -385.328373) (xy 41.458648 -385.306846)
			(xy 41.434345 -385.291486) (xy 41.406724 -385.283511) (xy 41.392348 -385.282948) (xy 38.312598 -385.282948)
			(xy 38.298766 -385.2834) (xy 38.272116 -385.290812) (xy 38.24844 -385.305117) (xy 38.229481 -385.325261)
			(xy 38.216637 -385.34976) (xy 38.210854 -385.376811) (xy 38.211252 -385.390644) (xy 38.21176 -385.412996)
			(xy 38.211297 -385.440248) (xy 38.20354 -385.494197) (xy 38.188184 -385.546492) (xy 38.165541 -385.59607)
			(xy 38.136072 -385.64192) (xy 38.100378 -385.683109) (xy 38.059185 -385.718799) (xy 38.013331 -385.748262)
			(xy 37.963751 -385.770899) (xy 37.911454 -385.786249) (xy 37.857504 -385.794) (xy 37.830252 -385.794504)
			(xy 36.966652 -385.794504) (xy 36.939403 -385.794015) (xy 36.885461 -385.786253) (xy 36.833172 -385.770894)
			(xy 36.783601 -385.74825) (xy 36.737757 -385.718782) (xy 36.696573 -385.68309) (xy 36.660887 -385.641901)
			(xy 36.631425 -385.596053) (xy 36.608788 -385.546479) (xy 36.593436 -385.494188) (xy 36.585681 -385.440245)
			(xy 36.585144 -385.412996) (xy 36.585652 -385.390644) (xy 36.586013 -385.37682) (xy 36.580195 -385.349797)
			(xy 36.567343 -385.325325) (xy 36.548398 -385.305196) (xy 36.524748 -385.290887) (xy 36.498126 -385.283445)
			(xy 36.484306 -385.282948) (xy 23.495 -385.282948) (xy 23.495 -385.802378) (xy 28.134562 -385.802378)
			(xy 28.138633 -385.746756) (xy 28.150759 -385.692319) (xy 28.170682 -385.640228) (xy 28.197978 -385.591593)
			(xy 28.232064 -385.54745) (xy 28.272213 -385.508741) (xy 28.317571 -385.47629) (xy 28.367171 -385.450789)
			(xy 28.419955 -385.432782) (xy 28.474798 -385.422652) (xy 28.530532 -385.420615) (xy 28.585969 -385.426715)
			(xy 28.639926 -385.440821) (xy 28.691255 -385.462633) (xy 28.738861 -385.491687) (xy 28.781729 -385.527362)
			(xy 28.818946 -385.568899) (xy 28.849719 -385.615412) (xy 28.873391 -385.665909) (xy 28.889459 -385.719316)
			(xy 28.897579 -385.774492) (xy 28.898088 -385.802378) (xy 28.897579 -385.830264) (xy 28.889459 -385.88544)
			(xy 28.873391 -385.938847) (xy 28.849719 -385.989344) (xy 28.818946 -386.035857) (xy 28.781729 -386.077394)
			(xy 28.738861 -386.113069) (xy 28.691255 -386.142123) (xy 28.639926 -386.163935) (xy 28.585969 -386.178041)
			(xy 28.530532 -386.184141) (xy 28.474798 -386.182104) (xy 28.419955 -386.171974) (xy 28.367171 -386.153967)
			(xy 28.317571 -386.128466) (xy 28.272213 -386.096015) (xy 28.232064 -386.057306) (xy 28.197978 -386.013163)
			(xy 28.170682 -385.964528) (xy 28.150759 -385.912437) (xy 28.138633 -385.858) (xy 28.134562 -385.802378)
			(xy 23.495 -385.802378) (xy 23.495 -385.809998) (xy 23.494547 -385.837393) (xy 23.486746 -385.891625)
			(xy 23.471261 -385.944181) (xy 23.448412 -385.993978) (xy 23.418668 -386.039991) (xy 23.40102 -386.06095)
			(xy 23.391791 -386.07225) (xy 23.379623 -386.098754) (xy 23.375456 -386.127619) (xy 23.379633 -386.156482)
			(xy 23.391812 -386.182982) (xy 23.40102 -386.1943) (xy 23.418661 -386.215232) (xy 23.448386 -386.261199)
			(xy 23.471228 -386.310945) (xy 23.476606 -386.329174) (xy 38.881556 -386.329174) (xy 38.885627 -386.273552)
			(xy 38.897753 -386.219115) (xy 38.917676 -386.167024) (xy 38.944972 -386.118389) (xy 38.979058 -386.074246)
			(xy 39.019207 -386.035537) (xy 39.064565 -386.003086) (xy 39.114165 -385.977585) (xy 39.166949 -385.959578)
			(xy 39.221792 -385.949448) (xy 39.277526 -385.947411) (xy 39.332963 -385.953511) (xy 39.38692 -385.967617)
			(xy 39.438249 -385.989429) (xy 39.485855 -386.018483) (xy 39.528723 -386.054158) (xy 39.56594 -386.095695)
			(xy 39.596713 -386.142208) (xy 39.620385 -386.192705) (xy 39.636453 -386.246112) (xy 39.644573 -386.301288)
			(xy 39.645082 -386.329174) (xy 39.894762 -386.329174) (xy 39.898833 -386.273552) (xy 39.910959 -386.219115)
			(xy 39.930882 -386.167024) (xy 39.958178 -386.118389) (xy 39.992264 -386.074246) (xy 40.032413 -386.035537)
			(xy 40.077771 -386.003086) (xy 40.127371 -385.977585) (xy 40.180155 -385.959578) (xy 40.234998 -385.949448)
			(xy 40.290732 -385.947411) (xy 40.346169 -385.953511) (xy 40.400126 -385.967617) (xy 40.451455 -385.989429)
			(xy 40.499061 -386.018483) (xy 40.541929 -386.054158) (xy 40.579146 -386.095695) (xy 40.609919 -386.142208)
			(xy 40.633591 -386.192705) (xy 40.649659 -386.246112) (xy 40.657779 -386.301288) (xy 40.658288 -386.329174)
			(xy 40.657779 -386.35706) (xy 40.649659 -386.412236) (xy 40.633591 -386.465643) (xy 40.609919 -386.51614)
			(xy 40.579146 -386.562653) (xy 40.541929 -386.60419) (xy 40.499061 -386.639865) (xy 40.451455 -386.668919)
			(xy 40.400126 -386.690731) (xy 40.346169 -386.704837) (xy 40.290732 -386.710937) (xy 40.234998 -386.7089)
			(xy 40.180155 -386.69877) (xy 40.127371 -386.680763) (xy 40.077771 -386.655262) (xy 40.032413 -386.622811)
			(xy 39.992264 -386.584102) (xy 39.958178 -386.539959) (xy 39.930882 -386.491324) (xy 39.910959 -386.439233)
			(xy 39.898833 -386.384796) (xy 39.894762 -386.329174) (xy 39.645082 -386.329174) (xy 39.644573 -386.35706)
			(xy 39.636453 -386.412236) (xy 39.620385 -386.465643) (xy 39.596713 -386.51614) (xy 39.56594 -386.562653)
			(xy 39.528723 -386.60419) (xy 39.485855 -386.639865) (xy 39.438249 -386.668919) (xy 39.38692 -386.690731)
			(xy 39.332963 -386.704837) (xy 39.277526 -386.710937) (xy 39.221792 -386.7089) (xy 39.166949 -386.69877)
			(xy 39.114165 -386.680763) (xy 39.064565 -386.655262) (xy 39.019207 -386.622811) (xy 38.979058 -386.584102)
			(xy 38.944972 -386.539959) (xy 38.917676 -386.491324) (xy 38.897753 -386.439233) (xy 38.885627 -386.384796)
			(xy 38.881556 -386.329174) (xy 23.476606 -386.329174) (xy 23.486717 -386.363449) (xy 23.494535 -386.417628)
			(xy 23.495 -386.444998) (xy 23.494514 -386.472249) (xy 23.486758 -386.526197) (xy 23.471403 -386.578492)
			(xy 23.448761 -386.628069) (xy 23.419295 -386.673919) (xy 23.383604 -386.71511) (xy 23.342413 -386.750801)
			(xy 23.296563 -386.780267) (xy 23.246986 -386.802909) (xy 23.194691 -386.818264) (xy 23.140743 -386.82602)
			(xy 23.086241 -386.82602) (xy 23.032293 -386.818264) (xy 22.979998 -386.802909) (xy 22.930421 -386.780267)
			(xy 22.884571 -386.750801) (xy 22.84338 -386.71511) (xy 22.807689 -386.673919) (xy 22.778223 -386.628069)
			(xy 22.755581 -386.578492) (xy 22.740226 -386.526197) (xy 22.73247 -386.472249) (xy 22.731984 -386.444998)
			(xy 22.732456 -386.417628) (xy 22.74028 -386.36345) (xy 22.755766 -386.310946) (xy 22.778598 -386.261194)
			(xy 22.808306 -386.215217) (xy 22.825964 -386.1943) (xy 22.835105 -386.18295) (xy 22.847198 -386.156451)
			(xy 22.851344 -386.127619) (xy 22.847209 -386.098786) (xy 22.835125 -386.072282) (xy 22.825964 -386.06095)
			(xy 22.808318 -386.039991) (xy 22.778589 -385.99397) (xy 22.755744 -385.944172) (xy 22.740253 -385.89162)
			(xy 22.732435 -385.837392) (xy 22.731984 -385.809998) (xy 22.731984 -385.282948) (xy 21.880068 -385.282948)
			(xy 21.865141 -385.283474) (xy 21.836564 -385.292108) (xy 21.811699 -385.30863) (xy 21.792668 -385.331631)
			(xy 21.781093 -385.359149) (xy 21.777962 -385.388838) (xy 21.780246 -385.403598) (xy 21.783451 -385.421332)
			(xy 21.786889 -385.457206) (xy 21.787104 -385.475226) (xy 21.786618 -385.502477) (xy 21.778862 -385.556425)
			(xy 21.763507 -385.60872) (xy 21.740865 -385.658297) (xy 21.711399 -385.704147) (xy 21.675708 -385.745338)
			(xy 21.634517 -385.781029) (xy 21.588667 -385.810495) (xy 21.53909 -385.833137) (xy 21.486795 -385.848492)
			(xy 21.432847 -385.856248) (xy 21.378345 -385.856248) (xy 21.324397 -385.848492) (xy 21.272102 -385.833137)
			(xy 21.222525 -385.810495) (xy 21.176675 -385.781029) (xy 21.135484 -385.745338) (xy 21.099793 -385.704147)
			(xy 21.070327 -385.658297) (xy 21.047685 -385.60872) (xy 21.03233 -385.556425) (xy 21.024574 -385.502477)
			(xy 21.024088 -385.475226) (xy 21.024324 -385.457208) (xy 21.027763 -385.421335) (xy 21.030946 -385.403598)
			(xy 21.033239 -385.388834) (xy 21.030131 -385.359133) (xy 21.018564 -385.331601) (xy 20.999528 -385.308591)
			(xy 20.974649 -385.292072) (xy 20.946056 -385.283455) (xy 20.931124 -385.282948) (xy 20.62988 -385.282948)
			(xy 20.223988 -385.68884) (xy 20.223988 -385.784344) (xy 20.223532 -385.811738) (xy 20.215725 -385.865966)
			(xy 20.200235 -385.918518) (xy 20.17738 -385.968311) (xy 20.147632 -386.014318) (xy 20.130008 -386.035296)
			(xy 20.120772 -386.046596) (xy 20.10859 -386.073105) (xy 20.104411 -386.101978) (xy 20.108578 -386.130853)
			(xy 20.120748 -386.157367) (xy 20.130008 -386.168646) (xy 20.147647 -386.189578) (xy 20.177367 -386.235546)
			(xy 20.200204 -386.285293) (xy 20.215687 -386.337796) (xy 20.223499 -386.391975) (xy 20.223988 -386.419344)
			(xy 20.223499 -386.446593) (xy 20.215737 -386.500534) (xy 20.200378 -386.552823) (xy 20.177734 -386.602393)
			(xy 20.148266 -386.648236) (xy 20.112574 -386.68942) (xy 20.071385 -386.725105) (xy 20.025537 -386.754565)
			(xy 19.975963 -386.7772) (xy 19.923672 -386.792551) (xy 19.869729 -386.800303) (xy 19.84248 -386.800852)
			(xy 19.815848 -386.800393) (xy 19.763101 -386.792992) (xy 19.711897 -386.778322) (xy 19.663233 -386.75667)
			(xy 19.618055 -386.728456) (xy 19.577243 -386.69423) (xy 19.541591 -386.654657) (xy 19.511794 -386.610508)
			(xy 19.48843 -386.562642) (xy 19.479768 -386.537454) (xy 19.475958 -386.526024) (xy 19.431508 -386.48132)
			(xy 19.35988 -386.552948) (xy 19.35988 -387.608826) (xy 24.833578 -387.608826) (xy 24.837649 -387.553204)
			(xy 24.849775 -387.498767) (xy 24.869698 -387.446676) (xy 24.896994 -387.398041) (xy 24.93108 -387.353898)
			(xy 24.971229 -387.315189) (xy 25.016587 -387.282738) (xy 25.066187 -387.257237) (xy 25.118971 -387.23923)
			(xy 25.173814 -387.2291) (xy 25.229548 -387.227063) (xy 25.284985 -387.233163) (xy 25.337439 -387.246876)
			(xy 28.256228 -387.246876) (xy 28.260299 -387.191254) (xy 28.272425 -387.136817) (xy 28.292348 -387.084726)
			(xy 28.319644 -387.036091) (xy 28.35373 -386.991948) (xy 28.393879 -386.953239) (xy 28.439237 -386.920788)
			(xy 28.488837 -386.895287) (xy 28.541621 -386.87728) (xy 28.596464 -386.86715) (xy 28.652198 -386.865113)
			(xy 28.707635 -386.871213) (xy 28.761592 -386.885319) (xy 28.812921 -386.907131) (xy 28.860527 -386.936185)
			(xy 28.903395 -386.97186) (xy 28.940612 -387.013397) (xy 28.971385 -387.05991) (xy 28.995057 -387.110407)
			(xy 29.011125 -387.163814) (xy 29.019245 -387.21899) (xy 29.019754 -387.246876) (xy 29.019245 -387.274762)
			(xy 29.011125 -387.329938) (xy 28.995057 -387.383345) (xy 28.971385 -387.433842) (xy 28.940612 -387.480355)
			(xy 28.903395 -387.521892) (xy 28.860527 -387.557567) (xy 28.812921 -387.586621) (xy 28.761592 -387.608433)
			(xy 28.707635 -387.622539) (xy 28.652198 -387.628639) (xy 28.596464 -387.626602) (xy 28.541621 -387.616472)
			(xy 28.488837 -387.598465) (xy 28.439237 -387.572964) (xy 28.393879 -387.540513) (xy 28.35373 -387.501804)
			(xy 28.319644 -387.457661) (xy 28.292348 -387.409026) (xy 28.272425 -387.356935) (xy 28.260299 -387.302498)
			(xy 28.256228 -387.246876) (xy 25.337439 -387.246876) (xy 25.338942 -387.247269) (xy 25.390271 -387.269081)
			(xy 25.437877 -387.298135) (xy 25.480745 -387.33381) (xy 25.517962 -387.375347) (xy 25.548735 -387.42186)
			(xy 25.572407 -387.472357) (xy 25.588475 -387.525764) (xy 25.596595 -387.58094) (xy 25.597104 -387.608826)
			(xy 25.596595 -387.636712) (xy 25.588475 -387.691888) (xy 25.572407 -387.745295) (xy 25.548735 -387.795792)
			(xy 25.517962 -387.842305) (xy 25.480745 -387.883842) (xy 25.437877 -387.919517) (xy 25.390271 -387.948571)
			(xy 25.338942 -387.970383) (xy 25.284985 -387.984489) (xy 25.229548 -387.990589) (xy 25.173814 -387.988552)
			(xy 25.118971 -387.978422) (xy 25.066187 -387.960415) (xy 25.016587 -387.934914) (xy 24.971229 -387.902463)
			(xy 24.93108 -387.863754) (xy 24.896994 -387.819611) (xy 24.869698 -387.770976) (xy 24.849775 -387.718885)
			(xy 24.837649 -387.664448) (xy 24.833578 -387.608826) (xy 19.35988 -387.608826) (xy 19.35988 -390.372346)
			(xy 20.201634 -390.372346) (xy 20.205705 -390.316724) (xy 20.217831 -390.262287) (xy 20.237754 -390.210196)
			(xy 20.26505 -390.161561) (xy 20.299136 -390.117418) (xy 20.339285 -390.078709) (xy 20.384643 -390.046258)
			(xy 20.434243 -390.020757) (xy 20.487027 -390.00275) (xy 20.54187 -389.99262) (xy 20.597604 -389.990583)
			(xy 20.653041 -389.996683) (xy 20.706998 -390.010789) (xy 20.758327 -390.032601) (xy 20.805933 -390.061655)
			(xy 20.848801 -390.09733) (xy 20.886018 -390.138867) (xy 20.916791 -390.18538) (xy 20.940463 -390.235877)
			(xy 20.956531 -390.289284) (xy 20.957354 -390.294876) (xy 28.256228 -390.294876) (xy 28.260299 -390.239254)
			(xy 28.272425 -390.184817) (xy 28.292348 -390.132726) (xy 28.319644 -390.084091) (xy 28.35373 -390.039948)
			(xy 28.393879 -390.001239) (xy 28.439237 -389.968788) (xy 28.488837 -389.943287) (xy 28.541621 -389.92528)
			(xy 28.596464 -389.91515) (xy 28.652198 -389.913113) (xy 28.707635 -389.919213) (xy 28.761592 -389.933319)
			(xy 28.812921 -389.955131) (xy 28.860527 -389.984185) (xy 28.903395 -390.01986) (xy 28.940612 -390.061397)
			(xy 28.970895 -390.10717) (xy 31.968946 -390.10717) (xy 31.973017 -390.051548) (xy 31.985143 -389.997111)
			(xy 32.005066 -389.94502) (xy 32.032362 -389.896385) (xy 32.066448 -389.852242) (xy 32.106597 -389.813533)
			(xy 32.151955 -389.781082) (xy 32.201555 -389.755581) (xy 32.254339 -389.737574) (xy 32.309182 -389.727444)
			(xy 32.364916 -389.725407) (xy 32.420353 -389.731507) (xy 32.47431 -389.745613) (xy 32.525639 -389.767425)
			(xy 32.573245 -389.796479) (xy 32.616113 -389.832154) (xy 32.65333 -389.873691) (xy 32.684103 -389.920204)
			(xy 32.707775 -389.970701) (xy 32.718801 -390.007348) (xy 46.835312 -390.007348) (xy 46.839383 -389.951726)
			(xy 46.851509 -389.897289) (xy 46.871432 -389.845198) (xy 46.898728 -389.796563) (xy 46.932814 -389.75242)
			(xy 46.972963 -389.713711) (xy 47.018321 -389.68126) (xy 47.067921 -389.655759) (xy 47.120705 -389.637752)
			(xy 47.175548 -389.627622) (xy 47.231282 -389.625585) (xy 47.286719 -389.631685) (xy 47.340676 -389.645791)
			(xy 47.392005 -389.667603) (xy 47.439611 -389.696657) (xy 47.482479 -389.732332) (xy 47.519696 -389.773869)
			(xy 47.550469 -389.820382) (xy 47.574141 -389.870879) (xy 47.590209 -389.924286) (xy 47.598329 -389.979462)
			(xy 47.598838 -390.007348) (xy 47.598329 -390.035234) (xy 47.590209 -390.09041) (xy 47.574141 -390.143817)
			(xy 47.550469 -390.194314) (xy 47.519696 -390.240827) (xy 47.482479 -390.282364) (xy 47.439611 -390.318039)
			(xy 47.392005 -390.347093) (xy 47.340676 -390.368905) (xy 47.286719 -390.383011) (xy 47.231282 -390.389111)
			(xy 47.175548 -390.387074) (xy 47.120705 -390.376944) (xy 47.067921 -390.358937) (xy 47.018321 -390.333436)
			(xy 46.972963 -390.300985) (xy 46.932814 -390.262276) (xy 46.898728 -390.218133) (xy 46.871432 -390.169498)
			(xy 46.851509 -390.117407) (xy 46.839383 -390.06297) (xy 46.835312 -390.007348) (xy 32.718801 -390.007348)
			(xy 32.723843 -390.024108) (xy 32.731963 -390.079284) (xy 32.732472 -390.10717) (xy 32.731963 -390.135056)
			(xy 32.723843 -390.190232) (xy 32.707775 -390.243639) (xy 32.684103 -390.294136) (xy 32.65333 -390.340649)
			(xy 32.616113 -390.382186) (xy 32.573245 -390.417861) (xy 32.525639 -390.446915) (xy 32.47431 -390.468727)
			(xy 32.420353 -390.482833) (xy 32.364916 -390.488933) (xy 32.309182 -390.486896) (xy 32.254339 -390.476766)
			(xy 32.201555 -390.458759) (xy 32.151955 -390.433258) (xy 32.106597 -390.400807) (xy 32.066448 -390.362098)
			(xy 32.032362 -390.317955) (xy 32.005066 -390.26932) (xy 31.985143 -390.217229) (xy 31.973017 -390.162792)
			(xy 31.968946 -390.10717) (xy 28.970895 -390.10717) (xy 28.971385 -390.10791) (xy 28.995057 -390.158407)
			(xy 29.011125 -390.211814) (xy 29.019245 -390.26699) (xy 29.019754 -390.294876) (xy 29.019245 -390.322762)
			(xy 29.011125 -390.377938) (xy 28.995057 -390.431345) (xy 28.971385 -390.481842) (xy 28.940612 -390.528355)
			(xy 28.903395 -390.569892) (xy 28.860527 -390.605567) (xy 28.812921 -390.634621) (xy 28.761592 -390.656433)
			(xy 28.707635 -390.670539) (xy 28.652198 -390.676639) (xy 28.596464 -390.674602) (xy 28.541621 -390.664472)
			(xy 28.488837 -390.646465) (xy 28.439237 -390.620964) (xy 28.393879 -390.588513) (xy 28.35373 -390.549804)
			(xy 28.319644 -390.505661) (xy 28.292348 -390.457026) (xy 28.272425 -390.404935) (xy 28.260299 -390.350498)
			(xy 28.256228 -390.294876) (xy 20.957354 -390.294876) (xy 20.964651 -390.34446) (xy 20.96516 -390.372346)
			(xy 20.964651 -390.400232) (xy 20.956531 -390.455408) (xy 20.940463 -390.508815) (xy 20.916791 -390.559312)
			(xy 20.886018 -390.605825) (xy 20.848801 -390.647362) (xy 20.805933 -390.683037) (xy 20.758327 -390.712091)
			(xy 20.706998 -390.733903) (xy 20.653041 -390.748009) (xy 20.597604 -390.754109) (xy 20.54187 -390.752072)
			(xy 20.487027 -390.741942) (xy 20.434243 -390.723935) (xy 20.384643 -390.698434) (xy 20.339285 -390.665983)
			(xy 20.299136 -390.627274) (xy 20.26505 -390.583131) (xy 20.237754 -390.534496) (xy 20.217831 -390.482405)
			(xy 20.205705 -390.427968) (xy 20.201634 -390.372346) (xy 19.35988 -390.372346) (xy 19.35988 -391.007346)
			(xy 22.868634 -391.007346) (xy 22.872705 -390.951724) (xy 22.884831 -390.897287) (xy 22.904754 -390.845196)
			(xy 22.93205 -390.796561) (xy 22.966136 -390.752418) (xy 23.006285 -390.713709) (xy 23.051643 -390.681258)
			(xy 23.101243 -390.655757) (xy 23.154027 -390.63775) (xy 23.20887 -390.62762) (xy 23.264604 -390.625583)
			(xy 23.320041 -390.631683) (xy 23.373998 -390.645789) (xy 23.425327 -390.667601) (xy 23.472933 -390.696655)
			(xy 23.515801 -390.73233) (xy 23.553018 -390.773867) (xy 23.583791 -390.82038) (xy 23.607463 -390.870877)
			(xy 23.623531 -390.924284) (xy 23.631651 -390.97946) (xy 23.63216 -391.007346) (xy 23.631651 -391.035232)
			(xy 23.623531 -391.090408) (xy 23.607463 -391.143815) (xy 23.583791 -391.194312) (xy 23.553018 -391.240825)
			(xy 23.515801 -391.282362) (xy 23.481538 -391.310876) (xy 28.256228 -391.310876) (xy 28.260299 -391.255254)
			(xy 28.272425 -391.200817) (xy 28.292348 -391.148726) (xy 28.319644 -391.100091) (xy 28.35373 -391.055948)
			(xy 28.393879 -391.017239) (xy 28.439237 -390.984788) (xy 28.488837 -390.959287) (xy 28.541621 -390.94128)
			(xy 28.596464 -390.93115) (xy 28.652198 -390.929113) (xy 28.707635 -390.935213) (xy 28.761592 -390.949319)
			(xy 28.812921 -390.971131) (xy 28.860527 -391.000185) (xy 28.903395 -391.03586) (xy 28.940612 -391.077397)
			(xy 28.971385 -391.12391) (xy 28.995057 -391.174407) (xy 29.011125 -391.227814) (xy 29.019245 -391.28299)
			(xy 29.019754 -391.310876) (xy 29.019245 -391.338762) (xy 29.011125 -391.393938) (xy 28.995057 -391.447345)
			(xy 28.971385 -391.497842) (xy 28.940612 -391.544355) (xy 28.903395 -391.585892) (xy 28.860527 -391.621567)
			(xy 28.836885 -391.635996) (xy 31.968946 -391.635996) (xy 31.973017 -391.580374) (xy 31.985143 -391.525937)
			(xy 32.005066 -391.473846) (xy 32.032362 -391.425211) (xy 32.066448 -391.381068) (xy 32.106597 -391.342359)
			(xy 32.151955 -391.309908) (xy 32.201555 -391.284407) (xy 32.254339 -391.2664) (xy 32.309182 -391.25627)
			(xy 32.364916 -391.254233) (xy 32.420353 -391.260333) (xy 32.47431 -391.274439) (xy 32.525639 -391.296251)
			(xy 32.573245 -391.325305) (xy 32.616113 -391.36098) (xy 32.65333 -391.402517) (xy 32.654373 -391.404094)
			(xy 38.548816 -391.404094) (xy 38.552887 -391.348472) (xy 38.565013 -391.294035) (xy 38.584936 -391.241944)
			(xy 38.612232 -391.193309) (xy 38.646318 -391.149166) (xy 38.686467 -391.110457) (xy 38.731825 -391.078006)
			(xy 38.781425 -391.052505) (xy 38.834209 -391.034498) (xy 38.889052 -391.024368) (xy 38.944786 -391.022331)
			(xy 39.000223 -391.028431) (xy 39.05418 -391.042537) (xy 39.105509 -391.064349) (xy 39.153115 -391.093403)
			(xy 39.195983 -391.129078) (xy 39.2332 -391.170615) (xy 39.263973 -391.217128) (xy 39.287645 -391.267625)
			(xy 39.303713 -391.321032) (xy 39.311833 -391.376208) (xy 39.311864 -391.377932) (xy 40.593516 -391.377932)
			(xy 40.597587 -391.32231) (xy 40.609713 -391.267873) (xy 40.629636 -391.215782) (xy 40.656932 -391.167147)
			(xy 40.691018 -391.123004) (xy 40.731167 -391.084295) (xy 40.776525 -391.051844) (xy 40.826125 -391.026343)
			(xy 40.878909 -391.008336) (xy 40.933752 -390.998206) (xy 40.989486 -390.996169) (xy 41.044923 -391.002269)
			(xy 41.09888 -391.016375) (xy 41.150209 -391.038187) (xy 41.197815 -391.067241) (xy 41.224733 -391.089642)
			(xy 46.835312 -391.089642) (xy 46.839383 -391.03402) (xy 46.851509 -390.979583) (xy 46.871432 -390.927492)
			(xy 46.898728 -390.878857) (xy 46.932814 -390.834714) (xy 46.972963 -390.796005) (xy 47.018321 -390.763554)
			(xy 47.067921 -390.738053) (xy 47.120705 -390.720046) (xy 47.175548 -390.709916) (xy 47.231282 -390.707879)
			(xy 47.286719 -390.713979) (xy 47.340676 -390.728085) (xy 47.392005 -390.749897) (xy 47.439611 -390.778951)
			(xy 47.482479 -390.814626) (xy 47.519696 -390.856163) (xy 47.550469 -390.902676) (xy 47.574141 -390.953173)
			(xy 47.590209 -391.00658) (xy 47.598329 -391.061756) (xy 47.598838 -391.089642) (xy 47.598329 -391.117528)
			(xy 47.590209 -391.172704) (xy 47.574141 -391.226111) (xy 47.550469 -391.276608) (xy 47.519696 -391.323121)
			(xy 47.482479 -391.364658) (xy 47.439611 -391.400333) (xy 47.392005 -391.429387) (xy 47.340676 -391.451199)
			(xy 47.286719 -391.465305) (xy 47.231282 -391.471405) (xy 47.175548 -391.469368) (xy 47.120705 -391.459238)
			(xy 47.067921 -391.441231) (xy 47.018321 -391.41573) (xy 46.972963 -391.383279) (xy 46.932814 -391.34457)
			(xy 46.898728 -391.300427) (xy 46.871432 -391.251792) (xy 46.851509 -391.199701) (xy 46.839383 -391.145264)
			(xy 46.835312 -391.089642) (xy 41.224733 -391.089642) (xy 41.240683 -391.102916) (xy 41.2779 -391.144453)
			(xy 41.308673 -391.190966) (xy 41.332345 -391.241463) (xy 41.348413 -391.29487) (xy 41.356533 -391.350046)
			(xy 41.357042 -391.377932) (xy 41.356533 -391.405818) (xy 41.348413 -391.460994) (xy 41.332345 -391.514401)
			(xy 41.308673 -391.564898) (xy 41.2779 -391.611411) (xy 41.240683 -391.652948) (xy 41.197815 -391.688623)
			(xy 41.150209 -391.717677) (xy 41.09888 -391.739489) (xy 41.044923 -391.753595) (xy 40.989486 -391.759695)
			(xy 40.933752 -391.757658) (xy 40.878909 -391.747528) (xy 40.826125 -391.729521) (xy 40.776525 -391.70402)
			(xy 40.731167 -391.671569) (xy 40.691018 -391.63286) (xy 40.656932 -391.588717) (xy 40.629636 -391.540082)
			(xy 40.609713 -391.487991) (xy 40.597587 -391.433554) (xy 40.593516 -391.377932) (xy 39.311864 -391.377932)
			(xy 39.312342 -391.404094) (xy 39.311833 -391.43198) (xy 39.303713 -391.487156) (xy 39.287645 -391.540563)
			(xy 39.263973 -391.59106) (xy 39.2332 -391.637573) (xy 39.195983 -391.67911) (xy 39.153115 -391.714785)
			(xy 39.105509 -391.743839) (xy 39.05418 -391.765651) (xy 39.000223 -391.779757) (xy 38.944786 -391.785857)
			(xy 38.889052 -391.78382) (xy 38.834209 -391.77369) (xy 38.781425 -391.755683) (xy 38.731825 -391.730182)
			(xy 38.686467 -391.697731) (xy 38.646318 -391.659022) (xy 38.612232 -391.614879) (xy 38.584936 -391.566244)
			(xy 38.565013 -391.514153) (xy 38.552887 -391.459716) (xy 38.548816 -391.404094) (xy 32.654373 -391.404094)
			(xy 32.684103 -391.44903) (xy 32.707775 -391.499527) (xy 32.723843 -391.552934) (xy 32.731963 -391.60811)
			(xy 32.732472 -391.635996) (xy 32.731963 -391.663882) (xy 32.723843 -391.719058) (xy 32.707775 -391.772465)
			(xy 32.684103 -391.822962) (xy 32.65333 -391.869475) (xy 32.616113 -391.911012) (xy 32.573245 -391.946687)
			(xy 32.525639 -391.975741) (xy 32.47431 -391.997553) (xy 32.420353 -392.011659) (xy 32.364916 -392.017759)
			(xy 32.309182 -392.015722) (xy 32.254339 -392.005592) (xy 32.201555 -391.987585) (xy 32.151955 -391.962084)
			(xy 32.106597 -391.929633) (xy 32.066448 -391.890924) (xy 32.032362 -391.846781) (xy 32.005066 -391.798146)
			(xy 31.985143 -391.746055) (xy 31.973017 -391.691618) (xy 31.968946 -391.635996) (xy 28.836885 -391.635996)
			(xy 28.812921 -391.650621) (xy 28.761592 -391.672433) (xy 28.707635 -391.686539) (xy 28.652198 -391.692639)
			(xy 28.596464 -391.690602) (xy 28.541621 -391.680472) (xy 28.488837 -391.662465) (xy 28.439237 -391.636964)
			(xy 28.393879 -391.604513) (xy 28.35373 -391.565804) (xy 28.319644 -391.521661) (xy 28.292348 -391.473026)
			(xy 28.272425 -391.420935) (xy 28.260299 -391.366498) (xy 28.256228 -391.310876) (xy 23.481538 -391.310876)
			(xy 23.472933 -391.318037) (xy 23.425327 -391.347091) (xy 23.373998 -391.368903) (xy 23.320041 -391.383009)
			(xy 23.264604 -391.389109) (xy 23.20887 -391.387072) (xy 23.154027 -391.376942) (xy 23.101243 -391.358935)
			(xy 23.051643 -391.333434) (xy 23.006285 -391.300983) (xy 22.966136 -391.262274) (xy 22.93205 -391.218131)
			(xy 22.904754 -391.169496) (xy 22.884831 -391.117405) (xy 22.872705 -391.062968) (xy 22.868634 -391.007346)
			(xy 19.35988 -391.007346) (xy 19.35988 -392.326876) (xy 28.256228 -392.326876) (xy 28.260299 -392.271254)
			(xy 28.272425 -392.216817) (xy 28.292348 -392.164726) (xy 28.319644 -392.116091) (xy 28.35373 -392.071948)
			(xy 28.393879 -392.033239) (xy 28.439237 -392.000788) (xy 28.488837 -391.975287) (xy 28.541621 -391.95728)
			(xy 28.596464 -391.94715) (xy 28.652198 -391.945113) (xy 28.707635 -391.951213) (xy 28.761592 -391.965319)
			(xy 28.812921 -391.987131) (xy 28.860527 -392.016185) (xy 28.903395 -392.05186) (xy 28.940612 -392.093397)
			(xy 28.971385 -392.13991) (xy 28.995057 -392.190407) (xy 29.011125 -392.243814) (xy 29.019245 -392.29899)
			(xy 29.019754 -392.326876) (xy 29.019245 -392.354762) (xy 29.011125 -392.409938) (xy 28.995057 -392.463345)
			(xy 28.971385 -392.513842) (xy 28.940612 -392.560355) (xy 28.903395 -392.601892) (xy 28.860527 -392.637567)
			(xy 28.812921 -392.666621) (xy 28.761592 -392.688433) (xy 28.707635 -392.702539) (xy 28.652198 -392.708639)
			(xy 28.596464 -392.706602) (xy 28.541621 -392.696472) (xy 28.488837 -392.678465) (xy 28.439237 -392.652964)
			(xy 28.393879 -392.620513) (xy 28.35373 -392.581804) (xy 28.319644 -392.537661) (xy 28.292348 -392.489026)
			(xy 28.272425 -392.436935) (xy 28.260299 -392.382498) (xy 28.256228 -392.326876) (xy 19.35988 -392.326876)
			(xy 19.35988 -393.342876) (xy 28.256228 -393.342876) (xy 28.260299 -393.287254) (xy 28.272425 -393.232817)
			(xy 28.292348 -393.180726) (xy 28.319644 -393.132091) (xy 28.35373 -393.087948) (xy 28.393879 -393.049239)
			(xy 28.439237 -393.016788) (xy 28.488837 -392.991287) (xy 28.541621 -392.97328) (xy 28.596464 -392.96315)
			(xy 28.652198 -392.961113) (xy 28.707635 -392.967213) (xy 28.761592 -392.981319) (xy 28.812921 -393.003131)
			(xy 28.860527 -393.032185) (xy 28.903395 -393.06786) (xy 28.940612 -393.109397) (xy 28.971385 -393.15591)
			(xy 28.980564 -393.17549) (xy 31.968946 -393.17549) (xy 31.973017 -393.119868) (xy 31.985143 -393.065431)
			(xy 32.005066 -393.01334) (xy 32.032362 -392.964705) (xy 32.066448 -392.920562) (xy 32.106597 -392.881853)
			(xy 32.151955 -392.849402) (xy 32.201555 -392.823901) (xy 32.254339 -392.805894) (xy 32.309182 -392.795764)
			(xy 32.364916 -392.793727) (xy 32.420353 -392.799827) (xy 32.47431 -392.813933) (xy 32.525639 -392.835745)
			(xy 32.573245 -392.864799) (xy 32.616113 -392.900474) (xy 32.65333 -392.942011) (xy 32.684103 -392.988524)
			(xy 32.707775 -393.039021) (xy 32.723843 -393.092428) (xy 32.731963 -393.147604) (xy 32.732472 -393.17549)
			(xy 32.731963 -393.203376) (xy 32.723843 -393.258552) (xy 32.707775 -393.311959) (xy 32.684103 -393.362456)
			(xy 32.65333 -393.408969) (xy 32.616113 -393.450506) (xy 32.611761 -393.454128) (xy 38.515034 -393.454128)
			(xy 38.519105 -393.398506) (xy 38.531231 -393.344069) (xy 38.551154 -393.291978) (xy 38.57845 -393.243343)
			(xy 38.612536 -393.1992) (xy 38.652685 -393.160491) (xy 38.698043 -393.12804) (xy 38.747643 -393.102539)
			(xy 38.800427 -393.084532) (xy 38.85527 -393.074402) (xy 38.911004 -393.072365) (xy 38.966441 -393.078465)
			(xy 39.020398 -393.092571) (xy 39.071727 -393.114383) (xy 39.119333 -393.143437) (xy 39.162201 -393.179112)
			(xy 39.199418 -393.220649) (xy 39.230191 -393.267162) (xy 39.253863 -393.317659) (xy 39.269931 -393.371066)
			(xy 39.278051 -393.426242) (xy 39.27856 -393.454128) (xy 39.27837 -393.464542) (xy 40.606978 -393.464542)
			(xy 40.611049 -393.40892) (xy 40.623175 -393.354483) (xy 40.643098 -393.302392) (xy 40.670394 -393.253757)
			(xy 40.70448 -393.209614) (xy 40.744629 -393.170905) (xy 40.789987 -393.138454) (xy 40.839587 -393.112953)
			(xy 40.892371 -393.094946) (xy 40.947214 -393.084816) (xy 41.002948 -393.082779) (xy 41.058385 -393.088879)
			(xy 41.112342 -393.102985) (xy 41.163671 -393.124797) (xy 41.211277 -393.153851) (xy 41.254145 -393.189526)
			(xy 41.291362 -393.231063) (xy 41.322135 -393.277576) (xy 41.345807 -393.328073) (xy 41.361875 -393.38148)
			(xy 41.369995 -393.436656) (xy 41.370504 -393.464542) (xy 41.369995 -393.492428) (xy 41.361875 -393.547604)
			(xy 41.345807 -393.601011) (xy 41.322135 -393.651508) (xy 41.291362 -393.698021) (xy 41.254145 -393.739558)
			(xy 41.211277 -393.775233) (xy 41.163671 -393.804287) (xy 41.112342 -393.826099) (xy 41.058385 -393.840205)
			(xy 41.002948 -393.846305) (xy 40.947214 -393.844268) (xy 40.892371 -393.834138) (xy 40.839587 -393.816131)
			(xy 40.789987 -393.79063) (xy 40.744629 -393.758179) (xy 40.70448 -393.71947) (xy 40.670394 -393.675327)
			(xy 40.643098 -393.626692) (xy 40.623175 -393.574601) (xy 40.611049 -393.520164) (xy 40.606978 -393.464542)
			(xy 39.27837 -393.464542) (xy 39.278051 -393.482014) (xy 39.269931 -393.53719) (xy 39.253863 -393.590597)
			(xy 39.230191 -393.641094) (xy 39.199418 -393.687607) (xy 39.162201 -393.729144) (xy 39.119333 -393.764819)
			(xy 39.071727 -393.793873) (xy 39.020398 -393.815685) (xy 38.966441 -393.829791) (xy 38.911004 -393.835891)
			(xy 38.85527 -393.833854) (xy 38.800427 -393.823724) (xy 38.747643 -393.805717) (xy 38.698043 -393.780216)
			(xy 38.652685 -393.747765) (xy 38.612536 -393.709056) (xy 38.57845 -393.664913) (xy 38.551154 -393.616278)
			(xy 38.531231 -393.564187) (xy 38.519105 -393.50975) (xy 38.515034 -393.454128) (xy 32.611761 -393.454128)
			(xy 32.573245 -393.486181) (xy 32.525639 -393.515235) (xy 32.47431 -393.537047) (xy 32.420353 -393.551153)
			(xy 32.364916 -393.557253) (xy 32.309182 -393.555216) (xy 32.254339 -393.545086) (xy 32.201555 -393.527079)
			(xy 32.151955 -393.501578) (xy 32.106597 -393.469127) (xy 32.066448 -393.430418) (xy 32.032362 -393.386275)
			(xy 32.005066 -393.33764) (xy 31.985143 -393.285549) (xy 31.973017 -393.231112) (xy 31.968946 -393.17549)
			(xy 28.980564 -393.17549) (xy 28.995057 -393.206407) (xy 29.011125 -393.259814) (xy 29.019245 -393.31499)
			(xy 29.019754 -393.342876) (xy 29.019245 -393.370762) (xy 29.011125 -393.425938) (xy 28.995057 -393.479345)
			(xy 28.971385 -393.529842) (xy 28.940612 -393.576355) (xy 28.903395 -393.617892) (xy 28.860527 -393.653567)
			(xy 28.812921 -393.682621) (xy 28.761592 -393.704433) (xy 28.707635 -393.718539) (xy 28.652198 -393.724639)
			(xy 28.596464 -393.722602) (xy 28.541621 -393.712472) (xy 28.488837 -393.694465) (xy 28.439237 -393.668964)
			(xy 28.393879 -393.636513) (xy 28.35373 -393.597804) (xy 28.319644 -393.553661) (xy 28.292348 -393.505026)
			(xy 28.272425 -393.452935) (xy 28.260299 -393.398498) (xy 28.256228 -393.342876) (xy 19.35988 -393.342876)
			(xy 19.35988 -394.968476) (xy 19.395694 -394.979652) (xy 19.4214 -394.987978) (xy 19.470345 -395.010873)
			(xy 19.515565 -395.040451) (xy 19.556153 -395.07612) (xy 19.591297 -395.117164) (xy 19.62029 -395.162761)
			(xy 19.642553 -395.211996) (xy 19.657638 -395.263882) (xy 19.665243 -395.317379) (xy 19.665696 -395.344396)
			(xy 19.665121 -395.374224) (xy 19.65584 -395.433154) (xy 19.637505 -395.489922) (xy 19.610561 -395.543147)
			(xy 19.59356 -395.567662) (xy 19.568414 -395.602714) (xy 22.225 -398.2593) (xy 24.943816 -398.2593)
		)
		(stroke
			(width 0)
			(type solid)
		)
		(fill yes)
		(layer "In11.Cu")
		(net "P3V3_AUX")
	)
	(gr_poly
		(pts
			(xy 362.263944 -271.604486) (xy 362.281147 -271.586036) (xy 362.320158 -271.554058) (xy 362.363577 -271.528382)
			(xy 362.410393 -271.509603) (xy 362.45952 -271.498158) (xy 362.509816 -271.494313) (xy 362.560112 -271.498158)
			(xy 362.609239 -271.509603) (xy 362.656055 -271.528382) (xy 362.699474 -271.554058) (xy 362.738485 -271.586036)
			(xy 362.755688 -271.604486) (xy 363.203744 -271.604486) (xy 363.220947 -271.586036) (xy 363.259958 -271.554058)
			(xy 363.303377 -271.528382) (xy 363.350193 -271.509603) (xy 363.39932 -271.498158) (xy 363.449616 -271.494313)
			(xy 363.499912 -271.498158) (xy 363.549039 -271.509603) (xy 363.595855 -271.528382) (xy 363.639274 -271.554058)
			(xy 363.678285 -271.586036) (xy 363.695488 -271.604486) (xy 364.143036 -271.604486) (xy 364.160239 -271.586036)
			(xy 364.19925 -271.554058) (xy 364.242669 -271.528382) (xy 364.289485 -271.509603) (xy 364.338612 -271.498158)
			(xy 364.388908 -271.494313) (xy 364.439204 -271.498158) (xy 364.488331 -271.509603) (xy 364.535147 -271.528382)
			(xy 364.578566 -271.554058) (xy 364.617577 -271.586036) (xy 364.63478 -271.604486) (xy 365.083344 -271.604486)
			(xy 365.102304 -271.584216) (xy 365.145754 -271.549689) (xy 365.194358 -271.5229) (xy 365.246753 -271.504601)
			(xy 365.301467 -271.495306) (xy 365.329216 -271.494758) (xy 365.354933 -271.495248) (xy 365.405747 -271.503215)
			(xy 365.454714 -271.518955) (xy 365.500653 -271.542087) (xy 365.542455 -271.572054) (xy 365.561118 -271.589754)
			(xy 365.576104 -271.604486) (xy 365.665004 -271.604486) (xy 365.766858 -271.502632) (xy 365.77608 -271.492835)
			(xy 365.789479 -271.469514) (xy 365.796317 -271.443501) (xy 365.796119 -271.416605) (xy 365.788897 -271.390696)
			(xy 365.775155 -271.367575) (xy 365.755848 -271.348849) (xy 365.732318 -271.335821) (xy 365.71936 -271.332198)
			(xy 365.695788 -271.325908) (xy 365.650673 -271.307342) (xy 365.608779 -271.282344) (xy 365.571017 -271.251456)
			(xy 365.538207 -271.215351) (xy 365.511063 -271.174814) (xy 365.490175 -271.130727) (xy 365.475998 -271.084046)
			(xy 365.468839 -271.035789) (xy 365.468408 -271.011396) (xy 365.468918 -270.985428) (xy 365.477042 -270.934131)
			(xy 365.493091 -270.884737) (xy 365.516668 -270.838461) (xy 365.547194 -270.796442) (xy 365.583916 -270.759716)
			(xy 365.625932 -270.729186) (xy 365.672205 -270.705604) (xy 365.721598 -270.68955) (xy 365.772894 -270.68142)
			(xy 365.798862 -270.680942) (xy 365.825233 -270.681479) (xy 365.877297 -270.689908) (xy 365.902494 -270.697706)
			(xy 365.915673 -270.701563) (xy 365.94309 -270.70287) (xy 365.969864 -270.696824) (xy 365.994059 -270.683861)
			(xy 366.013924 -270.664918) (xy 366.028022 -270.641367) (xy 366.035333 -270.61491) (xy 366.035844 -270.601186)
			(xy 366.035844 -270.431768) (xy 366.017735 -270.413047) (xy 365.987048 -270.370964) (xy 365.963343 -270.324587)
			(xy 365.947207 -270.275067) (xy 365.939039 -270.223628) (xy 365.939041 -270.171544) (xy 365.947213 -270.120106)
			(xy 365.963354 -270.070586) (xy 365.987063 -270.024212) (xy 366.017753 -269.982131) (xy 366.035844 -269.963392)
			(xy 366.035844 -269.793974) (xy 366.035391 -269.780245) (xy 366.028069 -269.753781) (xy 366.01396 -269.730225)
			(xy 365.994085 -269.71128) (xy 365.969881 -269.698314) (xy 365.943097 -269.692266) (xy 365.91567 -269.693573)
			(xy 365.902494 -269.697454) (xy 365.877351 -269.705176) (xy 365.825414 -269.713471) (xy 365.799116 -269.713964)
			(xy 365.773145 -269.713482) (xy 365.721842 -269.705359) (xy 365.672442 -269.68931) (xy 365.626161 -269.665731)
			(xy 365.584138 -269.635201) (xy 365.547409 -269.598474) (xy 365.516878 -269.556453) (xy 365.493296 -269.510172)
			(xy 365.477245 -269.460773) (xy 365.469119 -269.409471) (xy 365.469119 -269.357529) (xy 365.477245 -269.306227)
			(xy 365.493296 -269.256828) (xy 365.516878 -269.210547) (xy 365.547409 -269.168526) (xy 365.584138 -269.131799)
			(xy 365.626161 -269.101269) (xy 365.672442 -269.07769) (xy 365.721842 -269.061641) (xy 365.773145 -269.053518)
			(xy 365.799116 -269.053056) (xy 365.825414 -269.053544) (xy 365.877352 -269.061838) (xy 365.902494 -269.069566)
			(xy 365.915671 -269.073424) (xy 365.943086 -269.074733) (xy 365.969857 -269.068686) (xy 365.994048 -269.055722)
			(xy 366.013907 -269.036778) (xy 366.027998 -269.013226) (xy 366.035301 -268.986769) (xy 366.035844 -268.973046)
			(xy 366.035844 -268.803882) (xy 366.017733 -268.785161) (xy 365.987045 -268.743077) (xy 365.963338 -268.6967)
			(xy 365.9472 -268.647179) (xy 365.93903 -268.595738) (xy 365.93903 -268.543653) (xy 365.947202 -268.492213)
			(xy 365.963341 -268.442692) (xy 365.987049 -268.396315) (xy 366.017739 -268.354232) (xy 366.035844 -268.335506)
			(xy 366.035844 -268.166088) (xy 366.035393 -268.152358) (xy 366.028073 -268.125891) (xy 366.013965 -268.102331)
			(xy 365.994089 -268.083382) (xy 365.969883 -268.070415) (xy 365.943097 -268.064366) (xy 365.915667 -268.065674)
			(xy 365.902494 -268.069568) (xy 365.877298 -268.07737) (xy 365.825233 -268.085795) (xy 365.798862 -268.086332)
			(xy 365.772898 -268.08582) (xy 365.721611 -268.077691) (xy 365.672227 -268.061641) (xy 365.625962 -268.038062)
			(xy 365.583954 -268.007537) (xy 365.547238 -267.970817) (xy 365.516718 -267.928806) (xy 365.493145 -267.882538)
			(xy 365.4771 -267.833152) (xy 365.468977 -267.781864) (xy 365.468977 -267.729936) (xy 365.4771 -267.678648)
			(xy 365.493145 -267.629262) (xy 365.516718 -267.582994) (xy 365.547238 -267.540983) (xy 365.583954 -267.504263)
			(xy 365.625962 -267.473738) (xy 365.672227 -267.450159) (xy 365.721611 -267.434109) (xy 365.772898 -267.42598)
			(xy 365.798862 -267.425424) (xy 365.825233 -267.425961) (xy 365.877297 -267.43439) (xy 365.902494 -267.442188)
			(xy 365.915672 -267.446045) (xy 365.943088 -267.447353) (xy 365.969861 -267.441307) (xy 365.994054 -267.428343)
			(xy 366.013916 -267.4094) (xy 366.028011 -267.385848) (xy 366.035319 -267.359392) (xy 366.035844 -267.345668)
			(xy 366.035844 -267.176504) (xy 366.017645 -267.157768) (xy 365.986797 -267.115621) (xy 365.962962 -267.069146)
			(xy 365.946735 -267.019501) (xy 365.938518 -266.967921) (xy 365.938517 -266.915691) (xy 365.946732 -266.86411)
			(xy 365.962958 -266.814464) (xy 365.986791 -266.767989) (xy 366.017638 -266.725841) (xy 366.035844 -266.707112)
			(xy 366.035844 -266.538456) (xy 366.035389 -266.524729) (xy 366.028064 -266.498269) (xy 366.013954 -266.474718)
			(xy 365.99408 -266.455776) (xy 365.969878 -266.442813) (xy 365.943098 -266.436766) (xy 365.915674 -266.438072)
			(xy 365.902494 -266.441936) (xy 365.877298 -266.449739) (xy 365.825233 -266.458165) (xy 365.798862 -266.4587)
			(xy 365.772893 -266.458188) (xy 365.721596 -266.450058) (xy 365.672201 -266.434003) (xy 365.625926 -266.41042)
			(xy 365.58391 -266.379889) (xy 365.547186 -266.343161) (xy 365.51666 -266.301141) (xy 365.493082 -266.254864)
			(xy 365.477034 -266.205467) (xy 365.468909 -266.154169) (xy 365.468909 -266.102231) (xy 365.477034 -266.050933)
			(xy 365.493082 -266.001536) (xy 365.51666 -265.955259) (xy 365.547186 -265.913239) (xy 365.58391 -265.876511)
			(xy 365.625926 -265.84598) (xy 365.672201 -265.822397) (xy 365.721596 -265.806342) (xy 365.772893 -265.798212)
			(xy 365.798862 -265.797792) (xy 365.825233 -265.798329) (xy 365.877297 -265.806757) (xy 365.902494 -265.814556)
			(xy 365.915675 -265.818411) (xy 365.943096 -265.819718) (xy 365.969874 -265.813671) (xy 365.994073 -265.800709)
			(xy 366.013944 -265.781769) (xy 366.028051 -265.758219) (xy 366.035374 -265.731762) (xy 366.035844 -265.718036)
			(xy 366.035844 -265.548618) (xy 366.017694 -265.529888) (xy 365.986934 -265.487772) (xy 365.96317 -265.441347)
			(xy 365.946994 -265.391766) (xy 365.938805 -265.34026) (xy 365.938808 -265.288106) (xy 365.947002 -265.236601)
			(xy 365.963183 -265.187022) (xy 365.986951 -265.140599) (xy 366.017716 -265.098486) (xy 366.035844 -265.079734)
			(xy 366.035844 -264.91057) (xy 366.035391 -264.896841) (xy 366.028068 -264.870379) (xy 366.013959 -264.846823)
			(xy 365.994084 -264.827879) (xy 365.96988 -264.814914) (xy 365.943097 -264.808866) (xy 365.915671 -264.810173)
			(xy 365.902494 -264.81405) (xy 365.877298 -264.821853) (xy 365.825233 -264.830278) (xy 365.798862 -264.830814)
			(xy 365.7729 -264.830302) (xy 365.721616 -264.822174) (xy 365.672234 -264.806124) (xy 365.625971 -264.782547)
			(xy 365.583965 -264.752024) (xy 365.547252 -264.715306) (xy 365.516733 -264.673296) (xy 365.493162 -264.627031)
			(xy 365.477117 -264.577647) (xy 365.468995 -264.526362) (xy 365.468995 -264.474438) (xy 365.477117 -264.423153)
			(xy 365.493162 -264.373769) (xy 365.516733 -264.327504) (xy 365.547252 -264.285494) (xy 365.583965 -264.248776)
			(xy 365.625971 -264.218253) (xy 365.672234 -264.194676) (xy 365.721616 -264.178626) (xy 365.7729 -264.170498)
			(xy 365.798862 -264.169906) (xy 365.825233 -264.170443) (xy 365.877297 -264.178871) (xy 365.902494 -264.18667)
			(xy 365.915671 -264.190528) (xy 365.943086 -264.191836) (xy 365.969858 -264.18579) (xy 365.994049 -264.172826)
			(xy 366.013909 -264.153882) (xy 366.028001 -264.13033) (xy 366.035304 -264.103873) (xy 366.035844 -264.09015)
			(xy 366.035844 -262.104886) (xy 365.822484 -261.891526) (xy 363.584744 -261.891526) (xy 361.886754 -263.589516)
			(xy 361.892596 -263.61644) (xy 361.896148 -263.633748) (xy 361.899966 -263.668877) (xy 361.900216 -263.686544)
			(xy 361.89975 -263.71192) (xy 361.899659 -263.712511) (xy 362.179617 -263.712511) (xy 362.179617 -263.660577)
			(xy 362.187742 -263.609282) (xy 362.20379 -263.559889) (xy 362.227368 -263.513615) (xy 362.257894 -263.471599)
			(xy 362.294617 -263.434876) (xy 362.336633 -263.40435) (xy 362.382907 -263.380772) (xy 362.4323 -263.364724)
			(xy 362.483595 -263.356599) (xy 362.535529 -263.356599) (xy 362.586824 -263.364724) (xy 362.636217 -263.380772)
			(xy 362.682491 -263.40435) (xy 362.724507 -263.434876) (xy 362.76123 -263.471599) (xy 362.791756 -263.513615)
			(xy 362.815334 -263.559889) (xy 362.831382 -263.609282) (xy 362.839507 -263.660577) (xy 362.840016 -263.686544)
			(xy 362.839507 -263.712511) (xy 363.119671 -263.712511) (xy 363.119671 -263.660577) (xy 363.127796 -263.609282)
			(xy 363.143844 -263.559889) (xy 363.167422 -263.513615) (xy 363.197948 -263.471599) (xy 363.234671 -263.434876)
			(xy 363.276687 -263.40435) (xy 363.322961 -263.380772) (xy 363.372354 -263.364724) (xy 363.423649 -263.356599)
			(xy 363.475583 -263.356599) (xy 363.526878 -263.364724) (xy 363.576271 -263.380772) (xy 363.622545 -263.40435)
			(xy 363.664561 -263.434876) (xy 363.701284 -263.471599) (xy 363.73181 -263.513615) (xy 363.755388 -263.559889)
			(xy 363.771436 -263.609282) (xy 363.779561 -263.660577) (xy 363.78007 -263.686544) (xy 363.779561 -263.712511)
			(xy 363.771436 -263.763806) (xy 363.755388 -263.813199) (xy 363.73181 -263.859473) (xy 363.701284 -263.901489)
			(xy 363.664561 -263.938212) (xy 363.622545 -263.968738) (xy 363.576271 -263.992316) (xy 363.526878 -264.008364)
			(xy 363.475583 -264.016489) (xy 363.423649 -264.016489) (xy 363.372354 -264.008364) (xy 363.322961 -263.992316)
			(xy 363.276687 -263.968738) (xy 363.234671 -263.938212) (xy 363.197948 -263.901489) (xy 363.167422 -263.859473)
			(xy 363.143844 -263.813199) (xy 363.127796 -263.763806) (xy 363.119671 -263.712511) (xy 362.839507 -263.712511)
			(xy 362.831382 -263.763806) (xy 362.815334 -263.813199) (xy 362.791756 -263.859473) (xy 362.76123 -263.901489)
			(xy 362.724507 -263.938212) (xy 362.682491 -263.968738) (xy 362.636217 -263.992316) (xy 362.586824 -264.008364)
			(xy 362.535529 -264.016489) (xy 362.483595 -264.016489) (xy 362.4323 -264.008364) (xy 362.382907 -263.992316)
			(xy 362.336633 -263.968738) (xy 362.294617 -263.938212) (xy 362.257894 -263.901489) (xy 362.227368 -263.859473)
			(xy 362.20379 -263.813199) (xy 362.187742 -263.763806) (xy 362.179617 -263.712511) (xy 361.899659 -263.712511)
			(xy 361.891987 -263.762075) (xy 361.876651 -263.810455) (xy 361.854101 -263.855923) (xy 361.824868 -263.897411)
			(xy 361.789638 -263.933944) (xy 361.749239 -263.964664) (xy 361.70462 -263.988849) (xy 361.656828 -264.005931)
			(xy 361.631992 -264.011156) (xy 361.590844 -264.01903) (xy 361.590844 -264.526327) (xy 361.709717 -264.526327)
			(xy 361.709717 -264.474393) (xy 361.717842 -264.423098) (xy 361.73389 -264.373705) (xy 361.757468 -264.327431)
			(xy 361.787994 -264.285415) (xy 361.824717 -264.248692) (xy 361.866733 -264.218166) (xy 361.913007 -264.194588)
			(xy 361.9624 -264.17854) (xy 362.013695 -264.170415) (xy 362.065629 -264.170415) (xy 362.116924 -264.17854)
			(xy 362.166317 -264.194588) (xy 362.212591 -264.218166) (xy 362.254607 -264.248692) (xy 362.29133 -264.285415)
			(xy 362.321856 -264.327431) (xy 362.345434 -264.373705) (xy 362.361482 -264.423098) (xy 362.369607 -264.474393)
			(xy 362.370116 -264.50036) (xy 362.369607 -264.526327) (xy 362.649517 -264.526327) (xy 362.649517 -264.474393)
			(xy 362.657642 -264.423098) (xy 362.67369 -264.373705) (xy 362.697268 -264.327431) (xy 362.727794 -264.285415)
			(xy 362.764517 -264.248692) (xy 362.806533 -264.218166) (xy 362.852807 -264.194588) (xy 362.9022 -264.17854)
			(xy 362.953495 -264.170415) (xy 363.005429 -264.170415) (xy 363.056724 -264.17854) (xy 363.106117 -264.194588)
			(xy 363.152391 -264.218166) (xy 363.194407 -264.248692) (xy 363.23113 -264.285415) (xy 363.261656 -264.327431)
			(xy 363.285234 -264.373705) (xy 363.301282 -264.423098) (xy 363.309407 -264.474393) (xy 363.309916 -264.50036)
			(xy 363.309407 -264.526327) (xy 363.589317 -264.526327) (xy 363.589317 -264.474393) (xy 363.597442 -264.423098)
			(xy 363.61349 -264.373705) (xy 363.637068 -264.327431) (xy 363.667594 -264.285415) (xy 363.704317 -264.248692)
			(xy 363.746333 -264.218166) (xy 363.792607 -264.194588) (xy 363.842 -264.17854) (xy 363.893295 -264.170415)
			(xy 363.945229 -264.170415) (xy 363.996524 -264.17854) (xy 364.045917 -264.194588) (xy 364.092191 -264.218166)
			(xy 364.134207 -264.248692) (xy 364.17093 -264.285415) (xy 364.201456 -264.327431) (xy 364.225034 -264.373705)
			(xy 364.241082 -264.423098) (xy 364.249207 -264.474393) (xy 364.249716 -264.50036) (xy 364.249207 -264.526327)
			(xy 364.529117 -264.526327) (xy 364.529117 -264.474393) (xy 364.537242 -264.423098) (xy 364.55329 -264.373705)
			(xy 364.576868 -264.327431) (xy 364.607394 -264.285415) (xy 364.644117 -264.248692) (xy 364.686133 -264.218166)
			(xy 364.732407 -264.194588) (xy 364.7818 -264.17854) (xy 364.833095 -264.170415) (xy 364.885029 -264.170415)
			(xy 364.936324 -264.17854) (xy 364.985717 -264.194588) (xy 365.031991 -264.218166) (xy 365.074007 -264.248692)
			(xy 365.11073 -264.285415) (xy 365.141256 -264.327431) (xy 365.164834 -264.373705) (xy 365.180882 -264.423098)
			(xy 365.189007 -264.474393) (xy 365.189516 -264.50036) (xy 365.189007 -264.526327) (xy 365.180882 -264.577622)
			(xy 365.164834 -264.627015) (xy 365.141256 -264.673289) (xy 365.11073 -264.715305) (xy 365.074007 -264.752028)
			(xy 365.031991 -264.782554) (xy 364.985717 -264.806132) (xy 364.936324 -264.82218) (xy 364.885029 -264.830305)
			(xy 364.833095 -264.830305) (xy 364.7818 -264.82218) (xy 364.732407 -264.806132) (xy 364.686133 -264.782554)
			(xy 364.644117 -264.752028) (xy 364.607394 -264.715305) (xy 364.576868 -264.673289) (xy 364.55329 -264.627015)
			(xy 364.537242 -264.577622) (xy 364.529117 -264.526327) (xy 364.249207 -264.526327) (xy 364.241082 -264.577622)
			(xy 364.225034 -264.627015) (xy 364.201456 -264.673289) (xy 364.17093 -264.715305) (xy 364.134207 -264.752028)
			(xy 364.092191 -264.782554) (xy 364.045917 -264.806132) (xy 363.996524 -264.82218) (xy 363.945229 -264.830305)
			(xy 363.893295 -264.830305) (xy 363.842 -264.82218) (xy 363.792607 -264.806132) (xy 363.746333 -264.782554)
			(xy 363.704317 -264.752028) (xy 363.667594 -264.715305) (xy 363.637068 -264.673289) (xy 363.61349 -264.627015)
			(xy 363.597442 -264.577622) (xy 363.589317 -264.526327) (xy 363.309407 -264.526327) (xy 363.301282 -264.577622)
			(xy 363.285234 -264.627015) (xy 363.261656 -264.673289) (xy 363.23113 -264.715305) (xy 363.194407 -264.752028)
			(xy 363.152391 -264.782554) (xy 363.106117 -264.806132) (xy 363.056724 -264.82218) (xy 363.005429 -264.830305)
			(xy 362.953495 -264.830305) (xy 362.9022 -264.82218) (xy 362.852807 -264.806132) (xy 362.806533 -264.782554)
			(xy 362.764517 -264.752028) (xy 362.727794 -264.715305) (xy 362.697268 -264.673289) (xy 362.67369 -264.627015)
			(xy 362.657642 -264.577622) (xy 362.649517 -264.526327) (xy 362.369607 -264.526327) (xy 362.361482 -264.577622)
			(xy 362.345434 -264.627015) (xy 362.321856 -264.673289) (xy 362.29133 -264.715305) (xy 362.254607 -264.752028)
			(xy 362.212591 -264.782554) (xy 362.166317 -264.806132) (xy 362.116924 -264.82218) (xy 362.065629 -264.830305)
			(xy 362.013695 -264.830305) (xy 361.9624 -264.82218) (xy 361.913007 -264.806132) (xy 361.866733 -264.782554)
			(xy 361.824717 -264.752028) (xy 361.787994 -264.715305) (xy 361.757468 -264.673289) (xy 361.73389 -264.627015)
			(xy 361.717842 -264.577622) (xy 361.709717 -264.526327) (xy 361.590844 -264.526327) (xy 361.590844 -264.98169)
			(xy 361.631992 -264.989564) (xy 361.656835 -264.994795) (xy 361.704648 -265.011858) (xy 361.74929 -265.036031)
			(xy 361.789711 -265.066745) (xy 361.82496 -265.103279) (xy 361.854209 -265.144772) (xy 361.876771 -265.19025)
			(xy 361.892113 -265.238643) (xy 361.899876 -265.288812) (xy 361.899876 -265.339579) (xy 361.899789 -265.340143)
			(xy 362.179617 -265.340143) (xy 362.179617 -265.288209) (xy 362.187742 -265.236914) (xy 362.20379 -265.187521)
			(xy 362.227368 -265.141247) (xy 362.257894 -265.099231) (xy 362.294617 -265.062508) (xy 362.336633 -265.031982)
			(xy 362.382907 -265.008404) (xy 362.4323 -264.992356) (xy 362.483595 -264.984231) (xy 362.535529 -264.984231)
			(xy 362.586824 -264.992356) (xy 362.636217 -265.008404) (xy 362.682491 -265.031982) (xy 362.724507 -265.062508)
			(xy 362.76123 -265.099231) (xy 362.791756 -265.141247) (xy 362.815334 -265.187521) (xy 362.831382 -265.236914)
			(xy 362.839507 -265.288209) (xy 362.840016 -265.314176) (xy 362.839507 -265.340143) (xy 363.119671 -265.340143)
			(xy 363.119671 -265.288209) (xy 363.127796 -265.236914) (xy 363.143844 -265.187521) (xy 363.167422 -265.141247)
			(xy 363.197948 -265.099231) (xy 363.234671 -265.062508) (xy 363.276687 -265.031982) (xy 363.322961 -265.008404)
			(xy 363.372354 -264.992356) (xy 363.423649 -264.984231) (xy 363.475583 -264.984231) (xy 363.526878 -264.992356)
			(xy 363.576271 -265.008404) (xy 363.622545 -265.031982) (xy 363.664561 -265.062508) (xy 363.701284 -265.099231)
			(xy 363.73181 -265.141247) (xy 363.755388 -265.187521) (xy 363.771436 -265.236914) (xy 363.779561 -265.288209)
			(xy 363.78007 -265.314176) (xy 363.779561 -265.340143) (xy 364.059471 -265.340143) (xy 364.059471 -265.288209)
			(xy 364.067596 -265.236914) (xy 364.083644 -265.187521) (xy 364.107222 -265.141247) (xy 364.137748 -265.099231)
			(xy 364.174471 -265.062508) (xy 364.216487 -265.031982) (xy 364.262761 -265.008404) (xy 364.312154 -264.992356)
			(xy 364.363449 -264.984231) (xy 364.415383 -264.984231) (xy 364.466678 -264.992356) (xy 364.516071 -265.008404)
			(xy 364.562345 -265.031982) (xy 364.604361 -265.062508) (xy 364.641084 -265.099231) (xy 364.67161 -265.141247)
			(xy 364.695188 -265.187521) (xy 364.711236 -265.236914) (xy 364.719361 -265.288209) (xy 364.71987 -265.314176)
			(xy 364.719361 -265.340143) (xy 364.999271 -265.340143) (xy 364.999271 -265.288209) (xy 365.007396 -265.236914)
			(xy 365.023444 -265.187521) (xy 365.047022 -265.141247) (xy 365.077548 -265.099231) (xy 365.114271 -265.062508)
			(xy 365.156287 -265.031982) (xy 365.202561 -265.008404) (xy 365.251954 -264.992356) (xy 365.303249 -264.984231)
			(xy 365.355183 -264.984231) (xy 365.406478 -264.992356) (xy 365.455871 -265.008404) (xy 365.502145 -265.031982)
			(xy 365.544161 -265.062508) (xy 365.580884 -265.099231) (xy 365.61141 -265.141247) (xy 365.634988 -265.187521)
			(xy 365.651036 -265.236914) (xy 365.659161 -265.288209) (xy 365.65967 -265.314176) (xy 365.659161 -265.340143)
			(xy 365.651036 -265.391438) (xy 365.634988 -265.440831) (xy 365.61141 -265.487105) (xy 365.580884 -265.529121)
			(xy 365.544161 -265.565844) (xy 365.502145 -265.59637) (xy 365.455871 -265.619948) (xy 365.406478 -265.635996)
			(xy 365.355183 -265.644121) (xy 365.303249 -265.644121) (xy 365.251954 -265.635996) (xy 365.202561 -265.619948)
			(xy 365.156287 -265.59637) (xy 365.114271 -265.565844) (xy 365.077548 -265.529121) (xy 365.047022 -265.487105)
			(xy 365.023444 -265.440831) (xy 365.007396 -265.391438) (xy 364.999271 -265.340143) (xy 364.719361 -265.340143)
			(xy 364.711236 -265.391438) (xy 364.695188 -265.440831) (xy 364.67161 -265.487105) (xy 364.641084 -265.529121)
			(xy 364.604361 -265.565844) (xy 364.562345 -265.59637) (xy 364.516071 -265.619948) (xy 364.466678 -265.635996)
			(xy 364.415383 -265.644121) (xy 364.363449 -265.644121) (xy 364.312154 -265.635996) (xy 364.262761 -265.619948)
			(xy 364.216487 -265.59637) (xy 364.174471 -265.565844) (xy 364.137748 -265.529121) (xy 364.107222 -265.487105)
			(xy 364.083644 -265.440831) (xy 364.067596 -265.391438) (xy 364.059471 -265.340143) (xy 363.779561 -265.340143)
			(xy 363.771436 -265.391438) (xy 363.755388 -265.440831) (xy 363.73181 -265.487105) (xy 363.701284 -265.529121)
			(xy 363.664561 -265.565844) (xy 363.622545 -265.59637) (xy 363.576271 -265.619948) (xy 363.526878 -265.635996)
			(xy 363.475583 -265.644121) (xy 363.423649 -265.644121) (xy 363.372354 -265.635996) (xy 363.322961 -265.619948)
			(xy 363.276687 -265.59637) (xy 363.234671 -265.565844) (xy 363.197948 -265.529121) (xy 363.167422 -265.487105)
			(xy 363.143844 -265.440831) (xy 363.127796 -265.391438) (xy 363.119671 -265.340143) (xy 362.839507 -265.340143)
			(xy 362.831382 -265.391438) (xy 362.815334 -265.440831) (xy 362.791756 -265.487105) (xy 362.76123 -265.529121)
			(xy 362.724507 -265.565844) (xy 362.682491 -265.59637) (xy 362.636217 -265.619948) (xy 362.586824 -265.635996)
			(xy 362.535529 -265.644121) (xy 362.483595 -265.644121) (xy 362.4323 -265.635996) (xy 362.382907 -265.619948)
			(xy 362.336633 -265.59637) (xy 362.294617 -265.565844) (xy 362.257894 -265.529121) (xy 362.227368 -265.487105)
			(xy 362.20379 -265.440831) (xy 362.187742 -265.391438) (xy 362.179617 -265.340143) (xy 361.899789 -265.340143)
			(xy 361.892115 -265.389748) (xy 361.876774 -265.438141) (xy 361.854214 -265.48362) (xy 361.824966 -265.525114)
			(xy 361.789717 -265.561649) (xy 361.749297 -265.592364) (xy 361.704656 -265.616538) (xy 361.656843 -265.633602)
			(xy 361.631992 -265.638788) (xy 361.590844 -265.646662) (xy 361.590844 -266.154213) (xy 361.709717 -266.154213)
			(xy 361.709717 -266.102279) (xy 361.717842 -266.050984) (xy 361.73389 -266.001591) (xy 361.757468 -265.955317)
			(xy 361.787994 -265.913301) (xy 361.824717 -265.876578) (xy 361.866733 -265.846052) (xy 361.913007 -265.822474)
			(xy 361.9624 -265.806426) (xy 362.013695 -265.798301) (xy 362.065629 -265.798301) (xy 362.116924 -265.806426)
			(xy 362.166317 -265.822474) (xy 362.212591 -265.846052) (xy 362.254607 -265.876578) (xy 362.29133 -265.913301)
			(xy 362.321856 -265.955317) (xy 362.345434 -266.001591) (xy 362.361482 -266.050984) (xy 362.369607 -266.102279)
			(xy 362.370116 -266.128246) (xy 362.369607 -266.154213) (xy 362.649517 -266.154213) (xy 362.649517 -266.102279)
			(xy 362.657642 -266.050984) (xy 362.67369 -266.001591) (xy 362.697268 -265.955317) (xy 362.727794 -265.913301)
			(xy 362.764517 -265.876578) (xy 362.806533 -265.846052) (xy 362.852807 -265.822474) (xy 362.9022 -265.806426)
			(xy 362.953495 -265.798301) (xy 363.005429 -265.798301) (xy 363.056724 -265.806426) (xy 363.106117 -265.822474)
			(xy 363.152391 -265.846052) (xy 363.194407 -265.876578) (xy 363.23113 -265.913301) (xy 363.261656 -265.955317)
			(xy 363.285234 -266.001591) (xy 363.301282 -266.050984) (xy 363.309407 -266.102279) (xy 363.309916 -266.128246)
			(xy 363.309407 -266.154213) (xy 363.589317 -266.154213) (xy 363.589317 -266.102279) (xy 363.597442 -266.050984)
			(xy 363.61349 -266.001591) (xy 363.637068 -265.955317) (xy 363.667594 -265.913301) (xy 363.704317 -265.876578)
			(xy 363.746333 -265.846052) (xy 363.792607 -265.822474) (xy 363.842 -265.806426) (xy 363.893295 -265.798301)
			(xy 363.945229 -265.798301) (xy 363.996524 -265.806426) (xy 364.045917 -265.822474) (xy 364.092191 -265.846052)
			(xy 364.134207 -265.876578) (xy 364.17093 -265.913301) (xy 364.201456 -265.955317) (xy 364.225034 -266.001591)
			(xy 364.241082 -266.050984) (xy 364.249207 -266.102279) (xy 364.249716 -266.128246) (xy 364.249207 -266.154213)
			(xy 364.249167 -266.154467) (xy 364.529117 -266.154467) (xy 364.529117 -266.102533) (xy 364.537242 -266.051238)
			(xy 364.55329 -266.001845) (xy 364.576868 -265.955571) (xy 364.607394 -265.913555) (xy 364.644117 -265.876832)
			(xy 364.686133 -265.846306) (xy 364.732407 -265.822728) (xy 364.7818 -265.80668) (xy 364.833095 -265.798555)
			(xy 364.885029 -265.798555) (xy 364.936324 -265.80668) (xy 364.985717 -265.822728) (xy 365.031991 -265.846306)
			(xy 365.074007 -265.876832) (xy 365.11073 -265.913555) (xy 365.141256 -265.955571) (xy 365.164834 -266.001845)
			(xy 365.180882 -266.051238) (xy 365.189007 -266.102533) (xy 365.189516 -266.1285) (xy 365.189007 -266.154467)
			(xy 365.180882 -266.205762) (xy 365.164834 -266.255155) (xy 365.141256 -266.301429) (xy 365.11073 -266.343445)
			(xy 365.074007 -266.380168) (xy 365.031991 -266.410694) (xy 364.985717 -266.434272) (xy 364.936324 -266.45032)
			(xy 364.885029 -266.458445) (xy 364.833095 -266.458445) (xy 364.7818 -266.45032) (xy 364.732407 -266.434272)
			(xy 364.686133 -266.410694) (xy 364.644117 -266.380168) (xy 364.607394 -266.343445) (xy 364.576868 -266.301429)
			(xy 364.55329 -266.255155) (xy 364.537242 -266.205762) (xy 364.529117 -266.154467) (xy 364.249167 -266.154467)
			(xy 364.241082 -266.205508) (xy 364.225034 -266.254901) (xy 364.201456 -266.301175) (xy 364.17093 -266.343191)
			(xy 364.134207 -266.379914) (xy 364.092191 -266.41044) (xy 364.045917 -266.434018) (xy 363.996524 -266.450066)
			(xy 363.945229 -266.458191) (xy 363.893295 -266.458191) (xy 363.842 -266.450066) (xy 363.792607 -266.434018)
			(xy 363.746333 -266.41044) (xy 363.704317 -266.379914) (xy 363.667594 -266.343191) (xy 363.637068 -266.301175)
			(xy 363.61349 -266.254901) (xy 363.597442 -266.205508) (xy 363.589317 -266.154213) (xy 363.309407 -266.154213)
			(xy 363.301282 -266.205508) (xy 363.285234 -266.254901) (xy 363.261656 -266.301175) (xy 363.23113 -266.343191)
			(xy 363.194407 -266.379914) (xy 363.152391 -266.41044) (xy 363.106117 -266.434018) (xy 363.056724 -266.450066)
			(xy 363.005429 -266.458191) (xy 362.953495 -266.458191) (xy 362.9022 -266.450066) (xy 362.852807 -266.434018)
			(xy 362.806533 -266.41044) (xy 362.764517 -266.379914) (xy 362.727794 -266.343191) (xy 362.697268 -266.301175)
			(xy 362.67369 -266.254901) (xy 362.657642 -266.205508) (xy 362.649517 -266.154213) (xy 362.369607 -266.154213)
			(xy 362.361482 -266.205508) (xy 362.345434 -266.254901) (xy 362.321856 -266.301175) (xy 362.29133 -266.343191)
			(xy 362.254607 -266.379914) (xy 362.212591 -266.41044) (xy 362.166317 -266.434018) (xy 362.116924 -266.450066)
			(xy 362.065629 -266.458191) (xy 362.013695 -266.458191) (xy 361.9624 -266.450066) (xy 361.913007 -266.434018)
			(xy 361.866733 -266.41044) (xy 361.824717 -266.379914) (xy 361.787994 -266.343191) (xy 361.757468 -266.301175)
			(xy 361.73389 -266.254901) (xy 361.717842 -266.205508) (xy 361.709717 -266.154213) (xy 361.590844 -266.154213)
			(xy 361.590844 -266.609322) (xy 361.631992 -266.617196) (xy 361.656832 -266.622427) (xy 361.70464 -266.639489)
			(xy 361.749278 -266.663661) (xy 361.789694 -266.694373) (xy 361.82494 -266.730904) (xy 361.854186 -266.772394)
			(xy 361.876744 -266.817868) (xy 361.892084 -266.866256) (xy 361.899845 -266.916421) (xy 361.899845 -266.967182)
			(xy 361.899753 -266.967775) (xy 362.179617 -266.967775) (xy 362.179617 -266.915841) (xy 362.187742 -266.864546)
			(xy 362.20379 -266.815153) (xy 362.227368 -266.768879) (xy 362.257894 -266.726863) (xy 362.294617 -266.69014)
			(xy 362.336633 -266.659614) (xy 362.382907 -266.636036) (xy 362.4323 -266.619988) (xy 362.483595 -266.611863)
			(xy 362.535529 -266.611863) (xy 362.586824 -266.619988) (xy 362.636217 -266.636036) (xy 362.682491 -266.659614)
			(xy 362.724507 -266.69014) (xy 362.76123 -266.726863) (xy 362.791756 -266.768879) (xy 362.815334 -266.815153)
			(xy 362.831382 -266.864546) (xy 362.839507 -266.915841) (xy 362.840016 -266.941808) (xy 362.839507 -266.967775)
			(xy 363.119417 -266.967775) (xy 363.119417 -266.915841) (xy 363.127542 -266.864546) (xy 363.14359 -266.815153)
			(xy 363.167168 -266.768879) (xy 363.197694 -266.726863) (xy 363.234417 -266.69014) (xy 363.276433 -266.659614)
			(xy 363.322707 -266.636036) (xy 363.3721 -266.619988) (xy 363.423395 -266.611863) (xy 363.475329 -266.611863)
			(xy 363.526624 -266.619988) (xy 363.576017 -266.636036) (xy 363.622291 -266.659614) (xy 363.664307 -266.69014)
			(xy 363.70103 -266.726863) (xy 363.731556 -266.768879) (xy 363.755134 -266.815153) (xy 363.771182 -266.864546)
			(xy 363.779307 -266.915841) (xy 363.779816 -266.941808) (xy 363.779307 -266.967775) (xy 364.059217 -266.967775)
			(xy 364.059217 -266.915841) (xy 364.067342 -266.864546) (xy 364.08339 -266.815153) (xy 364.106968 -266.768879)
			(xy 364.137494 -266.726863) (xy 364.174217 -266.69014) (xy 364.216233 -266.659614) (xy 364.262507 -266.636036)
			(xy 364.3119 -266.619988) (xy 364.363195 -266.611863) (xy 364.415129 -266.611863) (xy 364.466424 -266.619988)
			(xy 364.515817 -266.636036) (xy 364.562091 -266.659614) (xy 364.604107 -266.69014) (xy 364.64083 -266.726863)
			(xy 364.671356 -266.768879) (xy 364.694934 -266.815153) (xy 364.710982 -266.864546) (xy 364.719107 -266.915841)
			(xy 364.719616 -266.941808) (xy 364.719107 -266.967775) (xy 364.999271 -266.967775) (xy 364.999271 -266.915841)
			(xy 365.007396 -266.864546) (xy 365.023444 -266.815153) (xy 365.047022 -266.768879) (xy 365.077548 -266.726863)
			(xy 365.114271 -266.69014) (xy 365.156287 -266.659614) (xy 365.202561 -266.636036) (xy 365.251954 -266.619988)
			(xy 365.303249 -266.611863) (xy 365.355183 -266.611863) (xy 365.406478 -266.619988) (xy 365.455871 -266.636036)
			(xy 365.502145 -266.659614) (xy 365.544161 -266.69014) (xy 365.580884 -266.726863) (xy 365.61141 -266.768879)
			(xy 365.634988 -266.815153) (xy 365.651036 -266.864546) (xy 365.659161 -266.915841) (xy 365.65967 -266.941808)
			(xy 365.659161 -266.967775) (xy 365.651036 -267.01907) (xy 365.634988 -267.068463) (xy 365.61141 -267.114737)
			(xy 365.580884 -267.156753) (xy 365.544161 -267.193476) (xy 365.502145 -267.224002) (xy 365.455871 -267.24758)
			(xy 365.406478 -267.263628) (xy 365.355183 -267.271753) (xy 365.303249 -267.271753) (xy 365.251954 -267.263628)
			(xy 365.202561 -267.24758) (xy 365.156287 -267.224002) (xy 365.114271 -267.193476) (xy 365.077548 -267.156753)
			(xy 365.047022 -267.114737) (xy 365.023444 -267.068463) (xy 365.007396 -267.01907) (xy 364.999271 -266.967775)
			(xy 364.719107 -266.967775) (xy 364.710982 -267.01907) (xy 364.694934 -267.068463) (xy 364.671356 -267.114737)
			(xy 364.64083 -267.156753) (xy 364.604107 -267.193476) (xy 364.562091 -267.224002) (xy 364.515817 -267.24758)
			(xy 364.466424 -267.263628) (xy 364.415129 -267.271753) (xy 364.363195 -267.271753) (xy 364.3119 -267.263628)
			(xy 364.262507 -267.24758) (xy 364.216233 -267.224002) (xy 364.174217 -267.193476) (xy 364.137494 -267.156753)
			(xy 364.106968 -267.114737) (xy 364.08339 -267.068463) (xy 364.067342 -267.01907) (xy 364.059217 -266.967775)
			(xy 363.779307 -266.967775) (xy 363.771182 -267.01907) (xy 363.755134 -267.068463) (xy 363.731556 -267.114737)
			(xy 363.70103 -267.156753) (xy 363.664307 -267.193476) (xy 363.622291 -267.224002) (xy 363.576017 -267.24758)
			(xy 363.526624 -267.263628) (xy 363.475329 -267.271753) (xy 363.423395 -267.271753) (xy 363.3721 -267.263628)
			(xy 363.322707 -267.24758) (xy 363.276433 -267.224002) (xy 363.234417 -267.193476) (xy 363.197694 -267.156753)
			(xy 363.167168 -267.114737) (xy 363.14359 -267.068463) (xy 363.127542 -267.01907) (xy 363.119417 -266.967775)
			(xy 362.839507 -266.967775) (xy 362.831382 -267.01907) (xy 362.815334 -267.068463) (xy 362.791756 -267.114737)
			(xy 362.76123 -267.156753) (xy 362.724507 -267.193476) (xy 362.682491 -267.224002) (xy 362.636217 -267.24758)
			(xy 362.586824 -267.263628) (xy 362.535529 -267.271753) (xy 362.483595 -267.271753) (xy 362.4323 -267.263628)
			(xy 362.382907 -267.24758) (xy 362.336633 -267.224002) (xy 362.294617 -267.193476) (xy 362.257894 -267.156753)
			(xy 362.227368 -267.114737) (xy 362.20379 -267.068463) (xy 362.187742 -267.01907) (xy 362.179617 -266.967775)
			(xy 361.899753 -266.967775) (xy 361.892083 -267.017347) (xy 361.876743 -267.065735) (xy 361.854184 -267.111209)
			(xy 361.824938 -267.152699) (xy 361.789692 -267.189229) (xy 361.749275 -267.219941) (xy 361.704638 -267.244112)
			(xy 361.656829 -267.261174) (xy 361.631992 -267.26642) (xy 361.590844 -267.274294) (xy 361.590844 -267.781845)
			(xy 361.709717 -267.781845) (xy 361.709717 -267.729911) (xy 361.717842 -267.678616) (xy 361.73389 -267.629223)
			(xy 361.757468 -267.582949) (xy 361.787994 -267.540933) (xy 361.824717 -267.50421) (xy 361.866733 -267.473684)
			(xy 361.913007 -267.450106) (xy 361.9624 -267.434058) (xy 362.013695 -267.425933) (xy 362.065629 -267.425933)
			(xy 362.116924 -267.434058) (xy 362.166317 -267.450106) (xy 362.212591 -267.473684) (xy 362.254607 -267.50421)
			(xy 362.29133 -267.540933) (xy 362.321856 -267.582949) (xy 362.345434 -267.629223) (xy 362.361482 -267.678616)
			(xy 362.369607 -267.729911) (xy 362.370116 -267.755878) (xy 362.369607 -267.781845) (xy 362.649517 -267.781845)
			(xy 362.649517 -267.729911) (xy 362.657642 -267.678616) (xy 362.67369 -267.629223) (xy 362.697268 -267.582949)
			(xy 362.727794 -267.540933) (xy 362.764517 -267.50421) (xy 362.806533 -267.473684) (xy 362.852807 -267.450106)
			(xy 362.9022 -267.434058) (xy 362.953495 -267.425933) (xy 363.005429 -267.425933) (xy 363.056724 -267.434058)
			(xy 363.106117 -267.450106) (xy 363.152391 -267.473684) (xy 363.194407 -267.50421) (xy 363.23113 -267.540933)
			(xy 363.261656 -267.582949) (xy 363.285234 -267.629223) (xy 363.301282 -267.678616) (xy 363.309407 -267.729911)
			(xy 363.309916 -267.755878) (xy 363.309407 -267.781845) (xy 363.589317 -267.781845) (xy 363.589317 -267.729911)
			(xy 363.597442 -267.678616) (xy 363.61349 -267.629223) (xy 363.637068 -267.582949) (xy 363.667594 -267.540933)
			(xy 363.704317 -267.50421) (xy 363.746333 -267.473684) (xy 363.792607 -267.450106) (xy 363.842 -267.434058)
			(xy 363.893295 -267.425933) (xy 363.945229 -267.425933) (xy 363.996524 -267.434058) (xy 364.045917 -267.450106)
			(xy 364.092191 -267.473684) (xy 364.134207 -267.50421) (xy 364.17093 -267.540933) (xy 364.201456 -267.582949)
			(xy 364.225034 -267.629223) (xy 364.241082 -267.678616) (xy 364.249207 -267.729911) (xy 364.249716 -267.755878)
			(xy 364.249207 -267.781845) (xy 364.529371 -267.781845) (xy 364.529371 -267.729911) (xy 364.537496 -267.678616)
			(xy 364.553544 -267.629223) (xy 364.577122 -267.582949) (xy 364.607648 -267.540933) (xy 364.644371 -267.50421)
			(xy 364.686387 -267.473684) (xy 364.732661 -267.450106) (xy 364.782054 -267.434058) (xy 364.833349 -267.425933)
			(xy 364.885283 -267.425933) (xy 364.936578 -267.434058) (xy 364.985971 -267.450106) (xy 365.032245 -267.473684)
			(xy 365.074261 -267.50421) (xy 365.110984 -267.540933) (xy 365.14151 -267.582949) (xy 365.165088 -267.629223)
			(xy 365.181136 -267.678616) (xy 365.189261 -267.729911) (xy 365.18977 -267.755878) (xy 365.189261 -267.781845)
			(xy 365.181136 -267.83314) (xy 365.165088 -267.882533) (xy 365.14151 -267.928807) (xy 365.110984 -267.970823)
			(xy 365.074261 -268.007546) (xy 365.032245 -268.038072) (xy 364.985971 -268.06165) (xy 364.936578 -268.077698)
			(xy 364.885283 -268.085823) (xy 364.833349 -268.085823) (xy 364.782054 -268.077698) (xy 364.732661 -268.06165)
			(xy 364.686387 -268.038072) (xy 364.644371 -268.007546) (xy 364.607648 -267.970823) (xy 364.577122 -267.928807)
			(xy 364.553544 -267.882533) (xy 364.537496 -267.83314) (xy 364.529371 -267.781845) (xy 364.249207 -267.781845)
			(xy 364.241082 -267.83314) (xy 364.225034 -267.882533) (xy 364.201456 -267.928807) (xy 364.17093 -267.970823)
			(xy 364.134207 -268.007546) (xy 364.092191 -268.038072) (xy 364.045917 -268.06165) (xy 363.996524 -268.077698)
			(xy 363.945229 -268.085823) (xy 363.893295 -268.085823) (xy 363.842 -268.077698) (xy 363.792607 -268.06165)
			(xy 363.746333 -268.038072) (xy 363.704317 -268.007546) (xy 363.667594 -267.970823) (xy 363.637068 -267.928807)
			(xy 363.61349 -267.882533) (xy 363.597442 -267.83314) (xy 363.589317 -267.781845) (xy 363.309407 -267.781845)
			(xy 363.301282 -267.83314) (xy 363.285234 -267.882533) (xy 363.261656 -267.928807) (xy 363.23113 -267.970823)
			(xy 363.194407 -268.007546) (xy 363.152391 -268.038072) (xy 363.106117 -268.06165) (xy 363.056724 -268.077698)
			(xy 363.005429 -268.085823) (xy 362.953495 -268.085823) (xy 362.9022 -268.077698) (xy 362.852807 -268.06165)
			(xy 362.806533 -268.038072) (xy 362.764517 -268.007546) (xy 362.727794 -267.970823) (xy 362.697268 -267.928807)
			(xy 362.67369 -267.882533) (xy 362.657642 -267.83314) (xy 362.649517 -267.781845) (xy 362.369607 -267.781845)
			(xy 362.361482 -267.83314) (xy 362.345434 -267.882533) (xy 362.321856 -267.928807) (xy 362.29133 -267.970823)
			(xy 362.254607 -268.007546) (xy 362.212591 -268.038072) (xy 362.166317 -268.06165) (xy 362.116924 -268.077698)
			(xy 362.065629 -268.085823) (xy 362.013695 -268.085823) (xy 361.9624 -268.077698) (xy 361.913007 -268.06165)
			(xy 361.866733 -268.038072) (xy 361.824717 -268.007546) (xy 361.787994 -267.970823) (xy 361.757468 -267.928807)
			(xy 361.73389 -267.882533) (xy 361.717842 -267.83314) (xy 361.709717 -267.781845) (xy 361.590844 -267.781845)
			(xy 361.590844 -268.237208) (xy 361.631992 -268.245082) (xy 361.656833 -268.250313) (xy 361.704644 -268.267376)
			(xy 361.749283 -268.291548) (xy 361.789701 -268.322261) (xy 361.824949 -268.358793) (xy 361.854196 -268.400284)
			(xy 361.876755 -268.44576) (xy 361.892096 -268.49415) (xy 361.899858 -268.544317) (xy 361.899858 -268.595081)
			(xy 361.899768 -268.595661) (xy 362.179871 -268.595661) (xy 362.179871 -268.543727) (xy 362.187996 -268.492432)
			(xy 362.204044 -268.443039) (xy 362.227622 -268.396765) (xy 362.258148 -268.354749) (xy 362.294871 -268.318026)
			(xy 362.336887 -268.2875) (xy 362.383161 -268.263922) (xy 362.432554 -268.247874) (xy 362.483849 -268.239749)
			(xy 362.535783 -268.239749) (xy 362.587078 -268.247874) (xy 362.636471 -268.263922) (xy 362.682745 -268.2875)
			(xy 362.724761 -268.318026) (xy 362.761484 -268.354749) (xy 362.79201 -268.396765) (xy 362.815588 -268.443039)
			(xy 362.831636 -268.492432) (xy 362.839761 -268.543727) (xy 362.84027 -268.569694) (xy 362.839761 -268.595661)
			(xy 363.119671 -268.595661) (xy 363.119671 -268.543727) (xy 363.127796 -268.492432) (xy 363.143844 -268.443039)
			(xy 363.167422 -268.396765) (xy 363.197948 -268.354749) (xy 363.234671 -268.318026) (xy 363.276687 -268.2875)
			(xy 363.322961 -268.263922) (xy 363.372354 -268.247874) (xy 363.423649 -268.239749) (xy 363.475583 -268.239749)
			(xy 363.526878 -268.247874) (xy 363.576271 -268.263922) (xy 363.622545 -268.2875) (xy 363.664561 -268.318026)
			(xy 363.701284 -268.354749) (xy 363.73181 -268.396765) (xy 363.755388 -268.443039) (xy 363.771436 -268.492432)
			(xy 363.779561 -268.543727) (xy 363.78007 -268.569694) (xy 363.779561 -268.595661) (xy 364.059471 -268.595661)
			(xy 364.059471 -268.543727) (xy 364.067596 -268.492432) (xy 364.083644 -268.443039) (xy 364.107222 -268.396765)
			(xy 364.137748 -268.354749) (xy 364.174471 -268.318026) (xy 364.216487 -268.2875) (xy 364.262761 -268.263922)
			(xy 364.312154 -268.247874) (xy 364.363449 -268.239749) (xy 364.415383 -268.239749) (xy 364.466678 -268.247874)
			(xy 364.516071 -268.263922) (xy 364.562345 -268.2875) (xy 364.604361 -268.318026) (xy 364.641084 -268.354749)
			(xy 364.67161 -268.396765) (xy 364.695188 -268.443039) (xy 364.711236 -268.492432) (xy 364.719361 -268.543727)
			(xy 364.71987 -268.569694) (xy 364.719361 -268.595661) (xy 364.999017 -268.595661) (xy 364.999017 -268.543727)
			(xy 365.007142 -268.492432) (xy 365.02319 -268.443039) (xy 365.046768 -268.396765) (xy 365.077294 -268.354749)
			(xy 365.114017 -268.318026) (xy 365.156033 -268.2875) (xy 365.202307 -268.263922) (xy 365.2517 -268.247874)
			(xy 365.302995 -268.239749) (xy 365.354929 -268.239749) (xy 365.406224 -268.247874) (xy 365.455617 -268.263922)
			(xy 365.501891 -268.2875) (xy 365.543907 -268.318026) (xy 365.58063 -268.354749) (xy 365.611156 -268.396765)
			(xy 365.634734 -268.443039) (xy 365.650782 -268.492432) (xy 365.658907 -268.543727) (xy 365.659416 -268.569694)
			(xy 365.658907 -268.595661) (xy 365.650782 -268.646956) (xy 365.634734 -268.696349) (xy 365.611156 -268.742623)
			(xy 365.58063 -268.784639) (xy 365.543907 -268.821362) (xy 365.501891 -268.851888) (xy 365.455617 -268.875466)
			(xy 365.406224 -268.891514) (xy 365.354929 -268.899639) (xy 365.302995 -268.899639) (xy 365.2517 -268.891514)
			(xy 365.202307 -268.875466) (xy 365.156033 -268.851888) (xy 365.114017 -268.821362) (xy 365.077294 -268.784639)
			(xy 365.046768 -268.742623) (xy 365.02319 -268.696349) (xy 365.007142 -268.646956) (xy 364.999017 -268.595661)
			(xy 364.719361 -268.595661) (xy 364.711236 -268.646956) (xy 364.695188 -268.696349) (xy 364.67161 -268.742623)
			(xy 364.641084 -268.784639) (xy 364.604361 -268.821362) (xy 364.562345 -268.851888) (xy 364.516071 -268.875466)
			(xy 364.466678 -268.891514) (xy 364.415383 -268.899639) (xy 364.363449 -268.899639) (xy 364.312154 -268.891514)
			(xy 364.262761 -268.875466) (xy 364.216487 -268.851888) (xy 364.174471 -268.821362) (xy 364.137748 -268.784639)
			(xy 364.107222 -268.742623) (xy 364.083644 -268.696349) (xy 364.067596 -268.646956) (xy 364.059471 -268.595661)
			(xy 363.779561 -268.595661) (xy 363.771436 -268.646956) (xy 363.755388 -268.696349) (xy 363.73181 -268.742623)
			(xy 363.701284 -268.784639) (xy 363.664561 -268.821362) (xy 363.622545 -268.851888) (xy 363.576271 -268.875466)
			(xy 363.526878 -268.891514) (xy 363.475583 -268.899639) (xy 363.423649 -268.899639) (xy 363.372354 -268.891514)
			(xy 363.322961 -268.875466) (xy 363.276687 -268.851888) (xy 363.234671 -268.821362) (xy 363.197948 -268.784639)
			(xy 363.167422 -268.742623) (xy 363.143844 -268.696349) (xy 363.127796 -268.646956) (xy 363.119671 -268.595661)
			(xy 362.839761 -268.595661) (xy 362.831636 -268.646956) (xy 362.815588 -268.696349) (xy 362.79201 -268.742623)
			(xy 362.761484 -268.784639) (xy 362.724761 -268.821362) (xy 362.682745 -268.851888) (xy 362.636471 -268.875466)
			(xy 362.587078 -268.891514) (xy 362.535783 -268.899639) (xy 362.483849 -268.899639) (xy 362.432554 -268.891514)
			(xy 362.383161 -268.875466) (xy 362.336887 -268.851888) (xy 362.294871 -268.821362) (xy 362.258148 -268.784639)
			(xy 362.227622 -268.742623) (xy 362.204044 -268.696349) (xy 362.187996 -268.646956) (xy 362.179871 -268.595661)
			(xy 361.899768 -268.595661) (xy 361.892097 -268.645248) (xy 361.876756 -268.693638) (xy 361.854197 -268.739114)
			(xy 361.82495 -268.780605) (xy 361.789703 -268.817138) (xy 361.749285 -268.847851) (xy 361.704646 -268.872023)
			(xy 361.656835 -268.889086) (xy 361.631992 -268.894306) (xy 361.590844 -268.90218) (xy 361.590844 -269.409477)
			(xy 361.710225 -269.409477) (xy 361.710225 -269.357543) (xy 361.71835 -269.306248) (xy 361.734398 -269.256855)
			(xy 361.757976 -269.210581) (xy 361.788502 -269.168565) (xy 361.825225 -269.131842) (xy 361.867241 -269.101316)
			(xy 361.913515 -269.077738) (xy 361.962908 -269.06169) (xy 362.014203 -269.053565) (xy 362.066137 -269.053565)
			(xy 362.117432 -269.06169) (xy 362.166825 -269.077738) (xy 362.213099 -269.101316) (xy 362.255115 -269.131842)
			(xy 362.291838 -269.168565) (xy 362.322364 -269.210581) (xy 362.345942 -269.256855) (xy 362.36199 -269.306248)
			(xy 362.370115 -269.357543) (xy 362.370624 -269.38351) (xy 362.370115 -269.409477) (xy 362.649517 -269.409477)
			(xy 362.649517 -269.357543) (xy 362.657642 -269.306248) (xy 362.67369 -269.256855) (xy 362.697268 -269.210581)
			(xy 362.727794 -269.168565) (xy 362.764517 -269.131842) (xy 362.806533 -269.101316) (xy 362.852807 -269.077738)
			(xy 362.9022 -269.06169) (xy 362.953495 -269.053565) (xy 363.005429 -269.053565) (xy 363.056724 -269.06169)
			(xy 363.106117 -269.077738) (xy 363.152391 -269.101316) (xy 363.194407 -269.131842) (xy 363.23113 -269.168565)
			(xy 363.261656 -269.210581) (xy 363.285234 -269.256855) (xy 363.301282 -269.306248) (xy 363.309407 -269.357543)
			(xy 363.309916 -269.38351) (xy 363.309407 -269.409477) (xy 363.589317 -269.409477) (xy 363.589317 -269.357543)
			(xy 363.597442 -269.306248) (xy 363.61349 -269.256855) (xy 363.637068 -269.210581) (xy 363.667594 -269.168565)
			(xy 363.704317 -269.131842) (xy 363.746333 -269.101316) (xy 363.792607 -269.077738) (xy 363.842 -269.06169)
			(xy 363.893295 -269.053565) (xy 363.945229 -269.053565) (xy 363.996524 -269.06169) (xy 364.045917 -269.077738)
			(xy 364.092191 -269.101316) (xy 364.134207 -269.131842) (xy 364.17093 -269.168565) (xy 364.201456 -269.210581)
			(xy 364.225034 -269.256855) (xy 364.241082 -269.306248) (xy 364.249207 -269.357543) (xy 364.249716 -269.38351)
			(xy 364.249207 -269.409477) (xy 364.529117 -269.409477) (xy 364.529117 -269.357543) (xy 364.537242 -269.306248)
			(xy 364.55329 -269.256855) (xy 364.576868 -269.210581) (xy 364.607394 -269.168565) (xy 364.644117 -269.131842)
			(xy 364.686133 -269.101316) (xy 364.732407 -269.077738) (xy 364.7818 -269.06169) (xy 364.833095 -269.053565)
			(xy 364.885029 -269.053565) (xy 364.936324 -269.06169) (xy 364.985717 -269.077738) (xy 365.031991 -269.101316)
			(xy 365.074007 -269.131842) (xy 365.11073 -269.168565) (xy 365.141256 -269.210581) (xy 365.164834 -269.256855)
			(xy 365.180882 -269.306248) (xy 365.189007 -269.357543) (xy 365.189516 -269.38351) (xy 365.189007 -269.409477)
			(xy 365.180882 -269.460772) (xy 365.164834 -269.510165) (xy 365.141256 -269.556439) (xy 365.11073 -269.598455)
			(xy 365.074007 -269.635178) (xy 365.031991 -269.665704) (xy 364.985717 -269.689282) (xy 364.936324 -269.70533)
			(xy 364.885029 -269.713455) (xy 364.833095 -269.713455) (xy 364.7818 -269.70533) (xy 364.732407 -269.689282)
			(xy 364.686133 -269.665704) (xy 364.644117 -269.635178) (xy 364.607394 -269.598455) (xy 364.576868 -269.556439)
			(xy 364.55329 -269.510165) (xy 364.537242 -269.460772) (xy 364.529117 -269.409477) (xy 364.249207 -269.409477)
			(xy 364.241082 -269.460772) (xy 364.225034 -269.510165) (xy 364.201456 -269.556439) (xy 364.17093 -269.598455)
			(xy 364.134207 -269.635178) (xy 364.092191 -269.665704) (xy 364.045917 -269.689282) (xy 363.996524 -269.70533)
			(xy 363.945229 -269.713455) (xy 363.893295 -269.713455) (xy 363.842 -269.70533) (xy 363.792607 -269.689282)
			(xy 363.746333 -269.665704) (xy 363.704317 -269.635178) (xy 363.667594 -269.598455) (xy 363.637068 -269.556439)
			(xy 363.61349 -269.510165) (xy 363.597442 -269.460772) (xy 363.589317 -269.409477) (xy 363.309407 -269.409477)
			(xy 363.301282 -269.460772) (xy 363.285234 -269.510165) (xy 363.261656 -269.556439) (xy 363.23113 -269.598455)
			(xy 363.194407 -269.635178) (xy 363.152391 -269.665704) (xy 363.106117 -269.689282) (xy 363.056724 -269.70533)
			(xy 363.005429 -269.713455) (xy 362.953495 -269.713455) (xy 362.9022 -269.70533) (xy 362.852807 -269.689282)
			(xy 362.806533 -269.665704) (xy 362.764517 -269.635178) (xy 362.727794 -269.598455) (xy 362.697268 -269.556439)
			(xy 362.67369 -269.510165) (xy 362.657642 -269.460772) (xy 362.649517 -269.409477) (xy 362.370115 -269.409477)
			(xy 362.36199 -269.460772) (xy 362.345942 -269.510165) (xy 362.322364 -269.556439) (xy 362.291838 -269.598455)
			(xy 362.255115 -269.635178) (xy 362.213099 -269.665704) (xy 362.166825 -269.689282) (xy 362.117432 -269.70533)
			(xy 362.066137 -269.713455) (xy 362.014203 -269.713455) (xy 361.962908 -269.70533) (xy 361.913515 -269.689282)
			(xy 361.867241 -269.665704) (xy 361.825225 -269.635178) (xy 361.788502 -269.598455) (xy 361.757976 -269.556439)
			(xy 361.734398 -269.510165) (xy 361.71835 -269.460772) (xy 361.710225 -269.409477) (xy 361.590844 -269.409477)
			(xy 361.590844 -269.865094) (xy 361.631992 -269.872968) (xy 361.656834 -269.878199) (xy 361.704647 -269.895262)
			(xy 361.749288 -269.919435) (xy 361.789709 -269.950149) (xy 361.824958 -269.986682) (xy 361.854206 -270.028175)
			(xy 361.876767 -270.073652) (xy 361.892109 -270.122044) (xy 361.899872 -270.172213) (xy 361.899872 -270.222979)
			(xy 361.899784 -270.223547) (xy 364.059471 -270.223547) (xy 364.059471 -270.171613) (xy 364.067596 -270.120318)
			(xy 364.083644 -270.070925) (xy 364.107222 -270.024651) (xy 364.137748 -269.982635) (xy 364.174471 -269.945912)
			(xy 364.216487 -269.915386) (xy 364.262761 -269.891808) (xy 364.312154 -269.87576) (xy 364.363449 -269.867635)
			(xy 364.415383 -269.867635) (xy 364.466678 -269.87576) (xy 364.516071 -269.891808) (xy 364.562345 -269.915386)
			(xy 364.604361 -269.945912) (xy 364.641084 -269.982635) (xy 364.67161 -270.024651) (xy 364.695188 -270.070925)
			(xy 364.711236 -270.120318) (xy 364.719361 -270.171613) (xy 364.71987 -270.19758) (xy 364.719361 -270.223547)
			(xy 364.999017 -270.223547) (xy 364.999017 -270.171613) (xy 365.007142 -270.120318) (xy 365.02319 -270.070925)
			(xy 365.046768 -270.024651) (xy 365.077294 -269.982635) (xy 365.114017 -269.945912) (xy 365.156033 -269.915386)
			(xy 365.202307 -269.891808) (xy 365.2517 -269.87576) (xy 365.302995 -269.867635) (xy 365.354929 -269.867635)
			(xy 365.406224 -269.87576) (xy 365.455617 -269.891808) (xy 365.501891 -269.915386) (xy 365.543907 -269.945912)
			(xy 365.58063 -269.982635) (xy 365.611156 -270.024651) (xy 365.634734 -270.070925) (xy 365.650782 -270.120318)
			(xy 365.658907 -270.171613) (xy 365.659416 -270.19758) (xy 365.658907 -270.223547) (xy 365.650782 -270.274842)
			(xy 365.634734 -270.324235) (xy 365.611156 -270.370509) (xy 365.58063 -270.412525) (xy 365.543907 -270.449248)
			(xy 365.501891 -270.479774) (xy 365.455617 -270.503352) (xy 365.406224 -270.5194) (xy 365.354929 -270.527525)
			(xy 365.302995 -270.527525) (xy 365.2517 -270.5194) (xy 365.202307 -270.503352) (xy 365.156033 -270.479774)
			(xy 365.114017 -270.449248) (xy 365.077294 -270.412525) (xy 365.046768 -270.370509) (xy 365.02319 -270.324235)
			(xy 365.007142 -270.274842) (xy 364.999017 -270.223547) (xy 364.719361 -270.223547) (xy 364.711236 -270.274842)
			(xy 364.695188 -270.324235) (xy 364.67161 -270.370509) (xy 364.641084 -270.412525) (xy 364.604361 -270.449248)
			(xy 364.562345 -270.479774) (xy 364.516071 -270.503352) (xy 364.466678 -270.5194) (xy 364.415383 -270.527525)
			(xy 364.363449 -270.527525) (xy 364.312154 -270.5194) (xy 364.262761 -270.503352) (xy 364.216487 -270.479774)
			(xy 364.174471 -270.449248) (xy 364.137748 -270.412525) (xy 364.107222 -270.370509) (xy 364.083644 -270.324235)
			(xy 364.067596 -270.274842) (xy 364.059471 -270.223547) (xy 361.899784 -270.223547) (xy 361.892111 -270.273148)
			(xy 361.87677 -270.321541) (xy 361.85421 -270.367018) (xy 361.824963 -270.408512) (xy 361.789714 -270.445046)
			(xy 361.749294 -270.475761) (xy 361.704654 -270.499935) (xy 361.656842 -270.516999) (xy 361.631992 -270.522192)
			(xy 361.590844 -270.530066) (xy 361.590844 -271.037363) (xy 364.529117 -271.037363) (xy 364.529117 -270.985429)
			(xy 364.537242 -270.934134) (xy 364.55329 -270.884741) (xy 364.576868 -270.838467) (xy 364.607394 -270.796451)
			(xy 364.644117 -270.759728) (xy 364.686133 -270.729202) (xy 364.732407 -270.705624) (xy 364.7818 -270.689576)
			(xy 364.833095 -270.681451) (xy 364.885029 -270.681451) (xy 364.936324 -270.689576) (xy 364.985717 -270.705624)
			(xy 365.031991 -270.729202) (xy 365.074007 -270.759728) (xy 365.11073 -270.796451) (xy 365.141256 -270.838467)
			(xy 365.164834 -270.884741) (xy 365.180882 -270.934134) (xy 365.189007 -270.985429) (xy 365.189516 -271.011396)
			(xy 365.189007 -271.037363) (xy 365.180882 -271.088658) (xy 365.164834 -271.138051) (xy 365.141256 -271.184325)
			(xy 365.11073 -271.226341) (xy 365.074007 -271.263064) (xy 365.031991 -271.29359) (xy 364.985717 -271.317168)
			(xy 364.936324 -271.333216) (xy 364.885029 -271.341341) (xy 364.833095 -271.341341) (xy 364.7818 -271.333216)
			(xy 364.732407 -271.317168) (xy 364.686133 -271.29359) (xy 364.644117 -271.263064) (xy 364.607394 -271.226341)
			(xy 364.576868 -271.184325) (xy 364.55329 -271.138051) (xy 364.537242 -271.088658) (xy 364.529117 -271.037363)
			(xy 361.590844 -271.037363) (xy 361.590844 -271.373346) (xy 361.821984 -271.604486)
		)
		(stroke
			(width 0)
			(type solid)
		)
		(fill yes)
		(layer "In11.Cu")
		(net "PVPP_HBM_CPU0")
	)
	(gr_poly
		(pts
			(xy 114.258852 -271.713452) (xy 114.267874 -271.689788) (xy 114.292078 -271.645304) (xy 114.322787 -271.605035)
			(xy 114.359282 -271.569924) (xy 114.400708 -271.540795) (xy 114.446094 -271.518329) (xy 114.494378 -271.503052)
			(xy 114.544427 -271.495324) (xy 114.595069 -271.495324) (xy 114.645118 -271.503052) (xy 114.693402 -271.518329)
			(xy 114.738788 -271.540795) (xy 114.780214 -271.569924) (xy 114.816709 -271.605035) (xy 114.847418 -271.645304)
			(xy 114.871622 -271.689788) (xy 114.880644 -271.713452) (xy 114.892836 -271.74698) (xy 115.18646 -271.74698)
			(xy 115.198652 -271.713452) (xy 115.207674 -271.689788) (xy 115.231878 -271.645304) (xy 115.262587 -271.605035)
			(xy 115.299082 -271.569924) (xy 115.340508 -271.540795) (xy 115.385894 -271.518329) (xy 115.434178 -271.503052)
			(xy 115.484227 -271.495324) (xy 115.534869 -271.495324) (xy 115.584918 -271.503052) (xy 115.633202 -271.518329)
			(xy 115.678588 -271.540795) (xy 115.720014 -271.569924) (xy 115.756509 -271.605035) (xy 115.787218 -271.645304)
			(xy 115.811422 -271.689788) (xy 115.820444 -271.713452) (xy 115.832636 -271.74698) (xy 116.125752 -271.74698)
			(xy 116.137944 -271.713452) (xy 116.146966 -271.689788) (xy 116.17117 -271.645304) (xy 116.201879 -271.605035)
			(xy 116.238374 -271.569924) (xy 116.2798 -271.540795) (xy 116.325186 -271.518329) (xy 116.37347 -271.503052)
			(xy 116.423519 -271.495324) (xy 116.474161 -271.495324) (xy 116.52421 -271.503052) (xy 116.572494 -271.518329)
			(xy 116.61788 -271.540795) (xy 116.659306 -271.569924) (xy 116.695801 -271.605035) (xy 116.72651 -271.645304)
			(xy 116.750714 -271.689788) (xy 116.759736 -271.713452) (xy 116.771928 -271.74698) (xy 117.06606 -271.74698)
			(xy 117.078252 -271.713452) (xy 117.087281 -271.689792) (xy 117.111496 -271.645317) (xy 117.14221 -271.605056)
			(xy 117.178705 -271.569949) (xy 117.220128 -271.54082) (xy 117.265508 -271.518348) (xy 117.313785 -271.503061)
			(xy 117.363829 -271.495315) (xy 117.389148 -271.494758) (xy 117.420732 -271.495541) (xy 117.48275 -271.507557)
			(xy 117.512338 -271.518634) (xy 117.543326 -271.53108) (xy 117.656864 -271.417542) (xy 117.666552 -271.407208)
			(xy 117.680316 -271.382464) (xy 117.686752 -271.35489) (xy 117.685366 -271.326609) (xy 117.676263 -271.299798)
			(xy 117.660144 -271.276519) (xy 117.649498 -271.267174) (xy 117.630897 -271.251396) (xy 117.598093 -271.215302)
			(xy 117.570954 -271.174775) (xy 117.55007 -271.130698) (xy 117.535895 -271.084029) (xy 117.528738 -271.035783)
			(xy 117.52834 -271.011396) (xy 117.52885 -270.985429) (xy 117.536974 -270.934134) (xy 117.553023 -270.884741)
			(xy 117.576601 -270.838468) (xy 117.607127 -270.796452) (xy 117.64385 -270.759729) (xy 117.685866 -270.729202)
			(xy 117.73214 -270.705624) (xy 117.781532 -270.689575) (xy 117.832827 -270.68145) (xy 117.858794 -270.680942)
			(xy 117.868917 -270.681034) (xy 117.889125 -270.682304) (xy 117.89918 -270.683482) (xy 117.913498 -270.684749)
			(xy 117.941862 -270.680181) (xy 117.967834 -270.667898) (xy 117.989358 -270.648869) (xy 118.004734 -270.624599)
			(xy 118.012745 -270.597009) (xy 118.013226 -270.582644) (xy 118.013226 -270.29537) (xy 118.011194 -270.288512)
			(xy 118.005259 -270.266249) (xy 117.998889 -270.220617) (xy 117.998494 -270.19758) (xy 117.998858 -270.174541)
			(xy 118.005235 -270.128906) (xy 118.011194 -270.106648) (xy 118.013226 -270.09979) (xy 118.013226 -269.812262)
			(xy 118.012728 -269.797899) (xy 118.00472 -269.770312) (xy 117.989347 -269.746045) (xy 117.967826 -269.727018)
			(xy 117.941858 -269.714736) (xy 117.913497 -269.710169) (xy 117.89918 -269.711424) (xy 117.889188 -269.712593)
			(xy 117.869108 -269.713863) (xy 117.859048 -269.713964) (xy 117.833075 -269.713485) (xy 117.781769 -269.705365)
			(xy 117.732365 -269.689319) (xy 117.686079 -269.665742) (xy 117.644052 -269.635213) (xy 117.607319 -269.598485)
			(xy 117.576784 -269.556462) (xy 117.553199 -269.51018) (xy 117.537146 -269.460778) (xy 117.529019 -269.409472)
			(xy 117.529019 -269.357528) (xy 117.537146 -269.306222) (xy 117.553199 -269.25682) (xy 117.576784 -269.210538)
			(xy 117.607319 -269.168515) (xy 117.644052 -269.131787) (xy 117.686079 -269.101258) (xy 117.732365 -269.077681)
			(xy 117.781769 -269.061635) (xy 117.833075 -269.053515) (xy 117.859048 -269.053056) (xy 117.869108 -269.053155)
			(xy 117.889188 -269.054425) (xy 117.89918 -269.055596) (xy 117.913493 -269.056863) (xy 117.94185 -269.052295)
			(xy 117.967811 -269.04001) (xy 117.989323 -269.020978) (xy 118.004681 -268.996707) (xy 118.012671 -268.969119)
			(xy 118.013226 -268.954758) (xy 118.013226 -268.667484) (xy 118.011194 -268.660626) (xy 118.005258 -268.638363)
			(xy 117.998886 -268.592731) (xy 117.998494 -268.569694) (xy 117.998857 -268.546655) (xy 118.005232 -268.50102)
			(xy 118.011194 -268.478762) (xy 118.013226 -268.471904) (xy 118.013226 -268.18463) (xy 118.012737 -268.17026)
			(xy 118.00474 -268.142657) (xy 117.989371 -268.118373) (xy 117.967845 -268.099331) (xy 117.941868 -268.087039)
			(xy 117.913495 -268.082469) (xy 117.89918 -268.083792) (xy 117.889125 -268.084969) (xy 117.868917 -268.086239)
			(xy 117.858794 -268.086332) (xy 117.832829 -268.085822) (xy 117.781538 -268.077698) (xy 117.732149 -268.06165)
			(xy 117.685879 -268.038073) (xy 117.643867 -268.007549) (xy 117.607147 -267.970828) (xy 117.576624 -267.928815)
			(xy 117.553048 -267.882545) (xy 117.537001 -267.833156) (xy 117.528877 -267.781865) (xy 117.528877 -267.729935)
			(xy 117.537001 -267.678644) (xy 117.553048 -267.629255) (xy 117.576624 -267.582985) (xy 117.607147 -267.540972)
			(xy 117.643867 -267.504251) (xy 117.685879 -267.473727) (xy 117.732149 -267.45015) (xy 117.781538 -267.434102)
			(xy 117.832829 -267.425978) (xy 117.858794 -267.425424) (xy 117.868917 -267.425516) (xy 117.889125 -267.426786)
			(xy 117.89918 -267.427964) (xy 117.913497 -267.429231) (xy 117.94186 -267.424663) (xy 117.967829 -267.412379)
			(xy 117.989351 -267.39335) (xy 118.004723 -267.36908) (xy 118.01273 -267.34149) (xy 118.013226 -267.327126)
			(xy 118.013226 -267.041376) (xy 118.011194 -267.034264) (xy 118.005025 -267.011649) (xy 117.998395 -266.965245)
			(xy 117.998394 -266.91837) (xy 118.005022 -266.871966) (xy 118.011194 -266.849352) (xy 118.013226 -266.84224)
			(xy 118.013226 -266.556998) (xy 118.012733 -266.542632) (xy 118.004731 -266.515036) (xy 117.98936 -266.49076)
			(xy 117.967836 -266.471725) (xy 117.941863 -266.459437) (xy 117.913496 -266.454869) (xy 117.89918 -266.45616)
			(xy 117.889125 -266.457337) (xy 117.868917 -266.458607) (xy 117.858794 -266.4587) (xy 117.832823 -266.45819)
			(xy 117.781522 -266.450064) (xy 117.732123 -266.434013) (xy 117.685844 -266.410431) (xy 117.643823 -266.379901)
			(xy 117.607096 -266.343172) (xy 117.576566 -266.301151) (xy 117.552985 -266.254871) (xy 117.536935 -266.205472)
			(xy 117.528809 -266.154171) (xy 117.528809 -266.102229) (xy 117.536935 -266.050928) (xy 117.552985 -266.001529)
			(xy 117.576566 -265.955249) (xy 117.607096 -265.913228) (xy 117.643823 -265.876499) (xy 117.685844 -265.845969)
			(xy 117.732123 -265.822387) (xy 117.781522 -265.806336) (xy 117.832823 -265.79821) (xy 117.858794 -265.797792)
			(xy 117.868917 -265.797884) (xy 117.889125 -265.799154) (xy 117.89918 -265.800332) (xy 117.913495 -265.801599)
			(xy 117.941855 -265.797032) (xy 117.967821 -265.784747) (xy 117.989338 -265.765716) (xy 118.004704 -265.741446)
			(xy 118.012702 -265.713857) (xy 118.013226 -265.699494) (xy 118.013226 -265.412728) (xy 118.011194 -265.40587)
			(xy 118.005124 -265.383435) (xy 117.998621 -265.337415) (xy 117.99824 -265.314176) (xy 117.998639 -265.290939)
			(xy 118.005147 -265.244922) (xy 118.011194 -265.222482) (xy 118.013226 -265.215624) (xy 118.013226 -264.929112)
			(xy 118.012735 -264.914744) (xy 118.004735 -264.887145) (xy 117.989364 -264.862866) (xy 117.96784 -264.843828)
			(xy 117.941865 -264.831538) (xy 117.913496 -264.826969) (xy 117.89918 -264.828274) (xy 117.889125 -264.829451)
			(xy 117.868917 -264.830721) (xy 117.858794 -264.830814) (xy 117.83283 -264.830304) (xy 117.781542 -264.82218)
			(xy 117.732156 -264.806133) (xy 117.685889 -264.782558) (xy 117.643879 -264.752035) (xy 117.607161 -264.715317)
			(xy 117.576639 -264.673306) (xy 117.553065 -264.627038) (xy 117.537018 -264.577652) (xy 117.528895 -264.526364)
			(xy 117.528895 -264.474436) (xy 117.537018 -264.423148) (xy 117.553065 -264.373762) (xy 117.576639 -264.327494)
			(xy 117.607161 -264.285483) (xy 117.643879 -264.248765) (xy 117.685889 -264.218242) (xy 117.732156 -264.194667)
			(xy 117.781542 -264.17862) (xy 117.83283 -264.170496) (xy 117.858794 -264.169906) (xy 117.868917 -264.169998)
			(xy 117.889125 -264.171268) (xy 117.89918 -264.172446) (xy 117.913496 -264.173713) (xy 117.941857 -264.169146)
			(xy 117.967825 -264.156861) (xy 117.989344 -264.137831) (xy 118.004712 -264.113561) (xy 118.012714 -264.085971)
			(xy 118.013226 -264.071608) (xy 118.013226 -261.94258) (xy 117.72265 -261.652004) (xy 117.69725 -261.655814)
			(xy 117.684944 -261.657583) (xy 117.660152 -261.659491) (xy 117.64772 -261.659624) (xy 117.620007 -261.659062)
			(xy 117.565356 -261.649823) (xy 117.513011 -261.6316) (xy 117.488462 -261.61873) (xy 117.477032 -261.61238)
			(xy 117.183408 -261.61238) (xy 117.171978 -261.61873) (xy 117.147423 -261.631591) (xy 117.095082 -261.649825)
			(xy 117.040433 -261.659072) (xy 116.985007 -261.659072) (xy 116.930358 -261.649825) (xy 116.878017 -261.631591)
			(xy 116.853462 -261.61873) (xy 116.842032 -261.61238) (xy 116.548408 -261.61238) (xy 116.536978 -261.61873)
			(xy 116.512423 -261.631591) (xy 116.460082 -261.649825) (xy 116.405433 -261.659072) (xy 116.350007 -261.659072)
			(xy 116.295358 -261.649825) (xy 116.243017 -261.631591) (xy 116.218462 -261.61873) (xy 116.207032 -261.61238)
			(xy 116.133626 -261.61238) (xy 114.558826 -263.18718) (xy 114.549177 -263.197464) (xy 114.53544 -263.222079)
			(xy 114.52895 -263.24951) (xy 114.530201 -263.277671) (xy 114.539097 -263.304419) (xy 114.554961 -263.327719)
			(xy 114.576587 -263.3458) (xy 114.60233 -263.357284) (xy 114.61623 -263.359646) (xy 114.642155 -263.363844)
			(xy 114.692324 -263.379369) (xy 114.739406 -263.402635) (xy 114.782216 -263.433054) (xy 114.819675 -263.469861)
			(xy 114.850841 -263.51213) (xy 114.87493 -263.558796) (xy 114.891334 -263.608684) (xy 114.89964 -263.66054)
			(xy 114.900202 -263.686798) (xy 114.899698 -263.712511) (xy 115.179603 -263.712511) (xy 115.179603 -263.660577)
			(xy 115.187728 -263.609282) (xy 115.203776 -263.559889) (xy 115.227354 -263.513615) (xy 115.25788 -263.471599)
			(xy 115.294603 -263.434876) (xy 115.336619 -263.40435) (xy 115.382893 -263.380772) (xy 115.432286 -263.364724)
			(xy 115.483581 -263.356599) (xy 115.535515 -263.356599) (xy 115.58681 -263.364724) (xy 115.636203 -263.380772)
			(xy 115.682477 -263.40435) (xy 115.724493 -263.434876) (xy 115.761216 -263.471599) (xy 115.791742 -263.513615)
			(xy 115.81532 -263.559889) (xy 115.831368 -263.609282) (xy 115.839493 -263.660577) (xy 115.840002 -263.686544)
			(xy 115.839493 -263.712511) (xy 115.831368 -263.763806) (xy 115.81532 -263.813199) (xy 115.791742 -263.859473)
			(xy 115.761216 -263.901489) (xy 115.724493 -263.938212) (xy 115.682477 -263.968738) (xy 115.636203 -263.992316)
			(xy 115.58681 -264.008364) (xy 115.535515 -264.016489) (xy 115.483581 -264.016489) (xy 115.432286 -264.008364)
			(xy 115.382893 -263.992316) (xy 115.336619 -263.968738) (xy 115.294603 -263.938212) (xy 115.25788 -263.901489)
			(xy 115.227354 -263.859473) (xy 115.203776 -263.813199) (xy 115.187728 -263.763806) (xy 115.179603 -263.712511)
			(xy 114.899698 -263.712511) (xy 114.899693 -263.712767) (xy 114.891569 -263.764065) (xy 114.875521 -263.813461)
			(xy 114.851944 -263.859738) (xy 114.821419 -263.901758) (xy 114.784697 -263.938486) (xy 114.742681 -263.969018)
			(xy 114.696407 -263.992602) (xy 114.647013 -264.008657) (xy 114.595717 -264.016789) (xy 114.569748 -264.017252)
			(xy 114.543484 -264.01675) (xy 114.491617 -264.008447) (xy 114.441716 -263.992044) (xy 114.395039 -263.967954)
			(xy 114.35276 -263.936782) (xy 114.315945 -263.899315) (xy 114.285521 -263.856495) (xy 114.262254 -263.809401)
			(xy 114.24673 -263.75922) (xy 114.242596 -263.73328) (xy 114.240136 -263.719407) (xy 114.228655 -263.69369)
			(xy 114.210587 -263.672086) (xy 114.187308 -263.656235) (xy 114.160585 -263.647344) (xy 114.132449 -263.646086)
			(xy 114.105039 -263.652559) (xy 114.080439 -263.66627) (xy 114.07013 -263.675876) (xy 113.936272 -263.809734)
			(xy 113.932462 -263.818624) (xy 113.922639 -263.840138) (xy 113.897753 -263.880353) (xy 113.867396 -263.916618)
			(xy 113.832186 -263.948192) (xy 113.792841 -263.974432) (xy 113.77168 -263.984994) (xy 113.77168 -264.132314)
			(xy 113.7721 -264.145804) (xy 113.77917 -264.171841) (xy 113.792815 -264.195117) (xy 113.812079 -264.214006)
			(xy 113.835619 -264.22719) (xy 113.86179 -264.233747) (xy 113.888765 -264.233219) (xy 113.91466 -264.225645)
			(xy 113.926366 -264.218928) (xy 113.945984 -264.207299) (xy 113.987738 -264.188959) (xy 114.031619 -264.176539)
			(xy 114.076792 -264.170276) (xy 114.099594 -264.169906) (xy 114.125567 -264.170389) (xy 114.176873 -264.178514)
			(xy 114.226276 -264.194565) (xy 114.27256 -264.218147) (xy 114.314585 -264.24868) (xy 114.351317 -264.28541)
			(xy 114.38185 -264.327435) (xy 114.405433 -264.373718) (xy 114.421485 -264.423121) (xy 114.429611 -264.474427)
			(xy 114.429611 -264.526327) (xy 114.709449 -264.526327) (xy 114.709449 -264.474393) (xy 114.717574 -264.423098)
			(xy 114.733622 -264.373705) (xy 114.7572 -264.327431) (xy 114.787726 -264.285415) (xy 114.824449 -264.248692)
			(xy 114.866465 -264.218166) (xy 114.912739 -264.194588) (xy 114.962132 -264.17854) (xy 115.013427 -264.170415)
			(xy 115.065361 -264.170415) (xy 115.116656 -264.17854) (xy 115.166049 -264.194588) (xy 115.212323 -264.218166)
			(xy 115.254339 -264.248692) (xy 115.291062 -264.285415) (xy 115.321588 -264.327431) (xy 115.345166 -264.373705)
			(xy 115.361214 -264.423098) (xy 115.369339 -264.474393) (xy 115.369848 -264.50036) (xy 115.369339 -264.526327)
			(xy 115.649249 -264.526327) (xy 115.649249 -264.474393) (xy 115.657374 -264.423098) (xy 115.673422 -264.373705)
			(xy 115.697 -264.327431) (xy 115.727526 -264.285415) (xy 115.764249 -264.248692) (xy 115.806265 -264.218166)
			(xy 115.852539 -264.194588) (xy 115.901932 -264.17854) (xy 115.953227 -264.170415) (xy 116.005161 -264.170415)
			(xy 116.056456 -264.17854) (xy 116.105849 -264.194588) (xy 116.152123 -264.218166) (xy 116.194139 -264.248692)
			(xy 116.230862 -264.285415) (xy 116.261388 -264.327431) (xy 116.284966 -264.373705) (xy 116.301014 -264.423098)
			(xy 116.309139 -264.474393) (xy 116.309648 -264.50036) (xy 116.309139 -264.526327) (xy 116.589049 -264.526327)
			(xy 116.589049 -264.474393) (xy 116.597174 -264.423098) (xy 116.613222 -264.373705) (xy 116.6368 -264.327431)
			(xy 116.667326 -264.285415) (xy 116.704049 -264.248692) (xy 116.746065 -264.218166) (xy 116.792339 -264.194588)
			(xy 116.841732 -264.17854) (xy 116.893027 -264.170415) (xy 116.944961 -264.170415) (xy 116.996256 -264.17854)
			(xy 117.045649 -264.194588) (xy 117.091923 -264.218166) (xy 117.133939 -264.248692) (xy 117.170662 -264.285415)
			(xy 117.201188 -264.327431) (xy 117.224766 -264.373705) (xy 117.240814 -264.423098) (xy 117.248939 -264.474393)
			(xy 117.249448 -264.50036) (xy 117.248939 -264.526327) (xy 117.240814 -264.577622) (xy 117.224766 -264.627015)
			(xy 117.201188 -264.673289) (xy 117.170662 -264.715305) (xy 117.133939 -264.752028) (xy 117.091923 -264.782554)
			(xy 117.045649 -264.806132) (xy 116.996256 -264.82218) (xy 116.944961 -264.830305) (xy 116.893027 -264.830305)
			(xy 116.841732 -264.82218) (xy 116.792339 -264.806132) (xy 116.746065 -264.782554) (xy 116.704049 -264.752028)
			(xy 116.667326 -264.715305) (xy 116.6368 -264.673289) (xy 116.613222 -264.627015) (xy 116.597174 -264.577622)
			(xy 116.589049 -264.526327) (xy 116.309139 -264.526327) (xy 116.301014 -264.577622) (xy 116.284966 -264.627015)
			(xy 116.261388 -264.673289) (xy 116.230862 -264.715305) (xy 116.194139 -264.752028) (xy 116.152123 -264.782554)
			(xy 116.105849 -264.806132) (xy 116.056456 -264.82218) (xy 116.005161 -264.830305) (xy 115.953227 -264.830305)
			(xy 115.901932 -264.82218) (xy 115.852539 -264.806132) (xy 115.806265 -264.782554) (xy 115.764249 -264.752028)
			(xy 115.727526 -264.715305) (xy 115.697 -264.673289) (xy 115.673422 -264.627015) (xy 115.657374 -264.577622)
			(xy 115.649249 -264.526327) (xy 115.369339 -264.526327) (xy 115.361214 -264.577622) (xy 115.345166 -264.627015)
			(xy 115.321588 -264.673289) (xy 115.291062 -264.715305) (xy 115.254339 -264.752028) (xy 115.212323 -264.782554)
			(xy 115.166049 -264.806132) (xy 115.116656 -264.82218) (xy 115.065361 -264.830305) (xy 115.013427 -264.830305)
			(xy 114.962132 -264.82218) (xy 114.912739 -264.806132) (xy 114.866465 -264.782554) (xy 114.824449 -264.752028)
			(xy 114.787726 -264.715305) (xy 114.7572 -264.673289) (xy 114.733622 -264.627015) (xy 114.717574 -264.577622)
			(xy 114.709449 -264.526327) (xy 114.429611 -264.526327) (xy 114.429611 -264.526373) (xy 114.421485 -264.577679)
			(xy 114.405433 -264.627082) (xy 114.38185 -264.673365) (xy 114.351317 -264.71539) (xy 114.314585 -264.75212)
			(xy 114.27256 -264.782653) (xy 114.226276 -264.806235) (xy 114.176873 -264.822286) (xy 114.125567 -264.830411)
			(xy 114.099594 -264.830814) (xy 114.076792 -264.830432) (xy 114.031621 -264.824165) (xy 113.98774 -264.811751)
			(xy 113.94598 -264.793426) (xy 113.926366 -264.781792) (xy 113.914649 -264.775102) (xy 113.888763 -264.767528)
			(xy 113.861797 -264.767001) (xy 113.835634 -264.773556) (xy 113.812102 -264.786736) (xy 113.792846 -264.805621)
			(xy 113.779209 -264.82889) (xy 113.772144 -264.85492) (xy 113.77168 -264.868406) (xy 113.77168 -265.015726)
			(xy 113.795486 -265.027641) (xy 113.83927 -265.057916) (xy 113.877635 -265.094817) (xy 113.909591 -265.13739)
			(xy 113.93431 -265.184534) (xy 113.951154 -265.235031) (xy 113.959687 -265.287574) (xy 113.959689 -265.340143)
			(xy 114.239549 -265.340143) (xy 114.239549 -265.288209) (xy 114.247674 -265.236914) (xy 114.263722 -265.187521)
			(xy 114.2873 -265.141247) (xy 114.317826 -265.099231) (xy 114.354549 -265.062508) (xy 114.396565 -265.031982)
			(xy 114.442839 -265.008404) (xy 114.492232 -264.992356) (xy 114.543527 -264.984231) (xy 114.595461 -264.984231)
			(xy 114.646756 -264.992356) (xy 114.696149 -265.008404) (xy 114.742423 -265.031982) (xy 114.784439 -265.062508)
			(xy 114.821162 -265.099231) (xy 114.851688 -265.141247) (xy 114.875266 -265.187521) (xy 114.891314 -265.236914)
			(xy 114.899439 -265.288209) (xy 114.899948 -265.314176) (xy 114.899439 -265.340143) (xy 115.179603 -265.340143)
			(xy 115.179603 -265.288209) (xy 115.187728 -265.236914) (xy 115.203776 -265.187521) (xy 115.227354 -265.141247)
			(xy 115.25788 -265.099231) (xy 115.294603 -265.062508) (xy 115.336619 -265.031982) (xy 115.382893 -265.008404)
			(xy 115.432286 -264.992356) (xy 115.483581 -264.984231) (xy 115.535515 -264.984231) (xy 115.58681 -264.992356)
			(xy 115.636203 -265.008404) (xy 115.682477 -265.031982) (xy 115.724493 -265.062508) (xy 115.761216 -265.099231)
			(xy 115.791742 -265.141247) (xy 115.81532 -265.187521) (xy 115.831368 -265.236914) (xy 115.839493 -265.288209)
			(xy 115.840002 -265.314176) (xy 115.839493 -265.340143) (xy 116.119403 -265.340143) (xy 116.119403 -265.288209)
			(xy 116.127528 -265.236914) (xy 116.143576 -265.187521) (xy 116.167154 -265.141247) (xy 116.19768 -265.099231)
			(xy 116.234403 -265.062508) (xy 116.276419 -265.031982) (xy 116.322693 -265.008404) (xy 116.372086 -264.992356)
			(xy 116.423381 -264.984231) (xy 116.475315 -264.984231) (xy 116.52661 -264.992356) (xy 116.576003 -265.008404)
			(xy 116.622277 -265.031982) (xy 116.664293 -265.062508) (xy 116.701016 -265.099231) (xy 116.731542 -265.141247)
			(xy 116.75512 -265.187521) (xy 116.771168 -265.236914) (xy 116.779293 -265.288209) (xy 116.779802 -265.314176)
			(xy 116.779293 -265.340143) (xy 117.059203 -265.340143) (xy 117.059203 -265.288209) (xy 117.067328 -265.236914)
			(xy 117.083376 -265.187521) (xy 117.106954 -265.141247) (xy 117.13748 -265.099231) (xy 117.174203 -265.062508)
			(xy 117.216219 -265.031982) (xy 117.262493 -265.008404) (xy 117.311886 -264.992356) (xy 117.363181 -264.984231)
			(xy 117.415115 -264.984231) (xy 117.46641 -264.992356) (xy 117.515803 -265.008404) (xy 117.562077 -265.031982)
			(xy 117.604093 -265.062508) (xy 117.640816 -265.099231) (xy 117.671342 -265.141247) (xy 117.69492 -265.187521)
			(xy 117.710968 -265.236914) (xy 117.719093 -265.288209) (xy 117.719602 -265.314176) (xy 117.719093 -265.340143)
			(xy 117.710968 -265.391438) (xy 117.69492 -265.440831) (xy 117.671342 -265.487105) (xy 117.640816 -265.529121)
			(xy 117.604093 -265.565844) (xy 117.562077 -265.59637) (xy 117.515803 -265.619948) (xy 117.46641 -265.635996)
			(xy 117.415115 -265.644121) (xy 117.363181 -265.644121) (xy 117.311886 -265.635996) (xy 117.262493 -265.619948)
			(xy 117.216219 -265.59637) (xy 117.174203 -265.565844) (xy 117.13748 -265.529121) (xy 117.106954 -265.487105)
			(xy 117.083376 -265.440831) (xy 117.067328 -265.391438) (xy 117.059203 -265.340143) (xy 116.779293 -265.340143)
			(xy 116.771168 -265.391438) (xy 116.75512 -265.440831) (xy 116.731542 -265.487105) (xy 116.701016 -265.529121)
			(xy 116.664293 -265.565844) (xy 116.622277 -265.59637) (xy 116.576003 -265.619948) (xy 116.52661 -265.635996)
			(xy 116.475315 -265.644121) (xy 116.423381 -265.644121) (xy 116.372086 -265.635996) (xy 116.322693 -265.619948)
			(xy 116.276419 -265.59637) (xy 116.234403 -265.565844) (xy 116.19768 -265.529121) (xy 116.167154 -265.487105)
			(xy 116.143576 -265.440831) (xy 116.127528 -265.391438) (xy 116.119403 -265.340143) (xy 115.839493 -265.340143)
			(xy 115.831368 -265.391438) (xy 115.81532 -265.440831) (xy 115.791742 -265.487105) (xy 115.761216 -265.529121)
			(xy 115.724493 -265.565844) (xy 115.682477 -265.59637) (xy 115.636203 -265.619948) (xy 115.58681 -265.635996)
			(xy 115.535515 -265.644121) (xy 115.483581 -265.644121) (xy 115.432286 -265.635996) (xy 115.382893 -265.619948)
			(xy 115.336619 -265.59637) (xy 115.294603 -265.565844) (xy 115.25788 -265.529121) (xy 115.227354 -265.487105)
			(xy 115.203776 -265.440831) (xy 115.187728 -265.391438) (xy 115.179603 -265.340143) (xy 114.899439 -265.340143)
			(xy 114.891314 -265.391438) (xy 114.875266 -265.440831) (xy 114.851688 -265.487105) (xy 114.821162 -265.529121)
			(xy 114.784439 -265.565844) (xy 114.742423 -265.59637) (xy 114.696149 -265.619948) (xy 114.646756 -265.635996)
			(xy 114.595461 -265.644121) (xy 114.543527 -265.644121) (xy 114.492232 -265.635996) (xy 114.442839 -265.619948)
			(xy 114.396565 -265.59637) (xy 114.354549 -265.565844) (xy 114.317826 -265.529121) (xy 114.2873 -265.487105)
			(xy 114.263722 -265.440831) (xy 114.247674 -265.391438) (xy 114.239549 -265.340143) (xy 113.959689 -265.340143)
			(xy 113.959689 -265.340806) (xy 113.951159 -265.393349) (xy 113.934318 -265.443847) (xy 113.909602 -265.490992)
			(xy 113.877649 -265.533567) (xy 113.839286 -265.57047) (xy 113.795504 -265.600748) (xy 113.77168 -265.612626)
			(xy 113.77168 -265.7602) (xy 113.772098 -265.773691) (xy 113.779166 -265.799732) (xy 113.79281 -265.823011)
			(xy 113.812075 -265.841903) (xy 113.835617 -265.855089) (xy 113.861791 -265.861647) (xy 113.888769 -265.861119)
			(xy 113.914666 -265.853542) (xy 113.926366 -265.846814) (xy 113.945984 -265.835186) (xy 113.987739 -265.816846)
			(xy 114.031619 -265.804427) (xy 114.076792 -265.798164) (xy 114.099594 -265.797792) (xy 114.12556 -265.798274)
			(xy 114.176853 -265.806397) (xy 114.226243 -265.822445) (xy 114.272515 -265.846021) (xy 114.314529 -265.876545)
			(xy 114.351251 -265.913266) (xy 114.381776 -265.95528) (xy 114.405353 -266.001551) (xy 114.421401 -266.050941)
			(xy 114.429525 -266.102234) (xy 114.429525 -266.154166) (xy 114.429518 -266.154213) (xy 114.709449 -266.154213)
			(xy 114.709449 -266.102279) (xy 114.717574 -266.050984) (xy 114.733622 -266.001591) (xy 114.7572 -265.955317)
			(xy 114.787726 -265.913301) (xy 114.824449 -265.876578) (xy 114.866465 -265.846052) (xy 114.912739 -265.822474)
			(xy 114.962132 -265.806426) (xy 115.013427 -265.798301) (xy 115.065361 -265.798301) (xy 115.116656 -265.806426)
			(xy 115.166049 -265.822474) (xy 115.212323 -265.846052) (xy 115.254339 -265.876578) (xy 115.291062 -265.913301)
			(xy 115.321588 -265.955317) (xy 115.345166 -266.001591) (xy 115.361214 -266.050984) (xy 115.369339 -266.102279)
			(xy 115.369848 -266.128246) (xy 115.369339 -266.154213) (xy 115.649249 -266.154213) (xy 115.649249 -266.102279)
			(xy 115.657374 -266.050984) (xy 115.673422 -266.001591) (xy 115.697 -265.955317) (xy 115.727526 -265.913301)
			(xy 115.764249 -265.876578) (xy 115.806265 -265.846052) (xy 115.852539 -265.822474) (xy 115.901932 -265.806426)
			(xy 115.953227 -265.798301) (xy 116.005161 -265.798301) (xy 116.056456 -265.806426) (xy 116.105849 -265.822474)
			(xy 116.152123 -265.846052) (xy 116.194139 -265.876578) (xy 116.230862 -265.913301) (xy 116.261388 -265.955317)
			(xy 116.284966 -266.001591) (xy 116.301014 -266.050984) (xy 116.309139 -266.102279) (xy 116.309648 -266.128246)
			(xy 116.309139 -266.154213) (xy 116.309099 -266.154467) (xy 116.589049 -266.154467) (xy 116.589049 -266.102533)
			(xy 116.597174 -266.051238) (xy 116.613222 -266.001845) (xy 116.6368 -265.955571) (xy 116.667326 -265.913555)
			(xy 116.704049 -265.876832) (xy 116.746065 -265.846306) (xy 116.792339 -265.822728) (xy 116.841732 -265.80668)
			(xy 116.893027 -265.798555) (xy 116.944961 -265.798555) (xy 116.996256 -265.80668) (xy 117.045649 -265.822728)
			(xy 117.091923 -265.846306) (xy 117.133939 -265.876832) (xy 117.170662 -265.913555) (xy 117.201188 -265.955571)
			(xy 117.224766 -266.001845) (xy 117.240814 -266.051238) (xy 117.248939 -266.102533) (xy 117.249448 -266.1285)
			(xy 117.248939 -266.154467) (xy 117.240814 -266.205762) (xy 117.224766 -266.255155) (xy 117.201188 -266.301429)
			(xy 117.170662 -266.343445) (xy 117.133939 -266.380168) (xy 117.091923 -266.410694) (xy 117.045649 -266.434272)
			(xy 116.996256 -266.45032) (xy 116.944961 -266.458445) (xy 116.893027 -266.458445) (xy 116.841732 -266.45032)
			(xy 116.792339 -266.434272) (xy 116.746065 -266.410694) (xy 116.704049 -266.380168) (xy 116.667326 -266.343445)
			(xy 116.6368 -266.301429) (xy 116.613222 -266.255155) (xy 116.597174 -266.205762) (xy 116.589049 -266.154467)
			(xy 116.309099 -266.154467) (xy 116.301014 -266.205508) (xy 116.284966 -266.254901) (xy 116.261388 -266.301175)
			(xy 116.230862 -266.343191) (xy 116.194139 -266.379914) (xy 116.152123 -266.41044) (xy 116.105849 -266.434018)
			(xy 116.056456 -266.450066) (xy 116.005161 -266.458191) (xy 115.953227 -266.458191) (xy 115.901932 -266.450066)
			(xy 115.852539 -266.434018) (xy 115.806265 -266.41044) (xy 115.764249 -266.379914) (xy 115.727526 -266.343191)
			(xy 115.697 -266.301175) (xy 115.673422 -266.254901) (xy 115.657374 -266.205508) (xy 115.649249 -266.154213)
			(xy 115.369339 -266.154213) (xy 115.361214 -266.205508) (xy 115.345166 -266.254901) (xy 115.321588 -266.301175)
			(xy 115.291062 -266.343191) (xy 115.254339 -266.379914) (xy 115.212323 -266.41044) (xy 115.166049 -266.434018)
			(xy 115.116656 -266.450066) (xy 115.065361 -266.458191) (xy 115.013427 -266.458191) (xy 114.962132 -266.450066)
			(xy 114.912739 -266.434018) (xy 114.866465 -266.41044) (xy 114.824449 -266.379914) (xy 114.787726 -266.343191)
			(xy 114.7572 -266.301175) (xy 114.733622 -266.254901) (xy 114.717574 -266.205508) (xy 114.709449 -266.154213)
			(xy 114.429518 -266.154213) (xy 114.421401 -266.205459) (xy 114.405353 -266.254849) (xy 114.381776 -266.30112)
			(xy 114.351251 -266.343134) (xy 114.314529 -266.379855) (xy 114.272515 -266.410379) (xy 114.226243 -266.433955)
			(xy 114.176853 -266.450003) (xy 114.12556 -266.458126) (xy 114.099594 -266.4587) (xy 114.076792 -266.458318)
			(xy 114.031621 -266.452051) (xy 113.98774 -266.439636) (xy 113.945981 -266.42131) (xy 113.926366 -266.409678)
			(xy 113.914648 -266.402989) (xy 113.888761 -266.395416) (xy 113.861795 -266.394889) (xy 113.835631 -266.401444)
			(xy 113.812099 -266.414624) (xy 113.792841 -266.433507) (xy 113.779202 -266.456777) (xy 113.772134 -266.482806)
			(xy 113.77168 -266.496292) (xy 113.77168 -266.643358) (xy 113.795483 -266.655273) (xy 113.839262 -266.685548)
			(xy 113.877623 -266.722447) (xy 113.909574 -266.765017) (xy 113.934289 -266.812158) (xy 113.95113 -266.862651)
			(xy 113.95966 -266.91519) (xy 113.959659 -266.967775) (xy 114.239803 -266.967775) (xy 114.239803 -266.915841)
			(xy 114.247928 -266.864546) (xy 114.263976 -266.815153) (xy 114.287554 -266.768879) (xy 114.31808 -266.726863)
			(xy 114.354803 -266.69014) (xy 114.396819 -266.659614) (xy 114.443093 -266.636036) (xy 114.492486 -266.619988)
			(xy 114.543781 -266.611863) (xy 114.595715 -266.611863) (xy 114.64701 -266.619988) (xy 114.696403 -266.636036)
			(xy 114.742677 -266.659614) (xy 114.784693 -266.69014) (xy 114.821416 -266.726863) (xy 114.851942 -266.768879)
			(xy 114.87552 -266.815153) (xy 114.891568 -266.864546) (xy 114.899693 -266.915841) (xy 114.900202 -266.941808)
			(xy 114.899693 -266.967775) (xy 115.179603 -266.967775) (xy 115.179603 -266.915841) (xy 115.187728 -266.864546)
			(xy 115.203776 -266.815153) (xy 115.227354 -266.768879) (xy 115.25788 -266.726863) (xy 115.294603 -266.69014)
			(xy 115.336619 -266.659614) (xy 115.382893 -266.636036) (xy 115.432286 -266.619988) (xy 115.483581 -266.611863)
			(xy 115.535515 -266.611863) (xy 115.58681 -266.619988) (xy 115.636203 -266.636036) (xy 115.682477 -266.659614)
			(xy 115.724493 -266.69014) (xy 115.761216 -266.726863) (xy 115.791742 -266.768879) (xy 115.81532 -266.815153)
			(xy 115.831368 -266.864546) (xy 115.839493 -266.915841) (xy 115.840002 -266.941808) (xy 115.839493 -266.967775)
			(xy 116.118895 -266.967775) (xy 116.118895 -266.915841) (xy 116.12702 -266.864546) (xy 116.143068 -266.815153)
			(xy 116.166646 -266.768879) (xy 116.197172 -266.726863) (xy 116.233895 -266.69014) (xy 116.275911 -266.659614)
			(xy 116.322185 -266.636036) (xy 116.371578 -266.619988) (xy 116.422873 -266.611863) (xy 116.474807 -266.611863)
			(xy 116.526102 -266.619988) (xy 116.575495 -266.636036) (xy 116.621769 -266.659614) (xy 116.663785 -266.69014)
			(xy 116.700508 -266.726863) (xy 116.731034 -266.768879) (xy 116.754612 -266.815153) (xy 116.77066 -266.864546)
			(xy 116.778785 -266.915841) (xy 116.779294 -266.941808) (xy 116.778785 -266.967775) (xy 117.059203 -266.967775)
			(xy 117.059203 -266.915841) (xy 117.067328 -266.864546) (xy 117.083376 -266.815153) (xy 117.106954 -266.768879)
			(xy 117.13748 -266.726863) (xy 117.174203 -266.69014) (xy 117.216219 -266.659614) (xy 117.262493 -266.636036)
			(xy 117.311886 -266.619988) (xy 117.363181 -266.611863) (xy 117.415115 -266.611863) (xy 117.46641 -266.619988)
			(xy 117.515803 -266.636036) (xy 117.562077 -266.659614) (xy 117.604093 -266.69014) (xy 117.640816 -266.726863)
			(xy 117.671342 -266.768879) (xy 117.69492 -266.815153) (xy 117.710968 -266.864546) (xy 117.719093 -266.915841)
			(xy 117.719602 -266.941808) (xy 117.719093 -266.967775) (xy 117.710968 -267.01907) (xy 117.69492 -267.068463)
			(xy 117.671342 -267.114737) (xy 117.640816 -267.156753) (xy 117.604093 -267.193476) (xy 117.562077 -267.224002)
			(xy 117.515803 -267.24758) (xy 117.46641 -267.263628) (xy 117.415115 -267.271753) (xy 117.363181 -267.271753)
			(xy 117.311886 -267.263628) (xy 117.262493 -267.24758) (xy 117.216219 -267.224002) (xy 117.174203 -267.193476)
			(xy 117.13748 -267.156753) (xy 117.106954 -267.114737) (xy 117.083376 -267.068463) (xy 117.067328 -267.01907)
			(xy 117.059203 -266.967775) (xy 116.778785 -266.967775) (xy 116.77066 -267.01907) (xy 116.754612 -267.068463)
			(xy 116.731034 -267.114737) (xy 116.700508 -267.156753) (xy 116.663785 -267.193476) (xy 116.621769 -267.224002)
			(xy 116.575495 -267.24758) (xy 116.526102 -267.263628) (xy 116.474807 -267.271753) (xy 116.422873 -267.271753)
			(xy 116.371578 -267.263628) (xy 116.322185 -267.24758) (xy 116.275911 -267.224002) (xy 116.233895 -267.193476)
			(xy 116.197172 -267.156753) (xy 116.166646 -267.114737) (xy 116.143068 -267.068463) (xy 116.12702 -267.01907)
			(xy 116.118895 -266.967775) (xy 115.839493 -266.967775) (xy 115.831368 -267.01907) (xy 115.81532 -267.068463)
			(xy 115.791742 -267.114737) (xy 115.761216 -267.156753) (xy 115.724493 -267.193476) (xy 115.682477 -267.224002)
			(xy 115.636203 -267.24758) (xy 115.58681 -267.263628) (xy 115.535515 -267.271753) (xy 115.483581 -267.271753)
			(xy 115.432286 -267.263628) (xy 115.382893 -267.24758) (xy 115.336619 -267.224002) (xy 115.294603 -267.193476)
			(xy 115.25788 -267.156753) (xy 115.227354 -267.114737) (xy 115.203776 -267.068463) (xy 115.187728 -267.01907)
			(xy 115.179603 -266.967775) (xy 114.899693 -266.967775) (xy 114.891568 -267.01907) (xy 114.87552 -267.068463)
			(xy 114.851942 -267.114737) (xy 114.821416 -267.156753) (xy 114.784693 -267.193476) (xy 114.742677 -267.224002)
			(xy 114.696403 -267.24758) (xy 114.64701 -267.263628) (xy 114.595715 -267.271753) (xy 114.543781 -267.271753)
			(xy 114.492486 -267.263628) (xy 114.443093 -267.24758) (xy 114.396819 -267.224002) (xy 114.354803 -267.193476)
			(xy 114.31808 -267.156753) (xy 114.287554 -267.114737) (xy 114.263976 -267.068463) (xy 114.247928 -267.01907)
			(xy 114.239803 -266.967775) (xy 113.959659 -266.967775) (xy 113.959659 -266.968417) (xy 113.951128 -267.020956)
			(xy 113.934286 -267.071448) (xy 113.90957 -267.118589) (xy 113.877618 -267.161158) (xy 113.839257 -267.198057)
			(xy 113.795477 -267.22833) (xy 113.77168 -267.240258) (xy 113.77168 -267.387832) (xy 113.772102 -267.40132)
			(xy 113.779175 -267.427353) (xy 113.79282 -267.450625) (xy 113.812084 -267.46951) (xy 113.835622 -267.482691)
			(xy 113.86179 -267.489247) (xy 113.888761 -267.48872) (xy 113.914653 -267.481148) (xy 113.926366 -267.474446)
			(xy 113.945985 -267.46282) (xy 113.98774 -267.444484) (xy 114.031621 -267.432068) (xy 114.076792 -267.425806)
			(xy 114.099594 -267.425424) (xy 114.125565 -267.425906) (xy 114.176869 -267.434031) (xy 114.226269 -267.450082)
			(xy 114.272551 -267.473663) (xy 114.314574 -267.504193) (xy 114.351303 -267.540922) (xy 114.381834 -267.582944)
			(xy 114.405416 -267.629225) (xy 114.421467 -267.678626) (xy 114.429593 -267.729929) (xy 114.429593 -267.781845)
			(xy 114.709449 -267.781845) (xy 114.709449 -267.729911) (xy 114.717574 -267.678616) (xy 114.733622 -267.629223)
			(xy 114.7572 -267.582949) (xy 114.787726 -267.540933) (xy 114.824449 -267.50421) (xy 114.866465 -267.473684)
			(xy 114.912739 -267.450106) (xy 114.962132 -267.434058) (xy 115.013427 -267.425933) (xy 115.065361 -267.425933)
			(xy 115.116656 -267.434058) (xy 115.166049 -267.450106) (xy 115.212323 -267.473684) (xy 115.254339 -267.50421)
			(xy 115.291062 -267.540933) (xy 115.321588 -267.582949) (xy 115.345166 -267.629223) (xy 115.361214 -267.678616)
			(xy 115.369339 -267.729911) (xy 115.369848 -267.755878) (xy 115.369339 -267.781845) (xy 115.649249 -267.781845)
			(xy 115.649249 -267.729911) (xy 115.657374 -267.678616) (xy 115.673422 -267.629223) (xy 115.697 -267.582949)
			(xy 115.727526 -267.540933) (xy 115.764249 -267.50421) (xy 115.806265 -267.473684) (xy 115.852539 -267.450106)
			(xy 115.901932 -267.434058) (xy 115.953227 -267.425933) (xy 116.005161 -267.425933) (xy 116.056456 -267.434058)
			(xy 116.105849 -267.450106) (xy 116.152123 -267.473684) (xy 116.194139 -267.50421) (xy 116.230862 -267.540933)
			(xy 116.261388 -267.582949) (xy 116.284966 -267.629223) (xy 116.301014 -267.678616) (xy 116.309139 -267.729911)
			(xy 116.309648 -267.755878) (xy 116.309139 -267.781845) (xy 116.589303 -267.781845) (xy 116.589303 -267.729911)
			(xy 116.597428 -267.678616) (xy 116.613476 -267.629223) (xy 116.637054 -267.582949) (xy 116.66758 -267.540933)
			(xy 116.704303 -267.50421) (xy 116.746319 -267.473684) (xy 116.792593 -267.450106) (xy 116.841986 -267.434058)
			(xy 116.893281 -267.425933) (xy 116.945215 -267.425933) (xy 116.99651 -267.434058) (xy 117.045903 -267.450106)
			(xy 117.092177 -267.473684) (xy 117.134193 -267.50421) (xy 117.170916 -267.540933) (xy 117.201442 -267.582949)
			(xy 117.22502 -267.629223) (xy 117.241068 -267.678616) (xy 117.249193 -267.729911) (xy 117.249702 -267.755878)
			(xy 117.249193 -267.781845) (xy 117.241068 -267.83314) (xy 117.22502 -267.882533) (xy 117.201442 -267.928807)
			(xy 117.170916 -267.970823) (xy 117.134193 -268.007546) (xy 117.092177 -268.038072) (xy 117.045903 -268.06165)
			(xy 116.99651 -268.077698) (xy 116.945215 -268.085823) (xy 116.893281 -268.085823) (xy 116.841986 -268.077698)
			(xy 116.792593 -268.06165) (xy 116.746319 -268.038072) (xy 116.704303 -268.007546) (xy 116.66758 -267.970823)
			(xy 116.637054 -267.928807) (xy 116.613476 -267.882533) (xy 116.597428 -267.83314) (xy 116.589303 -267.781845)
			(xy 116.309139 -267.781845) (xy 116.301014 -267.83314) (xy 116.284966 -267.882533) (xy 116.261388 -267.928807)
			(xy 116.230862 -267.970823) (xy 116.194139 -268.007546) (xy 116.152123 -268.038072) (xy 116.105849 -268.06165)
			(xy 116.056456 -268.077698) (xy 116.005161 -268.085823) (xy 115.953227 -268.085823) (xy 115.901932 -268.077698)
			(xy 115.852539 -268.06165) (xy 115.806265 -268.038072) (xy 115.764249 -268.007546) (xy 115.727526 -267.970823)
			(xy 115.697 -267.928807) (xy 115.673422 -267.882533) (xy 115.657374 -267.83314) (xy 115.649249 -267.781845)
			(xy 115.369339 -267.781845) (xy 115.361214 -267.83314) (xy 115.345166 -267.882533) (xy 115.321588 -267.928807)
			(xy 115.291062 -267.970823) (xy 115.254339 -268.007546) (xy 115.212323 -268.038072) (xy 115.166049 -268.06165)
			(xy 115.116656 -268.077698) (xy 115.065361 -268.085823) (xy 115.013427 -268.085823) (xy 114.962132 -268.077698)
			(xy 114.912739 -268.06165) (xy 114.866465 -268.038072) (xy 114.824449 -268.007546) (xy 114.787726 -267.970823)
			(xy 114.7572 -267.928807) (xy 114.733622 -267.882533) (xy 114.717574 -267.83314) (xy 114.709449 -267.781845)
			(xy 114.429593 -267.781845) (xy 114.429593 -267.781871) (xy 114.421467 -267.833174) (xy 114.405416 -267.882575)
			(xy 114.381834 -267.928856) (xy 114.351303 -267.970878) (xy 114.314574 -268.007607) (xy 114.272551 -268.038137)
			(xy 114.226269 -268.061718) (xy 114.176869 -268.077769) (xy 114.125565 -268.085894) (xy 114.099594 -268.086332)
			(xy 114.076792 -268.08595) (xy 114.031621 -268.079683) (xy 113.987739 -268.06727) (xy 113.945979 -268.048946)
			(xy 113.926366 -268.03731) (xy 113.91465 -268.03062) (xy 113.888765 -268.023044) (xy 113.861799 -268.022516)
			(xy 113.835637 -268.029071) (xy 113.812107 -268.042252) (xy 113.792852 -268.061137) (xy 113.779218 -268.084408)
			(xy 113.772157 -268.110439) (xy 113.77168 -268.123924) (xy 113.77168 -268.271244) (xy 113.795484 -268.283159)
			(xy 113.839265 -268.313434) (xy 113.877628 -268.350334) (xy 113.909581 -268.392905) (xy 113.934298 -268.440048)
			(xy 113.95114 -268.490542) (xy 113.959672 -268.543083) (xy 113.959672 -268.595661) (xy 114.239803 -268.595661)
			(xy 114.239803 -268.543727) (xy 114.247928 -268.492432) (xy 114.263976 -268.443039) (xy 114.287554 -268.396765)
			(xy 114.31808 -268.354749) (xy 114.354803 -268.318026) (xy 114.396819 -268.2875) (xy 114.443093 -268.263922)
			(xy 114.492486 -268.247874) (xy 114.543781 -268.239749) (xy 114.595715 -268.239749) (xy 114.64701 -268.247874)
			(xy 114.696403 -268.263922) (xy 114.742677 -268.2875) (xy 114.784693 -268.318026) (xy 114.821416 -268.354749)
			(xy 114.851942 -268.396765) (xy 114.87552 -268.443039) (xy 114.891568 -268.492432) (xy 114.899693 -268.543727)
			(xy 114.900202 -268.569694) (xy 114.899693 -268.595661) (xy 115.179603 -268.595661) (xy 115.179603 -268.543727)
			(xy 115.187728 -268.492432) (xy 115.203776 -268.443039) (xy 115.227354 -268.396765) (xy 115.25788 -268.354749)
			(xy 115.294603 -268.318026) (xy 115.336619 -268.2875) (xy 115.382893 -268.263922) (xy 115.432286 -268.247874)
			(xy 115.483581 -268.239749) (xy 115.535515 -268.239749) (xy 115.58681 -268.247874) (xy 115.636203 -268.263922)
			(xy 115.682477 -268.2875) (xy 115.724493 -268.318026) (xy 115.761216 -268.354749) (xy 115.791742 -268.396765)
			(xy 115.81532 -268.443039) (xy 115.831368 -268.492432) (xy 115.839493 -268.543727) (xy 115.840002 -268.569694)
			(xy 115.839493 -268.595661) (xy 116.119403 -268.595661) (xy 116.119403 -268.543727) (xy 116.127528 -268.492432)
			(xy 116.143576 -268.443039) (xy 116.167154 -268.396765) (xy 116.19768 -268.354749) (xy 116.234403 -268.318026)
			(xy 116.276419 -268.2875) (xy 116.322693 -268.263922) (xy 116.372086 -268.247874) (xy 116.423381 -268.239749)
			(xy 116.475315 -268.239749) (xy 116.52661 -268.247874) (xy 116.576003 -268.263922) (xy 116.622277 -268.2875)
			(xy 116.664293 -268.318026) (xy 116.701016 -268.354749) (xy 116.731542 -268.396765) (xy 116.75512 -268.443039)
			(xy 116.771168 -268.492432) (xy 116.779293 -268.543727) (xy 116.779802 -268.569694) (xy 116.779293 -268.595661)
			(xy 117.058949 -268.595661) (xy 117.058949 -268.543727) (xy 117.067074 -268.492432) (xy 117.083122 -268.443039)
			(xy 117.1067 -268.396765) (xy 117.137226 -268.354749) (xy 117.173949 -268.318026) (xy 117.215965 -268.2875)
			(xy 117.262239 -268.263922) (xy 117.311632 -268.247874) (xy 117.362927 -268.239749) (xy 117.414861 -268.239749)
			(xy 117.466156 -268.247874) (xy 117.515549 -268.263922) (xy 117.561823 -268.2875) (xy 117.603839 -268.318026)
			(xy 117.640562 -268.354749) (xy 117.671088 -268.396765) (xy 117.694666 -268.443039) (xy 117.710714 -268.492432)
			(xy 117.718839 -268.543727) (xy 117.719348 -268.569694) (xy 117.718839 -268.595661) (xy 117.710714 -268.646956)
			(xy 117.694666 -268.696349) (xy 117.671088 -268.742623) (xy 117.640562 -268.784639) (xy 117.603839 -268.821362)
			(xy 117.561823 -268.851888) (xy 117.515549 -268.875466) (xy 117.466156 -268.891514) (xy 117.414861 -268.899639)
			(xy 117.362927 -268.899639) (xy 117.311632 -268.891514) (xy 117.262239 -268.875466) (xy 117.215965 -268.851888)
			(xy 117.173949 -268.821362) (xy 117.137226 -268.784639) (xy 117.1067 -268.742623) (xy 117.083122 -268.696349)
			(xy 117.067074 -268.646956) (xy 117.058949 -268.595661) (xy 116.779293 -268.595661) (xy 116.771168 -268.646956)
			(xy 116.75512 -268.696349) (xy 116.731542 -268.742623) (xy 116.701016 -268.784639) (xy 116.664293 -268.821362)
			(xy 116.622277 -268.851888) (xy 116.576003 -268.875466) (xy 116.52661 -268.891514) (xy 116.475315 -268.899639)
			(xy 116.423381 -268.899639) (xy 116.372086 -268.891514) (xy 116.322693 -268.875466) (xy 116.276419 -268.851888)
			(xy 116.234403 -268.821362) (xy 116.19768 -268.784639) (xy 116.167154 -268.742623) (xy 116.143576 -268.696349)
			(xy 116.127528 -268.646956) (xy 116.119403 -268.595661) (xy 115.839493 -268.595661) (xy 115.831368 -268.646956)
			(xy 115.81532 -268.696349) (xy 115.791742 -268.742623) (xy 115.761216 -268.784639) (xy 115.724493 -268.821362)
			(xy 115.682477 -268.851888) (xy 115.636203 -268.875466) (xy 115.58681 -268.891514) (xy 115.535515 -268.899639)
			(xy 115.483581 -268.899639) (xy 115.432286 -268.891514) (xy 115.382893 -268.875466) (xy 115.336619 -268.851888)
			(xy 115.294603 -268.821362) (xy 115.25788 -268.784639) (xy 115.227354 -268.742623) (xy 115.203776 -268.696349)
			(xy 115.187728 -268.646956) (xy 115.179603 -268.595661) (xy 114.899693 -268.595661) (xy 114.891568 -268.646956)
			(xy 114.87552 -268.696349) (xy 114.851942 -268.742623) (xy 114.821416 -268.784639) (xy 114.784693 -268.821362)
			(xy 114.742677 -268.851888) (xy 114.696403 -268.875466) (xy 114.64701 -268.891514) (xy 114.595715 -268.899639)
			(xy 114.543781 -268.899639) (xy 114.492486 -268.891514) (xy 114.443093 -268.875466) (xy 114.396819 -268.851888)
			(xy 114.354803 -268.821362) (xy 114.31808 -268.784639) (xy 114.287554 -268.742623) (xy 114.263976 -268.696349)
			(xy 114.247928 -268.646956) (xy 114.239803 -268.595661) (xy 113.959672 -268.595661) (xy 113.959672 -268.596312)
			(xy 113.951142 -268.648853) (xy 113.9343 -268.699348) (xy 113.909584 -268.74649) (xy 113.877632 -268.789062)
			(xy 113.839269 -268.825963) (xy 113.795489 -268.856238) (xy 113.77168 -268.868144) (xy 113.77168 -269.015972)
			(xy 113.772098 -269.02948) (xy 113.779183 -269.05555) (xy 113.792864 -269.078845) (xy 113.812181 -269.097732)
			(xy 113.835779 -269.110884) (xy 113.862002 -269.11738) (xy 113.889011 -269.116764) (xy 113.91491 -269.109079)
			(xy 113.92662 -269.102332) (xy 113.946263 -269.090669) (xy 113.988074 -269.07226) (xy 114.032018 -269.059772)
			(xy 114.077261 -269.05344) (xy 114.100102 -269.053056) (xy 114.126068 -269.053565) (xy 114.177362 -269.06169)
			(xy 114.226752 -269.077738) (xy 114.273025 -269.101315) (xy 114.315039 -269.131841) (xy 114.351761 -269.168563)
			(xy 114.382286 -269.210577) (xy 114.405863 -269.256849) (xy 114.421911 -269.30624) (xy 114.430035 -269.357534)
			(xy 114.430035 -269.409466) (xy 114.430033 -269.409477) (xy 114.709449 -269.409477) (xy 114.709449 -269.357543)
			(xy 114.717574 -269.306248) (xy 114.733622 -269.256855) (xy 114.7572 -269.210581) (xy 114.787726 -269.168565)
			(xy 114.824449 -269.131842) (xy 114.866465 -269.101316) (xy 114.912739 -269.077738) (xy 114.962132 -269.06169)
			(xy 115.013427 -269.053565) (xy 115.065361 -269.053565) (xy 115.116656 -269.06169) (xy 115.166049 -269.077738)
			(xy 115.212323 -269.101316) (xy 115.254339 -269.131842) (xy 115.291062 -269.168565) (xy 115.321588 -269.210581)
			(xy 115.345166 -269.256855) (xy 115.361214 -269.306248) (xy 115.369339 -269.357543) (xy 115.369848 -269.38351)
			(xy 115.369339 -269.409477) (xy 115.649249 -269.409477) (xy 115.649249 -269.357543) (xy 115.657374 -269.306248)
			(xy 115.673422 -269.256855) (xy 115.697 -269.210581) (xy 115.727526 -269.168565) (xy 115.764249 -269.131842)
			(xy 115.806265 -269.101316) (xy 115.852539 -269.077738) (xy 115.901932 -269.06169) (xy 115.953227 -269.053565)
			(xy 116.005161 -269.053565) (xy 116.056456 -269.06169) (xy 116.105849 -269.077738) (xy 116.152123 -269.101316)
			(xy 116.194139 -269.131842) (xy 116.230862 -269.168565) (xy 116.261388 -269.210581) (xy 116.284966 -269.256855)
			(xy 116.301014 -269.306248) (xy 116.309139 -269.357543) (xy 116.309648 -269.38351) (xy 116.309139 -269.409477)
			(xy 116.589049 -269.409477) (xy 116.589049 -269.357543) (xy 116.597174 -269.306248) (xy 116.613222 -269.256855)
			(xy 116.6368 -269.210581) (xy 116.667326 -269.168565) (xy 116.704049 -269.131842) (xy 116.746065 -269.101316)
			(xy 116.792339 -269.077738) (xy 116.841732 -269.06169) (xy 116.893027 -269.053565) (xy 116.944961 -269.053565)
			(xy 116.996256 -269.06169) (xy 117.045649 -269.077738) (xy 117.091923 -269.101316) (xy 117.133939 -269.131842)
			(xy 117.170662 -269.168565) (xy 117.201188 -269.210581) (xy 117.224766 -269.256855) (xy 117.240814 -269.306248)
			(xy 117.248939 -269.357543) (xy 117.249448 -269.38351) (xy 117.248939 -269.409477) (xy 117.240814 -269.460772)
			(xy 117.224766 -269.510165) (xy 117.201188 -269.556439) (xy 117.170662 -269.598455) (xy 117.133939 -269.635178)
			(xy 117.091923 -269.665704) (xy 117.045649 -269.689282) (xy 116.996256 -269.70533) (xy 116.944961 -269.713455)
			(xy 116.893027 -269.713455) (xy 116.841732 -269.70533) (xy 116.792339 -269.689282) (xy 116.746065 -269.665704)
			(xy 116.704049 -269.635178) (xy 116.667326 -269.598455) (xy 116.6368 -269.556439) (xy 116.613222 -269.510165)
			(xy 116.597174 -269.460772) (xy 116.589049 -269.409477) (xy 116.309139 -269.409477) (xy 116.301014 -269.460772)
			(xy 116.284966 -269.510165) (xy 116.261388 -269.556439) (xy 116.230862 -269.598455) (xy 116.194139 -269.635178)
			(xy 116.152123 -269.665704) (xy 116.105849 -269.689282) (xy 116.056456 -269.70533) (xy 116.005161 -269.713455)
			(xy 115.953227 -269.713455) (xy 115.901932 -269.70533) (xy 115.852539 -269.689282) (xy 115.806265 -269.665704)
			(xy 115.764249 -269.635178) (xy 115.727526 -269.598455) (xy 115.697 -269.556439) (xy 115.673422 -269.510165)
			(xy 115.657374 -269.460772) (xy 115.649249 -269.409477) (xy 115.369339 -269.409477) (xy 115.361214 -269.460772)
			(xy 115.345166 -269.510165) (xy 115.321588 -269.556439) (xy 115.291062 -269.598455) (xy 115.254339 -269.635178)
			(xy 115.212323 -269.665704) (xy 115.166049 -269.689282) (xy 115.116656 -269.70533) (xy 115.065361 -269.713455)
			(xy 115.013427 -269.713455) (xy 114.962132 -269.70533) (xy 114.912739 -269.689282) (xy 114.866465 -269.665704)
			(xy 114.824449 -269.635178) (xy 114.787726 -269.598455) (xy 114.7572 -269.556439) (xy 114.733622 -269.510165)
			(xy 114.717574 -269.460772) (xy 114.709449 -269.409477) (xy 114.430033 -269.409477) (xy 114.421911 -269.46076)
			(xy 114.405863 -269.510151) (xy 114.382286 -269.556423) (xy 114.351761 -269.598437) (xy 114.315039 -269.635159)
			(xy 114.273025 -269.665685) (xy 114.226752 -269.689262) (xy 114.177362 -269.70531) (xy 114.126068 -269.713435)
			(xy 114.100102 -269.713964) (xy 114.077259 -269.713582) (xy 114.032008 -269.707285) (xy 113.988061 -269.694799)
			(xy 113.946259 -269.676362) (xy 113.92662 -269.664688) (xy 113.914908 -269.657962) (xy 113.889015 -269.650316)
			(xy 113.862023 -269.649724) (xy 113.83582 -269.656227) (xy 113.812237 -269.669371) (xy 113.792924 -269.688237)
			(xy 113.779231 -269.711505) (xy 113.772116 -269.737549) (xy 113.77168 -269.751048) (xy 113.77168 -269.89913)
			(xy 113.795485 -269.911045) (xy 113.839269 -269.94132) (xy 113.877634 -269.978221) (xy 113.909589 -270.020794)
			(xy 113.934308 -270.067937) (xy 113.951151 -270.118433) (xy 113.959684 -270.170976) (xy 113.959685 -270.223547)
			(xy 116.119403 -270.223547) (xy 116.119403 -270.171613) (xy 116.127528 -270.120318) (xy 116.143576 -270.070925)
			(xy 116.167154 -270.024651) (xy 116.19768 -269.982635) (xy 116.234403 -269.945912) (xy 116.276419 -269.915386)
			(xy 116.322693 -269.891808) (xy 116.372086 -269.87576) (xy 116.423381 -269.867635) (xy 116.475315 -269.867635)
			(xy 116.52661 -269.87576) (xy 116.576003 -269.891808) (xy 116.622277 -269.915386) (xy 116.664293 -269.945912)
			(xy 116.701016 -269.982635) (xy 116.731542 -270.024651) (xy 116.75512 -270.070925) (xy 116.771168 -270.120318)
			(xy 116.779293 -270.171613) (xy 116.779802 -270.19758) (xy 116.779293 -270.223547) (xy 117.058949 -270.223547)
			(xy 117.058949 -270.171613) (xy 117.067074 -270.120318) (xy 117.083122 -270.070925) (xy 117.1067 -270.024651)
			(xy 117.137226 -269.982635) (xy 117.173949 -269.945912) (xy 117.215965 -269.915386) (xy 117.262239 -269.891808)
			(xy 117.311632 -269.87576) (xy 117.362927 -269.867635) (xy 117.414861 -269.867635) (xy 117.466156 -269.87576)
			(xy 117.515549 -269.891808) (xy 117.561823 -269.915386) (xy 117.603839 -269.945912) (xy 117.640562 -269.982635)
			(xy 117.671088 -270.024651) (xy 117.694666 -270.070925) (xy 117.710714 -270.120318) (xy 117.718839 -270.171613)
			(xy 117.719348 -270.19758) (xy 117.718839 -270.223547) (xy 117.710714 -270.274842) (xy 117.694666 -270.324235)
			(xy 117.671088 -270.370509) (xy 117.640562 -270.412525) (xy 117.603839 -270.449248) (xy 117.561823 -270.479774)
			(xy 117.515549 -270.503352) (xy 117.466156 -270.5194) (xy 117.414861 -270.527525) (xy 117.362927 -270.527525)
			(xy 117.311632 -270.5194) (xy 117.262239 -270.503352) (xy 117.215965 -270.479774) (xy 117.173949 -270.449248)
			(xy 117.137226 -270.412525) (xy 117.1067 -270.370509) (xy 117.083122 -270.324235) (xy 117.067074 -270.274842)
			(xy 117.058949 -270.223547) (xy 116.779293 -270.223547) (xy 116.771168 -270.274842) (xy 116.75512 -270.324235)
			(xy 116.731542 -270.370509) (xy 116.701016 -270.412525) (xy 116.664293 -270.449248) (xy 116.622277 -270.479774)
			(xy 116.576003 -270.503352) (xy 116.52661 -270.5194) (xy 116.475315 -270.527525) (xy 116.423381 -270.527525)
			(xy 116.372086 -270.5194) (xy 116.322693 -270.503352) (xy 116.276419 -270.479774) (xy 116.234403 -270.449248)
			(xy 116.19768 -270.412525) (xy 116.167154 -270.370509) (xy 116.143576 -270.324235) (xy 116.127528 -270.274842)
			(xy 116.119403 -270.223547) (xy 113.959685 -270.223547) (xy 113.959685 -270.224207) (xy 113.951155 -270.27675)
			(xy 113.934314 -270.327247) (xy 113.909598 -270.374392) (xy 113.877645 -270.416966) (xy 113.839282 -270.453869)
			(xy 113.7955 -270.484146) (xy 113.77168 -270.49603) (xy 113.77168 -271.037363) (xy 116.589049 -271.037363)
			(xy 116.589049 -270.985429) (xy 116.597174 -270.934134) (xy 116.613222 -270.884741) (xy 116.6368 -270.838467)
			(xy 116.667326 -270.796451) (xy 116.704049 -270.759728) (xy 116.746065 -270.729202) (xy 116.792339 -270.705624)
			(xy 116.841732 -270.689576) (xy 116.893027 -270.681451) (xy 116.944961 -270.681451) (xy 116.996256 -270.689576)
			(xy 117.045649 -270.705624) (xy 117.091923 -270.729202) (xy 117.133939 -270.759728) (xy 117.170662 -270.796451)
			(xy 117.201188 -270.838467) (xy 117.224766 -270.884741) (xy 117.240814 -270.934134) (xy 117.248939 -270.985429)
			(xy 117.249448 -271.011396) (xy 117.248939 -271.037363) (xy 117.240814 -271.088658) (xy 117.224766 -271.138051)
			(xy 117.201188 -271.184325) (xy 117.170662 -271.226341) (xy 117.133939 -271.263064) (xy 117.091923 -271.29359)
			(xy 117.045649 -271.317168) (xy 116.996256 -271.333216) (xy 116.944961 -271.341341) (xy 116.893027 -271.341341)
			(xy 116.841732 -271.333216) (xy 116.792339 -271.317168) (xy 116.746065 -271.29359) (xy 116.704049 -271.263064)
			(xy 116.667326 -271.226341) (xy 116.6368 -271.184325) (xy 116.613222 -271.138051) (xy 116.597174 -271.088658)
			(xy 116.589049 -271.037363) (xy 113.77168 -271.037363) (xy 113.77168 -271.39138) (xy 114.127026 -271.74698)
			(xy 114.24666 -271.74698)
		)
		(stroke
			(width 0)
			(type solid)
		)
		(fill yes)
		(layer "In11.Cu")
		(net "PVPP_HBM_CPU1")
	)
	(gr_poly
		(pts
			(xy 278.5364 -78.420468) (xy 278.5364 -63.34252) (xy 277.33752 -62.14364) (xy 275.681186 -62.14364)
			(xy 275.666379 -62.144133) (xy 275.638002 -62.152605) (xy 275.613249 -62.168862) (xy 275.594201 -62.191536)
			(xy 275.582458 -62.218723) (xy 275.579009 -62.248135) (xy 275.584142 -62.277301) (xy 275.597427 -62.303767)
			(xy 275.607272 -62.314836) (xy 275.626581 -62.336174) (xy 275.659216 -62.383572) (xy 275.684364 -62.435333)
			(xy 275.701456 -62.490282) (xy 275.710104 -62.547175) (xy 275.71065 -62.575948) (xy 275.710161 -62.603198)
			(xy 275.702399 -62.657143) (xy 275.68704 -62.709434) (xy 275.664397 -62.759008) (xy 275.63493 -62.804856)
			(xy 275.599239 -62.846043) (xy 275.558051 -62.881734) (xy 275.512203 -62.9112) (xy 275.462629 -62.933842)
			(xy 275.410337 -62.9492) (xy 275.356392 -62.956961) (xy 275.329142 -62.957456) (xy 275.300228 -62.956918)
			(xy 275.243062 -62.948182) (xy 275.18787 -62.930921) (xy 275.135915 -62.905528) (xy 275.088386 -62.872586)
			(xy 275.046373 -62.832848) (xy 275.028152 -62.81039) (xy 275.018255 -62.798585) (xy 274.992931 -62.781066)
			(xy 274.963538 -62.77189) (xy 274.932746 -62.77189) (xy 274.903353 -62.781066) (xy 274.878029 -62.798585)
			(xy 274.868132 -62.81039) (xy 274.851379 -62.831173) (xy 274.813025 -62.868303) (xy 274.769871 -62.899725)
			(xy 274.722757 -62.924824) (xy 274.672605 -62.94311) (xy 274.620394 -62.954227) (xy 274.567142 -62.957957)
			(xy 274.51389 -62.954227) (xy 274.461679 -62.94311) (xy 274.411527 -62.924824) (xy 274.364413 -62.899725)
			(xy 274.321259 -62.868303) (xy 274.282905 -62.831173) (xy 274.266152 -62.81039) (xy 274.256255 -62.798585)
			(xy 274.230931 -62.781066) (xy 274.201538 -62.77189) (xy 274.170746 -62.77189) (xy 274.141353 -62.781066)
			(xy 274.116029 -62.798585) (xy 274.106132 -62.81039) (xy 274.087942 -62.832874) (xy 274.045925 -62.872613)
			(xy 273.99839 -62.905553) (xy 273.946428 -62.930939) (xy 273.891229 -62.948191) (xy 273.834058 -62.956913)
			(xy 273.805142 -62.957456) (xy 273.777888 -62.956973) (xy 273.723933 -62.949222) (xy 273.67163 -62.933871)
			(xy 273.622045 -62.911233) (xy 273.576185 -62.881768) (xy 273.534986 -62.846077) (xy 273.499286 -62.804887)
			(xy 273.469811 -62.759034) (xy 273.447161 -62.709454) (xy 273.431797 -62.657155) (xy 273.424033 -62.603202)
			(xy 273.423634 -62.575948) (xy 273.424155 -62.547173) (xy 273.432795 -62.490274) (xy 273.449887 -62.43532)
			(xy 273.475041 -62.383558) (xy 273.507688 -62.336163) (xy 273.527012 -62.314836) (xy 273.536785 -62.303715)
			(xy 273.550038 -62.277255) (xy 273.555154 -62.248107) (xy 273.551704 -62.218716) (xy 273.539977 -62.191545)
			(xy 273.520957 -62.168873) (xy 273.496239 -62.152602) (xy 273.467894 -62.144096) (xy 273.453098 -62.14364)
			(xy 256.68859 -62.14364) (xy 254.903224 -63.928752) (xy 254.882376 -63.948882) (xy 254.835529 -63.982994)
			(xy 254.783921 -64.009355) (xy 254.728824 -64.027316) (xy 254.671595 -64.036433) (xy 254.64262 -64.036956)
			(xy 251.604526 -64.036956) (xy 249.296565 -66.3448) (xy 263.172954 -66.3448) (xy 263.177025 -66.289178)
			(xy 263.189151 -66.234741) (xy 263.209074 -66.18265) (xy 263.23637 -66.134015) (xy 263.270456 -66.089872)
			(xy 263.310605 -66.051163) (xy 263.355963 -66.018712) (xy 263.405563 -65.993211) (xy 263.458347 -65.975204)
			(xy 263.51319 -65.965074) (xy 263.568924 -65.963037) (xy 263.624361 -65.969137) (xy 263.678318 -65.983243)
			(xy 263.729647 -66.005055) (xy 263.777253 -66.034109) (xy 263.820121 -66.069784) (xy 263.857338 -66.111321)
			(xy 263.888111 -66.157834) (xy 263.911783 -66.208331) (xy 263.927851 -66.261738) (xy 263.930708 -66.281153)
			(xy 273.401246 -66.281153) (xy 273.401246 -66.226647) (xy 273.409003 -66.172697) (xy 273.424358 -66.120399)
			(xy 273.447 -66.070819) (xy 273.476467 -66.024965) (xy 273.512159 -65.983772) (xy 273.553351 -65.948078)
			(xy 273.599203 -65.918608) (xy 273.648782 -65.895964) (xy 273.701079 -65.880606) (xy 273.755029 -65.872847)
			(xy 273.782282 -65.87236) (xy 273.8112 -65.872868) (xy 273.868372 -65.881596) (xy 273.923572 -65.898855)
			(xy 273.975534 -65.924248) (xy 274.023068 -65.957194) (xy 274.065083 -65.996939) (xy 274.083272 -66.019426)
			(xy 274.093169 -66.031231) (xy 274.118493 -66.04875) (xy 274.147886 -66.057926) (xy 274.178678 -66.057926)
			(xy 274.208071 -66.04875) (xy 274.233395 -66.031231) (xy 274.243292 -66.019426) (xy 274.260045 -65.998643)
			(xy 274.298399 -65.961513) (xy 274.341553 -65.930091) (xy 274.388667 -65.904992) (xy 274.438819 -65.886706)
			(xy 274.49103 -65.875589) (xy 274.544282 -65.871859) (xy 274.597534 -65.875589) (xy 274.649745 -65.886706)
			(xy 274.699897 -65.904992) (xy 274.747011 -65.930091) (xy 274.790165 -65.961513) (xy 274.828519 -65.998643)
			(xy 274.845272 -66.019426) (xy 274.855169 -66.031231) (xy 274.880493 -66.04875) (xy 274.909886 -66.057926)
			(xy 274.940678 -66.057926) (xy 274.970071 -66.04875) (xy 274.995395 -66.031231) (xy 275.005292 -66.019426)
			(xy 275.023494 -65.996952) (xy 275.065511 -65.957215) (xy 275.113043 -65.924274) (xy 275.165002 -65.898884)
			(xy 275.220198 -65.881626) (xy 275.277367 -65.872896) (xy 275.306282 -65.87236) (xy 275.333533 -65.872886)
			(xy 275.387482 -65.88064) (xy 275.439777 -65.895993) (xy 275.489356 -65.918633) (xy 275.535207 -65.948098)
			(xy 275.576399 -65.983789) (xy 275.612091 -66.024978) (xy 275.641558 -66.070829) (xy 275.6642 -66.120406)
			(xy 275.679556 -66.172701) (xy 275.687313 -66.226649) (xy 275.687313 -66.281151) (xy 275.679556 -66.335099)
			(xy 275.6642 -66.387394) (xy 275.641558 -66.436971) (xy 275.612091 -66.482822) (xy 275.576399 -66.524011)
			(xy 275.535207 -66.559702) (xy 275.489356 -66.589167) (xy 275.439777 -66.611807) (xy 275.387482 -66.62716)
			(xy 275.333533 -66.634914) (xy 275.306282 -66.635376) (xy 275.277367 -66.634808) (xy 275.220197 -66.626091)
			(xy 275.164999 -66.608843) (xy 275.113037 -66.583461) (xy 275.065502 -66.550526) (xy 275.023483 -66.510792)
			(xy 275.005292 -66.48831) (xy 274.995395 -66.476505) (xy 274.970071 -66.458986) (xy 274.940678 -66.44981)
			(xy 274.909886 -66.44981) (xy 274.880493 -66.458986) (xy 274.855169 -66.476505) (xy 274.845272 -66.48831)
			(xy 274.828519 -66.509093) (xy 274.790165 -66.546223) (xy 274.747011 -66.577645) (xy 274.699897 -66.602744)
			(xy 274.649745 -66.62103) (xy 274.597534 -66.632147) (xy 274.544282 -66.635877) (xy 274.49103 -66.632147)
			(xy 274.438819 -66.62103) (xy 274.388667 -66.602744) (xy 274.341553 -66.577645) (xy 274.298399 -66.546223)
			(xy 274.260045 -66.509093) (xy 274.243292 -66.48831) (xy 274.233395 -66.476505) (xy 274.208071 -66.458986)
			(xy 274.178678 -66.44981) (xy 274.147886 -66.44981) (xy 274.118493 -66.458986) (xy 274.093169 -66.476505)
			(xy 274.083272 -66.48831) (xy 274.065099 -66.510809) (xy 274.023075 -66.550543) (xy 273.975537 -66.58348)
			(xy 273.923572 -66.608865) (xy 273.868371 -66.626118) (xy 273.811199 -66.634843) (xy 273.782282 -66.635376)
			(xy 273.755029 -66.634953) (xy 273.701079 -66.627194) (xy 273.648782 -66.611836) (xy 273.599203 -66.589192)
			(xy 273.553351 -66.559722) (xy 273.512159 -66.524028) (xy 273.476467 -66.482835) (xy 273.447 -66.436981)
			(xy 273.424358 -66.387401) (xy 273.409003 -66.335103) (xy 273.401246 -66.281153) (xy 263.930708 -66.281153)
			(xy 263.935971 -66.316914) (xy 263.93648 -66.3448) (xy 263.935971 -66.372686) (xy 263.927851 -66.427862)
			(xy 263.911783 -66.481269) (xy 263.888111 -66.531766) (xy 263.857338 -66.578279) (xy 263.820121 -66.619816)
			(xy 263.777253 -66.655491) (xy 263.729647 -66.684545) (xy 263.678318 -66.706357) (xy 263.624361 -66.720463)
			(xy 263.568924 -66.726563) (xy 263.51319 -66.724526) (xy 263.458347 -66.714396) (xy 263.405563 -66.696389)
			(xy 263.355963 -66.670888) (xy 263.310605 -66.638437) (xy 263.270456 -66.599728) (xy 263.23637 -66.555585)
			(xy 263.209074 -66.50695) (xy 263.189151 -66.454859) (xy 263.177025 -66.400422) (xy 263.172954 -66.3448)
			(xy 249.296565 -66.3448) (xy 248.552307 -67.08902) (xy 261.67029 -67.08902) (xy 261.674361 -67.033398)
			(xy 261.686487 -66.978961) (xy 261.70641 -66.92687) (xy 261.733706 -66.878235) (xy 261.767792 -66.834092)
			(xy 261.807941 -66.795383) (xy 261.853299 -66.762932) (xy 261.902899 -66.737431) (xy 261.955683 -66.719424)
			(xy 262.010526 -66.709294) (xy 262.06626 -66.707257) (xy 262.121697 -66.713357) (xy 262.175654 -66.727463)
			(xy 262.226983 -66.749275) (xy 262.274589 -66.778329) (xy 262.317457 -66.814004) (xy 262.354674 -66.855541)
			(xy 262.385447 -66.902054) (xy 262.409119 -66.952551) (xy 262.425187 -67.005958) (xy 262.433307 -67.061134)
			(xy 262.433816 -67.08902) (xy 262.433307 -67.116906) (xy 262.425187 -67.172082) (xy 262.409119 -67.225489)
			(xy 262.385447 -67.275986) (xy 262.354674 -67.322499) (xy 262.317457 -67.364036) (xy 262.274589 -67.399711)
			(xy 262.239293 -67.421252) (xy 273.131024 -67.421252) (xy 273.135095 -67.36563) (xy 273.147221 -67.311193)
			(xy 273.167144 -67.259102) (xy 273.19444 -67.210467) (xy 273.228526 -67.166324) (xy 273.268675 -67.127615)
			(xy 273.314033 -67.095164) (xy 273.363633 -67.069663) (xy 273.416417 -67.051656) (xy 273.47126 -67.041526)
			(xy 273.526994 -67.039489) (xy 273.582431 -67.045589) (xy 273.636388 -67.059695) (xy 273.687717 -67.081507)
			(xy 273.735323 -67.110561) (xy 273.778191 -67.146236) (xy 273.815408 -67.187773) (xy 273.846181 -67.234286)
			(xy 273.869853 -67.284783) (xy 273.885921 -67.33819) (xy 273.894041 -67.393366) (xy 273.89455 -67.421252)
			(xy 274.020024 -67.421252) (xy 274.024095 -67.36563) (xy 274.036221 -67.311193) (xy 274.056144 -67.259102)
			(xy 274.08344 -67.210467) (xy 274.117526 -67.166324) (xy 274.157675 -67.127615) (xy 274.203033 -67.095164)
			(xy 274.252633 -67.069663) (xy 274.305417 -67.051656) (xy 274.36026 -67.041526) (xy 274.415994 -67.039489)
			(xy 274.471431 -67.045589) (xy 274.525388 -67.059695) (xy 274.576717 -67.081507) (xy 274.624323 -67.110561)
			(xy 274.667191 -67.146236) (xy 274.704408 -67.187773) (xy 274.735181 -67.234286) (xy 274.758853 -67.284783)
			(xy 274.774921 -67.33819) (xy 274.783041 -67.393366) (xy 274.78355 -67.421252) (xy 274.909024 -67.421252)
			(xy 274.913095 -67.36563) (xy 274.925221 -67.311193) (xy 274.945144 -67.259102) (xy 274.97244 -67.210467)
			(xy 275.006526 -67.166324) (xy 275.046675 -67.127615) (xy 275.092033 -67.095164) (xy 275.141633 -67.069663)
			(xy 275.194417 -67.051656) (xy 275.24926 -67.041526) (xy 275.304994 -67.039489) (xy 275.360431 -67.045589)
			(xy 275.414388 -67.059695) (xy 275.465717 -67.081507) (xy 275.513323 -67.110561) (xy 275.556191 -67.146236)
			(xy 275.593408 -67.187773) (xy 275.624181 -67.234286) (xy 275.647853 -67.284783) (xy 275.663921 -67.33819)
			(xy 275.672041 -67.393366) (xy 275.67255 -67.421252) (xy 275.672041 -67.449138) (xy 275.663921 -67.504314)
			(xy 275.647853 -67.557721) (xy 275.624181 -67.608218) (xy 275.593408 -67.654731) (xy 275.556191 -67.696268)
			(xy 275.513323 -67.731943) (xy 275.465717 -67.760997) (xy 275.414388 -67.782809) (xy 275.360431 -67.796915)
			(xy 275.304994 -67.803015) (xy 275.24926 -67.800978) (xy 275.194417 -67.790848) (xy 275.141633 -67.772841)
			(xy 275.092033 -67.74734) (xy 275.046675 -67.714889) (xy 275.006526 -67.67618) (xy 274.97244 -67.632037)
			(xy 274.945144 -67.583402) (xy 274.925221 -67.531311) (xy 274.913095 -67.476874) (xy 274.909024 -67.421252)
			(xy 274.78355 -67.421252) (xy 274.783041 -67.449138) (xy 274.774921 -67.504314) (xy 274.758853 -67.557721)
			(xy 274.735181 -67.608218) (xy 274.704408 -67.654731) (xy 274.667191 -67.696268) (xy 274.624323 -67.731943)
			(xy 274.576717 -67.760997) (xy 274.525388 -67.782809) (xy 274.471431 -67.796915) (xy 274.415994 -67.803015)
			(xy 274.36026 -67.800978) (xy 274.305417 -67.790848) (xy 274.252633 -67.772841) (xy 274.203033 -67.74734)
			(xy 274.157675 -67.714889) (xy 274.117526 -67.67618) (xy 274.08344 -67.632037) (xy 274.056144 -67.583402)
			(xy 274.036221 -67.531311) (xy 274.024095 -67.476874) (xy 274.020024 -67.421252) (xy 273.89455 -67.421252)
			(xy 273.894041 -67.449138) (xy 273.885921 -67.504314) (xy 273.869853 -67.557721) (xy 273.846181 -67.608218)
			(xy 273.815408 -67.654731) (xy 273.778191 -67.696268) (xy 273.735323 -67.731943) (xy 273.687717 -67.760997)
			(xy 273.636388 -67.782809) (xy 273.582431 -67.796915) (xy 273.526994 -67.803015) (xy 273.47126 -67.800978)
			(xy 273.416417 -67.790848) (xy 273.363633 -67.772841) (xy 273.314033 -67.74734) (xy 273.268675 -67.714889)
			(xy 273.228526 -67.67618) (xy 273.19444 -67.632037) (xy 273.167144 -67.583402) (xy 273.147221 -67.531311)
			(xy 273.135095 -67.476874) (xy 273.131024 -67.421252) (xy 262.239293 -67.421252) (xy 262.226983 -67.428765)
			(xy 262.175654 -67.450577) (xy 262.121697 -67.464683) (xy 262.06626 -67.470783) (xy 262.010526 -67.468746)
			(xy 261.955683 -67.458616) (xy 261.902899 -67.440609) (xy 261.853299 -67.415108) (xy 261.807941 -67.382657)
			(xy 261.767792 -67.343948) (xy 261.733706 -67.299805) (xy 261.70641 -67.25117) (xy 261.686487 -67.199079)
			(xy 261.674361 -67.144642) (xy 261.67029 -67.08902) (xy 248.552307 -67.08902) (xy 247.434142 -68.207128)
			(xy 248.911362 -68.207128) (xy 248.915433 -68.151506) (xy 248.927559 -68.097069) (xy 248.947482 -68.044978)
			(xy 248.974778 -67.996343) (xy 249.008864 -67.9522) (xy 249.049013 -67.913491) (xy 249.094371 -67.88104)
			(xy 249.143971 -67.855539) (xy 249.196755 -67.837532) (xy 249.251598 -67.827402) (xy 249.307332 -67.825365)
			(xy 249.362769 -67.831465) (xy 249.416726 -67.845571) (xy 249.468055 -67.867383) (xy 249.515661 -67.896437)
			(xy 249.558529 -67.932112) (xy 249.595746 -67.973649) (xy 249.626519 -68.020162) (xy 249.650191 -68.070659)
			(xy 249.666259 -68.124066) (xy 249.674379 -68.179242) (xy 249.674888 -68.207128) (xy 249.674379 -68.235014)
			(xy 249.666259 -68.29019) (xy 249.650191 -68.343597) (xy 249.626519 -68.394094) (xy 249.595746 -68.440607)
			(xy 249.562016 -68.478252) (xy 273.901646 -68.478252) (xy 273.901646 -68.423748) (xy 273.909402 -68.369799)
			(xy 273.924756 -68.317503) (xy 273.947397 -68.267924) (xy 273.976862 -68.222072) (xy 274.012552 -68.180879)
			(xy 274.053741 -68.145185) (xy 274.099591 -68.115715) (xy 274.149168 -68.09307) (xy 274.201462 -68.07771)
			(xy 274.25541 -68.069948) (xy 274.282662 -68.06946) (xy 274.311579 -68.069983) (xy 274.368751 -68.078708)
			(xy 274.423951 -68.095963) (xy 274.475913 -68.121354) (xy 274.523447 -68.154298) (xy 274.565463 -68.19404)
			(xy 274.583652 -68.216526) (xy 274.593549 -68.228331) (xy 274.618873 -68.24585) (xy 274.648266 -68.255026)
			(xy 274.679058 -68.255026) (xy 274.708451 -68.24585) (xy 274.733775 -68.228331) (xy 274.743672 -68.216526)
			(xy 274.761885 -68.194061) (xy 274.8039 -68.154324) (xy 274.85143 -68.121382) (xy 274.903387 -68.09599)
			(xy 274.958581 -68.07873) (xy 275.015747 -68.069997) (xy 275.044662 -68.06946) (xy 275.071914 -68.069985)
			(xy 275.125865 -68.077737) (xy 275.178163 -68.093088) (xy 275.227744 -68.115726) (xy 275.273598 -68.145191)
			(xy 275.314791 -68.180882) (xy 275.350486 -68.222072) (xy 275.379955 -68.267923) (xy 275.402599 -68.317501)
			(xy 275.417955 -68.369798) (xy 275.425713 -68.423748) (xy 275.425713 -68.478252) (xy 275.417955 -68.532202)
			(xy 275.402599 -68.584499) (xy 275.379955 -68.634077) (xy 275.350486 -68.679928) (xy 275.314791 -68.721118)
			(xy 275.273598 -68.756809) (xy 275.227744 -68.786274) (xy 275.178163 -68.808912) (xy 275.125865 -68.824263)
			(xy 275.071914 -68.832015) (xy 275.044662 -68.832476) (xy 275.015746 -68.831922) (xy 274.958576 -68.823202)
			(xy 274.903378 -68.805952) (xy 274.851416 -68.780567) (xy 274.803881 -68.747629) (xy 274.761863 -68.707893)
			(xy 274.743672 -68.68541) (xy 274.733775 -68.673605) (xy 274.708451 -68.656086) (xy 274.679058 -68.64691)
			(xy 274.648266 -68.64691) (xy 274.618873 -68.656086) (xy 274.593549 -68.673605) (xy 274.583652 -68.68541)
			(xy 274.565434 -68.707871) (xy 274.52342 -68.747607) (xy 274.47589 -68.780548) (xy 274.423934 -68.80594)
			(xy 274.368742 -68.823202) (xy 274.311576 -68.831937) (xy 274.282662 -68.832476) (xy 274.25541 -68.832052)
			(xy 274.201462 -68.82429) (xy 274.149168 -68.80893) (xy 274.099591 -68.786285) (xy 274.053741 -68.756815)
			(xy 274.012552 -68.721121) (xy 273.976862 -68.679928) (xy 273.947397 -68.634076) (xy 273.924756 -68.584497)
			(xy 273.909402 -68.532201) (xy 273.901646 -68.478252) (xy 249.562016 -68.478252) (xy 249.558529 -68.482144)
			(xy 249.515661 -68.517819) (xy 249.468055 -68.546873) (xy 249.416726 -68.568685) (xy 249.362769 -68.582791)
			(xy 249.307332 -68.588891) (xy 249.251598 -68.586854) (xy 249.196755 -68.576724) (xy 249.143971 -68.558717)
			(xy 249.094371 -68.533216) (xy 249.049013 -68.500765) (xy 249.008864 -68.462056) (xy 248.974778 -68.417913)
			(xy 248.947482 -68.369278) (xy 248.927559 -68.317187) (xy 248.915433 -68.26275) (xy 248.911362 -68.207128)
			(xy 247.434142 -68.207128) (xy 246.61368 -69.027548) (xy 246.61368 -69.562748) (xy 272.770626 -69.562748)
			(xy 272.770626 -69.508252) (xy 272.778382 -69.454311) (xy 272.793735 -69.402023) (xy 272.816373 -69.352452)
			(xy 272.845836 -69.306608) (xy 272.881523 -69.265423) (xy 272.922708 -69.229736) (xy 272.968552 -69.200273)
			(xy 273.018123 -69.177635) (xy 273.070411 -69.162282) (xy 273.124352 -69.154526) (xy 273.1516 -69.15404)
			(xy 273.180518 -69.154543) (xy 273.23769 -69.163273) (xy 273.29289 -69.180533) (xy 273.344852 -69.205928)
			(xy 273.392385 -69.238875) (xy 273.434401 -69.278619) (xy 273.45259 -69.301106) (xy 273.462487 -69.312911)
			(xy 273.487811 -69.33043) (xy 273.517204 -69.339606) (xy 273.547996 -69.339606) (xy 273.577389 -69.33043)
			(xy 273.602713 -69.312911) (xy 273.61261 -69.301106) (xy 273.629363 -69.280323) (xy 273.667717 -69.243193)
			(xy 273.710871 -69.211771) (xy 273.757985 -69.186672) (xy 273.808137 -69.168386) (xy 273.860348 -69.157269)
			(xy 273.9136 -69.153539) (xy 273.966852 -69.157269) (xy 274.019063 -69.168386) (xy 274.069215 -69.186672)
			(xy 274.116329 -69.211771) (xy 274.159483 -69.243193) (xy 274.197837 -69.280323) (xy 274.21459 -69.301106)
			(xy 274.224487 -69.312911) (xy 274.249811 -69.33043) (xy 274.279204 -69.339606) (xy 274.309996 -69.339606)
			(xy 274.339389 -69.33043) (xy 274.364713 -69.312911) (xy 274.37461 -69.301106) (xy 274.391363 -69.280323)
			(xy 274.429717 -69.243193) (xy 274.472871 -69.211771) (xy 274.519985 -69.186672) (xy 274.570137 -69.168386)
			(xy 274.622348 -69.157269) (xy 274.6756 -69.153539) (xy 274.728852 -69.157269) (xy 274.781063 -69.168386)
			(xy 274.831215 -69.186672) (xy 274.878329 -69.211771) (xy 274.921483 -69.243193) (xy 274.959837 -69.280323)
			(xy 274.97659 -69.301106) (xy 274.986487 -69.312911) (xy 275.011811 -69.33043) (xy 275.041204 -69.339606)
			(xy 275.071996 -69.339606) (xy 275.101389 -69.33043) (xy 275.126713 -69.312911) (xy 275.13661 -69.301106)
			(xy 275.153363 -69.280323) (xy 275.191717 -69.243193) (xy 275.234871 -69.211771) (xy 275.281985 -69.186672)
			(xy 275.332137 -69.168386) (xy 275.384348 -69.157269) (xy 275.4376 -69.153539) (xy 275.490852 -69.157269)
			(xy 275.543063 -69.168386) (xy 275.593215 -69.186672) (xy 275.640329 -69.211771) (xy 275.683483 -69.243193)
			(xy 275.721837 -69.280323) (xy 275.73859 -69.301106) (xy 275.748487 -69.312911) (xy 275.773811 -69.33043)
			(xy 275.803204 -69.339606) (xy 275.833996 -69.339606) (xy 275.863389 -69.33043) (xy 275.888713 -69.312911)
			(xy 275.89861 -69.301106) (xy 275.916797 -69.278619) (xy 275.958817 -69.238884) (xy 276.006353 -69.205945)
			(xy 276.058315 -69.180557) (xy 276.113514 -69.163302) (xy 276.170684 -69.154574) (xy 276.1996 -69.15404)
			(xy 276.226855 -69.15443) (xy 276.280809 -69.162187) (xy 276.333111 -69.177544) (xy 276.382694 -69.200188)
			(xy 276.42855 -69.229658) (xy 276.469746 -69.265354) (xy 276.505442 -69.30655) (xy 276.534912 -69.352406)
			(xy 276.557556 -69.401989) (xy 276.572913 -69.454291) (xy 276.58067 -69.508245) (xy 276.58067 -69.562755)
			(xy 276.572913 -69.616709) (xy 276.557556 -69.669011) (xy 276.534912 -69.718594) (xy 276.505442 -69.76445)
			(xy 276.469746 -69.805646) (xy 276.42855 -69.841342) (xy 276.382694 -69.870812) (xy 276.333111 -69.893456)
			(xy 276.280809 -69.908813) (xy 276.226855 -69.91657) (xy 276.1996 -69.917056) (xy 276.170682 -69.916554)
			(xy 276.11351 -69.907824) (xy 276.05831 -69.890564) (xy 276.006348 -69.865169) (xy 275.958814 -69.832222)
			(xy 275.916799 -69.792477) (xy 275.89861 -69.76999) (xy 275.888713 -69.758185) (xy 275.863389 -69.740666)
			(xy 275.833996 -69.73149) (xy 275.803204 -69.73149) (xy 275.773811 -69.740666) (xy 275.748487 -69.758185)
			(xy 275.73859 -69.76999) (xy 275.721837 -69.790773) (xy 275.683483 -69.827903) (xy 275.640329 -69.859325)
			(xy 275.593215 -69.884424) (xy 275.543063 -69.90271) (xy 275.490852 -69.913827) (xy 275.4376 -69.917557)
			(xy 275.384348 -69.913827) (xy 275.332137 -69.90271) (xy 275.281985 -69.884424) (xy 275.234871 -69.859325)
			(xy 275.191717 -69.827903) (xy 275.153363 -69.790773) (xy 275.13661 -69.76999) (xy 275.126713 -69.758185)
			(xy 275.101389 -69.740666) (xy 275.071996 -69.73149) (xy 275.041204 -69.73149) (xy 275.011811 -69.740666)
			(xy 274.986487 -69.758185) (xy 274.97659 -69.76999) (xy 274.959837 -69.790773) (xy 274.921483 -69.827903)
			(xy 274.878329 -69.859325) (xy 274.831215 -69.884424) (xy 274.781063 -69.90271) (xy 274.728852 -69.913827)
			(xy 274.6756 -69.917557) (xy 274.622348 -69.913827) (xy 274.570137 -69.90271) (xy 274.519985 -69.884424)
			(xy 274.472871 -69.859325) (xy 274.429717 -69.827903) (xy 274.391363 -69.790773) (xy 274.37461 -69.76999)
			(xy 274.364713 -69.758185) (xy 274.339389 -69.740666) (xy 274.309996 -69.73149) (xy 274.279204 -69.73149)
			(xy 274.249811 -69.740666) (xy 274.224487 -69.758185) (xy 274.21459 -69.76999) (xy 274.197837 -69.790773)
			(xy 274.159483 -69.827903) (xy 274.116329 -69.859325) (xy 274.069215 -69.884424) (xy 274.019063 -69.90271)
			(xy 273.966852 -69.913827) (xy 273.9136 -69.917557) (xy 273.860348 -69.913827) (xy 273.808137 -69.90271)
			(xy 273.757985 -69.884424) (xy 273.710871 -69.859325) (xy 273.667717 -69.827903) (xy 273.629363 -69.790773)
			(xy 273.61261 -69.76999) (xy 273.602713 -69.758185) (xy 273.577389 -69.740666) (xy 273.547996 -69.73149)
			(xy 273.517204 -69.73149) (xy 273.487811 -69.740666) (xy 273.462487 -69.758185) (xy 273.45259 -69.76999)
			(xy 273.434402 -69.792476) (xy 273.392382 -69.832212) (xy 273.344847 -69.865151) (xy 273.292885 -69.890539)
			(xy 273.237686 -69.907794) (xy 273.180516 -69.916522) (xy 273.1516 -69.917056) (xy 273.124352 -69.916474)
			(xy 273.070411 -69.908718) (xy 273.018123 -69.893365) (xy 272.968552 -69.870727) (xy 272.922708 -69.841264)
			(xy 272.881523 -69.805577) (xy 272.845836 -69.764392) (xy 272.816373 -69.718548) (xy 272.793735 -69.668977)
			(xy 272.778382 -69.616689) (xy 272.770626 -69.562748) (xy 246.61368 -69.562748) (xy 246.61368 -71.652384)
			(xy 247.39854 -71.652384) (xy 247.398982 -71.625711) (xy 247.406426 -71.572887) (xy 247.421154 -71.521615)
			(xy 247.442878 -71.472893) (xy 247.471175 -71.42767) (xy 247.505494 -71.386829) (xy 247.525032 -71.368666)
			(xy 247.535357 -71.35882) (xy 247.550505 -71.334654) (xy 247.558383 -71.307243) (xy 247.558378 -71.278722)
			(xy 247.550491 -71.251314) (xy 247.535335 -71.227153) (xy 247.525032 -71.217282) (xy 247.505486 -71.199126)
			(xy 247.471158 -71.15829) (xy 247.442856 -71.113068) (xy 247.421133 -71.064343) (xy 247.406413 -71.013066)
			(xy 247.398983 -70.960238) (xy 247.39854 -70.933564) (xy 247.398922 -70.906308) (xy 247.406685 -70.852352)
			(xy 247.422048 -70.800049) (xy 247.444698 -70.750466) (xy 247.474174 -70.70461) (xy 247.509876 -70.663417)
			(xy 247.551078 -70.627724) (xy 247.59694 -70.598258) (xy 247.646528 -70.575618) (xy 247.698834 -70.560267)
			(xy 247.752792 -70.552516) (xy 247.780048 -70.552056) (xy 247.806286 -70.552464) (xy 247.858265 -70.559667)
			(xy 247.908765 -70.57393) (xy 247.956831 -70.594984) (xy 248.001557 -70.622431) (xy 248.042096 -70.655752)
			(xy 248.06021 -70.674738) (xy 248.067739 -70.68211) (xy 248.087024 -70.690541) (xy 248.108072 -70.690541)
			(xy 248.127357 -70.68211) (xy 248.134886 -70.674738) (xy 248.160032 -70.649846) (xy 248.170378 -70.64002)
			(xy 248.185524 -70.615848) (xy 248.1934 -70.588432) (xy 248.193392 -70.559907) (xy 248.185499 -70.532495)
			(xy 248.170338 -70.508333) (xy 248.160032 -70.498462) (xy 248.140476 -70.480316) (xy 248.106149 -70.439478)
			(xy 248.077849 -70.394254) (xy 248.056128 -70.345527) (xy 248.04141 -70.294248) (xy 248.033982 -70.241419)
			(xy 248.03354 -70.214744) (xy 248.034026 -70.187493) (xy 248.041782 -70.133545) (xy 248.057137 -70.08125)
			(xy 248.079779 -70.031673) (xy 248.109245 -69.985823) (xy 248.144936 -69.944632) (xy 248.186127 -69.908941)
			(xy 248.231977 -69.879475) (xy 248.281554 -69.856833) (xy 248.333849 -69.841478) (xy 248.387797 -69.833722)
			(xy 248.442299 -69.833722) (xy 248.496247 -69.841478) (xy 248.548542 -69.856833) (xy 248.598119 -69.879475)
			(xy 248.643969 -69.908941) (xy 248.68516 -69.944632) (xy 248.720851 -69.985823) (xy 248.750317 -70.031673)
			(xy 248.772959 -70.08125) (xy 248.788314 -70.133545) (xy 248.79607 -70.187493) (xy 248.796556 -70.214744)
			(xy 248.796067 -70.241415) (xy 248.788632 -70.294237) (xy 248.773914 -70.345509) (xy 248.752199 -70.394231)
			(xy 248.72391 -70.439455) (xy 248.689599 -70.480298) (xy 248.670064 -70.498462) (xy 248.659811 -70.508377)
			(xy 248.644661 -70.532524) (xy 248.636774 -70.559917) (xy 248.636765 -70.588422) (xy 248.644635 -70.61582)
			(xy 248.659771 -70.639975) (xy 248.670064 -70.649846) (xy 248.689565 -70.668046) (xy 248.72388 -70.708882)
			(xy 248.752172 -70.7541) (xy 248.773889 -70.802819) (xy 248.788608 -70.854087) (xy 248.796041 -70.906906)
			(xy 248.796045 -70.960246) (xy 248.788618 -71.013066) (xy 248.773905 -71.064336) (xy 248.752194 -71.113057)
			(xy 248.723908 -71.158279) (xy 248.689599 -71.199119) (xy 248.670064 -71.217282) (xy 248.659791 -71.227178)
			(xy 248.644642 -71.25133) (xy 248.636757 -71.278728) (xy 248.636752 -71.307238) (xy 248.644627 -71.334638)
			(xy 248.659769 -71.358795) (xy 248.670064 -71.368666) (xy 248.689584 -71.386849) (xy 248.723915 -71.427679)
			(xy 248.75222 -71.472895) (xy 248.773947 -71.521615) (xy 248.788673 -71.572887) (xy 248.796109 -71.625712)
			(xy 248.796556 -71.652384) (xy 248.796094 -71.679035) (xy 248.788674 -71.731818) (xy 248.773975 -71.783053)
			(xy 248.763536 -71.807578) (xy 248.757906 -71.821707) (xy 248.754301 -71.85189) (xy 248.759721 -71.8818)
			(xy 248.773687 -71.9088) (xy 248.794967 -71.930506) (xy 248.821683 -71.945005) (xy 248.85148 -71.951017)
			(xy 248.86666 -71.950072) (xy 248.90476 -71.94804) (xy 248.932014 -71.948493) (xy 248.985968 -71.956245)
			(xy 249.038269 -71.971599) (xy 249.087852 -71.99424) (xy 249.133708 -72.023708) (xy 249.174902 -72.059404)
			(xy 249.210596 -72.100599) (xy 249.240064 -72.146455) (xy 249.262704 -72.196039) (xy 249.278056 -72.24834)
			(xy 249.285808 -72.302294) (xy 249.286268 -72.329548) (xy 249.285779 -72.356918) (xy 249.277968 -72.411096)
			(xy 249.262485 -72.463599) (xy 249.239648 -72.513346) (xy 249.209927 -72.559314) (xy 249.192288 -72.580246)
			(xy 249.183006 -72.591539) (xy 249.170836 -72.61811) (xy 249.166673 -72.647036) (xy 249.170856 -72.67596)
			(xy 249.183045 -72.702522) (xy 249.192288 -72.71385) (xy 249.209975 -72.734745) (xy 249.239697 -72.78072)
			(xy 249.262538 -72.830472) (xy 249.27803 -72.88298) (xy 249.285854 -72.937163) (xy 249.285849 -72.991909)
			(xy 249.278015 -73.046091) (xy 249.262513 -73.098596) (xy 249.239662 -73.148344) (xy 249.209931 -73.194313)
			(xy 249.192288 -73.215246) (xy 249.183006 -73.226539) (xy 249.170836 -73.25311) (xy 249.166673 -73.282036)
			(xy 249.170856 -73.31096) (xy 249.183045 -73.337522) (xy 249.192288 -73.34885) (xy 249.209975 -73.369745)
			(xy 249.239697 -73.41572) (xy 249.262538 -73.465472) (xy 249.27803 -73.51798) (xy 249.285854 -73.572163)
			(xy 249.28585 -73.620122) (xy 252.28245 -73.620122) (xy 252.286523 -73.564463) (xy 252.298658 -73.50999)
			(xy 252.318594 -73.457864) (xy 252.345908 -73.409196) (xy 252.380016 -73.365024) (xy 252.420193 -73.326289)
			(xy 252.465581 -73.293817) (xy 252.515213 -73.268299) (xy 252.568033 -73.25028) (xy 252.622912 -73.240143)
			(xy 252.678683 -73.238105) (xy 252.734157 -73.244208) (xy 252.78815 -73.258324) (xy 252.839513 -73.280151)
			(xy 252.887151 -73.309224) (xy 252.930047 -73.344923) (xy 252.967289 -73.386487) (xy 252.998083 -73.433031)
			(xy 253.021771 -73.483562) (xy 253.037201 -73.53485) (xy 272.927578 -73.53485) (xy 272.927578 -73.48035)
			(xy 272.935333 -73.426405) (xy 272.950687 -73.374112) (xy 272.973326 -73.324537) (xy 273.00279 -73.278688)
			(xy 273.038478 -73.237498) (xy 273.079665 -73.201807) (xy 273.125512 -73.17234) (xy 273.175086 -73.149697)
			(xy 273.227377 -73.134339) (xy 273.281322 -73.12658) (xy 273.308572 -73.126092) (xy 273.33749 -73.126595)
			(xy 273.394663 -73.135323) (xy 273.449864 -73.152581) (xy 273.501827 -73.177975) (xy 273.54936 -73.210923)
			(xy 273.591374 -73.25067) (xy 273.609562 -73.273158) (xy 273.619459 -73.284963) (xy 273.644783 -73.302482)
			(xy 273.674176 -73.311658) (xy 273.704968 -73.311658) (xy 273.734361 -73.302482) (xy 273.759685 -73.284963)
			(xy 273.769582 -73.273158) (xy 273.786335 -73.252375) (xy 273.824689 -73.215245) (xy 273.867843 -73.183823)
			(xy 273.914957 -73.158724) (xy 273.965109 -73.140438) (xy 274.01732 -73.129321) (xy 274.070572 -73.125591)
			(xy 274.123824 -73.129321) (xy 274.176035 -73.140438) (xy 274.226187 -73.158724) (xy 274.273301 -73.183823)
			(xy 274.316455 -73.215245) (xy 274.354809 -73.252375) (xy 274.371562 -73.273158) (xy 274.381459 -73.284963)
			(xy 274.406783 -73.302482) (xy 274.436176 -73.311658) (xy 274.466968 -73.311658) (xy 274.496361 -73.302482)
			(xy 274.521685 -73.284963) (xy 274.531582 -73.273158) (xy 274.548335 -73.252375) (xy 274.586689 -73.215245)
			(xy 274.629843 -73.183823) (xy 274.676957 -73.158724) (xy 274.727109 -73.140438) (xy 274.77932 -73.129321)
			(xy 274.832572 -73.125591) (xy 274.885824 -73.129321) (xy 274.938035 -73.140438) (xy 274.988187 -73.158724)
			(xy 275.035301 -73.183823) (xy 275.078455 -73.215245) (xy 275.116809 -73.252375) (xy 275.133562 -73.273158)
			(xy 275.143459 -73.284963) (xy 275.168783 -73.302482) (xy 275.198176 -73.311658) (xy 275.228968 -73.311658)
			(xy 275.258361 -73.302482) (xy 275.283685 -73.284963) (xy 275.293582 -73.273158) (xy 275.310335 -73.252375)
			(xy 275.348689 -73.215245) (xy 275.391843 -73.183823) (xy 275.438957 -73.158724) (xy 275.489109 -73.140438)
			(xy 275.54132 -73.129321) (xy 275.594572 -73.125591) (xy 275.647824 -73.129321) (xy 275.700035 -73.140438)
			(xy 275.750187 -73.158724) (xy 275.797301 -73.183823) (xy 275.840455 -73.215245) (xy 275.878809 -73.252375)
			(xy 275.895562 -73.273158) (xy 275.905459 -73.284963) (xy 275.930783 -73.302482) (xy 275.960176 -73.311658)
			(xy 275.990968 -73.311658) (xy 276.020361 -73.302482) (xy 276.045685 -73.284963) (xy 276.055582 -73.273158)
			(xy 276.073773 -73.250674) (xy 276.115794 -73.210941) (xy 276.163329 -73.178003) (xy 276.21529 -73.152615)
			(xy 276.270487 -73.135359) (xy 276.327656 -73.126628) (xy 276.356572 -73.126092) (xy 276.383826 -73.126553)
			(xy 276.43778 -73.134307) (xy 276.490081 -73.149661) (xy 276.539665 -73.172302) (xy 276.585522 -73.201769)
			(xy 276.626718 -73.237463) (xy 276.662414 -73.278656) (xy 276.691885 -73.32451) (xy 276.714529 -73.374092)
			(xy 276.729887 -73.426392) (xy 276.737645 -73.480346) (xy 276.737645 -73.534854) (xy 276.729887 -73.588808)
			(xy 276.714529 -73.641108) (xy 276.691885 -73.69069) (xy 276.662414 -73.736544) (xy 276.626718 -73.777737)
			(xy 276.585522 -73.813431) (xy 276.539665 -73.842898) (xy 276.490081 -73.865539) (xy 276.43778 -73.880893)
			(xy 276.383826 -73.888647) (xy 276.356572 -73.889108) (xy 276.327655 -73.888573) (xy 276.270483 -73.879852)
			(xy 276.215283 -73.8626) (xy 276.163321 -73.837212) (xy 276.115787 -73.804269) (xy 276.073771 -73.764528)
			(xy 276.055582 -73.742042) (xy 276.045685 -73.730237) (xy 276.020361 -73.712718) (xy 275.990968 -73.703542)
			(xy 275.960176 -73.703542) (xy 275.930783 -73.712718) (xy 275.905459 -73.730237) (xy 275.895562 -73.742042)
			(xy 275.878809 -73.762825) (xy 275.840455 -73.799955) (xy 275.797301 -73.831377) (xy 275.750187 -73.856476)
			(xy 275.700035 -73.874762) (xy 275.647824 -73.885879) (xy 275.594572 -73.889609) (xy 275.54132 -73.885879)
			(xy 275.489109 -73.874762) (xy 275.438957 -73.856476) (xy 275.391843 -73.831377) (xy 275.348689 -73.799955)
			(xy 275.310335 -73.762825) (xy 275.293582 -73.742042) (xy 275.283685 -73.730237) (xy 275.258361 -73.712718)
			(xy 275.228968 -73.703542) (xy 275.198176 -73.703542) (xy 275.168783 -73.712718) (xy 275.143459 -73.730237)
			(xy 275.133562 -73.742042) (xy 275.116809 -73.762825) (xy 275.078455 -73.799955) (xy 275.035301 -73.831377)
			(xy 274.988187 -73.856476) (xy 274.938035 -73.874762) (xy 274.885824 -73.885879) (xy 274.832572 -73.889609)
			(xy 274.77932 -73.885879) (xy 274.727109 -73.874762) (xy 274.676957 -73.856476) (xy 274.629843 -73.831377)
			(xy 274.586689 -73.799955) (xy 274.548335 -73.762825) (xy 274.531582 -73.742042) (xy 274.521685 -73.730237)
			(xy 274.496361 -73.712718) (xy 274.466968 -73.703542) (xy 274.436176 -73.703542) (xy 274.406783 -73.712718)
			(xy 274.381459 -73.730237) (xy 274.371562 -73.742042) (xy 274.354809 -73.762825) (xy 274.316455 -73.799955)
			(xy 274.273301 -73.831377) (xy 274.226187 -73.856476) (xy 274.176035 -73.874762) (xy 274.123824 -73.885879)
			(xy 274.070572 -73.889609) (xy 274.01732 -73.885879) (xy 273.965109 -73.874762) (xy 273.914957 -73.856476)
			(xy 273.867843 -73.831377) (xy 273.824689 -73.799955) (xy 273.786335 -73.762825) (xy 273.769582 -73.742042)
			(xy 273.759685 -73.730237) (xy 273.734361 -73.712718) (xy 273.704968 -73.703542) (xy 273.674176 -73.703542)
			(xy 273.644783 -73.712718) (xy 273.619459 -73.730237) (xy 273.609562 -73.742042) (xy 273.591403 -73.764552)
			(xy 273.549375 -73.804284) (xy 273.501833 -73.837219) (xy 273.449866 -73.862602) (xy 273.394663 -73.879853)
			(xy 273.33749 -73.888576) (xy 273.308572 -73.889108) (xy 273.281322 -73.88862) (xy 273.227377 -73.880861)
			(xy 273.175086 -73.865503) (xy 273.125512 -73.84286) (xy 273.079665 -73.813393) (xy 273.038478 -73.777702)
			(xy 273.00279 -73.736512) (xy 272.973326 -73.690663) (xy 272.950687 -73.641088) (xy 272.935333 -73.588795)
			(xy 272.927578 -73.53485) (xy 253.037201 -73.53485) (xy 253.037849 -73.537004) (xy 253.045975 -73.592218)
			(xy 253.046484 -73.620122) (xy 253.045975 -73.648026) (xy 253.037849 -73.70324) (xy 253.021771 -73.756682)
			(xy 252.998083 -73.807213) (xy 252.967289 -73.853757) (xy 252.930047 -73.895321) (xy 252.887151 -73.93102)
			(xy 252.839513 -73.960093) (xy 252.78815 -73.98192) (xy 252.734157 -73.996036) (xy 252.678683 -74.002139)
			(xy 252.622912 -74.000101) (xy 252.568033 -73.989964) (xy 252.515213 -73.971945) (xy 252.465581 -73.946427)
			(xy 252.420193 -73.913955) (xy 252.380016 -73.87522) (xy 252.345908 -73.831048) (xy 252.318594 -73.78238)
			(xy 252.298658 -73.730254) (xy 252.286523 -73.675781) (xy 252.28245 -73.620122) (xy 249.28585 -73.620122)
			(xy 249.285849 -73.626909) (xy 249.278015 -73.681091) (xy 249.262513 -73.733596) (xy 249.239662 -73.783344)
			(xy 249.209931 -73.829313) (xy 249.192288 -73.850246) (xy 249.183006 -73.861539) (xy 249.170836 -73.88811)
			(xy 249.166673 -73.917036) (xy 249.170856 -73.94596) (xy 249.183045 -73.972522) (xy 249.192288 -73.98385)
			(xy 249.209915 -74.004792) (xy 249.239629 -74.050762) (xy 249.261619 -74.098658) (xy 260.18693 -74.098658)
			(xy 260.191001 -74.043036) (xy 260.203127 -73.988599) (xy 260.22305 -73.936508) (xy 260.250346 -73.887873)
			(xy 260.284432 -73.84373) (xy 260.324581 -73.805021) (xy 260.369939 -73.77257) (xy 260.419539 -73.747069)
			(xy 260.472323 -73.729062) (xy 260.527166 -73.718932) (xy 260.5829 -73.716895) (xy 260.638337 -73.722995)
			(xy 260.692294 -73.737101) (xy 260.743623 -73.758913) (xy 260.791229 -73.787967) (xy 260.834097 -73.823642)
			(xy 260.871314 -73.865179) (xy 260.902087 -73.911692) (xy 260.925759 -73.962189) (xy 260.932964 -73.986136)
			(xy 261.8265 -73.986136) (xy 261.830571 -73.930514) (xy 261.842697 -73.876077) (xy 261.86262 -73.823986)
			(xy 261.889916 -73.775351) (xy 261.924002 -73.731208) (xy 261.964151 -73.692499) (xy 262.009509 -73.660048)
			(xy 262.059109 -73.634547) (xy 262.111893 -73.61654) (xy 262.166736 -73.60641) (xy 262.22247 -73.604373)
			(xy 262.277907 -73.610473) (xy 262.331864 -73.624579) (xy 262.383193 -73.646391) (xy 262.430799 -73.675445)
			(xy 262.473667 -73.71112) (xy 262.510884 -73.752657) (xy 262.541657 -73.79917) (xy 262.565329 -73.849667)
			(xy 262.581397 -73.903074) (xy 262.589517 -73.95825) (xy 262.590026 -73.986136) (xy 262.589517 -74.014022)
			(xy 262.581397 -74.069198) (xy 262.565329 -74.122605) (xy 262.541657 -74.173102) (xy 262.510884 -74.219615)
			(xy 262.473667 -74.261152) (xy 262.430799 -74.296827) (xy 262.383193 -74.325881) (xy 262.331864 -74.347693)
			(xy 262.277907 -74.361799) (xy 262.22247 -74.367899) (xy 262.166736 -74.365862) (xy 262.111893 -74.355732)
			(xy 262.059109 -74.337725) (xy 262.009509 -74.312224) (xy 261.964151 -74.279773) (xy 261.924002 -74.241064)
			(xy 261.889916 -74.196921) (xy 261.86262 -74.148286) (xy 261.842697 -74.096195) (xy 261.830571 -74.041758)
			(xy 261.8265 -73.986136) (xy 260.932964 -73.986136) (xy 260.941827 -74.015596) (xy 260.949947 -74.070772)
			(xy 260.950456 -74.098658) (xy 260.949947 -74.126544) (xy 260.941827 -74.18172) (xy 260.925759 -74.235127)
			(xy 260.902087 -74.285624) (xy 260.871314 -74.332137) (xy 260.834097 -74.373674) (xy 260.791229 -74.409349)
			(xy 260.743623 -74.438403) (xy 260.692294 -74.460215) (xy 260.638337 -74.474321) (xy 260.5829 -74.480421)
			(xy 260.527166 -74.478384) (xy 260.472323 -74.468254) (xy 260.419539 -74.450247) (xy 260.369939 -74.424746)
			(xy 260.324581 -74.392295) (xy 260.284432 -74.353586) (xy 260.250346 -74.309443) (xy 260.22305 -74.260808)
			(xy 260.203127 -74.208717) (xy 260.191001 -74.15428) (xy 260.18693 -74.098658) (xy 249.261619 -74.098658)
			(xy 249.262468 -74.100507) (xy 249.277961 -74.153005) (xy 249.285793 -74.207179) (xy 249.286268 -74.234548)
			(xy 249.285867 -74.261802) (xy 249.278103 -74.315755) (xy 249.262739 -74.368054) (xy 249.24009 -74.417634)
			(xy 249.210615 -74.463486) (xy 249.174914 -74.504677) (xy 249.133715 -74.540368) (xy 249.087857 -74.569832)
			(xy 249.038271 -74.59247) (xy 248.985969 -74.607821) (xy 248.932014 -74.615573) (xy 248.90476 -74.616056)
			(xy 248.893495 -74.616003) (xy 248.871001 -74.614732) (xy 248.859802 -74.613516) (xy 248.846201 -74.612398)
			(xy 248.819238 -74.616521) (xy 248.79433 -74.627641) (xy 248.773259 -74.644963) (xy 248.757532 -74.667249)
			(xy 248.748272 -74.692906) (xy 248.746141 -74.7201) (xy 248.751293 -74.746886) (xy 248.752552 -74.74966)
			(xy 258.981954 -74.74966) (xy 258.986025 -74.694038) (xy 258.998151 -74.639601) (xy 259.018074 -74.58751)
			(xy 259.04537 -74.538875) (xy 259.079456 -74.494732) (xy 259.119605 -74.456023) (xy 259.164963 -74.423572)
			(xy 259.214563 -74.398071) (xy 259.267347 -74.380064) (xy 259.32219 -74.369934) (xy 259.377924 -74.367897)
			(xy 259.433361 -74.373997) (xy 259.487318 -74.388103) (xy 259.538647 -74.409915) (xy 259.586253 -74.438969)
			(xy 259.629121 -74.474644) (xy 259.666338 -74.516181) (xy 259.697111 -74.562694) (xy 259.720783 -74.613191)
			(xy 259.736851 -74.666598) (xy 259.744971 -74.721774) (xy 259.74548 -74.74966) (xy 259.744971 -74.777546)
			(xy 259.736851 -74.832722) (xy 259.720783 -74.886129) (xy 259.697111 -74.936626) (xy 259.666338 -74.983139)
			(xy 259.629121 -75.024676) (xy 259.586253 -75.060351) (xy 259.538647 -75.089405) (xy 259.487318 -75.111217)
			(xy 259.433361 -75.125323) (xy 259.377924 -75.131423) (xy 259.32219 -75.129386) (xy 259.267347 -75.119256)
			(xy 259.214563 -75.101249) (xy 259.164963 -75.075748) (xy 259.119605 -75.043297) (xy 259.079456 -75.004588)
			(xy 259.04537 -74.960445) (xy 259.018074 -74.91181) (xy 258.998151 -74.859719) (xy 258.986025 -74.805282)
			(xy 258.981954 -74.74966) (xy 248.752552 -74.74966) (xy 248.756932 -74.759312) (xy 248.769388 -74.785711)
			(xy 248.787005 -74.841359) (xy 248.795961 -74.899038) (xy 248.796556 -74.928222) (xy 248.796556 -74.928984)
			(xy 248.796007 -74.956233) (xy 248.788254 -75.010176) (xy 248.772903 -75.062466) (xy 248.750268 -75.11204)
			(xy 248.720807 -75.157888) (xy 248.685123 -75.199077) (xy 248.643939 -75.234769) (xy 248.598096 -75.264237)
			(xy 248.548526 -75.286881) (xy 248.496238 -75.30224) (xy 248.442297 -75.310002) (xy 248.415048 -75.310492)
			(xy 248.387679 -75.31) (xy 248.333501 -75.302189) (xy 248.280998 -75.286706) (xy 248.23125 -75.26387)
			(xy 248.185283 -75.234151) (xy 248.16435 -75.216512) (xy 248.153022 -75.207276) (xy 248.126465 -75.1951)
			(xy 248.097548 -75.190927) (xy 248.068631 -75.1951) (xy 248.042074 -75.207276) (xy 248.030746 -75.216512)
			(xy 248.009809 -75.234145) (xy 247.963837 -75.263857) (xy 247.914091 -75.286694) (xy 247.861592 -75.302187)
			(xy 247.807417 -75.310017) (xy 247.780048 -75.310492) (xy 247.752792 -75.310064) (xy 247.698833 -75.302313)
			(xy 247.646527 -75.28696) (xy 247.596939 -75.264319) (xy 247.551078 -75.234851) (xy 247.509878 -75.199156)
			(xy 247.474177 -75.15796) (xy 247.444704 -75.112103) (xy 247.422057 -75.062518) (xy 247.406698 -75.010214)
			(xy 247.398939 -74.956256) (xy 247.398939 -74.901744) (xy 247.406698 -74.847786) (xy 247.422057 -74.795482)
			(xy 247.444704 -74.745897) (xy 247.474177 -74.70004) (xy 247.509878 -74.658844) (xy 247.551078 -74.623149)
			(xy 247.596939 -74.593681) (xy 247.646527 -74.57104) (xy 247.698833 -74.555687) (xy 247.752792 -74.547936)
			(xy 247.780048 -74.547476) (xy 247.807418 -74.547954) (xy 247.861597 -74.555766) (xy 247.914101 -74.571251)
			(xy 247.963848 -74.594091) (xy 248.009815 -74.623815) (xy 248.030746 -74.641456) (xy 248.042074 -74.650692)
			(xy 248.068631 -74.662868) (xy 248.097548 -74.667041) (xy 248.126465 -74.662868) (xy 248.153022 -74.650692)
			(xy 248.16435 -74.641456) (xy 248.185284 -74.62382) (xy 248.231257 -74.594109) (xy 248.281004 -74.571273)
			(xy 248.333504 -74.555781) (xy 248.387679 -74.547951) (xy 248.415048 -74.547476) (xy 248.426313 -74.547528)
			(xy 248.448807 -74.5488) (xy 248.460006 -74.550016) (xy 248.473603 -74.551239) (xy 248.500583 -74.547112)
			(xy 248.525505 -74.535982) (xy 248.546585 -74.518644) (xy 248.562316 -74.496339) (xy 248.571573 -74.470663)
			(xy 248.573693 -74.443451) (xy 248.568525 -74.416651) (xy 248.562876 -74.40422) (xy 248.550432 -74.377816)
			(xy 248.532811 -74.32217) (xy 248.52385 -74.264494) (xy 248.523252 -74.23531) (xy 248.523252 -74.234548)
			(xy 248.523734 -74.207178) (xy 248.531546 -74.152999) (xy 248.54703 -74.100496) (xy 248.569869 -74.050749)
			(xy 248.599591 -74.004782) (xy 248.617232 -73.98385) (xy 248.62642 -73.972487) (xy 248.638599 -73.945942)
			(xy 248.642779 -73.917036) (xy 248.63862 -73.888128) (xy 248.62646 -73.861574) (xy 248.617232 -73.850246)
			(xy 248.599638 -73.829275) (xy 248.569911 -73.783314) (xy 248.547063 -73.733574) (xy 248.531562 -73.681078)
			(xy 248.523729 -73.626905) (xy 248.523724 -73.572168) (xy 248.531547 -73.517993) (xy 248.547037 -73.465494)
			(xy 248.569876 -73.415749) (xy 248.599595 -73.369783) (xy 248.617232 -73.34885) (xy 248.62642 -73.337487)
			(xy 248.638599 -73.310942) (xy 248.642779 -73.282036) (xy 248.63862 -73.253128) (xy 248.62646 -73.226574)
			(xy 248.617232 -73.215246) (xy 248.599638 -73.194275) (xy 248.569911 -73.148314) (xy 248.547063 -73.098574)
			(xy 248.531562 -73.046078) (xy 248.523729 -72.991905) (xy 248.523724 -72.937168) (xy 248.531547 -72.882993)
			(xy 248.547037 -72.830494) (xy 248.569876 -72.780749) (xy 248.599595 -72.734783) (xy 248.617232 -72.71385)
			(xy 248.62642 -72.702487) (xy 248.638599 -72.675942) (xy 248.642779 -72.647036) (xy 248.63862 -72.618128)
			(xy 248.62646 -72.591574) (xy 248.617232 -72.580246) (xy 248.599606 -72.559303) (xy 248.569891 -72.513334)
			(xy 248.547052 -72.463589) (xy 248.531558 -72.411091) (xy 248.523727 -72.356917) (xy 248.523252 -72.329548)
			(xy 248.52369 -72.302896) (xy 248.53112 -72.250113) (xy 248.545828 -72.198878) (xy 248.556272 -72.174354)
			(xy 248.561856 -72.160208) (xy 248.565466 -72.130032) (xy 248.560054 -72.100128) (xy 248.546096 -72.073132)
			(xy 248.524823 -72.051428) (xy 248.498114 -72.036929) (xy 248.468324 -72.030916) (xy 248.453148 -72.03186)
			(xy 248.415048 -72.033892) (xy 248.387679 -72.0334) (xy 248.333501 -72.025589) (xy 248.280998 -72.010106)
			(xy 248.23125 -71.98727) (xy 248.185283 -71.957551) (xy 248.16435 -71.939912) (xy 248.153022 -71.930676)
			(xy 248.126465 -71.9185) (xy 248.097548 -71.914327) (xy 248.068631 -71.9185) (xy 248.042074 -71.930676)
			(xy 248.030746 -71.939912) (xy 248.009809 -71.957545) (xy 247.963837 -71.987257) (xy 247.914091 -72.010094)
			(xy 247.861592 -72.025587) (xy 247.807417 -72.033417) (xy 247.780048 -72.033892) (xy 247.752796 -72.0334)
			(xy 247.698845 -72.025649) (xy 247.646547 -72.010298) (xy 247.596966 -71.98766) (xy 247.551111 -71.958196)
			(xy 247.509918 -71.922505) (xy 247.474223 -71.881314) (xy 247.444755 -71.835463) (xy 247.422113 -71.785883)
			(xy 247.406758 -71.733586) (xy 247.399002 -71.679636) (xy 247.39854 -71.652384) (xy 246.61368 -71.652384)
			(xy 246.61368 -75.377548) (xy 247.042288 -75.806156) (xy 274.987923 -75.806156) (xy 274.987923 -75.751644)
			(xy 274.995681 -75.697687) (xy 275.011039 -75.645383) (xy 275.033685 -75.595797) (xy 275.063158 -75.549939)
			(xy 275.098857 -75.508742) (xy 275.140055 -75.473046) (xy 275.185915 -75.443576) (xy 275.235502 -75.420932)
			(xy 275.287806 -75.405577) (xy 275.341764 -75.397822) (xy 275.36902 -75.39736) (xy 275.396391 -75.3978)
			(xy 275.450572 -75.405622) (xy 275.503076 -75.421116) (xy 275.552823 -75.443964) (xy 275.598788 -75.473695)
			(xy 275.619718 -75.49134) (xy 275.631046 -75.500576) (xy 275.657603 -75.512752) (xy 275.68652 -75.516925)
			(xy 275.715437 -75.512752) (xy 275.741994 -75.500576) (xy 275.753322 -75.49134) (xy 275.774255 -75.473699)
			(xy 275.820223 -75.443975) (xy 275.869969 -75.421129) (xy 275.922471 -75.405633) (xy 275.976649 -75.397804)
			(xy 276.031391 -75.397804) (xy 276.085569 -75.405633) (xy 276.138071 -75.421129) (xy 276.187817 -75.443975)
			(xy 276.233785 -75.473699) (xy 276.254718 -75.49134) (xy 276.266046 -75.500576) (xy 276.292603 -75.512752)
			(xy 276.32152 -75.516925) (xy 276.350437 -75.512752) (xy 276.376994 -75.500576) (xy 276.388322 -75.49134)
			(xy 276.409255 -75.473699) (xy 276.455223 -75.443975) (xy 276.504969 -75.421129) (xy 276.557471 -75.405633)
			(xy 276.611649 -75.397804) (xy 276.666391 -75.397804) (xy 276.720569 -75.405633) (xy 276.773071 -75.421129)
			(xy 276.822817 -75.443975) (xy 276.868785 -75.473699) (xy 276.889718 -75.49134) (xy 276.901046 -75.500576)
			(xy 276.927603 -75.512752) (xy 276.95652 -75.516925) (xy 276.985437 -75.512752) (xy 277.011994 -75.500576)
			(xy 277.023322 -75.49134) (xy 277.044255 -75.473699) (xy 277.090223 -75.443975) (xy 277.139969 -75.421129)
			(xy 277.192471 -75.405633) (xy 277.246649 -75.397804) (xy 277.301391 -75.397804) (xy 277.355569 -75.405633)
			(xy 277.408071 -75.421129) (xy 277.457817 -75.443975) (xy 277.503785 -75.473699) (xy 277.524718 -75.49134)
			(xy 277.536046 -75.500576) (xy 277.562603 -75.512752) (xy 277.59152 -75.516925) (xy 277.620437 -75.512752)
			(xy 277.646994 -75.500576) (xy 277.658322 -75.49134) (xy 277.679278 -75.47373) (xy 277.725243 -75.444013)
			(xy 277.774985 -75.42117) (xy 277.827481 -75.405673) (xy 277.881652 -75.397837) (xy 277.90902 -75.39736)
			(xy 277.936268 -75.397912) (xy 277.990209 -75.40567) (xy 278.042497 -75.421025) (xy 278.092067 -75.443666)
			(xy 278.137911 -75.47313) (xy 278.179096 -75.508818) (xy 278.214782 -75.550005) (xy 278.244244 -75.59585)
			(xy 278.266882 -75.645422) (xy 278.282235 -75.697711) (xy 278.28999 -75.751652) (xy 278.28999 -75.806148)
			(xy 278.282235 -75.860089) (xy 278.266882 -75.912378) (xy 278.244244 -75.96195) (xy 278.214782 -76.007795)
			(xy 278.179096 -76.048982) (xy 278.137911 -76.08467) (xy 278.092067 -76.114134) (xy 278.042497 -76.136775)
			(xy 277.990209 -76.15213) (xy 277.936268 -76.159888) (xy 277.90902 -76.160376) (xy 277.88165 -76.159904)
			(xy 277.827471 -76.152089) (xy 277.774968 -76.136601) (xy 277.725221 -76.113761) (xy 277.679254 -76.084037)
			(xy 277.658322 -76.066396) (xy 277.646994 -76.05716) (xy 277.620437 -76.044984) (xy 277.59152 -76.040811)
			(xy 277.562603 -76.044984) (xy 277.536046 -76.05716) (xy 277.524718 -76.066396) (xy 277.503785 -76.084037)
			(xy 277.457817 -76.113761) (xy 277.408071 -76.136607) (xy 277.355569 -76.152103) (xy 277.301391 -76.159932)
			(xy 277.246649 -76.159932) (xy 277.192471 -76.152103) (xy 277.139969 -76.136607) (xy 277.090223 -76.113761)
			(xy 277.044255 -76.084037) (xy 277.023322 -76.066396) (xy 277.011994 -76.05716) (xy 276.985437 -76.044984)
			(xy 276.95652 -76.040811) (xy 276.927603 -76.044984) (xy 276.901046 -76.05716) (xy 276.889718 -76.066396)
			(xy 276.868785 -76.084037) (xy 276.822817 -76.113761) (xy 276.773071 -76.136607) (xy 276.720569 -76.152103)
			(xy 276.666391 -76.159932) (xy 276.611649 -76.159932) (xy 276.557471 -76.152103) (xy 276.504969 -76.136607)
			(xy 276.455223 -76.113761) (xy 276.409255 -76.084037) (xy 276.388322 -76.066396) (xy 276.376994 -76.05716)
			(xy 276.350437 -76.044984) (xy 276.32152 -76.040811) (xy 276.292603 -76.044984) (xy 276.266046 -76.05716)
			(xy 276.254718 -76.066396) (xy 276.233785 -76.084037) (xy 276.187817 -76.113761) (xy 276.138071 -76.136607)
			(xy 276.085569 -76.152103) (xy 276.031391 -76.159932) (xy 275.976649 -76.159932) (xy 275.922471 -76.152103)
			(xy 275.869969 -76.136607) (xy 275.820223 -76.113761) (xy 275.774255 -76.084037) (xy 275.753322 -76.066396)
			(xy 275.741994 -76.05716) (xy 275.715437 -76.044984) (xy 275.68652 -76.040811) (xy 275.657603 -76.044984)
			(xy 275.631046 -76.05716) (xy 275.619718 -76.066396) (xy 275.598789 -76.084039) (xy 275.552816 -76.113751)
			(xy 275.503067 -76.136586) (xy 275.450566 -76.152076) (xy 275.396389 -76.159903) (xy 275.36902 -76.160376)
			(xy 275.341764 -76.159978) (xy 275.287806 -76.152223) (xy 275.235502 -76.136868) (xy 275.185915 -76.114224)
			(xy 275.140055 -76.084754) (xy 275.098857 -76.049058) (xy 275.063158 -76.007861) (xy 275.033685 -75.962003)
			(xy 275.011039 -75.912417) (xy 274.995681 -75.860113) (xy 274.987923 -75.806156) (xy 247.042288 -75.806156)
			(xy 248.16308 -76.926948) (xy 257.560062 -76.926948) (xy 257.564133 -76.871326) (xy 257.576259 -76.816889)
			(xy 257.596182 -76.764798) (xy 257.623478 -76.716163) (xy 257.657564 -76.67202) (xy 257.697713 -76.633311)
			(xy 257.743071 -76.60086) (xy 257.792671 -76.575359) (xy 257.845455 -76.557352) (xy 257.900298 -76.547222)
			(xy 257.956032 -76.545185) (xy 258.011469 -76.551285) (xy 258.065426 -76.565391) (xy 258.116755 -76.587203)
			(xy 258.164361 -76.616257) (xy 258.207229 -76.651932) (xy 258.244446 -76.693469) (xy 258.275219 -76.739982)
			(xy 258.298891 -76.790479) (xy 258.314959 -76.843886) (xy 258.323079 -76.899062) (xy 258.323588 -76.926948)
			(xy 258.323079 -76.954834) (xy 258.314959 -77.01001) (xy 258.298891 -77.063417) (xy 258.275219 -77.113914)
			(xy 258.244446 -77.160427) (xy 258.207229 -77.201964) (xy 258.164361 -77.237639) (xy 258.116755 -77.266693)
			(xy 258.065426 -77.288505) (xy 258.011469 -77.302611) (xy 257.956032 -77.308711) (xy 257.900298 -77.306674)
			(xy 257.845455 -77.296544) (xy 257.792671 -77.278537) (xy 257.743071 -77.253036) (xy 257.697713 -77.220585)
			(xy 257.657564 -77.181876) (xy 257.623478 -77.137733) (xy 257.596182 -77.089098) (xy 257.576259 -77.037007)
			(xy 257.564133 -76.98257) (xy 257.560062 -76.926948) (xy 248.16308 -76.926948) (xy 249.313954 -78.077822)
			(xy 262.833104 -78.077822) (xy 262.833509 -78.051441) (xy 262.840772 -77.999182) (xy 262.855163 -77.948421)
			(xy 262.876408 -77.900125) (xy 262.904101 -77.855216) (xy 262.937715 -77.814548) (xy 262.97661 -77.778897)
			(xy 263.020043 -77.748942) (xy 263.043416 -77.7367) (xy 263.05576 -77.72997) (xy 263.076497 -77.711003)
			(xy 263.091265 -77.687094) (xy 263.098943 -77.660061) (xy 263.098945 -77.631959) (xy 263.091273 -77.604924)
			(xy 263.076509 -77.581012) (xy 263.055777 -77.562042) (xy 263.043416 -77.555344) (xy 263.020059 -77.543078)
			(xy 262.976634 -77.513121) (xy 262.937747 -77.477469) (xy 262.90414 -77.436803) (xy 262.876451 -77.391898)
			(xy 262.855209 -77.343608) (xy 262.840817 -77.292853) (xy 262.833551 -77.2406) (xy 262.833104 -77.214222)
			(xy 262.83359 -77.186971) (xy 262.841346 -77.133023) (xy 262.856701 -77.080728) (xy 262.879343 -77.031151)
			(xy 262.908809 -76.985301) (xy 262.9445 -76.94411) (xy 262.985691 -76.908419) (xy 263.031541 -76.878953)
			(xy 263.081118 -76.856311) (xy 263.133413 -76.840956) (xy 263.187361 -76.8332) (xy 263.241863 -76.8332)
			(xy 263.295811 -76.840956) (xy 263.348106 -76.856311) (xy 263.397683 -76.878953) (xy 263.443533 -76.908419)
			(xy 263.484724 -76.94411) (xy 263.520415 -76.985301) (xy 263.549881 -77.031151) (xy 263.572523 -77.080728)
			(xy 263.587878 -77.133023) (xy 263.595634 -77.186971) (xy 263.59612 -77.214222) (xy 263.595656 -77.240601)
			(xy 263.588401 -77.292857) (xy 263.574018 -77.343616) (xy 263.552782 -77.39191) (xy 263.525097 -77.43682)
			(xy 263.491491 -77.477489) (xy 263.452604 -77.513142) (xy 263.409177 -77.5431) (xy 263.385808 -77.555344)
			(xy 263.373433 -77.562015) (xy 263.352707 -77.580998) (xy 263.337949 -77.604918) (xy 263.330281 -77.631957)
			(xy 263.330283 -77.660063) (xy 263.337957 -77.6871) (xy 263.352719 -77.711017) (xy 263.373449 -77.729996)
			(xy 263.385808 -77.7367) (xy 263.409189 -77.748922) (xy 263.452614 -77.778887) (xy 263.491499 -77.814545)
			(xy 263.525104 -77.855217) (xy 263.55279 -77.900129) (xy 263.574029 -77.948425) (xy 263.588415 -77.999185)
			(xy 263.595676 -78.051442) (xy 263.59612 -78.077822) (xy 263.595634 -78.105073) (xy 263.587878 -78.159021)
			(xy 263.572523 -78.211316) (xy 263.549881 -78.260893) (xy 263.520415 -78.306743) (xy 263.484724 -78.347934)
			(xy 263.443533 -78.383625) (xy 263.397683 -78.413091) (xy 263.348106 -78.435733) (xy 263.295811 -78.451088)
			(xy 263.241863 -78.458844) (xy 263.187361 -78.458844) (xy 263.133413 -78.451088) (xy 263.081118 -78.435733)
			(xy 263.031541 -78.413091) (xy 262.985691 -78.383625) (xy 262.9445 -78.347934) (xy 262.908809 -78.306743)
			(xy 262.879343 -78.260893) (xy 262.856701 -78.211316) (xy 262.841346 -78.159021) (xy 262.83359 -78.105073)
			(xy 262.833104 -78.077822) (xy 249.313954 -78.077822) (xy 250.21413 -78.977998) (xy 258.880862 -78.977998)
			(xy 258.884933 -78.922376) (xy 258.897059 -78.867939) (xy 258.916982 -78.815848) (xy 258.944278 -78.767213)
			(xy 258.978364 -78.72307) (xy 259.018513 -78.684361) (xy 259.063871 -78.65191) (xy 259.113471 -78.626409)
			(xy 259.166255 -78.608402) (xy 259.221098 -78.598272) (xy 259.276832 -78.596235) (xy 259.332269 -78.602335)
			(xy 259.386226 -78.616441) (xy 259.437555 -78.638253) (xy 259.485161 -78.667307) (xy 259.528029 -78.702982)
			(xy 259.565246 -78.744519) (xy 259.596019 -78.791032) (xy 259.619691 -78.841529) (xy 259.635759 -78.894936)
			(xy 259.643879 -78.950112) (xy 259.644388 -78.977998) (xy 259.643879 -79.005884) (xy 259.635759 -79.06106)
			(xy 259.619691 -79.114467) (xy 259.596019 -79.164964) (xy 259.565246 -79.211477) (xy 259.528029 -79.253014)
			(xy 259.485161 -79.288689) (xy 259.437555 -79.317743) (xy 259.386226 -79.339555) (xy 259.332269 -79.353661)
			(xy 259.276832 -79.359761) (xy 259.221098 -79.357724) (xy 259.166255 -79.347594) (xy 259.113471 -79.329587)
			(xy 259.063871 -79.304086) (xy 259.018513 -79.271635) (xy 258.978364 -79.232926) (xy 258.944278 -79.188783)
			(xy 258.916982 -79.140148) (xy 258.897059 -79.088057) (xy 258.884933 -79.03362) (xy 258.880862 -78.977998)
			(xy 250.21413 -78.977998) (xy 250.77928 -79.543148) (xy 277.41372 -79.543148)
		)
		(stroke
			(width 0)
			(type solid)
		)
		(fill yes)
		(layer "In11.Cu")
		(net "GND")
	)
	(gr_poly
		(pts
			(xy 253.072392 -55.6768) (xy 253.072903 -55.651816) (xy 253.080753 -55.602468) (xy 253.096212 -55.55495)
			(xy 253.118903 -55.51043) (xy 253.148267 -55.47) (xy 253.16561 -55.45201) (xy 253.836932 -54.780688)
			(xy 253.836932 -53.81498) (xy 253.821885 -53.791402) (xy 253.798114 -53.740772) (xy 253.781998 -53.687213)
			(xy 253.773882 -53.631873) (xy 253.773432 -53.603906) (xy 253.773918 -53.576655) (xy 253.781674 -53.522707)
			(xy 253.797029 -53.470412) (xy 253.819671 -53.420835) (xy 253.849137 -53.374985) (xy 253.884828 -53.333794)
			(xy 253.926019 -53.298103) (xy 253.971869 -53.268637) (xy 254.021446 -53.245995) (xy 254.073741 -53.23064)
			(xy 254.127689 -53.222884) (xy 254.182191 -53.222884) (xy 254.236139 -53.23064) (xy 254.288434 -53.245995)
			(xy 254.338011 -53.268637) (xy 254.383861 -53.298103) (xy 254.425052 -53.333794) (xy 254.460743 -53.374985)
			(xy 254.490209 -53.420835) (xy 254.512851 -53.470412) (xy 254.528206 -53.522707) (xy 254.535962 -53.576655)
			(xy 254.536131 -53.586126) (xy 255.050542 -53.586126) (xy 255.054613 -53.530504) (xy 255.066739 -53.476067)
			(xy 255.086662 -53.423976) (xy 255.113958 -53.375341) (xy 255.148044 -53.331198) (xy 255.188193 -53.292489)
			(xy 255.233551 -53.260038) (xy 255.283151 -53.234537) (xy 255.335935 -53.21653) (xy 255.390778 -53.2064)
			(xy 255.446512 -53.204363) (xy 255.501949 -53.210463) (xy 255.555906 -53.224569) (xy 255.607235 -53.246381)
			(xy 255.654841 -53.275435) (xy 255.697709 -53.31111) (xy 255.734926 -53.352647) (xy 255.765699 -53.39916)
			(xy 255.789371 -53.449657) (xy 255.805439 -53.503064) (xy 255.813559 -53.55824) (xy 255.814068 -53.586126)
			(xy 255.813559 -53.614012) (xy 255.805439 -53.669188) (xy 255.789371 -53.722595) (xy 255.765699 -53.773092)
			(xy 255.734926 -53.819605) (xy 255.697709 -53.861142) (xy 255.654841 -53.896817) (xy 255.607235 -53.925871)
			(xy 255.555906 -53.947683) (xy 255.501949 -53.961789) (xy 255.446512 -53.967889) (xy 255.390778 -53.965852)
			(xy 255.335935 -53.955722) (xy 255.283151 -53.937715) (xy 255.233551 -53.912214) (xy 255.188193 -53.879763)
			(xy 255.148044 -53.841054) (xy 255.113958 -53.796911) (xy 255.086662 -53.748276) (xy 255.066739 -53.696185)
			(xy 255.054613 -53.641748) (xy 255.050542 -53.586126) (xy 254.536131 -53.586126) (xy 254.536448 -53.603906)
			(xy 254.535974 -53.63187) (xy 254.527844 -53.687204) (xy 254.511729 -53.740759) (xy 254.487975 -53.791392)
			(xy 254.472948 -53.81498) (xy 254.472948 -54.91226) (xy 254.472432 -54.937242) (xy 254.464573 -54.986584)
			(xy 254.449105 -55.034094) (xy 254.426406 -55.078604) (xy 254.397034 -55.119024) (xy 254.37973 -55.13705)
			(xy 254.217424 -55.299356) (xy 254.207086 -55.310491) (xy 254.192876 -55.33733) (xy 254.187181 -55.367159)
			(xy 254.190502 -55.397345) (xy 254.202546 -55.425223) (xy 254.222251 -55.448331) (xy 254.247876 -55.464628)
			(xy 254.277158 -55.472676) (xy 254.292354 -55.472838) (xy 254.30353 -55.472584) (xy 254.330781 -55.473072)
			(xy 254.384729 -55.480833) (xy 254.437023 -55.496192) (xy 254.486599 -55.518837) (xy 254.532448 -55.548307)
			(xy 254.573636 -55.584001) (xy 254.609325 -55.625194) (xy 254.638788 -55.671047) (xy 254.661427 -55.720626)
			(xy 254.676779 -55.772922) (xy 254.684532 -55.826871) (xy 254.684529 -55.881374) (xy 254.676769 -55.935322)
			(xy 254.661411 -55.987616) (xy 254.638767 -56.037193) (xy 254.609298 -56.083042) (xy 254.573604 -56.124231)
			(xy 254.532411 -56.159921) (xy 254.486559 -56.189385) (xy 254.436981 -56.212024) (xy 254.384685 -56.227377)
			(xy 254.330736 -56.235131) (xy 254.276233 -56.235129) (xy 254.222285 -56.22737) (xy 254.169991 -56.212013)
			(xy 254.120414 -56.18937) (xy 254.074564 -56.159902) (xy 254.033374 -56.124209) (xy 253.997684 -56.083017)
			(xy 253.968219 -56.037166) (xy 253.945579 -55.987587) (xy 253.930225 -55.935292) (xy 253.922469 -55.881343)
			(xy 253.922022 -55.854092) (xy 253.922276 -55.842916) (xy 253.922167 -55.827724) (xy 253.91411 -55.798448)
			(xy 253.897807 -55.772831) (xy 253.874697 -55.753135) (xy 253.84682 -55.7411) (xy 253.816636 -55.737786)
			(xy 253.786812 -55.743487) (xy 253.759979 -55.7577) (xy 253.748794 -55.767986) (xy 253.708408 -55.808372)
			(xy 253.708408 -58.953146) (xy 254.947928 -58.953146) (xy 254.96271 -58.952654) (xy 254.991041 -58.944206)
			(xy 255.015764 -58.927996) (xy 255.034808 -58.905384) (xy 255.046577 -58.878264) (xy 255.050084 -58.848909)
			(xy 255.045035 -58.81978) (xy 255.031854 -58.793317) (xy 255.022096 -58.782204) (xy 255.002824 -58.760877)
			(xy 254.970255 -58.713516) (xy 254.945159 -58.661804) (xy 254.928104 -58.606914) (xy 254.919475 -58.550086)
			(xy 254.918972 -58.521346) (xy 254.919432 -58.49409) (xy 254.927183 -58.440133) (xy 254.942535 -58.387829)
			(xy 254.965175 -58.338242) (xy 254.994641 -58.292381) (xy 255.030335 -58.251181) (xy 255.071528 -58.215481)
			(xy 255.117384 -58.186006) (xy 255.166967 -58.163358) (xy 255.219269 -58.147997) (xy 255.273225 -58.140236)
			(xy 255.30048 -58.139838) (xy 255.325412 -58.14024) (xy 255.374854 -58.146727) (xy 255.42303 -58.159592)
			(xy 255.469123 -58.178617) (xy 255.512348 -58.203478) (xy 255.532382 -58.218324) (xy 255.54343 -58.226214)
			(xy 255.568577 -58.236415) (xy 255.595523 -58.239642) (xy 255.622369 -58.235667) (xy 255.647223 -58.224769)
			(xy 255.668335 -58.207718) (xy 255.676654 -58.196988) (xy 255.692068 -58.17627) (xy 255.727586 -58.138785)
			(xy 255.76784 -58.106439) (xy 255.812092 -58.079824) (xy 255.859532 -58.059426) (xy 255.909292 -58.045621)
			(xy 255.96046 -58.03866) (xy 255.98628 -58.038238) (xy 256.013531 -58.0387) (xy 256.067477 -58.046454)
			(xy 256.119771 -58.061806) (xy 256.169348 -58.084445) (xy 256.215198 -58.113909) (xy 256.256388 -58.149598)
			(xy 256.292079 -58.190786) (xy 256.321546 -58.236635) (xy 256.344187 -58.28621) (xy 256.359542 -58.338503)
			(xy 256.360267 -58.343546) (xy 256.594862 -58.343546) (xy 256.598933 -58.287924) (xy 256.611059 -58.233487)
			(xy 256.630982 -58.181396) (xy 256.658278 -58.132761) (xy 256.692364 -58.088618) (xy 256.732513 -58.049909)
			(xy 256.777871 -58.017458) (xy 256.827471 -57.991957) (xy 256.880255 -57.97395) (xy 256.935098 -57.96382)
			(xy 256.990832 -57.961783) (xy 257.046269 -57.967883) (xy 257.100226 -57.981989) (xy 257.151555 -58.003801)
			(xy 257.199161 -58.032855) (xy 257.242029 -58.06853) (xy 257.279246 -58.110067) (xy 257.310019 -58.15658)
			(xy 257.333691 -58.207077) (xy 257.349759 -58.260484) (xy 257.357879 -58.31566) (xy 257.358388 -58.343546)
			(xy 257.357879 -58.371432) (xy 257.349759 -58.426608) (xy 257.333691 -58.480015) (xy 257.310019 -58.530512)
			(xy 257.279246 -58.577025) (xy 257.242029 -58.618562) (xy 257.199161 -58.654237) (xy 257.151555 -58.683291)
			(xy 257.100226 -58.705103) (xy 257.046269 -58.719209) (xy 256.990832 -58.725309) (xy 256.935098 -58.723272)
			(xy 256.880255 -58.713142) (xy 256.827471 -58.695135) (xy 256.777871 -58.669634) (xy 256.732513 -58.637183)
			(xy 256.692364 -58.598474) (xy 256.658278 -58.554331) (xy 256.630982 -58.505696) (xy 256.611059 -58.453605)
			(xy 256.598933 -58.399168) (xy 256.594862 -58.343546) (xy 256.360267 -58.343546) (xy 256.367299 -58.39245)
			(xy 256.367299 -58.44695) (xy 256.359542 -58.500897) (xy 256.344187 -58.55319) (xy 256.321546 -58.602765)
			(xy 256.292079 -58.648614) (xy 256.256388 -58.689802) (xy 256.215198 -58.725491) (xy 256.169348 -58.754955)
			(xy 256.119771 -58.777594) (xy 256.067477 -58.792946) (xy 256.013531 -58.8007) (xy 255.98628 -58.801254)
			(xy 255.961348 -58.800849) (xy 255.91191 -58.794358) (xy 255.863736 -58.781488) (xy 255.817647 -58.762459)
			(xy 255.774426 -58.737595) (xy 255.754378 -58.722768) (xy 255.743329 -58.71487) (xy 255.718175 -58.704654)
			(xy 255.691219 -58.701415) (xy 255.66436 -58.705381) (xy 255.639491 -58.716272) (xy 255.618363 -58.733322)
			(xy 255.610106 -58.744104) (xy 255.60284 -58.754063) (xy 255.587205 -58.773127) (xy 255.578864 -58.782204)
			(xy 255.569138 -58.793341) (xy 255.555977 -58.819805) (xy 255.55094 -58.848929) (xy 255.554448 -58.878276)
			(xy 255.566208 -58.905392) (xy 255.585236 -58.928008) (xy 255.60994 -58.944234) (xy 255.638254 -58.952711)
			(xy 255.653032 -58.953146) (xy 257.94208 -58.953146) (xy 258.860544 -58.034682) (xy 258.870387 -58.02407)
			(xy 258.884225 -57.998664) (xy 258.890384 -57.970397) (xy 258.888372 -57.941537) (xy 258.87835 -57.914398)
			(xy 258.861121 -57.891158) (xy 258.838067 -57.873679) (xy 258.82473 -57.868058) (xy 258.798022 -57.857296)
			(xy 258.747926 -57.828908) (xy 258.70266 -57.793321) (xy 258.663249 -57.751341) (xy 258.630587 -57.703921)
			(xy 258.605415 -57.652135) (xy 258.588302 -57.597156) (xy 258.579636 -57.540232) (xy 258.579112 -57.511442)
			(xy 258.579572 -57.484188) (xy 258.587325 -57.430233) (xy 258.602677 -57.377932) (xy 258.625318 -57.328347)
			(xy 258.654785 -57.28249) (xy 258.690479 -57.241294) (xy 258.731673 -57.205598) (xy 258.777528 -57.176128)
			(xy 258.827111 -57.153485) (xy 258.879412 -57.138129) (xy 258.933366 -57.130374) (xy 258.96062 -57.129934)
			(xy 258.986748 -57.130383) (xy 259.038511 -57.137546) (xy 259.088816 -57.151695) (xy 259.136723 -57.172567)
			(xy 259.159248 -57.185814) (xy 259.170977 -57.192468) (xy 259.19687 -57.199973) (xy 259.223825 -57.200439)
			(xy 259.249962 -57.193836) (xy 259.27346 -57.180623) (xy 259.292682 -57.161721) (xy 259.306287 -57.138448)
			(xy 259.313328 -57.112425) (xy 259.31368 -57.098946) (xy 259.31368 -56.877204) (xy 259.313213 -56.863016)
			(xy 259.305404 -56.835736) (xy 259.290389 -56.811658) (xy 259.269328 -56.792643) (xy 259.243846 -56.780158)
			(xy 259.215913 -56.775169) (xy 259.187685 -56.77806) (xy 259.161343 -56.788608) (xy 259.14985 -56.79694)
			(xy 259.129719 -56.812043) (xy 259.086241 -56.837386) (xy 259.039806 -56.856788) (xy 258.991222 -56.869913)
			(xy 258.941333 -56.87653) (xy 258.91617 -56.87695) (xy 258.888917 -56.876462) (xy 258.834967 -56.868701)
			(xy 258.78267 -56.853342) (xy 258.733091 -56.830696) (xy 258.687239 -56.801226) (xy 258.646048 -56.765531)
			(xy 258.610356 -56.724337) (xy 258.580889 -56.678483) (xy 258.558248 -56.628902) (xy 258.542892 -56.576604)
			(xy 258.535136 -56.522653) (xy 258.535136 -56.468147) (xy 258.542892 -56.414196) (xy 258.558248 -56.361898)
			(xy 258.580889 -56.312317) (xy 258.610356 -56.266463) (xy 258.646048 -56.225269) (xy 258.687239 -56.189574)
			(xy 258.733091 -56.160104) (xy 258.78267 -56.137458) (xy 258.834967 -56.122099) (xy 258.888917 -56.114338)
			(xy 258.91617 -56.113934) (xy 258.941334 -56.114336) (xy 258.991225 -56.120954) (xy 259.039812 -56.134078)
			(xy 259.08625 -56.153481) (xy 259.129731 -56.178824) (xy 259.14985 -56.193944) (xy 259.161351 -56.202264)
			(xy 259.187696 -56.212803) (xy 259.215924 -56.215689) (xy 259.243857 -56.210699) (xy 259.26934 -56.198219)
			(xy 259.290407 -56.179211) (xy 259.305433 -56.155141) (xy 259.313259 -56.127867) (xy 259.31368 -56.11368)
			(xy 259.31368 -55.861204) (xy 259.313213 -55.847016) (xy 259.305404 -55.819736) (xy 259.290389 -55.795658)
			(xy 259.269328 -55.776643) (xy 259.243846 -55.764158) (xy 259.215913 -55.759169) (xy 259.187685 -55.76206)
			(xy 259.161343 -55.772608) (xy 259.14985 -55.78094) (xy 259.129719 -55.796043) (xy 259.086241 -55.821386)
			(xy 259.039806 -55.840788) (xy 258.991222 -55.853913) (xy 258.941333 -55.86053) (xy 258.91617 -55.86095)
			(xy 258.888917 -55.860462) (xy 258.834967 -55.852701) (xy 258.78267 -55.837342) (xy 258.733091 -55.814696)
			(xy 258.687239 -55.785226) (xy 258.646048 -55.749531) (xy 258.610356 -55.708337) (xy 258.580889 -55.662483)
			(xy 258.558248 -55.612902) (xy 258.542892 -55.560604) (xy 258.535136 -55.506653) (xy 258.535136 -55.452147)
			(xy 258.542892 -55.398196) (xy 258.558248 -55.345898) (xy 258.580889 -55.296317) (xy 258.610356 -55.250463)
			(xy 258.646048 -55.209269) (xy 258.687239 -55.173574) (xy 258.733091 -55.144104) (xy 258.78267 -55.121458)
			(xy 258.834967 -55.106099) (xy 258.888917 -55.098338) (xy 258.91617 -55.097934) (xy 258.941334 -55.098336)
			(xy 258.991225 -55.104954) (xy 259.039812 -55.118078) (xy 259.08625 -55.137481) (xy 259.129731 -55.162824)
			(xy 259.14985 -55.177944) (xy 259.161351 -55.186264) (xy 259.187696 -55.196803) (xy 259.215924 -55.199689)
			(xy 259.243857 -55.194699) (xy 259.26934 -55.182219) (xy 259.290407 -55.163211) (xy 259.305433 -55.139141)
			(xy 259.313259 -55.111867) (xy 259.31368 -55.09768) (xy 259.31368 -54.82844) (xy 259.31321 -54.814207)
			(xy 259.305354 -54.786846) (xy 259.290243 -54.762722) (xy 259.269055 -54.743713) (xy 259.243438 -54.731299)
			(xy 259.215388 -54.726448) (xy 259.18709 -54.729537) (xy 259.173726 -54.73446) (xy 259.150781 -54.743402)
			(xy 259.103167 -54.755969) (xy 259.05433 -54.762293) (xy 259.029708 -54.762654) (xy 259.002451 -54.762192)
			(xy 258.948493 -54.754435) (xy 258.896188 -54.739077) (xy 258.846601 -54.716433) (xy 258.800741 -54.686961)
			(xy 258.759542 -54.651263) (xy 258.723844 -54.610065) (xy 258.694371 -54.564206) (xy 258.671725 -54.51462)
			(xy 258.656367 -54.462315) (xy 258.648609 -54.408357) (xy 258.648609 -54.353843) (xy 258.656367 -54.299885)
			(xy 258.671725 -54.24758) (xy 258.694371 -54.197994) (xy 258.723844 -54.152135) (xy 258.759542 -54.110937)
			(xy 258.800741 -54.075239) (xy 258.846601 -54.045767) (xy 258.896188 -54.023123) (xy 258.948493 -54.007765)
			(xy 259.002451 -54.000008) (xy 259.029708 -53.999638) (xy 259.054328 -54.000028) (xy 259.10316 -54.006363)
			(xy 259.150774 -54.018914) (xy 259.173726 -54.027832) (xy 259.187084 -54.032766) (xy 259.215383 -54.035823)
			(xy 259.243427 -54.030955) (xy 259.26904 -54.018539) (xy 259.290235 -53.99954) (xy 259.305365 -53.975431)
			(xy 259.313258 -53.948083) (xy 259.31368 -53.933852) (xy 259.31368 -50.977546) (xy 258.85648 -50.520346)
			(xy 258.85648 -47.488856) (xy 258.855941 -47.473774) (xy 258.847139 -47.444923) (xy 258.830288 -47.419905)
			(xy 258.80686 -47.400906) (xy 258.778901 -47.389585) (xy 258.748854 -47.386932) (xy 258.719344 -47.393178)
			(xy 258.705858 -47.399956) (xy 258.677402 -47.41491) (xy 258.616719 -47.436105) (xy 258.55334 -47.44682)
			(xy 258.5212 -47.447454) (xy 258.493626 -47.446967) (xy 258.439052 -47.439026) (xy 258.386191 -47.423308)
			(xy 258.336144 -47.400142) (xy 258.289954 -47.37001) (xy 258.248586 -47.333541) (xy 258.23037 -47.312834)
			(xy 258.220472 -47.301936) (xy 258.195822 -47.285861) (xy 258.167614 -47.277477) (xy 258.138186 -47.277477)
			(xy 258.109978 -47.285861) (xy 258.085328 -47.301936) (xy 258.07543 -47.312834) (xy 258.057215 -47.33354)
			(xy 258.015844 -47.370005) (xy 257.969654 -47.400132) (xy 257.919607 -47.423295) (xy 257.866746 -47.439011)
			(xy 257.812174 -47.446951) (xy 257.757026 -47.446951) (xy 257.702454 -47.439011) (xy 257.649593 -47.423295)
			(xy 257.599546 -47.400132) (xy 257.553356 -47.370005) (xy 257.511985 -47.33354) (xy 257.49377 -47.312834)
			(xy 257.483872 -47.301936) (xy 257.459222 -47.285861) (xy 257.431014 -47.277477) (xy 257.401586 -47.277477)
			(xy 257.373378 -47.285861) (xy 257.348728 -47.301936) (xy 257.33883 -47.312834) (xy 257.320615 -47.333543)
			(xy 257.279246 -47.370015) (xy 257.233057 -47.400151) (xy 257.18301 -47.423324) (xy 257.13015 -47.439051)
			(xy 257.075575 -47.447004) (xy 257.048 -47.447454) (xy 257.020745 -47.446968) (xy 256.966791 -47.439211)
			(xy 256.91449 -47.423854) (xy 256.864907 -47.40121) (xy 256.819051 -47.37174) (xy 256.777856 -47.336044)
			(xy 256.74216 -47.294849) (xy 256.71269 -47.248993) (xy 256.690046 -47.19941) (xy 256.674689 -47.147109)
			(xy 256.666932 -47.093155) (xy 256.666932 -47.038645) (xy 256.674689 -46.984691) (xy 256.690046 -46.93239)
			(xy 256.71269 -46.882807) (xy 256.74216 -46.836951) (xy 256.777856 -46.795756) (xy 256.819051 -46.76006)
			(xy 256.864907 -46.73059) (xy 256.91449 -46.707946) (xy 256.966791 -46.692589) (xy 257.020745 -46.684832)
			(xy 257.048 -46.684438) (xy 257.075574 -46.684925) (xy 257.130148 -46.692866) (xy 257.18301 -46.708584)
			(xy 257.233057 -46.73175) (xy 257.279247 -46.761881) (xy 257.320616 -46.79835) (xy 257.33883 -46.819058)
			(xy 257.348728 -46.829956) (xy 257.373378 -46.846031) (xy 257.401586 -46.854415) (xy 257.431014 -46.854415)
			(xy 257.459222 -46.846031) (xy 257.483872 -46.829956) (xy 257.49377 -46.819058) (xy 257.511985 -46.798352)
			(xy 257.553356 -46.761887) (xy 257.599546 -46.73176) (xy 257.649593 -46.708597) (xy 257.702454 -46.692881)
			(xy 257.757026 -46.684941) (xy 257.812174 -46.684941) (xy 257.866746 -46.692881) (xy 257.919607 -46.708597)
			(xy 257.969654 -46.73176) (xy 258.015844 -46.761887) (xy 258.057215 -46.798352) (xy 258.07543 -46.819058)
			(xy 258.085328 -46.829956) (xy 258.109978 -46.846031) (xy 258.138186 -46.854415) (xy 258.167614 -46.854415)
			(xy 258.195822 -46.846031) (xy 258.220472 -46.829956) (xy 258.23037 -46.819058) (xy 258.248585 -46.798349)
			(xy 258.289955 -46.761879) (xy 258.336144 -46.731743) (xy 258.38619 -46.708571) (xy 258.439051 -46.692844)
			(xy 258.493625 -46.68489) (xy 258.5212 -46.684438) (xy 258.553338 -46.685083) (xy 258.616712 -46.695811)
			(xy 258.677395 -46.716998) (xy 258.705858 -46.731936) (xy 258.71933 -46.738735) (xy 258.748845 -46.744944)
			(xy 258.778887 -46.742269) (xy 258.806841 -46.730944) (xy 258.830273 -46.711954) (xy 258.847144 -46.686952)
			(xy 258.855984 -46.658116) (xy 258.85648 -46.643036) (xy 258.85648 -44.979082) (xy 258.833824 -44.964742)
			(xy 258.792393 -44.930707) (xy 258.77393 -44.911264) (xy 258.764546 -44.901687) (xy 258.741876 -44.887384)
			(xy 258.71627 -44.879462) (xy 258.689484 -44.878463) (xy 258.663359 -44.884458) (xy 258.639687 -44.897034)
			(xy 258.629658 -44.90593) (xy 258.60833 -44.925198) (xy 258.560966 -44.957759) (xy 258.509254 -44.982847)
			(xy 258.454364 -44.999895) (xy 258.397538 -45.008516) (xy 258.3688 -45.009054) (xy 258.341226 -45.008567)
			(xy 258.286652 -45.000626) (xy 258.233791 -44.984908) (xy 258.183744 -44.961742) (xy 258.137554 -44.93161)
			(xy 258.096186 -44.895141) (xy 258.07797 -44.874434) (xy 258.068072 -44.863536) (xy 258.043422 -44.847461)
			(xy 258.015214 -44.839077) (xy 257.985786 -44.839077) (xy 257.957578 -44.847461) (xy 257.932928 -44.863536)
			(xy 257.92303 -44.874434) (xy 257.904815 -44.895143) (xy 257.863446 -44.931615) (xy 257.817257 -44.961751)
			(xy 257.76721 -44.984924) (xy 257.71435 -45.000651) (xy 257.659775 -45.008604) (xy 257.6322 -45.009054)
			(xy 257.604945 -45.008568) (xy 257.550991 -45.000811) (xy 257.49869 -44.985454) (xy 257.449107 -44.96281)
			(xy 257.403251 -44.93334) (xy 257.362056 -44.897644) (xy 257.32636 -44.856449) (xy 257.29689 -44.810593)
			(xy 257.274246 -44.76101) (xy 257.258889 -44.708709) (xy 257.251132 -44.654755) (xy 257.251132 -44.600245)
			(xy 257.258889 -44.546291) (xy 257.274246 -44.49399) (xy 257.29689 -44.444407) (xy 257.32636 -44.398551)
			(xy 257.362056 -44.357356) (xy 257.403251 -44.32166) (xy 257.449107 -44.29219) (xy 257.49869 -44.269546)
			(xy 257.550991 -44.254189) (xy 257.604945 -44.246432) (xy 257.6322 -44.246038) (xy 257.659774 -44.246525)
			(xy 257.714348 -44.254466) (xy 257.76721 -44.270184) (xy 257.817257 -44.29335) (xy 257.863447 -44.323481)
			(xy 257.904816 -44.35995) (xy 257.92303 -44.380658) (xy 257.932928 -44.391556) (xy 257.957578 -44.407631)
			(xy 257.985786 -44.416015) (xy 258.015214 -44.416015) (xy 258.043422 -44.407631) (xy 258.068072 -44.391556)
			(xy 258.07797 -44.380658) (xy 258.096185 -44.359949) (xy 258.137555 -44.323479) (xy 258.183744 -44.293343)
			(xy 258.23379 -44.270171) (xy 258.286651 -44.254444) (xy 258.341225 -44.24649) (xy 258.3688 -44.246038)
			(xy 258.395097 -44.246479) (xy 258.447193 -44.253707) (xy 258.497802 -44.268025) (xy 258.545963 -44.289161)
			(xy 258.590762 -44.316715) (xy 258.63135 -44.350164) (xy 258.64947 -44.369228) (xy 258.658858 -44.378798)
			(xy 258.681529 -44.393088) (xy 258.707133 -44.401003) (xy 258.733913 -44.402) (xy 258.760035 -44.396012)
			(xy 258.783707 -44.383448) (xy 258.793742 -44.374562) (xy 258.808312 -44.361225) (xy 258.839742 -44.337297)
			(xy 258.85648 -44.32681) (xy 258.85648 -43.967146) (xy 257.901948 -43.012614) (xy 257.589528 -43.325034)
			(xy 257.567934 -43.345828) (xy 257.519423 -43.381045) (xy 257.465996 -43.40823) (xy 257.40897 -43.426713)
			(xy 257.349754 -43.436036) (xy 257.31978 -43.43654) (xy 253.487174 -43.43654) (xy 253.457207 -43.435967)
			(xy 253.398007 -43.426623) (xy 253.340996 -43.408138) (xy 253.287577 -43.380966) (xy 253.239063 -43.345776)
			(xy 253.217426 -43.325034) (xy 252.818392 -42.925746) (xy 250.695206 -42.925746) (xy 250.685046 -42.963338)
			(xy 250.677294 -42.989919) (xy 250.655176 -43.040677) (xy 250.625956 -43.087708) (xy 250.590249 -43.130023)
			(xy 250.548802 -43.166736) (xy 250.502487 -43.197076) (xy 250.452274 -43.220406) (xy 250.399217 -43.236236)
			(xy 250.34443 -43.244236) (xy 250.289062 -43.244236) (xy 250.234275 -43.236236) (xy 250.181218 -43.220406)
			(xy 250.131005 -43.197076) (xy 250.08469 -43.166736) (xy 250.043243 -43.130023) (xy 250.007536 -43.087708)
			(xy 249.978316 -43.040677) (xy 249.956198 -42.989919) (xy 249.948446 -42.963338) (xy 249.938286 -42.925746)
			(xy 248.97588 -42.925746) (xy 247.94972 -43.951906) (xy 251.107192 -43.951906) (xy 251.111263 -43.896284)
			(xy 251.123389 -43.841847) (xy 251.143312 -43.789756) (xy 251.170608 -43.741121) (xy 251.204694 -43.696978)
			(xy 251.244843 -43.658269) (xy 251.290201 -43.625818) (xy 251.339801 -43.600317) (xy 251.392585 -43.58231)
			(xy 251.447428 -43.57218) (xy 251.503162 -43.570143) (xy 251.558599 -43.576243) (xy 251.612556 -43.590349)
			(xy 251.663885 -43.612161) (xy 251.711491 -43.641215) (xy 251.754359 -43.67689) (xy 251.791576 -43.718427)
			(xy 251.822349 -43.76494) (xy 251.846021 -43.815437) (xy 251.851927 -43.835066) (xy 252.707392 -43.835066)
			(xy 252.711463 -43.779444) (xy 252.723589 -43.725007) (xy 252.743512 -43.672916) (xy 252.770808 -43.624281)
			(xy 252.804894 -43.580138) (xy 252.845043 -43.541429) (xy 252.890401 -43.508978) (xy 252.940001 -43.483477)
			(xy 252.992785 -43.46547) (xy 253.047628 -43.45534) (xy 253.103362 -43.453303) (xy 253.158799 -43.459403)
			(xy 253.212756 -43.473509) (xy 253.264085 -43.495321) (xy 253.311691 -43.524375) (xy 253.354559 -43.56005)
			(xy 253.391776 -43.601587) (xy 253.422549 -43.6481) (xy 253.446221 -43.698597) (xy 253.462289 -43.752004)
			(xy 253.470409 -43.80718) (xy 253.470918 -43.835066) (xy 253.470409 -43.862952) (xy 253.462289 -43.918128)
			(xy 253.446221 -43.971535) (xy 253.422549 -44.022032) (xy 253.391776 -44.068545) (xy 253.354559 -44.110082)
			(xy 253.311691 -44.145757) (xy 253.264085 -44.174811) (xy 253.212756 -44.196623) (xy 253.158799 -44.210729)
			(xy 253.103362 -44.216829) (xy 253.047628 -44.214792) (xy 252.992785 -44.204662) (xy 252.940001 -44.186655)
			(xy 252.890401 -44.161154) (xy 252.845043 -44.128703) (xy 252.804894 -44.089994) (xy 252.770808 -44.045851)
			(xy 252.743512 -43.997216) (xy 252.723589 -43.945125) (xy 252.711463 -43.890688) (xy 252.707392 -43.835066)
			(xy 251.851927 -43.835066) (xy 251.862089 -43.868844) (xy 251.870209 -43.92402) (xy 251.870718 -43.951906)
			(xy 251.870209 -43.979792) (xy 251.862089 -44.034968) (xy 251.846021 -44.088375) (xy 251.822349 -44.138872)
			(xy 251.791576 -44.185385) (xy 251.754359 -44.226922) (xy 251.711491 -44.262597) (xy 251.663885 -44.291651)
			(xy 251.612556 -44.313463) (xy 251.558599 -44.327569) (xy 251.503162 -44.333669) (xy 251.447428 -44.331632)
			(xy 251.392585 -44.321502) (xy 251.339801 -44.303495) (xy 251.290201 -44.277994) (xy 251.244843 -44.245543)
			(xy 251.204694 -44.206834) (xy 251.170608 -44.162691) (xy 251.143312 -44.114056) (xy 251.123389 -44.061965)
			(xy 251.111263 -44.007528) (xy 251.107192 -43.951906) (xy 247.94972 -43.951906) (xy 247.50268 -44.398946)
			(xy 254.359662 -44.398946) (xy 254.363733 -44.343324) (xy 254.375859 -44.288887) (xy 254.395782 -44.236796)
			(xy 254.423078 -44.188161) (xy 254.457164 -44.144018) (xy 254.497313 -44.105309) (xy 254.542671 -44.072858)
			(xy 254.592271 -44.047357) (xy 254.645055 -44.02935) (xy 254.699898 -44.01922) (xy 254.755632 -44.017183)
			(xy 254.811069 -44.023283) (xy 254.865026 -44.037389) (xy 254.916355 -44.059201) (xy 254.963961 -44.088255)
			(xy 255.006829 -44.12393) (xy 255.044046 -44.165467) (xy 255.074819 -44.21198) (xy 255.098491 -44.262477)
			(xy 255.114559 -44.315884) (xy 255.122679 -44.37106) (xy 255.123188 -44.398946) (xy 255.122679 -44.426832)
			(xy 255.114559 -44.482008) (xy 255.098491 -44.535415) (xy 255.074819 -44.585912) (xy 255.044046 -44.632425)
			(xy 255.006829 -44.673962) (xy 254.963961 -44.709637) (xy 254.916355 -44.738691) (xy 254.865026 -44.760503)
			(xy 254.811069 -44.774609) (xy 254.755632 -44.780709) (xy 254.699898 -44.778672) (xy 254.645055 -44.768542)
			(xy 254.592271 -44.750535) (xy 254.542671 -44.725034) (xy 254.497313 -44.692583) (xy 254.457164 -44.653874)
			(xy 254.423078 -44.609731) (xy 254.395782 -44.561096) (xy 254.375859 -44.509005) (xy 254.363733 -44.454568)
			(xy 254.359662 -44.398946) (xy 247.50268 -44.398946) (xy 245.912894 -45.988732) (xy 249.917456 -45.988732)
			(xy 249.921527 -45.93311) (xy 249.933653 -45.878673) (xy 249.953576 -45.826582) (xy 249.980872 -45.777947)
			(xy 250.014958 -45.733804) (xy 250.055107 -45.695095) (xy 250.100465 -45.662644) (xy 250.150065 -45.637143)
			(xy 250.202849 -45.619136) (xy 250.257692 -45.609006) (xy 250.313426 -45.606969) (xy 250.368863 -45.613069)
			(xy 250.42282 -45.627175) (xy 250.474149 -45.648987) (xy 250.521755 -45.678041) (xy 250.564623 -45.713716)
			(xy 250.60184 -45.755253) (xy 250.632613 -45.801766) (xy 250.656285 -45.852263) (xy 250.672353 -45.90567)
			(xy 250.680473 -45.960846) (xy 250.680982 -45.988732) (xy 250.680473 -46.016618) (xy 250.672353 -46.071794)
			(xy 250.656285 -46.125201) (xy 250.632613 -46.175698) (xy 250.60184 -46.222211) (xy 250.564623 -46.263748)
			(xy 250.521755 -46.299423) (xy 250.474149 -46.328477) (xy 250.42282 -46.350289) (xy 250.368863 -46.364395)
			(xy 250.313426 -46.370495) (xy 250.257692 -46.368458) (xy 250.202849 -46.358328) (xy 250.150065 -46.340321)
			(xy 250.100465 -46.31482) (xy 250.055107 -46.282369) (xy 250.014958 -46.24366) (xy 249.980872 -46.199517)
			(xy 249.953576 -46.150882) (xy 249.933653 -46.098791) (xy 249.921527 -46.044354) (xy 249.917456 -45.988732)
			(xy 245.912894 -45.988732) (xy 244.83568 -47.065946) (xy 253.419862 -47.065946) (xy 253.423933 -47.010324)
			(xy 253.436059 -46.955887) (xy 253.455982 -46.903796) (xy 253.483278 -46.855161) (xy 253.517364 -46.811018)
			(xy 253.557513 -46.772309) (xy 253.602871 -46.739858) (xy 253.652471 -46.714357) (xy 253.705255 -46.69635)
			(xy 253.760098 -46.68622) (xy 253.815832 -46.684183) (xy 253.871269 -46.690283) (xy 253.925226 -46.704389)
			(xy 253.976555 -46.726201) (xy 254.024161 -46.755255) (xy 254.067029 -46.79093) (xy 254.104246 -46.832467)
			(xy 254.135019 -46.87898) (xy 254.158691 -46.929477) (xy 254.174759 -46.982884) (xy 254.182879 -47.03806)
			(xy 254.183388 -47.065946) (xy 254.308862 -47.065946) (xy 254.312933 -47.010324) (xy 254.325059 -46.955887)
			(xy 254.344982 -46.903796) (xy 254.372278 -46.855161) (xy 254.406364 -46.811018) (xy 254.446513 -46.772309)
			(xy 254.491871 -46.739858) (xy 254.541471 -46.714357) (xy 254.594255 -46.69635) (xy 254.649098 -46.68622)
			(xy 254.704832 -46.684183) (xy 254.760269 -46.690283) (xy 254.814226 -46.704389) (xy 254.865555 -46.726201)
			(xy 254.913161 -46.755255) (xy 254.956029 -46.79093) (xy 254.993246 -46.832467) (xy 255.024019 -46.87898)
			(xy 255.047691 -46.929477) (xy 255.063759 -46.982884) (xy 255.071879 -47.03806) (xy 255.072388 -47.065946)
			(xy 255.197862 -47.065946) (xy 255.201933 -47.010324) (xy 255.214059 -46.955887) (xy 255.233982 -46.903796)
			(xy 255.261278 -46.855161) (xy 255.295364 -46.811018) (xy 255.335513 -46.772309) (xy 255.380871 -46.739858)
			(xy 255.430471 -46.714357) (xy 255.483255 -46.69635) (xy 255.538098 -46.68622) (xy 255.593832 -46.684183)
			(xy 255.649269 -46.690283) (xy 255.703226 -46.704389) (xy 255.754555 -46.726201) (xy 255.802161 -46.755255)
			(xy 255.845029 -46.79093) (xy 255.882246 -46.832467) (xy 255.913019 -46.87898) (xy 255.936691 -46.929477)
			(xy 255.952759 -46.982884) (xy 255.960879 -47.03806) (xy 255.961388 -47.065946) (xy 255.960879 -47.093832)
			(xy 255.952759 -47.149008) (xy 255.936691 -47.202415) (xy 255.913019 -47.252912) (xy 255.882246 -47.299425)
			(xy 255.845029 -47.340962) (xy 255.802161 -47.376637) (xy 255.754555 -47.405691) (xy 255.703226 -47.427503)
			(xy 255.649269 -47.441609) (xy 255.593832 -47.447709) (xy 255.538098 -47.445672) (xy 255.483255 -47.435542)
			(xy 255.430471 -47.417535) (xy 255.380871 -47.392034) (xy 255.335513 -47.359583) (xy 255.295364 -47.320874)
			(xy 255.261278 -47.276731) (xy 255.233982 -47.228096) (xy 255.214059 -47.176005) (xy 255.201933 -47.121568)
			(xy 255.197862 -47.065946) (xy 255.072388 -47.065946) (xy 255.071879 -47.093832) (xy 255.063759 -47.149008)
			(xy 255.047691 -47.202415) (xy 255.024019 -47.252912) (xy 254.993246 -47.299425) (xy 254.956029 -47.340962)
			(xy 254.913161 -47.376637) (xy 254.865555 -47.405691) (xy 254.814226 -47.427503) (xy 254.760269 -47.441609)
			(xy 254.704832 -47.447709) (xy 254.649098 -47.445672) (xy 254.594255 -47.435542) (xy 254.541471 -47.417535)
			(xy 254.491871 -47.392034) (xy 254.446513 -47.359583) (xy 254.406364 -47.320874) (xy 254.372278 -47.276731)
			(xy 254.344982 -47.228096) (xy 254.325059 -47.176005) (xy 254.312933 -47.121568) (xy 254.308862 -47.065946)
			(xy 254.183388 -47.065946) (xy 254.182879 -47.093832) (xy 254.174759 -47.149008) (xy 254.158691 -47.202415)
			(xy 254.135019 -47.252912) (xy 254.104246 -47.299425) (xy 254.067029 -47.340962) (xy 254.024161 -47.376637)
			(xy 253.976555 -47.405691) (xy 253.925226 -47.427503) (xy 253.871269 -47.441609) (xy 253.815832 -47.447709)
			(xy 253.760098 -47.445672) (xy 253.705255 -47.435542) (xy 253.652471 -47.417535) (xy 253.602871 -47.392034)
			(xy 253.557513 -47.359583) (xy 253.517364 -47.320874) (xy 253.483278 -47.276731) (xy 253.455982 -47.228096)
			(xy 253.436059 -47.176005) (xy 253.423933 -47.121568) (xy 253.419862 -47.065946) (xy 244.83568 -47.065946)
			(xy 244.32768 -47.573946) (xy 244.32768 -48.539146) (xy 250.067062 -48.539146) (xy 250.071133 -48.483524)
			(xy 250.083259 -48.429087) (xy 250.103182 -48.376996) (xy 250.130478 -48.328361) (xy 250.164564 -48.284218)
			(xy 250.204713 -48.245509) (xy 250.250071 -48.213058) (xy 250.299671 -48.187557) (xy 250.352455 -48.16955)
			(xy 250.407298 -48.15942) (xy 250.463032 -48.157383) (xy 250.518469 -48.163483) (xy 250.572426 -48.177589)
			(xy 250.623755 -48.199401) (xy 250.671361 -48.228455) (xy 250.714229 -48.26413) (xy 250.751446 -48.305667)
			(xy 250.782219 -48.35218) (xy 250.805891 -48.402677) (xy 250.821959 -48.456084) (xy 250.830079 -48.51126)
			(xy 250.830588 -48.539146) (xy 250.830079 -48.567032) (xy 250.821959 -48.622208) (xy 250.805891 -48.675615)
			(xy 250.782219 -48.726112) (xy 250.751446 -48.772625) (xy 250.714229 -48.814162) (xy 250.71142 -48.8165)
			(xy 253.187506 -48.8165) (xy 253.191489 -48.763355) (xy 253.203347 -48.711398) (xy 253.222817 -48.661788)
			(xy 253.249462 -48.615633) (xy 253.282689 -48.573965) (xy 253.321754 -48.537715) (xy 253.365786 -48.507691)
			(xy 253.4138 -48.484565) (xy 253.464725 -48.468853) (xy 253.517423 -48.460906) (xy 253.54407 -48.460406)
			(xy 253.57139 -48.460944) (xy 253.625391 -48.469278) (xy 253.677487 -48.485754) (xy 253.726459 -48.509989)
			(xy 253.771159 -48.541412) (xy 253.791212 -48.559974) (xy 253.802834 -48.570371) (xy 253.830768 -48.584195)
			(xy 253.86157 -48.588951) (xy 253.892372 -48.584195) (xy 253.920306 -48.570371) (xy 253.931928 -48.559974)
			(xy 253.951933 -48.541352) (xy 253.996629 -48.509898) (xy 254.04561 -48.485651) (xy 254.097723 -48.469181)
			(xy 254.151742 -48.460877) (xy 254.17907 -48.460406) (xy 254.205724 -48.460849) (xy 254.258436 -48.46879)
			(xy 254.309376 -48.484499) (xy 254.357406 -48.507625) (xy 254.401452 -48.537652) (xy 254.44053 -48.573909)
			(xy 254.473768 -48.615585) (xy 254.500423 -48.661749) (xy 254.5199 -48.711371) (xy 254.531762 -48.763342)
			(xy 254.535746 -48.8165) (xy 254.531762 -48.869658) (xy 254.5199 -48.921629) (xy 254.500423 -48.971251)
			(xy 254.473768 -49.017415) (xy 254.44053 -49.059091) (xy 254.401452 -49.095348) (xy 254.357406 -49.125375)
			(xy 254.309376 -49.148501) (xy 254.258436 -49.16421) (xy 254.205724 -49.172151) (xy 254.17907 -49.172622)
			(xy 254.151749 -49.172113) (xy 254.097747 -49.163771) (xy 254.045651 -49.147287) (xy 253.996679 -49.123047)
			(xy 253.95198 -49.091618) (xy 253.931928 -49.073054) (xy 253.920306 -49.062657) (xy 253.892372 -49.048833)
			(xy 253.86157 -49.044077) (xy 253.830768 -49.048833) (xy 253.802834 -49.062657) (xy 253.791212 -49.073054)
			(xy 253.771179 -49.091645) (xy 253.726492 -49.123106) (xy 253.677519 -49.14736) (xy 253.625411 -49.163837)
			(xy 253.571396 -49.172148) (xy 253.54407 -49.172622) (xy 253.517423 -49.172094) (xy 253.464725 -49.164147)
			(xy 253.4138 -49.148435) (xy 253.365786 -49.125309) (xy 253.321754 -49.095285) (xy 253.282689 -49.059035)
			(xy 253.249462 -49.017367) (xy 253.222817 -48.971212) (xy 253.203347 -48.921602) (xy 253.191489 -48.869645)
			(xy 253.187506 -48.8165) (xy 250.71142 -48.8165) (xy 250.671361 -48.849837) (xy 250.623755 -48.878891)
			(xy 250.572426 -48.900703) (xy 250.518469 -48.914809) (xy 250.463032 -48.920909) (xy 250.407298 -48.918872)
			(xy 250.352455 -48.908742) (xy 250.299671 -48.890735) (xy 250.250071 -48.865234) (xy 250.204713 -48.832783)
			(xy 250.164564 -48.794074) (xy 250.130478 -48.749931) (xy 250.103182 -48.701296) (xy 250.083259 -48.649205)
			(xy 250.071133 -48.594768) (xy 250.067062 -48.539146) (xy 244.32768 -48.539146) (xy 244.32768 -48.775112)
			(xy 244.3507 -48.790171) (xy 244.39256 -48.825857) (xy 244.42886 -48.867186) (xy 244.458846 -48.913302)
			(xy 244.481896 -48.963246) (xy 244.497533 -49.015984) (xy 244.505431 -49.070421) (xy 244.505427 -49.125428)
			(xy 244.50525 -49.126648) (xy 244.766082 -49.126648) (xy 244.770153 -49.071026) (xy 244.782279 -49.016589)
			(xy 244.802202 -48.964498) (xy 244.829498 -48.915863) (xy 244.863584 -48.87172) (xy 244.903733 -48.833011)
			(xy 244.949091 -48.80056) (xy 244.998691 -48.775059) (xy 245.051475 -48.757052) (xy 245.106318 -48.746922)
			(xy 245.162052 -48.744885) (xy 245.217489 -48.750985) (xy 245.271446 -48.765091) (xy 245.322775 -48.786903)
			(xy 245.370381 -48.815957) (xy 245.413249 -48.851632) (xy 245.450466 -48.893169) (xy 245.481239 -48.939682)
			(xy 245.504911 -48.990179) (xy 245.520979 -49.043586) (xy 245.529099 -49.098762) (xy 245.529608 -49.126648)
			(xy 245.529099 -49.154534) (xy 245.520979 -49.20971) (xy 245.504911 -49.263117) (xy 245.481239 -49.313614)
			(xy 245.450466 -49.360127) (xy 245.413249 -49.401664) (xy 245.370381 -49.437339) (xy 245.340874 -49.455347)
			(xy 250.398324 -49.455347) (xy 250.398324 -49.400853) (xy 250.406079 -49.346914) (xy 250.421431 -49.294627)
			(xy 250.444068 -49.245057) (xy 250.473529 -49.199213) (xy 250.509214 -49.158028) (xy 250.550397 -49.122341)
			(xy 250.596239 -49.092878) (xy 250.645808 -49.070238) (xy 250.698094 -49.054883) (xy 250.752033 -49.047126)
			(xy 250.77928 -49.046638) (xy 250.807178 -49.04716) (xy 250.862382 -49.055264) (xy 250.915814 -49.07133)
			(xy 250.966333 -49.095015) (xy 251.012859 -49.125813) (xy 251.054397 -49.163065) (xy 251.090059 -49.205976)
			(xy 251.119083 -49.253628) (xy 251.14085 -49.305003) (xy 251.148342 -49.33188) (xy 251.15221 -49.345218)
			(xy 251.166121 -49.369242) (xy 251.185996 -49.388625) (xy 251.210362 -49.40193) (xy 251.237414 -49.40817)
			(xy 251.265146 -49.406884) (xy 251.291503 -49.398167) (xy 251.303282 -49.390808) (xy 251.326979 -49.375506)
			(xy 251.377927 -49.351298) (xy 251.431885 -49.334859) (xy 251.487677 -49.326548) (xy 251.51588 -49.326038)
			(xy 251.543137 -49.326408) (xy 251.597097 -49.334163) (xy 251.649403 -49.349519) (xy 251.698992 -49.372163)
			(xy 251.744853 -49.401635) (xy 251.786053 -49.437333) (xy 251.821753 -49.478531) (xy 251.851227 -49.52439)
			(xy 251.873874 -49.573978) (xy 251.889233 -49.626284) (xy 251.896991 -49.680243) (xy 251.896991 -49.7167)
			(xy 253.187482 -49.7167) (xy 253.191465 -49.663552) (xy 253.203324 -49.611591) (xy 253.222795 -49.561977)
			(xy 253.249442 -49.51582) (xy 253.282671 -49.474149) (xy 253.321739 -49.437896) (xy 253.365774 -49.40787)
			(xy 253.413792 -49.384742) (xy 253.46472 -49.369029) (xy 253.517421 -49.361082) (xy 253.54407 -49.360582)
			(xy 253.57139 -49.361126) (xy 253.62539 -49.36946) (xy 253.677486 -49.385935) (xy 253.726458 -49.410168)
			(xy 253.771159 -49.441589) (xy 253.791212 -49.46015) (xy 253.802834 -49.470547) (xy 253.830768 -49.484371)
			(xy 253.86157 -49.489127) (xy 253.892372 -49.484371) (xy 253.920306 -49.470547) (xy 253.931928 -49.46015)
			(xy 253.951945 -49.441541) (xy 253.996636 -49.410082) (xy 254.045613 -49.385831) (xy 254.097725 -49.369359)
			(xy 254.151743 -49.361053) (xy 254.17907 -49.360582) (xy 254.205722 -49.361073) (xy 254.258431 -49.369014)
			(xy 254.309367 -49.384722) (xy 254.357394 -49.407846) (xy 254.401437 -49.437871) (xy 254.440513 -49.474125)
			(xy 254.473748 -49.515798) (xy 254.500402 -49.56196) (xy 254.519877 -49.611578) (xy 254.531738 -49.663545)
			(xy 254.535722 -49.7167) (xy 254.531738 -49.769855) (xy 254.519877 -49.821822) (xy 254.500402 -49.87144)
			(xy 254.473748 -49.917602) (xy 254.440513 -49.959275) (xy 254.401437 -49.995529) (xy 254.357394 -50.025554)
			(xy 254.309367 -50.048678) (xy 254.258431 -50.064386) (xy 254.205722 -50.072327) (xy 254.17907 -50.072798)
			(xy 254.151749 -50.072296) (xy 254.097746 -50.063953) (xy 254.045649 -50.047468) (xy 253.996678 -50.023226)
			(xy 253.95198 -49.991795) (xy 253.931928 -49.97323) (xy 253.920306 -49.962833) (xy 253.892372 -49.949009)
			(xy 253.86157 -49.944253) (xy 253.830768 -49.949009) (xy 253.802834 -49.962833) (xy 253.791212 -49.97323)
			(xy 253.771191 -49.991834) (xy 253.7265 -50.02329) (xy 253.677523 -50.047541) (xy 253.625413 -50.064015)
			(xy 253.571396 -50.072324) (xy 253.54407 -50.072798) (xy 253.517421 -50.072318) (xy 253.46472 -50.064371)
			(xy 253.413792 -50.048658) (xy 253.365774 -50.02553) (xy 253.321739 -49.995504) (xy 253.282671 -49.959251)
			(xy 253.249442 -49.91758) (xy 253.222795 -49.871423) (xy 253.203324 -49.821809) (xy 253.191465 -49.769848)
			(xy 253.187482 -49.7167) (xy 251.896991 -49.7167) (xy 251.896991 -49.734757) (xy 251.889233 -49.788716)
			(xy 251.873874 -49.841022) (xy 251.851227 -49.89061) (xy 251.821753 -49.936469) (xy 251.786053 -49.977667)
			(xy 251.744853 -50.013365) (xy 251.698992 -50.042837) (xy 251.649403 -50.065481) (xy 251.597097 -50.080837)
			(xy 251.543137 -50.088592) (xy 251.51588 -50.089054) (xy 251.487981 -50.088574) (xy 251.432775 -50.080464)
			(xy 251.379341 -50.064393) (xy 251.328821 -50.040702) (xy 251.282296 -50.009899) (xy 251.240759 -49.972641)
			(xy 251.205097 -49.929726) (xy 251.176074 -49.88207) (xy 251.154309 -49.830691) (xy 251.146818 -49.803812)
			(xy 251.14287 -49.790502) (xy 251.128968 -49.766488) (xy 251.109107 -49.747111) (xy 251.084757 -49.733806)
			(xy 251.057721 -49.72756) (xy 251.030003 -49.728834) (xy 251.003654 -49.737534) (xy 250.991878 -49.744884)
			(xy 250.968191 -49.760202) (xy 250.917239 -49.784406) (xy 250.863278 -49.800841) (xy 250.807484 -49.809147)
			(xy 250.77928 -49.809654) (xy 250.752033 -49.809074) (xy 250.698094 -49.801317) (xy 250.645808 -49.785962)
			(xy 250.596239 -49.763322) (xy 250.550397 -49.733859) (xy 250.509214 -49.698172) (xy 250.473529 -49.656987)
			(xy 250.444068 -49.611143) (xy 250.421431 -49.561573) (xy 250.406079 -49.509286) (xy 250.398324 -49.455347)
			(xy 245.340874 -49.455347) (xy 245.322775 -49.466393) (xy 245.271446 -49.488205) (xy 245.217489 -49.502311)
			(xy 245.162052 -49.508411) (xy 245.106318 -49.506374) (xy 245.051475 -49.496244) (xy 244.998691 -49.478237)
			(xy 244.949091 -49.452736) (xy 244.903733 -49.420285) (xy 244.863584 -49.381576) (xy 244.829498 -49.337433)
			(xy 244.802202 -49.288798) (xy 244.782279 -49.236707) (xy 244.770153 -49.18227) (xy 244.766082 -49.126648)
			(xy 244.50525 -49.126648) (xy 244.497522 -49.179864) (xy 244.481879 -49.2326) (xy 244.458822 -49.282541)
			(xy 244.42883 -49.328653) (xy 244.392525 -49.369977) (xy 244.35066 -49.405658) (xy 244.32768 -49.42078)
			(xy 244.32768 -50.317146) (xy 245.164862 -50.317146) (xy 245.168933 -50.261524) (xy 245.181059 -50.207087)
			(xy 245.200982 -50.154996) (xy 245.228278 -50.106361) (xy 245.262364 -50.062218) (xy 245.302513 -50.023509)
			(xy 245.347871 -49.991058) (xy 245.397471 -49.965557) (xy 245.450255 -49.94755) (xy 245.505098 -49.93742)
			(xy 245.560832 -49.935383) (xy 245.616269 -49.941483) (xy 245.670226 -49.955589) (xy 245.721555 -49.977401)
			(xy 245.769161 -50.006455) (xy 245.812029 -50.04213) (xy 245.849246 -50.083667) (xy 245.880019 -50.13018)
			(xy 245.903691 -50.180677) (xy 245.919759 -50.234084) (xy 245.927879 -50.28926) (xy 245.928388 -50.317146)
			(xy 246.180862 -50.317146) (xy 246.184933 -50.261524) (xy 246.197059 -50.207087) (xy 246.216982 -50.154996)
			(xy 246.244278 -50.106361) (xy 246.278364 -50.062218) (xy 246.318513 -50.023509) (xy 246.363871 -49.991058)
			(xy 246.413471 -49.965557) (xy 246.466255 -49.94755) (xy 246.521098 -49.93742) (xy 246.576832 -49.935383)
			(xy 246.632269 -49.941483) (xy 246.686226 -49.955589) (xy 246.737555 -49.977401) (xy 246.785161 -50.006455)
			(xy 246.828029 -50.04213) (xy 246.865246 -50.083667) (xy 246.896019 -50.13018) (xy 246.919691 -50.180677)
			(xy 246.935759 -50.234084) (xy 246.943879 -50.28926) (xy 246.944388 -50.317146) (xy 246.943892 -50.344347)
			(xy 250.398324 -50.344347) (xy 250.398324 -50.289853) (xy 250.406079 -50.235914) (xy 250.421431 -50.183627)
			(xy 250.444068 -50.134057) (xy 250.473529 -50.088213) (xy 250.509214 -50.047028) (xy 250.550397 -50.011341)
			(xy 250.596239 -49.981878) (xy 250.645808 -49.959238) (xy 250.698094 -49.943883) (xy 250.752033 -49.936126)
			(xy 250.77928 -49.935638) (xy 250.807178 -49.93616) (xy 250.862382 -49.944264) (xy 250.915814 -49.96033)
			(xy 250.966333 -49.984015) (xy 251.012859 -50.014813) (xy 251.054397 -50.052065) (xy 251.090059 -50.094976)
			(xy 251.119083 -50.142628) (xy 251.14085 -50.194003) (xy 251.148342 -50.22088) (xy 251.15221 -50.234218)
			(xy 251.166121 -50.258242) (xy 251.185996 -50.277625) (xy 251.210362 -50.29093) (xy 251.237414 -50.29717)
			(xy 251.265146 -50.295884) (xy 251.291503 -50.287167) (xy 251.303282 -50.279808) (xy 251.326979 -50.264506)
			(xy 251.377927 -50.240298) (xy 251.431885 -50.223859) (xy 251.487677 -50.215548) (xy 251.51588 -50.215038)
			(xy 251.543137 -50.215408) (xy 251.597097 -50.223163) (xy 251.649403 -50.238519) (xy 251.698992 -50.261163)
			(xy 251.744853 -50.290635) (xy 251.786053 -50.326333) (xy 251.821753 -50.367531) (xy 251.851227 -50.41339)
			(xy 251.873874 -50.462978) (xy 251.889233 -50.515284) (xy 251.896991 -50.569243) (xy 251.896991 -50.6166)
			(xy 253.187504 -50.6166) (xy 253.191487 -50.563455) (xy 253.203345 -50.511497) (xy 253.222815 -50.461887)
			(xy 253.249461 -50.415732) (xy 253.282687 -50.374064) (xy 253.321753 -50.337813) (xy 253.365785 -50.307789)
			(xy 253.4138 -50.284663) (xy 253.464725 -50.268951) (xy 253.517423 -50.261004) (xy 253.54407 -50.260504)
			(xy 253.57139 -50.261042) (xy 253.625391 -50.269376) (xy 253.677487 -50.285853) (xy 253.726459 -50.310087)
			(xy 253.771159 -50.34151) (xy 253.791212 -50.360072) (xy 253.802834 -50.370469) (xy 253.830768 -50.384293)
			(xy 253.86157 -50.389049) (xy 253.892372 -50.384293) (xy 253.920306 -50.370469) (xy 253.931928 -50.360072)
			(xy 253.951933 -50.341449) (xy 253.996628 -50.309995) (xy 254.045609 -50.285748) (xy 254.097723 -50.269279)
			(xy 254.151742 -50.260975) (xy 254.17907 -50.260504) (xy 254.205724 -50.260951) (xy 254.258436 -50.268892)
			(xy 254.309375 -50.284601) (xy 254.357405 -50.307727) (xy 254.40145 -50.337754) (xy 254.43235 -50.366422)
			(xy 255.680462 -50.366422) (xy 255.684533 -50.3108) (xy 255.696659 -50.256363) (xy 255.716582 -50.204272)
			(xy 255.743878 -50.155637) (xy 255.777964 -50.111494) (xy 255.818113 -50.072785) (xy 255.863471 -50.040334)
			(xy 255.913071 -50.014833) (xy 255.965855 -49.996826) (xy 256.020698 -49.986696) (xy 256.076432 -49.984659)
			(xy 256.131869 -49.990759) (xy 256.185826 -50.004865) (xy 256.237155 -50.026677) (xy 256.284761 -50.055731)
			(xy 256.327629 -50.091406) (xy 256.364846 -50.132943) (xy 256.395619 -50.179456) (xy 256.419291 -50.229953)
			(xy 256.435359 -50.28336) (xy 256.443479 -50.338536) (xy 256.443988 -50.366422) (xy 256.443479 -50.394308)
			(xy 256.435359 -50.449484) (xy 256.419291 -50.502891) (xy 256.395619 -50.553388) (xy 256.364846 -50.599901)
			(xy 256.327629 -50.641438) (xy 256.284761 -50.677113) (xy 256.237155 -50.706167) (xy 256.185826 -50.727979)
			(xy 256.131869 -50.742085) (xy 256.076432 -50.748185) (xy 256.020698 -50.746148) (xy 255.965855 -50.736018)
			(xy 255.913071 -50.718011) (xy 255.863471 -50.69251) (xy 255.818113 -50.660059) (xy 255.777964 -50.62135)
			(xy 255.743878 -50.577207) (xy 255.716582 -50.528572) (xy 255.696659 -50.476481) (xy 255.684533 -50.422044)
			(xy 255.680462 -50.366422) (xy 254.43235 -50.366422) (xy 254.440529 -50.37401) (xy 254.473767 -50.415686)
			(xy 254.500421 -50.46185) (xy 254.519898 -50.511472) (xy 254.53176 -50.563442) (xy 254.535744 -50.6166)
			(xy 254.53176 -50.669758) (xy 254.519898 -50.721728) (xy 254.500421 -50.77135) (xy 254.473767 -50.817514)
			(xy 254.440529 -50.85919) (xy 254.40145 -50.895446) (xy 254.357405 -50.925473) (xy 254.309375 -50.948599)
			(xy 254.258436 -50.964308) (xy 254.205724 -50.972249) (xy 254.17907 -50.97272) (xy 254.151749 -50.972212)
			(xy 254.097747 -50.96387) (xy 254.045651 -50.947386) (xy 253.996679 -50.923145) (xy 253.95198 -50.891716)
			(xy 253.931928 -50.873152) (xy 253.920306 -50.862755) (xy 253.892372 -50.848931) (xy 253.86157 -50.844175)
			(xy 253.830768 -50.848931) (xy 253.802834 -50.862755) (xy 253.791212 -50.873152) (xy 253.771179 -50.891743)
			(xy 253.726492 -50.923204) (xy 253.677519 -50.947458) (xy 253.625411 -50.963935) (xy 253.571396 -50.972246)
			(xy 253.54407 -50.97272) (xy 253.517423 -50.972196) (xy 253.464725 -50.964249) (xy 253.4138 -50.948537)
			(xy 253.365785 -50.925411) (xy 253.321753 -50.895387) (xy 253.282687 -50.859136) (xy 253.249461 -50.817468)
			(xy 253.222815 -50.771313) (xy 253.203345 -50.721703) (xy 253.191487 -50.669745) (xy 253.187504 -50.6166)
			(xy 251.896991 -50.6166) (xy 251.896991 -50.623757) (xy 251.889233 -50.677716) (xy 251.873874 -50.730022)
			(xy 251.851227 -50.77961) (xy 251.821753 -50.825469) (xy 251.786053 -50.866667) (xy 251.744853 -50.902365)
			(xy 251.698992 -50.931837) (xy 251.649403 -50.954481) (xy 251.597097 -50.969837) (xy 251.543137 -50.977592)
			(xy 251.51588 -50.978054) (xy 251.487981 -50.977574) (xy 251.432775 -50.969464) (xy 251.379341 -50.953393)
			(xy 251.328821 -50.929702) (xy 251.282296 -50.898899) (xy 251.240759 -50.861641) (xy 251.205097 -50.818726)
			(xy 251.176074 -50.77107) (xy 251.154309 -50.719691) (xy 251.146818 -50.692812) (xy 251.14287 -50.679502)
			(xy 251.128968 -50.655488) (xy 251.109107 -50.636111) (xy 251.084757 -50.622806) (xy 251.057721 -50.61656)
			(xy 251.030003 -50.617834) (xy 251.003654 -50.626534) (xy 250.991878 -50.633884) (xy 250.968191 -50.649202)
			(xy 250.917239 -50.673406) (xy 250.863278 -50.689841) (xy 250.807484 -50.698147) (xy 250.77928 -50.698654)
			(xy 250.752033 -50.698074) (xy 250.698094 -50.690317) (xy 250.645808 -50.674962) (xy 250.596239 -50.652322)
			(xy 250.550397 -50.622859) (xy 250.509214 -50.587172) (xy 250.473529 -50.545987) (xy 250.444068 -50.500143)
			(xy 250.421431 -50.450573) (xy 250.406079 -50.398286) (xy 250.398324 -50.344347) (xy 246.943892 -50.344347)
			(xy 246.943879 -50.345032) (xy 246.935759 -50.400208) (xy 246.919691 -50.453615) (xy 246.896019 -50.504112)
			(xy 246.865246 -50.550625) (xy 246.828029 -50.592162) (xy 246.785161 -50.627837) (xy 246.737555 -50.656891)
			(xy 246.686226 -50.678703) (xy 246.632269 -50.692809) (xy 246.576832 -50.698909) (xy 246.521098 -50.696872)
			(xy 246.466255 -50.686742) (xy 246.413471 -50.668735) (xy 246.363871 -50.643234) (xy 246.318513 -50.610783)
			(xy 246.278364 -50.572074) (xy 246.244278 -50.527931) (xy 246.216982 -50.479296) (xy 246.197059 -50.427205)
			(xy 246.184933 -50.372768) (xy 246.180862 -50.317146) (xy 245.928388 -50.317146) (xy 245.927879 -50.345032)
			(xy 245.919759 -50.400208) (xy 245.903691 -50.453615) (xy 245.880019 -50.504112) (xy 245.849246 -50.550625)
			(xy 245.812029 -50.592162) (xy 245.769161 -50.627837) (xy 245.721555 -50.656891) (xy 245.670226 -50.678703)
			(xy 245.616269 -50.692809) (xy 245.560832 -50.698909) (xy 245.505098 -50.696872) (xy 245.450255 -50.686742)
			(xy 245.397471 -50.668735) (xy 245.347871 -50.643234) (xy 245.302513 -50.610783) (xy 245.262364 -50.572074)
			(xy 245.228278 -50.527931) (xy 245.200982 -50.479296) (xy 245.181059 -50.427205) (xy 245.168933 -50.372768)
			(xy 245.164862 -50.317146) (xy 244.32768 -50.317146) (xy 244.32768 -51.155346) (xy 247.831862 -51.155346)
			(xy 247.835933 -51.099724) (xy 247.848059 -51.045287) (xy 247.867982 -50.993196) (xy 247.895278 -50.944561)
			(xy 247.929364 -50.900418) (xy 247.969513 -50.861709) (xy 248.014871 -50.829258) (xy 248.064471 -50.803757)
			(xy 248.117255 -50.78575) (xy 248.172098 -50.77562) (xy 248.227832 -50.773583) (xy 248.283269 -50.779683)
			(xy 248.337226 -50.793789) (xy 248.388555 -50.815601) (xy 248.436161 -50.844655) (xy 248.479029 -50.88033)
			(xy 248.516246 -50.921867) (xy 248.547019 -50.96838) (xy 248.570691 -51.018877) (xy 248.586759 -51.072284)
			(xy 248.594879 -51.12746) (xy 248.595388 -51.155346) (xy 248.594879 -51.183232) (xy 248.587504 -51.233347)
			(xy 250.398324 -51.233347) (xy 250.398324 -51.178853) (xy 250.406079 -51.124914) (xy 250.421431 -51.072627)
			(xy 250.444068 -51.023057) (xy 250.473529 -50.977213) (xy 250.509214 -50.936028) (xy 250.550397 -50.900341)
			(xy 250.596239 -50.870878) (xy 250.645808 -50.848238) (xy 250.698094 -50.832883) (xy 250.752033 -50.825126)
			(xy 250.77928 -50.824638) (xy 250.807178 -50.82516) (xy 250.862382 -50.833264) (xy 250.915814 -50.84933)
			(xy 250.966333 -50.873015) (xy 251.012859 -50.903813) (xy 251.054397 -50.941065) (xy 251.090059 -50.983976)
			(xy 251.119083 -51.031628) (xy 251.14085 -51.083003) (xy 251.148342 -51.10988) (xy 251.15221 -51.123218)
			(xy 251.166121 -51.147242) (xy 251.185996 -51.166625) (xy 251.210362 -51.17993) (xy 251.237414 -51.18617)
			(xy 251.265146 -51.184884) (xy 251.291503 -51.176167) (xy 251.303282 -51.168808) (xy 251.326979 -51.153506)
			(xy 251.377927 -51.129298) (xy 251.431885 -51.112859) (xy 251.487677 -51.104548) (xy 251.51588 -51.104038)
			(xy 251.543137 -51.104408) (xy 251.597097 -51.112163) (xy 251.649403 -51.127519) (xy 251.698992 -51.150163)
			(xy 251.744853 -51.179635) (xy 251.786053 -51.215333) (xy 251.821753 -51.256531) (xy 251.851227 -51.30239)
			(xy 251.873874 -51.351978) (xy 251.889233 -51.404284) (xy 251.896991 -51.458243) (xy 251.896991 -51.512757)
			(xy 251.896453 -51.5165) (xy 253.187527 -51.5165) (xy 253.191509 -51.463358) (xy 253.203367 -51.411404)
			(xy 253.222835 -51.361797) (xy 253.249479 -51.315645) (xy 253.282704 -51.273979) (xy 253.321767 -51.237731)
			(xy 253.365796 -51.207709) (xy 253.413808 -51.184584) (xy 253.46473 -51.168873) (xy 253.517425 -51.160926)
			(xy 253.54407 -51.160426) (xy 253.57139 -51.160958) (xy 253.625392 -51.169293) (xy 253.677488 -51.18577)
			(xy 253.72646 -51.210006) (xy 253.77116 -51.241431) (xy 253.791212 -51.259994) (xy 253.802834 -51.270391)
			(xy 253.830768 -51.284215) (xy 253.86157 -51.288971) (xy 253.892372 -51.284215) (xy 253.920306 -51.270391)
			(xy 253.931928 -51.259994) (xy 253.951936 -51.241375) (xy 253.99663 -51.20992) (xy 254.045611 -51.185672)
			(xy 254.097724 -51.169202) (xy 254.151743 -51.160897) (xy 254.17907 -51.160426) (xy 254.205725 -51.160829)
			(xy 254.258441 -51.168771) (xy 254.309383 -51.184481) (xy 254.357416 -51.207608) (xy 254.401464 -51.237637)
			(xy 254.440545 -51.273895) (xy 254.473785 -51.315573) (xy 254.494197 -51.350926) (xy 256.493262 -51.350926)
			(xy 256.497333 -51.295304) (xy 256.509459 -51.240867) (xy 256.529382 -51.188776) (xy 256.556678 -51.140141)
			(xy 256.590764 -51.095998) (xy 256.630913 -51.057289) (xy 256.676271 -51.024838) (xy 256.725871 -50.999337)
			(xy 256.778655 -50.98133) (xy 256.833498 -50.9712) (xy 256.889232 -50.969163) (xy 256.944669 -50.975263)
			(xy 256.998626 -50.989369) (xy 257.049955 -51.011181) (xy 257.097561 -51.040235) (xy 257.140429 -51.07591)
			(xy 257.177646 -51.117447) (xy 257.208419 -51.16396) (xy 257.232091 -51.214457) (xy 257.248159 -51.267864)
			(xy 257.256279 -51.32304) (xy 257.256788 -51.350926) (xy 257.256279 -51.378812) (xy 257.248159 -51.433988)
			(xy 257.232091 -51.487395) (xy 257.208419 -51.537892) (xy 257.177646 -51.584405) (xy 257.140429 -51.625942)
			(xy 257.097561 -51.661617) (xy 257.049955 -51.690671) (xy 256.998626 -51.712483) (xy 256.944669 -51.726589)
			(xy 256.889232 -51.732689) (xy 256.833498 -51.730652) (xy 256.778655 -51.720522) (xy 256.725871 -51.702515)
			(xy 256.676271 -51.677014) (xy 256.630913 -51.644563) (xy 256.590764 -51.605854) (xy 256.556678 -51.561711)
			(xy 256.529382 -51.513076) (xy 256.509459 -51.460985) (xy 256.497333 -51.406548) (xy 256.493262 -51.350926)
			(xy 254.494197 -51.350926) (xy 254.500441 -51.361741) (xy 254.519919 -51.411365) (xy 254.531782 -51.463339)
			(xy 254.535766 -51.5165) (xy 254.531782 -51.569661) (xy 254.519919 -51.621635) (xy 254.500441 -51.671259)
			(xy 254.473785 -51.717427) (xy 254.440545 -51.759105) (xy 254.401464 -51.795363) (xy 254.357416 -51.825392)
			(xy 254.309383 -51.848519) (xy 254.258441 -51.864229) (xy 254.205725 -51.872171) (xy 254.17907 -51.872642)
			(xy 254.151748 -51.872156) (xy 254.097744 -51.863811) (xy 254.045646 -51.847323) (xy 253.996675 -51.823077)
			(xy 253.951978 -51.791642) (xy 253.931928 -51.773074) (xy 253.920306 -51.762677) (xy 253.892372 -51.748853)
			(xy 253.86157 -51.744097) (xy 253.830768 -51.748853) (xy 253.802834 -51.762677) (xy 253.791212 -51.773074)
			(xy 253.771182 -51.791668) (xy 253.726494 -51.823128) (xy 253.67752 -51.847382) (xy 253.625411 -51.863857)
			(xy 253.571396 -51.872168) (xy 253.54407 -51.872642) (xy 253.517425 -51.872074) (xy 253.46473 -51.864127)
			(xy 253.413808 -51.848416) (xy 253.365796 -51.825291) (xy 253.321767 -51.795269) (xy 253.282704 -51.759021)
			(xy 253.249479 -51.717355) (xy 253.222835 -51.671203) (xy 253.203367 -51.621596) (xy 253.191509 -51.569642)
			(xy 253.187527 -51.5165) (xy 251.896453 -51.5165) (xy 251.889233 -51.566716) (xy 251.873874 -51.619022)
			(xy 251.851227 -51.66861) (xy 251.821753 -51.714469) (xy 251.786053 -51.755667) (xy 251.744853 -51.791365)
			(xy 251.698992 -51.820837) (xy 251.649403 -51.843481) (xy 251.597097 -51.858837) (xy 251.543137 -51.866592)
			(xy 251.51588 -51.867054) (xy 251.487981 -51.866574) (xy 251.432775 -51.858464) (xy 251.379341 -51.842393)
			(xy 251.328821 -51.818702) (xy 251.282296 -51.787899) (xy 251.240759 -51.750641) (xy 251.205097 -51.707726)
			(xy 251.176074 -51.66007) (xy 251.154309 -51.608691) (xy 251.146818 -51.581812) (xy 251.14287 -51.568502)
			(xy 251.128968 -51.544488) (xy 251.109107 -51.525111) (xy 251.084757 -51.511806) (xy 251.057721 -51.50556)
			(xy 251.030003 -51.506834) (xy 251.003654 -51.515534) (xy 250.991878 -51.522884) (xy 250.968191 -51.538202)
			(xy 250.917239 -51.562406) (xy 250.863278 -51.578841) (xy 250.807484 -51.587147) (xy 250.77928 -51.587654)
			(xy 250.752033 -51.587074) (xy 250.698094 -51.579317) (xy 250.645808 -51.563962) (xy 250.596239 -51.541322)
			(xy 250.550397 -51.511859) (xy 250.509214 -51.476172) (xy 250.473529 -51.434987) (xy 250.444068 -51.389143)
			(xy 250.421431 -51.339573) (xy 250.406079 -51.287286) (xy 250.398324 -51.233347) (xy 248.587504 -51.233347)
			(xy 248.586759 -51.238408) (xy 248.570691 -51.291815) (xy 248.547019 -51.342312) (xy 248.516246 -51.388825)
			(xy 248.479029 -51.430362) (xy 248.436161 -51.466037) (xy 248.388555 -51.495091) (xy 248.337226 -51.516903)
			(xy 248.283269 -51.531009) (xy 248.227832 -51.537109) (xy 248.172098 -51.535072) (xy 248.117255 -51.524942)
			(xy 248.064471 -51.506935) (xy 248.014871 -51.481434) (xy 247.969513 -51.448983) (xy 247.929364 -51.410274)
			(xy 247.895278 -51.366131) (xy 247.867982 -51.317496) (xy 247.848059 -51.265405) (xy 247.835933 -51.210968)
			(xy 247.831862 -51.155346) (xy 244.32768 -51.155346) (xy 244.32768 -52.939696) (xy 256.159252 -52.939696)
			(xy 256.163323 -52.884074) (xy 256.175449 -52.829637) (xy 256.195372 -52.777546) (xy 256.222668 -52.728911)
			(xy 256.256754 -52.684768) (xy 256.296903 -52.646059) (xy 256.342261 -52.613608) (xy 256.391861 -52.588107)
			(xy 256.444645 -52.5701) (xy 256.499488 -52.55997) (xy 256.555222 -52.557933) (xy 256.610659 -52.564033)
			(xy 256.664616 -52.578139) (xy 256.715945 -52.599951) (xy 256.763551 -52.629005) (xy 256.806419 -52.66468)
			(xy 256.843636 -52.706217) (xy 256.874409 -52.75273) (xy 256.898081 -52.803227) (xy 256.914149 -52.856634)
			(xy 256.922269 -52.91181) (xy 256.922778 -52.939696) (xy 256.922269 -52.967582) (xy 256.914149 -53.022758)
			(xy 256.898081 -53.076165) (xy 256.874409 -53.126662) (xy 256.843636 -53.173175) (xy 256.806419 -53.214712)
			(xy 256.763551 -53.250387) (xy 256.715945 -53.279441) (xy 256.664616 -53.301253) (xy 256.610659 -53.315359)
			(xy 256.555222 -53.321459) (xy 256.499488 -53.319422) (xy 256.444645 -53.309292) (xy 256.391861 -53.291285)
			(xy 256.342261 -53.265784) (xy 256.296903 -53.233333) (xy 256.256754 -53.194624) (xy 256.222668 -53.150481)
			(xy 256.195372 -53.101846) (xy 256.175449 -53.049755) (xy 256.163323 -52.995318) (xy 256.159252 -52.939696)
			(xy 244.32768 -52.939696) (xy 244.32768 -53.84038) (xy 244.333522 -53.851556) (xy 244.346486 -53.877306)
			(xy 244.36483 -53.931958) (xy 244.374125 -53.988851) (xy 244.374129 -54.046499) (xy 244.364842 -54.103394)
			(xy 244.346505 -54.158048) (xy 244.333522 -54.183788) (xy 244.32768 -54.194964) (xy 244.32768 -55.022242)
			(xy 248.993912 -55.022242) (xy 248.997983 -54.96662) (xy 249.010109 -54.912183) (xy 249.030032 -54.860092)
			(xy 249.057328 -54.811457) (xy 249.091414 -54.767314) (xy 249.131563 -54.728605) (xy 249.176921 -54.696154)
			(xy 249.226521 -54.670653) (xy 249.279305 -54.652646) (xy 249.334148 -54.642516) (xy 249.389882 -54.640479)
			(xy 249.445319 -54.646579) (xy 249.499276 -54.660685) (xy 249.550605 -54.682497) (xy 249.598211 -54.711551)
			(xy 249.641079 -54.747226) (xy 249.678296 -54.788763) (xy 249.709069 -54.835276) (xy 249.732741 -54.885773)
			(xy 249.748809 -54.93918) (xy 249.756929 -54.994356) (xy 249.757438 -55.022242) (xy 249.756929 -55.050128)
			(xy 249.753557 -55.073042) (xy 251.127512 -55.073042) (xy 251.131583 -55.01742) (xy 251.143709 -54.962983)
			(xy 251.163632 -54.910892) (xy 251.190928 -54.862257) (xy 251.225014 -54.818114) (xy 251.265163 -54.779405)
			(xy 251.310521 -54.746954) (xy 251.360121 -54.721453) (xy 251.412905 -54.703446) (xy 251.467748 -54.693316)
			(xy 251.523482 -54.691279) (xy 251.578919 -54.697379) (xy 251.632876 -54.711485) (xy 251.684205 -54.733297)
			(xy 251.731811 -54.762351) (xy 251.774679 -54.798026) (xy 251.811896 -54.839563) (xy 251.842669 -54.886076)
			(xy 251.866341 -54.936573) (xy 251.882409 -54.98998) (xy 251.890529 -55.045156) (xy 251.891038 -55.073042)
			(xy 251.890529 -55.100928) (xy 251.882409 -55.156104) (xy 251.866341 -55.209511) (xy 251.842669 -55.260008)
			(xy 251.811896 -55.306521) (xy 251.774679 -55.348058) (xy 251.731811 -55.383733) (xy 251.684205 -55.412787)
			(xy 251.632876 -55.434599) (xy 251.578919 -55.448705) (xy 251.523482 -55.454805) (xy 251.467748 -55.452768)
			(xy 251.412905 -55.442638) (xy 251.360121 -55.424631) (xy 251.310521 -55.39913) (xy 251.265163 -55.366679)
			(xy 251.225014 -55.32797) (xy 251.190928 -55.283827) (xy 251.163632 -55.235192) (xy 251.143709 -55.183101)
			(xy 251.131583 -55.128664) (xy 251.127512 -55.073042) (xy 249.753557 -55.073042) (xy 249.748809 -55.105304)
			(xy 249.732741 -55.158711) (xy 249.709069 -55.209208) (xy 249.678296 -55.255721) (xy 249.641079 -55.297258)
			(xy 249.598211 -55.332933) (xy 249.550605 -55.361987) (xy 249.499276 -55.383799) (xy 249.445319 -55.397905)
			(xy 249.389882 -55.404005) (xy 249.334148 -55.401968) (xy 249.279305 -55.391838) (xy 249.226521 -55.373831)
			(xy 249.176921 -55.34833) (xy 249.131563 -55.315879) (xy 249.091414 -55.27717) (xy 249.057328 -55.233027)
			(xy 249.030032 -55.184392) (xy 249.010109 -55.132301) (xy 248.997983 -55.077864) (xy 248.993912 -55.022242)
			(xy 244.32768 -55.022242) (xy 244.32768 -56.971946) (xy 246.30888 -58.953146) (xy 253.072392 -58.953146)
		)
		(stroke
			(width 0)
			(type solid)
		)
		(fill yes)
		(layer "In11.Cu")
		(net "GND")
	)
	(gr_poly
		(pts
			(xy 381.665734 -222.150432) (xy 381.683436 -222.150065) (xy 381.718302 -222.143909) (xy 381.751568 -222.131791)
			(xy 381.76708 -222.123254) (xy 381.800754 -222.104366) (xy 381.871286 -222.072947) (xy 381.944715 -222.049075)
			(xy 382.020239 -222.033011) (xy 382.097028 -222.024931) (xy 382.135634 -222.024448) (xy 382.169416 -222.02521)
			(xy 382.182658 -222.025409) (xy 382.208531 -222.019807) (xy 382.23209 -222.007733) (xy 382.251747 -221.99)
			(xy 382.266176 -221.967805) (xy 382.274404 -221.942643) (xy 382.275588 -221.929452) (xy 382.277363 -221.905237)
			(xy 382.287121 -221.857676) (xy 382.303732 -221.812054) (xy 382.326839 -221.769353) (xy 382.355943 -221.730492)
			(xy 382.39042 -221.696307) (xy 382.4097 -221.681548) (xy 382.4097 -221.530164) (xy 382.409197 -221.515751)
			(xy 382.40114 -221.488074) (xy 382.385676 -221.463747) (xy 382.364036 -221.444704) (xy 382.33794 -221.43246)
			(xy 382.309464 -221.427987) (xy 382.28087 -221.431643) (xy 382.26746 -221.436946) (xy 382.24658 -221.445628)
			(xy 382.203042 -221.457848) (xy 382.158244 -221.464018) (xy 382.135634 -221.464378) (xy 382.109662 -221.463898)
			(xy 382.058358 -221.455777) (xy 382.008955 -221.439731) (xy 381.962671 -221.416153) (xy 381.920645 -221.385625)
			(xy 381.883912 -221.348899) (xy 381.853377 -221.306879) (xy 381.829792 -221.260599) (xy 381.813736 -221.211199)
			(xy 381.805607 -221.159896) (xy 381.80518 -221.133924) (xy 381.805791 -221.105943) (xy 381.815239 -221.050784)
			(xy 381.823976 -221.024196) (xy 381.831596 -221.002098) (xy 381.627888 -220.649038) (xy 381.605028 -220.64472)
			(xy 381.580084 -220.639583) (xy 381.532051 -220.622663) (xy 381.487183 -220.598573) (xy 381.446542 -220.567886)
			(xy 381.41109 -220.531326) (xy 381.381667 -220.48976) (xy 381.358969 -220.444172) (xy 381.343535 -220.395641)
			(xy 381.335729 -220.345317) (xy 381.33528 -220.319854) (xy 381.335789 -220.293887) (xy 381.343914 -220.242592)
			(xy 381.359962 -220.193199) (xy 381.38354 -220.146925) (xy 381.414066 -220.104909) (xy 381.450789 -220.068186)
			(xy 381.492805 -220.03766) (xy 381.539079 -220.014082) (xy 381.588472 -219.998034) (xy 381.639767 -219.989909)
			(xy 381.691701 -219.989909) (xy 381.742996 -219.998034) (xy 381.792389 -220.014082) (xy 381.838663 -220.03766)
			(xy 381.880679 -220.068186) (xy 381.917402 -220.104909) (xy 381.947928 -220.146925) (xy 381.971506 -220.193199)
			(xy 381.987554 -220.242592) (xy 381.995679 -220.293887) (xy 381.996188 -220.319854) (xy 381.995579 -220.347835)
			(xy 381.986134 -220.402995) (xy 381.977392 -220.429582) (xy 381.969772 -220.451426) (xy 382.173734 -220.80474)
			(xy 382.196594 -220.809058) (xy 382.214811 -220.812744) (xy 382.25033 -220.823691) (xy 382.26746 -220.830902)
			(xy 382.280874 -220.836211) (xy 382.309474 -220.839899) (xy 382.337965 -220.835443) (xy 382.364073 -220.823199)
			(xy 382.385717 -220.804145) (xy 382.401171 -220.779799) (xy 382.409201 -220.752103) (xy 382.4097 -220.737684)
			(xy 382.4097 -220.5863) (xy 382.389181 -220.570601) (xy 382.35282 -220.533903) (xy 382.322608 -220.491996)
			(xy 382.299283 -220.4459) (xy 382.283412 -220.396737) (xy 382.27538 -220.345704) (xy 382.275385 -220.294042)
			(xy 382.283424 -220.24301) (xy 382.299304 -220.193849) (xy 382.322637 -220.147757) (xy 382.352855 -220.105855)
			(xy 382.389223 -220.069163) (xy 382.4097 -220.053408) (xy 382.4097 -219.902278) (xy 382.409199 -219.887864)
			(xy 382.401144 -219.860183) (xy 382.385681 -219.835853) (xy 382.36404 -219.816807) (xy 382.337942 -219.80456)
			(xy 382.309462 -219.800087) (xy 382.280866 -219.803744) (xy 382.26746 -219.80906) (xy 382.24658 -219.817744)
			(xy 382.203043 -219.829967) (xy 382.158245 -219.836139) (xy 382.135634 -219.836492) (xy 382.10966 -219.836012)
			(xy 382.058351 -219.82789) (xy 382.008944 -219.811841) (xy 381.962656 -219.788261) (xy 381.920628 -219.757729)
			(xy 381.883893 -219.720998) (xy 381.853357 -219.678973) (xy 381.829772 -219.632687) (xy 381.813718 -219.583282)
			(xy 381.805591 -219.531974) (xy 381.805591 -219.480026) (xy 381.813718 -219.428718) (xy 381.829772 -219.379313)
			(xy 381.853357 -219.333027) (xy 381.883893 -219.291002) (xy 381.920628 -219.254271) (xy 381.962656 -219.223739)
			(xy 382.008944 -219.200159) (xy 382.058351 -219.18411) (xy 382.10966 -219.175988) (xy 382.135634 -219.175584)
			(xy 382.158243 -219.175956) (xy 382.20304 -219.182125) (xy 382.246576 -219.194344) (xy 382.26746 -219.203016)
			(xy 382.280875 -219.208325) (xy 382.309476 -219.212011) (xy 382.337967 -219.207556) (xy 382.364076 -219.195312)
			(xy 382.385722 -219.176258) (xy 382.401178 -219.151913) (xy 382.409212 -219.124217) (xy 382.4097 -219.109798)
			(xy 382.4097 -218.958414) (xy 382.389205 -218.942724) (xy 382.352887 -218.906051) (xy 382.322712 -218.864178)
			(xy 382.299413 -218.818122) (xy 382.283558 -218.769005) (xy 382.275532 -218.71802) (xy 382.27553 -218.666406)
			(xy 382.283552 -218.615421) (xy 382.299403 -218.566302) (xy 382.322698 -218.520245) (xy 382.35287 -218.478369)
			(xy 382.389185 -218.441693) (xy 382.4097 -218.42603) (xy 382.4097 -218.274646) (xy 382.409194 -218.260235)
			(xy 382.401134 -218.232563) (xy 382.38567 -218.20824) (xy 382.364032 -218.189201) (xy 382.337938 -218.176959)
			(xy 382.309465 -218.172487) (xy 382.280876 -218.176141) (xy 382.26746 -218.181428) (xy 382.24658 -218.19011)
			(xy 382.203042 -218.202331) (xy 382.158244 -218.208502) (xy 382.135634 -218.20886) (xy 382.109663 -218.20838)
			(xy 382.058359 -218.200259) (xy 382.008958 -218.184212) (xy 381.962675 -218.160634) (xy 381.920651 -218.130106)
			(xy 381.88392 -218.09338) (xy 381.853387 -218.051359) (xy 381.829803 -218.005079) (xy 381.81375 -217.95568)
			(xy 381.805623 -217.904377) (xy 381.80518 -217.878406) (xy 381.805793 -217.850426) (xy 381.815243 -217.795268)
			(xy 381.823976 -217.768678) (xy 381.831596 -217.74658) (xy 381.627888 -217.39352) (xy 381.604774 -217.389202)
			(xy 381.579828 -217.384067) (xy 381.531791 -217.367152) (xy 381.486919 -217.343065) (xy 381.446273 -217.312378)
			(xy 381.410818 -217.275818) (xy 381.381392 -217.234251) (xy 381.358693 -217.188661) (xy 381.343258 -217.140127)
			(xy 381.335454 -217.0898) (xy 381.335026 -217.064336) (xy 381.335535 -217.038369) (xy 381.34366 -216.987074)
			(xy 381.359708 -216.937681) (xy 381.383286 -216.891407) (xy 381.413812 -216.849391) (xy 381.450535 -216.812668)
			(xy 381.492551 -216.782142) (xy 381.538825 -216.758564) (xy 381.588218 -216.742516) (xy 381.639513 -216.734391)
			(xy 381.691447 -216.734391) (xy 381.742742 -216.742516) (xy 381.792135 -216.758564) (xy 381.838409 -216.782142)
			(xy 381.880425 -216.812668) (xy 381.917148 -216.849391) (xy 381.947674 -216.891407) (xy 381.971252 -216.937681)
			(xy 381.9873 -216.987074) (xy 381.995425 -217.038369) (xy 381.995934 -217.064336) (xy 381.995372 -217.092243)
			(xy 381.98605 -217.147274) (xy 381.977392 -217.17381) (xy 381.969518 -217.195654) (xy 382.173734 -217.549222)
			(xy 382.196594 -217.55354) (xy 382.214811 -217.557226) (xy 382.250331 -217.568172) (xy 382.26746 -217.575384)
			(xy 382.280874 -217.580694) (xy 382.309472 -217.584382) (xy 382.337961 -217.579926) (xy 382.364068 -217.567682)
			(xy 382.38571 -217.548627) (xy 382.40116 -217.52428) (xy 382.409187 -217.496584) (xy 382.4097 -217.482166)
			(xy 382.4097 -217.330528) (xy 382.389204 -217.314838) (xy 382.352884 -217.278164) (xy 382.322706 -217.236291)
			(xy 382.299406 -217.190234) (xy 382.283549 -217.141115) (xy 382.275521 -217.090129) (xy 382.275518 -217.038514)
			(xy 382.283539 -216.987526) (xy 382.29939 -216.938405) (xy 382.322684 -216.892346) (xy 382.352856 -216.850468)
			(xy 382.389172 -216.81379) (xy 382.4097 -216.798144) (xy 382.4097 -216.64676) (xy 382.409196 -216.632348)
			(xy 382.401138 -216.604672) (xy 382.385675 -216.580346) (xy 382.364035 -216.561304) (xy 382.33794 -216.54906)
			(xy 382.309464 -216.544587) (xy 382.280872 -216.548242) (xy 382.26746 -216.553542) (xy 382.24658 -216.562224)
			(xy 382.203042 -216.574444) (xy 382.158244 -216.580615) (xy 382.135634 -216.580974) (xy 382.109661 -216.580494)
			(xy 382.058355 -216.572372) (xy 382.008951 -216.556325) (xy 381.962666 -216.532745) (xy 381.920639 -216.502215)
			(xy 381.883907 -216.465486) (xy 381.853373 -216.423463) (xy 381.829789 -216.37718) (xy 381.813736 -216.327778)
			(xy 381.805609 -216.276473) (xy 381.805609 -216.224527) (xy 381.813736 -216.173222) (xy 381.829789 -216.12382)
			(xy 381.853373 -216.077537) (xy 381.883907 -216.035514) (xy 381.920639 -215.998785) (xy 381.962666 -215.968255)
			(xy 382.008951 -215.944675) (xy 382.058355 -215.928628) (xy 382.109661 -215.920506) (xy 382.135634 -215.920066)
			(xy 382.158243 -215.920438) (xy 382.203039 -215.926609) (xy 382.246575 -215.93883) (xy 382.26746 -215.947498)
			(xy 382.280874 -215.952807) (xy 382.309474 -215.956495) (xy 382.337964 -215.952039) (xy 382.364072 -215.939796)
			(xy 382.385715 -215.920741) (xy 382.401168 -215.896395) (xy 382.409198 -215.868699) (xy 382.4097 -215.85428)
			(xy 382.4097 -215.425528) (xy 381.92202 -214.937848) (xy 375.6406 -214.937848) (xy 375.24436 -215.334088)
			(xy 375.24436 -215.873584) (xy 375.24491 -215.888707) (xy 375.253766 -215.917628) (xy 375.270705 -215.942686)
			(xy 375.294242 -215.961683) (xy 375.32231 -215.972951) (xy 375.352449 -215.975503) (xy 375.382013 -215.969115)
			(xy 375.39549 -215.96223) (xy 375.420325 -215.948962) (xy 375.473394 -215.930158) (xy 375.528883 -215.920621)
			(xy 375.557034 -215.920066) (xy 375.582998 -215.920578) (xy 375.634286 -215.928706) (xy 375.683671 -215.944756)
			(xy 375.729937 -215.968335) (xy 375.771946 -215.99886) (xy 375.808663 -216.03558) (xy 375.839183 -216.077592)
			(xy 375.862757 -216.123861) (xy 375.878802 -216.173247) (xy 375.886925 -216.224536) (xy 375.886925 -216.276464)
			(xy 375.886921 -216.276487) (xy 376.166889 -216.276487) (xy 376.166889 -216.224553) (xy 376.175014 -216.173258)
			(xy 376.191062 -216.123865) (xy 376.21464 -216.077591) (xy 376.245166 -216.035575) (xy 376.281889 -215.998852)
			(xy 376.323905 -215.968326) (xy 376.370179 -215.944748) (xy 376.419572 -215.9287) (xy 376.470867 -215.920575)
			(xy 376.522801 -215.920575) (xy 376.574096 -215.9287) (xy 376.623489 -215.944748) (xy 376.669763 -215.968326)
			(xy 376.711779 -215.998852) (xy 376.748502 -216.035575) (xy 376.779028 -216.077591) (xy 376.802606 -216.123865)
			(xy 376.818654 -216.173258) (xy 376.826779 -216.224553) (xy 376.827288 -216.25052) (xy 376.826779 -216.276487)
			(xy 377.106689 -216.276487) (xy 377.106689 -216.224553) (xy 377.114814 -216.173258) (xy 377.130862 -216.123865)
			(xy 377.15444 -216.077591) (xy 377.184966 -216.035575) (xy 377.221689 -215.998852) (xy 377.263705 -215.968326)
			(xy 377.309979 -215.944748) (xy 377.359372 -215.9287) (xy 377.410667 -215.920575) (xy 377.462601 -215.920575)
			(xy 377.513896 -215.9287) (xy 377.563289 -215.944748) (xy 377.609563 -215.968326) (xy 377.651579 -215.998852)
			(xy 377.688302 -216.035575) (xy 377.718828 -216.077591) (xy 377.742406 -216.123865) (xy 377.758454 -216.173258)
			(xy 377.766579 -216.224553) (xy 377.767088 -216.25052) (xy 377.766579 -216.276487) (xy 378.046489 -216.276487)
			(xy 378.046489 -216.224553) (xy 378.054614 -216.173258) (xy 378.070662 -216.123865) (xy 378.09424 -216.077591)
			(xy 378.124766 -216.035575) (xy 378.161489 -215.998852) (xy 378.203505 -215.968326) (xy 378.249779 -215.944748)
			(xy 378.299172 -215.9287) (xy 378.350467 -215.920575) (xy 378.402401 -215.920575) (xy 378.453696 -215.9287)
			(xy 378.503089 -215.944748) (xy 378.549363 -215.968326) (xy 378.591379 -215.998852) (xy 378.628102 -216.035575)
			(xy 378.658628 -216.077591) (xy 378.682206 -216.123865) (xy 378.698254 -216.173258) (xy 378.706379 -216.224553)
			(xy 378.706888 -216.25052) (xy 378.706379 -216.276487) (xy 378.986289 -216.276487) (xy 378.986289 -216.224553)
			(xy 378.994414 -216.173258) (xy 379.010462 -216.123865) (xy 379.03404 -216.077591) (xy 379.064566 -216.035575)
			(xy 379.101289 -215.998852) (xy 379.143305 -215.968326) (xy 379.189579 -215.944748) (xy 379.238972 -215.9287)
			(xy 379.290267 -215.920575) (xy 379.342201 -215.920575) (xy 379.393496 -215.9287) (xy 379.442889 -215.944748)
			(xy 379.489163 -215.968326) (xy 379.531179 -215.998852) (xy 379.567902 -216.035575) (xy 379.598428 -216.077591)
			(xy 379.622006 -216.123865) (xy 379.638054 -216.173258) (xy 379.646179 -216.224553) (xy 379.646688 -216.25052)
			(xy 379.646179 -216.276487) (xy 379.926089 -216.276487) (xy 379.926089 -216.224553) (xy 379.934214 -216.173258)
			(xy 379.950262 -216.123865) (xy 379.97384 -216.077591) (xy 380.004366 -216.035575) (xy 380.041089 -215.998852)
			(xy 380.083105 -215.968326) (xy 380.129379 -215.944748) (xy 380.178772 -215.9287) (xy 380.230067 -215.920575)
			(xy 380.282001 -215.920575) (xy 380.333296 -215.9287) (xy 380.382689 -215.944748) (xy 380.428963 -215.968326)
			(xy 380.470979 -215.998852) (xy 380.507702 -216.035575) (xy 380.538228 -216.077591) (xy 380.561806 -216.123865)
			(xy 380.577854 -216.173258) (xy 380.585979 -216.224553) (xy 380.586488 -216.25052) (xy 380.585979 -216.276487)
			(xy 380.865889 -216.276487) (xy 380.865889 -216.224553) (xy 380.874014 -216.173258) (xy 380.890062 -216.123865)
			(xy 380.91364 -216.077591) (xy 380.944166 -216.035575) (xy 380.980889 -215.998852) (xy 381.022905 -215.968326)
			(xy 381.069179 -215.944748) (xy 381.118572 -215.9287) (xy 381.169867 -215.920575) (xy 381.221801 -215.920575)
			(xy 381.273096 -215.9287) (xy 381.322489 -215.944748) (xy 381.368763 -215.968326) (xy 381.410779 -215.998852)
			(xy 381.447502 -216.035575) (xy 381.478028 -216.077591) (xy 381.501606 -216.123865) (xy 381.517654 -216.173258)
			(xy 381.525779 -216.224553) (xy 381.526288 -216.25052) (xy 381.525779 -216.276487) (xy 381.517654 -216.327782)
			(xy 381.501606 -216.377175) (xy 381.478028 -216.423449) (xy 381.447502 -216.465465) (xy 381.410779 -216.502188)
			(xy 381.368763 -216.532714) (xy 381.322489 -216.556292) (xy 381.273096 -216.57234) (xy 381.221801 -216.580465)
			(xy 381.169867 -216.580465) (xy 381.118572 -216.57234) (xy 381.069179 -216.556292) (xy 381.022905 -216.532714)
			(xy 380.980889 -216.502188) (xy 380.944166 -216.465465) (xy 380.91364 -216.423449) (xy 380.890062 -216.377175)
			(xy 380.874014 -216.327782) (xy 380.865889 -216.276487) (xy 380.585979 -216.276487) (xy 380.577854 -216.327782)
			(xy 380.561806 -216.377175) (xy 380.538228 -216.423449) (xy 380.507702 -216.465465) (xy 380.470979 -216.502188)
			(xy 380.428963 -216.532714) (xy 380.382689 -216.556292) (xy 380.333296 -216.57234) (xy 380.282001 -216.580465)
			(xy 380.230067 -216.580465) (xy 380.178772 -216.57234) (xy 380.129379 -216.556292) (xy 380.083105 -216.532714)
			(xy 380.041089 -216.502188) (xy 380.004366 -216.465465) (xy 379.97384 -216.423449) (xy 379.950262 -216.377175)
			(xy 379.934214 -216.327782) (xy 379.926089 -216.276487) (xy 379.646179 -216.276487) (xy 379.638054 -216.327782)
			(xy 379.622006 -216.377175) (xy 379.598428 -216.423449) (xy 379.567902 -216.465465) (xy 379.531179 -216.502188)
			(xy 379.489163 -216.532714) (xy 379.442889 -216.556292) (xy 379.393496 -216.57234) (xy 379.342201 -216.580465)
			(xy 379.290267 -216.580465) (xy 379.238972 -216.57234) (xy 379.189579 -216.556292) (xy 379.143305 -216.532714)
			(xy 379.101289 -216.502188) (xy 379.064566 -216.465465) (xy 379.03404 -216.423449) (xy 379.010462 -216.377175)
			(xy 378.994414 -216.327782) (xy 378.986289 -216.276487) (xy 378.706379 -216.276487) (xy 378.698254 -216.327782)
			(xy 378.682206 -216.377175) (xy 378.658628 -216.423449) (xy 378.628102 -216.465465) (xy 378.591379 -216.502188)
			(xy 378.549363 -216.532714) (xy 378.503089 -216.556292) (xy 378.453696 -216.57234) (xy 378.402401 -216.580465)
			(xy 378.350467 -216.580465) (xy 378.299172 -216.57234) (xy 378.249779 -216.556292) (xy 378.203505 -216.532714)
			(xy 378.161489 -216.502188) (xy 378.124766 -216.465465) (xy 378.09424 -216.423449) (xy 378.070662 -216.377175)
			(xy 378.054614 -216.327782) (xy 378.046489 -216.276487) (xy 377.766579 -216.276487) (xy 377.758454 -216.327782)
			(xy 377.742406 -216.377175) (xy 377.718828 -216.423449) (xy 377.688302 -216.465465) (xy 377.651579 -216.502188)
			(xy 377.609563 -216.532714) (xy 377.563289 -216.556292) (xy 377.513896 -216.57234) (xy 377.462601 -216.580465)
			(xy 377.410667 -216.580465) (xy 377.359372 -216.57234) (xy 377.309979 -216.556292) (xy 377.263705 -216.532714)
			(xy 377.221689 -216.502188) (xy 377.184966 -216.465465) (xy 377.15444 -216.423449) (xy 377.130862 -216.377175)
			(xy 377.114814 -216.327782) (xy 377.106689 -216.276487) (xy 376.826779 -216.276487) (xy 376.818654 -216.327782)
			(xy 376.802606 -216.377175) (xy 376.779028 -216.423449) (xy 376.748502 -216.465465) (xy 376.711779 -216.502188)
			(xy 376.669763 -216.532714) (xy 376.623489 -216.556292) (xy 376.574096 -216.57234) (xy 376.522801 -216.580465)
			(xy 376.470867 -216.580465) (xy 376.419572 -216.57234) (xy 376.370179 -216.556292) (xy 376.323905 -216.532714)
			(xy 376.281889 -216.502188) (xy 376.245166 -216.465465) (xy 376.21464 -216.423449) (xy 376.191062 -216.377175)
			(xy 376.175014 -216.327782) (xy 376.166889 -216.276487) (xy 375.886921 -216.276487) (xy 375.878802 -216.327753)
			(xy 375.862757 -216.377139) (xy 375.839183 -216.423408) (xy 375.808663 -216.46542) (xy 375.771946 -216.50214)
			(xy 375.729937 -216.532665) (xy 375.683671 -216.556244) (xy 375.634286 -216.572294) (xy 375.582998 -216.580422)
			(xy 375.557034 -216.580974) (xy 375.528885 -216.580402) (xy 375.473401 -216.570859) (xy 375.420334 -216.552059)
			(xy 375.39549 -216.53881) (xy 375.382023 -216.531926) (xy 375.352471 -216.525568) (xy 375.322352 -216.528138)
			(xy 375.294305 -216.539411) (xy 375.270786 -216.5584) (xy 375.253854 -216.583442) (xy 375.244994 -216.612342)
			(xy 375.24436 -216.627456) (xy 375.24436 -216.77376) (xy 375.266472 -216.786234) (xy 375.306919 -216.816916)
			(xy 375.342193 -216.853426) (xy 375.371464 -216.894905) (xy 375.394043 -216.940375) (xy 375.409396 -216.988764)
			(xy 375.417163 -217.038934) (xy 375.417162 -217.064336) (xy 375.696226 -217.064336) (xy 375.696735 -217.038369)
			(xy 375.70486 -216.987074) (xy 375.720908 -216.937681) (xy 375.744486 -216.891407) (xy 375.775012 -216.849391)
			(xy 375.811735 -216.812668) (xy 375.853751 -216.782142) (xy 375.900025 -216.758564) (xy 375.949418 -216.742516)
			(xy 376.000713 -216.734391) (xy 376.052647 -216.734391) (xy 376.103942 -216.742516) (xy 376.153335 -216.758564)
			(xy 376.199609 -216.782142) (xy 376.241625 -216.812668) (xy 376.278348 -216.849391) (xy 376.308874 -216.891407)
			(xy 376.332452 -216.937681) (xy 376.3485 -216.987074) (xy 376.356625 -217.038369) (xy 376.357134 -217.064336)
			(xy 376.356634 -217.090303) (xy 376.636789 -217.090303) (xy 376.636789 -217.038369) (xy 376.644914 -216.987074)
			(xy 376.660962 -216.937681) (xy 376.68454 -216.891407) (xy 376.715066 -216.849391) (xy 376.751789 -216.812668)
			(xy 376.793805 -216.782142) (xy 376.840079 -216.758564) (xy 376.889472 -216.742516) (xy 376.940767 -216.734391)
			(xy 376.992701 -216.734391) (xy 377.043996 -216.742516) (xy 377.093389 -216.758564) (xy 377.139663 -216.782142)
			(xy 377.181679 -216.812668) (xy 377.218402 -216.849391) (xy 377.248928 -216.891407) (xy 377.272506 -216.937681)
			(xy 377.288554 -216.987074) (xy 377.296679 -217.038369) (xy 377.297188 -217.064336) (xy 377.575826 -217.064336)
			(xy 377.576335 -217.038369) (xy 377.58446 -216.987074) (xy 377.600508 -216.937681) (xy 377.624086 -216.891407)
			(xy 377.654612 -216.849391) (xy 377.691335 -216.812668) (xy 377.733351 -216.782142) (xy 377.779625 -216.758564)
			(xy 377.829018 -216.742516) (xy 377.880313 -216.734391) (xy 377.932247 -216.734391) (xy 377.983542 -216.742516)
			(xy 378.032935 -216.758564) (xy 378.079209 -216.782142) (xy 378.121225 -216.812668) (xy 378.157948 -216.849391)
			(xy 378.188474 -216.891407) (xy 378.212052 -216.937681) (xy 378.2281 -216.987074) (xy 378.236225 -217.038369)
			(xy 378.236734 -217.064336) (xy 378.236234 -217.090303) (xy 378.516389 -217.090303) (xy 378.516389 -217.038369)
			(xy 378.524514 -216.987074) (xy 378.540562 -216.937681) (xy 378.56414 -216.891407) (xy 378.594666 -216.849391)
			(xy 378.631389 -216.812668) (xy 378.673405 -216.782142) (xy 378.719679 -216.758564) (xy 378.769072 -216.742516)
			(xy 378.820367 -216.734391) (xy 378.872301 -216.734391) (xy 378.923596 -216.742516) (xy 378.972989 -216.758564)
			(xy 379.019263 -216.782142) (xy 379.061279 -216.812668) (xy 379.098002 -216.849391) (xy 379.128528 -216.891407)
			(xy 379.152106 -216.937681) (xy 379.168154 -216.987074) (xy 379.176279 -217.038369) (xy 379.176788 -217.064336)
			(xy 379.455426 -217.064336) (xy 379.455935 -217.038369) (xy 379.46406 -216.987074) (xy 379.480108 -216.937681)
			(xy 379.503686 -216.891407) (xy 379.534212 -216.849391) (xy 379.570935 -216.812668) (xy 379.612951 -216.782142)
			(xy 379.659225 -216.758564) (xy 379.708618 -216.742516) (xy 379.759913 -216.734391) (xy 379.811847 -216.734391)
			(xy 379.863142 -216.742516) (xy 379.912535 -216.758564) (xy 379.958809 -216.782142) (xy 380.000825 -216.812668)
			(xy 380.037548 -216.849391) (xy 380.068074 -216.891407) (xy 380.091652 -216.937681) (xy 380.1077 -216.987074)
			(xy 380.115825 -217.038369) (xy 380.116334 -217.064336) (xy 380.115834 -217.090303) (xy 380.395989 -217.090303)
			(xy 380.395989 -217.038369) (xy 380.404114 -216.987074) (xy 380.420162 -216.937681) (xy 380.44374 -216.891407)
			(xy 380.474266 -216.849391) (xy 380.510989 -216.812668) (xy 380.553005 -216.782142) (xy 380.599279 -216.758564)
			(xy 380.648672 -216.742516) (xy 380.699967 -216.734391) (xy 380.751901 -216.734391) (xy 380.803196 -216.742516)
			(xy 380.852589 -216.758564) (xy 380.898863 -216.782142) (xy 380.940879 -216.812668) (xy 380.977602 -216.849391)
			(xy 381.008128 -216.891407) (xy 381.031706 -216.937681) (xy 381.047754 -216.987074) (xy 381.055879 -217.038369)
			(xy 381.056388 -217.064336) (xy 381.055879 -217.090303) (xy 381.047754 -217.141598) (xy 381.031706 -217.190991)
			(xy 381.008128 -217.237265) (xy 380.977602 -217.279281) (xy 380.940879 -217.316004) (xy 380.898863 -217.34653)
			(xy 380.852589 -217.370108) (xy 380.803196 -217.386156) (xy 380.751901 -217.394281) (xy 380.699967 -217.394281)
			(xy 380.648672 -217.386156) (xy 380.599279 -217.370108) (xy 380.553005 -217.34653) (xy 380.510989 -217.316004)
			(xy 380.474266 -217.279281) (xy 380.44374 -217.237265) (xy 380.420162 -217.190991) (xy 380.404114 -217.141598)
			(xy 380.395989 -217.090303) (xy 380.115834 -217.090303) (xy 380.115797 -217.092246) (xy 380.106471 -217.147278)
			(xy 380.097792 -217.17381) (xy 380.089918 -217.195654) (xy 380.294134 -217.549222) (xy 380.316994 -217.55354)
			(xy 380.341903 -217.558766) (xy 380.389885 -217.575722) (xy 380.434702 -217.599831) (xy 380.475295 -217.630524)
			(xy 380.510705 -217.667074) (xy 380.540096 -217.70862) (xy 380.562772 -217.754178) (xy 380.5782 -217.802674)
			(xy 380.586013 -217.852961) (xy 380.586488 -217.878406) (xy 380.585979 -217.904373) (xy 380.577854 -217.955668)
			(xy 380.561806 -218.005061) (xy 380.538228 -218.051335) (xy 380.507702 -218.093351) (xy 380.470979 -218.130074)
			(xy 380.428963 -218.1606) (xy 380.382689 -218.184178) (xy 380.333296 -218.200226) (xy 380.282001 -218.208351)
			(xy 380.230067 -218.208351) (xy 380.178772 -218.200226) (xy 380.129379 -218.184178) (xy 380.083105 -218.1606)
			(xy 380.041089 -218.130074) (xy 380.004366 -218.093351) (xy 379.97384 -218.051335) (xy 379.950262 -218.005061)
			(xy 379.934214 -217.955668) (xy 379.926089 -217.904373) (xy 379.92558 -217.878406) (xy 379.926135 -217.85042)
			(xy 379.935584 -217.795252) (xy 379.944376 -217.768678) (xy 379.951996 -217.74658) (xy 379.748288 -217.39352)
			(xy 379.725174 -217.389202) (xy 379.700229 -217.384082) (xy 379.652205 -217.367147) (xy 379.607346 -217.343047)
			(xy 379.566713 -217.312353) (xy 379.531268 -217.275792) (xy 379.501849 -217.234227) (xy 379.479151 -217.188643)
			(xy 379.463713 -217.140117) (xy 379.455898 -217.089797) (xy 379.455426 -217.064336) (xy 379.176788 -217.064336)
			(xy 379.176279 -217.090303) (xy 379.168154 -217.141598) (xy 379.152106 -217.190991) (xy 379.128528 -217.237265)
			(xy 379.098002 -217.279281) (xy 379.061279 -217.316004) (xy 379.019263 -217.34653) (xy 378.972989 -217.370108)
			(xy 378.923596 -217.386156) (xy 378.872301 -217.394281) (xy 378.820367 -217.394281) (xy 378.769072 -217.386156)
			(xy 378.719679 -217.370108) (xy 378.673405 -217.34653) (xy 378.631389 -217.316004) (xy 378.594666 -217.279281)
			(xy 378.56414 -217.237265) (xy 378.540562 -217.190991) (xy 378.524514 -217.141598) (xy 378.516389 -217.090303)
			(xy 378.236234 -217.090303) (xy 378.236197 -217.092246) (xy 378.226871 -217.147278) (xy 378.218192 -217.17381)
			(xy 378.210318 -217.195654) (xy 378.414534 -217.549222) (xy 378.437394 -217.55354) (xy 378.462303 -217.558766)
			(xy 378.510285 -217.575722) (xy 378.555102 -217.599831) (xy 378.595695 -217.630524) (xy 378.631105 -217.667074)
			(xy 378.660496 -217.70862) (xy 378.683172 -217.754178) (xy 378.6986 -217.802674) (xy 378.706413 -217.852961)
			(xy 378.706888 -217.878406) (xy 378.706379 -217.904373) (xy 378.698254 -217.955668) (xy 378.682206 -218.005061)
			(xy 378.658628 -218.051335) (xy 378.628102 -218.093351) (xy 378.591379 -218.130074) (xy 378.549363 -218.1606)
			(xy 378.503089 -218.184178) (xy 378.453696 -218.200226) (xy 378.402401 -218.208351) (xy 378.350467 -218.208351)
			(xy 378.299172 -218.200226) (xy 378.249779 -218.184178) (xy 378.203505 -218.1606) (xy 378.161489 -218.130074)
			(xy 378.124766 -218.093351) (xy 378.09424 -218.051335) (xy 378.070662 -218.005061) (xy 378.054614 -217.955668)
			(xy 378.046489 -217.904373) (xy 378.04598 -217.878406) (xy 378.046535 -217.85042) (xy 378.055984 -217.795252)
			(xy 378.064776 -217.768678) (xy 378.072396 -217.74658) (xy 377.868688 -217.39352) (xy 377.845574 -217.389202)
			(xy 377.820629 -217.384082) (xy 377.772605 -217.367147) (xy 377.727746 -217.343047) (xy 377.687113 -217.312353)
			(xy 377.651668 -217.275792) (xy 377.622249 -217.234227) (xy 377.599551 -217.188643) (xy 377.584113 -217.140117)
			(xy 377.576298 -217.089797) (xy 377.575826 -217.064336) (xy 377.297188 -217.064336) (xy 377.296679 -217.090303)
			(xy 377.288554 -217.141598) (xy 377.272506 -217.190991) (xy 377.248928 -217.237265) (xy 377.218402 -217.279281)
			(xy 377.181679 -217.316004) (xy 377.139663 -217.34653) (xy 377.093389 -217.370108) (xy 377.043996 -217.386156)
			(xy 376.992701 -217.394281) (xy 376.940767 -217.394281) (xy 376.889472 -217.386156) (xy 376.840079 -217.370108)
			(xy 376.793805 -217.34653) (xy 376.751789 -217.316004) (xy 376.715066 -217.279281) (xy 376.68454 -217.237265)
			(xy 376.660962 -217.190991) (xy 376.644914 -217.141598) (xy 376.636789 -217.090303) (xy 376.356634 -217.090303)
			(xy 376.356597 -217.092246) (xy 376.347271 -217.147278) (xy 376.338592 -217.17381) (xy 376.330718 -217.195654)
			(xy 376.534934 -217.549222) (xy 376.557794 -217.55354) (xy 376.582703 -217.558766) (xy 376.630685 -217.575722)
			(xy 376.675502 -217.599831) (xy 376.716095 -217.630524) (xy 376.751505 -217.667074) (xy 376.780896 -217.70862)
			(xy 376.803572 -217.754178) (xy 376.819 -217.802674) (xy 376.826813 -217.852961) (xy 376.827288 -217.878406)
			(xy 376.826779 -217.904373) (xy 376.818654 -217.955668) (xy 376.802606 -218.005061) (xy 376.779028 -218.051335)
			(xy 376.748502 -218.093351) (xy 376.711779 -218.130074) (xy 376.669763 -218.1606) (xy 376.623489 -218.184178)
			(xy 376.574096 -218.200226) (xy 376.522801 -218.208351) (xy 376.470867 -218.208351) (xy 376.419572 -218.200226)
			(xy 376.370179 -218.184178) (xy 376.323905 -218.1606) (xy 376.281889 -218.130074) (xy 376.245166 -218.093351)
			(xy 376.21464 -218.051335) (xy 376.191062 -218.005061) (xy 376.175014 -217.955668) (xy 376.166889 -217.904373)
			(xy 376.16638 -217.878406) (xy 376.166935 -217.85042) (xy 376.176384 -217.795252) (xy 376.185176 -217.768678)
			(xy 376.192796 -217.74658) (xy 375.989088 -217.39352) (xy 375.965974 -217.389202) (xy 375.941029 -217.384082)
			(xy 375.893005 -217.367147) (xy 375.848146 -217.343047) (xy 375.807513 -217.312353) (xy 375.772068 -217.275792)
			(xy 375.742649 -217.234227) (xy 375.719951 -217.188643) (xy 375.704513 -217.140117) (xy 375.696698 -217.089797)
			(xy 375.696226 -217.064336) (xy 375.417162 -217.064336) (xy 375.417161 -217.089701) (xy 375.409389 -217.139869)
			(xy 375.39403 -217.188257) (xy 375.371447 -217.233725) (xy 375.342171 -217.2752) (xy 375.306893 -217.311707)
			(xy 375.266443 -217.342384) (xy 375.24436 -217.354912) (xy 375.24436 -217.50147) (xy 375.244908 -217.516595)
			(xy 375.253762 -217.545519) (xy 375.270701 -217.570581) (xy 375.294238 -217.589581) (xy 375.32231 -217.600851)
			(xy 375.352451 -217.603403) (xy 375.382018 -217.597013) (xy 375.39549 -217.590116) (xy 375.420324 -217.576845)
			(xy 375.473393 -217.558036) (xy 375.528882 -217.548496) (xy 375.557034 -217.547952) (xy 375.582999 -217.548464)
			(xy 375.63429 -217.556592) (xy 375.683678 -217.572644) (xy 375.729946 -217.596224) (xy 375.771957 -217.626751)
			(xy 375.808675 -217.663473) (xy 375.839197 -217.705488) (xy 375.862771 -217.75176) (xy 375.878817 -217.801149)
			(xy 375.886939 -217.852441) (xy 375.887488 -217.878406) (xy 375.887017 -217.903878) (xy 375.879196 -217.954219)
			(xy 375.86374 -218.002763) (xy 375.841016 -218.048359) (xy 375.811562 -218.089926) (xy 375.776077 -218.126479)
			(xy 375.735401 -218.157153) (xy 375.690499 -218.181218) (xy 375.642435 -218.198106) (xy 375.617486 -218.203272)
			(xy 375.594372 -218.20759) (xy 375.390918 -218.560396) (xy 375.398538 -218.582494) (xy 375.407331 -218.609068)
			(xy 375.416779 -218.664236) (xy 375.417334 -218.692222) (xy 376.636026 -218.692222) (xy 376.636459 -218.66677)
			(xy 376.644247 -218.616464) (xy 376.65966 -218.567949) (xy 376.682331 -218.522372) (xy 376.711724 -218.480811)
			(xy 376.747144 -218.44425) (xy 376.787752 -218.413554) (xy 376.832588 -218.38945) (xy 376.88059 -218.372507)
			(xy 376.90552 -218.367356) (xy 376.92838 -218.363038) (xy 377.132342 -218.00947) (xy 377.124722 -217.987626)
			(xy 377.116084 -217.96115) (xy 377.106759 -217.906249) (xy 377.10618 -217.878406) (xy 377.106689 -217.852439)
			(xy 377.114814 -217.801144) (xy 377.130862 -217.751751) (xy 377.15444 -217.705477) (xy 377.184966 -217.663461)
			(xy 377.221689 -217.626738) (xy 377.263705 -217.596212) (xy 377.309979 -217.572634) (xy 377.359372 -217.556586)
			(xy 377.410667 -217.548461) (xy 377.462601 -217.548461) (xy 377.513896 -217.556586) (xy 377.563289 -217.572634)
			(xy 377.609563 -217.596212) (xy 377.651579 -217.626738) (xy 377.688302 -217.663461) (xy 377.718828 -217.705477)
			(xy 377.742406 -217.751751) (xy 377.758454 -217.801144) (xy 377.766579 -217.852439) (xy 377.767088 -217.878406)
			(xy 377.766584 -217.903878) (xy 377.758764 -217.954219) (xy 377.743312 -218.002763) (xy 377.720593 -218.04836)
			(xy 377.691145 -218.089931) (xy 377.655666 -218.12649) (xy 377.614997 -218.15717) (xy 377.570101 -218.181246)
			(xy 377.522042 -218.198147) (xy 377.497086 -218.203272) (xy 377.473972 -218.20759) (xy 377.270518 -218.560396)
			(xy 377.278138 -218.582494) (xy 377.286872 -218.609083) (xy 377.296322 -218.664242) (xy 377.296934 -218.692222)
			(xy 378.515626 -218.692222) (xy 378.516059 -218.66677) (xy 378.523847 -218.616464) (xy 378.53926 -218.567949)
			(xy 378.561931 -218.522372) (xy 378.591324 -218.480811) (xy 378.626744 -218.44425) (xy 378.667352 -218.413554)
			(xy 378.712188 -218.38945) (xy 378.76019 -218.372507) (xy 378.78512 -218.367356) (xy 378.80798 -218.363038)
			(xy 379.011942 -218.00947) (xy 379.004322 -217.987626) (xy 378.995684 -217.96115) (xy 378.986359 -217.906249)
			(xy 378.98578 -217.878406) (xy 378.986289 -217.852439) (xy 378.994414 -217.801144) (xy 379.010462 -217.751751)
			(xy 379.03404 -217.705477) (xy 379.064566 -217.663461) (xy 379.101289 -217.626738) (xy 379.143305 -217.596212)
			(xy 379.189579 -217.572634) (xy 379.238972 -217.556586) (xy 379.290267 -217.548461) (xy 379.342201 -217.548461)
			(xy 379.393496 -217.556586) (xy 379.442889 -217.572634) (xy 379.489163 -217.596212) (xy 379.531179 -217.626738)
			(xy 379.567902 -217.663461) (xy 379.598428 -217.705477) (xy 379.622006 -217.751751) (xy 379.638054 -217.801144)
			(xy 379.646179 -217.852439) (xy 379.646688 -217.878406) (xy 379.646184 -217.903878) (xy 379.638364 -217.954219)
			(xy 379.622912 -218.002763) (xy 379.600193 -218.04836) (xy 379.570745 -218.089931) (xy 379.535266 -218.12649)
			(xy 379.494597 -218.15717) (xy 379.449701 -218.181246) (xy 379.401642 -218.198147) (xy 379.376686 -218.203272)
			(xy 379.353572 -218.20759) (xy 379.150118 -218.560396) (xy 379.157738 -218.582494) (xy 379.166472 -218.609083)
			(xy 379.175922 -218.664242) (xy 379.176534 -218.692222) (xy 380.395226 -218.692222) (xy 380.395659 -218.66677)
			(xy 380.403447 -218.616464) (xy 380.41886 -218.567949) (xy 380.441531 -218.522372) (xy 380.470924 -218.480811)
			(xy 380.506344 -218.44425) (xy 380.546952 -218.413554) (xy 380.591788 -218.38945) (xy 380.63979 -218.372507)
			(xy 380.66472 -218.367356) (xy 380.68758 -218.363038) (xy 380.891542 -218.00947) (xy 380.883922 -217.987626)
			(xy 380.875284 -217.96115) (xy 380.865959 -217.906249) (xy 380.86538 -217.878406) (xy 380.865889 -217.852439)
			(xy 380.874014 -217.801144) (xy 380.890062 -217.751751) (xy 380.91364 -217.705477) (xy 380.944166 -217.663461)
			(xy 380.980889 -217.626738) (xy 381.022905 -217.596212) (xy 381.069179 -217.572634) (xy 381.118572 -217.556586)
			(xy 381.169867 -217.548461) (xy 381.221801 -217.548461) (xy 381.273096 -217.556586) (xy 381.322489 -217.572634)
			(xy 381.368763 -217.596212) (xy 381.410779 -217.626738) (xy 381.447502 -217.663461) (xy 381.478028 -217.705477)
			(xy 381.501606 -217.751751) (xy 381.517654 -217.801144) (xy 381.525779 -217.852439) (xy 381.526288 -217.878406)
			(xy 381.525784 -217.903878) (xy 381.517964 -217.954219) (xy 381.502512 -218.002763) (xy 381.479793 -218.04836)
			(xy 381.450345 -218.089931) (xy 381.414866 -218.12649) (xy 381.374197 -218.15717) (xy 381.329301 -218.181246)
			(xy 381.281242 -218.198147) (xy 381.256286 -218.203272) (xy 381.233172 -218.20759) (xy 381.029718 -218.560396)
			(xy 381.037338 -218.582494) (xy 381.046072 -218.609083) (xy 381.055522 -218.664242) (xy 381.056134 -218.692222)
			(xy 381.055625 -218.718189) (xy 381.0475 -218.769484) (xy 381.031452 -218.818877) (xy 381.007874 -218.865151)
			(xy 380.977348 -218.907167) (xy 380.940625 -218.94389) (xy 380.898609 -218.974416) (xy 380.852335 -218.997994)
			(xy 380.802942 -219.014042) (xy 380.751647 -219.022167) (xy 380.699713 -219.022167) (xy 380.648418 -219.014042)
			(xy 380.599025 -218.997994) (xy 380.552751 -218.974416) (xy 380.510735 -218.94389) (xy 380.474012 -218.907167)
			(xy 380.443486 -218.865151) (xy 380.419908 -218.818877) (xy 380.40386 -218.769484) (xy 380.395735 -218.718189)
			(xy 380.395226 -218.692222) (xy 379.176534 -218.692222) (xy 379.176025 -218.718189) (xy 379.1679 -218.769484)
			(xy 379.151852 -218.818877) (xy 379.128274 -218.865151) (xy 379.097748 -218.907167) (xy 379.061025 -218.94389)
			(xy 379.019009 -218.974416) (xy 378.972735 -218.997994) (xy 378.923342 -219.014042) (xy 378.872047 -219.022167)
			(xy 378.820113 -219.022167) (xy 378.768818 -219.014042) (xy 378.719425 -218.997994) (xy 378.673151 -218.974416)
			(xy 378.631135 -218.94389) (xy 378.594412 -218.907167) (xy 378.563886 -218.865151) (xy 378.540308 -218.818877)
			(xy 378.52426 -218.769484) (xy 378.516135 -218.718189) (xy 378.515626 -218.692222) (xy 377.296934 -218.692222)
			(xy 377.296425 -218.718189) (xy 377.2883 -218.769484) (xy 377.272252 -218.818877) (xy 377.248674 -218.865151)
			(xy 377.218148 -218.907167) (xy 377.181425 -218.94389) (xy 377.139409 -218.974416) (xy 377.093135 -218.997994)
			(xy 377.043742 -219.014042) (xy 376.992447 -219.022167) (xy 376.940513 -219.022167) (xy 376.889218 -219.014042)
			(xy 376.839825 -218.997994) (xy 376.793551 -218.974416) (xy 376.751535 -218.94389) (xy 376.714812 -218.907167)
			(xy 376.684286 -218.865151) (xy 376.660708 -218.818877) (xy 376.64466 -218.769484) (xy 376.636535 -218.718189)
			(xy 376.636026 -218.692222) (xy 375.417334 -218.692222) (xy 375.41687 -218.717592) (xy 375.409115 -218.767736)
			(xy 375.39379 -218.816106) (xy 375.371255 -218.861568) (xy 375.342039 -218.903053) (xy 375.306829 -218.939587)
			(xy 375.26645 -218.970313) (xy 375.24436 -218.982798) (xy 375.24436 -219.129102) (xy 375.244913 -219.144223)
			(xy 375.253771 -219.173139) (xy 375.270711 -219.198192) (xy 375.294246 -219.217185) (xy 375.322311 -219.228452)
			(xy 375.352446 -219.231003) (xy 375.382006 -219.224617) (xy 375.39549 -219.217748) (xy 375.420325 -219.20448)
			(xy 375.473394 -219.185675) (xy 375.528883 -219.176137) (xy 375.557034 -219.175584) (xy 375.582996 -219.176096)
			(xy 375.634282 -219.184223) (xy 375.683664 -219.200273) (xy 375.729928 -219.22385) (xy 375.771934 -219.254373)
			(xy 375.808649 -219.291092) (xy 375.839168 -219.333101) (xy 375.86274 -219.379368) (xy 375.878785 -219.428752)
			(xy 375.886907 -219.480037) (xy 375.886907 -219.531963) (xy 375.8869 -219.532005) (xy 376.166889 -219.532005)
			(xy 376.166889 -219.480071) (xy 376.175014 -219.428776) (xy 376.191062 -219.379383) (xy 376.21464 -219.333109)
			(xy 376.245166 -219.291093) (xy 376.281889 -219.25437) (xy 376.323905 -219.223844) (xy 376.370179 -219.200266)
			(xy 376.419572 -219.184218) (xy 376.470867 -219.176093) (xy 376.522801 -219.176093) (xy 376.574096 -219.184218)
			(xy 376.623489 -219.200266) (xy 376.669763 -219.223844) (xy 376.711779 -219.25437) (xy 376.748502 -219.291093)
			(xy 376.779028 -219.333109) (xy 376.802606 -219.379383) (xy 376.818654 -219.428776) (xy 376.826779 -219.480071)
			(xy 376.827288 -219.506038) (xy 376.826779 -219.532005) (xy 377.106689 -219.532005) (xy 377.106689 -219.480071)
			(xy 377.114814 -219.428776) (xy 377.130862 -219.379383) (xy 377.15444 -219.333109) (xy 377.184966 -219.291093)
			(xy 377.221689 -219.25437) (xy 377.263705 -219.223844) (xy 377.309979 -219.200266) (xy 377.359372 -219.184218)
			(xy 377.410667 -219.176093) (xy 377.462601 -219.176093) (xy 377.513896 -219.184218) (xy 377.563289 -219.200266)
			(xy 377.609563 -219.223844) (xy 377.651579 -219.25437) (xy 377.688302 -219.291093) (xy 377.718828 -219.333109)
			(xy 377.742406 -219.379383) (xy 377.758454 -219.428776) (xy 377.766579 -219.480071) (xy 377.767088 -219.506038)
			(xy 377.766579 -219.532005) (xy 378.046489 -219.532005) (xy 378.046489 -219.480071) (xy 378.054614 -219.428776)
			(xy 378.070662 -219.379383) (xy 378.09424 -219.333109) (xy 378.124766 -219.291093) (xy 378.161489 -219.25437)
			(xy 378.203505 -219.223844) (xy 378.249779 -219.200266) (xy 378.299172 -219.184218) (xy 378.350467 -219.176093)
			(xy 378.402401 -219.176093) (xy 378.453696 -219.184218) (xy 378.503089 -219.200266) (xy 378.549363 -219.223844)
			(xy 378.591379 -219.25437) (xy 378.628102 -219.291093) (xy 378.658628 -219.333109) (xy 378.682206 -219.379383)
			(xy 378.698254 -219.428776) (xy 378.706379 -219.480071) (xy 378.706888 -219.506038) (xy 378.706379 -219.532005)
			(xy 378.986289 -219.532005) (xy 378.986289 -219.480071) (xy 378.994414 -219.428776) (xy 379.010462 -219.379383)
			(xy 379.03404 -219.333109) (xy 379.064566 -219.291093) (xy 379.101289 -219.25437) (xy 379.143305 -219.223844)
			(xy 379.189579 -219.200266) (xy 379.238972 -219.184218) (xy 379.290267 -219.176093) (xy 379.342201 -219.176093)
			(xy 379.393496 -219.184218) (xy 379.442889 -219.200266) (xy 379.489163 -219.223844) (xy 379.531179 -219.25437)
			(xy 379.567902 -219.291093) (xy 379.598428 -219.333109) (xy 379.622006 -219.379383) (xy 379.638054 -219.428776)
			(xy 379.646179 -219.480071) (xy 379.646688 -219.506038) (xy 379.646179 -219.532005) (xy 379.926089 -219.532005)
			(xy 379.926089 -219.480071) (xy 379.934214 -219.428776) (xy 379.950262 -219.379383) (xy 379.97384 -219.333109)
			(xy 380.004366 -219.291093) (xy 380.041089 -219.25437) (xy 380.083105 -219.223844) (xy 380.129379 -219.200266)
			(xy 380.178772 -219.184218) (xy 380.230067 -219.176093) (xy 380.282001 -219.176093) (xy 380.333296 -219.184218)
			(xy 380.382689 -219.200266) (xy 380.428963 -219.223844) (xy 380.470979 -219.25437) (xy 380.507702 -219.291093)
			(xy 380.538228 -219.333109) (xy 380.561806 -219.379383) (xy 380.577854 -219.428776) (xy 380.585979 -219.480071)
			(xy 380.586488 -219.506038) (xy 380.585979 -219.532005) (xy 380.865889 -219.532005) (xy 380.865889 -219.480071)
			(xy 380.874014 -219.428776) (xy 380.890062 -219.379383) (xy 380.91364 -219.333109) (xy 380.944166 -219.291093)
			(xy 380.980889 -219.25437) (xy 381.022905 -219.223844) (xy 381.069179 -219.200266) (xy 381.118572 -219.184218)
			(xy 381.169867 -219.176093) (xy 381.221801 -219.176093) (xy 381.273096 -219.184218) (xy 381.322489 -219.200266)
			(xy 381.368763 -219.223844) (xy 381.410779 -219.25437) (xy 381.447502 -219.291093) (xy 381.478028 -219.333109)
			(xy 381.501606 -219.379383) (xy 381.517654 -219.428776) (xy 381.525779 -219.480071) (xy 381.526288 -219.506038)
			(xy 381.525779 -219.532005) (xy 381.517654 -219.5833) (xy 381.501606 -219.632693) (xy 381.478028 -219.678967)
			(xy 381.447502 -219.720983) (xy 381.410779 -219.757706) (xy 381.368763 -219.788232) (xy 381.322489 -219.81181)
			(xy 381.273096 -219.827858) (xy 381.221801 -219.835983) (xy 381.169867 -219.835983) (xy 381.118572 -219.827858)
			(xy 381.069179 -219.81181) (xy 381.022905 -219.788232) (xy 380.980889 -219.757706) (xy 380.944166 -219.720983)
			(xy 380.91364 -219.678967) (xy 380.890062 -219.632693) (xy 380.874014 -219.5833) (xy 380.865889 -219.532005)
			(xy 380.585979 -219.532005) (xy 380.577854 -219.5833) (xy 380.561806 -219.632693) (xy 380.538228 -219.678967)
			(xy 380.507702 -219.720983) (xy 380.470979 -219.757706) (xy 380.428963 -219.788232) (xy 380.382689 -219.81181)
			(xy 380.333296 -219.827858) (xy 380.282001 -219.835983) (xy 380.230067 -219.835983) (xy 380.178772 -219.827858)
			(xy 380.129379 -219.81181) (xy 380.083105 -219.788232) (xy 380.041089 -219.757706) (xy 380.004366 -219.720983)
			(xy 379.97384 -219.678967) (xy 379.950262 -219.632693) (xy 379.934214 -219.5833) (xy 379.926089 -219.532005)
			(xy 379.646179 -219.532005) (xy 379.638054 -219.5833) (xy 379.622006 -219.632693) (xy 379.598428 -219.678967)
			(xy 379.567902 -219.720983) (xy 379.531179 -219.757706) (xy 379.489163 -219.788232) (xy 379.442889 -219.81181)
			(xy 379.393496 -219.827858) (xy 379.342201 -219.835983) (xy 379.290267 -219.835983) (xy 379.238972 -219.827858)
			(xy 379.189579 -219.81181) (xy 379.143305 -219.788232) (xy 379.101289 -219.757706) (xy 379.064566 -219.720983)
			(xy 379.03404 -219.678967) (xy 379.010462 -219.632693) (xy 378.994414 -219.5833) (xy 378.986289 -219.532005)
			(xy 378.706379 -219.532005) (xy 378.698254 -219.5833) (xy 378.682206 -219.632693) (xy 378.658628 -219.678967)
			(xy 378.628102 -219.720983) (xy 378.591379 -219.757706) (xy 378.549363 -219.788232) (xy 378.503089 -219.81181)
			(xy 378.453696 -219.827858) (xy 378.402401 -219.835983) (xy 378.350467 -219.835983) (xy 378.299172 -219.827858)
			(xy 378.249779 -219.81181) (xy 378.203505 -219.788232) (xy 378.161489 -219.757706) (xy 378.124766 -219.720983)
			(xy 378.09424 -219.678967) (xy 378.070662 -219.632693) (xy 378.054614 -219.5833) (xy 378.046489 -219.532005)
			(xy 377.766579 -219.532005) (xy 377.758454 -219.5833) (xy 377.742406 -219.632693) (xy 377.718828 -219.678967)
			(xy 377.688302 -219.720983) (xy 377.651579 -219.757706) (xy 377.609563 -219.788232) (xy 377.563289 -219.81181)
			(xy 377.513896 -219.827858) (xy 377.462601 -219.835983) (xy 377.410667 -219.835983) (xy 377.359372 -219.827858)
			(xy 377.309979 -219.81181) (xy 377.263705 -219.788232) (xy 377.221689 -219.757706) (xy 377.184966 -219.720983)
			(xy 377.15444 -219.678967) (xy 377.130862 -219.632693) (xy 377.114814 -219.5833) (xy 377.106689 -219.532005)
			(xy 376.826779 -219.532005) (xy 376.818654 -219.5833) (xy 376.802606 -219.632693) (xy 376.779028 -219.678967)
			(xy 376.748502 -219.720983) (xy 376.711779 -219.757706) (xy 376.669763 -219.788232) (xy 376.623489 -219.81181)
			(xy 376.574096 -219.827858) (xy 376.522801 -219.835983) (xy 376.470867 -219.835983) (xy 376.419572 -219.827858)
			(xy 376.370179 -219.81181) (xy 376.323905 -219.788232) (xy 376.281889 -219.757706) (xy 376.245166 -219.720983)
			(xy 376.21464 -219.678967) (xy 376.191062 -219.632693) (xy 376.175014 -219.5833) (xy 376.166889 -219.532005)
			(xy 375.8869 -219.532005) (xy 375.878785 -219.583248) (xy 375.86274 -219.632632) (xy 375.839168 -219.678899)
			(xy 375.808649 -219.720908) (xy 375.771934 -219.757627) (xy 375.729928 -219.78815) (xy 375.683664 -219.811727)
			(xy 375.634282 -219.827777) (xy 375.582996 -219.835904) (xy 375.557034 -219.836492) (xy 375.528885 -219.83592)
			(xy 375.473402 -219.826374) (xy 375.420337 -219.80757) (xy 375.39549 -219.794328) (xy 375.382024 -219.787443)
			(xy 375.352473 -219.781084) (xy 375.322355 -219.783654) (xy 375.294309 -219.794927) (xy 375.270791 -219.813917)
			(xy 375.253863 -219.83896) (xy 375.245007 -219.86786) (xy 375.24436 -219.882974) (xy 375.24436 -220.029278)
			(xy 375.266478 -220.041752) (xy 375.306937 -220.072436) (xy 375.342224 -220.10895) (xy 375.371506 -220.150434)
			(xy 375.394095 -220.195911) (xy 375.409458 -220.24431) (xy 375.417232 -220.294489) (xy 375.417234 -220.319854)
			(xy 375.696226 -220.319854) (xy 375.696735 -220.293887) (xy 375.70486 -220.242592) (xy 375.720908 -220.193199)
			(xy 375.744486 -220.146925) (xy 375.775012 -220.104909) (xy 375.811735 -220.068186) (xy 375.853751 -220.03766)
			(xy 375.900025 -220.014082) (xy 375.949418 -219.998034) (xy 376.000713 -219.989909) (xy 376.052647 -219.989909)
			(xy 376.103942 -219.998034) (xy 376.153335 -220.014082) (xy 376.199609 -220.03766) (xy 376.241625 -220.068186)
			(xy 376.278348 -220.104909) (xy 376.308874 -220.146925) (xy 376.332452 -220.193199) (xy 376.3485 -220.242592)
			(xy 376.356625 -220.293887) (xy 376.357134 -220.319854) (xy 376.356638 -220.345821) (xy 376.636789 -220.345821)
			(xy 376.636789 -220.293887) (xy 376.644914 -220.242592) (xy 376.660962 -220.193199) (xy 376.68454 -220.146925)
			(xy 376.715066 -220.104909) (xy 376.751789 -220.068186) (xy 376.793805 -220.03766) (xy 376.840079 -220.014082)
			(xy 376.889472 -219.998034) (xy 376.940767 -219.989909) (xy 376.992701 -219.989909) (xy 377.043996 -219.998034)
			(xy 377.093389 -220.014082) (xy 377.139663 -220.03766) (xy 377.181679 -220.068186) (xy 377.218402 -220.104909)
			(xy 377.248928 -220.146925) (xy 377.272506 -220.193199) (xy 377.288554 -220.242592) (xy 377.296679 -220.293887)
			(xy 377.297188 -220.319854) (xy 377.575826 -220.319854) (xy 377.576335 -220.293887) (xy 377.58446 -220.242592)
			(xy 377.600508 -220.193199) (xy 377.624086 -220.146925) (xy 377.654612 -220.104909) (xy 377.691335 -220.068186)
			(xy 377.733351 -220.03766) (xy 377.779625 -220.014082) (xy 377.829018 -219.998034) (xy 377.880313 -219.989909)
			(xy 377.932247 -219.989909) (xy 377.983542 -219.998034) (xy 378.032935 -220.014082) (xy 378.079209 -220.03766)
			(xy 378.121225 -220.068186) (xy 378.157948 -220.104909) (xy 378.188474 -220.146925) (xy 378.212052 -220.193199)
			(xy 378.2281 -220.242592) (xy 378.236225 -220.293887) (xy 378.236734 -220.319854) (xy 378.236238 -220.345821)
			(xy 378.516389 -220.345821) (xy 378.516389 -220.293887) (xy 378.524514 -220.242592) (xy 378.540562 -220.193199)
			(xy 378.56414 -220.146925) (xy 378.594666 -220.104909) (xy 378.631389 -220.068186) (xy 378.673405 -220.03766)
			(xy 378.719679 -220.014082) (xy 378.769072 -219.998034) (xy 378.820367 -219.989909) (xy 378.872301 -219.989909)
			(xy 378.923596 -219.998034) (xy 378.972989 -220.014082) (xy 379.019263 -220.03766) (xy 379.061279 -220.068186)
			(xy 379.098002 -220.104909) (xy 379.128528 -220.146925) (xy 379.152106 -220.193199) (xy 379.168154 -220.242592)
			(xy 379.176279 -220.293887) (xy 379.176788 -220.319854) (xy 379.455426 -220.319854) (xy 379.455935 -220.293887)
			(xy 379.46406 -220.242592) (xy 379.480108 -220.193199) (xy 379.503686 -220.146925) (xy 379.534212 -220.104909)
			(xy 379.570935 -220.068186) (xy 379.612951 -220.03766) (xy 379.659225 -220.014082) (xy 379.708618 -219.998034)
			(xy 379.759913 -219.989909) (xy 379.811847 -219.989909) (xy 379.863142 -219.998034) (xy 379.912535 -220.014082)
			(xy 379.958809 -220.03766) (xy 380.000825 -220.068186) (xy 380.037548 -220.104909) (xy 380.068074 -220.146925)
			(xy 380.091652 -220.193199) (xy 380.1077 -220.242592) (xy 380.115825 -220.293887) (xy 380.116334 -220.319854)
			(xy 380.115838 -220.345821) (xy 380.395989 -220.345821) (xy 380.395989 -220.293887) (xy 380.404114 -220.242592)
			(xy 380.420162 -220.193199) (xy 380.44374 -220.146925) (xy 380.474266 -220.104909) (xy 380.510989 -220.068186)
			(xy 380.553005 -220.03766) (xy 380.599279 -220.014082) (xy 380.648672 -219.998034) (xy 380.699967 -219.989909)
			(xy 380.751901 -219.989909) (xy 380.803196 -219.998034) (xy 380.852589 -220.014082) (xy 380.898863 -220.03766)
			(xy 380.940879 -220.068186) (xy 380.977602 -220.104909) (xy 381.008128 -220.146925) (xy 381.031706 -220.193199)
			(xy 381.047754 -220.242592) (xy 381.055879 -220.293887) (xy 381.056388 -220.319854) (xy 381.055879 -220.345821)
			(xy 381.047754 -220.397116) (xy 381.031706 -220.446509) (xy 381.008128 -220.492783) (xy 380.977602 -220.534799)
			(xy 380.940879 -220.571522) (xy 380.898863 -220.602048) (xy 380.852589 -220.625626) (xy 380.803196 -220.641674)
			(xy 380.751901 -220.649799) (xy 380.699967 -220.649799) (xy 380.648672 -220.641674) (xy 380.599279 -220.625626)
			(xy 380.553005 -220.602048) (xy 380.510989 -220.571522) (xy 380.474266 -220.534799) (xy 380.44374 -220.492783)
			(xy 380.420162 -220.446509) (xy 380.404114 -220.397116) (xy 380.395989 -220.345821) (xy 380.115838 -220.345821)
			(xy 380.115801 -220.347764) (xy 380.106472 -220.402797) (xy 380.097792 -220.429328) (xy 380.089918 -220.451172)
			(xy 380.294134 -220.80474) (xy 380.316994 -220.809058) (xy 380.341907 -220.814267) (xy 380.38989 -220.831224)
			(xy 380.434708 -220.855335) (xy 380.475302 -220.886029) (xy 380.510712 -220.922582) (xy 380.540102 -220.96413)
			(xy 380.562778 -221.009691) (xy 380.578203 -221.058189) (xy 380.586014 -221.108478) (xy 380.586488 -221.133924)
			(xy 380.585979 -221.159891) (xy 380.577854 -221.211186) (xy 380.561806 -221.260579) (xy 380.538228 -221.306853)
			(xy 380.507702 -221.348869) (xy 380.470979 -221.385592) (xy 380.428963 -221.416118) (xy 380.382689 -221.439696)
			(xy 380.333296 -221.455744) (xy 380.282001 -221.463869) (xy 380.230067 -221.463869) (xy 380.178772 -221.455744)
			(xy 380.129379 -221.439696) (xy 380.083105 -221.416118) (xy 380.041089 -221.385592) (xy 380.004366 -221.348869)
			(xy 379.97384 -221.306853) (xy 379.950262 -221.260579) (xy 379.934214 -221.211186) (xy 379.926089 -221.159891)
			(xy 379.92558 -221.133924) (xy 379.92614 -221.105938) (xy 379.935585 -221.050771) (xy 379.944376 -221.024196)
			(xy 379.951996 -221.002098) (xy 379.748288 -220.649038) (xy 379.725174 -220.64472) (xy 379.700233 -220.639583)
			(xy 379.65221 -220.622649) (xy 379.607352 -220.598551) (xy 379.56672 -220.567859) (xy 379.531275 -220.5313)
			(xy 379.501855 -220.489738) (xy 379.479156 -220.444156) (xy 379.463716 -220.395632) (xy 379.4559 -220.345314)
			(xy 379.455426 -220.319854) (xy 379.176788 -220.319854) (xy 379.176279 -220.345821) (xy 379.168154 -220.397116)
			(xy 379.152106 -220.446509) (xy 379.128528 -220.492783) (xy 379.098002 -220.534799) (xy 379.061279 -220.571522)
			(xy 379.019263 -220.602048) (xy 378.972989 -220.625626) (xy 378.923596 -220.641674) (xy 378.872301 -220.649799)
			(xy 378.820367 -220.649799) (xy 378.769072 -220.641674) (xy 378.719679 -220.625626) (xy 378.673405 -220.602048)
			(xy 378.631389 -220.571522) (xy 378.594666 -220.534799) (xy 378.56414 -220.492783) (xy 378.540562 -220.446509)
			(xy 378.524514 -220.397116) (xy 378.516389 -220.345821) (xy 378.236238 -220.345821) (xy 378.236201 -220.347764)
			(xy 378.226872 -220.402797) (xy 378.218192 -220.429328) (xy 378.210318 -220.451172) (xy 378.414534 -220.80474)
			(xy 378.437394 -220.809058) (xy 378.462307 -220.814267) (xy 378.51029 -220.831224) (xy 378.555108 -220.855335)
			(xy 378.595702 -220.886029) (xy 378.631112 -220.922582) (xy 378.660502 -220.96413) (xy 378.683178 -221.009691)
			(xy 378.698603 -221.058189) (xy 378.706414 -221.108478) (xy 378.706888 -221.133924) (xy 378.706379 -221.159891)
			(xy 378.698254 -221.211186) (xy 378.682206 -221.260579) (xy 378.658628 -221.306853) (xy 378.628102 -221.348869)
			(xy 378.591379 -221.385592) (xy 378.549363 -221.416118) (xy 378.503089 -221.439696) (xy 378.453696 -221.455744)
			(xy 378.402401 -221.463869) (xy 378.350467 -221.463869) (xy 378.299172 -221.455744) (xy 378.249779 -221.439696)
			(xy 378.203505 -221.416118) (xy 378.161489 -221.385592) (xy 378.124766 -221.348869) (xy 378.09424 -221.306853)
			(xy 378.070662 -221.260579) (xy 378.054614 -221.211186) (xy 378.046489 -221.159891) (xy 378.04598 -221.133924)
			(xy 378.04654 -221.105938) (xy 378.055985 -221.050771) (xy 378.064776 -221.024196) (xy 378.072396 -221.002098)
			(xy 377.868688 -220.649038) (xy 377.845574 -220.64472) (xy 377.820633 -220.639583) (xy 377.77261 -220.622649)
			(xy 377.727752 -220.598551) (xy 377.68712 -220.567859) (xy 377.651675 -220.5313) (xy 377.622255 -220.489738)
			(xy 377.599556 -220.444156) (xy 377.584116 -220.395632) (xy 377.5763 -220.345314) (xy 377.575826 -220.319854)
			(xy 377.297188 -220.319854) (xy 377.296679 -220.345821) (xy 377.288554 -220.397116) (xy 377.272506 -220.446509)
			(xy 377.248928 -220.492783) (xy 377.218402 -220.534799) (xy 377.181679 -220.571522) (xy 377.139663 -220.602048)
			(xy 377.093389 -220.625626) (xy 377.043996 -220.641674) (xy 376.992701 -220.649799) (xy 376.940767 -220.649799)
			(xy 376.889472 -220.641674) (xy 376.840079 -220.625626) (xy 376.793805 -220.602048) (xy 376.751789 -220.571522)
			(xy 376.715066 -220.534799) (xy 376.68454 -220.492783) (xy 376.660962 -220.446509) (xy 376.644914 -220.397116)
			(xy 376.636789 -220.345821) (xy 376.356638 -220.345821) (xy 376.356601 -220.347764) (xy 376.347272 -220.402797)
			(xy 376.338592 -220.429328) (xy 376.330718 -220.451172) (xy 376.534934 -220.80474) (xy 376.557794 -220.809058)
			(xy 376.582707 -220.814267) (xy 376.63069 -220.831224) (xy 376.675508 -220.855335) (xy 376.716102 -220.886029)
			(xy 376.751512 -220.922582) (xy 376.780902 -220.96413) (xy 376.803578 -221.009691) (xy 376.819003 -221.058189)
			(xy 376.826814 -221.108478) (xy 376.827288 -221.133924) (xy 376.826779 -221.159891) (xy 376.818654 -221.211186)
			(xy 376.802606 -221.260579) (xy 376.779028 -221.306853) (xy 376.748502 -221.348869) (xy 376.711779 -221.385592)
			(xy 376.669763 -221.416118) (xy 376.623489 -221.439696) (xy 376.574096 -221.455744) (xy 376.522801 -221.463869)
			(xy 376.470867 -221.463869) (xy 376.419572 -221.455744) (xy 376.370179 -221.439696) (xy 376.323905 -221.416118)
			(xy 376.281889 -221.385592) (xy 376.245166 -221.348869) (xy 376.21464 -221.306853) (xy 376.191062 -221.260579)
			(xy 376.175014 -221.211186) (xy 376.166889 -221.159891) (xy 376.16638 -221.133924) (xy 376.16694 -221.105938)
			(xy 376.176385 -221.050771) (xy 376.185176 -221.024196) (xy 376.192796 -221.002098) (xy 375.989088 -220.649038)
			(xy 375.965974 -220.64472) (xy 375.941033 -220.639583) (xy 375.89301 -220.622649) (xy 375.848152 -220.598551)
			(xy 375.80752 -220.567859) (xy 375.772075 -220.5313) (xy 375.742655 -220.489738) (xy 375.719956 -220.444156)
			(xy 375.704516 -220.395632) (xy 375.6967 -220.345314) (xy 375.696226 -220.319854) (xy 375.417234 -220.319854)
			(xy 375.417236 -220.345267) (xy 375.409468 -220.395448) (xy 375.394112 -220.443848) (xy 375.371529 -220.489328)
			(xy 375.342252 -220.530816) (xy 375.30697 -220.567335) (xy 375.266515 -220.598024) (xy 375.24436 -220.61043)
			(xy 375.24436 -220.756988) (xy 375.244911 -220.772111) (xy 375.253767 -220.801031) (xy 375.270706 -220.826087)
			(xy 375.294242 -220.845083) (xy 375.32231 -220.856351) (xy 375.352448 -220.858903) (xy 375.382011 -220.852515)
			(xy 375.39549 -220.845634) (xy 375.420325 -220.832366) (xy 375.473394 -220.813562) (xy 375.528883 -220.804025)
			(xy 375.557034 -220.80347) (xy 375.582999 -220.803982) (xy 375.634288 -220.812111) (xy 375.683675 -220.828162)
			(xy 375.729942 -220.851742) (xy 375.771951 -220.88227) (xy 375.808668 -220.918993) (xy 375.839188 -220.961007)
			(xy 375.86276 -221.007279) (xy 375.878803 -221.056668) (xy 375.886923 -221.107959) (xy 375.887488 -221.133924)
			(xy 375.887015 -221.159396) (xy 375.879192 -221.209734) (xy 375.863735 -221.258276) (xy 375.84101 -221.303869)
			(xy 375.811555 -221.345434) (xy 375.77607 -221.381985) (xy 375.735395 -221.412657) (xy 375.690493 -221.436721)
			(xy 375.642431 -221.453607) (xy 375.617486 -221.45879) (xy 375.594372 -221.463108) (xy 375.390918 -221.815914)
			(xy 375.398538 -221.838012) (xy 375.40733 -221.864586) (xy 375.416775 -221.919754) (xy 375.417334 -221.94774)
			(xy 375.416572 -221.969076) (xy 375.415048 -221.991936) (xy 375.454164 -222.031052) (xy 375.478294 -222.028512)
			(xy 375.515008 -222.025023) (xy 375.58876 -222.024511) (xy 375.662194 -222.031361) (xy 375.734579 -222.045503)
			(xy 375.805192 -222.066797) (xy 375.873327 -222.09503) (xy 375.90603 -222.112078) (xy 375.911618 -222.115126)
			(xy 375.925842 -222.123508) (xy 375.941301 -222.131938) (xy 375.974404 -222.143926) (xy 376.009077 -222.150039)
			(xy 376.02668 -222.150432) (xy 376.044384 -222.15007) (xy 376.079253 -222.143923) (xy 376.112524 -222.131811)
			(xy 376.128026 -222.123254) (xy 376.164701 -222.10274) (xy 376.241764 -222.069223) (xy 376.322136 -222.044678)
			(xy 376.404776 -222.029423) (xy 376.488614 -222.023655) (xy 376.530616 -222.024956) (xy 376.543842 -222.025131)
			(xy 376.569675 -222.019494) (xy 376.593192 -222.007407) (xy 376.612811 -221.989682) (xy 376.627215 -221.967508)
			(xy 376.635435 -221.942378) (xy 376.636534 -221.929198) (xy 376.638345 -221.904847) (xy 376.648234 -221.857029)
			(xy 376.665049 -221.811186) (xy 376.688425 -221.768315) (xy 376.717852 -221.729349) (xy 376.752691 -221.695135)
			(xy 376.792184 -221.666419) (xy 376.835471 -221.643824) (xy 376.881611 -221.627842) (xy 376.90552 -221.622874)
			(xy 376.92838 -221.618556) (xy 377.132342 -221.264988) (xy 377.124722 -221.243144) (xy 377.116064 -221.216673)
			(xy 377.106749 -221.161769) (xy 377.10618 -221.133924) (xy 377.106689 -221.107957) (xy 377.114814 -221.056662)
			(xy 377.130862 -221.007269) (xy 377.15444 -220.960995) (xy 377.184966 -220.918979) (xy 377.221689 -220.882256)
			(xy 377.263705 -220.85173) (xy 377.309979 -220.828152) (xy 377.359372 -220.812104) (xy 377.410667 -220.803979)
			(xy 377.462601 -220.803979) (xy 377.513896 -220.812104) (xy 377.563289 -220.828152) (xy 377.609563 -220.85173)
			(xy 377.651579 -220.882256) (xy 377.688302 -220.918979) (xy 377.718828 -220.960995) (xy 377.742406 -221.007269)
			(xy 377.758454 -221.056662) (xy 377.766579 -221.107957) (xy 377.767088 -221.133924) (xy 377.766615 -221.159396)
			(xy 377.758792 -221.209734) (xy 377.743335 -221.258276) (xy 377.72061 -221.303869) (xy 377.691155 -221.345434)
			(xy 377.65567 -221.381985) (xy 377.614995 -221.412657) (xy 377.570093 -221.436721) (xy 377.522031 -221.453607)
			(xy 377.497086 -221.45879) (xy 377.473972 -221.463108) (xy 377.270518 -221.815914) (xy 377.278138 -221.838012)
			(xy 377.285525 -221.860154) (xy 377.294701 -221.90592) (xy 377.296426 -221.929198) (xy 377.297568 -221.942411)
			(xy 377.305772 -221.96762) (xy 377.320192 -221.989866) (xy 377.339854 -222.007648) (xy 377.363433 -222.019765)
			(xy 377.389337 -222.025402) (xy 377.402598 -222.02521) (xy 377.442345 -222.023896) (xy 377.521724 -222.028775)
			(xy 377.600119 -222.042164) (xy 377.676618 -222.063908) (xy 377.750335 -222.093754) (xy 377.78563 -222.112078)
			(xy 377.791218 -222.115126) (xy 377.805442 -222.123508) (xy 377.820901 -222.131938) (xy 377.854004 -222.143926)
			(xy 377.888677 -222.150039) (xy 377.90628 -222.150432) (xy 377.923984 -222.15007) (xy 377.958853 -222.143923)
			(xy 377.992124 -222.131811) (xy 378.007626 -222.123254) (xy 378.044301 -222.10274) (xy 378.121364 -222.069223)
			(xy 378.201736 -222.044678) (xy 378.284376 -222.029423) (xy 378.368214 -222.023655) (xy 378.410216 -222.024956)
			(xy 378.423442 -222.025131) (xy 378.449275 -222.019494) (xy 378.472792 -222.007407) (xy 378.492411 -221.989682)
			(xy 378.506815 -221.967508) (xy 378.515035 -221.942378) (xy 378.516134 -221.929198) (xy 378.517945 -221.904847)
			(xy 378.527834 -221.857029) (xy 378.544649 -221.811186) (xy 378.568025 -221.768315) (xy 378.597452 -221.729349)
			(xy 378.632291 -221.695135) (xy 378.671784 -221.666419) (xy 378.715071 -221.643824) (xy 378.761211 -221.627842)
			(xy 378.78512 -221.622874) (xy 378.80798 -221.618556) (xy 379.011942 -221.264988) (xy 379.004322 -221.243144)
			(xy 378.995664 -221.216673) (xy 378.986349 -221.161769) (xy 378.98578 -221.133924) (xy 378.986289 -221.107957)
			(xy 378.994414 -221.056662) (xy 379.010462 -221.007269) (xy 379.03404 -220.960995) (xy 379.064566 -220.918979)
			(xy 379.101289 -220.882256) (xy 379.143305 -220.85173) (xy 379.189579 -220.828152) (xy 379.238972 -220.812104)
			(xy 379.290267 -220.803979) (xy 379.342201 -220.803979) (xy 379.393496 -220.812104) (xy 379.442889 -220.828152)
			(xy 379.489163 -220.85173) (xy 379.531179 -220.882256) (xy 379.567902 -220.918979) (xy 379.598428 -220.960995)
			(xy 379.622006 -221.007269) (xy 379.638054 -221.056662) (xy 379.646179 -221.107957) (xy 379.646688 -221.133924)
			(xy 379.646215 -221.159396) (xy 379.638392 -221.209734) (xy 379.622935 -221.258276) (xy 379.60021 -221.303869)
			(xy 379.570755 -221.345434) (xy 379.53527 -221.381985) (xy 379.494595 -221.412657) (xy 379.449693 -221.436721)
			(xy 379.401631 -221.453607) (xy 379.376686 -221.45879) (xy 379.353572 -221.463108) (xy 379.150118 -221.815914)
			(xy 379.157738 -221.838012) (xy 379.165125 -221.860154) (xy 379.174301 -221.90592) (xy 379.176026 -221.929198)
			(xy 379.177168 -221.942411) (xy 379.185372 -221.96762) (xy 379.199792 -221.989866) (xy 379.219454 -222.007648)
			(xy 379.243033 -222.019765) (xy 379.268937 -222.025402) (xy 379.282198 -222.02521) (xy 379.321945 -222.023896)
			(xy 379.401324 -222.028775) (xy 379.479719 -222.042164) (xy 379.556218 -222.063908) (xy 379.629935 -222.093754)
			(xy 379.66523 -222.112078) (xy 379.670818 -222.115126) (xy 379.685042 -222.123508) (xy 379.700501 -222.131938)
			(xy 379.733604 -222.143926) (xy 379.768277 -222.150039) (xy 379.78588 -222.150432) (xy 379.803584 -222.15007)
			(xy 379.838453 -222.143923) (xy 379.871724 -222.131811) (xy 379.887226 -222.123254) (xy 379.923901 -222.10274)
			(xy 380.000964 -222.069223) (xy 380.081336 -222.044678) (xy 380.163976 -222.029423) (xy 380.247814 -222.023655)
			(xy 380.289816 -222.024956) (xy 380.303042 -222.025131) (xy 380.328875 -222.019494) (xy 380.352392 -222.007407)
			(xy 380.372011 -221.989682) (xy 380.386415 -221.967508) (xy 380.394635 -221.942378) (xy 380.395734 -221.929198)
			(xy 380.397545 -221.904847) (xy 380.407434 -221.857029) (xy 380.424249 -221.811186) (xy 380.447625 -221.768315)
			(xy 380.477052 -221.729349) (xy 380.511891 -221.695135) (xy 380.551384 -221.666419) (xy 380.594671 -221.643824)
			(xy 380.640811 -221.627842) (xy 380.66472 -221.622874) (xy 380.687834 -221.618556) (xy 380.891542 -221.264988)
			(xy 380.883922 -221.24289) (xy 380.875276 -221.216481) (xy 380.865954 -221.161706) (xy 380.86538 -221.133924)
			(xy 380.865889 -221.107957) (xy 380.874014 -221.056662) (xy 380.890062 -221.007269) (xy 380.91364 -220.960995)
			(xy 380.944166 -220.918979) (xy 380.980889 -220.882256) (xy 381.022905 -220.85173) (xy 381.069179 -220.828152)
			(xy 381.118572 -220.812104) (xy 381.169867 -220.803979) (xy 381.221801 -220.803979) (xy 381.273096 -220.812104)
			(xy 381.322489 -220.828152) (xy 381.368763 -220.85173) (xy 381.410779 -220.882256) (xy 381.447502 -220.918979)
			(xy 381.478028 -220.960995) (xy 381.501606 -221.007269) (xy 381.517654 -221.056662) (xy 381.525779 -221.107957)
			(xy 381.526288 -221.133924) (xy 381.525815 -221.159396) (xy 381.517992 -221.209734) (xy 381.502535 -221.258276)
			(xy 381.47981 -221.303869) (xy 381.450355 -221.345434) (xy 381.41487 -221.381985) (xy 381.374195 -221.412657)
			(xy 381.329293 -221.436721) (xy 381.281231 -221.453607) (xy 381.256286 -221.45879) (xy 381.233172 -221.463108)
			(xy 381.029718 -221.815914) (xy 381.037338 -221.838012) (xy 381.044725 -221.860154) (xy 381.053901 -221.90592)
			(xy 381.055626 -221.929198) (xy 381.056801 -221.942394) (xy 381.065047 -221.967561) (xy 381.079478 -221.989768)
			(xy 381.099127 -222.007524) (xy 381.122677 -222.01964) (xy 381.148547 -222.025303) (xy 381.161798 -222.02521)
			(xy 381.202238 -222.023882) (xy 381.282994 -222.028999) (xy 381.362704 -222.042921) (xy 381.440412 -222.065483)
			(xy 381.515185 -222.096412) (xy 381.550926 -222.11538) (xy 381.55499 -222.117666) (xy 381.564896 -222.123508)
			(xy 381.580356 -222.131933) (xy 381.61346 -222.143913) (xy 381.648132 -222.150017)
		)
		(stroke
			(width 0)
			(type solid)
		)
		(fill yes)
		(layer "In11.Cu")
		(net "PVCCFA_EHV_FIVRA_CPU0")
	)
	(gr_poly
		(pts
			(xy 181.922674 -34.788348) (xy 181.936572 -34.787879) (xy 181.963341 -34.780391) (xy 181.9871 -34.765962)
			(xy 182.006087 -34.74566) (xy 182.018897 -34.720991) (xy 182.02458 -34.693782) (xy 182.022716 -34.666048)
			(xy 182.013442 -34.639844) (xy 181.997446 -34.617111) (xy 181.986936 -34.608008) (xy 181.9654 -34.589789)
			(xy 181.92741 -34.548091) (xy 181.89597 -34.501257) (xy 181.871765 -34.450306) (xy 181.855321 -34.396347)
			(xy 181.846997 -34.340556) (xy 181.846474 -34.312352) (xy 181.846963 -34.285103) (xy 181.854725 -34.231159)
			(xy 181.870084 -34.178869) (xy 181.892728 -34.129297) (xy 181.922195 -34.083451) (xy 181.957886 -34.042265)
			(xy 181.999075 -34.006577) (xy 182.044923 -33.977113) (xy 182.094497 -33.954474) (xy 182.146788 -33.939119)
			(xy 182.200732 -33.931361) (xy 182.227982 -33.930844) (xy 182.256899 -33.931377) (xy 182.31407 -33.940102)
			(xy 182.369271 -33.957356) (xy 182.421235 -33.982742) (xy 182.468772 -34.01568) (xy 182.510794 -34.055415)
			(xy 182.528972 -34.07791) (xy 182.538869 -34.089715) (xy 182.564193 -34.107234) (xy 182.593586 -34.11641)
			(xy 182.624378 -34.11641) (xy 182.653771 -34.107234) (xy 182.679095 -34.089715) (xy 182.688992 -34.07791)
			(xy 182.707183 -34.055427) (xy 182.749201 -34.015692) (xy 182.796736 -33.982755) (xy 182.848698 -33.957371)
			(xy 182.903897 -33.940123) (xy 182.961066 -33.931405) (xy 182.989982 -33.930844) (xy 183.017235 -33.931329)
			(xy 183.071188 -33.939083) (xy 183.123487 -33.954436) (xy 183.17307 -33.977075) (xy 183.218926 -34.00654)
			(xy 183.260122 -34.042231) (xy 183.29582 -34.083421) (xy 183.325293 -34.129272) (xy 183.347941 -34.178851)
			(xy 183.363303 -34.231148) (xy 183.371067 -34.285099) (xy 183.37149 -34.312352) (xy 183.371037 -34.338863)
			(xy 183.363698 -34.391374) (xy 183.349153 -34.442361) (xy 183.327685 -34.490842) (xy 183.299706 -34.53588)
			(xy 183.265757 -34.576607) (xy 183.226493 -34.612238) (xy 183.18267 -34.642085) (xy 183.135135 -34.665573)
			(xy 183.084804 -34.682248) (xy 183.058816 -34.68751) (xy 183.01716 -34.69513) (xy 183.01716 -34.788348)
			(xy 183.261 -34.788348) (xy 184.060592 -33.988756) (xy 184.060592 -32.011112) (xy 184.060129 -31.997157)
			(xy 184.052515 -31.970305) (xy 184.037908 -31.946522) (xy 184.017402 -31.927587) (xy 183.992531 -31.914919)
			(xy 183.965158 -31.909466) (xy 183.937332 -31.911635) (xy 183.911135 -31.921265) (xy 183.899556 -31.92907)
			(xy 183.874985 -31.94612) (xy 183.821653 -31.973177) (xy 183.764756 -31.99159) (xy 183.705683 -32.000909)
			(xy 183.675782 -32.00146) (xy 183.648525 -32.000973) (xy 183.594565 -31.993213) (xy 183.542259 -31.977855)
			(xy 183.49267 -31.95521) (xy 183.446808 -31.92574) (xy 183.405605 -31.890044) (xy 183.369902 -31.848848)
			(xy 183.354726 -31.8262) (xy 183.346445 -31.814273) (xy 183.324509 -31.795269) (xy 183.298109 -31.783214)
			(xy 183.269382 -31.779084) (xy 183.240655 -31.783214) (xy 183.214255 -31.795269) (xy 183.192319 -31.814273)
			(xy 183.184038 -31.8262) (xy 183.168883 -31.848861) (xy 183.133168 -31.890046) (xy 183.091959 -31.925734)
			(xy 183.046093 -31.955198) (xy 182.996503 -31.97784) (xy 182.944197 -31.993199) (xy 182.890239 -32.000964)
			(xy 182.862982 -32.00146) (xy 182.835735 -32.000973) (xy 182.781796 -31.993215) (xy 182.72951 -31.97786)
			(xy 182.679942 -31.955221) (xy 182.634099 -31.925758) (xy 182.592916 -31.890071) (xy 182.557231 -31.848886)
			(xy 182.52777 -31.803043) (xy 182.505133 -31.753473) (xy 182.489781 -31.701186) (xy 182.482026 -31.647247)
			(xy 182.482026 -31.592753) (xy 182.489781 -31.538814) (xy 182.505133 -31.486527) (xy 182.52777 -31.436957)
			(xy 182.557231 -31.391114) (xy 182.592916 -31.349929) (xy 182.634099 -31.314242) (xy 182.679942 -31.284779)
			(xy 182.72951 -31.26214) (xy 182.781796 -31.246785) (xy 182.835735 -31.239027) (xy 182.862982 -31.238444)
			(xy 182.89024 -31.238929) (xy 182.944203 -31.246684) (xy 182.996513 -31.262039) (xy 183.046105 -31.284681)
			(xy 183.091971 -31.314149) (xy 183.133177 -31.349845) (xy 183.168885 -31.39104) (xy 183.184038 -31.413704)
			(xy 183.192319 -31.425631) (xy 183.214255 -31.444635) (xy 183.240655 -31.45669) (xy 183.269382 -31.46082)
			(xy 183.298109 -31.45669) (xy 183.324509 -31.444635) (xy 183.346445 -31.425631) (xy 183.354726 -31.413704)
			(xy 183.369881 -31.391042) (xy 183.405594 -31.349852) (xy 183.446802 -31.31416) (xy 183.492668 -31.284691)
			(xy 183.542258 -31.262045) (xy 183.594564 -31.24668) (xy 183.648524 -31.238911) (xy 183.675782 -31.238444)
			(xy 183.705685 -31.239003) (xy 183.764762 -31.248297) (xy 183.821663 -31.266705) (xy 183.874989 -31.293776)
			(xy 183.899556 -31.310834) (xy 183.911125 -31.318641) (xy 183.937324 -31.328228) (xy 183.965141 -31.330369)
			(xy 183.992499 -31.324905) (xy 184.017359 -31.312243) (xy 184.037866 -31.293327) (xy 184.052491 -31.269569)
			(xy 184.060142 -31.24274) (xy 184.060592 -31.228792) (xy 184.060592 -29.309568) (xy 184.061105 -29.284585)
			(xy 184.068959 -29.235239) (xy 184.084423 -29.187725) (xy 184.107116 -29.143209) (xy 184.136482 -29.102782)
			(xy 184.15381 -29.084778) (xy 185.223658 -28.01493) (xy 185.234098 -28.003689) (xy 185.248307 -27.976514)
			(xy 185.25383 -27.94635) (xy 185.250173 -27.915903) (xy 185.237662 -27.887906) (xy 185.217422 -27.864869)
			(xy 185.204608 -27.856434) (xy 185.181016 -27.8415) (xy 185.138069 -27.805822) (xy 185.100781 -27.764265)
			(xy 185.069949 -27.717716) (xy 185.046231 -27.66717) (xy 185.030134 -27.613707) (xy 185.022003 -27.558469)
			(xy 185.021474 -27.530552) (xy 185.021963 -27.503303) (xy 185.029725 -27.449359) (xy 185.045084 -27.397069)
			(xy 185.067728 -27.347497) (xy 185.097195 -27.301651) (xy 185.132886 -27.260465) (xy 185.174075 -27.224777)
			(xy 185.219923 -27.195313) (xy 185.269497 -27.172674) (xy 185.321788 -27.157319) (xy 185.375732 -27.149561)
			(xy 185.402982 -27.149044) (xy 185.430902 -27.149529) (xy 185.486145 -27.157665) (xy 185.539612 -27.173766)
			(xy 185.590162 -27.197488) (xy 185.636715 -27.228324) (xy 185.678276 -27.265615) (xy 185.713958 -27.308566)
			(xy 185.728864 -27.332178) (xy 185.737276 -27.345033) (xy 185.760285 -27.36537) (xy 185.788301 -27.377941)
			(xy 185.818789 -27.38161) (xy 185.848988 -27.376044) (xy 185.876165 -27.361747) (xy 185.88736 -27.351228)
			(xy 186.937904 -26.300684) (xy 186.948229 -26.289569) (xy 186.962435 -26.262782) (xy 186.968161 -26.233006)
			(xy 186.964902 -26.20286) (xy 186.952946 -26.174995) (xy 186.933344 -26.151863) (xy 186.920886 -26.143204)
			(xy 186.898185 -26.128086) (xy 186.856942 -26.092395) (xy 186.821199 -26.051196) (xy 186.791686 -26.005329)
			(xy 186.769003 -25.955728) (xy 186.753612 -25.903402) (xy 186.745827 -25.849419) (xy 186.745372 -25.822148)
			(xy 186.745832 -25.794892) (xy 186.753583 -25.740935) (xy 186.768935 -25.68863) (xy 186.791574 -25.639043)
			(xy 186.82104 -25.593182) (xy 186.856734 -25.551982) (xy 186.897928 -25.516281) (xy 186.943783 -25.486807)
			(xy 186.993366 -25.464158) (xy 187.045669 -25.448797) (xy 187.099624 -25.441036) (xy 187.12688 -25.44064)
			(xy 187.154151 -25.441104) (xy 187.208136 -25.448873) (xy 187.260464 -25.464256) (xy 187.310065 -25.486939)
			(xy 187.355928 -25.516459) (xy 187.397116 -25.552212) (xy 187.432789 -25.59347) (xy 187.447936 -25.616154)
			(xy 187.456586 -25.628616) (xy 187.479718 -25.648218) (xy 187.507582 -25.660171) (xy 187.537727 -25.663424)
			(xy 187.567499 -25.657691) (xy 187.59428 -25.643476) (xy 187.605416 -25.633172) (xy 187.890912 -25.347676)
			(xy 187.890912 -23.552658) (xy 187.839858 -23.501604) (xy 187.825888 -23.498048) (xy 187.798482 -23.49095)
			(xy 187.745987 -23.469761) (xy 187.697203 -23.44104) (xy 187.653204 -23.40542) (xy 187.614957 -23.363683)
			(xy 187.583305 -23.316748) (xy 187.558943 -23.265647) (xy 187.542408 -23.211506) (xy 187.534063 -23.155514)
			(xy 187.533534 -23.127208) (xy 187.533997 -23.099956) (xy 187.541753 -23.046006) (xy 187.557109 -22.99371)
			(xy 187.579751 -22.944131) (xy 187.60922 -22.89828) (xy 187.644914 -22.85709) (xy 187.686108 -22.8214)
			(xy 187.731961 -22.791935) (xy 187.781542 -22.769297) (xy 187.83384 -22.753946) (xy 187.88779 -22.746194)
			(xy 187.915042 -22.7457) (xy 187.943346 -22.746218) (xy 187.999332 -22.754589) (xy 188.053466 -22.771141)
			(xy 188.10456 -22.795511) (xy 188.151492 -22.827163) (xy 188.193232 -22.865402) (xy 188.228862 -22.90939)
			(xy 188.257602 -22.95816) (xy 188.27882 -23.010641) (xy 188.285882 -23.038054) (xy 188.289438 -23.052024)
			(xy 188.43371 -23.196296) (xy 188.451066 -23.21428) (xy 188.480471 -23.254692) (xy 188.503184 -23.29921)
			(xy 188.518646 -23.346736) (xy 188.526475 -23.396097) (xy 188.526928 -23.421086) (xy 188.526928 -23.593552)
			(xy 190.126874 -23.593552) (xy 190.127385 -23.565979) (xy 190.135329 -23.511409) (xy 190.151046 -23.45855)
			(xy 190.174208 -23.408504) (xy 190.204332 -23.362313) (xy 190.240791 -23.32094) (xy 190.261494 -23.302722)
			(xy 190.272439 -23.292872) (xy 190.288511 -23.268208) (xy 190.296889 -23.239988) (xy 190.29688 -23.21055)
			(xy 190.288484 -23.182335) (xy 190.272398 -23.157681) (xy 190.261494 -23.147782) (xy 190.24077 -23.129585)
			(xy 190.204301 -23.088213) (xy 190.17417 -23.04202) (xy 190.151007 -22.99197) (xy 190.135293 -22.939104)
			(xy 190.127357 -22.884528) (xy 190.126874 -22.856952) (xy 190.12736 -22.829701) (xy 190.135116 -22.775753)
			(xy 190.150471 -22.723458) (xy 190.173113 -22.673881) (xy 190.202579 -22.628031) (xy 190.23827 -22.58684)
			(xy 190.279461 -22.551149) (xy 190.325311 -22.521683) (xy 190.374888 -22.499041) (xy 190.427183 -22.483686)
			(xy 190.481131 -22.47593) (xy 190.535633 -22.47593) (xy 190.589581 -22.483686) (xy 190.641876 -22.499041)
			(xy 190.691453 -22.521683) (xy 190.737303 -22.551149) (xy 190.778494 -22.58684) (xy 190.814185 -22.628031)
			(xy 190.843651 -22.673881) (xy 190.866293 -22.723458) (xy 190.881648 -22.775753) (xy 190.889404 -22.829701)
			(xy 190.88989 -22.856952) (xy 190.889395 -22.884526) (xy 190.881449 -22.939097) (xy 190.86573 -22.991957)
			(xy 190.842565 -23.042003) (xy 190.812438 -23.088193) (xy 190.775975 -23.129565) (xy 190.75527 -23.147782)
			(xy 190.744424 -23.157731) (xy 190.728355 -23.182368) (xy 190.719969 -23.210562) (xy 190.71996 -23.239976)
			(xy 190.728329 -23.268175) (xy 190.744383 -23.292822) (xy 190.75527 -23.302722) (xy 190.775989 -23.320925)
			(xy 190.81246 -23.362295) (xy 190.842592 -23.408486) (xy 190.865757 -23.458536) (xy 190.881471 -23.5114)
			(xy 190.889407 -23.565977) (xy 190.88989 -23.593552) (xy 190.889404 -23.620803) (xy 190.881648 -23.674751)
			(xy 190.866293 -23.727046) (xy 190.843651 -23.776623) (xy 190.814185 -23.822473) (xy 190.778494 -23.863664)
			(xy 190.737303 -23.899355) (xy 190.691453 -23.928821) (xy 190.641876 -23.951463) (xy 190.589581 -23.966818)
			(xy 190.535633 -23.974574) (xy 190.481131 -23.974574) (xy 190.427183 -23.966818) (xy 190.374888 -23.951463)
			(xy 190.325311 -23.928821) (xy 190.279461 -23.899355) (xy 190.23827 -23.863664) (xy 190.202579 -23.822473)
			(xy 190.173113 -23.776623) (xy 190.150471 -23.727046) (xy 190.135116 -23.674751) (xy 190.12736 -23.620803)
			(xy 190.126874 -23.593552) (xy 188.526928 -23.593552) (xy 188.526928 -24.036528) (xy 188.856872 -24.036528)
			(xy 188.860943 -23.980906) (xy 188.873069 -23.926469) (xy 188.892992 -23.874378) (xy 188.920288 -23.825743)
			(xy 188.954374 -23.7816) (xy 188.994523 -23.742891) (xy 189.039881 -23.71044) (xy 189.089481 -23.684939)
			(xy 189.142265 -23.666932) (xy 189.197108 -23.656802) (xy 189.252842 -23.654765) (xy 189.308279 -23.660865)
			(xy 189.362236 -23.674971) (xy 189.413565 -23.696783) (xy 189.461171 -23.725837) (xy 189.504039 -23.761512)
			(xy 189.541256 -23.803049) (xy 189.572029 -23.849562) (xy 189.595701 -23.900059) (xy 189.611769 -23.953466)
			(xy 189.619889 -24.008642) (xy 189.620398 -24.036528) (xy 189.619889 -24.064414) (xy 189.611769 -24.11959)
			(xy 189.595701 -24.172997) (xy 189.572029 -24.223494) (xy 189.541256 -24.270007) (xy 189.504039 -24.311544)
			(xy 189.461171 -24.347219) (xy 189.413565 -24.376273) (xy 189.362236 -24.398085) (xy 189.308279 -24.412191)
			(xy 189.252842 -24.418291) (xy 189.197108 -24.416254) (xy 189.142265 -24.406124) (xy 189.089481 -24.388117)
			(xy 189.039881 -24.362616) (xy 188.994523 -24.330165) (xy 188.954374 -24.291456) (xy 188.920288 -24.247313)
			(xy 188.892992 -24.198678) (xy 188.873069 -24.146587) (xy 188.860943 -24.09215) (xy 188.856872 -24.036528)
			(xy 188.526928 -24.036528) (xy 188.526928 -24.686049) (xy 191.338206 -24.686049) (xy 191.338206 -24.631551)
			(xy 191.345962 -24.577607) (xy 191.361316 -24.525316) (xy 191.383956 -24.475743) (xy 191.41342 -24.429896)
			(xy 191.449109 -24.388709) (xy 191.490296 -24.35302) (xy 191.536143 -24.323556) (xy 191.585716 -24.300916)
			(xy 191.638007 -24.285562) (xy 191.691951 -24.277806) (xy 191.7192 -24.27732) (xy 191.744806 -24.277739)
			(xy 191.795561 -24.284561) (xy 191.844948 -24.298108) (xy 191.892081 -24.318138) (xy 191.936111 -24.344291)
			(xy 191.956436 -24.35987) (xy 191.968626 -24.368901) (xy 191.996881 -24.379922) (xy 192.027124 -24.38217)
			(xy 192.056698 -24.375449) (xy 192.082999 -24.360349) (xy 192.103714 -24.3382) (xy 192.110868 -24.324818)
			(xy 192.122938 -24.301012) (xy 192.152705 -24.256709) (xy 192.188359 -24.216989) (xy 192.229202 -24.182629)
			(xy 192.274438 -24.1543) (xy 192.323182 -24.132555) (xy 192.374481 -24.117818) (xy 192.427335 -24.110379)
			(xy 192.454022 -24.109934) (xy 192.481275 -24.110337) (xy 192.535227 -24.118097) (xy 192.587524 -24.133456)
			(xy 192.637104 -24.156101) (xy 192.682957 -24.185571) (xy 192.724149 -24.221266) (xy 192.759842 -24.262461)
			(xy 192.78931 -24.308315) (xy 192.811952 -24.357896) (xy 192.827307 -24.410195) (xy 192.835064 -24.464147)
			(xy 192.835064 -24.518653) (xy 192.827307 -24.572605) (xy 192.811952 -24.624904) (xy 192.78931 -24.674485)
			(xy 192.759842 -24.720339) (xy 192.724149 -24.761534) (xy 192.682957 -24.797229) (xy 192.637104 -24.826699)
			(xy 192.587524 -24.849344) (xy 192.535227 -24.864703) (xy 192.481275 -24.872463) (xy 192.454022 -24.87295)
			(xy 192.428416 -24.872525) (xy 192.377661 -24.865706) (xy 192.328273 -24.85216) (xy 192.281141 -24.832131)
			(xy 192.237111 -24.805979) (xy 192.216786 -24.7904) (xy 192.204572 -24.781406) (xy 192.176326 -24.770387)
			(xy 192.146091 -24.768136) (xy 192.116524 -24.77485) (xy 192.090227 -24.789939) (xy 192.069511 -24.812077)
			(xy 192.062354 -24.825452) (xy 192.050254 -24.849242) (xy 192.020492 -24.893546) (xy 191.984844 -24.933267)
			(xy 191.944005 -24.967629) (xy 191.898773 -24.99596) (xy 191.850033 -25.017708) (xy 191.798737 -25.032447)
			(xy 191.745886 -25.039889) (xy 191.7192 -25.040336) (xy 191.691951 -25.039794) (xy 191.638007 -25.032038)
			(xy 191.585716 -25.016684) (xy 191.536143 -24.994044) (xy 191.490296 -24.96458) (xy 191.449109 -24.928891)
			(xy 191.41342 -24.887704) (xy 191.383956 -24.841857) (xy 191.361316 -24.792284) (xy 191.345962 -24.739993)
			(xy 191.338206 -24.686049) (xy 188.526928 -24.686049) (xy 188.526928 -25.479248) (xy 188.526413 -25.504231)
			(xy 188.518558 -25.553576) (xy 188.514559 -25.565862) (xy 192.072004 -25.565862) (xy 192.076075 -25.51024)
			(xy 192.088201 -25.455803) (xy 192.108124 -25.403712) (xy 192.13542 -25.355077) (xy 192.169506 -25.310934)
			(xy 192.209655 -25.272225) (xy 192.255013 -25.239774) (xy 192.304613 -25.214273) (xy 192.357397 -25.196266)
			(xy 192.41224 -25.186136) (xy 192.467974 -25.184099) (xy 192.523411 -25.190199) (xy 192.577368 -25.204305)
			(xy 192.628697 -25.226117) (xy 192.676303 -25.255171) (xy 192.719171 -25.290846) (xy 192.756388 -25.332383)
			(xy 192.787161 -25.378896) (xy 192.810833 -25.429393) (xy 192.826901 -25.4828) (xy 192.835021 -25.537976)
			(xy 192.83553 -25.565862) (xy 192.835021 -25.593748) (xy 192.826901 -25.648924) (xy 192.810833 -25.702331)
			(xy 192.787161 -25.752828) (xy 192.756388 -25.799341) (xy 192.719171 -25.840878) (xy 192.676303 -25.876553)
			(xy 192.628697 -25.905607) (xy 192.577368 -25.927419) (xy 192.523411 -25.941525) (xy 192.467974 -25.947625)
			(xy 192.41224 -25.945588) (xy 192.357397 -25.935458) (xy 192.304613 -25.917451) (xy 192.255013 -25.89195)
			(xy 192.209655 -25.859499) (xy 192.169506 -25.82079) (xy 192.13542 -25.776647) (xy 192.108124 -25.728012)
			(xy 192.088201 -25.675921) (xy 192.076075 -25.621484) (xy 192.072004 -25.565862) (xy 188.514559 -25.565862)
			(xy 188.503093 -25.601089) (xy 188.4804 -25.645604) (xy 188.451034 -25.68603) (xy 188.43371 -25.704038)
			(xy 187.05068 -27.087068) (xy 190.295782 -27.087068) (xy 190.299853 -27.031446) (xy 190.311979 -26.977009)
			(xy 190.331902 -26.924918) (xy 190.359198 -26.876283) (xy 190.393284 -26.83214) (xy 190.433433 -26.793431)
			(xy 190.478791 -26.76098) (xy 190.528391 -26.735479) (xy 190.581175 -26.717472) (xy 190.636018 -26.707342)
			(xy 190.691752 -26.705305) (xy 190.747189 -26.711405) (xy 190.801146 -26.725511) (xy 190.852475 -26.747323)
			(xy 190.900081 -26.776377) (xy 190.942949 -26.812052) (xy 190.980166 -26.853589) (xy 191.010939 -26.900102)
			(xy 191.034611 -26.950599) (xy 191.050679 -27.004006) (xy 191.058799 -27.059182) (xy 191.059308 -27.087068)
			(xy 191.058799 -27.114954) (xy 191.050679 -27.17013) (xy 191.034611 -27.223537) (xy 191.010939 -27.274034)
			(xy 190.980166 -27.320547) (xy 190.942949 -27.362084) (xy 190.900081 -27.397759) (xy 190.852475 -27.426813)
			(xy 190.801146 -27.448625) (xy 190.747189 -27.462731) (xy 190.691752 -27.468831) (xy 190.636018 -27.466794)
			(xy 190.581175 -27.456664) (xy 190.528391 -27.438657) (xy 190.478791 -27.413156) (xy 190.433433 -27.380705)
			(xy 190.393284 -27.341996) (xy 190.359198 -27.297853) (xy 190.331902 -27.249218) (xy 190.311979 -27.197127)
			(xy 190.299853 -27.14269) (xy 190.295782 -27.087068) (xy 187.05068 -27.087068) (xy 186.51728 -27.620468)
			(xy 187.910214 -27.620468) (xy 187.914285 -27.564846) (xy 187.926411 -27.510409) (xy 187.946334 -27.458318)
			(xy 187.97363 -27.409683) (xy 188.007716 -27.36554) (xy 188.047865 -27.326831) (xy 188.093223 -27.29438)
			(xy 188.142823 -27.268879) (xy 188.195607 -27.250872) (xy 188.25045 -27.240742) (xy 188.306184 -27.238705)
			(xy 188.361621 -27.244805) (xy 188.415578 -27.258911) (xy 188.466907 -27.280723) (xy 188.514513 -27.309777)
			(xy 188.557381 -27.345452) (xy 188.594598 -27.386989) (xy 188.625371 -27.433502) (xy 188.649043 -27.483999)
			(xy 188.665111 -27.537406) (xy 188.67098 -27.577288) (xy 189.414402 -27.577288) (xy 189.418473 -27.521666)
			(xy 189.430599 -27.467229) (xy 189.450522 -27.415138) (xy 189.477818 -27.366503) (xy 189.511904 -27.32236)
			(xy 189.552053 -27.283651) (xy 189.597411 -27.2512) (xy 189.647011 -27.225699) (xy 189.699795 -27.207692)
			(xy 189.754638 -27.197562) (xy 189.810372 -27.195525) (xy 189.865809 -27.201625) (xy 189.919766 -27.215731)
			(xy 189.971095 -27.237543) (xy 190.018701 -27.266597) (xy 190.061569 -27.302272) (xy 190.098786 -27.343809)
			(xy 190.129559 -27.390322) (xy 190.153231 -27.440819) (xy 190.169299 -27.494226) (xy 190.177419 -27.549402)
			(xy 190.177928 -27.577288) (xy 190.177419 -27.605174) (xy 190.169299 -27.66035) (xy 190.153231 -27.713757)
			(xy 190.129559 -27.764254) (xy 190.098786 -27.810767) (xy 190.061569 -27.852304) (xy 190.018701 -27.887979)
			(xy 189.971095 -27.917033) (xy 189.919766 -27.938845) (xy 189.865809 -27.952951) (xy 189.810372 -27.959051)
			(xy 189.754638 -27.957014) (xy 189.699795 -27.946884) (xy 189.647011 -27.928877) (xy 189.597411 -27.903376)
			(xy 189.552053 -27.870925) (xy 189.511904 -27.832216) (xy 189.477818 -27.788073) (xy 189.450522 -27.739438)
			(xy 189.430599 -27.687347) (xy 189.418473 -27.63291) (xy 189.414402 -27.577288) (xy 188.67098 -27.577288)
			(xy 188.673231 -27.592582) (xy 188.67374 -27.620468) (xy 188.673231 -27.648354) (xy 188.665111 -27.70353)
			(xy 188.649043 -27.756937) (xy 188.625371 -27.807434) (xy 188.594598 -27.853947) (xy 188.557381 -27.895484)
			(xy 188.514513 -27.931159) (xy 188.466907 -27.960213) (xy 188.415578 -27.982025) (xy 188.361621 -27.996131)
			(xy 188.306184 -28.002231) (xy 188.25045 -28.000194) (xy 188.195607 -27.990064) (xy 188.142823 -27.972057)
			(xy 188.093223 -27.946556) (xy 188.047865 -27.914105) (xy 188.007716 -27.875396) (xy 187.97363 -27.831253)
			(xy 187.946334 -27.782618) (xy 187.926411 -27.730527) (xy 187.914285 -27.67609) (xy 187.910214 -27.620468)
			(xy 186.51728 -27.620468) (xy 184.696608 -29.44114) (xy 184.696608 -29.537152) (xy 189.618364 -29.537152)
			(xy 189.622435 -29.48153) (xy 189.634561 -29.427093) (xy 189.654484 -29.375002) (xy 189.68178 -29.326367)
			(xy 189.715866 -29.282224) (xy 189.756015 -29.243515) (xy 189.801373 -29.211064) (xy 189.850973 -29.185563)
			(xy 189.903757 -29.167556) (xy 189.9586 -29.157426) (xy 190.014334 -29.155389) (xy 190.069771 -29.161489)
			(xy 190.123728 -29.175595) (xy 190.175057 -29.197407) (xy 190.222663 -29.226461) (xy 190.265531 -29.262136)
			(xy 190.302748 -29.303673) (xy 190.333521 -29.350186) (xy 190.357193 -29.400683) (xy 190.373261 -29.45409)
			(xy 190.381381 -29.509266) (xy 190.38189 -29.537152) (xy 190.381381 -29.565038) (xy 190.373261 -29.620214)
			(xy 190.357193 -29.673621) (xy 190.333521 -29.724118) (xy 190.302748 -29.770631) (xy 190.265531 -29.812168)
			(xy 190.222663 -29.847843) (xy 190.175057 -29.876897) (xy 190.123728 -29.898709) (xy 190.069771 -29.912815)
			(xy 190.014334 -29.918915) (xy 189.9586 -29.916878) (xy 189.903757 -29.906748) (xy 189.850973 -29.888741)
			(xy 189.801373 -29.86324) (xy 189.756015 -29.830789) (xy 189.715866 -29.79208) (xy 189.68178 -29.747937)
			(xy 189.654484 -29.699302) (xy 189.634561 -29.647211) (xy 189.622435 -29.592774) (xy 189.618364 -29.537152)
			(xy 184.696608 -29.537152) (xy 184.696608 -31.724092) (xy 184.697072 -31.738349) (xy 184.704934 -31.765758)
			(xy 184.720075 -31.789919) (xy 184.741312 -31.808947) (xy 184.766985 -31.821353) (xy 184.795089 -31.82617)
			(xy 184.823428 -31.82302) (xy 184.849789 -31.81215) (xy 184.8612 -31.803594) (xy 184.881503 -31.788025)
			(xy 184.925484 -31.761883) (xy 184.972564 -31.741851) (xy 185.021897 -31.728288) (xy 185.0726 -31.721438)
			(xy 185.098182 -31.721044) (xy 185.125435 -31.721529) (xy 185.179388 -31.729283) (xy 185.231687 -31.744636)
			(xy 185.28127 -31.767275) (xy 185.327126 -31.79674) (xy 185.368322 -31.832431) (xy 185.40402 -31.873621)
			(xy 185.433493 -31.919472) (xy 185.456141 -31.969051) (xy 185.471503 -32.021348) (xy 185.479267 -32.075299)
			(xy 185.47969 -32.102552) (xy 185.479207 -32.130127) (xy 185.47127 -32.184703) (xy 185.455555 -32.237567)
			(xy 185.43239 -32.287617) (xy 185.402258 -32.333808) (xy 185.365787 -32.375177) (xy 185.34507 -32.393382)
			(xy 185.334169 -32.403282) (xy 185.318088 -32.427937) (xy 185.309696 -32.456151) (xy 185.309687 -32.485587)
			(xy 185.318062 -32.513806) (xy 185.334127 -32.538471) (xy 185.34507 -32.548322) (xy 185.365775 -32.566539)
			(xy 185.402237 -32.607911) (xy 185.432364 -32.654101) (xy 185.455528 -32.704148) (xy 185.471247 -32.757007)
			(xy 185.479192 -32.811579) (xy 185.47969 -32.839152) (xy 185.479271 -32.865472) (xy 185.472075 -32.917618)
			(xy 185.457773 -32.968277) (xy 185.436637 -33.016487) (xy 185.409068 -33.06133) (xy 185.375591 -33.101953)
			(xy 185.3565 -33.120076) (xy 185.346473 -33.129888) (xy 185.331763 -33.153765) (xy 185.324114 -33.180746)
			(xy 185.324105 -33.20879) (xy 185.331737 -33.235776) (xy 185.346432 -33.259661) (xy 185.3565 -33.269428)
			(xy 185.375562 -33.287577) (xy 185.409018 -33.328209) (xy 185.436576 -33.37305) (xy 185.457713 -33.421252)
			(xy 185.472029 -33.471901) (xy 185.479252 -33.524036) (xy 185.47969 -33.550352) (xy 185.47923 -33.577607)
			(xy 185.471478 -33.631562) (xy 185.456126 -33.683864) (xy 185.433486 -33.733449) (xy 185.404019 -33.779307)
			(xy 185.368325 -33.820504) (xy 185.327131 -33.856201) (xy 185.281276 -33.885672) (xy 185.231693 -33.908316)
			(xy 185.179391 -33.923672) (xy 185.125437 -33.931428) (xy 185.098182 -33.93186) (xy 185.072601 -33.931446)
			(xy 185.021899 -33.924604) (xy 184.972567 -33.911044) (xy 184.925491 -33.89101) (xy 184.881516 -33.864862)
			(xy 184.8612 -33.84931) (xy 184.849739 -33.840854) (xy 184.823398 -33.830051) (xy 184.795098 -33.82694)
			(xy 184.767039 -33.831764) (xy 184.741403 -33.844147) (xy 184.720183 -33.863127) (xy 184.705028 -33.887229)
			(xy 184.697116 -33.914578) (xy 184.696608 -33.928812) (xy 184.696608 -34.120328) (xy 184.696095 -34.145311)
			(xy 184.688241 -34.194657) (xy 184.672779 -34.242172) (xy 184.650086 -34.286689) (xy 184.62072 -34.327116)
			(xy 184.60339 -34.345118) (xy 184.333642 -34.614866) (xy 184.323428 -34.625833) (xy 184.309303 -34.652249)
			(xy 184.303446 -34.681626) (xy 184.30636 -34.711439) (xy 184.317795 -34.739126) (xy 184.336767 -34.762307)
			(xy 184.361646 -34.77899) (xy 184.390294 -34.787742) (xy 184.40527 -34.788348) (xy 187.121292 -34.788348)
			(xy 187.134445 -34.787937) (xy 187.159878 -34.781217) (xy 187.18275 -34.768221) (xy 187.201541 -34.749812)
			(xy 187.215004 -34.727212) (xy 187.222245 -34.701922) (xy 187.222892 -34.68878) (xy 187.223885 -34.661882)
			(xy 187.2325 -34.608751) (xy 187.248497 -34.557358) (xy 187.27156 -34.508724) (xy 187.30123 -34.463815)
			(xy 187.336918 -34.423523) (xy 187.377916 -34.388647) (xy 187.423408 -34.35988) (xy 187.472493 -34.337793)
			(xy 187.524195 -34.322825) (xy 187.577487 -34.315273) (xy 187.6044 -34.314892) (xy 187.632702 -34.315414)
			(xy 187.688682 -34.323792) (xy 187.742809 -34.340349) (xy 187.793897 -34.364722) (xy 187.840822 -34.396376)
			(xy 187.882555 -34.434616) (xy 187.918181 -34.478602) (xy 187.946916 -34.527369) (xy 187.96813 -34.579847)
			(xy 187.97524 -34.607246) (xy 187.978796 -34.621216) (xy 188.145928 -34.788348) (xy 190.504826 -34.788348)
			(xy 190.521549 -34.766884) (xy 190.560075 -34.728461) (xy 190.603668 -34.695902) (xy 190.651445 -34.669866)
			(xy 190.702436 -34.650882) (xy 190.755608 -34.639335) (xy 190.80988 -34.63546) (xy 190.864152 -34.639335)
			(xy 190.917324 -34.650882) (xy 190.968315 -34.669866) (xy 191.016092 -34.695902) (xy 191.059685 -34.728461)
			(xy 191.098211 -34.766884) (xy 191.114934 -34.788348) (xy 193.40068 -34.788348) (xy 194.08648 -34.102548)
			(xy 194.08648 -29.03982) (xy 193.764408 -28.717748) (xy 193.350134 -28.717748) (xy 193.326556 -28.732793)
			(xy 193.275925 -28.756559) (xy 193.222365 -28.772669) (xy 193.167026 -28.78078) (xy 193.13906 -28.781248)
			(xy 193.111808 -28.780759) (xy 193.057859 -28.772997) (xy 193.005563 -28.757637) (xy 192.955986 -28.734991)
			(xy 192.910136 -28.705521) (xy 192.868946 -28.669826) (xy 192.833255 -28.628632) (xy 192.803789 -28.582779)
			(xy 192.781149 -28.533199) (xy 192.765794 -28.480902) (xy 192.758038 -28.426952) (xy 192.758038 -28.372448)
			(xy 192.765794 -28.318498) (xy 192.781149 -28.266201) (xy 192.803789 -28.216621) (xy 192.833255 -28.170768)
			(xy 192.868946 -28.129574) (xy 192.910136 -28.093879) (xy 192.955986 -28.064409) (xy 193.005563 -28.041763)
			(xy 193.057859 -28.026403) (xy 193.111808 -28.018641) (xy 193.13906 -28.018232) (xy 193.165263 -28.018664)
			(xy 193.217175 -28.025834) (xy 193.267617 -28.040045) (xy 193.315638 -28.061028) (xy 193.338196 -28.074366)
			(xy 193.350388 -28.081732) (xy 193.43243 -28.081732) (xy 193.447412 -28.081211) (xy 193.47609 -28.072533)
			(xy 193.501015 -28.055905) (xy 193.52004 -28.032758) (xy 193.531527 -28.005085) (xy 193.534486 -27.975269)
			(xy 193.528664 -27.945877) (xy 193.514561 -27.919442) (xy 193.504312 -27.908504) (xy 193.318892 -27.72283)
			(xy 193.295723 -27.698932) (xy 193.255197 -27.646129) (xy 193.221912 -27.588486) (xy 193.196439 -27.526991)
			(xy 193.179214 -27.462695) (xy 193.170533 -27.396701) (xy 193.170048 -27.36342) (xy 193.170048 -24.037544)
			(xy 192.838578 -23.706328) (xy 192.827588 -23.696092) (xy 192.801112 -23.681946) (xy 192.771669 -23.6761)
			(xy 192.741798 -23.679059) (xy 192.714073 -23.690567) (xy 192.690887 -23.709632) (xy 192.682114 -23.721822)
			(xy 192.666882 -23.743923) (xy 192.631208 -23.784028) (xy 192.590267 -23.81874) (xy 192.544867 -23.847373)
			(xy 192.495903 -23.869363) (xy 192.44434 -23.884276) (xy 192.391198 -23.891819) (xy 192.36436 -23.892256)
			(xy 192.336057 -23.891738) (xy 192.280073 -23.883367) (xy 192.22594 -23.866814) (xy 192.174849 -23.842444)
			(xy 192.12792 -23.81079) (xy 192.086183 -23.772549) (xy 192.050557 -23.72856) (xy 192.021822 -23.679789)
			(xy 192.00061 -23.627307) (xy 191.99352 -23.599902) (xy 191.989964 -23.585932) (xy 190.62954 -22.225508)
			(xy 183.323992 -22.225508) (xy 182.439564 -23.109936) (xy 184.407554 -23.109936) (xy 184.411625 -23.054314)
			(xy 184.423751 -22.999877) (xy 184.443674 -22.947786) (xy 184.47097 -22.899151) (xy 184.505056 -22.855008)
			(xy 184.545205 -22.816299) (xy 184.590563 -22.783848) (xy 184.640163 -22.758347) (xy 184.692947 -22.74034)
			(xy 184.74779 -22.73021) (xy 184.803524 -22.728173) (xy 184.858961 -22.734273) (xy 184.912918 -22.748379)
			(xy 184.964247 -22.770191) (xy 185.011853 -22.799245) (xy 185.054721 -22.83492) (xy 185.091938 -22.876457)
			(xy 185.122711 -22.92297) (xy 185.146383 -22.973467) (xy 185.162451 -23.026874) (xy 185.170571 -23.08205)
			(xy 185.17108 -23.109936) (xy 185.170571 -23.137822) (xy 185.162451 -23.192998) (xy 185.146383 -23.246405)
			(xy 185.122711 -23.296902) (xy 185.091938 -23.343415) (xy 185.054721 -23.384952) (xy 185.011853 -23.420627)
			(xy 184.964247 -23.449681) (xy 184.912918 -23.471493) (xy 184.858961 -23.485599) (xy 184.803524 -23.491699)
			(xy 184.74779 -23.489662) (xy 184.692947 -23.479532) (xy 184.640163 -23.461525) (xy 184.590563 -23.436024)
			(xy 184.545205 -23.403573) (xy 184.505056 -23.364864) (xy 184.47097 -23.320721) (xy 184.443674 -23.272086)
			(xy 184.423751 -23.219995) (xy 184.411625 -23.165558) (xy 184.407554 -23.109936) (xy 182.439564 -23.109936)
			(xy 181.99735 -23.55215) (xy 181.979366 -23.569506) (xy 181.938954 -23.598909) (xy 181.894436 -23.621619)
			(xy 181.846909 -23.637076) (xy 181.797548 -23.644898) (xy 181.77256 -23.645368) (xy 172.386752 -23.645368)
			(xy 171.905168 -24.126952) (xy 186.503562 -24.126952) (xy 186.507633 -24.07133) (xy 186.519759 -24.016893)
			(xy 186.539682 -23.964802) (xy 186.566978 -23.916167) (xy 186.601064 -23.872024) (xy 186.641213 -23.833315)
			(xy 186.686571 -23.800864) (xy 186.736171 -23.775363) (xy 186.788955 -23.757356) (xy 186.843798 -23.747226)
			(xy 186.899532 -23.745189) (xy 186.954969 -23.751289) (xy 187.008926 -23.765395) (xy 187.060255 -23.787207)
			(xy 187.107861 -23.816261) (xy 187.150729 -23.851936) (xy 187.187946 -23.893473) (xy 187.218719 -23.939986)
			(xy 187.242391 -23.990483) (xy 187.258459 -24.04389) (xy 187.266579 -24.099066) (xy 187.267088 -24.126952)
			(xy 187.266579 -24.154838) (xy 187.258459 -24.210014) (xy 187.242391 -24.263421) (xy 187.218719 -24.313918)
			(xy 187.187946 -24.360431) (xy 187.150729 -24.401968) (xy 187.107861 -24.437643) (xy 187.060255 -24.466697)
			(xy 187.008926 -24.488509) (xy 186.954969 -24.502615) (xy 186.899532 -24.508715) (xy 186.843798 -24.506678)
			(xy 186.788955 -24.496548) (xy 186.736171 -24.478541) (xy 186.686571 -24.45304) (xy 186.641213 -24.420589)
			(xy 186.601064 -24.38188) (xy 186.566978 -24.337737) (xy 186.539682 -24.289102) (xy 186.519759 -24.237011)
			(xy 186.507633 -24.182574) (xy 186.503562 -24.126952) (xy 171.905168 -24.126952) (xy 171.823888 -24.208232)
			(xy 171.823888 -25.517348) (xy 179.124862 -25.517348) (xy 179.128933 -25.461726) (xy 179.141059 -25.407289)
			(xy 179.160982 -25.355198) (xy 179.188278 -25.306563) (xy 179.222364 -25.26242) (xy 179.262513 -25.223711)
			(xy 179.307871 -25.19126) (xy 179.357471 -25.165759) (xy 179.410255 -25.147752) (xy 179.465098 -25.137622)
			(xy 179.520832 -25.135585) (xy 179.576269 -25.141685) (xy 179.630226 -25.155791) (xy 179.681555 -25.177603)
			(xy 179.729161 -25.206657) (xy 179.772029 -25.242332) (xy 179.809246 -25.283869) (xy 179.840019 -25.330382)
			(xy 179.863691 -25.380879) (xy 179.879759 -25.434286) (xy 179.887879 -25.489462) (xy 179.888388 -25.517348)
			(xy 179.887879 -25.545234) (xy 179.879759 -25.60041) (xy 179.863691 -25.653817) (xy 179.840019 -25.704314)
			(xy 179.809246 -25.750827) (xy 179.772029 -25.792364) (xy 179.729161 -25.828039) (xy 179.681555 -25.857093)
			(xy 179.630226 -25.878905) (xy 179.576269 -25.893011) (xy 179.520832 -25.899111) (xy 179.465098 -25.897074)
			(xy 179.410255 -25.886944) (xy 179.357471 -25.868937) (xy 179.307871 -25.843436) (xy 179.262513 -25.810985)
			(xy 179.222364 -25.772276) (xy 179.188278 -25.728133) (xy 179.160982 -25.679498) (xy 179.141059 -25.627407)
			(xy 179.128933 -25.57297) (xy 179.124862 -25.517348) (xy 171.823888 -25.517348) (xy 171.823888 -25.855168)
			(xy 172.233844 -26.265124) (xy 172.247814 -26.26868) (xy 172.274933 -26.275678) (xy 172.326909 -26.29654)
			(xy 172.375276 -26.324776) (xy 172.418995 -26.359781) (xy 172.457127 -26.400802) (xy 172.473366 -26.42362)
			(xy 172.482304 -26.435735) (xy 172.505789 -26.454547) (xy 172.533737 -26.465698) (xy 172.563722 -26.468222)
			(xy 172.59314 -26.461897) (xy 172.619439 -26.447274) (xy 172.640335 -26.425622) (xy 172.64761 -26.412444)
			(xy 172.659909 -26.38928) (xy 172.689906 -26.34626) (xy 172.72551 -26.307752) (xy 172.766053 -26.274483)
			(xy 172.810769 -26.247079) (xy 172.858817 -26.226055) (xy 172.90929 -26.211809) (xy 172.961239 -26.204609)
			(xy 172.987462 -26.204164) (xy 173.014719 -26.204624) (xy 173.068678 -26.212377) (xy 173.120984 -26.227731)
			(xy 173.170573 -26.250373) (xy 173.216434 -26.279843) (xy 173.257634 -26.315539) (xy 173.293335 -26.356736)
			(xy 173.322808 -26.402594) (xy 173.345455 -26.45218) (xy 173.360814 -26.504485) (xy 173.368573 -26.558443)
			(xy 173.368573 -26.612957) (xy 173.360814 -26.666915) (xy 173.345455 -26.71922) (xy 173.322808 -26.768806)
			(xy 173.293335 -26.814664) (xy 173.257634 -26.855861) (xy 173.216434 -26.891557) (xy 173.170573 -26.921027)
			(xy 173.120984 -26.943669) (xy 173.068678 -26.959023) (xy 173.014719 -26.966776) (xy 172.987462 -26.96718)
			(xy 172.961029 -26.966729) (xy 172.908668 -26.959431) (xy 172.857815 -26.944981) (xy 172.80944 -26.923654)
			(xy 172.764471 -26.895859) (xy 172.723765 -26.862126) (xy 172.688101 -26.8231) (xy 172.672756 -26.801572)
			(xy 172.663818 -26.78947) (xy 172.64034 -26.770682) (xy 172.612407 -26.759551) (xy 172.582442 -26.757041)
			(xy 172.553047 -26.763372) (xy 172.526772 -26.777994) (xy 172.505897 -26.799637) (xy 172.498512 -26.812748)
			(xy 172.486214 -26.835913) (xy 172.456218 -26.878936) (xy 172.420614 -26.917446) (xy 172.380072 -26.950719)
			(xy 172.335356 -26.978126) (xy 172.287308 -26.999153) (xy 172.236834 -27.013402) (xy 172.184883 -27.020605)
			(xy 172.15866 -27.021028) (xy 172.130357 -27.02051) (xy 172.074375 -27.012139) (xy 172.020244 -26.995585)
			(xy 171.969153 -26.971214) (xy 171.922226 -26.93956) (xy 171.880492 -26.901318) (xy 171.844868 -26.857328)
			(xy 171.816137 -26.808556) (xy 171.794929 -26.756074) (xy 171.78782 -26.728674) (xy 171.784264 -26.714704)
			(xy 171.28109 -26.21153) (xy 171.270624 -26.200849) (xy 171.251542 -26.177823) (xy 171.24299 -26.165556)
			(xy 171.15028 -26.194258) (xy 171.15028 -26.98115) (xy 172.652944 -28.483814) (xy 174.105062 -27.031442)
			(xy 174.123046 -27.014088) (xy 174.163459 -26.984686) (xy 174.207978 -26.961978) (xy 174.255504 -26.946523)
			(xy 174.304864 -26.938704) (xy 174.329852 -26.938224) (xy 175.892968 -26.938224) (xy 175.907526 -26.937759)
			(xy 175.935461 -26.929549) (xy 175.959943 -26.913788) (xy 175.97898 -26.891757) (xy 175.991025 -26.865249)
			(xy 175.995097 -26.836418) (xy 175.990866 -26.807611) (xy 175.98517 -26.794206) (xy 175.974172 -26.769113)
			(xy 175.958671 -26.716566) (xy 175.950844 -26.662341) (xy 175.950372 -26.634948) (xy 175.950875 -26.607188)
			(xy 175.95893 -26.552256) (xy 175.974861 -26.499071) (xy 175.998333 -26.448757) (xy 176.028849 -26.402377)
			(xy 176.065766 -26.360909) (xy 176.108303 -26.32523) (xy 176.155562 -26.296092) (xy 176.206546 -26.274113)
			(xy 176.260176 -26.259755) (xy 176.287684 -26.25598) (xy 176.301293 -26.253895) (xy 176.326755 -26.243451)
			(xy 176.348506 -26.22659) (xy 176.364968 -26.204536) (xy 176.374947 -26.178888) (xy 176.377719 -26.151507)
			(xy 176.373083 -26.12438) (xy 176.367694 -26.111708) (xy 176.356205 -26.086167) (xy 176.340009 -26.032556)
			(xy 176.331842 -25.97715) (xy 176.331372 -25.949148) (xy 176.331858 -25.921897) (xy 176.339614 -25.867949)
			(xy 176.354969 -25.815654) (xy 176.377611 -25.766077) (xy 176.407077 -25.720227) (xy 176.442768 -25.679036)
			(xy 176.483959 -25.643345) (xy 176.529809 -25.613879) (xy 176.579386 -25.591237) (xy 176.631681 -25.575882)
			(xy 176.685629 -25.568126) (xy 176.740131 -25.568126) (xy 176.794079 -25.575882) (xy 176.846374 -25.591237)
			(xy 176.895951 -25.613879) (xy 176.941801 -25.643345) (xy 176.982992 -25.679036) (xy 177.018683 -25.720227)
			(xy 177.048149 -25.766077) (xy 177.070791 -25.815654) (xy 177.086146 -25.867949) (xy 177.093902 -25.921897)
			(xy 177.094388 -25.949148) (xy 177.09389 -25.977474) (xy 177.085552 -26.033507) (xy 177.069021 -26.087692)
			(xy 177.057304 -26.113486) (xy 177.051737 -26.126106) (xy 177.04687 -26.153245) (xy 177.049456 -26.180696)
			(xy 177.059305 -26.206448) (xy 177.075696 -26.228619) (xy 177.09743 -26.245585) (xy 177.122917 -26.256104)
			(xy 177.15029 -26.259407) (xy 177.163984 -26.257758) (xy 177.176684 -26.25598) (xy 177.190293 -26.253895)
			(xy 177.215755 -26.243451) (xy 177.237506 -26.22659) (xy 177.253968 -26.204536) (xy 177.263947 -26.178888)
			(xy 177.266719 -26.151507) (xy 177.262083 -26.12438) (xy 177.256694 -26.111708) (xy 177.245205 -26.086167)
			(xy 177.229009 -26.032556) (xy 177.220842 -25.97715) (xy 177.220372 -25.949148) (xy 177.220858 -25.921897)
			(xy 177.228614 -25.867949) (xy 177.243969 -25.815654) (xy 177.266611 -25.766077) (xy 177.296077 -25.720227)
			(xy 177.331768 -25.679036) (xy 177.372959 -25.643345) (xy 177.418809 -25.613879) (xy 177.468386 -25.591237)
			(xy 177.520681 -25.575882) (xy 177.574629 -25.568126) (xy 177.629131 -25.568126) (xy 177.683079 -25.575882)
			(xy 177.735374 -25.591237) (xy 177.784951 -25.613879) (xy 177.830801 -25.643345) (xy 177.871992 -25.679036)
			(xy 177.907683 -25.720227) (xy 177.937149 -25.766077) (xy 177.959791 -25.815654) (xy 177.975146 -25.867949)
			(xy 177.982902 -25.921897) (xy 177.983388 -25.949148) (xy 177.98289 -25.977474) (xy 177.974552 -26.033507)
			(xy 177.958021 -26.087692) (xy 177.946304 -26.113486) (xy 177.940737 -26.126106) (xy 177.93587 -26.153245)
			(xy 177.938456 -26.180696) (xy 177.948305 -26.206448) (xy 177.964696 -26.228619) (xy 177.98643 -26.245585)
			(xy 178.011917 -26.256104) (xy 178.03929 -26.259407) (xy 178.052984 -26.257758) (xy 178.065684 -26.25598)
			(xy 178.079293 -26.253895) (xy 178.104755 -26.243451) (xy 178.126506 -26.22659) (xy 178.142968 -26.204536)
			(xy 178.152947 -26.178888) (xy 178.155719 -26.151507) (xy 178.151083 -26.12438) (xy 178.145694 -26.111708)
			(xy 178.134205 -26.086167) (xy 178.118009 -26.032556) (xy 178.109842 -25.97715) (xy 178.109372 -25.949148)
			(xy 178.109858 -25.921897) (xy 178.117614 -25.867949) (xy 178.132969 -25.815654) (xy 178.155611 -25.766077)
			(xy 178.185077 -25.720227) (xy 178.220768 -25.679036) (xy 178.261959 -25.643345) (xy 178.307809 -25.613879)
			(xy 178.357386 -25.591237) (xy 178.409681 -25.575882) (xy 178.463629 -25.568126) (xy 178.518131 -25.568126)
			(xy 178.572079 -25.575882) (xy 178.624374 -25.591237) (xy 178.673951 -25.613879) (xy 178.719801 -25.643345)
			(xy 178.760992 -25.679036) (xy 178.796683 -25.720227) (xy 178.826149 -25.766077) (xy 178.848791 -25.815654)
			(xy 178.864146 -25.867949) (xy 178.871902 -25.921897) (xy 178.872388 -25.949148) (xy 178.871885 -25.976909)
			(xy 178.863832 -26.031845) (xy 178.847901 -26.085033) (xy 178.824431 -26.135351) (xy 178.793916 -26.181737)
			(xy 178.757001 -26.22321) (xy 178.714465 -26.258895) (xy 178.667207 -26.28804) (xy 178.616223 -26.310027)
			(xy 178.562591 -26.324394) (xy 178.535076 -26.328116) (xy 178.52146 -26.330194) (xy 178.495984 -26.34063)
			(xy 178.474218 -26.35749) (xy 178.457744 -26.379549) (xy 178.447758 -26.405205) (xy 178.444985 -26.432597)
			(xy 178.449625 -26.459735) (xy 178.455066 -26.472388) (xy 178.466556 -26.497929) (xy 178.482754 -26.55154)
			(xy 178.490923 -26.606945) (xy 178.491388 -26.634948) (xy 178.490913 -26.66234) (xy 178.483077 -26.716562)
			(xy 178.467574 -26.769108) (xy 178.45659 -26.794206) (xy 178.450944 -26.807619) (xy 178.446747 -26.836406)
			(xy 178.450835 -26.865209) (xy 178.462876 -26.891691) (xy 178.481893 -26.913705) (xy 178.506344 -26.929467)
			(xy 178.534247 -26.937697) (xy 178.548792 -26.938224) (xy 178.916584 -26.938224) (xy 178.97221 -26.882598)
			(xy 178.990194 -26.865243) (xy 179.030607 -26.835839) (xy 179.075125 -26.813126) (xy 179.122651 -26.797666)
			(xy 179.172011 -26.78984) (xy 179.197 -26.78938) (xy 180.710586 -26.78938) (xy 180.734164 -26.774335)
			(xy 180.784795 -26.75057) (xy 180.838355 -26.734461) (xy 180.893694 -26.726353) (xy 180.92166 -26.72588)
			(xy 180.948916 -26.72634) (xy 181.002873 -26.734093) (xy 181.055177 -26.749446) (xy 181.104764 -26.772087)
			(xy 181.150623 -26.801555) (xy 181.191822 -26.837249) (xy 181.227521 -26.878445) (xy 181.256994 -26.924301)
			(xy 181.27964 -26.973885) (xy 181.294999 -27.026188) (xy 181.302757 -27.080144) (xy 181.302757 -27.134656)
			(xy 181.294999 -27.188612) (xy 181.27964 -27.240915) (xy 181.256994 -27.290499) (xy 181.227521 -27.336355)
			(xy 181.191822 -27.377551) (xy 181.150623 -27.413245) (xy 181.104764 -27.442713) (xy 181.055177 -27.465354)
			(xy 181.002873 -27.480707) (xy 180.948916 -27.48846) (xy 180.92166 -27.488896) (xy 180.893697 -27.48842)
			(xy 180.838365 -27.480286) (xy 180.78481 -27.464169) (xy 180.73418 -27.440414) (xy 180.710586 -27.425396)
			(xy 179.328572 -27.425396) (xy 179.272946 -27.481022) (xy 179.25496 -27.498374) (xy 179.214546 -27.52777)
			(xy 179.170027 -27.550475) (xy 179.122502 -27.565928) (xy 179.073143 -27.573747) (xy 179.048156 -27.57424)
			(xy 175.184308 -27.57424) (xy 175.16937 -27.574764) (xy 175.140771 -27.583407) (xy 175.115897 -27.599956)
			(xy 175.096876 -27.622996) (xy 175.085336 -27.650554) (xy 175.082264 -27.680272) (xy 175.087924 -27.709607)
			(xy 175.094392 -27.723084) (xy 175.108228 -27.750612) (xy 175.127809 -27.809025) (xy 175.137742 -27.869826)
			(xy 175.138334 -27.90063) (xy 175.137894 -27.927286) (xy 175.130479 -27.980079) (xy 175.115782 -28.031325)
			(xy 175.094091 -28.080024) (xy 175.065828 -28.125227) (xy 175.031545 -28.166054) (xy 174.991909 -28.201707)
			(xy 174.947694 -28.231492) (xy 174.899761 -28.254828) (xy 174.849045 -28.27126) (xy 174.822866 -28.276296)
			(xy 174.809128 -28.279154) (xy 174.783856 -28.291326) (xy 174.762848 -28.309914) (xy 174.747688 -28.333514)
			(xy 174.739519 -28.360348) (xy 174.738956 -28.388393) (xy 174.746043 -28.415534) (xy 174.760244 -28.439723)
			(xy 174.770034 -28.449778) (xy 174.788202 -28.467832) (xy 174.820032 -28.50796) (xy 174.846213 -28.551982)
			(xy 174.866277 -28.599109) (xy 174.879862 -28.648493) (xy 174.886726 -28.699251) (xy 174.887128 -28.72486)
			(xy 174.886706 -28.75121) (xy 174.879494 -28.803414) (xy 174.86516 -28.854127) (xy 174.843978 -28.902382)
			(xy 174.816351 -28.947259) (xy 174.782806 -28.987904) (xy 174.763684 -29.006038) (xy 174.753586 -29.015873)
			(xy 174.738772 -29.039841) (xy 174.731091 -29.066951) (xy 174.73113 -29.095128) (xy 174.738886 -29.122216)
			(xy 174.753766 -29.146143) (xy 174.763938 -29.155898) (xy 174.783145 -29.174045) (xy 174.816873 -29.214719)
			(xy 174.841915 -29.255212) (xy 176.187862 -29.255212) (xy 176.188401 -29.227892) (xy 176.196736 -29.173892)
			(xy 176.213214 -29.121796) (xy 176.237447 -29.072824) (xy 176.268869 -29.028123) (xy 176.28743 -29.00807)
			(xy 176.297817 -28.996439) (xy 176.311645 -28.968509) (xy 176.316404 -28.937709) (xy 176.311651 -28.906908)
			(xy 176.297827 -28.878975) (xy 176.28743 -28.867354) (xy 176.268809 -28.847348) (xy 176.237352 -28.802654)
			(xy 176.213104 -28.753673) (xy 176.196635 -28.701559) (xy 176.188332 -28.64754) (xy 176.187862 -28.620212)
			(xy 176.18836 -28.593563) (xy 176.196303 -28.540859) (xy 176.212013 -28.489929) (xy 176.235139 -28.441908)
			(xy 176.265163 -28.397871) (xy 176.301415 -28.3588) (xy 176.343086 -28.325569) (xy 176.389244 -28.29892)
			(xy 176.438858 -28.279448) (xy 176.49082 -28.267588) (xy 176.54397 -28.263605) (xy 176.59712 -28.267588)
			(xy 176.649082 -28.279448) (xy 176.698696 -28.29892) (xy 176.744854 -28.325569) (xy 176.786525 -28.3588)
			(xy 176.822777 -28.397871) (xy 176.852801 -28.441908) (xy 176.875927 -28.489929) (xy 176.891637 -28.540859)
			(xy 176.89958 -28.593563) (xy 176.900078 -28.620212) (xy 176.89957 -28.647533) (xy 176.89123 -28.701536)
			(xy 176.874746 -28.753633) (xy 176.850505 -28.802604) (xy 176.819075 -28.847302) (xy 176.80051 -28.867354)
			(xy 176.790105 -28.878968) (xy 176.776287 -28.906905) (xy 176.771535 -28.937709) (xy 176.776292 -28.968511)
			(xy 176.790115 -28.996446) (xy 176.80051 -29.00807) (xy 176.819102 -29.028102) (xy 176.850561 -29.07279)
			(xy 176.874814 -29.121764) (xy 176.89129 -29.173872) (xy 176.899602 -29.227886) (xy 176.900078 -29.255212)
			(xy 177.087784 -29.255212) (xy 177.088317 -29.227892) (xy 177.096653 -29.173891) (xy 177.113131 -29.121795)
			(xy 177.137366 -29.072823) (xy 177.16879 -29.028123) (xy 177.187352 -29.00807) (xy 177.197737 -28.996438)
			(xy 177.211562 -28.968508) (xy 177.21632 -28.937709) (xy 177.211568 -28.906909) (xy 177.197747 -28.878976)
			(xy 177.187352 -28.867354) (xy 177.168734 -28.847345) (xy 177.137277 -28.802652) (xy 177.113027 -28.753672)
			(xy 177.096557 -28.701559) (xy 177.088254 -28.647539) (xy 177.087784 -28.620212) (xy 177.088282 -28.593563)
			(xy 177.096225 -28.540859) (xy 177.111935 -28.489929) (xy 177.135061 -28.441908) (xy 177.165085 -28.397871)
			(xy 177.201337 -28.3588) (xy 177.243008 -28.325569) (xy 177.289166 -28.29892) (xy 177.33878 -28.279448)
			(xy 177.390742 -28.267588) (xy 177.443892 -28.263605) (xy 177.497042 -28.267588) (xy 177.549004 -28.279448)
			(xy 177.598618 -28.29892) (xy 177.644776 -28.325569) (xy 177.686447 -28.3588) (xy 177.722699 -28.397871)
			(xy 177.752723 -28.441908) (xy 177.775849 -28.489929) (xy 177.791559 -28.540859) (xy 177.799502 -28.593563)
			(xy 177.8 -28.620212) (xy 177.799486 -28.647533) (xy 177.791146 -28.701535) (xy 177.774664 -28.753631)
			(xy 177.750424 -28.802603) (xy 177.718996 -28.847302) (xy 177.700432 -28.867354) (xy 177.690025 -28.878967)
			(xy 177.676204 -28.906904) (xy 177.671452 -28.937709) (xy 177.676209 -28.968512) (xy 177.690035 -28.996447)
			(xy 177.700432 -29.00807) (xy 177.719028 -29.028099) (xy 177.750485 -29.072788) (xy 177.774737 -29.121763)
			(xy 177.791213 -29.173871) (xy 177.799524 -29.227886) (xy 177.8 -29.255212) (xy 177.987706 -29.255212)
			(xy 177.988233 -29.227892) (xy 177.996569 -29.17389) (xy 178.013049 -29.121794) (xy 178.037285 -29.072822)
			(xy 178.068711 -29.028122) (xy 178.087274 -29.00807) (xy 178.097657 -28.996437) (xy 178.111479 -28.968507)
			(xy 178.116236 -28.937709) (xy 178.111485 -28.90691) (xy 178.097667 -28.878977) (xy 178.087274 -28.867354)
			(xy 178.068643 -28.847357) (xy 178.03719 -28.802659) (xy 178.012945 -28.753676) (xy 177.996477 -28.701561)
			(xy 177.988176 -28.64754) (xy 177.987706 -28.620212) (xy 177.988204 -28.593563) (xy 177.996147 -28.540859)
			(xy 178.011857 -28.489929) (xy 178.034983 -28.441908) (xy 178.065007 -28.397871) (xy 178.101259 -28.3588)
			(xy 178.14293 -28.325569) (xy 178.189088 -28.29892) (xy 178.238702 -28.279448) (xy 178.290664 -28.267588)
			(xy 178.343814 -28.263605) (xy 178.396964 -28.267588) (xy 178.448926 -28.279448) (xy 178.49854 -28.29892)
			(xy 178.544698 -28.325569) (xy 178.586369 -28.3588) (xy 178.622621 -28.397871) (xy 178.652645 -28.441908)
			(xy 178.675771 -28.489929) (xy 178.691481 -28.540859) (xy 178.699424 -28.593563) (xy 178.699922 -28.620212)
			(xy 178.699402 -28.647533) (xy 178.691063 -28.701534) (xy 178.674581 -28.75363) (xy 178.650344 -28.802602)
			(xy 178.618917 -28.847301) (xy 178.600354 -28.867354) (xy 178.589945 -28.878966) (xy 178.576121 -28.906903)
			(xy 178.571367 -28.937709) (xy 178.576126 -28.968513) (xy 178.589955 -28.996448) (xy 178.600354 -29.00807)
			(xy 178.618936 -29.028111) (xy 178.650399 -29.072795) (xy 178.674655 -29.121767) (xy 178.691133 -29.173873)
			(xy 178.699446 -29.227887) (xy 178.699922 -29.255212) (xy 178.887882 -29.255212) (xy 178.888415 -29.227892)
			(xy 178.896751 -29.173891) (xy 178.91323 -29.121795) (xy 178.937464 -29.072823) (xy 178.968888 -29.028123)
			(xy 178.98745 -29.00807) (xy 178.997835 -28.996438) (xy 179.011661 -28.968508) (xy 179.016419 -28.937709)
			(xy 179.011666 -28.906908) (xy 178.997845 -28.878976) (xy 178.98745 -28.867354) (xy 178.968832 -28.847345)
			(xy 178.937374 -28.802652) (xy 178.913125 -28.753672) (xy 178.896655 -28.701559) (xy 178.888352 -28.647539)
			(xy 178.887882 -28.620212) (xy 178.88838 -28.593563) (xy 178.896323 -28.540859) (xy 178.912033 -28.489929)
			(xy 178.935159 -28.441908) (xy 178.965183 -28.397871) (xy 179.001435 -28.3588) (xy 179.043106 -28.325569)
			(xy 179.089264 -28.29892) (xy 179.138878 -28.279448) (xy 179.19084 -28.267588) (xy 179.24399 -28.263605)
			(xy 179.29714 -28.267588) (xy 179.349102 -28.279448) (xy 179.398716 -28.29892) (xy 179.444874 -28.325569)
			(xy 179.486545 -28.3588) (xy 179.522797 -28.397871) (xy 179.552821 -28.441908) (xy 179.575947 -28.489929)
			(xy 179.591657 -28.540859) (xy 179.5996 -28.593563) (xy 179.600098 -28.620212) (xy 179.599585 -28.647533)
			(xy 179.591245 -28.701535) (xy 179.574762 -28.753632) (xy 179.550523 -28.802603) (xy 179.519094 -28.847302)
			(xy 179.50053 -28.867354) (xy 179.490123 -28.878967) (xy 179.476303 -28.906904) (xy 179.47155 -28.937709)
			(xy 179.476308 -28.968512) (xy 179.490133 -28.996447) (xy 179.50053 -29.00807) (xy 179.519125 -29.028099)
			(xy 179.550583 -29.072788) (xy 179.574835 -29.121763) (xy 179.591311 -29.173871) (xy 179.599622 -29.227886)
			(xy 179.600098 -29.255212) (xy 179.5996 -29.281861) (xy 179.591657 -29.334565) (xy 179.575947 -29.385495)
			(xy 179.552821 -29.433516) (xy 179.522797 -29.477553) (xy 179.486545 -29.516624) (xy 179.444874 -29.549855)
			(xy 179.398716 -29.576504) (xy 179.349102 -29.595976) (xy 179.29714 -29.607836) (xy 179.24399 -29.61182)
			(xy 179.19084 -29.607836) (xy 179.138878 -29.595976) (xy 179.089264 -29.576504) (xy 179.043106 -29.549855)
			(xy 179.001435 -29.516624) (xy 178.965183 -29.477553) (xy 178.935159 -29.433516) (xy 178.912033 -29.385495)
			(xy 178.896323 -29.334565) (xy 178.88838 -29.281861) (xy 178.887882 -29.255212) (xy 178.699922 -29.255212)
			(xy 178.699424 -29.281861) (xy 178.691481 -29.334565) (xy 178.675771 -29.385495) (xy 178.652645 -29.433516)
			(xy 178.622621 -29.477553) (xy 178.586369 -29.516624) (xy 178.544698 -29.549855) (xy 178.49854 -29.576504)
			(xy 178.448926 -29.595976) (xy 178.396964 -29.607836) (xy 178.343814 -29.61182) (xy 178.290664 -29.607836)
			(xy 178.238702 -29.595976) (xy 178.189088 -29.576504) (xy 178.14293 -29.549855) (xy 178.101259 -29.516624)
			(xy 178.065007 -29.477553) (xy 178.034983 -29.433516) (xy 178.011857 -29.385495) (xy 177.996147 -29.334565)
			(xy 177.988204 -29.281861) (xy 177.987706 -29.255212) (xy 177.8 -29.255212) (xy 177.799502 -29.281861)
			(xy 177.791559 -29.334565) (xy 177.775849 -29.385495) (xy 177.752723 -29.433516) (xy 177.722699 -29.477553)
			(xy 177.686447 -29.516624) (xy 177.644776 -29.549855) (xy 177.598618 -29.576504) (xy 177.549004 -29.595976)
			(xy 177.497042 -29.607836) (xy 177.443892 -29.61182) (xy 177.390742 -29.607836) (xy 177.33878 -29.595976)
			(xy 177.289166 -29.576504) (xy 177.243008 -29.549855) (xy 177.201337 -29.516624) (xy 177.165085 -29.477553)
			(xy 177.135061 -29.433516) (xy 177.111935 -29.385495) (xy 177.096225 -29.334565) (xy 177.088282 -29.281861)
			(xy 177.087784 -29.255212) (xy 176.900078 -29.255212) (xy 176.89958 -29.281861) (xy 176.891637 -29.334565)
			(xy 176.875927 -29.385495) (xy 176.852801 -29.433516) (xy 176.822777 -29.477553) (xy 176.786525 -29.516624)
			(xy 176.744854 -29.549855) (xy 176.698696 -29.576504) (xy 176.649082 -29.595976) (xy 176.59712 -29.607836)
			(xy 176.54397 -29.61182) (xy 176.49082 -29.607836) (xy 176.438858 -29.595976) (xy 176.389244 -29.576504)
			(xy 176.343086 -29.549855) (xy 176.301415 -29.516624) (xy 176.265163 -29.477553) (xy 176.235139 -29.433516)
			(xy 176.212013 -29.385495) (xy 176.196303 -29.334565) (xy 176.18836 -29.281861) (xy 176.187862 -29.255212)
			(xy 174.841915 -29.255212) (xy 174.844665 -29.259659) (xy 174.865989 -29.308005) (xy 174.880436 -29.358831)
			(xy 174.887731 -29.411164) (xy 174.888144 -29.437584) (xy 174.887658 -29.464835) (xy 174.879902 -29.518783)
			(xy 174.864547 -29.571078) (xy 174.841905 -29.620655) (xy 174.812439 -29.666505) (xy 174.776748 -29.707696)
			(xy 174.735557 -29.743387) (xy 174.689707 -29.772853) (xy 174.64013 -29.795495) (xy 174.587835 -29.81085)
			(xy 174.533887 -29.818606) (xy 174.479385 -29.818606) (xy 174.425437 -29.81085) (xy 174.373142 -29.795495)
			(xy 174.323565 -29.772853) (xy 174.277715 -29.743387) (xy 174.236524 -29.707696) (xy 174.200833 -29.666505)
			(xy 174.171367 -29.620655) (xy 174.148725 -29.571078) (xy 174.13337 -29.518783) (xy 174.125614 -29.464835)
			(xy 174.125128 -29.437584) (xy 174.125553 -29.411235) (xy 174.132772 -29.359035) (xy 174.14711 -29.308326)
			(xy 174.168295 -29.260074) (xy 174.195924 -29.2152) (xy 174.229469 -29.174559) (xy 174.248572 -29.156406)
			(xy 174.258666 -29.146573) (xy 174.273471 -29.12261) (xy 174.281143 -29.095507) (xy 174.281094 -29.06734)
			(xy 174.273327 -29.040264) (xy 174.258438 -29.016353) (xy 174.248318 -29.006546) (xy 174.229116 -28.988397)
			(xy 174.195398 -28.94772) (xy 174.167615 -28.902778) (xy 174.146301 -28.854433) (xy 174.131863 -28.803608)
			(xy 174.124577 -28.751278) (xy 174.124112 -28.72486) (xy 174.124552 -28.698206) (xy 174.13197 -28.645415)
			(xy 174.146668 -28.594173) (xy 174.168361 -28.545477) (xy 174.196625 -28.500278) (xy 174.23091 -28.459457)
			(xy 174.270546 -28.423809) (xy 174.314762 -28.394029) (xy 174.362694 -28.370699) (xy 174.41341 -28.354273)
			(xy 174.43958 -28.349194) (xy 174.453312 -28.346331) (xy 174.478571 -28.334154) (xy 174.499566 -28.315567)
			(xy 174.514717 -28.291971) (xy 174.522881 -28.265145) (xy 174.523443 -28.23711) (xy 174.51636 -28.209979)
			(xy 174.502168 -28.185795) (xy 174.492412 -28.175712) (xy 174.47093 -28.154253) (xy 174.43437 -28.105778)
			(xy 174.405951 -28.052123) (xy 174.386392 -27.994643) (xy 174.376186 -27.934791) (xy 174.375318 -27.90444)
			(xy 174.374652 -27.889507) (xy 174.365733 -27.860993) (xy 174.348942 -27.836282) (xy 174.325716 -27.817489)
			(xy 174.298045 -27.806225) (xy 174.268298 -27.803452) (xy 174.239021 -27.80941) (xy 174.212723 -27.823588)
			(xy 174.201836 -27.833828) (xy 173.10227 -28.93314) (xy 173.202854 -29.033724) (xy 173.202854 -29.841952)
			(xy 180.652674 -29.841952) (xy 180.653185 -29.814379) (xy 180.661129 -29.759809) (xy 180.676846 -29.70695)
			(xy 180.700008 -29.656904) (xy 180.730132 -29.610713) (xy 180.766591 -29.56934) (xy 180.787294 -29.551122)
			(xy 180.798239 -29.541272) (xy 180.814311 -29.516608) (xy 180.822689 -29.488388) (xy 180.82268 -29.45895)
			(xy 180.814284 -29.430735) (xy 180.798198 -29.406081) (xy 180.787294 -29.396182) (xy 180.76657 -29.377985)
			(xy 180.730101 -29.336613) (xy 180.69997 -29.29042) (xy 180.676807 -29.24037) (xy 180.661093 -29.187504)
			(xy 180.653157 -29.132928) (xy 180.652674 -29.105352) (xy 180.653133 -29.0781) (xy 180.660896 -29.024153)
			(xy 180.676256 -28.971859) (xy 180.698901 -28.922282) (xy 180.728371 -28.876433) (xy 180.764065 -28.835244)
			(xy 180.805257 -28.799553) (xy 180.851109 -28.770087) (xy 180.900687 -28.747445) (xy 180.952982 -28.732089)
			(xy 181.00693 -28.724331) (xy 181.034182 -28.723844) (xy 181.061439 -28.724338) (xy 181.115398 -28.732103)
			(xy 181.167704 -28.747462) (xy 181.217293 -28.770105) (xy 181.263159 -28.799569) (xy 181.304368 -28.835257)
			(xy 181.340083 -28.876443) (xy 181.355238 -28.899104) (xy 181.363519 -28.911031) (xy 181.385455 -28.930035)
			(xy 181.411855 -28.94209) (xy 181.440582 -28.94622) (xy 181.469309 -28.94209) (xy 181.495709 -28.930035)
			(xy 181.517645 -28.911031) (xy 181.525926 -28.899104) (xy 181.541103 -28.876457) (xy 181.576806 -28.835261)
			(xy 181.618008 -28.799565) (xy 181.66387 -28.770094) (xy 181.713459 -28.747449) (xy 181.765765 -28.732091)
			(xy 181.819725 -28.724331) (xy 181.846982 -28.723844) (xy 181.874231 -28.724395) (xy 181.928173 -28.732148)
			(xy 181.980464 -28.747498) (xy 182.030038 -28.770134) (xy 182.075886 -28.799593) (xy 182.117075 -28.835278)
			(xy 182.152767 -28.876461) (xy 182.182235 -28.922304) (xy 182.204879 -28.971874) (xy 182.220238 -29.024162)
			(xy 182.228 -29.078103) (xy 182.22849 -29.105352) (xy 182.227995 -29.132926) (xy 182.220049 -29.187497)
			(xy 182.20433 -29.240357) (xy 182.181165 -29.290403) (xy 182.151038 -29.336593) (xy 182.114575 -29.377965)
			(xy 182.09387 -29.396182) (xy 182.083024 -29.406131) (xy 182.066955 -29.430768) (xy 182.058569 -29.458962)
			(xy 182.05856 -29.488376) (xy 182.066929 -29.516575) (xy 182.082983 -29.541222) (xy 182.09387 -29.551122)
			(xy 182.114589 -29.569325) (xy 182.15106 -29.610695) (xy 182.181192 -29.656886) (xy 182.204357 -29.706936)
			(xy 182.220071 -29.7598) (xy 182.228007 -29.814377) (xy 182.22849 -29.841952) (xy 182.228 -29.869204)
			(xy 182.220249 -29.923155) (xy 182.204898 -29.975454) (xy 182.18226 -30.025035) (xy 182.152795 -30.070889)
			(xy 182.117104 -30.112083) (xy 182.075913 -30.147777) (xy 182.030061 -30.177246) (xy 181.980482 -30.199888)
			(xy 181.928185 -30.215243) (xy 181.874234 -30.222998) (xy 181.846982 -30.22346) (xy 181.819724 -30.222991)
			(xy 181.765764 -30.215222) (xy 181.713458 -30.199858) (xy 181.663868 -30.177211) (xy 181.618003 -30.147743)
			(xy 181.576795 -30.112051) (xy 181.541081 -30.070862) (xy 181.525926 -30.0482) (xy 181.517645 -30.036273)
			(xy 181.495709 -30.017269) (xy 181.469309 -30.005214) (xy 181.440582 -30.001084) (xy 181.411855 -30.005214)
			(xy 181.385455 -30.017269) (xy 181.363519 -30.036273) (xy 181.355238 -30.0482) (xy 181.340086 -30.070864)
			(xy 181.304378 -30.11206) (xy 181.263172 -30.147755) (xy 181.217306 -30.177224) (xy 181.167713 -30.199866)
			(xy 181.115403 -30.21522) (xy 181.061441 -30.222975) (xy 181.034182 -30.22346) (xy 181.006926 -30.223062)
			(xy 180.952971 -30.215301) (xy 180.900669 -30.19994) (xy 180.851085 -30.177292) (xy 180.80523 -30.147818)
			(xy 180.764036 -30.112117) (xy 180.728343 -30.070917) (xy 180.698876 -30.025057) (xy 180.676237 -29.975469)
			(xy 180.660885 -29.923165) (xy 180.653134 -29.869208) (xy 180.652674 -29.841952) (xy 173.202854 -29.841952)
			(xy 173.202854 -31.446248) (xy 176.813144 -31.446248) (xy 176.813145 -31.39174) (xy 176.820904 -31.337786)
			(xy 176.836262 -31.285486) (xy 176.858907 -31.235903) (xy 176.888378 -31.190049) (xy 176.924075 -31.148855)
			(xy 176.965271 -31.113161) (xy 177.011128 -31.083693) (xy 177.060712 -31.061052) (xy 177.113013 -31.045698)
			(xy 177.166968 -31.037943) (xy 177.221476 -31.037946) (xy 177.27543 -31.045707) (xy 177.327729 -31.061067)
			(xy 177.377311 -31.083715) (xy 177.423164 -31.113188) (xy 177.464356 -31.148886) (xy 177.500048 -31.190084)
			(xy 177.529514 -31.235942) (xy 177.552154 -31.285527) (xy 177.567506 -31.337829) (xy 177.575258 -31.391784)
			(xy 177.575718 -31.419038) (xy 177.575718 -31.428944) (xy 177.575825 -31.44294) (xy 177.582765 -31.470045)
			(xy 177.5968 -31.49425) (xy 177.616878 -31.513737) (xy 177.64149 -31.527045) (xy 177.66879 -31.533174)
			(xy 177.696728 -31.531664) (xy 177.723209 -31.522629) (xy 177.734976 -31.51505) (xy 177.759047 -31.498984)
			(xy 177.811029 -31.473548) (xy 177.866258 -31.45626) (xy 177.923464 -31.447515) (xy 177.9524 -31.446978)
			(xy 177.979653 -31.447455) (xy 178.033604 -31.455212) (xy 178.085903 -31.470569) (xy 178.135483 -31.493212)
			(xy 178.181336 -31.52268) (xy 178.222529 -31.558374) (xy 178.258223 -31.599567) (xy 178.287691 -31.645421)
			(xy 178.310333 -31.695002) (xy 178.325689 -31.7473) (xy 178.333445 -31.801252) (xy 178.333444 -31.855758)
			(xy 178.325687 -31.909709) (xy 178.312618 -31.954216) (xy 179.198014 -31.954216) (xy 179.202085 -31.898594)
			(xy 179.214211 -31.844157) (xy 179.234134 -31.792066) (xy 179.26143 -31.743431) (xy 179.295516 -31.699288)
			(xy 179.335665 -31.660579) (xy 179.381023 -31.628128) (xy 179.430623 -31.602627) (xy 179.483407 -31.58462)
			(xy 179.53825 -31.57449) (xy 179.593984 -31.572453) (xy 179.649421 -31.578553) (xy 179.703378 -31.592659)
			(xy 179.754707 -31.614471) (xy 179.802313 -31.643525) (xy 179.845181 -31.6792) (xy 179.882398 -31.720737)
			(xy 179.913171 -31.76725) (xy 179.936843 -31.817747) (xy 179.952911 -31.871154) (xy 179.961031 -31.92633)
			(xy 179.96154 -31.954216) (xy 179.961031 -31.982102) (xy 179.952911 -32.037278) (xy 179.936843 -32.090685)
			(xy 179.913171 -32.141182) (xy 179.882398 -32.187695) (xy 179.845181 -32.229232) (xy 179.802313 -32.264907)
			(xy 179.754707 -32.293961) (xy 179.703378 -32.315773) (xy 179.649421 -32.329879) (xy 179.593984 -32.335979)
			(xy 179.53825 -32.333942) (xy 179.483407 -32.323812) (xy 179.430623 -32.305805) (xy 179.381023 -32.280304)
			(xy 179.335665 -32.247853) (xy 179.295516 -32.209144) (xy 179.26143 -32.165001) (xy 179.234134 -32.116366)
			(xy 179.214211 -32.064275) (xy 179.202085 -32.009838) (xy 179.198014 -31.954216) (xy 178.312618 -31.954216)
			(xy 178.31033 -31.962007) (xy 178.287686 -32.011587) (xy 178.258217 -32.05744) (xy 178.222523 -32.098632)
			(xy 178.181329 -32.134326) (xy 178.135475 -32.163793) (xy 178.085894 -32.186435) (xy 178.033595 -32.20179)
			(xy 177.979644 -32.209545) (xy 177.925138 -32.209544) (xy 177.871186 -32.201786) (xy 177.818889 -32.186428)
			(xy 177.769309 -32.163784) (xy 177.723456 -32.134314) (xy 177.682264 -32.098619) (xy 177.646572 -32.057425)
			(xy 177.617105 -32.011571) (xy 177.594464 -31.961989) (xy 177.579109 -31.909691) (xy 177.571354 -31.855739)
			(xy 177.570892 -31.828486) (xy 177.570892 -31.81858) (xy 177.570823 -31.804585) (xy 177.563868 -31.777484)
			(xy 177.549822 -31.753286) (xy 177.52974 -31.733805) (xy 177.505126 -31.7205) (xy 177.477827 -31.714371)
			(xy 177.449888 -31.715875) (xy 177.423405 -31.724901) (xy 177.411634 -31.732474) (xy 177.387554 -31.748527)
			(xy 177.335576 -31.773968) (xy 177.28035 -31.791261) (xy 177.223145 -31.800008) (xy 177.19421 -31.800546)
			(xy 177.166956 -31.800056) (xy 177.113002 -31.7923) (xy 177.060701 -31.776944) (xy 177.011118 -31.754301)
			(xy 176.965262 -31.724832) (xy 176.924066 -31.689136) (xy 176.888371 -31.647942) (xy 176.858901 -31.602086)
			(xy 176.836258 -31.552503) (xy 176.820901 -31.500202) (xy 176.813144 -31.446248) (xy 173.202854 -31.446248)
			(xy 173.202854 -32.535622) (xy 180.552342 -32.535622) (xy 180.556413 -32.48) (xy 180.568539 -32.425563)
			(xy 180.588462 -32.373472) (xy 180.615758 -32.324837) (xy 180.649844 -32.280694) (xy 180.689993 -32.241985)
			(xy 180.735351 -32.209534) (xy 180.784951 -32.184033) (xy 180.837735 -32.166026) (xy 180.892578 -32.155896)
			(xy 180.948312 -32.153859) (xy 181.003749 -32.159959) (xy 181.057706 -32.174065) (xy 181.109035 -32.195877)
			(xy 181.156641 -32.224931) (xy 181.199509 -32.260606) (xy 181.236726 -32.302143) (xy 181.267499 -32.348656)
			(xy 181.291171 -32.399153) (xy 181.307239 -32.45256) (xy 181.315359 -32.507736) (xy 181.315868 -32.535622)
			(xy 181.315359 -32.563508) (xy 181.307239 -32.618684) (xy 181.291171 -32.672091) (xy 181.267499 -32.722588)
			(xy 181.236726 -32.769101) (xy 181.199509 -32.810638) (xy 181.156641 -32.846313) (xy 181.109035 -32.875367)
			(xy 181.057706 -32.897179) (xy 181.003749 -32.911285) (xy 180.948312 -32.917385) (xy 180.892578 -32.915348)
			(xy 180.837735 -32.905218) (xy 180.784951 -32.887211) (xy 180.735351 -32.86171) (xy 180.689993 -32.829259)
			(xy 180.649844 -32.79055) (xy 180.615758 -32.746407) (xy 180.588462 -32.697772) (xy 180.568539 -32.645681)
			(xy 180.556413 -32.591244) (xy 180.552342 -32.535622) (xy 173.202854 -32.535622) (xy 173.202854 -33.307274)
			(xy 174.683928 -34.788348)
		)
		(stroke
			(width 0)
			(type solid)
		)
		(fill yes)
		(layer "In11.Cu")
		(net "GND")
	)
	(gr_poly
		(pts
			(xy 128.337056 -222.514668) (xy 128.357365 -222.4973) (xy 128.402489 -222.468679) (xy 128.451629 -222.447687)
			(xy 128.503504 -222.434869) (xy 128.556766 -222.430559) (xy 128.610028 -222.434869) (xy 128.661903 -222.447687)
			(xy 128.711043 -222.468679) (xy 128.756167 -222.4973) (xy 128.776476 -222.514668) (xy 129.276856 -222.514668)
			(xy 129.297165 -222.4973) (xy 129.342289 -222.468679) (xy 129.391429 -222.447687) (xy 129.443304 -222.434869)
			(xy 129.496566 -222.430559) (xy 129.549828 -222.434869) (xy 129.601703 -222.447687) (xy 129.650843 -222.468679)
			(xy 129.695967 -222.4973) (xy 129.716276 -222.514668) (xy 130.216656 -222.514668) (xy 130.236965 -222.4973)
			(xy 130.282089 -222.468679) (xy 130.331229 -222.447687) (xy 130.383104 -222.434869) (xy 130.436366 -222.430559)
			(xy 130.489628 -222.434869) (xy 130.541503 -222.447687) (xy 130.590643 -222.468679) (xy 130.635767 -222.4973)
			(xy 130.656076 -222.514668) (xy 131.156456 -222.514668) (xy 131.176765 -222.4973) (xy 131.221889 -222.468679)
			(xy 131.271029 -222.447687) (xy 131.322904 -222.434869) (xy 131.376166 -222.430559) (xy 131.429428 -222.434869)
			(xy 131.481303 -222.447687) (xy 131.530443 -222.468679) (xy 131.575567 -222.4973) (xy 131.595876 -222.514668)
			(xy 132.096256 -222.514668) (xy 132.116565 -222.4973) (xy 132.161689 -222.468679) (xy 132.210829 -222.447687)
			(xy 132.262704 -222.434869) (xy 132.315966 -222.430559) (xy 132.369228 -222.434869) (xy 132.421103 -222.447687)
			(xy 132.470243 -222.468679) (xy 132.515367 -222.4973) (xy 132.535676 -222.514668) (xy 133.036056 -222.514668)
			(xy 133.054312 -222.499017) (xy 133.094498 -222.47261) (xy 133.138082 -222.452296) (xy 133.184147 -222.438505)
			(xy 133.231723 -222.431526) (xy 133.255766 -222.431102) (xy 133.279809 -222.431532) (xy 133.327389 -222.438496)
			(xy 133.373457 -222.452281) (xy 133.417041 -222.472597) (xy 133.457221 -222.499015) (xy 133.475476 -222.514668)
			(xy 133.96468 -222.514668) (xy 134.373112 -222.106236) (xy 134.360158 -222.07474) (xy 134.352114 -222.054544)
			(xy 134.340797 -222.012571) (xy 134.335087 -221.969476) (xy 134.334758 -221.94774) (xy 134.33524 -221.922413)
			(xy 134.342964 -221.872351) (xy 134.358239 -221.824054) (xy 134.380706 -221.778654) (xy 134.409838 -221.737215)
			(xy 134.444954 -221.700708) (xy 134.48523 -221.669988) (xy 134.507224 -221.657418) (xy 134.53364 -221.643194)
			(xy 134.53364 -221.49562) (xy 134.533188 -221.481951) (xy 134.525914 -221.455597) (xy 134.511908 -221.432117)
			(xy 134.492175 -221.413195) (xy 134.468129 -221.400187) (xy 134.441493 -221.394024) (xy 134.414176 -221.395149)
			(xy 134.388138 -221.403482) (xy 134.376414 -221.41053) (xy 134.356147 -221.42326) (xy 134.312724 -221.443382)
			(xy 134.266854 -221.457038) (xy 134.219496 -221.463943) (xy 134.195566 -221.464378) (xy 134.1696 -221.463866)
			(xy 134.118308 -221.455738) (xy 134.068918 -221.439686) (xy 134.022647 -221.416107) (xy 133.980634 -221.385581)
			(xy 133.943913 -221.348859) (xy 133.913387 -221.306844) (xy 133.88981 -221.260573) (xy 133.87376 -221.211183)
			(xy 133.865633 -221.15989) (xy 133.865112 -221.133924) (xy 133.865723 -221.105944) (xy 133.875171 -221.050785)
			(xy 133.883908 -221.024196) (xy 133.891528 -221.002098) (xy 133.68782 -220.649038) (xy 133.66496 -220.64472)
			(xy 133.640014 -220.639585) (xy 133.591978 -220.622668) (xy 133.547105 -220.598581) (xy 133.50646 -220.567894)
			(xy 133.471005 -220.531334) (xy 133.441578 -220.489767) (xy 133.418878 -220.444178) (xy 133.403442 -220.395645)
			(xy 133.395635 -220.345318) (xy 133.395212 -220.319854) (xy 133.395721 -220.293887) (xy 133.403846 -220.242592)
			(xy 133.419894 -220.193199) (xy 133.443472 -220.146925) (xy 133.473998 -220.104909) (xy 133.510721 -220.068186)
			(xy 133.552737 -220.03766) (xy 133.599011 -220.014082) (xy 133.648404 -219.998034) (xy 133.699699 -219.989909)
			(xy 133.751633 -219.989909) (xy 133.802928 -219.998034) (xy 133.852321 -220.014082) (xy 133.898595 -220.03766)
			(xy 133.940611 -220.068186) (xy 133.977334 -220.104909) (xy 134.00786 -220.146925) (xy 134.031438 -220.193199)
			(xy 134.047486 -220.242592) (xy 134.055611 -220.293887) (xy 134.05612 -220.319854) (xy 134.055511 -220.347835)
			(xy 134.046067 -220.402995) (xy 134.037324 -220.429582) (xy 134.029704 -220.451426) (xy 134.233666 -220.80474)
			(xy 134.256526 -220.809058) (xy 134.277781 -220.813388) (xy 134.319001 -220.8269) (xy 134.358089 -220.845711)
			(xy 134.376414 -220.857318) (xy 134.388103 -220.864431) (xy 134.414149 -220.872781) (xy 134.441477 -220.873913)
			(xy 134.468125 -220.867747) (xy 134.492177 -220.854724) (xy 134.511907 -220.835782) (xy 134.525898 -220.812279)
			(xy 134.533144 -220.785904) (xy 134.53364 -220.772228) (xy 134.53364 -220.6244) (xy 134.507224 -220.610176)
			(xy 134.485224 -220.59763) (xy 134.44498 -220.56689) (xy 134.409893 -220.530373) (xy 134.380786 -220.488931)
			(xy 134.35834 -220.443536) (xy 134.343078 -220.395249) (xy 134.335359 -220.345199) (xy 134.335362 -220.294557)
			(xy 134.343088 -220.244508) (xy 134.358356 -220.196223) (xy 134.380809 -220.150831) (xy 134.409921 -220.109393)
			(xy 134.445013 -220.07288) (xy 134.485261 -220.042146) (xy 134.507224 -220.029532) (xy 134.53364 -220.015308)
			(xy 134.53364 -219.867734) (xy 134.53319 -219.854063) (xy 134.525918 -219.827706) (xy 134.511913 -219.804223)
			(xy 134.492179 -219.785298) (xy 134.46813 -219.772287) (xy 134.441492 -219.766124) (xy 134.414173 -219.76725)
			(xy 134.388132 -219.775585) (xy 134.376414 -219.782644) (xy 134.356147 -219.795374) (xy 134.312723 -219.815495)
			(xy 134.266854 -219.82915) (xy 134.219495 -219.836055) (xy 134.195566 -219.836492) (xy 134.169598 -219.83598)
			(xy 134.118301 -219.827851) (xy 134.068907 -219.811797) (xy 134.022633 -219.788215) (xy 133.980617 -219.757684)
			(xy 133.943893 -219.720958) (xy 133.913367 -219.678938) (xy 133.88979 -219.632662) (xy 133.873741 -219.583266)
			(xy 133.865617 -219.531969) (xy 133.865617 -219.480032) (xy 133.873741 -219.428734) (xy 133.88979 -219.379339)
			(xy 133.913367 -219.333062) (xy 133.943893 -219.291042) (xy 133.980617 -219.254316) (xy 134.022633 -219.223785)
			(xy 134.068907 -219.200203) (xy 134.118301 -219.184149) (xy 134.169598 -219.17602) (xy 134.195566 -219.175584)
			(xy 134.219497 -219.176006) (xy 134.266858 -219.182904) (xy 134.31273 -219.196562) (xy 134.356151 -219.216693)
			(xy 134.376414 -219.229432) (xy 134.388104 -219.236544) (xy 134.41415 -219.244893) (xy 134.441479 -219.246025)
			(xy 134.468127 -219.239859) (xy 134.49218 -219.226837) (xy 134.511912 -219.207894) (xy 134.525905 -219.184392)
			(xy 134.533153 -219.158018) (xy 134.53364 -219.144342) (xy 134.53364 -218.996768) (xy 134.507224 -218.98229)
			(xy 134.485246 -218.969749) (xy 134.445042 -218.939026) (xy 134.409991 -218.902533) (xy 134.380913 -218.861123)
			(xy 134.358488 -218.815765) (xy 134.343239 -218.767518) (xy 134.335524 -218.71751) (xy 134.335522 -218.666911)
			(xy 134.343234 -218.616903) (xy 134.35848 -218.568655) (xy 134.380902 -218.523295) (xy 134.409977 -218.481883)
			(xy 134.445026 -218.445388) (xy 134.485228 -218.414662) (xy 134.507224 -218.402154) (xy 134.53364 -218.387676)
			(xy 134.53364 -218.240102) (xy 134.533198 -218.226424) (xy 134.525937 -218.20005) (xy 134.511935 -218.17655)
			(xy 134.492196 -218.157611) (xy 134.468139 -218.14459) (xy 134.441487 -218.138424) (xy 134.414156 -218.139553)
			(xy 134.388104 -218.147898) (xy 134.376414 -218.155012) (xy 134.356147 -218.167743) (xy 134.312724 -218.187866)
			(xy 134.266854 -218.201523) (xy 134.219496 -218.208428) (xy 134.195566 -218.20886) (xy 134.1696 -218.208348)
			(xy 134.118309 -218.20022) (xy 134.068921 -218.184168) (xy 134.022651 -218.160589) (xy 133.980639 -218.130062)
			(xy 133.94392 -218.093339) (xy 133.913397 -218.051325) (xy 133.889821 -218.005053) (xy 133.873774 -217.955664)
			(xy 133.86565 -217.904372) (xy 133.865112 -217.878406) (xy 133.865725 -217.850426) (xy 133.875176 -217.795268)
			(xy 133.883908 -217.768678) (xy 133.891528 -217.74658) (xy 133.68782 -217.39352) (xy 133.664706 -217.389202)
			(xy 133.639764 -217.384063) (xy 133.591735 -217.36714) (xy 133.546871 -217.343049) (xy 133.506234 -217.312361)
			(xy 133.470787 -217.275801) (xy 133.441368 -217.234235) (xy 133.418675 -217.188648) (xy 133.403244 -217.140119)
			(xy 133.395441 -217.089798) (xy 133.394958 -217.064336) (xy 133.395467 -217.038369) (xy 133.403592 -216.987074)
			(xy 133.41964 -216.937681) (xy 133.443218 -216.891407) (xy 133.473744 -216.849391) (xy 133.510467 -216.812668)
			(xy 133.552483 -216.782142) (xy 133.598757 -216.758564) (xy 133.64815 -216.742516) (xy 133.699445 -216.734391)
			(xy 133.751379 -216.734391) (xy 133.802674 -216.742516) (xy 133.852067 -216.758564) (xy 133.898341 -216.782142)
			(xy 133.940357 -216.812668) (xy 133.97708 -216.849391) (xy 134.007606 -216.891407) (xy 134.031184 -216.937681)
			(xy 134.047232 -216.987074) (xy 134.055357 -217.038369) (xy 134.055866 -217.064336) (xy 134.055304 -217.092243)
			(xy 134.045983 -217.147274) (xy 134.037324 -217.17381) (xy 134.02945 -217.195654) (xy 134.233666 -217.549222)
			(xy 134.256526 -217.55354) (xy 134.277782 -217.55787) (xy 134.319002 -217.571381) (xy 134.35809 -217.590191)
			(xy 134.376414 -217.6018) (xy 134.388102 -217.608914) (xy 134.414147 -217.617265) (xy 134.441475 -217.618399)
			(xy 134.468121 -217.612232) (xy 134.492173 -217.599209) (xy 134.511901 -217.580265) (xy 134.525889 -217.556761)
			(xy 134.533131 -217.530386) (xy 134.53364 -217.51671) (xy 134.53364 -217.368882) (xy 134.507224 -217.354404)
			(xy 134.485245 -217.341863) (xy 134.445038 -217.31114) (xy 134.409985 -217.274646) (xy 134.380905 -217.233236)
			(xy 134.358478 -217.187876) (xy 134.343228 -217.139627) (xy 134.335511 -217.089618) (xy 134.335509 -217.039017)
			(xy 134.34322 -216.989006) (xy 134.358465 -216.940756) (xy 134.380888 -216.895394) (xy 134.409963 -216.85398)
			(xy 134.445012 -216.817483) (xy 134.485216 -216.786755) (xy 134.507224 -216.774268) (xy 134.53364 -216.75979)
			(xy 134.53364 -216.612216) (xy 134.5332 -216.598537) (xy 134.525941 -216.57216) (xy 134.511939 -216.548656)
			(xy 134.4922 -216.529713) (xy 134.46814 -216.516691) (xy 134.441487 -216.510524) (xy 134.414152 -216.511654)
			(xy 134.388098 -216.520001) (xy 134.376414 -216.527126) (xy 134.356147 -216.539856) (xy 134.312724 -216.559979)
			(xy 134.266854 -216.573635) (xy 134.219496 -216.58054) (xy 134.195566 -216.580974) (xy 134.169599 -216.580462)
			(xy 134.118305 -216.572333) (xy 134.068914 -216.55628) (xy 134.022642 -216.5327) (xy 133.980628 -216.502171)
			(xy 133.943907 -216.465446) (xy 133.913383 -216.423429) (xy 133.889806 -216.377155) (xy 133.873759 -216.327762)
			(xy 133.865635 -216.276467) (xy 133.865635 -216.224533) (xy 133.873759 -216.173238) (xy 133.889806 -216.123845)
			(xy 133.913383 -216.077571) (xy 133.943907 -216.035554) (xy 133.980628 -215.998829) (xy 134.022642 -215.9683)
			(xy 134.068914 -215.94472) (xy 134.118305 -215.928667) (xy 134.169599 -215.920538) (xy 134.195566 -215.920066)
			(xy 134.219497 -215.920488) (xy 134.266859 -215.927386) (xy 134.31273 -215.941043) (xy 134.356153 -215.961173)
			(xy 134.376414 -215.973914) (xy 134.388103 -215.981027) (xy 134.414148 -215.989378) (xy 134.441477 -215.99051)
			(xy 134.468124 -215.984344) (xy 134.492176 -215.971321) (xy 134.511906 -215.952378) (xy 134.525896 -215.928875)
			(xy 134.533141 -215.9025) (xy 134.53364 -215.888824) (xy 134.53364 -215.74125) (xy 134.507224 -215.727026)
			(xy 134.48653 -215.715296) (xy 134.44844 -215.686804) (xy 134.414833 -215.65314) (xy 134.40029 -215.634316)
			(xy 133.990334 -215.634316) (xy 133.974614 -215.654553) (xy 133.937983 -215.690383) (xy 133.896265 -215.720137)
			(xy 133.850458 -215.743102) (xy 133.801658 -215.758731) (xy 133.751032 -215.766648) (xy 133.725412 -215.767158)
			(xy 133.699442 -215.766676) (xy 133.648141 -215.758552) (xy 133.598742 -215.742503) (xy 133.552462 -215.718924)
			(xy 133.510441 -215.688395) (xy 133.473713 -215.651668) (xy 133.443182 -215.609648) (xy 133.419601 -215.563369)
			(xy 133.40355 -215.513971) (xy 133.395425 -215.46267) (xy 133.395425 -215.41073) (xy 133.40355 -215.359429)
			(xy 133.419601 -215.310031) (xy 133.443182 -215.263752) (xy 133.473713 -215.221732) (xy 133.510441 -215.185005)
			(xy 133.552462 -215.154476) (xy 133.598742 -215.130897) (xy 133.648141 -215.114848) (xy 133.699442 -215.106724)
			(xy 133.725412 -215.10625) (xy 133.751037 -215.106726) (xy 133.801673 -215.114624) (xy 133.850483 -215.130246)
			(xy 133.896297 -215.153215) (xy 133.938015 -215.182982) (xy 133.974637 -215.218833) (xy 133.990334 -215.239092)
			(xy 134.097776 -215.239092) (xy 134.107801 -215.238693) (xy 134.126334 -215.231049) (xy 134.140517 -215.216881)
			(xy 134.148182 -215.198356) (xy 134.148155 -215.178309) (xy 134.140441 -215.159805) (xy 134.13359 -215.152478)
			(xy 133.96722 -214.986108) (xy 133.273546 -214.986108) (xy 133.08965 -215.304878) (xy 133.09727 -215.326976)
			(xy 133.106064 -215.35355) (xy 133.115514 -215.408718) (xy 133.116066 -215.436704) (xy 133.115557 -215.462671)
			(xy 133.107432 -215.513966) (xy 133.091384 -215.563359) (xy 133.067806 -215.609633) (xy 133.03728 -215.651649)
			(xy 133.000557 -215.688372) (xy 132.958541 -215.718898) (xy 132.912267 -215.742476) (xy 132.862874 -215.758524)
			(xy 132.811579 -215.766649) (xy 132.759645 -215.766649) (xy 132.70835 -215.758524) (xy 132.658957 -215.742476)
			(xy 132.612683 -215.718898) (xy 132.570667 -215.688372) (xy 132.533944 -215.651649) (xy 132.503418 -215.609633)
			(xy 132.47984 -215.563359) (xy 132.463792 -215.513966) (xy 132.455667 -215.462671) (xy 132.455158 -215.436704)
			(xy 132.455634 -215.411258) (xy 132.463446 -215.360969) (xy 132.478873 -215.31247) (xy 132.501548 -215.266908)
			(xy 132.530937 -215.225359) (xy 132.566346 -215.188804) (xy 132.606937 -215.158106) (xy 132.651753 -215.13399)
			(xy 132.699735 -215.117026) (xy 132.724652 -215.111838) (xy 132.747512 -215.10752) (xy 132.773674 -215.062308)
			(xy 132.778535 -215.052787) (xy 132.780775 -215.031554) (xy 132.774186 -215.011244) (xy 132.759908 -214.99537)
			(xy 132.740407 -214.986675) (xy 132.729732 -214.986108) (xy 131.393946 -214.986108) (xy 131.21005 -215.304878)
			(xy 131.21767 -215.326976) (xy 131.226464 -215.35355) (xy 131.235914 -215.408718) (xy 131.236466 -215.436704)
			(xy 131.235957 -215.462671) (xy 131.227832 -215.513966) (xy 131.211784 -215.563359) (xy 131.188206 -215.609633)
			(xy 131.15768 -215.651649) (xy 131.120957 -215.688372) (xy 131.078941 -215.718898) (xy 131.032667 -215.742476)
			(xy 130.983274 -215.758524) (xy 130.931979 -215.766649) (xy 130.880045 -215.766649) (xy 130.82875 -215.758524)
			(xy 130.779357 -215.742476) (xy 130.733083 -215.718898) (xy 130.691067 -215.688372) (xy 130.654344 -215.651649)
			(xy 130.623818 -215.609633) (xy 130.60024 -215.563359) (xy 130.584192 -215.513966) (xy 130.576067 -215.462671)
			(xy 130.575558 -215.436704) (xy 130.576034 -215.411258) (xy 130.583846 -215.360969) (xy 130.599273 -215.31247)
			(xy 130.621948 -215.266908) (xy 130.651337 -215.225359) (xy 130.686746 -215.188804) (xy 130.727337 -215.158106)
			(xy 130.772153 -215.13399) (xy 130.820135 -215.117026) (xy 130.845052 -215.111838) (xy 130.867912 -215.10752)
			(xy 130.894074 -215.062308) (xy 130.898935 -215.052787) (xy 130.901175 -215.031554) (xy 130.894586 -215.011244)
			(xy 130.880308 -214.99537) (xy 130.860807 -214.986675) (xy 130.850132 -214.986108) (xy 129.514346 -214.986108)
			(xy 129.33045 -215.304878) (xy 129.33807 -215.326976) (xy 129.346864 -215.35355) (xy 129.356314 -215.408718)
			(xy 129.356866 -215.436704) (xy 129.356357 -215.462671) (xy 129.348232 -215.513966) (xy 129.332184 -215.563359)
			(xy 129.308606 -215.609633) (xy 129.27808 -215.651649) (xy 129.241357 -215.688372) (xy 129.199341 -215.718898)
			(xy 129.153067 -215.742476) (xy 129.103674 -215.758524) (xy 129.052379 -215.766649) (xy 129.000445 -215.766649)
			(xy 128.94915 -215.758524) (xy 128.899757 -215.742476) (xy 128.853483 -215.718898) (xy 128.811467 -215.688372)
			(xy 128.774744 -215.651649) (xy 128.744218 -215.609633) (xy 128.72064 -215.563359) (xy 128.704592 -215.513966)
			(xy 128.696467 -215.462671) (xy 128.695958 -215.436704) (xy 128.696434 -215.411258) (xy 128.704246 -215.360969)
			(xy 128.719673 -215.31247) (xy 128.742348 -215.266908) (xy 128.771737 -215.225359) (xy 128.807146 -215.188804)
			(xy 128.847737 -215.158106) (xy 128.892553 -215.13399) (xy 128.940535 -215.117026) (xy 128.965452 -215.111838)
			(xy 128.988312 -215.10752) (xy 129.014474 -215.062308) (xy 129.019335 -215.052787) (xy 129.021575 -215.031554)
			(xy 129.014986 -215.011244) (xy 129.000708 -214.99537) (xy 128.981207 -214.986675) (xy 128.970532 -214.986108)
			(xy 127.70104 -214.986108) (xy 127.544068 -215.14308) (xy 127.45085 -215.304878) (xy 127.45847 -215.326976)
			(xy 127.467264 -215.35355) (xy 127.476714 -215.408718) (xy 127.477266 -215.436704) (xy 127.476789 -215.462034)
			(xy 127.469072 -215.512102) (xy 127.453804 -215.560406) (xy 127.431342 -215.605813) (xy 127.402213 -215.647261)
			(xy 127.3671 -215.683777) (xy 127.326824 -215.714506) (xy 127.3048 -215.727026) (xy 127.3048 -215.87333)
			(xy 127.305343 -215.888456) (xy 127.31419 -215.917384) (xy 127.331126 -215.942449) (xy 127.354665 -215.96145)
			(xy 127.382739 -215.972717) (xy 127.412883 -215.975261) (xy 127.442448 -215.968858) (xy 127.45593 -215.961976)
			(xy 127.480714 -215.948819) (xy 127.533616 -215.930132) (xy 127.588913 -215.920641) (xy 127.616966 -215.920066)
			(xy 127.642935 -215.920546) (xy 127.694236 -215.928667) (xy 127.743634 -215.944712) (xy 127.789913 -215.968289)
			(xy 127.831935 -215.998815) (xy 127.868663 -216.03554) (xy 127.899193 -216.077558) (xy 127.922775 -216.123835)
			(xy 127.938826 -216.173231) (xy 127.946951 -216.224531) (xy 127.946951 -216.276469) (xy 127.946948 -216.276487)
			(xy 128.226821 -216.276487) (xy 128.226821 -216.224553) (xy 128.234946 -216.173258) (xy 128.250994 -216.123865)
			(xy 128.274572 -216.077591) (xy 128.305098 -216.035575) (xy 128.341821 -215.998852) (xy 128.383837 -215.968326)
			(xy 128.430111 -215.944748) (xy 128.479504 -215.9287) (xy 128.530799 -215.920575) (xy 128.582733 -215.920575)
			(xy 128.634028 -215.9287) (xy 128.683421 -215.944748) (xy 128.729695 -215.968326) (xy 128.771711 -215.998852)
			(xy 128.808434 -216.035575) (xy 128.83896 -216.077591) (xy 128.862538 -216.123865) (xy 128.878586 -216.173258)
			(xy 128.886711 -216.224553) (xy 128.88722 -216.25052) (xy 128.886711 -216.276487) (xy 129.166621 -216.276487)
			(xy 129.166621 -216.224553) (xy 129.174746 -216.173258) (xy 129.190794 -216.123865) (xy 129.214372 -216.077591)
			(xy 129.244898 -216.035575) (xy 129.281621 -215.998852) (xy 129.323637 -215.968326) (xy 129.369911 -215.944748)
			(xy 129.419304 -215.9287) (xy 129.470599 -215.920575) (xy 129.522533 -215.920575) (xy 129.573828 -215.9287)
			(xy 129.623221 -215.944748) (xy 129.669495 -215.968326) (xy 129.711511 -215.998852) (xy 129.748234 -216.035575)
			(xy 129.77876 -216.077591) (xy 129.802338 -216.123865) (xy 129.818386 -216.173258) (xy 129.826511 -216.224553)
			(xy 129.82702 -216.25052) (xy 129.826511 -216.276487) (xy 130.106421 -216.276487) (xy 130.106421 -216.224553)
			(xy 130.114546 -216.173258) (xy 130.130594 -216.123865) (xy 130.154172 -216.077591) (xy 130.184698 -216.035575)
			(xy 130.221421 -215.998852) (xy 130.263437 -215.968326) (xy 130.309711 -215.944748) (xy 130.359104 -215.9287)
			(xy 130.410399 -215.920575) (xy 130.462333 -215.920575) (xy 130.513628 -215.9287) (xy 130.563021 -215.944748)
			(xy 130.609295 -215.968326) (xy 130.651311 -215.998852) (xy 130.688034 -216.035575) (xy 130.71856 -216.077591)
			(xy 130.742138 -216.123865) (xy 130.758186 -216.173258) (xy 130.766311 -216.224553) (xy 130.76682 -216.25052)
			(xy 130.766311 -216.276487) (xy 131.046221 -216.276487) (xy 131.046221 -216.224553) (xy 131.054346 -216.173258)
			(xy 131.070394 -216.123865) (xy 131.093972 -216.077591) (xy 131.124498 -216.035575) (xy 131.161221 -215.998852)
			(xy 131.203237 -215.968326) (xy 131.249511 -215.944748) (xy 131.298904 -215.9287) (xy 131.350199 -215.920575)
			(xy 131.402133 -215.920575) (xy 131.453428 -215.9287) (xy 131.502821 -215.944748) (xy 131.549095 -215.968326)
			(xy 131.591111 -215.998852) (xy 131.627834 -216.035575) (xy 131.65836 -216.077591) (xy 131.681938 -216.123865)
			(xy 131.697986 -216.173258) (xy 131.706111 -216.224553) (xy 131.70662 -216.25052) (xy 131.706111 -216.276487)
			(xy 131.986021 -216.276487) (xy 131.986021 -216.224553) (xy 131.994146 -216.173258) (xy 132.010194 -216.123865)
			(xy 132.033772 -216.077591) (xy 132.064298 -216.035575) (xy 132.101021 -215.998852) (xy 132.143037 -215.968326)
			(xy 132.189311 -215.944748) (xy 132.238704 -215.9287) (xy 132.289999 -215.920575) (xy 132.341933 -215.920575)
			(xy 132.393228 -215.9287) (xy 132.442621 -215.944748) (xy 132.488895 -215.968326) (xy 132.530911 -215.998852)
			(xy 132.567634 -216.035575) (xy 132.59816 -216.077591) (xy 132.621738 -216.123865) (xy 132.637786 -216.173258)
			(xy 132.645911 -216.224553) (xy 132.64642 -216.25052) (xy 132.645911 -216.276487) (xy 132.925821 -216.276487)
			(xy 132.925821 -216.224553) (xy 132.933946 -216.173258) (xy 132.949994 -216.123865) (xy 132.973572 -216.077591)
			(xy 133.004098 -216.035575) (xy 133.040821 -215.998852) (xy 133.082837 -215.968326) (xy 133.129111 -215.944748)
			(xy 133.178504 -215.9287) (xy 133.229799 -215.920575) (xy 133.281733 -215.920575) (xy 133.333028 -215.9287)
			(xy 133.382421 -215.944748) (xy 133.428695 -215.968326) (xy 133.470711 -215.998852) (xy 133.507434 -216.035575)
			(xy 133.53796 -216.077591) (xy 133.561538 -216.123865) (xy 133.577586 -216.173258) (xy 133.585711 -216.224553)
			(xy 133.58622 -216.25052) (xy 133.585711 -216.276487) (xy 133.577586 -216.327782) (xy 133.561538 -216.377175)
			(xy 133.53796 -216.423449) (xy 133.507434 -216.465465) (xy 133.470711 -216.502188) (xy 133.428695 -216.532714)
			(xy 133.382421 -216.556292) (xy 133.333028 -216.57234) (xy 133.281733 -216.580465) (xy 133.229799 -216.580465)
			(xy 133.178504 -216.57234) (xy 133.129111 -216.556292) (xy 133.082837 -216.532714) (xy 133.040821 -216.502188)
			(xy 133.004098 -216.465465) (xy 132.973572 -216.423449) (xy 132.949994 -216.377175) (xy 132.933946 -216.327782)
			(xy 132.925821 -216.276487) (xy 132.645911 -216.276487) (xy 132.637786 -216.327782) (xy 132.621738 -216.377175)
			(xy 132.59816 -216.423449) (xy 132.567634 -216.465465) (xy 132.530911 -216.502188) (xy 132.488895 -216.532714)
			(xy 132.442621 -216.556292) (xy 132.393228 -216.57234) (xy 132.341933 -216.580465) (xy 132.289999 -216.580465)
			(xy 132.238704 -216.57234) (xy 132.189311 -216.556292) (xy 132.143037 -216.532714) (xy 132.101021 -216.502188)
			(xy 132.064298 -216.465465) (xy 132.033772 -216.423449) (xy 132.010194 -216.377175) (xy 131.994146 -216.327782)
			(xy 131.986021 -216.276487) (xy 131.706111 -216.276487) (xy 131.697986 -216.327782) (xy 131.681938 -216.377175)
			(xy 131.65836 -216.423449) (xy 131.627834 -216.465465) (xy 131.591111 -216.502188) (xy 131.549095 -216.532714)
			(xy 131.502821 -216.556292) (xy 131.453428 -216.57234) (xy 131.402133 -216.580465) (xy 131.350199 -216.580465)
			(xy 131.298904 -216.57234) (xy 131.249511 -216.556292) (xy 131.203237 -216.532714) (xy 131.161221 -216.502188)
			(xy 131.124498 -216.465465) (xy 131.093972 -216.423449) (xy 131.070394 -216.377175) (xy 131.054346 -216.327782)
			(xy 131.046221 -216.276487) (xy 130.766311 -216.276487) (xy 130.758186 -216.327782) (xy 130.742138 -216.377175)
			(xy 130.71856 -216.423449) (xy 130.688034 -216.465465) (xy 130.651311 -216.502188) (xy 130.609295 -216.532714)
			(xy 130.563021 -216.556292) (xy 130.513628 -216.57234) (xy 130.462333 -216.580465) (xy 130.410399 -216.580465)
			(xy 130.359104 -216.57234) (xy 130.309711 -216.556292) (xy 130.263437 -216.532714) (xy 130.221421 -216.502188)
			(xy 130.184698 -216.465465) (xy 130.154172 -216.423449) (xy 130.130594 -216.377175) (xy 130.114546 -216.327782)
			(xy 130.106421 -216.276487) (xy 129.826511 -216.276487) (xy 129.818386 -216.327782) (xy 129.802338 -216.377175)
			(xy 129.77876 -216.423449) (xy 129.748234 -216.465465) (xy 129.711511 -216.502188) (xy 129.669495 -216.532714)
			(xy 129.623221 -216.556292) (xy 129.573828 -216.57234) (xy 129.522533 -216.580465) (xy 129.470599 -216.580465)
			(xy 129.419304 -216.57234) (xy 129.369911 -216.556292) (xy 129.323637 -216.532714) (xy 129.281621 -216.502188)
			(xy 129.244898 -216.465465) (xy 129.214372 -216.423449) (xy 129.190794 -216.377175) (xy 129.174746 -216.327782)
			(xy 129.166621 -216.276487) (xy 128.886711 -216.276487) (xy 128.878586 -216.327782) (xy 128.862538 -216.377175)
			(xy 128.83896 -216.423449) (xy 128.808434 -216.465465) (xy 128.771711 -216.502188) (xy 128.729695 -216.532714)
			(xy 128.683421 -216.556292) (xy 128.634028 -216.57234) (xy 128.582733 -216.580465) (xy 128.530799 -216.580465)
			(xy 128.479504 -216.57234) (xy 128.430111 -216.556292) (xy 128.383837 -216.532714) (xy 128.341821 -216.502188)
			(xy 128.305098 -216.465465) (xy 128.274572 -216.423449) (xy 128.250994 -216.377175) (xy 128.234946 -216.327782)
			(xy 128.226821 -216.276487) (xy 127.946948 -216.276487) (xy 127.938826 -216.327769) (xy 127.922775 -216.377165)
			(xy 127.899193 -216.423442) (xy 127.868663 -216.46546) (xy 127.831935 -216.502185) (xy 127.789913 -216.532711)
			(xy 127.743634 -216.556288) (xy 127.694236 -216.572333) (xy 127.642935 -216.580454) (xy 127.616966 -216.580974)
			(xy 127.588912 -216.580385) (xy 127.53361 -216.570916) (xy 127.480703 -216.55224) (xy 127.45593 -216.539064)
			(xy 127.442458 -216.532175) (xy 127.412895 -216.525809) (xy 127.382762 -216.528374) (xy 127.3547 -216.539644)
			(xy 127.331164 -216.558634) (xy 127.314217 -216.58368) (xy 127.305341 -216.61259) (xy 127.3048 -216.62771)
			(xy 127.3048 -216.774014) (xy 127.326845 -216.786514) (xy 127.367159 -216.817222) (xy 127.40231 -216.853726)
			(xy 127.431474 -216.89517) (xy 127.453966 -216.940582) (xy 127.46926 -216.988896) (xy 127.476997 -217.038979)
			(xy 127.476995 -217.064336) (xy 127.756158 -217.064336) (xy 127.756667 -217.038369) (xy 127.764792 -216.987074)
			(xy 127.78084 -216.937681) (xy 127.804418 -216.891407) (xy 127.834944 -216.849391) (xy 127.871667 -216.812668)
			(xy 127.913683 -216.782142) (xy 127.959957 -216.758564) (xy 128.00935 -216.742516) (xy 128.060645 -216.734391)
			(xy 128.112579 -216.734391) (xy 128.163874 -216.742516) (xy 128.213267 -216.758564) (xy 128.259541 -216.782142)
			(xy 128.301557 -216.812668) (xy 128.33828 -216.849391) (xy 128.368806 -216.891407) (xy 128.392384 -216.937681)
			(xy 128.408432 -216.987074) (xy 128.416557 -217.038369) (xy 128.417066 -217.064336) (xy 128.416565 -217.090303)
			(xy 128.696721 -217.090303) (xy 128.696721 -217.038369) (xy 128.704846 -216.987074) (xy 128.720894 -216.937681)
			(xy 128.744472 -216.891407) (xy 128.774998 -216.849391) (xy 128.811721 -216.812668) (xy 128.853737 -216.782142)
			(xy 128.900011 -216.758564) (xy 128.949404 -216.742516) (xy 129.000699 -216.734391) (xy 129.052633 -216.734391)
			(xy 129.103928 -216.742516) (xy 129.153321 -216.758564) (xy 129.199595 -216.782142) (xy 129.241611 -216.812668)
			(xy 129.278334 -216.849391) (xy 129.30886 -216.891407) (xy 129.332438 -216.937681) (xy 129.348486 -216.987074)
			(xy 129.356611 -217.038369) (xy 129.35712 -217.064336) (xy 129.635758 -217.064336) (xy 129.636267 -217.038369)
			(xy 129.644392 -216.987074) (xy 129.66044 -216.937681) (xy 129.684018 -216.891407) (xy 129.714544 -216.849391)
			(xy 129.751267 -216.812668) (xy 129.793283 -216.782142) (xy 129.839557 -216.758564) (xy 129.88895 -216.742516)
			(xy 129.940245 -216.734391) (xy 129.992179 -216.734391) (xy 130.043474 -216.742516) (xy 130.092867 -216.758564)
			(xy 130.139141 -216.782142) (xy 130.181157 -216.812668) (xy 130.21788 -216.849391) (xy 130.248406 -216.891407)
			(xy 130.271984 -216.937681) (xy 130.288032 -216.987074) (xy 130.296157 -217.038369) (xy 130.296666 -217.064336)
			(xy 130.296165 -217.090303) (xy 130.576321 -217.090303) (xy 130.576321 -217.038369) (xy 130.584446 -216.987074)
			(xy 130.600494 -216.937681) (xy 130.624072 -216.891407) (xy 130.654598 -216.849391) (xy 130.691321 -216.812668)
			(xy 130.733337 -216.782142) (xy 130.779611 -216.758564) (xy 130.829004 -216.742516) (xy 130.880299 -216.734391)
			(xy 130.932233 -216.734391) (xy 130.983528 -216.742516) (xy 131.032921 -216.758564) (xy 131.079195 -216.782142)
			(xy 131.121211 -216.812668) (xy 131.157934 -216.849391) (xy 131.18846 -216.891407) (xy 131.212038 -216.937681)
			(xy 131.228086 -216.987074) (xy 131.236211 -217.038369) (xy 131.23672 -217.064336) (xy 131.515358 -217.064336)
			(xy 131.515867 -217.038369) (xy 131.523992 -216.987074) (xy 131.54004 -216.937681) (xy 131.563618 -216.891407)
			(xy 131.594144 -216.849391) (xy 131.630867 -216.812668) (xy 131.672883 -216.782142) (xy 131.719157 -216.758564)
			(xy 131.76855 -216.742516) (xy 131.819845 -216.734391) (xy 131.871779 -216.734391) (xy 131.923074 -216.742516)
			(xy 131.972467 -216.758564) (xy 132.018741 -216.782142) (xy 132.060757 -216.812668) (xy 132.09748 -216.849391)
			(xy 132.128006 -216.891407) (xy 132.151584 -216.937681) (xy 132.167632 -216.987074) (xy 132.175757 -217.038369)
			(xy 132.176266 -217.064336) (xy 132.175765 -217.090303) (xy 132.455921 -217.090303) (xy 132.455921 -217.038369)
			(xy 132.464046 -216.987074) (xy 132.480094 -216.937681) (xy 132.503672 -216.891407) (xy 132.534198 -216.849391)
			(xy 132.570921 -216.812668) (xy 132.612937 -216.782142) (xy 132.659211 -216.758564) (xy 132.708604 -216.742516)
			(xy 132.759899 -216.734391) (xy 132.811833 -216.734391) (xy 132.863128 -216.742516) (xy 132.912521 -216.758564)
			(xy 132.958795 -216.782142) (xy 133.000811 -216.812668) (xy 133.037534 -216.849391) (xy 133.06806 -216.891407)
			(xy 133.091638 -216.937681) (xy 133.107686 -216.987074) (xy 133.115811 -217.038369) (xy 133.11632 -217.064336)
			(xy 133.115811 -217.090303) (xy 133.107686 -217.141598) (xy 133.091638 -217.190991) (xy 133.06806 -217.237265)
			(xy 133.037534 -217.279281) (xy 133.000811 -217.316004) (xy 132.958795 -217.34653) (xy 132.912521 -217.370108)
			(xy 132.863128 -217.386156) (xy 132.811833 -217.394281) (xy 132.759899 -217.394281) (xy 132.708604 -217.386156)
			(xy 132.659211 -217.370108) (xy 132.612937 -217.34653) (xy 132.570921 -217.316004) (xy 132.534198 -217.279281)
			(xy 132.503672 -217.237265) (xy 132.480094 -217.190991) (xy 132.464046 -217.141598) (xy 132.455921 -217.090303)
			(xy 132.175765 -217.090303) (xy 132.175727 -217.092245) (xy 132.166402 -217.147278) (xy 132.157724 -217.17381)
			(xy 132.14985 -217.195654) (xy 132.354066 -217.549222) (xy 132.376926 -217.55354) (xy 132.40184 -217.558742)
			(xy 132.449822 -217.575703) (xy 132.494638 -217.599816) (xy 132.535231 -217.630512) (xy 132.57064 -217.667066)
			(xy 132.600029 -217.708614) (xy 132.622705 -217.754174) (xy 132.638132 -217.802672) (xy 132.645945 -217.85296)
			(xy 132.64642 -217.878406) (xy 132.645911 -217.904373) (xy 132.637786 -217.955668) (xy 132.621738 -218.005061)
			(xy 132.59816 -218.051335) (xy 132.567634 -218.093351) (xy 132.530911 -218.130074) (xy 132.488895 -218.1606)
			(xy 132.442621 -218.184178) (xy 132.393228 -218.200226) (xy 132.341933 -218.208351) (xy 132.289999 -218.208351)
			(xy 132.238704 -218.200226) (xy 132.189311 -218.184178) (xy 132.143037 -218.1606) (xy 132.101021 -218.130074)
			(xy 132.064298 -218.093351) (xy 132.033772 -218.051335) (xy 132.010194 -218.005061) (xy 131.994146 -217.955668)
			(xy 131.986021 -217.904373) (xy 131.985512 -217.878406) (xy 131.986066 -217.85042) (xy 131.995515 -217.795252)
			(xy 132.004308 -217.768678) (xy 132.011928 -217.74658) (xy 131.80822 -217.39352) (xy 131.785106 -217.389202)
			(xy 131.760166 -217.384059) (xy 131.712142 -217.367128) (xy 131.667282 -217.343032) (xy 131.626649 -217.312342)
			(xy 131.591203 -217.275784) (xy 131.561782 -217.234221) (xy 131.539084 -217.188639) (xy 131.523645 -217.140115)
			(xy 131.51583 -217.089797) (xy 131.515358 -217.064336) (xy 131.23672 -217.064336) (xy 131.236211 -217.090303)
			(xy 131.228086 -217.141598) (xy 131.212038 -217.190991) (xy 131.18846 -217.237265) (xy 131.157934 -217.279281)
			(xy 131.121211 -217.316004) (xy 131.079195 -217.34653) (xy 131.032921 -217.370108) (xy 130.983528 -217.386156)
			(xy 130.932233 -217.394281) (xy 130.880299 -217.394281) (xy 130.829004 -217.386156) (xy 130.779611 -217.370108)
			(xy 130.733337 -217.34653) (xy 130.691321 -217.316004) (xy 130.654598 -217.279281) (xy 130.624072 -217.237265)
			(xy 130.600494 -217.190991) (xy 130.584446 -217.141598) (xy 130.576321 -217.090303) (xy 130.296165 -217.090303)
			(xy 130.296127 -217.092245) (xy 130.286802 -217.147278) (xy 130.278124 -217.17381) (xy 130.27025 -217.195654)
			(xy 130.474466 -217.549222) (xy 130.497326 -217.55354) (xy 130.52224 -217.558742) (xy 130.570222 -217.575703)
			(xy 130.615038 -217.599816) (xy 130.655631 -217.630512) (xy 130.69104 -217.667066) (xy 130.720429 -217.708614)
			(xy 130.743105 -217.754174) (xy 130.758532 -217.802672) (xy 130.766345 -217.85296) (xy 130.76682 -217.878406)
			(xy 130.766311 -217.904373) (xy 130.758186 -217.955668) (xy 130.742138 -218.005061) (xy 130.71856 -218.051335)
			(xy 130.688034 -218.093351) (xy 130.651311 -218.130074) (xy 130.609295 -218.1606) (xy 130.563021 -218.184178)
			(xy 130.513628 -218.200226) (xy 130.462333 -218.208351) (xy 130.410399 -218.208351) (xy 130.359104 -218.200226)
			(xy 130.309711 -218.184178) (xy 130.263437 -218.1606) (xy 130.221421 -218.130074) (xy 130.184698 -218.093351)
			(xy 130.154172 -218.051335) (xy 130.130594 -218.005061) (xy 130.114546 -217.955668) (xy 130.106421 -217.904373)
			(xy 130.105912 -217.878406) (xy 130.106466 -217.85042) (xy 130.115915 -217.795252) (xy 130.124708 -217.768678)
			(xy 130.132328 -217.74658) (xy 129.92862 -217.39352) (xy 129.905506 -217.389202) (xy 129.880566 -217.384059)
			(xy 129.832542 -217.367128) (xy 129.787682 -217.343032) (xy 129.747049 -217.312342) (xy 129.711603 -217.275784)
			(xy 129.682182 -217.234221) (xy 129.659484 -217.188639) (xy 129.644045 -217.140115) (xy 129.63623 -217.089797)
			(xy 129.635758 -217.064336) (xy 129.35712 -217.064336) (xy 129.356611 -217.090303) (xy 129.348486 -217.141598)
			(xy 129.332438 -217.190991) (xy 129.30886 -217.237265) (xy 129.278334 -217.279281) (xy 129.241611 -217.316004)
			(xy 129.199595 -217.34653) (xy 129.153321 -217.370108) (xy 129.103928 -217.386156) (xy 129.052633 -217.394281)
			(xy 129.000699 -217.394281) (xy 128.949404 -217.386156) (xy 128.900011 -217.370108) (xy 128.853737 -217.34653)
			(xy 128.811721 -217.316004) (xy 128.774998 -217.279281) (xy 128.744472 -217.237265) (xy 128.720894 -217.190991)
			(xy 128.704846 -217.141598) (xy 128.696721 -217.090303) (xy 128.416565 -217.090303) (xy 128.416527 -217.092245)
			(xy 128.407202 -217.147278) (xy 128.398524 -217.17381) (xy 128.39065 -217.195654) (xy 128.594866 -217.549222)
			(xy 128.617726 -217.55354) (xy 128.64264 -217.558742) (xy 128.690622 -217.575703) (xy 128.735438 -217.599816)
			(xy 128.776031 -217.630512) (xy 128.81144 -217.667066) (xy 128.840829 -217.708614) (xy 128.863505 -217.754174)
			(xy 128.878932 -217.802672) (xy 128.886745 -217.85296) (xy 128.88722 -217.878406) (xy 128.886711 -217.904373)
			(xy 128.878586 -217.955668) (xy 128.862538 -218.005061) (xy 128.83896 -218.051335) (xy 128.808434 -218.093351)
			(xy 128.771711 -218.130074) (xy 128.729695 -218.1606) (xy 128.683421 -218.184178) (xy 128.634028 -218.200226)
			(xy 128.582733 -218.208351) (xy 128.530799 -218.208351) (xy 128.479504 -218.200226) (xy 128.430111 -218.184178)
			(xy 128.383837 -218.1606) (xy 128.341821 -218.130074) (xy 128.305098 -218.093351) (xy 128.274572 -218.051335)
			(xy 128.250994 -218.005061) (xy 128.234946 -217.955668) (xy 128.226821 -217.904373) (xy 128.226312 -217.878406)
			(xy 128.226866 -217.85042) (xy 128.236315 -217.795252) (xy 128.245108 -217.768678) (xy 128.252728 -217.74658)
			(xy 128.04902 -217.39352) (xy 128.025906 -217.389202) (xy 128.000966 -217.384059) (xy 127.952942 -217.367128)
			(xy 127.908082 -217.343032) (xy 127.867449 -217.312342) (xy 127.832003 -217.275784) (xy 127.802582 -217.234221)
			(xy 127.779884 -217.188639) (xy 127.764445 -217.140115) (xy 127.75663 -217.089797) (xy 127.756158 -217.064336)
			(xy 127.476995 -217.064336) (xy 127.476994 -217.089656) (xy 127.469253 -217.139738) (xy 127.453954 -217.18805)
			(xy 127.431456 -217.233459) (xy 127.402288 -217.2749) (xy 127.367133 -217.311401) (xy 127.326816 -217.342104)
			(xy 127.3048 -217.354658) (xy 127.3048 -217.501216) (xy 127.305355 -217.516332) (xy 127.314215 -217.545237)
			(xy 127.331154 -217.570279) (xy 127.354684 -217.589261) (xy 127.382743 -217.600517) (xy 127.412868 -217.603061)
			(xy 127.442417 -217.59667) (xy 127.45593 -217.589862) (xy 127.480714 -217.576706) (xy 127.533616 -217.55802)
			(xy 127.588913 -217.548529) (xy 127.616966 -217.547952) (xy 127.642937 -217.548432) (xy 127.69424 -217.556553)
			(xy 127.74364 -217.5726) (xy 127.789922 -217.596178) (xy 127.831946 -217.626706) (xy 127.868676 -217.663433)
			(xy 127.899207 -217.705454) (xy 127.922789 -217.751734) (xy 127.93884 -217.801133) (xy 127.946965 -217.852435)
			(xy 127.94742 -217.878406) (xy 127.946949 -217.903879) (xy 127.939128 -217.954221) (xy 127.923673 -218.002767)
			(xy 127.90095 -218.048365) (xy 127.871497 -218.089934) (xy 127.836012 -218.126491) (xy 127.795337 -218.157167)
			(xy 127.750436 -218.181237) (xy 127.702372 -218.19813) (xy 127.677418 -218.203272) (xy 127.654304 -218.20759)
			(xy 127.45085 -218.560396) (xy 127.45847 -218.582494) (xy 127.467262 -218.609068) (xy 127.47671 -218.664236)
			(xy 127.477266 -218.692222) (xy 128.695958 -218.692222) (xy 128.696365 -218.666768) (xy 128.704154 -218.616461)
			(xy 128.719569 -218.567943) (xy 128.742242 -218.522364) (xy 128.771639 -218.480803) (xy 128.807062 -218.444242)
			(xy 128.847674 -218.413547) (xy 128.892514 -218.389444) (xy 128.94052 -218.372505) (xy 128.965452 -218.367356)
			(xy 128.988312 -218.363038) (xy 129.192274 -218.00947) (xy 129.184654 -217.987626) (xy 129.176017 -217.96115)
			(xy 129.166692 -217.906249) (xy 129.166112 -217.878406) (xy 129.166621 -217.852439) (xy 129.174746 -217.801144)
			(xy 129.190794 -217.751751) (xy 129.214372 -217.705477) (xy 129.244898 -217.663461) (xy 129.281621 -217.626738)
			(xy 129.323637 -217.596212) (xy 129.369911 -217.572634) (xy 129.419304 -217.556586) (xy 129.470599 -217.548461)
			(xy 129.522533 -217.548461) (xy 129.573828 -217.556586) (xy 129.623221 -217.572634) (xy 129.669495 -217.596212)
			(xy 129.711511 -217.626738) (xy 129.748234 -217.663461) (xy 129.77876 -217.705477) (xy 129.802338 -217.751751)
			(xy 129.818386 -217.801144) (xy 129.826511 -217.852439) (xy 129.82702 -217.878406) (xy 129.826571 -217.903881)
			(xy 129.81875 -217.954227) (xy 129.803294 -218.002775) (xy 129.780569 -218.048376) (xy 129.751114 -218.089949)
			(xy 129.715627 -218.126507) (xy 129.674949 -218.157186) (xy 129.630045 -218.181258) (xy 129.581977 -218.198151)
			(xy 129.557018 -218.203272) (xy 129.533904 -218.20759) (xy 129.33045 -218.560396) (xy 129.33807 -218.582494)
			(xy 129.346805 -218.609083) (xy 129.356255 -218.664242) (xy 129.356866 -218.692222) (xy 130.575558 -218.692222)
			(xy 130.575965 -218.666768) (xy 130.583754 -218.616461) (xy 130.599169 -218.567943) (xy 130.621842 -218.522364)
			(xy 130.651239 -218.480803) (xy 130.686662 -218.444242) (xy 130.727274 -218.413547) (xy 130.772114 -218.389444)
			(xy 130.82012 -218.372505) (xy 130.845052 -218.367356) (xy 130.867912 -218.363038) (xy 131.071874 -218.00947)
			(xy 131.064254 -217.987626) (xy 131.055617 -217.96115) (xy 131.046292 -217.906249) (xy 131.045712 -217.878406)
			(xy 131.046221 -217.852439) (xy 131.054346 -217.801144) (xy 131.070394 -217.751751) (xy 131.093972 -217.705477)
			(xy 131.124498 -217.663461) (xy 131.161221 -217.626738) (xy 131.203237 -217.596212) (xy 131.249511 -217.572634)
			(xy 131.298904 -217.556586) (xy 131.350199 -217.548461) (xy 131.402133 -217.548461) (xy 131.453428 -217.556586)
			(xy 131.502821 -217.572634) (xy 131.549095 -217.596212) (xy 131.591111 -217.626738) (xy 131.627834 -217.663461)
			(xy 131.65836 -217.705477) (xy 131.681938 -217.751751) (xy 131.697986 -217.801144) (xy 131.706111 -217.852439)
			(xy 131.70662 -217.878406) (xy 131.706171 -217.903881) (xy 131.69835 -217.954227) (xy 131.682894 -218.002775)
			(xy 131.660169 -218.048376) (xy 131.630714 -218.089949) (xy 131.595227 -218.126507) (xy 131.554549 -218.157186)
			(xy 131.509645 -218.181258) (xy 131.461577 -218.198151) (xy 131.436618 -218.203272) (xy 131.413504 -218.20759)
			(xy 131.21005 -218.560396) (xy 131.21767 -218.582494) (xy 131.226405 -218.609083) (xy 131.235855 -218.664242)
			(xy 131.236466 -218.692222) (xy 132.455158 -218.692222) (xy 132.455565 -218.666768) (xy 132.463354 -218.616461)
			(xy 132.478769 -218.567943) (xy 132.501442 -218.522364) (xy 132.530839 -218.480803) (xy 132.566262 -218.444242)
			(xy 132.606874 -218.413547) (xy 132.651714 -218.389444) (xy 132.69972 -218.372505) (xy 132.724652 -218.367356)
			(xy 132.747512 -218.363038) (xy 132.951474 -218.00947) (xy 132.943854 -217.987626) (xy 132.935217 -217.96115)
			(xy 132.925892 -217.906249) (xy 132.925312 -217.878406) (xy 132.925821 -217.852439) (xy 132.933946 -217.801144)
			(xy 132.949994 -217.751751) (xy 132.973572 -217.705477) (xy 133.004098 -217.663461) (xy 133.040821 -217.626738)
			(xy 133.082837 -217.596212) (xy 133.129111 -217.572634) (xy 133.178504 -217.556586) (xy 133.229799 -217.548461)
			(xy 133.281733 -217.548461) (xy 133.333028 -217.556586) (xy 133.382421 -217.572634) (xy 133.428695 -217.596212)
			(xy 133.470711 -217.626738) (xy 133.507434 -217.663461) (xy 133.53796 -217.705477) (xy 133.561538 -217.751751)
			(xy 133.577586 -217.801144) (xy 133.585711 -217.852439) (xy 133.58622 -217.878406) (xy 133.585771 -217.903881)
			(xy 133.57795 -217.954227) (xy 133.562494 -218.002775) (xy 133.539769 -218.048376) (xy 133.510314 -218.089949)
			(xy 133.474827 -218.126507) (xy 133.434149 -218.157186) (xy 133.389245 -218.181258) (xy 133.341177 -218.198151)
			(xy 133.316218 -218.203272) (xy 133.293104 -218.20759) (xy 133.08965 -218.560396) (xy 133.09727 -218.582494)
			(xy 133.106005 -218.609083) (xy 133.115455 -218.664242) (xy 133.116066 -218.692222) (xy 133.115557 -218.718189)
			(xy 133.107432 -218.769484) (xy 133.091384 -218.818877) (xy 133.067806 -218.865151) (xy 133.03728 -218.907167)
			(xy 133.000557 -218.94389) (xy 132.958541 -218.974416) (xy 132.912267 -218.997994) (xy 132.862874 -219.014042)
			(xy 132.811579 -219.022167) (xy 132.759645 -219.022167) (xy 132.70835 -219.014042) (xy 132.658957 -218.997994)
			(xy 132.612683 -218.974416) (xy 132.570667 -218.94389) (xy 132.533944 -218.907167) (xy 132.503418 -218.865151)
			(xy 132.47984 -218.818877) (xy 132.463792 -218.769484) (xy 132.455667 -218.718189) (xy 132.455158 -218.692222)
			(xy 131.236466 -218.692222) (xy 131.235957 -218.718189) (xy 131.227832 -218.769484) (xy 131.211784 -218.818877)
			(xy 131.188206 -218.865151) (xy 131.15768 -218.907167) (xy 131.120957 -218.94389) (xy 131.078941 -218.974416)
			(xy 131.032667 -218.997994) (xy 130.983274 -219.014042) (xy 130.931979 -219.022167) (xy 130.880045 -219.022167)
			(xy 130.82875 -219.014042) (xy 130.779357 -218.997994) (xy 130.733083 -218.974416) (xy 130.691067 -218.94389)
			(xy 130.654344 -218.907167) (xy 130.623818 -218.865151) (xy 130.60024 -218.818877) (xy 130.584192 -218.769484)
			(xy 130.576067 -218.718189) (xy 130.575558 -218.692222) (xy 129.356866 -218.692222) (xy 129.356357 -218.718189)
			(xy 129.348232 -218.769484) (xy 129.332184 -218.818877) (xy 129.308606 -218.865151) (xy 129.27808 -218.907167)
			(xy 129.241357 -218.94389) (xy 129.199341 -218.974416) (xy 129.153067 -218.997994) (xy 129.103674 -219.014042)
			(xy 129.052379 -219.022167) (xy 129.000445 -219.022167) (xy 128.94915 -219.014042) (xy 128.899757 -218.997994)
			(xy 128.853483 -218.974416) (xy 128.811467 -218.94389) (xy 128.774744 -218.907167) (xy 128.744218 -218.865151)
			(xy 128.72064 -218.818877) (xy 128.704592 -218.769484) (xy 128.696467 -218.718189) (xy 128.695958 -218.692222)
			(xy 127.477266 -218.692222) (xy 127.476788 -218.717551) (xy 127.469068 -218.767618) (xy 127.453798 -218.815919)
			(xy 127.431335 -218.861325) (xy 127.402205 -218.90277) (xy 127.367092 -218.939284) (xy 127.326817 -218.970011)
			(xy 127.3048 -218.982544) (xy 127.3048 -219.128848) (xy 127.305346 -219.143972) (xy 127.314195 -219.172895)
			(xy 127.331132 -219.197955) (xy 127.354669 -219.216952) (xy 127.38274 -219.228217) (xy 127.41288 -219.230761)
			(xy 127.442442 -219.22436) (xy 127.45593 -219.217494) (xy 127.480714 -219.20434) (xy 127.533617 -219.185658)
			(xy 127.588914 -219.17617) (xy 127.616966 -219.175584) (xy 127.642934 -219.176064) (xy 127.694231 -219.184184)
			(xy 127.743627 -219.200229) (xy 127.789904 -219.223804) (xy 127.831923 -219.254329) (xy 127.868649 -219.291051)
			(xy 127.899178 -219.333067) (xy 127.922758 -219.379342) (xy 127.938808 -219.428735) (xy 127.946933 -219.480032)
			(xy 127.946933 -219.531968) (xy 127.946927 -219.532005) (xy 128.226821 -219.532005) (xy 128.226821 -219.480071)
			(xy 128.234946 -219.428776) (xy 128.250994 -219.379383) (xy 128.274572 -219.333109) (xy 128.305098 -219.291093)
			(xy 128.341821 -219.25437) (xy 128.383837 -219.223844) (xy 128.430111 -219.200266) (xy 128.479504 -219.184218)
			(xy 128.530799 -219.176093) (xy 128.582733 -219.176093) (xy 128.634028 -219.184218) (xy 128.683421 -219.200266)
			(xy 128.729695 -219.223844) (xy 128.771711 -219.25437) (xy 128.808434 -219.291093) (xy 128.83896 -219.333109)
			(xy 128.862538 -219.379383) (xy 128.878586 -219.428776) (xy 128.886711 -219.480071) (xy 128.88722 -219.506038)
			(xy 128.886711 -219.532005) (xy 129.166621 -219.532005) (xy 129.166621 -219.480071) (xy 129.174746 -219.428776)
			(xy 129.190794 -219.379383) (xy 129.214372 -219.333109) (xy 129.244898 -219.291093) (xy 129.281621 -219.25437)
			(xy 129.323637 -219.223844) (xy 129.369911 -219.200266) (xy 129.419304 -219.184218) (xy 129.470599 -219.176093)
			(xy 129.522533 -219.176093) (xy 129.573828 -219.184218) (xy 129.623221 -219.200266) (xy 129.669495 -219.223844)
			(xy 129.711511 -219.25437) (xy 129.748234 -219.291093) (xy 129.77876 -219.333109) (xy 129.802338 -219.379383)
			(xy 129.818386 -219.428776) (xy 129.826511 -219.480071) (xy 129.82702 -219.506038) (xy 129.826511 -219.532005)
			(xy 130.106421 -219.532005) (xy 130.106421 -219.480071) (xy 130.114546 -219.428776) (xy 130.130594 -219.379383)
			(xy 130.154172 -219.333109) (xy 130.184698 -219.291093) (xy 130.221421 -219.25437) (xy 130.263437 -219.223844)
			(xy 130.309711 -219.200266) (xy 130.359104 -219.184218) (xy 130.410399 -219.176093) (xy 130.462333 -219.176093)
			(xy 130.513628 -219.184218) (xy 130.563021 -219.200266) (xy 130.609295 -219.223844) (xy 130.651311 -219.25437)
			(xy 130.688034 -219.291093) (xy 130.71856 -219.333109) (xy 130.742138 -219.379383) (xy 130.758186 -219.428776)
			(xy 130.766311 -219.480071) (xy 130.76682 -219.506038) (xy 130.766311 -219.532005) (xy 131.046221 -219.532005)
			(xy 131.046221 -219.480071) (xy 131.054346 -219.428776) (xy 131.070394 -219.379383) (xy 131.093972 -219.333109)
			(xy 131.124498 -219.291093) (xy 131.161221 -219.25437) (xy 131.203237 -219.223844) (xy 131.249511 -219.200266)
			(xy 131.298904 -219.184218) (xy 131.350199 -219.176093) (xy 131.402133 -219.176093) (xy 131.453428 -219.184218)
			(xy 131.502821 -219.200266) (xy 131.549095 -219.223844) (xy 131.591111 -219.25437) (xy 131.627834 -219.291093)
			(xy 131.65836 -219.333109) (xy 131.681938 -219.379383) (xy 131.697986 -219.428776) (xy 131.706111 -219.480071)
			(xy 131.70662 -219.506038) (xy 131.706111 -219.532005) (xy 131.986021 -219.532005) (xy 131.986021 -219.480071)
			(xy 131.994146 -219.428776) (xy 132.010194 -219.379383) (xy 132.033772 -219.333109) (xy 132.064298 -219.291093)
			(xy 132.101021 -219.25437) (xy 132.143037 -219.223844) (xy 132.189311 -219.200266) (xy 132.238704 -219.184218)
			(xy 132.289999 -219.176093) (xy 132.341933 -219.176093) (xy 132.393228 -219.184218) (xy 132.442621 -219.200266)
			(xy 132.488895 -219.223844) (xy 132.530911 -219.25437) (xy 132.567634 -219.291093) (xy 132.59816 -219.333109)
			(xy 132.621738 -219.379383) (xy 132.637786 -219.428776) (xy 132.645911 -219.480071) (xy 132.64642 -219.506038)
			(xy 132.645911 -219.532005) (xy 132.925821 -219.532005) (xy 132.925821 -219.480071) (xy 132.933946 -219.428776)
			(xy 132.949994 -219.379383) (xy 132.973572 -219.333109) (xy 133.004098 -219.291093) (xy 133.040821 -219.25437)
			(xy 133.082837 -219.223844) (xy 133.129111 -219.200266) (xy 133.178504 -219.184218) (xy 133.229799 -219.176093)
			(xy 133.281733 -219.176093) (xy 133.333028 -219.184218) (xy 133.382421 -219.200266) (xy 133.428695 -219.223844)
			(xy 133.470711 -219.25437) (xy 133.507434 -219.291093) (xy 133.53796 -219.333109) (xy 133.561538 -219.379383)
			(xy 133.577586 -219.428776) (xy 133.585711 -219.480071) (xy 133.58622 -219.506038) (xy 133.585711 -219.532005)
			(xy 133.577586 -219.5833) (xy 133.561538 -219.632693) (xy 133.53796 -219.678967) (xy 133.507434 -219.720983)
			(xy 133.470711 -219.757706) (xy 133.428695 -219.788232) (xy 133.382421 -219.81181) (xy 133.333028 -219.827858)
			(xy 133.281733 -219.835983) (xy 133.229799 -219.835983) (xy 133.178504 -219.827858) (xy 133.129111 -219.81181)
			(xy 133.082837 -219.788232) (xy 133.040821 -219.757706) (xy 133.004098 -219.720983) (xy 132.973572 -219.678967)
			(xy 132.949994 -219.632693) (xy 132.933946 -219.5833) (xy 132.925821 -219.532005) (xy 132.645911 -219.532005)
			(xy 132.637786 -219.5833) (xy 132.621738 -219.632693) (xy 132.59816 -219.678967) (xy 132.567634 -219.720983)
			(xy 132.530911 -219.757706) (xy 132.488895 -219.788232) (xy 132.442621 -219.81181) (xy 132.393228 -219.827858)
			(xy 132.341933 -219.835983) (xy 132.289999 -219.835983) (xy 132.238704 -219.827858) (xy 132.189311 -219.81181)
			(xy 132.143037 -219.788232) (xy 132.101021 -219.757706) (xy 132.064298 -219.720983) (xy 132.033772 -219.678967)
			(xy 132.010194 -219.632693) (xy 131.994146 -219.5833) (xy 131.986021 -219.532005) (xy 131.706111 -219.532005)
			(xy 131.697986 -219.5833) (xy 131.681938 -219.632693) (xy 131.65836 -219.678967) (xy 131.627834 -219.720983)
			(xy 131.591111 -219.757706) (xy 131.549095 -219.788232) (xy 131.502821 -219.81181) (xy 131.453428 -219.827858)
			(xy 131.402133 -219.835983) (xy 131.350199 -219.835983) (xy 131.298904 -219.827858) (xy 131.249511 -219.81181)
			(xy 131.203237 -219.788232) (xy 131.161221 -219.757706) (xy 131.124498 -219.720983) (xy 131.093972 -219.678967)
			(xy 131.070394 -219.632693) (xy 131.054346 -219.5833) (xy 131.046221 -219.532005) (xy 130.766311 -219.532005)
			(xy 130.758186 -219.5833) (xy 130.742138 -219.632693) (xy 130.71856 -219.678967) (xy 130.688034 -219.720983)
			(xy 130.651311 -219.757706) (xy 130.609295 -219.788232) (xy 130.563021 -219.81181) (xy 130.513628 -219.827858)
			(xy 130.462333 -219.835983) (xy 130.410399 -219.835983) (xy 130.359104 -219.827858) (xy 130.309711 -219.81181)
			(xy 130.263437 -219.788232) (xy 130.221421 -219.757706) (xy 130.184698 -219.720983) (xy 130.154172 -219.678967)
			(xy 130.130594 -219.632693) (xy 130.114546 -219.5833) (xy 130.106421 -219.532005) (xy 129.826511 -219.532005)
			(xy 129.818386 -219.5833) (xy 129.802338 -219.632693) (xy 129.77876 -219.678967) (xy 129.748234 -219.720983)
			(xy 129.711511 -219.757706) (xy 129.669495 -219.788232) (xy 129.623221 -219.81181) (xy 129.573828 -219.827858)
			(xy 129.522533 -219.835983) (xy 129.470599 -219.835983) (xy 129.419304 -219.827858) (xy 129.369911 -219.81181)
			(xy 129.323637 -219.788232) (xy 129.281621 -219.757706) (xy 129.244898 -219.720983) (xy 129.214372 -219.678967)
			(xy 129.190794 -219.632693) (xy 129.174746 -219.5833) (xy 129.166621 -219.532005) (xy 128.886711 -219.532005)
			(xy 128.878586 -219.5833) (xy 128.862538 -219.632693) (xy 128.83896 -219.678967) (xy 128.808434 -219.720983)
			(xy 128.771711 -219.757706) (xy 128.729695 -219.788232) (xy 128.683421 -219.81181) (xy 128.634028 -219.827858)
			(xy 128.582733 -219.835983) (xy 128.530799 -219.835983) (xy 128.479504 -219.827858) (xy 128.430111 -219.81181)
			(xy 128.383837 -219.788232) (xy 128.341821 -219.757706) (xy 128.305098 -219.720983) (xy 128.274572 -219.678967)
			(xy 128.250994 -219.632693) (xy 128.234946 -219.5833) (xy 128.226821 -219.532005) (xy 127.946927 -219.532005)
			(xy 127.938808 -219.583265) (xy 127.922758 -219.632658) (xy 127.899178 -219.678933) (xy 127.868649 -219.720949)
			(xy 127.831923 -219.757671) (xy 127.789904 -219.788196) (xy 127.743627 -219.811771) (xy 127.694231 -219.827816)
			(xy 127.642934 -219.835936) (xy 127.616966 -219.836492) (xy 127.58891 -219.835936) (xy 127.533603 -219.826464)
			(xy 127.480693 -219.807782) (xy 127.45593 -219.794582) (xy 127.442459 -219.787692) (xy 127.412897 -219.781325)
			(xy 127.382765 -219.783889) (xy 127.354704 -219.79516) (xy 127.33117 -219.814151) (xy 127.314226 -219.839198)
			(xy 127.305354 -219.868108) (xy 127.3048 -219.883228) (xy 127.3048 -220.029532) (xy 127.326851 -220.042033)
			(xy 127.367177 -220.072742) (xy 127.40234 -220.10925) (xy 127.431515 -220.1507) (xy 127.454019 -220.196119)
			(xy 127.469322 -220.244441) (xy 127.477066 -220.294534) (xy 127.477067 -220.319854) (xy 127.756158 -220.319854)
			(xy 127.756667 -220.293887) (xy 127.764792 -220.242592) (xy 127.78084 -220.193199) (xy 127.804418 -220.146925)
			(xy 127.834944 -220.104909) (xy 127.871667 -220.068186) (xy 127.913683 -220.03766) (xy 127.959957 -220.014082)
			(xy 128.00935 -219.998034) (xy 128.060645 -219.989909) (xy 128.112579 -219.989909) (xy 128.163874 -219.998034)
			(xy 128.213267 -220.014082) (xy 128.259541 -220.03766) (xy 128.301557 -220.068186) (xy 128.33828 -220.104909)
			(xy 128.368806 -220.146925) (xy 128.392384 -220.193199) (xy 128.408432 -220.242592) (xy 128.416557 -220.293887)
			(xy 128.417066 -220.319854) (xy 128.416569 -220.345821) (xy 128.696721 -220.345821) (xy 128.696721 -220.293887)
			(xy 128.704846 -220.242592) (xy 128.720894 -220.193199) (xy 128.744472 -220.146925) (xy 128.774998 -220.104909)
			(xy 128.811721 -220.068186) (xy 128.853737 -220.03766) (xy 128.900011 -220.014082) (xy 128.949404 -219.998034)
			(xy 129.000699 -219.989909) (xy 129.052633 -219.989909) (xy 129.103928 -219.998034) (xy 129.153321 -220.014082)
			(xy 129.199595 -220.03766) (xy 129.241611 -220.068186) (xy 129.278334 -220.104909) (xy 129.30886 -220.146925)
			(xy 129.332438 -220.193199) (xy 129.348486 -220.242592) (xy 129.356611 -220.293887) (xy 129.35712 -220.319854)
			(xy 129.635758 -220.319854) (xy 129.636267 -220.293887) (xy 129.644392 -220.242592) (xy 129.66044 -220.193199)
			(xy 129.684018 -220.146925) (xy 129.714544 -220.104909) (xy 129.751267 -220.068186) (xy 129.793283 -220.03766)
			(xy 129.839557 -220.014082) (xy 129.88895 -219.998034) (xy 129.940245 -219.989909) (xy 129.992179 -219.989909)
			(xy 130.043474 -219.998034) (xy 130.092867 -220.014082) (xy 130.139141 -220.03766) (xy 130.181157 -220.068186)
			(xy 130.21788 -220.104909) (xy 130.248406 -220.146925) (xy 130.271984 -220.193199) (xy 130.288032 -220.242592)
			(xy 130.296157 -220.293887) (xy 130.296666 -220.319854) (xy 130.296169 -220.345821) (xy 130.576321 -220.345821)
			(xy 130.576321 -220.293887) (xy 130.584446 -220.242592) (xy 130.600494 -220.193199) (xy 130.624072 -220.146925)
			(xy 130.654598 -220.104909) (xy 130.691321 -220.068186) (xy 130.733337 -220.03766) (xy 130.779611 -220.014082)
			(xy 130.829004 -219.998034) (xy 130.880299 -219.989909) (xy 130.932233 -219.989909) (xy 130.983528 -219.998034)
			(xy 131.032921 -220.014082) (xy 131.079195 -220.03766) (xy 131.121211 -220.068186) (xy 131.157934 -220.104909)
			(xy 131.18846 -220.146925) (xy 131.212038 -220.193199) (xy 131.228086 -220.242592) (xy 131.236211 -220.293887)
			(xy 131.23672 -220.319854) (xy 131.515358 -220.319854) (xy 131.515867 -220.293887) (xy 131.523992 -220.242592)
			(xy 131.54004 -220.193199) (xy 131.563618 -220.146925) (xy 131.594144 -220.104909) (xy 131.630867 -220.068186)
			(xy 131.672883 -220.03766) (xy 131.719157 -220.014082) (xy 131.76855 -219.998034) (xy 131.819845 -219.989909)
			(xy 131.871779 -219.989909) (xy 131.923074 -219.998034) (xy 131.972467 -220.014082) (xy 132.018741 -220.03766)
			(xy 132.060757 -220.068186) (xy 132.09748 -220.104909) (xy 132.128006 -220.146925) (xy 132.151584 -220.193199)
			(xy 132.167632 -220.242592) (xy 132.175757 -220.293887) (xy 132.176266 -220.319854) (xy 132.175769 -220.345821)
			(xy 132.455921 -220.345821) (xy 132.455921 -220.293887) (xy 132.464046 -220.242592) (xy 132.480094 -220.193199)
			(xy 132.503672 -220.146925) (xy 132.534198 -220.104909) (xy 132.570921 -220.068186) (xy 132.612937 -220.03766)
			(xy 132.659211 -220.014082) (xy 132.708604 -219.998034) (xy 132.759899 -219.989909) (xy 132.811833 -219.989909)
			(xy 132.863128 -219.998034) (xy 132.912521 -220.014082) (xy 132.958795 -220.03766) (xy 133.000811 -220.068186)
			(xy 133.037534 -220.104909) (xy 133.06806 -220.146925) (xy 133.091638 -220.193199) (xy 133.107686 -220.242592)
			(xy 133.115811 -220.293887) (xy 133.11632 -220.319854) (xy 133.115811 -220.345821) (xy 133.107686 -220.397116)
			(xy 133.091638 -220.446509) (xy 133.06806 -220.492783) (xy 133.037534 -220.534799) (xy 133.000811 -220.571522)
			(xy 132.958795 -220.602048) (xy 132.912521 -220.625626) (xy 132.863128 -220.641674) (xy 132.811833 -220.649799)
			(xy 132.759899 -220.649799) (xy 132.708604 -220.641674) (xy 132.659211 -220.625626) (xy 132.612937 -220.602048)
			(xy 132.570921 -220.571522) (xy 132.534198 -220.534799) (xy 132.503672 -220.492783) (xy 132.480094 -220.446509)
			(xy 132.464046 -220.397116) (xy 132.455921 -220.345821) (xy 132.175769 -220.345821) (xy 132.175732 -220.347764)
			(xy 132.166404 -220.402797) (xy 132.157724 -220.429328) (xy 132.14985 -220.451172) (xy 132.354066 -220.80474)
			(xy 132.376926 -220.809058) (xy 132.401844 -220.814243) (xy 132.449827 -220.831206) (xy 132.494645 -220.85532)
			(xy 132.535238 -220.886018) (xy 132.570647 -220.922574) (xy 132.600036 -220.964124) (xy 132.622711 -221.009687)
			(xy 132.638135 -221.058187) (xy 132.645946 -221.108477) (xy 132.64642 -221.133924) (xy 132.645911 -221.159891)
			(xy 132.637786 -221.211186) (xy 132.621738 -221.260579) (xy 132.59816 -221.306853) (xy 132.567634 -221.348869)
			(xy 132.530911 -221.385592) (xy 132.488895 -221.416118) (xy 132.442621 -221.439696) (xy 132.393228 -221.455744)
			(xy 132.341933 -221.463869) (xy 132.289999 -221.463869) (xy 132.238704 -221.455744) (xy 132.189311 -221.439696)
			(xy 132.143037 -221.416118) (xy 132.101021 -221.385592) (xy 132.064298 -221.348869) (xy 132.033772 -221.306853)
			(xy 132.010194 -221.260579) (xy 131.994146 -221.211186) (xy 131.986021 -221.159891) (xy 131.985512 -221.133924)
			(xy 131.98607 -221.105938) (xy 131.995516 -221.050771) (xy 132.004308 -221.024196) (xy 132.011928 -221.002098)
			(xy 131.80822 -220.649038) (xy 131.785106 -220.64472) (xy 131.76017 -220.63956) (xy 131.712147 -220.62263)
			(xy 131.667288 -220.598536) (xy 131.626655 -220.567848) (xy 131.591209 -220.531292) (xy 131.561789 -220.489732)
			(xy 131.539089 -220.444152) (xy 131.523649 -220.39563) (xy 131.515832 -220.345314) (xy 131.515358 -220.319854)
			(xy 131.23672 -220.319854) (xy 131.236211 -220.345821) (xy 131.228086 -220.397116) (xy 131.212038 -220.446509)
			(xy 131.18846 -220.492783) (xy 131.157934 -220.534799) (xy 131.121211 -220.571522) (xy 131.079195 -220.602048)
			(xy 131.032921 -220.625626) (xy 130.983528 -220.641674) (xy 130.932233 -220.649799) (xy 130.880299 -220.649799)
			(xy 130.829004 -220.641674) (xy 130.779611 -220.625626) (xy 130.733337 -220.602048) (xy 130.691321 -220.571522)
			(xy 130.654598 -220.534799) (xy 130.624072 -220.492783) (xy 130.600494 -220.446509) (xy 130.584446 -220.397116)
			(xy 130.576321 -220.345821) (xy 130.296169 -220.345821) (xy 130.296132 -220.347764) (xy 130.286804 -220.402797)
			(xy 130.278124 -220.429328) (xy 130.27025 -220.451172) (xy 130.474466 -220.80474) (xy 130.497326 -220.809058)
			(xy 130.522244 -220.814243) (xy 130.570227 -220.831206) (xy 130.615045 -220.85532) (xy 130.655638 -220.886018)
			(xy 130.691047 -220.922574) (xy 130.720436 -220.964124) (xy 130.743111 -221.009687) (xy 130.758535 -221.058187)
			(xy 130.766346 -221.108477) (xy 130.76682 -221.133924) (xy 130.766311 -221.159891) (xy 130.758186 -221.211186)
			(xy 130.742138 -221.260579) (xy 130.71856 -221.306853) (xy 130.688034 -221.348869) (xy 130.651311 -221.385592)
			(xy 130.609295 -221.416118) (xy 130.563021 -221.439696) (xy 130.513628 -221.455744) (xy 130.462333 -221.463869)
			(xy 130.410399 -221.463869) (xy 130.359104 -221.455744) (xy 130.309711 -221.439696) (xy 130.263437 -221.416118)
			(xy 130.221421 -221.385592) (xy 130.184698 -221.348869) (xy 130.154172 -221.306853) (xy 130.130594 -221.260579)
			(xy 130.114546 -221.211186) (xy 130.106421 -221.159891) (xy 130.105912 -221.133924) (xy 130.10647 -221.105938)
			(xy 130.115916 -221.050771) (xy 130.124708 -221.024196) (xy 130.132328 -221.002098) (xy 129.92862 -220.649038)
			(xy 129.905506 -220.64472) (xy 129.88057 -220.63956) (xy 129.832547 -220.62263) (xy 129.787688 -220.598536)
			(xy 129.747055 -220.567848) (xy 129.711609 -220.531292) (xy 129.682189 -220.489732) (xy 129.659489 -220.444152)
			(xy 129.644049 -220.39563) (xy 129.636232 -220.345314) (xy 129.635758 -220.319854) (xy 129.35712 -220.319854)
			(xy 129.356611 -220.345821) (xy 129.348486 -220.397116) (xy 129.332438 -220.446509) (xy 129.30886 -220.492783)
			(xy 129.278334 -220.534799) (xy 129.241611 -220.571522) (xy 129.199595 -220.602048) (xy 129.153321 -220.625626)
			(xy 129.103928 -220.641674) (xy 129.052633 -220.649799) (xy 129.000699 -220.649799) (xy 128.949404 -220.641674)
			(xy 128.900011 -220.625626) (xy 128.853737 -220.602048) (xy 128.811721 -220.571522) (xy 128.774998 -220.534799)
			(xy 128.744472 -220.492783) (xy 128.720894 -220.446509) (xy 128.704846 -220.397116) (xy 128.696721 -220.345821)
			(xy 128.416569 -220.345821) (xy 128.416532 -220.347764) (xy 128.407204 -220.402797) (xy 128.398524 -220.429328)
			(xy 128.39065 -220.451172) (xy 128.594866 -220.80474) (xy 128.617726 -220.809058) (xy 128.642644 -220.814243)
			(xy 128.690627 -220.831206) (xy 128.735445 -220.85532) (xy 128.776038 -220.886018) (xy 128.811447 -220.922574)
			(xy 128.840836 -220.964124) (xy 128.863511 -221.009687) (xy 128.878935 -221.058187) (xy 128.886746 -221.108477)
			(xy 128.88722 -221.133924) (xy 128.886711 -221.159891) (xy 128.878586 -221.211186) (xy 128.862538 -221.260579)
			(xy 128.83896 -221.306853) (xy 128.808434 -221.348869) (xy 128.771711 -221.385592) (xy 128.729695 -221.416118)
			(xy 128.683421 -221.439696) (xy 128.634028 -221.455744) (xy 128.582733 -221.463869) (xy 128.530799 -221.463869)
			(xy 128.479504 -221.455744) (xy 128.430111 -221.439696) (xy 128.383837 -221.416118) (xy 128.341821 -221.385592)
			(xy 128.305098 -221.348869) (xy 128.274572 -221.306853) (xy 128.250994 -221.260579) (xy 128.234946 -221.211186)
			(xy 128.226821 -221.159891) (xy 128.226312 -221.133924) (xy 128.22687 -221.105938) (xy 128.236316 -221.050771)
			(xy 128.245108 -221.024196) (xy 128.252728 -221.002098) (xy 128.04902 -220.649038) (xy 128.025906 -220.64472)
			(xy 128.00097 -220.63956) (xy 127.952947 -220.62263) (xy 127.908088 -220.598536) (xy 127.867455 -220.567848)
			(xy 127.832009 -220.531292) (xy 127.802589 -220.489732) (xy 127.779889 -220.444152) (xy 127.764449 -220.39563)
			(xy 127.756632 -220.345314) (xy 127.756158 -220.319854) (xy 127.477067 -220.319854) (xy 127.477069 -220.345222)
			(xy 127.469332 -220.395316) (xy 127.454035 -220.443641) (xy 127.431538 -220.489062) (xy 127.402368 -220.530516)
			(xy 127.36721 -220.567028) (xy 127.326888 -220.597743) (xy 127.3048 -220.610176) (xy 127.3048 -220.756734)
			(xy 127.305344 -220.771859) (xy 127.314191 -220.800787) (xy 127.331127 -220.825851) (xy 127.354666 -220.84485)
			(xy 127.382739 -220.856117) (xy 127.412882 -220.858661) (xy 127.442447 -220.852258) (xy 127.45593 -220.84538)
			(xy 127.480713 -220.832223) (xy 127.533616 -220.813536) (xy 127.588913 -220.804045) (xy 127.616966 -220.80347)
			(xy 127.642936 -220.80395) (xy 127.694238 -220.812071) (xy 127.743638 -220.828118) (xy 127.789918 -220.851697)
			(xy 127.83194 -220.882225) (xy 127.868668 -220.918952) (xy 127.899198 -220.960973) (xy 127.922778 -221.007253)
			(xy 127.938826 -221.056652) (xy 127.946949 -221.107954) (xy 127.94742 -221.133924) (xy 127.946947 -221.159396)
			(xy 127.939124 -221.209737) (xy 127.923668 -221.25828) (xy 127.900943 -221.303875) (xy 127.87149 -221.345443)
			(xy 127.836005 -221.381997) (xy 127.795331 -221.412671) (xy 127.75043 -221.436739) (xy 127.702368 -221.453631)
			(xy 127.677418 -221.45879) (xy 127.654304 -221.463108) (xy 127.45085 -221.815914) (xy 127.45847 -221.838012)
			(xy 127.467261 -221.864587) (xy 127.476705 -221.919755) (xy 127.477266 -221.94774) (xy 128.695958 -221.94774)
			(xy 128.696381 -221.922287) (xy 128.704168 -221.87198) (xy 128.71958 -221.823463) (xy 128.742251 -221.777884)
			(xy 128.771645 -221.736322) (xy 128.807067 -221.699761) (xy 128.847678 -221.669066) (xy 128.892516 -221.644963)
			(xy 128.940521 -221.628023) (xy 128.965452 -221.622874) (xy 128.988312 -221.618556) (xy 129.192274 -221.264988)
			(xy 129.184654 -221.243144) (xy 129.176021 -221.216666) (xy 129.166693 -221.161767) (xy 129.166112 -221.133924)
			(xy 129.166621 -221.107957) (xy 129.174746 -221.056662) (xy 129.190794 -221.007269) (xy 129.214372 -220.960995)
			(xy 129.244898 -220.918979) (xy 129.281621 -220.882256) (xy 129.323637 -220.85173) (xy 129.369911 -220.828152)
			(xy 129.419304 -220.812104) (xy 129.470599 -220.803979) (xy 129.522533 -220.803979) (xy 129.573828 -220.812104)
			(xy 129.623221 -220.828152) (xy 129.669495 -220.85173) (xy 129.711511 -220.882256) (xy 129.748234 -220.918979)
			(xy 129.77876 -220.960995) (xy 129.802338 -221.007269) (xy 129.818386 -221.056662) (xy 129.826511 -221.107957)
			(xy 129.82702 -221.133924) (xy 129.826587 -221.159399) (xy 129.818763 -221.209746) (xy 129.803305 -221.258295)
			(xy 129.780578 -221.303896) (xy 129.751121 -221.345468) (xy 129.715632 -221.382027) (xy 129.674953 -221.412705)
			(xy 129.630046 -221.436776) (xy 129.581978 -221.453669) (xy 129.557018 -221.45879) (xy 129.533904 -221.463108)
			(xy 129.33045 -221.815914) (xy 129.33807 -221.838012) (xy 129.34681 -221.8646) (xy 129.356256 -221.919759)
			(xy 129.356866 -221.94774) (xy 130.575558 -221.94774) (xy 130.575981 -221.922287) (xy 130.583768 -221.87198)
			(xy 130.59918 -221.823463) (xy 130.621851 -221.777884) (xy 130.651245 -221.736322) (xy 130.686667 -221.699761)
			(xy 130.727278 -221.669066) (xy 130.772116 -221.644963) (xy 130.820121 -221.628023) (xy 130.845052 -221.622874)
			(xy 130.867912 -221.618556) (xy 131.071874 -221.264988) (xy 131.064254 -221.243144) (xy 131.055621 -221.216666)
			(xy 131.046293 -221.161767) (xy 131.045712 -221.133924) (xy 131.046221 -221.107957) (xy 131.054346 -221.056662)
			(xy 131.070394 -221.007269) (xy 131.093972 -220.960995) (xy 131.124498 -220.918979) (xy 131.161221 -220.882256)
			(xy 131.203237 -220.85173) (xy 131.249511 -220.828152) (xy 131.298904 -220.812104) (xy 131.350199 -220.803979)
			(xy 131.402133 -220.803979) (xy 131.453428 -220.812104) (xy 131.502821 -220.828152) (xy 131.549095 -220.85173)
			(xy 131.591111 -220.882256) (xy 131.627834 -220.918979) (xy 131.65836 -220.960995) (xy 131.681938 -221.007269)
			(xy 131.697986 -221.056662) (xy 131.706111 -221.107957) (xy 131.70662 -221.133924) (xy 131.706187 -221.159399)
			(xy 131.698363 -221.209746) (xy 131.682905 -221.258295) (xy 131.660178 -221.303896) (xy 131.630721 -221.345468)
			(xy 131.595232 -221.382027) (xy 131.554553 -221.412705) (xy 131.509646 -221.436776) (xy 131.461578 -221.453669)
			(xy 131.436618 -221.45879) (xy 131.413504 -221.463108) (xy 131.21005 -221.815914) (xy 131.21767 -221.838012)
			(xy 131.22641 -221.8646) (xy 131.235856 -221.919759) (xy 131.236466 -221.94774) (xy 132.455158 -221.94774)
			(xy 132.455581 -221.922287) (xy 132.463368 -221.87198) (xy 132.47878 -221.823463) (xy 132.501451 -221.777884)
			(xy 132.530845 -221.736322) (xy 132.566267 -221.699761) (xy 132.606878 -221.669066) (xy 132.651716 -221.644963)
			(xy 132.699721 -221.628023) (xy 132.724652 -221.622874) (xy 132.747766 -221.618556) (xy 132.951474 -221.264988)
			(xy 132.943854 -221.24289) (xy 132.935224 -221.216478) (xy 132.925905 -221.161704) (xy 132.925312 -221.133924)
			(xy 132.925821 -221.107957) (xy 132.933946 -221.056662) (xy 132.949994 -221.007269) (xy 132.973572 -220.960995)
			(xy 133.004098 -220.918979) (xy 133.040821 -220.882256) (xy 133.082837 -220.85173) (xy 133.129111 -220.828152)
			(xy 133.178504 -220.812104) (xy 133.229799 -220.803979) (xy 133.281733 -220.803979) (xy 133.333028 -220.812104)
			(xy 133.382421 -220.828152) (xy 133.428695 -220.85173) (xy 133.470711 -220.882256) (xy 133.507434 -220.918979)
			(xy 133.53796 -220.960995) (xy 133.561538 -221.007269) (xy 133.577586 -221.056662) (xy 133.585711 -221.107957)
			(xy 133.58622 -221.133924) (xy 133.585787 -221.159399) (xy 133.577963 -221.209746) (xy 133.562505 -221.258295)
			(xy 133.539778 -221.303896) (xy 133.510321 -221.345468) (xy 133.474832 -221.382027) (xy 133.434153 -221.412705)
			(xy 133.389246 -221.436776) (xy 133.341178 -221.453669) (xy 133.316218 -221.45879) (xy 133.293104 -221.463108)
			(xy 133.08965 -221.815914) (xy 133.09727 -221.838012) (xy 133.10601 -221.8646) (xy 133.115456 -221.919759)
			(xy 133.116066 -221.94774) (xy 133.115557 -221.973707) (xy 133.107432 -222.025002) (xy 133.091384 -222.074395)
			(xy 133.067806 -222.120669) (xy 133.03728 -222.162685) (xy 133.000557 -222.199408) (xy 132.958541 -222.229934)
			(xy 132.912267 -222.253512) (xy 132.862874 -222.26956) (xy 132.811579 -222.277685) (xy 132.759645 -222.277685)
			(xy 132.70835 -222.26956) (xy 132.658957 -222.253512) (xy 132.612683 -222.229934) (xy 132.570667 -222.199408)
			(xy 132.533944 -222.162685) (xy 132.503418 -222.120669) (xy 132.47984 -222.074395) (xy 132.463792 -222.025002)
			(xy 132.455667 -221.973707) (xy 132.455158 -221.94774) (xy 131.236466 -221.94774) (xy 131.235957 -221.973707)
			(xy 131.227832 -222.025002) (xy 131.211784 -222.074395) (xy 131.188206 -222.120669) (xy 131.15768 -222.162685)
			(xy 131.120957 -222.199408) (xy 131.078941 -222.229934) (xy 131.032667 -222.253512) (xy 130.983274 -222.26956)
			(xy 130.931979 -222.277685) (xy 130.880045 -222.277685) (xy 130.82875 -222.26956) (xy 130.779357 -222.253512)
			(xy 130.733083 -222.229934) (xy 130.691067 -222.199408) (xy 130.654344 -222.162685) (xy 130.623818 -222.120669)
			(xy 130.60024 -222.074395) (xy 130.584192 -222.025002) (xy 130.576067 -221.973707) (xy 130.575558 -221.94774)
			(xy 129.356866 -221.94774) (xy 129.356357 -221.973707) (xy 129.348232 -222.025002) (xy 129.332184 -222.074395)
			(xy 129.308606 -222.120669) (xy 129.27808 -222.162685) (xy 129.241357 -222.199408) (xy 129.199341 -222.229934)
			(xy 129.153067 -222.253512) (xy 129.103674 -222.26956) (xy 129.052379 -222.277685) (xy 129.000445 -222.277685)
			(xy 128.94915 -222.26956) (xy 128.899757 -222.253512) (xy 128.853483 -222.229934) (xy 128.811467 -222.199408)
			(xy 128.774744 -222.162685) (xy 128.744218 -222.120669) (xy 128.72064 -222.074395) (xy 128.704592 -222.025002)
			(xy 128.696467 -221.973707) (xy 128.695958 -221.94774) (xy 127.477266 -221.94774) (xy 127.476808 -221.972099)
			(xy 127.469612 -222.020283) (xy 127.455426 -222.066891) (xy 127.434556 -222.110913) (xy 127.407455 -222.151399)
			(xy 127.391414 -222.169736) (xy 127.358902 -222.20555) (xy 127.585216 -222.431864) (xy 127.60706 -222.431356)
			(xy 127.616966 -222.431102) (xy 127.641009 -222.431532) (xy 127.688589 -222.438496) (xy 127.734657 -222.452281)
			(xy 127.778241 -222.472597) (xy 127.818421 -222.499015) (xy 127.836676 -222.514668)
		)
		(stroke
			(width 0)
			(type solid)
		)
		(fill yes)
		(layer "In11.Cu")
		(net "PVCCFA_EHV_FIVRA_CPU1")
	)
	(gr_poly
		(pts
			(xy 108.859828 -236.728) (xy 108.873719 -236.727524) (xy 108.90047 -236.720026) (xy 108.924208 -236.705592)
			(xy 108.943175 -236.685293) (xy 108.955967 -236.660631) (xy 108.961635 -236.633433) (xy 108.961174 -236.619542)
			(xy 108.960412 -236.597698) (xy 108.960921 -236.57173) (xy 108.969046 -236.520433) (xy 108.985094 -236.471039)
			(xy 109.008671 -236.424763) (xy 109.039197 -236.382744) (xy 109.07592 -236.346018) (xy 109.117935 -236.315488)
			(xy 109.164209 -236.291906) (xy 109.213602 -236.275853) (xy 109.264898 -236.267724) (xy 109.290866 -236.267244)
			(xy 109.317442 -236.267772) (xy 109.36991 -236.276275) (xy 109.42034 -236.293066) (xy 109.467433 -236.317713)
			(xy 109.509973 -236.349579) (xy 109.546864 -236.387845) (xy 109.577154 -236.431521) (xy 109.600063 -236.479483)
			(xy 109.614999 -236.530494) (xy 109.61878 -236.556804) (xy 109.62102 -236.57083) (xy 109.632186 -236.596933)
			(xy 109.650106 -236.618954) (xy 109.673396 -236.635192) (xy 109.700256 -236.644391) (xy 109.72861 -236.645842)
			(xy 109.756268 -236.639431) (xy 109.781093 -236.625655) (xy 109.7915 -236.615986) (xy 109.872526 -236.53496)
			(xy 109.872526 -236.215936) (xy 109.872097 -236.202427) (xy 109.864994 -236.176359) (xy 109.851302 -236.153066)
			(xy 109.83198 -236.134181) (xy 109.808381 -236.121025) (xy 109.782157 -236.114519) (xy 109.76864 -236.114336)
			(xy 109.76102 -236.114336) (xy 109.735051 -236.113855) (xy 109.683752 -236.105733) (xy 109.634356 -236.089685)
			(xy 109.588078 -236.066108) (xy 109.546058 -236.035581) (xy 109.509332 -235.998857) (xy 109.478802 -235.956839)
			(xy 109.455222 -235.910563) (xy 109.439172 -235.861167) (xy 109.431047 -235.809869) (xy 109.431047 -235.757931)
			(xy 109.439172 -235.706633) (xy 109.455222 -235.657237) (xy 109.478802 -235.610961) (xy 109.509332 -235.568943)
			(xy 109.546058 -235.532219) (xy 109.588078 -235.501692) (xy 109.634356 -235.478115) (xy 109.683752 -235.462067)
			(xy 109.735051 -235.453945) (xy 109.76102 -235.453428) (xy 109.76864 -235.453428) (xy 109.782157 -235.453308)
			(xy 109.808383 -235.446796) (xy 109.83198 -235.433628) (xy 109.851293 -235.414727) (xy 109.864966 -235.391419)
			(xy 109.872042 -235.36534) (xy 109.872526 -235.351828) (xy 109.872526 -234.58805) (xy 109.872075 -234.574557)
			(xy 109.86494 -234.548529) (xy 109.851235 -234.52528) (xy 109.831917 -234.506433) (xy 109.808336 -234.493307)
			(xy 109.78214 -234.486817) (xy 109.76864 -234.486704) (xy 109.760766 -234.486704) (xy 109.734797 -234.486192)
			(xy 109.683498 -234.478062) (xy 109.634102 -234.462008) (xy 109.587826 -234.438425) (xy 109.545809 -234.407894)
			(xy 109.509084 -234.371165) (xy 109.478557 -234.329145) (xy 109.454979 -234.282866) (xy 109.43893 -234.233469)
			(xy 109.430805 -234.182169) (xy 109.430805 -234.130231) (xy 109.43893 -234.078931) (xy 109.454979 -234.029534)
			(xy 109.478557 -233.983255) (xy 109.509084 -233.941235) (xy 109.545809 -233.904506) (xy 109.587826 -233.873975)
			(xy 109.634102 -233.850392) (xy 109.683498 -233.834338) (xy 109.734797 -233.826208) (xy 109.760766 -233.825796)
			(xy 109.76864 -233.825796) (xy 109.782139 -233.825678) (xy 109.808334 -233.819188) (xy 109.831914 -233.806062)
			(xy 109.85123 -233.787217) (xy 109.864935 -233.763969) (xy 109.87207 -233.737942) (xy 109.872526 -233.72445)
			(xy 109.872526 -232.960164) (xy 109.872076 -232.94667) (xy 109.864944 -232.920639) (xy 109.85124 -232.897386)
			(xy 109.831921 -232.878537) (xy 109.808339 -232.865408) (xy 109.782141 -232.858917) (xy 109.76864 -232.858818)
			(xy 109.760766 -232.858818) (xy 109.734803 -232.858306) (xy 109.683518 -232.850179) (xy 109.634135 -232.834129)
			(xy 109.587871 -232.810552) (xy 109.545865 -232.780028) (xy 109.50915 -232.74331) (xy 109.47863 -232.7013)
			(xy 109.455058 -232.655033) (xy 109.439013 -232.605649) (xy 109.430891 -232.554363) (xy 109.430891 -232.502437)
			(xy 109.439013 -232.451151) (xy 109.455058 -232.401767) (xy 109.47863 -232.3555) (xy 109.50915 -232.31349)
			(xy 109.545865 -232.276772) (xy 109.587871 -232.246248) (xy 109.634135 -232.222671) (xy 109.683518 -232.206621)
			(xy 109.734803 -232.198494) (xy 109.760766 -232.19791) (xy 109.76864 -232.19791) (xy 109.782135 -232.197792)
			(xy 109.808321 -232.191301) (xy 109.83189 -232.178173) (xy 109.851193 -232.159325) (xy 109.864881 -232.136076)
			(xy 109.871995 -232.110052) (xy 109.872526 -232.096564) (xy 109.872526 -231.332278) (xy 109.872063 -231.31877)
			(xy 109.864894 -231.292721) (xy 109.851143 -231.269463) (xy 109.831774 -231.250627) (xy 109.808143 -231.23753)
			(xy 109.781903 -231.231091) (xy 109.768386 -231.230932) (xy 109.760512 -231.230932) (xy 109.734544 -231.23045)
			(xy 109.683247 -231.222327) (xy 109.633852 -231.206279) (xy 109.587576 -231.182702) (xy 109.545558 -231.152175)
			(xy 109.508832 -231.115452) (xy 109.478304 -231.073435) (xy 109.454725 -231.027159) (xy 109.438676 -230.977765)
			(xy 109.430551 -230.926468) (xy 109.430551 -230.874532) (xy 109.438676 -230.823235) (xy 109.454725 -230.773841)
			(xy 109.478304 -230.727565) (xy 109.508832 -230.685548) (xy 109.545558 -230.648825) (xy 109.587576 -230.618298)
			(xy 109.633852 -230.594721) (xy 109.683247 -230.578673) (xy 109.734544 -230.57055) (xy 109.760512 -230.570024)
			(xy 109.768386 -230.570024) (xy 109.781904 -230.569937) (xy 109.808148 -230.563491) (xy 109.831778 -230.550381)
			(xy 109.851139 -230.531527) (xy 109.86487 -230.508252) (xy 109.87201 -230.482189) (xy 109.872526 -230.468678)
			(xy 109.872526 -229.704646) (xy 109.872074 -229.691153) (xy 109.864939 -229.665126) (xy 109.851233 -229.641878)
			(xy 109.831916 -229.623032) (xy 109.808335 -229.609906) (xy 109.78214 -229.603417) (xy 109.76864 -229.6033)
			(xy 109.760766 -229.6033) (xy 109.734797 -229.602788) (xy 109.683499 -229.594658) (xy 109.634104 -229.578605)
			(xy 109.587828 -229.555022) (xy 109.545811 -229.524491) (xy 109.509087 -229.487763) (xy 109.47856 -229.445743)
			(xy 109.454982 -229.399465) (xy 109.438934 -229.350068) (xy 109.430809 -229.298769) (xy 109.430809 -229.246831)
			(xy 109.438934 -229.195532) (xy 109.454982 -229.146135) (xy 109.47856 -229.099857) (xy 109.509087 -229.057837)
			(xy 109.545811 -229.021109) (xy 109.587828 -228.990578) (xy 109.634104 -228.966995) (xy 109.683499 -228.950942)
			(xy 109.734797 -228.942812) (xy 109.760766 -228.942392) (xy 109.76864 -228.942392) (xy 109.782139 -228.942274)
			(xy 109.808334 -228.935784) (xy 109.831913 -228.922658) (xy 109.851229 -228.903813) (xy 109.864932 -228.880565)
			(xy 109.872066 -228.854538) (xy 109.872526 -228.841046) (xy 109.872526 -228.51618) (xy 109.542326 -228.18598)
			(xy 108.747306 -228.18598) (xy 108.732912 -228.186476) (xy 108.705266 -228.194507) (xy 108.680959 -228.209934)
			(xy 108.661923 -228.23153) (xy 108.649668 -228.257581) (xy 108.64517 -228.286016) (xy 108.648784 -228.314577)
			(xy 108.654088 -228.327966) (xy 108.662676 -228.348738) (xy 108.674782 -228.392025) (xy 108.680896 -228.436556)
			(xy 108.681266 -228.45903) (xy 108.680757 -228.484997) (xy 108.672632 -228.536292) (xy 108.656584 -228.585685)
			(xy 108.633006 -228.631959) (xy 108.60248 -228.673975) (xy 108.565757 -228.710698) (xy 108.523741 -228.741224)
			(xy 108.477467 -228.764802) (xy 108.428074 -228.78085) (xy 108.376779 -228.788975) (xy 108.324845 -228.788975)
			(xy 108.27355 -228.78085) (xy 108.224157 -228.764802) (xy 108.177883 -228.741224) (xy 108.135867 -228.710698)
			(xy 108.099144 -228.673975) (xy 108.068618 -228.631959) (xy 108.04504 -228.585685) (xy 108.028992 -228.536292)
			(xy 108.020867 -228.484997) (xy 108.020358 -228.45903) (xy 108.020758 -228.436559) (xy 108.026885 -228.392034)
			(xy 108.038976 -228.348747) (xy 108.047536 -228.327966) (xy 108.052797 -228.314564) (xy 108.056409 -228.286014)
			(xy 108.051912 -228.257589) (xy 108.039664 -228.231548) (xy 108.020636 -228.209958) (xy 107.996341 -228.194534)
			(xy 107.968707 -228.1865) (xy 107.954318 -228.18598) (xy 106.867706 -228.18598) (xy 106.853312 -228.186476)
			(xy 106.825666 -228.194507) (xy 106.801359 -228.209934) (xy 106.782323 -228.23153) (xy 106.770068 -228.257581)
			(xy 106.76557 -228.286016) (xy 106.769184 -228.314577) (xy 106.774488 -228.327966) (xy 106.783076 -228.348738)
			(xy 106.795182 -228.392025) (xy 106.801296 -228.436556) (xy 106.801666 -228.45903) (xy 106.801157 -228.484997)
			(xy 106.793032 -228.536292) (xy 106.776984 -228.585685) (xy 106.753406 -228.631959) (xy 106.72288 -228.673975)
			(xy 106.686157 -228.710698) (xy 106.644141 -228.741224) (xy 106.597867 -228.764802) (xy 106.548474 -228.78085)
			(xy 106.497179 -228.788975) (xy 106.445245 -228.788975) (xy 106.39395 -228.78085) (xy 106.344557 -228.764802)
			(xy 106.298283 -228.741224) (xy 106.256267 -228.710698) (xy 106.219544 -228.673975) (xy 106.189018 -228.631959)
			(xy 106.16544 -228.585685) (xy 106.149392 -228.536292) (xy 106.141267 -228.484997) (xy 106.140758 -228.45903)
			(xy 106.141158 -228.436559) (xy 106.147285 -228.392034) (xy 106.159376 -228.348747) (xy 106.167936 -228.327966)
			(xy 106.173197 -228.314564) (xy 106.176809 -228.286014) (xy 106.172312 -228.257589) (xy 106.160064 -228.231548)
			(xy 106.141036 -228.209958) (xy 106.116741 -228.194534) (xy 106.089107 -228.1865) (xy 106.074718 -228.18598)
			(xy 104.988106 -228.18598) (xy 104.973712 -228.186476) (xy 104.946066 -228.194507) (xy 104.921759 -228.209934)
			(xy 104.902723 -228.23153) (xy 104.890468 -228.257581) (xy 104.88597 -228.286016) (xy 104.889584 -228.314577)
			(xy 104.894888 -228.327966) (xy 104.903476 -228.348738) (xy 104.915582 -228.392025) (xy 104.921696 -228.436556)
			(xy 104.922066 -228.45903) (xy 104.921557 -228.484997) (xy 104.913432 -228.536292) (xy 104.897384 -228.585685)
			(xy 104.873806 -228.631959) (xy 104.84328 -228.673975) (xy 104.806557 -228.710698) (xy 104.764541 -228.741224)
			(xy 104.718267 -228.764802) (xy 104.668874 -228.78085) (xy 104.617579 -228.788975) (xy 104.565645 -228.788975)
			(xy 104.51435 -228.78085) (xy 104.464957 -228.764802) (xy 104.418683 -228.741224) (xy 104.376667 -228.710698)
			(xy 104.339944 -228.673975) (xy 104.309418 -228.631959) (xy 104.28584 -228.585685) (xy 104.269792 -228.536292)
			(xy 104.261667 -228.484997) (xy 104.261158 -228.45903) (xy 104.261558 -228.436559) (xy 104.267685 -228.392034)
			(xy 104.279776 -228.348747) (xy 104.288336 -228.327966) (xy 104.293597 -228.314564) (xy 104.297209 -228.286014)
			(xy 104.292712 -228.257589) (xy 104.280464 -228.231548) (xy 104.261436 -228.209958) (xy 104.237141 -228.194534)
			(xy 104.209507 -228.1865) (xy 104.195118 -228.18598) (xy 103.108506 -228.18598) (xy 103.094112 -228.186476)
			(xy 103.066466 -228.194507) (xy 103.042159 -228.209934) (xy 103.023123 -228.23153) (xy 103.010868 -228.257581)
			(xy 103.00637 -228.286016) (xy 103.009984 -228.314577) (xy 103.015288 -228.327966) (xy 103.023876 -228.348738)
			(xy 103.035982 -228.392025) (xy 103.042096 -228.436556) (xy 103.042466 -228.45903) (xy 103.042001 -228.48398)
			(xy 103.034484 -228.53331) (xy 103.01964 -228.580951) (xy 102.997806 -228.62582) (xy 102.969479 -228.666899)
			(xy 102.9353 -228.703256) (xy 102.896046 -228.734064) (xy 102.852609 -228.758624) (xy 102.805975 -228.776379)
			(xy 102.757203 -228.786925) (xy 102.732332 -228.788976) (xy 102.722771 -228.789979) (xy 102.705375 -228.798126)
			(xy 102.692184 -228.81209) (xy 102.685037 -228.82992) (xy 102.68458 -228.839522) (xy 102.68458 -229.298813)
			(xy 102.852221 -229.298813) (xy 102.852221 -229.246879) (xy 102.860346 -229.195584) (xy 102.876394 -229.146191)
			(xy 102.899972 -229.099917) (xy 102.930498 -229.057901) (xy 102.967221 -229.021178) (xy 103.009237 -228.990652)
			(xy 103.055511 -228.967074) (xy 103.104904 -228.951026) (xy 103.156199 -228.942901) (xy 103.208133 -228.942901)
			(xy 103.259428 -228.951026) (xy 103.308821 -228.967074) (xy 103.355095 -228.990652) (xy 103.397111 -229.021178)
			(xy 103.433834 -229.057901) (xy 103.46436 -229.099917) (xy 103.487938 -229.146191) (xy 103.503986 -229.195584)
			(xy 103.512111 -229.246879) (xy 103.51262 -229.272846) (xy 103.512111 -229.298813) (xy 103.792021 -229.298813)
			(xy 103.792021 -229.246879) (xy 103.800146 -229.195584) (xy 103.816194 -229.146191) (xy 103.839772 -229.099917)
			(xy 103.870298 -229.057901) (xy 103.907021 -229.021178) (xy 103.949037 -228.990652) (xy 103.995311 -228.967074)
			(xy 104.044704 -228.951026) (xy 104.095999 -228.942901) (xy 104.147933 -228.942901) (xy 104.199228 -228.951026)
			(xy 104.248621 -228.967074) (xy 104.294895 -228.990652) (xy 104.336911 -229.021178) (xy 104.373634 -229.057901)
			(xy 104.40416 -229.099917) (xy 104.427738 -229.146191) (xy 104.443786 -229.195584) (xy 104.451911 -229.246879)
			(xy 104.45242 -229.272846) (xy 104.451911 -229.298813) (xy 104.731821 -229.298813) (xy 104.731821 -229.246879)
			(xy 104.739946 -229.195584) (xy 104.755994 -229.146191) (xy 104.779572 -229.099917) (xy 104.810098 -229.057901)
			(xy 104.846821 -229.021178) (xy 104.888837 -228.990652) (xy 104.935111 -228.967074) (xy 104.984504 -228.951026)
			(xy 105.035799 -228.942901) (xy 105.087733 -228.942901) (xy 105.139028 -228.951026) (xy 105.188421 -228.967074)
			(xy 105.234695 -228.990652) (xy 105.276711 -229.021178) (xy 105.313434 -229.057901) (xy 105.34396 -229.099917)
			(xy 105.367538 -229.146191) (xy 105.383586 -229.195584) (xy 105.391711 -229.246879) (xy 105.39222 -229.272846)
			(xy 105.391711 -229.298813) (xy 105.671621 -229.298813) (xy 105.671621 -229.246879) (xy 105.679746 -229.195584)
			(xy 105.695794 -229.146191) (xy 105.719372 -229.099917) (xy 105.749898 -229.057901) (xy 105.786621 -229.021178)
			(xy 105.828637 -228.990652) (xy 105.874911 -228.967074) (xy 105.924304 -228.951026) (xy 105.975599 -228.942901)
			(xy 106.027533 -228.942901) (xy 106.078828 -228.951026) (xy 106.128221 -228.967074) (xy 106.174495 -228.990652)
			(xy 106.216511 -229.021178) (xy 106.253234 -229.057901) (xy 106.28376 -229.099917) (xy 106.307338 -229.146191)
			(xy 106.323386 -229.195584) (xy 106.331511 -229.246879) (xy 106.33202 -229.272846) (xy 106.331511 -229.298813)
			(xy 106.611421 -229.298813) (xy 106.611421 -229.246879) (xy 106.619546 -229.195584) (xy 106.635594 -229.146191)
			(xy 106.659172 -229.099917) (xy 106.689698 -229.057901) (xy 106.726421 -229.021178) (xy 106.768437 -228.990652)
			(xy 106.814711 -228.967074) (xy 106.864104 -228.951026) (xy 106.915399 -228.942901) (xy 106.967333 -228.942901)
			(xy 107.018628 -228.951026) (xy 107.068021 -228.967074) (xy 107.114295 -228.990652) (xy 107.156311 -229.021178)
			(xy 107.193034 -229.057901) (xy 107.22356 -229.099917) (xy 107.247138 -229.146191) (xy 107.263186 -229.195584)
			(xy 107.271311 -229.246879) (xy 107.27182 -229.272846) (xy 107.271311 -229.298813) (xy 107.551221 -229.298813)
			(xy 107.551221 -229.246879) (xy 107.559346 -229.195584) (xy 107.575394 -229.146191) (xy 107.598972 -229.099917)
			(xy 107.629498 -229.057901) (xy 107.666221 -229.021178) (xy 107.708237 -228.990652) (xy 107.754511 -228.967074)
			(xy 107.803904 -228.951026) (xy 107.855199 -228.942901) (xy 107.907133 -228.942901) (xy 107.958428 -228.951026)
			(xy 108.007821 -228.967074) (xy 108.054095 -228.990652) (xy 108.096111 -229.021178) (xy 108.132834 -229.057901)
			(xy 108.16336 -229.099917) (xy 108.186938 -229.146191) (xy 108.202986 -229.195584) (xy 108.211111 -229.246879)
			(xy 108.21162 -229.272846) (xy 108.211111 -229.298813) (xy 108.491021 -229.298813) (xy 108.491021 -229.246879)
			(xy 108.499146 -229.195584) (xy 108.515194 -229.146191) (xy 108.538772 -229.099917) (xy 108.569298 -229.057901)
			(xy 108.606021 -229.021178) (xy 108.648037 -228.990652) (xy 108.694311 -228.967074) (xy 108.743704 -228.951026)
			(xy 108.794999 -228.942901) (xy 108.846933 -228.942901) (xy 108.898228 -228.951026) (xy 108.947621 -228.967074)
			(xy 108.993895 -228.990652) (xy 109.035911 -229.021178) (xy 109.072634 -229.057901) (xy 109.10316 -229.099917)
			(xy 109.126738 -229.146191) (xy 109.142786 -229.195584) (xy 109.150911 -229.246879) (xy 109.15142 -229.272846)
			(xy 109.150911 -229.298813) (xy 109.142786 -229.350108) (xy 109.126738 -229.399501) (xy 109.10316 -229.445775)
			(xy 109.072634 -229.487791) (xy 109.035911 -229.524514) (xy 108.993895 -229.55504) (xy 108.947621 -229.578618)
			(xy 108.898228 -229.594666) (xy 108.846933 -229.602791) (xy 108.794999 -229.602791) (xy 108.743704 -229.594666)
			(xy 108.694311 -229.578618) (xy 108.648037 -229.55504) (xy 108.606021 -229.524514) (xy 108.569298 -229.487791)
			(xy 108.538772 -229.445775) (xy 108.515194 -229.399501) (xy 108.499146 -229.350108) (xy 108.491021 -229.298813)
			(xy 108.211111 -229.298813) (xy 108.202986 -229.350108) (xy 108.186938 -229.399501) (xy 108.16336 -229.445775)
			(xy 108.132834 -229.487791) (xy 108.096111 -229.524514) (xy 108.054095 -229.55504) (xy 108.007821 -229.578618)
			(xy 107.958428 -229.594666) (xy 107.907133 -229.602791) (xy 107.855199 -229.602791) (xy 107.803904 -229.594666)
			(xy 107.754511 -229.578618) (xy 107.708237 -229.55504) (xy 107.666221 -229.524514) (xy 107.629498 -229.487791)
			(xy 107.598972 -229.445775) (xy 107.575394 -229.399501) (xy 107.559346 -229.350108) (xy 107.551221 -229.298813)
			(xy 107.271311 -229.298813) (xy 107.263186 -229.350108) (xy 107.247138 -229.399501) (xy 107.22356 -229.445775)
			(xy 107.193034 -229.487791) (xy 107.156311 -229.524514) (xy 107.114295 -229.55504) (xy 107.068021 -229.578618)
			(xy 107.018628 -229.594666) (xy 106.967333 -229.602791) (xy 106.915399 -229.602791) (xy 106.864104 -229.594666)
			(xy 106.814711 -229.578618) (xy 106.768437 -229.55504) (xy 106.726421 -229.524514) (xy 106.689698 -229.487791)
			(xy 106.659172 -229.445775) (xy 106.635594 -229.399501) (xy 106.619546 -229.350108) (xy 106.611421 -229.298813)
			(xy 106.331511 -229.298813) (xy 106.323386 -229.350108) (xy 106.307338 -229.399501) (xy 106.28376 -229.445775)
			(xy 106.253234 -229.487791) (xy 106.216511 -229.524514) (xy 106.174495 -229.55504) (xy 106.128221 -229.578618)
			(xy 106.078828 -229.594666) (xy 106.027533 -229.602791) (xy 105.975599 -229.602791) (xy 105.924304 -229.594666)
			(xy 105.874911 -229.578618) (xy 105.828637 -229.55504) (xy 105.786621 -229.524514) (xy 105.749898 -229.487791)
			(xy 105.719372 -229.445775) (xy 105.695794 -229.399501) (xy 105.679746 -229.350108) (xy 105.671621 -229.298813)
			(xy 105.391711 -229.298813) (xy 105.383586 -229.350108) (xy 105.367538 -229.399501) (xy 105.34396 -229.445775)
			(xy 105.313434 -229.487791) (xy 105.276711 -229.524514) (xy 105.234695 -229.55504) (xy 105.188421 -229.578618)
			(xy 105.139028 -229.594666) (xy 105.087733 -229.602791) (xy 105.035799 -229.602791) (xy 104.984504 -229.594666)
			(xy 104.935111 -229.578618) (xy 104.888837 -229.55504) (xy 104.846821 -229.524514) (xy 104.810098 -229.487791)
			(xy 104.779572 -229.445775) (xy 104.755994 -229.399501) (xy 104.739946 -229.350108) (xy 104.731821 -229.298813)
			(xy 104.451911 -229.298813) (xy 104.443786 -229.350108) (xy 104.427738 -229.399501) (xy 104.40416 -229.445775)
			(xy 104.373634 -229.487791) (xy 104.336911 -229.524514) (xy 104.294895 -229.55504) (xy 104.248621 -229.578618)
			(xy 104.199228 -229.594666) (xy 104.147933 -229.602791) (xy 104.095999 -229.602791) (xy 104.044704 -229.594666)
			(xy 103.995311 -229.578618) (xy 103.949037 -229.55504) (xy 103.907021 -229.524514) (xy 103.870298 -229.487791)
			(xy 103.839772 -229.445775) (xy 103.816194 -229.399501) (xy 103.800146 -229.350108) (xy 103.792021 -229.298813)
			(xy 103.512111 -229.298813) (xy 103.503986 -229.350108) (xy 103.487938 -229.399501) (xy 103.46436 -229.445775)
			(xy 103.433834 -229.487791) (xy 103.397111 -229.524514) (xy 103.355095 -229.55504) (xy 103.308821 -229.578618)
			(xy 103.259428 -229.594666) (xy 103.208133 -229.602791) (xy 103.156199 -229.602791) (xy 103.104904 -229.594666)
			(xy 103.055511 -229.578618) (xy 103.009237 -229.55504) (xy 102.967221 -229.524514) (xy 102.930498 -229.487791)
			(xy 102.899972 -229.445775) (xy 102.876394 -229.399501) (xy 102.860346 -229.350108) (xy 102.852221 -229.298813)
			(xy 102.68458 -229.298813) (xy 102.68458 -229.70617) (xy 102.684977 -229.715796) (xy 102.692064 -229.733695)
			(xy 102.70528 -229.747692) (xy 102.722743 -229.755796) (xy 102.732332 -229.756716) (xy 102.758528 -229.758837)
			(xy 102.80981 -229.770327) (xy 102.858629 -229.789785) (xy 102.903755 -229.816721) (xy 102.944051 -229.850456)
			(xy 102.978503 -229.890142) (xy 103.006243 -229.934779) (xy 103.026571 -229.983241) (xy 103.038977 -230.03431)
			(xy 103.043148 -230.086698) (xy 103.041084 -230.112629) (xy 103.321867 -230.112629) (xy 103.321867 -230.060695)
			(xy 103.329992 -230.0094) (xy 103.34604 -229.960007) (xy 103.369618 -229.913733) (xy 103.400144 -229.871717)
			(xy 103.436867 -229.834994) (xy 103.478883 -229.804468) (xy 103.525157 -229.78089) (xy 103.57455 -229.764842)
			(xy 103.625845 -229.756717) (xy 103.677779 -229.756717) (xy 103.729074 -229.764842) (xy 103.778467 -229.78089)
			(xy 103.824741 -229.804468) (xy 103.866757 -229.834994) (xy 103.90348 -229.871717) (xy 103.934006 -229.913733)
			(xy 103.957584 -229.960007) (xy 103.973632 -230.0094) (xy 103.981757 -230.060695) (xy 103.982266 -230.086662)
			(xy 103.981757 -230.112629) (xy 104.261667 -230.112629) (xy 104.261667 -230.060695) (xy 104.269792 -230.0094)
			(xy 104.28584 -229.960007) (xy 104.309418 -229.913733) (xy 104.339944 -229.871717) (xy 104.376667 -229.834994)
			(xy 104.418683 -229.804468) (xy 104.464957 -229.78089) (xy 104.51435 -229.764842) (xy 104.565645 -229.756717)
			(xy 104.617579 -229.756717) (xy 104.668874 -229.764842) (xy 104.718267 -229.78089) (xy 104.764541 -229.804468)
			(xy 104.806557 -229.834994) (xy 104.84328 -229.871717) (xy 104.873806 -229.913733) (xy 104.897384 -229.960007)
			(xy 104.913432 -230.0094) (xy 104.921557 -230.060695) (xy 104.922066 -230.086662) (xy 104.921557 -230.112629)
			(xy 105.201467 -230.112629) (xy 105.201467 -230.060695) (xy 105.209592 -230.0094) (xy 105.22564 -229.960007)
			(xy 105.249218 -229.913733) (xy 105.279744 -229.871717) (xy 105.316467 -229.834994) (xy 105.358483 -229.804468)
			(xy 105.404757 -229.78089) (xy 105.45415 -229.764842) (xy 105.505445 -229.756717) (xy 105.557379 -229.756717)
			(xy 105.608674 -229.764842) (xy 105.658067 -229.78089) (xy 105.704341 -229.804468) (xy 105.746357 -229.834994)
			(xy 105.78308 -229.871717) (xy 105.813606 -229.913733) (xy 105.837184 -229.960007) (xy 105.853232 -230.0094)
			(xy 105.861357 -230.060695) (xy 105.861866 -230.086662) (xy 105.861357 -230.112629) (xy 106.141521 -230.112629)
			(xy 106.141521 -230.060695) (xy 106.149646 -230.0094) (xy 106.165694 -229.960007) (xy 106.189272 -229.913733)
			(xy 106.219798 -229.871717) (xy 106.256521 -229.834994) (xy 106.298537 -229.804468) (xy 106.344811 -229.78089)
			(xy 106.394204 -229.764842) (xy 106.445499 -229.756717) (xy 106.497433 -229.756717) (xy 106.548728 -229.764842)
			(xy 106.598121 -229.78089) (xy 106.644395 -229.804468) (xy 106.686411 -229.834994) (xy 106.723134 -229.871717)
			(xy 106.75366 -229.913733) (xy 106.777238 -229.960007) (xy 106.793286 -230.0094) (xy 106.801411 -230.060695)
			(xy 106.80192 -230.086662) (xy 106.801411 -230.112629) (xy 107.081067 -230.112629) (xy 107.081067 -230.060695)
			(xy 107.089192 -230.0094) (xy 107.10524 -229.960007) (xy 107.128818 -229.913733) (xy 107.159344 -229.871717)
			(xy 107.196067 -229.834994) (xy 107.238083 -229.804468) (xy 107.284357 -229.78089) (xy 107.33375 -229.764842)
			(xy 107.385045 -229.756717) (xy 107.436979 -229.756717) (xy 107.488274 -229.764842) (xy 107.537667 -229.78089)
			(xy 107.583941 -229.804468) (xy 107.625957 -229.834994) (xy 107.66268 -229.871717) (xy 107.693206 -229.913733)
			(xy 107.716784 -229.960007) (xy 107.732832 -230.0094) (xy 107.740957 -230.060695) (xy 107.741466 -230.086662)
			(xy 107.740957 -230.112629) (xy 108.020867 -230.112629) (xy 108.020867 -230.060695) (xy 108.028992 -230.0094)
			(xy 108.04504 -229.960007) (xy 108.068618 -229.913733) (xy 108.099144 -229.871717) (xy 108.135867 -229.834994)
			(xy 108.177883 -229.804468) (xy 108.224157 -229.78089) (xy 108.27355 -229.764842) (xy 108.324845 -229.756717)
			(xy 108.376779 -229.756717) (xy 108.428074 -229.764842) (xy 108.477467 -229.78089) (xy 108.523741 -229.804468)
			(xy 108.565757 -229.834994) (xy 108.60248 -229.871717) (xy 108.633006 -229.913733) (xy 108.656584 -229.960007)
			(xy 108.672632 -230.0094) (xy 108.680757 -230.060695) (xy 108.681266 -230.086662) (xy 108.680757 -230.112629)
			(xy 108.960667 -230.112629) (xy 108.960667 -230.060695) (xy 108.968792 -230.0094) (xy 108.98484 -229.960007)
			(xy 109.008418 -229.913733) (xy 109.038944 -229.871717) (xy 109.075667 -229.834994) (xy 109.117683 -229.804468)
			(xy 109.163957 -229.78089) (xy 109.21335 -229.764842) (xy 109.264645 -229.756717) (xy 109.316579 -229.756717)
			(xy 109.367874 -229.764842) (xy 109.417267 -229.78089) (xy 109.463541 -229.804468) (xy 109.505557 -229.834994)
			(xy 109.54228 -229.871717) (xy 109.572806 -229.913733) (xy 109.596384 -229.960007) (xy 109.612432 -230.0094)
			(xy 109.620557 -230.060695) (xy 109.621066 -230.086662) (xy 109.620557 -230.112629) (xy 109.612432 -230.163924)
			(xy 109.596384 -230.213317) (xy 109.572806 -230.259591) (xy 109.54228 -230.301607) (xy 109.505557 -230.33833)
			(xy 109.463541 -230.368856) (xy 109.417267 -230.392434) (xy 109.367874 -230.408482) (xy 109.316579 -230.416607)
			(xy 109.264645 -230.416607) (xy 109.21335 -230.408482) (xy 109.163957 -230.392434) (xy 109.117683 -230.368856)
			(xy 109.075667 -230.33833) (xy 109.038944 -230.301607) (xy 109.008418 -230.259591) (xy 108.98484 -230.213317)
			(xy 108.968792 -230.163924) (xy 108.960667 -230.112629) (xy 108.680757 -230.112629) (xy 108.672632 -230.163924)
			(xy 108.656584 -230.213317) (xy 108.633006 -230.259591) (xy 108.60248 -230.301607) (xy 108.565757 -230.33833)
			(xy 108.523741 -230.368856) (xy 108.477467 -230.392434) (xy 108.428074 -230.408482) (xy 108.376779 -230.416607)
			(xy 108.324845 -230.416607) (xy 108.27355 -230.408482) (xy 108.224157 -230.392434) (xy 108.177883 -230.368856)
			(xy 108.135867 -230.33833) (xy 108.099144 -230.301607) (xy 108.068618 -230.259591) (xy 108.04504 -230.213317)
			(xy 108.028992 -230.163924) (xy 108.020867 -230.112629) (xy 107.740957 -230.112629) (xy 107.732832 -230.163924)
			(xy 107.716784 -230.213317) (xy 107.693206 -230.259591) (xy 107.66268 -230.301607) (xy 107.625957 -230.33833)
			(xy 107.583941 -230.368856) (xy 107.537667 -230.392434) (xy 107.488274 -230.408482) (xy 107.436979 -230.416607)
			(xy 107.385045 -230.416607) (xy 107.33375 -230.408482) (xy 107.284357 -230.392434) (xy 107.238083 -230.368856)
			(xy 107.196067 -230.33833) (xy 107.159344 -230.301607) (xy 107.128818 -230.259591) (xy 107.10524 -230.213317)
			(xy 107.089192 -230.163924) (xy 107.081067 -230.112629) (xy 106.801411 -230.112629) (xy 106.793286 -230.163924)
			(xy 106.777238 -230.213317) (xy 106.75366 -230.259591) (xy 106.723134 -230.301607) (xy 106.686411 -230.33833)
			(xy 106.644395 -230.368856) (xy 106.598121 -230.392434) (xy 106.548728 -230.408482) (xy 106.497433 -230.416607)
			(xy 106.445499 -230.416607) (xy 106.394204 -230.408482) (xy 106.344811 -230.392434) (xy 106.298537 -230.368856)
			(xy 106.256521 -230.33833) (xy 106.219798 -230.301607) (xy 106.189272 -230.259591) (xy 106.165694 -230.213317)
			(xy 106.149646 -230.163924) (xy 106.141521 -230.112629) (xy 105.861357 -230.112629) (xy 105.853232 -230.163924)
			(xy 105.837184 -230.213317) (xy 105.813606 -230.259591) (xy 105.78308 -230.301607) (xy 105.746357 -230.33833)
			(xy 105.704341 -230.368856) (xy 105.658067 -230.392434) (xy 105.608674 -230.408482) (xy 105.557379 -230.416607)
			(xy 105.505445 -230.416607) (xy 105.45415 -230.408482) (xy 105.404757 -230.392434) (xy 105.358483 -230.368856)
			(xy 105.316467 -230.33833) (xy 105.279744 -230.301607) (xy 105.249218 -230.259591) (xy 105.22564 -230.213317)
			(xy 105.209592 -230.163924) (xy 105.201467 -230.112629) (xy 104.921557 -230.112629) (xy 104.913432 -230.163924)
			(xy 104.897384 -230.213317) (xy 104.873806 -230.259591) (xy 104.84328 -230.301607) (xy 104.806557 -230.33833)
			(xy 104.764541 -230.368856) (xy 104.718267 -230.392434) (xy 104.668874 -230.408482) (xy 104.617579 -230.416607)
			(xy 104.565645 -230.416607) (xy 104.51435 -230.408482) (xy 104.464957 -230.392434) (xy 104.418683 -230.368856)
			(xy 104.376667 -230.33833) (xy 104.339944 -230.301607) (xy 104.309418 -230.259591) (xy 104.28584 -230.213317)
			(xy 104.269792 -230.163924) (xy 104.261667 -230.112629) (xy 103.981757 -230.112629) (xy 103.973632 -230.163924)
			(xy 103.957584 -230.213317) (xy 103.934006 -230.259591) (xy 103.90348 -230.301607) (xy 103.866757 -230.33833)
			(xy 103.824741 -230.368856) (xy 103.778467 -230.392434) (xy 103.729074 -230.408482) (xy 103.677779 -230.416607)
			(xy 103.625845 -230.416607) (xy 103.57455 -230.408482) (xy 103.525157 -230.392434) (xy 103.478883 -230.368856)
			(xy 103.436867 -230.33833) (xy 103.400144 -230.301607) (xy 103.369618 -230.259591) (xy 103.34604 -230.213317)
			(xy 103.329992 -230.163924) (xy 103.321867 -230.112629) (xy 103.041084 -230.112629) (xy 103.038978 -230.139086)
			(xy 103.026573 -230.190154) (xy 103.006245 -230.238617) (xy 102.978506 -230.283254) (xy 102.944055 -230.32294)
			(xy 102.903759 -230.356677) (xy 102.858633 -230.383613) (xy 102.809815 -230.403072) (xy 102.758533 -230.414562)
			(xy 102.732332 -230.416608) (xy 102.722774 -230.417612) (xy 102.705384 -230.42576) (xy 102.6922 -230.439725)
			(xy 102.685063 -230.457554) (xy 102.68458 -230.467154) (xy 102.68458 -230.926445) (xy 102.852221 -230.926445)
			(xy 102.852221 -230.874511) (xy 102.860346 -230.823216) (xy 102.876394 -230.773823) (xy 102.899972 -230.727549)
			(xy 102.930498 -230.685533) (xy 102.967221 -230.64881) (xy 103.009237 -230.618284) (xy 103.055511 -230.594706)
			(xy 103.104904 -230.578658) (xy 103.156199 -230.570533) (xy 103.208133 -230.570533) (xy 103.259428 -230.578658)
			(xy 103.308821 -230.594706) (xy 103.355095 -230.618284) (xy 103.397111 -230.64881) (xy 103.433834 -230.685533)
			(xy 103.46436 -230.727549) (xy 103.487938 -230.773823) (xy 103.503986 -230.823216) (xy 103.512111 -230.874511)
			(xy 103.51262 -230.900478) (xy 103.512111 -230.926445) (xy 103.792021 -230.926445) (xy 103.792021 -230.874511)
			(xy 103.800146 -230.823216) (xy 103.816194 -230.773823) (xy 103.839772 -230.727549) (xy 103.870298 -230.685533)
			(xy 103.907021 -230.64881) (xy 103.949037 -230.618284) (xy 103.995311 -230.594706) (xy 104.044704 -230.578658)
			(xy 104.095999 -230.570533) (xy 104.147933 -230.570533) (xy 104.199228 -230.578658) (xy 104.248621 -230.594706)
			(xy 104.294895 -230.618284) (xy 104.336911 -230.64881) (xy 104.373634 -230.685533) (xy 104.40416 -230.727549)
			(xy 104.427738 -230.773823) (xy 104.443786 -230.823216) (xy 104.451911 -230.874511) (xy 104.45242 -230.900478)
			(xy 104.451911 -230.926445) (xy 104.731821 -230.926445) (xy 104.731821 -230.874511) (xy 104.739946 -230.823216)
			(xy 104.755994 -230.773823) (xy 104.779572 -230.727549) (xy 104.810098 -230.685533) (xy 104.846821 -230.64881)
			(xy 104.888837 -230.618284) (xy 104.935111 -230.594706) (xy 104.984504 -230.578658) (xy 105.035799 -230.570533)
			(xy 105.087733 -230.570533) (xy 105.139028 -230.578658) (xy 105.188421 -230.594706) (xy 105.234695 -230.618284)
			(xy 105.276711 -230.64881) (xy 105.313434 -230.685533) (xy 105.34396 -230.727549) (xy 105.367538 -230.773823)
			(xy 105.383586 -230.823216) (xy 105.391711 -230.874511) (xy 105.39222 -230.900478) (xy 105.391711 -230.926445)
			(xy 105.671621 -230.926445) (xy 105.671621 -230.874511) (xy 105.679746 -230.823216) (xy 105.695794 -230.773823)
			(xy 105.719372 -230.727549) (xy 105.749898 -230.685533) (xy 105.786621 -230.64881) (xy 105.828637 -230.618284)
			(xy 105.874911 -230.594706) (xy 105.924304 -230.578658) (xy 105.975599 -230.570533) (xy 106.027533 -230.570533)
			(xy 106.078828 -230.578658) (xy 106.128221 -230.594706) (xy 106.174495 -230.618284) (xy 106.216511 -230.64881)
			(xy 106.253234 -230.685533) (xy 106.28376 -230.727549) (xy 106.307338 -230.773823) (xy 106.323386 -230.823216)
			(xy 106.331511 -230.874511) (xy 106.33202 -230.900478) (xy 106.331511 -230.926445) (xy 106.611421 -230.926445)
			(xy 106.611421 -230.874511) (xy 106.619546 -230.823216) (xy 106.635594 -230.773823) (xy 106.659172 -230.727549)
			(xy 106.689698 -230.685533) (xy 106.726421 -230.64881) (xy 106.768437 -230.618284) (xy 106.814711 -230.594706)
			(xy 106.864104 -230.578658) (xy 106.915399 -230.570533) (xy 106.967333 -230.570533) (xy 107.018628 -230.578658)
			(xy 107.068021 -230.594706) (xy 107.114295 -230.618284) (xy 107.156311 -230.64881) (xy 107.193034 -230.685533)
			(xy 107.22356 -230.727549) (xy 107.247138 -230.773823) (xy 107.263186 -230.823216) (xy 107.271311 -230.874511)
			(xy 107.27182 -230.900478) (xy 107.271311 -230.926445) (xy 107.550967 -230.926445) (xy 107.550967 -230.874511)
			(xy 107.559092 -230.823216) (xy 107.57514 -230.773823) (xy 107.598718 -230.727549) (xy 107.629244 -230.685533)
			(xy 107.665967 -230.64881) (xy 107.707983 -230.618284) (xy 107.754257 -230.594706) (xy 107.80365 -230.578658)
			(xy 107.854945 -230.570533) (xy 107.906879 -230.570533) (xy 107.958174 -230.578658) (xy 108.007567 -230.594706)
			(xy 108.053841 -230.618284) (xy 108.095857 -230.64881) (xy 108.13258 -230.685533) (xy 108.163106 -230.727549)
			(xy 108.186684 -230.773823) (xy 108.202732 -230.823216) (xy 108.210857 -230.874511) (xy 108.211366 -230.900478)
			(xy 108.210857 -230.926445) (xy 108.491021 -230.926445) (xy 108.491021 -230.874511) (xy 108.499146 -230.823216)
			(xy 108.515194 -230.773823) (xy 108.538772 -230.727549) (xy 108.569298 -230.685533) (xy 108.606021 -230.64881)
			(xy 108.648037 -230.618284) (xy 108.694311 -230.594706) (xy 108.743704 -230.578658) (xy 108.794999 -230.570533)
			(xy 108.846933 -230.570533) (xy 108.898228 -230.578658) (xy 108.947621 -230.594706) (xy 108.993895 -230.618284)
			(xy 109.035911 -230.64881) (xy 109.072634 -230.685533) (xy 109.10316 -230.727549) (xy 109.126738 -230.773823)
			(xy 109.142786 -230.823216) (xy 109.150911 -230.874511) (xy 109.15142 -230.900478) (xy 109.150911 -230.926445)
			(xy 109.142786 -230.97774) (xy 109.126738 -231.027133) (xy 109.10316 -231.073407) (xy 109.072634 -231.115423)
			(xy 109.035911 -231.152146) (xy 108.993895 -231.182672) (xy 108.947621 -231.20625) (xy 108.898228 -231.222298)
			(xy 108.846933 -231.230423) (xy 108.794999 -231.230423) (xy 108.743704 -231.222298) (xy 108.694311 -231.20625)
			(xy 108.648037 -231.182672) (xy 108.606021 -231.152146) (xy 108.569298 -231.115423) (xy 108.538772 -231.073407)
			(xy 108.515194 -231.027133) (xy 108.499146 -230.97774) (xy 108.491021 -230.926445) (xy 108.210857 -230.926445)
			(xy 108.202732 -230.97774) (xy 108.186684 -231.027133) (xy 108.163106 -231.073407) (xy 108.13258 -231.115423)
			(xy 108.095857 -231.152146) (xy 108.053841 -231.182672) (xy 108.007567 -231.20625) (xy 107.958174 -231.222298)
			(xy 107.906879 -231.230423) (xy 107.854945 -231.230423) (xy 107.80365 -231.222298) (xy 107.754257 -231.20625)
			(xy 107.707983 -231.182672) (xy 107.665967 -231.152146) (xy 107.629244 -231.115423) (xy 107.598718 -231.073407)
			(xy 107.57514 -231.027133) (xy 107.559092 -230.97774) (xy 107.550967 -230.926445) (xy 107.271311 -230.926445)
			(xy 107.263186 -230.97774) (xy 107.247138 -231.027133) (xy 107.22356 -231.073407) (xy 107.193034 -231.115423)
			(xy 107.156311 -231.152146) (xy 107.114295 -231.182672) (xy 107.068021 -231.20625) (xy 107.018628 -231.222298)
			(xy 106.967333 -231.230423) (xy 106.915399 -231.230423) (xy 106.864104 -231.222298) (xy 106.814711 -231.20625)
			(xy 106.768437 -231.182672) (xy 106.726421 -231.152146) (xy 106.689698 -231.115423) (xy 106.659172 -231.073407)
			(xy 106.635594 -231.027133) (xy 106.619546 -230.97774) (xy 106.611421 -230.926445) (xy 106.331511 -230.926445)
			(xy 106.323386 -230.97774) (xy 106.307338 -231.027133) (xy 106.28376 -231.073407) (xy 106.253234 -231.115423)
			(xy 106.216511 -231.152146) (xy 106.174495 -231.182672) (xy 106.128221 -231.20625) (xy 106.078828 -231.222298)
			(xy 106.027533 -231.230423) (xy 105.975599 -231.230423) (xy 105.924304 -231.222298) (xy 105.874911 -231.20625)
			(xy 105.828637 -231.182672) (xy 105.786621 -231.152146) (xy 105.749898 -231.115423) (xy 105.719372 -231.073407)
			(xy 105.695794 -231.027133) (xy 105.679746 -230.97774) (xy 105.671621 -230.926445) (xy 105.391711 -230.926445)
			(xy 105.383586 -230.97774) (xy 105.367538 -231.027133) (xy 105.34396 -231.073407) (xy 105.313434 -231.115423)
			(xy 105.276711 -231.152146) (xy 105.234695 -231.182672) (xy 105.188421 -231.20625) (xy 105.139028 -231.222298)
			(xy 105.087733 -231.230423) (xy 105.035799 -231.230423) (xy 104.984504 -231.222298) (xy 104.935111 -231.20625)
			(xy 104.888837 -231.182672) (xy 104.846821 -231.152146) (xy 104.810098 -231.115423) (xy 104.779572 -231.073407)
			(xy 104.755994 -231.027133) (xy 104.739946 -230.97774) (xy 104.731821 -230.926445) (xy 104.451911 -230.926445)
			(xy 104.443786 -230.97774) (xy 104.427738 -231.027133) (xy 104.40416 -231.073407) (xy 104.373634 -231.115423)
			(xy 104.336911 -231.152146) (xy 104.294895 -231.182672) (xy 104.248621 -231.20625) (xy 104.199228 -231.222298)
			(xy 104.147933 -231.230423) (xy 104.095999 -231.230423) (xy 104.044704 -231.222298) (xy 103.995311 -231.20625)
			(xy 103.949037 -231.182672) (xy 103.907021 -231.152146) (xy 103.870298 -231.115423) (xy 103.839772 -231.073407)
			(xy 103.816194 -231.027133) (xy 103.800146 -230.97774) (xy 103.792021 -230.926445) (xy 103.512111 -230.926445)
			(xy 103.503986 -230.97774) (xy 103.487938 -231.027133) (xy 103.46436 -231.073407) (xy 103.433834 -231.115423)
			(xy 103.397111 -231.152146) (xy 103.355095 -231.182672) (xy 103.308821 -231.20625) (xy 103.259428 -231.222298)
			(xy 103.208133 -231.230423) (xy 103.156199 -231.230423) (xy 103.104904 -231.222298) (xy 103.055511 -231.20625)
			(xy 103.009237 -231.182672) (xy 102.967221 -231.152146) (xy 102.930498 -231.115423) (xy 102.899972 -231.073407)
			(xy 102.876394 -231.027133) (xy 102.860346 -230.97774) (xy 102.852221 -230.926445) (xy 102.68458 -230.926445)
			(xy 102.68458 -231.334056) (xy 102.684974 -231.343684) (xy 102.692059 -231.361587) (xy 102.705276 -231.375589)
			(xy 102.72274 -231.383695) (xy 102.732332 -231.384602) (xy 102.758521 -231.386723) (xy 102.80979 -231.398211)
			(xy 102.858596 -231.417664) (xy 102.903709 -231.444594) (xy 102.943995 -231.478322) (xy 102.978437 -231.517998)
			(xy 103.006168 -231.562623) (xy 103.026491 -231.611073) (xy 103.038893 -231.662129) (xy 103.043061 -231.714503)
			(xy 103.04099 -231.740515) (xy 103.321867 -231.740515) (xy 103.321867 -231.688581) (xy 103.329992 -231.637286)
			(xy 103.34604 -231.587893) (xy 103.369618 -231.541619) (xy 103.400144 -231.499603) (xy 103.436867 -231.46288)
			(xy 103.478883 -231.432354) (xy 103.525157 -231.408776) (xy 103.57455 -231.392728) (xy 103.625845 -231.384603)
			(xy 103.677779 -231.384603) (xy 103.729074 -231.392728) (xy 103.778467 -231.408776) (xy 103.824741 -231.432354)
			(xy 103.866757 -231.46288) (xy 103.90348 -231.499603) (xy 103.934006 -231.541619) (xy 103.957584 -231.587893)
			(xy 103.973632 -231.637286) (xy 103.981757 -231.688581) (xy 103.982266 -231.714548) (xy 103.981757 -231.740515)
			(xy 104.261667 -231.740515) (xy 104.261667 -231.688581) (xy 104.269792 -231.637286) (xy 104.28584 -231.587893)
			(xy 104.309418 -231.541619) (xy 104.339944 -231.499603) (xy 104.376667 -231.46288) (xy 104.418683 -231.432354)
			(xy 104.464957 -231.408776) (xy 104.51435 -231.392728) (xy 104.565645 -231.384603) (xy 104.617579 -231.384603)
			(xy 104.668874 -231.392728) (xy 104.718267 -231.408776) (xy 104.764541 -231.432354) (xy 104.806557 -231.46288)
			(xy 104.84328 -231.499603) (xy 104.873806 -231.541619) (xy 104.897384 -231.587893) (xy 104.913432 -231.637286)
			(xy 104.921557 -231.688581) (xy 104.922066 -231.714548) (xy 104.921557 -231.740515) (xy 105.201467 -231.740515)
			(xy 105.201467 -231.688581) (xy 105.209592 -231.637286) (xy 105.22564 -231.587893) (xy 105.249218 -231.541619)
			(xy 105.279744 -231.499603) (xy 105.316467 -231.46288) (xy 105.358483 -231.432354) (xy 105.404757 -231.408776)
			(xy 105.45415 -231.392728) (xy 105.505445 -231.384603) (xy 105.557379 -231.384603) (xy 105.608674 -231.392728)
			(xy 105.658067 -231.408776) (xy 105.704341 -231.432354) (xy 105.746357 -231.46288) (xy 105.78308 -231.499603)
			(xy 105.813606 -231.541619) (xy 105.837184 -231.587893) (xy 105.853232 -231.637286) (xy 105.861357 -231.688581)
			(xy 105.861866 -231.714548) (xy 105.861357 -231.740515) (xy 106.141267 -231.740515) (xy 106.141267 -231.688581)
			(xy 106.149392 -231.637286) (xy 106.16544 -231.587893) (xy 106.189018 -231.541619) (xy 106.219544 -231.499603)
			(xy 106.256267 -231.46288) (xy 106.298283 -231.432354) (xy 106.344557 -231.408776) (xy 106.39395 -231.392728)
			(xy 106.445245 -231.384603) (xy 106.497179 -231.384603) (xy 106.548474 -231.392728) (xy 106.597867 -231.408776)
			(xy 106.644141 -231.432354) (xy 106.686157 -231.46288) (xy 106.72288 -231.499603) (xy 106.753406 -231.541619)
			(xy 106.776984 -231.587893) (xy 106.793032 -231.637286) (xy 106.801157 -231.688581) (xy 106.801666 -231.714548)
			(xy 106.801157 -231.740515) (xy 107.081067 -231.740515) (xy 107.081067 -231.688581) (xy 107.089192 -231.637286)
			(xy 107.10524 -231.587893) (xy 107.128818 -231.541619) (xy 107.159344 -231.499603) (xy 107.196067 -231.46288)
			(xy 107.238083 -231.432354) (xy 107.284357 -231.408776) (xy 107.33375 -231.392728) (xy 107.385045 -231.384603)
			(xy 107.436979 -231.384603) (xy 107.488274 -231.392728) (xy 107.537667 -231.408776) (xy 107.583941 -231.432354)
			(xy 107.625957 -231.46288) (xy 107.66268 -231.499603) (xy 107.693206 -231.541619) (xy 107.716784 -231.587893)
			(xy 107.732832 -231.637286) (xy 107.740957 -231.688581) (xy 107.741466 -231.714548) (xy 107.740957 -231.740515)
			(xy 108.020867 -231.740515) (xy 108.020867 -231.688581) (xy 108.028992 -231.637286) (xy 108.04504 -231.587893)
			(xy 108.068618 -231.541619) (xy 108.099144 -231.499603) (xy 108.135867 -231.46288) (xy 108.177883 -231.432354)
			(xy 108.224157 -231.408776) (xy 108.27355 -231.392728) (xy 108.324845 -231.384603) (xy 108.376779 -231.384603)
			(xy 108.428074 -231.392728) (xy 108.477467 -231.408776) (xy 108.523741 -231.432354) (xy 108.565757 -231.46288)
			(xy 108.60248 -231.499603) (xy 108.633006 -231.541619) (xy 108.656584 -231.587893) (xy 108.672632 -231.637286)
			(xy 108.680757 -231.688581) (xy 108.681266 -231.714548) (xy 108.680757 -231.740515) (xy 108.960667 -231.740515)
			(xy 108.960667 -231.688581) (xy 108.968792 -231.637286) (xy 108.98484 -231.587893) (xy 109.008418 -231.541619)
			(xy 109.038944 -231.499603) (xy 109.075667 -231.46288) (xy 109.117683 -231.432354) (xy 109.163957 -231.408776)
			(xy 109.21335 -231.392728) (xy 109.264645 -231.384603) (xy 109.316579 -231.384603) (xy 109.367874 -231.392728)
			(xy 109.417267 -231.408776) (xy 109.463541 -231.432354) (xy 109.505557 -231.46288) (xy 109.54228 -231.499603)
			(xy 109.572806 -231.541619) (xy 109.596384 -231.587893) (xy 109.612432 -231.637286) (xy 109.620557 -231.688581)
			(xy 109.621066 -231.714548) (xy 109.620557 -231.740515) (xy 109.612432 -231.79181) (xy 109.596384 -231.841203)
			(xy 109.572806 -231.887477) (xy 109.54228 -231.929493) (xy 109.505557 -231.966216) (xy 109.463541 -231.996742)
			(xy 109.417267 -232.02032) (xy 109.367874 -232.036368) (xy 109.316579 -232.044493) (xy 109.264645 -232.044493)
			(xy 109.21335 -232.036368) (xy 109.163957 -232.02032) (xy 109.117683 -231.996742) (xy 109.075667 -231.966216)
			(xy 109.038944 -231.929493) (xy 109.008418 -231.887477) (xy 108.98484 -231.841203) (xy 108.968792 -231.79181)
			(xy 108.960667 -231.740515) (xy 108.680757 -231.740515) (xy 108.672632 -231.79181) (xy 108.656584 -231.841203)
			(xy 108.633006 -231.887477) (xy 108.60248 -231.929493) (xy 108.565757 -231.966216) (xy 108.523741 -231.996742)
			(xy 108.477467 -232.02032) (xy 108.428074 -232.036368) (xy 108.376779 -232.044493) (xy 108.324845 -232.044493)
			(xy 108.27355 -232.036368) (xy 108.224157 -232.02032) (xy 108.177883 -231.996742) (xy 108.135867 -231.966216)
			(xy 108.099144 -231.929493) (xy 108.068618 -231.887477) (xy 108.04504 -231.841203) (xy 108.028992 -231.79181)
			(xy 108.020867 -231.740515) (xy 107.740957 -231.740515) (xy 107.732832 -231.79181) (xy 107.716784 -231.841203)
			(xy 107.693206 -231.887477) (xy 107.66268 -231.929493) (xy 107.625957 -231.966216) (xy 107.583941 -231.996742)
			(xy 107.537667 -232.02032) (xy 107.488274 -232.036368) (xy 107.436979 -232.044493) (xy 107.385045 -232.044493)
			(xy 107.33375 -232.036368) (xy 107.284357 -232.02032) (xy 107.238083 -231.996742) (xy 107.196067 -231.966216)
			(xy 107.159344 -231.929493) (xy 107.128818 -231.887477) (xy 107.10524 -231.841203) (xy 107.089192 -231.79181)
			(xy 107.081067 -231.740515) (xy 106.801157 -231.740515) (xy 106.793032 -231.79181) (xy 106.776984 -231.841203)
			(xy 106.753406 -231.887477) (xy 106.72288 -231.929493) (xy 106.686157 -231.966216) (xy 106.644141 -231.996742)
			(xy 106.597867 -232.02032) (xy 106.548474 -232.036368) (xy 106.497179 -232.044493) (xy 106.445245 -232.044493)
			(xy 106.39395 -232.036368) (xy 106.344557 -232.02032) (xy 106.298283 -231.996742) (xy 106.256267 -231.966216)
			(xy 106.219544 -231.929493) (xy 106.189018 -231.887477) (xy 106.16544 -231.841203) (xy 106.149392 -231.79181)
			(xy 106.141267 -231.740515) (xy 105.861357 -231.740515) (xy 105.853232 -231.79181) (xy 105.837184 -231.841203)
			(xy 105.813606 -231.887477) (xy 105.78308 -231.929493) (xy 105.746357 -231.966216) (xy 105.704341 -231.996742)
			(xy 105.658067 -232.02032) (xy 105.608674 -232.036368) (xy 105.557379 -232.044493) (xy 105.505445 -232.044493)
			(xy 105.45415 -232.036368) (xy 105.404757 -232.02032) (xy 105.358483 -231.996742) (xy 105.316467 -231.966216)
			(xy 105.279744 -231.929493) (xy 105.249218 -231.887477) (xy 105.22564 -231.841203) (xy 105.209592 -231.79181)
			(xy 105.201467 -231.740515) (xy 104.921557 -231.740515) (xy 104.913432 -231.79181) (xy 104.897384 -231.841203)
			(xy 104.873806 -231.887477) (xy 104.84328 -231.929493) (xy 104.806557 -231.966216) (xy 104.764541 -231.996742)
			(xy 104.718267 -232.02032) (xy 104.668874 -232.036368) (xy 104.617579 -232.044493) (xy 104.565645 -232.044493)
			(xy 104.51435 -232.036368) (xy 104.464957 -232.02032) (xy 104.418683 -231.996742) (xy 104.376667 -231.966216)
			(xy 104.339944 -231.929493) (xy 104.309418 -231.887477) (xy 104.28584 -231.841203) (xy 104.269792 -231.79181)
			(xy 104.261667 -231.740515) (xy 103.981757 -231.740515) (xy 103.973632 -231.79181) (xy 103.957584 -231.841203)
			(xy 103.934006 -231.887477) (xy 103.90348 -231.929493) (xy 103.866757 -231.966216) (xy 103.824741 -231.996742)
			(xy 103.778467 -232.02032) (xy 103.729074 -232.036368) (xy 103.677779 -232.044493) (xy 103.625845 -232.044493)
			(xy 103.57455 -232.036368) (xy 103.525157 -232.02032) (xy 103.478883 -231.996742) (xy 103.436867 -231.966216)
			(xy 103.400144 -231.929493) (xy 103.369618 -231.887477) (xy 103.34604 -231.841203) (xy 103.329992 -231.79181)
			(xy 103.321867 -231.740515) (xy 103.04099 -231.740515) (xy 103.038892 -231.766877) (xy 103.026489 -231.817932)
			(xy 103.006166 -231.866382) (xy 102.978433 -231.911007) (xy 102.94399 -231.950682) (xy 102.903705 -231.984409)
			(xy 102.85859 -232.011338) (xy 102.809784 -232.030791) (xy 102.758515 -232.042277) (xy 102.732332 -232.044494)
			(xy 102.722773 -232.045497) (xy 102.70538 -232.053646) (xy 102.692193 -232.067609) (xy 102.685052 -232.085439)
			(xy 102.68458 -232.09504) (xy 102.68458 -232.554331) (xy 102.852221 -232.554331) (xy 102.852221 -232.502397)
			(xy 102.860346 -232.451102) (xy 102.876394 -232.401709) (xy 102.899972 -232.355435) (xy 102.930498 -232.313419)
			(xy 102.967221 -232.276696) (xy 103.009237 -232.24617) (xy 103.055511 -232.222592) (xy 103.104904 -232.206544)
			(xy 103.156199 -232.198419) (xy 103.208133 -232.198419) (xy 103.259428 -232.206544) (xy 103.308821 -232.222592)
			(xy 103.355095 -232.24617) (xy 103.397111 -232.276696) (xy 103.433834 -232.313419) (xy 103.46436 -232.355435)
			(xy 103.487938 -232.401709) (xy 103.503986 -232.451102) (xy 103.512111 -232.502397) (xy 103.51262 -232.528364)
			(xy 103.512111 -232.554331) (xy 103.792021 -232.554331) (xy 103.792021 -232.502397) (xy 103.800146 -232.451102)
			(xy 103.816194 -232.401709) (xy 103.839772 -232.355435) (xy 103.870298 -232.313419) (xy 103.907021 -232.276696)
			(xy 103.949037 -232.24617) (xy 103.995311 -232.222592) (xy 104.044704 -232.206544) (xy 104.095999 -232.198419)
			(xy 104.147933 -232.198419) (xy 104.199228 -232.206544) (xy 104.248621 -232.222592) (xy 104.294895 -232.24617)
			(xy 104.336911 -232.276696) (xy 104.373634 -232.313419) (xy 104.40416 -232.355435) (xy 104.427738 -232.401709)
			(xy 104.443786 -232.451102) (xy 104.451911 -232.502397) (xy 104.45242 -232.528364) (xy 104.451911 -232.554331)
			(xy 104.731821 -232.554331) (xy 104.731821 -232.502397) (xy 104.739946 -232.451102) (xy 104.755994 -232.401709)
			(xy 104.779572 -232.355435) (xy 104.810098 -232.313419) (xy 104.846821 -232.276696) (xy 104.888837 -232.24617)
			(xy 104.935111 -232.222592) (xy 104.984504 -232.206544) (xy 105.035799 -232.198419) (xy 105.087733 -232.198419)
			(xy 105.139028 -232.206544) (xy 105.188421 -232.222592) (xy 105.234695 -232.24617) (xy 105.276711 -232.276696)
			(xy 105.313434 -232.313419) (xy 105.34396 -232.355435) (xy 105.367538 -232.401709) (xy 105.383586 -232.451102)
			(xy 105.391711 -232.502397) (xy 105.39222 -232.528364) (xy 105.391711 -232.554331) (xy 105.671621 -232.554331)
			(xy 105.671621 -232.502397) (xy 105.679746 -232.451102) (xy 105.695794 -232.401709) (xy 105.719372 -232.355435)
			(xy 105.749898 -232.313419) (xy 105.786621 -232.276696) (xy 105.828637 -232.24617) (xy 105.874911 -232.222592)
			(xy 105.924304 -232.206544) (xy 105.975599 -232.198419) (xy 106.027533 -232.198419) (xy 106.078828 -232.206544)
			(xy 106.128221 -232.222592) (xy 106.174495 -232.24617) (xy 106.216511 -232.276696) (xy 106.253234 -232.313419)
			(xy 106.28376 -232.355435) (xy 106.307338 -232.401709) (xy 106.323386 -232.451102) (xy 106.331511 -232.502397)
			(xy 106.33202 -232.528364) (xy 106.331511 -232.554331) (xy 106.611421 -232.554331) (xy 106.611421 -232.502397)
			(xy 106.619546 -232.451102) (xy 106.635594 -232.401709) (xy 106.659172 -232.355435) (xy 106.689698 -232.313419)
			(xy 106.726421 -232.276696) (xy 106.768437 -232.24617) (xy 106.814711 -232.222592) (xy 106.864104 -232.206544)
			(xy 106.915399 -232.198419) (xy 106.967333 -232.198419) (xy 107.018628 -232.206544) (xy 107.068021 -232.222592)
			(xy 107.114295 -232.24617) (xy 107.156311 -232.276696) (xy 107.193034 -232.313419) (xy 107.22356 -232.355435)
			(xy 107.247138 -232.401709) (xy 107.263186 -232.451102) (xy 107.271311 -232.502397) (xy 107.27182 -232.528364)
			(xy 107.271311 -232.554331) (xy 107.551221 -232.554331) (xy 107.551221 -232.502397) (xy 107.559346 -232.451102)
			(xy 107.575394 -232.401709) (xy 107.598972 -232.355435) (xy 107.629498 -232.313419) (xy 107.666221 -232.276696)
			(xy 107.708237 -232.24617) (xy 107.754511 -232.222592) (xy 107.803904 -232.206544) (xy 107.855199 -232.198419)
			(xy 107.907133 -232.198419) (xy 107.958428 -232.206544) (xy 108.007821 -232.222592) (xy 108.054095 -232.24617)
			(xy 108.096111 -232.276696) (xy 108.132834 -232.313419) (xy 108.16336 -232.355435) (xy 108.186938 -232.401709)
			(xy 108.202986 -232.451102) (xy 108.211111 -232.502397) (xy 108.21162 -232.528364) (xy 108.211111 -232.554331)
			(xy 108.491021 -232.554331) (xy 108.491021 -232.502397) (xy 108.499146 -232.451102) (xy 108.515194 -232.401709)
			(xy 108.538772 -232.355435) (xy 108.569298 -232.313419) (xy 108.606021 -232.276696) (xy 108.648037 -232.24617)
			(xy 108.694311 -232.222592) (xy 108.743704 -232.206544) (xy 108.794999 -232.198419) (xy 108.846933 -232.198419)
			(xy 108.898228 -232.206544) (xy 108.947621 -232.222592) (xy 108.993895 -232.24617) (xy 109.035911 -232.276696)
			(xy 109.072634 -232.313419) (xy 109.10316 -232.355435) (xy 109.126738 -232.401709) (xy 109.142786 -232.451102)
			(xy 109.150911 -232.502397) (xy 109.15142 -232.528364) (xy 109.150911 -232.554331) (xy 109.142786 -232.605626)
			(xy 109.126738 -232.655019) (xy 109.10316 -232.701293) (xy 109.072634 -232.743309) (xy 109.035911 -232.780032)
			(xy 108.993895 -232.810558) (xy 108.947621 -232.834136) (xy 108.898228 -232.850184) (xy 108.846933 -232.858309)
			(xy 108.794999 -232.858309) (xy 108.743704 -232.850184) (xy 108.694311 -232.834136) (xy 108.648037 -232.810558)
			(xy 108.606021 -232.780032) (xy 108.569298 -232.743309) (xy 108.538772 -232.701293) (xy 108.515194 -232.655019)
			(xy 108.499146 -232.605626) (xy 108.491021 -232.554331) (xy 108.211111 -232.554331) (xy 108.202986 -232.605626)
			(xy 108.186938 -232.655019) (xy 108.16336 -232.701293) (xy 108.132834 -232.743309) (xy 108.096111 -232.780032)
			(xy 108.054095 -232.810558) (xy 108.007821 -232.834136) (xy 107.958428 -232.850184) (xy 107.907133 -232.858309)
			(xy 107.855199 -232.858309) (xy 107.803904 -232.850184) (xy 107.754511 -232.834136) (xy 107.708237 -232.810558)
			(xy 107.666221 -232.780032) (xy 107.629498 -232.743309) (xy 107.598972 -232.701293) (xy 107.575394 -232.655019)
			(xy 107.559346 -232.605626) (xy 107.551221 -232.554331) (xy 107.271311 -232.554331) (xy 107.263186 -232.605626)
			(xy 107.247138 -232.655019) (xy 107.22356 -232.701293) (xy 107.193034 -232.743309) (xy 107.156311 -232.780032)
			(xy 107.114295 -232.810558) (xy 107.068021 -232.834136) (xy 107.018628 -232.850184) (xy 106.967333 -232.858309)
			(xy 106.915399 -232.858309) (xy 106.864104 -232.850184) (xy 106.814711 -232.834136) (xy 106.768437 -232.810558)
			(xy 106.726421 -232.780032) (xy 106.689698 -232.743309) (xy 106.659172 -232.701293) (xy 106.635594 -232.655019)
			(xy 106.619546 -232.605626) (xy 106.611421 -232.554331) (xy 106.331511 -232.554331) (xy 106.323386 -232.605626)
			(xy 106.307338 -232.655019) (xy 106.28376 -232.701293) (xy 106.253234 -232.743309) (xy 106.216511 -232.780032)
			(xy 106.174495 -232.810558) (xy 106.128221 -232.834136) (xy 106.078828 -232.850184) (xy 106.027533 -232.858309)
			(xy 105.975599 -232.858309) (xy 105.924304 -232.850184) (xy 105.874911 -232.834136) (xy 105.828637 -232.810558)
			(xy 105.786621 -232.780032) (xy 105.749898 -232.743309) (xy 105.719372 -232.701293) (xy 105.695794 -232.655019)
			(xy 105.679746 -232.605626) (xy 105.671621 -232.554331) (xy 105.391711 -232.554331) (xy 105.383586 -232.605626)
			(xy 105.367538 -232.655019) (xy 105.34396 -232.701293) (xy 105.313434 -232.743309) (xy 105.276711 -232.780032)
			(xy 105.234695 -232.810558) (xy 105.188421 -232.834136) (xy 105.139028 -232.850184) (xy 105.087733 -232.858309)
			(xy 105.035799 -232.858309) (xy 104.984504 -232.850184) (xy 104.935111 -232.834136) (xy 104.888837 -232.810558)
			(xy 104.846821 -232.780032) (xy 104.810098 -232.743309) (xy 104.779572 -232.701293) (xy 104.755994 -232.655019)
			(xy 104.739946 -232.605626) (xy 104.731821 -232.554331) (xy 104.451911 -232.554331) (xy 104.443786 -232.605626)
			(xy 104.427738 -232.655019) (xy 104.40416 -232.701293) (xy 104.373634 -232.743309) (xy 104.336911 -232.780032)
			(xy 104.294895 -232.810558) (xy 104.248621 -232.834136) (xy 104.199228 -232.850184) (xy 104.147933 -232.858309)
			(xy 104.095999 -232.858309) (xy 104.044704 -232.850184) (xy 103.995311 -232.834136) (xy 103.949037 -232.810558)
			(xy 103.907021 -232.780032) (xy 103.870298 -232.743309) (xy 103.839772 -232.701293) (xy 103.816194 -232.655019)
			(xy 103.800146 -232.605626) (xy 103.792021 -232.554331) (xy 103.512111 -232.554331) (xy 103.503986 -232.605626)
			(xy 103.487938 -232.655019) (xy 103.46436 -232.701293) (xy 103.433834 -232.743309) (xy 103.397111 -232.780032)
			(xy 103.355095 -232.810558) (xy 103.308821 -232.834136) (xy 103.259428 -232.850184) (xy 103.208133 -232.858309)
			(xy 103.156199 -232.858309) (xy 103.104904 -232.850184) (xy 103.055511 -232.834136) (xy 103.009237 -232.810558)
			(xy 102.967221 -232.780032) (xy 102.930498 -232.743309) (xy 102.899972 -232.701293) (xy 102.876394 -232.655019)
			(xy 102.860346 -232.605626) (xy 102.852221 -232.554331) (xy 102.68458 -232.554331) (xy 102.68458 -232.961688)
			(xy 102.68498 -232.971312) (xy 102.692071 -232.989205) (xy 102.705286 -233.003197) (xy 102.722746 -233.011297)
			(xy 102.732332 -233.012234) (xy 102.758526 -233.014356) (xy 102.809806 -233.025845) (xy 102.858622 -233.045302)
			(xy 102.903745 -233.072236) (xy 102.944039 -233.10597) (xy 102.978489 -233.145654) (xy 103.006227 -233.190288)
			(xy 103.026554 -233.238748) (xy 103.038959 -233.289814) (xy 103.043129 -233.342199) (xy 103.041064 -233.368147)
			(xy 103.321867 -233.368147) (xy 103.321867 -233.316213) (xy 103.329992 -233.264918) (xy 103.34604 -233.215525)
			(xy 103.369618 -233.169251) (xy 103.400144 -233.127235) (xy 103.436867 -233.090512) (xy 103.478883 -233.059986)
			(xy 103.525157 -233.036408) (xy 103.57455 -233.02036) (xy 103.625845 -233.012235) (xy 103.677779 -233.012235)
			(xy 103.729074 -233.02036) (xy 103.778467 -233.036408) (xy 103.824741 -233.059986) (xy 103.866757 -233.090512)
			(xy 103.90348 -233.127235) (xy 103.934006 -233.169251) (xy 103.957584 -233.215525) (xy 103.973632 -233.264918)
			(xy 103.981757 -233.316213) (xy 103.982266 -233.34218) (xy 103.981757 -233.368147) (xy 104.261921 -233.368147)
			(xy 104.261921 -233.316213) (xy 104.270046 -233.264918) (xy 104.286094 -233.215525) (xy 104.309672 -233.169251)
			(xy 104.340198 -233.127235) (xy 104.376921 -233.090512) (xy 104.418937 -233.059986) (xy 104.465211 -233.036408)
			(xy 104.514604 -233.02036) (xy 104.565899 -233.012235) (xy 104.617833 -233.012235) (xy 104.669128 -233.02036)
			(xy 104.718521 -233.036408) (xy 104.764795 -233.059986) (xy 104.806811 -233.090512) (xy 104.843534 -233.127235)
			(xy 104.87406 -233.169251) (xy 104.897638 -233.215525) (xy 104.913686 -233.264918) (xy 104.921811 -233.316213)
			(xy 104.92232 -233.34218) (xy 104.921811 -233.368147) (xy 105.201721 -233.368147) (xy 105.201721 -233.316213)
			(xy 105.209846 -233.264918) (xy 105.225894 -233.215525) (xy 105.249472 -233.169251) (xy 105.279998 -233.127235)
			(xy 105.316721 -233.090512) (xy 105.358737 -233.059986) (xy 105.405011 -233.036408) (xy 105.454404 -233.02036)
			(xy 105.505699 -233.012235) (xy 105.557633 -233.012235) (xy 105.608928 -233.02036) (xy 105.658321 -233.036408)
			(xy 105.704595 -233.059986) (xy 105.746611 -233.090512) (xy 105.783334 -233.127235) (xy 105.81386 -233.169251)
			(xy 105.837438 -233.215525) (xy 105.853486 -233.264918) (xy 105.861611 -233.316213) (xy 105.86212 -233.34218)
			(xy 105.861611 -233.368147) (xy 106.141267 -233.368147) (xy 106.141267 -233.316213) (xy 106.149392 -233.264918)
			(xy 106.16544 -233.215525) (xy 106.189018 -233.169251) (xy 106.219544 -233.127235) (xy 106.256267 -233.090512)
			(xy 106.298283 -233.059986) (xy 106.344557 -233.036408) (xy 106.39395 -233.02036) (xy 106.445245 -233.012235)
			(xy 106.497179 -233.012235) (xy 106.548474 -233.02036) (xy 106.597867 -233.036408) (xy 106.644141 -233.059986)
			(xy 106.686157 -233.090512) (xy 106.72288 -233.127235) (xy 106.753406 -233.169251) (xy 106.776984 -233.215525)
			(xy 106.793032 -233.264918) (xy 106.801157 -233.316213) (xy 106.801666 -233.34218) (xy 106.801157 -233.368147)
			(xy 107.081067 -233.368147) (xy 107.081067 -233.316213) (xy 107.089192 -233.264918) (xy 107.10524 -233.215525)
			(xy 107.128818 -233.169251) (xy 107.159344 -233.127235) (xy 107.196067 -233.090512) (xy 107.238083 -233.059986)
			(xy 107.284357 -233.036408) (xy 107.33375 -233.02036) (xy 107.385045 -233.012235) (xy 107.436979 -233.012235)
			(xy 107.488274 -233.02036) (xy 107.537667 -233.036408) (xy 107.583941 -233.059986) (xy 107.625957 -233.090512)
			(xy 107.66268 -233.127235) (xy 107.693206 -233.169251) (xy 107.716784 -233.215525) (xy 107.732832 -233.264918)
			(xy 107.740957 -233.316213) (xy 107.741466 -233.34218) (xy 107.740957 -233.368147) (xy 108.020867 -233.368147)
			(xy 108.020867 -233.316213) (xy 108.028992 -233.264918) (xy 108.04504 -233.215525) (xy 108.068618 -233.169251)
			(xy 108.099144 -233.127235) (xy 108.135867 -233.090512) (xy 108.177883 -233.059986) (xy 108.224157 -233.036408)
			(xy 108.27355 -233.02036) (xy 108.324845 -233.012235) (xy 108.376779 -233.012235) (xy 108.428074 -233.02036)
			(xy 108.477467 -233.036408) (xy 108.523741 -233.059986) (xy 108.565757 -233.090512) (xy 108.60248 -233.127235)
			(xy 108.633006 -233.169251) (xy 108.656584 -233.215525) (xy 108.672632 -233.264918) (xy 108.680757 -233.316213)
			(xy 108.681266 -233.34218) (xy 108.680757 -233.368147) (xy 108.960667 -233.368147) (xy 108.960667 -233.316213)
			(xy 108.968792 -233.264918) (xy 108.98484 -233.215525) (xy 109.008418 -233.169251) (xy 109.038944 -233.127235)
			(xy 109.075667 -233.090512) (xy 109.117683 -233.059986) (xy 109.163957 -233.036408) (xy 109.21335 -233.02036)
			(xy 109.264645 -233.012235) (xy 109.316579 -233.012235) (xy 109.367874 -233.02036) (xy 109.417267 -233.036408)
			(xy 109.463541 -233.059986) (xy 109.505557 -233.090512) (xy 109.54228 -233.127235) (xy 109.572806 -233.169251)
			(xy 109.596384 -233.215525) (xy 109.612432 -233.264918) (xy 109.620557 -233.316213) (xy 109.621066 -233.34218)
			(xy 109.620557 -233.368147) (xy 109.612432 -233.419442) (xy 109.596384 -233.468835) (xy 109.572806 -233.515109)
			(xy 109.54228 -233.557125) (xy 109.505557 -233.593848) (xy 109.463541 -233.624374) (xy 109.417267 -233.647952)
			(xy 109.367874 -233.664) (xy 109.316579 -233.672125) (xy 109.264645 -233.672125) (xy 109.21335 -233.664)
			(xy 109.163957 -233.647952) (xy 109.117683 -233.624374) (xy 109.075667 -233.593848) (xy 109.038944 -233.557125)
			(xy 109.008418 -233.515109) (xy 108.98484 -233.468835) (xy 108.968792 -233.419442) (xy 108.960667 -233.368147)
			(xy 108.680757 -233.368147) (xy 108.672632 -233.419442) (xy 108.656584 -233.468835) (xy 108.633006 -233.515109)
			(xy 108.60248 -233.557125) (xy 108.565757 -233.593848) (xy 108.523741 -233.624374) (xy 108.477467 -233.647952)
			(xy 108.428074 -233.664) (xy 108.376779 -233.672125) (xy 108.324845 -233.672125) (xy 108.27355 -233.664)
			(xy 108.224157 -233.647952) (xy 108.177883 -233.624374) (xy 108.135867 -233.593848) (xy 108.099144 -233.557125)
			(xy 108.068618 -233.515109) (xy 108.04504 -233.468835) (xy 108.028992 -233.419442) (xy 108.020867 -233.368147)
			(xy 107.740957 -233.368147) (xy 107.732832 -233.419442) (xy 107.716784 -233.468835) (xy 107.693206 -233.515109)
			(xy 107.66268 -233.557125) (xy 107.625957 -233.593848) (xy 107.583941 -233.624374) (xy 107.537667 -233.647952)
			(xy 107.488274 -233.664) (xy 107.436979 -233.672125) (xy 107.385045 -233.672125) (xy 107.33375 -233.664)
			(xy 107.284357 -233.647952) (xy 107.238083 -233.624374) (xy 107.196067 -233.593848) (xy 107.159344 -233.557125)
			(xy 107.128818 -233.515109) (xy 107.10524 -233.468835) (xy 107.089192 -233.419442) (xy 107.081067 -233.368147)
			(xy 106.801157 -233.368147) (xy 106.793032 -233.419442) (xy 106.776984 -233.468835) (xy 106.753406 -233.515109)
			(xy 106.72288 -233.557125) (xy 106.686157 -233.593848) (xy 106.644141 -233.624374) (xy 106.597867 -233.647952)
			(xy 106.548474 -233.664) (xy 106.497179 -233.672125) (xy 106.445245 -233.672125) (xy 106.39395 -233.664)
			(xy 106.344557 -233.647952) (xy 106.298283 -233.624374) (xy 106.256267 -233.593848) (xy 106.219544 -233.557125)
			(xy 106.189018 -233.515109) (xy 106.16544 -233.468835) (xy 106.149392 -233.419442) (xy 106.141267 -233.368147)
			(xy 105.861611 -233.368147) (xy 105.853486 -233.419442) (xy 105.837438 -233.468835) (xy 105.81386 -233.515109)
			(xy 105.783334 -233.557125) (xy 105.746611 -233.593848) (xy 105.704595 -233.624374) (xy 105.658321 -233.647952)
			(xy 105.608928 -233.664) (xy 105.557633 -233.672125) (xy 105.505699 -233.672125) (xy 105.454404 -233.664)
			(xy 105.405011 -233.647952) (xy 105.358737 -233.624374) (xy 105.316721 -233.593848) (xy 105.279998 -233.557125)
			(xy 105.249472 -233.515109) (xy 105.225894 -233.468835) (xy 105.209846 -233.419442) (xy 105.201721 -233.368147)
			(xy 104.921811 -233.368147) (xy 104.913686 -233.419442) (xy 104.897638 -233.468835) (xy 104.87406 -233.515109)
			(xy 104.843534 -233.557125) (xy 104.806811 -233.593848) (xy 104.764795 -233.624374) (xy 104.718521 -233.647952)
			(xy 104.669128 -233.664) (xy 104.617833 -233.672125) (xy 104.565899 -233.672125) (xy 104.514604 -233.664)
			(xy 104.465211 -233.647952) (xy 104.418937 -233.624374) (xy 104.376921 -233.593848) (xy 104.340198 -233.557125)
			(xy 104.309672 -233.515109) (xy 104.286094 -233.468835) (xy 104.270046 -233.419442) (xy 104.261921 -233.368147)
			(xy 103.981757 -233.368147) (xy 103.973632 -233.419442) (xy 103.957584 -233.468835) (xy 103.934006 -233.515109)
			(xy 103.90348 -233.557125) (xy 103.866757 -233.593848) (xy 103.824741 -233.624374) (xy 103.778467 -233.647952)
			(xy 103.729074 -233.664) (xy 103.677779 -233.672125) (xy 103.625845 -233.672125) (xy 103.57455 -233.664)
			(xy 103.525157 -233.647952) (xy 103.478883 -233.624374) (xy 103.436867 -233.593848) (xy 103.400144 -233.557125)
			(xy 103.369618 -233.515109) (xy 103.34604 -233.468835) (xy 103.329992 -233.419442) (xy 103.321867 -233.368147)
			(xy 103.041064 -233.368147) (xy 103.03896 -233.394584) (xy 103.026555 -233.44565) (xy 103.006228 -233.49411)
			(xy 102.97849 -233.538744) (xy 102.944041 -233.578428) (xy 102.903747 -233.612162) (xy 102.858624 -233.639097)
			(xy 102.809808 -233.658554) (xy 102.758529 -233.670044) (xy 102.732332 -233.672126) (xy 102.722768 -233.673128)
			(xy 102.705363 -233.681273) (xy 102.692159 -233.695235) (xy 102.684996 -233.713066) (xy 102.68458 -233.722672)
			(xy 102.68458 -234.182217) (xy 102.852221 -234.182217) (xy 102.852221 -234.130283) (xy 102.860346 -234.078988)
			(xy 102.876394 -234.029595) (xy 102.899972 -233.983321) (xy 102.930498 -233.941305) (xy 102.967221 -233.904582)
			(xy 103.009237 -233.874056) (xy 103.055511 -233.850478) (xy 103.104904 -233.83443) (xy 103.156199 -233.826305)
			(xy 103.208133 -233.826305) (xy 103.259428 -233.83443) (xy 103.308821 -233.850478) (xy 103.355095 -233.874056)
			(xy 103.397111 -233.904582) (xy 103.433834 -233.941305) (xy 103.46436 -233.983321) (xy 103.487938 -234.029595)
			(xy 103.503986 -234.078988) (xy 103.512111 -234.130283) (xy 103.51262 -234.15625) (xy 103.512111 -234.182217)
			(xy 103.792021 -234.182217) (xy 103.792021 -234.130283) (xy 103.800146 -234.078988) (xy 103.816194 -234.029595)
			(xy 103.839772 -233.983321) (xy 103.870298 -233.941305) (xy 103.907021 -233.904582) (xy 103.949037 -233.874056)
			(xy 103.995311 -233.850478) (xy 104.044704 -233.83443) (xy 104.095999 -233.826305) (xy 104.147933 -233.826305)
			(xy 104.199228 -233.83443) (xy 104.248621 -233.850478) (xy 104.294895 -233.874056) (xy 104.336911 -233.904582)
			(xy 104.373634 -233.941305) (xy 104.40416 -233.983321) (xy 104.427738 -234.029595) (xy 104.443786 -234.078988)
			(xy 104.451911 -234.130283) (xy 104.45242 -234.15625) (xy 104.451911 -234.182217) (xy 105.671621 -234.182217)
			(xy 105.671621 -234.130283) (xy 105.679746 -234.078988) (xy 105.695794 -234.029595) (xy 105.719372 -233.983321)
			(xy 105.749898 -233.941305) (xy 105.786621 -233.904582) (xy 105.828637 -233.874056) (xy 105.874911 -233.850478)
			(xy 105.924304 -233.83443) (xy 105.975599 -233.826305) (xy 106.027533 -233.826305) (xy 106.078828 -233.83443)
			(xy 106.128221 -233.850478) (xy 106.174495 -233.874056) (xy 106.216511 -233.904582) (xy 106.253234 -233.941305)
			(xy 106.28376 -233.983321) (xy 106.307338 -234.029595) (xy 106.323386 -234.078988) (xy 106.331511 -234.130283)
			(xy 106.33202 -234.15625) (xy 106.331511 -234.182217) (xy 106.611421 -234.182217) (xy 106.611421 -234.130283)
			(xy 106.619546 -234.078988) (xy 106.635594 -234.029595) (xy 106.659172 -233.983321) (xy 106.689698 -233.941305)
			(xy 106.726421 -233.904582) (xy 106.768437 -233.874056) (xy 106.814711 -233.850478) (xy 106.864104 -233.83443)
			(xy 106.915399 -233.826305) (xy 106.967333 -233.826305) (xy 107.018628 -233.83443) (xy 107.068021 -233.850478)
			(xy 107.114295 -233.874056) (xy 107.156311 -233.904582) (xy 107.193034 -233.941305) (xy 107.22356 -233.983321)
			(xy 107.247138 -234.029595) (xy 107.263186 -234.078988) (xy 107.271311 -234.130283) (xy 107.27182 -234.15625)
			(xy 107.271311 -234.182217) (xy 107.551221 -234.182217) (xy 107.551221 -234.130283) (xy 107.559346 -234.078988)
			(xy 107.575394 -234.029595) (xy 107.598972 -233.983321) (xy 107.629498 -233.941305) (xy 107.666221 -233.904582)
			(xy 107.708237 -233.874056) (xy 107.754511 -233.850478) (xy 107.803904 -233.83443) (xy 107.855199 -233.826305)
			(xy 107.907133 -233.826305) (xy 107.958428 -233.83443) (xy 108.007821 -233.850478) (xy 108.054095 -233.874056)
			(xy 108.096111 -233.904582) (xy 108.132834 -233.941305) (xy 108.16336 -233.983321) (xy 108.186938 -234.029595)
			(xy 108.202986 -234.078988) (xy 108.211111 -234.130283) (xy 108.21162 -234.15625) (xy 108.211111 -234.182217)
			(xy 108.491021 -234.182217) (xy 108.491021 -234.130283) (xy 108.499146 -234.078988) (xy 108.515194 -234.029595)
			(xy 108.538772 -233.983321) (xy 108.569298 -233.941305) (xy 108.606021 -233.904582) (xy 108.648037 -233.874056)
			(xy 108.694311 -233.850478) (xy 108.743704 -233.83443) (xy 108.794999 -233.826305) (xy 108.846933 -233.826305)
			(xy 108.898228 -233.83443) (xy 108.947621 -233.850478) (xy 108.993895 -233.874056) (xy 109.035911 -233.904582)
			(xy 109.072634 -233.941305) (xy 109.10316 -233.983321) (xy 109.126738 -234.029595) (xy 109.142786 -234.078988)
			(xy 109.150911 -234.130283) (xy 109.15142 -234.15625) (xy 109.150911 -234.182217) (xy 109.142786 -234.233512)
			(xy 109.126738 -234.282905) (xy 109.10316 -234.329179) (xy 109.072634 -234.371195) (xy 109.035911 -234.407918)
			(xy 108.993895 -234.438444) (xy 108.947621 -234.462022) (xy 108.898228 -234.47807) (xy 108.846933 -234.486195)
			(xy 108.794999 -234.486195) (xy 108.743704 -234.47807) (xy 108.694311 -234.462022) (xy 108.648037 -234.438444)
			(xy 108.606021 -234.407918) (xy 108.569298 -234.371195) (xy 108.538772 -234.329179) (xy 108.515194 -234.282905)
			(xy 108.499146 -234.233512) (xy 108.491021 -234.182217) (xy 108.211111 -234.182217) (xy 108.202986 -234.233512)
			(xy 108.186938 -234.282905) (xy 108.16336 -234.329179) (xy 108.132834 -234.371195) (xy 108.096111 -234.407918)
			(xy 108.054095 -234.438444) (xy 108.007821 -234.462022) (xy 107.958428 -234.47807) (xy 107.907133 -234.486195)
			(xy 107.855199 -234.486195) (xy 107.803904 -234.47807) (xy 107.754511 -234.462022) (xy 107.708237 -234.438444)
			(xy 107.666221 -234.407918) (xy 107.629498 -234.371195) (xy 107.598972 -234.329179) (xy 107.575394 -234.282905)
			(xy 107.559346 -234.233512) (xy 107.551221 -234.182217) (xy 107.271311 -234.182217) (xy 107.263186 -234.233512)
			(xy 107.247138 -234.282905) (xy 107.22356 -234.329179) (xy 107.193034 -234.371195) (xy 107.156311 -234.407918)
			(xy 107.114295 -234.438444) (xy 107.068021 -234.462022) (xy 107.018628 -234.47807) (xy 106.967333 -234.486195)
			(xy 106.915399 -234.486195) (xy 106.864104 -234.47807) (xy 106.814711 -234.462022) (xy 106.768437 -234.438444)
			(xy 106.726421 -234.407918) (xy 106.689698 -234.371195) (xy 106.659172 -234.329179) (xy 106.635594 -234.282905)
			(xy 106.619546 -234.233512) (xy 106.611421 -234.182217) (xy 106.331511 -234.182217) (xy 106.323386 -234.233512)
			(xy 106.307338 -234.282905) (xy 106.28376 -234.329179) (xy 106.253234 -234.371195) (xy 106.216511 -234.407918)
			(xy 106.174495 -234.438444) (xy 106.128221 -234.462022) (xy 106.078828 -234.47807) (xy 106.027533 -234.486195)
			(xy 105.975599 -234.486195) (xy 105.924304 -234.47807) (xy 105.874911 -234.462022) (xy 105.828637 -234.438444)
			(xy 105.786621 -234.407918) (xy 105.749898 -234.371195) (xy 105.719372 -234.329179) (xy 105.695794 -234.282905)
			(xy 105.679746 -234.233512) (xy 105.671621 -234.182217) (xy 104.451911 -234.182217) (xy 104.443786 -234.233512)
			(xy 104.427738 -234.282905) (xy 104.40416 -234.329179) (xy 104.373634 -234.371195) (xy 104.336911 -234.407918)
			(xy 104.294895 -234.438444) (xy 104.248621 -234.462022) (xy 104.199228 -234.47807) (xy 104.147933 -234.486195)
			(xy 104.095999 -234.486195) (xy 104.044704 -234.47807) (xy 103.995311 -234.462022) (xy 103.949037 -234.438444)
			(xy 103.907021 -234.407918) (xy 103.870298 -234.371195) (xy 103.839772 -234.329179) (xy 103.816194 -234.282905)
			(xy 103.800146 -234.233512) (xy 103.792021 -234.182217) (xy 103.512111 -234.182217) (xy 103.503986 -234.233512)
			(xy 103.487938 -234.282905) (xy 103.46436 -234.329179) (xy 103.433834 -234.371195) (xy 103.397111 -234.407918)
			(xy 103.355095 -234.438444) (xy 103.308821 -234.462022) (xy 103.259428 -234.47807) (xy 103.208133 -234.486195)
			(xy 103.156199 -234.486195) (xy 103.104904 -234.47807) (xy 103.055511 -234.462022) (xy 103.009237 -234.438444)
			(xy 102.967221 -234.407918) (xy 102.930498 -234.371195) (xy 102.899972 -234.329179) (xy 102.876394 -234.282905)
			(xy 102.860346 -234.233512) (xy 102.852221 -234.182217) (xy 102.68458 -234.182217) (xy 102.68458 -235.043023)
			(xy 104.285543 -235.043023) (xy 104.285543 -234.991089) (xy 104.293668 -234.939794) (xy 104.309716 -234.890401)
			(xy 104.333294 -234.844127) (xy 104.36382 -234.802111) (xy 104.400543 -234.765388) (xy 104.442559 -234.734862)
			(xy 104.488833 -234.711284) (xy 104.538226 -234.695236) (xy 104.589521 -234.687111) (xy 104.641455 -234.687111)
			(xy 104.69275 -234.695236) (xy 104.742143 -234.711284) (xy 104.788417 -234.734862) (xy 104.830433 -234.765388)
			(xy 104.867156 -234.802111) (xy 104.897682 -234.844127) (xy 104.92126 -234.890401) (xy 104.937308 -234.939794)
			(xy 104.945433 -234.991089) (xy 104.94553 -234.996033) (xy 108.960921 -234.996033) (xy 108.960921 -234.944099)
			(xy 108.969046 -234.892804) (xy 108.985094 -234.843411) (xy 109.008672 -234.797137) (xy 109.039198 -234.755121)
			(xy 109.075921 -234.718398) (xy 109.117937 -234.687872) (xy 109.164211 -234.664294) (xy 109.213604 -234.648246)
			(xy 109.264899 -234.640121) (xy 109.316833 -234.640121) (xy 109.368128 -234.648246) (xy 109.417521 -234.664294)
			(xy 109.463795 -234.687872) (xy 109.505811 -234.718398) (xy 109.542534 -234.755121) (xy 109.57306 -234.797137)
			(xy 109.596638 -234.843411) (xy 109.612686 -234.892804) (xy 109.620811 -234.944099) (xy 109.62132 -234.970066)
			(xy 109.620811 -234.996033) (xy 109.612686 -235.047328) (xy 109.596638 -235.096721) (xy 109.57306 -235.142995)
			(xy 109.542534 -235.185011) (xy 109.505811 -235.221734) (xy 109.463795 -235.25226) (xy 109.417521 -235.275838)
			(xy 109.368128 -235.291886) (xy 109.316833 -235.300011) (xy 109.264899 -235.300011) (xy 109.213604 -235.291886)
			(xy 109.164211 -235.275838) (xy 109.117937 -235.25226) (xy 109.075921 -235.221734) (xy 109.039198 -235.185011)
			(xy 109.008672 -235.142995) (xy 108.985094 -235.096721) (xy 108.969046 -235.047328) (xy 108.960921 -234.996033)
			(xy 104.94553 -234.996033) (xy 104.945942 -235.017056) (xy 104.945433 -235.043023) (xy 104.937308 -235.094318)
			(xy 104.92126 -235.143711) (xy 104.897682 -235.189985) (xy 104.867156 -235.232001) (xy 104.830433 -235.268724)
			(xy 104.788417 -235.29925) (xy 104.742143 -235.322828) (xy 104.69275 -235.338876) (xy 104.641455 -235.347001)
			(xy 104.589521 -235.347001) (xy 104.538226 -235.338876) (xy 104.488833 -235.322828) (xy 104.442559 -235.29925)
			(xy 104.400543 -235.268724) (xy 104.36382 -235.232001) (xy 104.333294 -235.189985) (xy 104.309716 -235.143711)
			(xy 104.293668 -235.094318) (xy 104.285543 -235.043023) (xy 102.68458 -235.043023) (xy 102.68458 -235.457551)
			(xy 105.900221 -235.457551) (xy 105.900221 -235.405617) (xy 105.908346 -235.354322) (xy 105.924394 -235.304929)
			(xy 105.947972 -235.258655) (xy 105.978498 -235.216639) (xy 106.015221 -235.179916) (xy 106.057237 -235.14939)
			(xy 106.103511 -235.125812) (xy 106.152904 -235.109764) (xy 106.204199 -235.101639) (xy 106.256133 -235.101639)
			(xy 106.307428 -235.109764) (xy 106.356821 -235.125812) (xy 106.403095 -235.14939) (xy 106.445111 -235.179916)
			(xy 106.481834 -235.216639) (xy 106.51236 -235.258655) (xy 106.535938 -235.304929) (xy 106.551986 -235.354322)
			(xy 106.560111 -235.405617) (xy 106.56062 -235.431584) (xy 106.560111 -235.457551) (xy 106.551986 -235.508846)
			(xy 106.535938 -235.558239) (xy 106.51236 -235.604513) (xy 106.481834 -235.646529) (xy 106.445111 -235.683252)
			(xy 106.403095 -235.713778) (xy 106.356821 -235.737356) (xy 106.307428 -235.753404) (xy 106.256133 -235.761529)
			(xy 106.204199 -235.761529) (xy 106.152904 -235.753404) (xy 106.103511 -235.737356) (xy 106.057237 -235.713778)
			(xy 106.015221 -235.683252) (xy 105.978498 -235.646529) (xy 105.947972 -235.604513) (xy 105.924394 -235.558239)
			(xy 105.908346 -235.508846) (xy 105.900221 -235.457551) (xy 102.68458 -235.457551) (xy 102.68458 -236.005116)
			(xy 102.685149 -236.020344) (xy 102.694129 -236.049445) (xy 102.711285 -236.074608) (xy 102.735095 -236.093598)
			(xy 102.763444 -236.104728) (xy 102.793814 -236.10701) (xy 102.808786 -236.104176) (xy 102.812596 -236.10316)
			(xy 102.826366 -236.099736) (xy 102.851394 -236.086393) (xy 102.871777 -236.06667) (xy 102.885935 -236.042094)
			(xy 102.892772 -236.014567) (xy 102.891759 -235.986223) (xy 102.88778 -235.972604) (xy 102.88031 -235.94787)
			(xy 102.872266 -235.896836) (xy 102.871778 -235.871004) (xy 102.872261 -235.845035) (xy 102.880385 -235.793738)
			(xy 102.896435 -235.744343) (xy 102.920015 -235.698067) (xy 102.950544 -235.65605) (xy 102.987271 -235.619326)
			(xy 103.029291 -235.5888) (xy 103.075569 -235.565224) (xy 103.124965 -235.549179) (xy 103.176263 -235.541058)
			(xy 103.202232 -235.54055) (xy 103.228613 -235.541067) (xy 103.280706 -235.549451) (xy 103.330806 -235.566002)
			(xy 103.377642 -235.590299) (xy 103.420025 -235.621725) (xy 103.456879 -235.659483) (xy 103.472488 -235.680758)
			(xy 103.481701 -235.692846) (xy 103.505738 -235.711418) (xy 103.534178 -235.72209) (xy 103.5645 -235.723915)
			(xy 103.594014 -235.716731) (xy 103.607362 -235.70946) (xy 103.633152 -235.694892) (xy 103.688632 -235.674167)
			(xy 103.746913 -235.663639) (xy 103.776526 -235.662978) (xy 103.802489 -235.663489) (xy 103.853776 -235.671616)
			(xy 103.903161 -235.687665) (xy 103.949426 -235.711242) (xy 103.991435 -235.741766) (xy 104.028151 -235.778485)
			(xy 104.058672 -235.820496) (xy 104.082245 -235.866763) (xy 104.09829 -235.916149) (xy 104.106413 -235.967437)
			(xy 104.106413 -236.019363) (xy 104.09829 -236.070651) (xy 104.082245 -236.120037) (xy 104.058672 -236.166304)
			(xy 104.028151 -236.208315) (xy 103.991435 -236.245034) (xy 103.949426 -236.275558) (xy 103.903161 -236.299135)
			(xy 103.853776 -236.315184) (xy 103.802489 -236.323311) (xy 103.776526 -236.323886) (xy 103.750146 -236.323366)
			(xy 103.698056 -236.314977) (xy 103.647959 -236.298423) (xy 103.601127 -236.274124) (xy 103.558746 -236.242698)
			(xy 103.521894 -236.204941) (xy 103.50627 -236.183678) (xy 103.497054 -236.171589) (xy 103.473013 -236.153013)
			(xy 103.444571 -236.142334) (xy 103.414245 -236.140496) (xy 103.384721 -236.147663) (xy 103.371396 -236.154976)
			(xy 103.348036 -236.168284) (xy 103.298 -236.187943) (xy 103.271828 -236.194092) (xy 103.25806 -236.197515)
			(xy 103.233035 -236.210855) (xy 103.212657 -236.230577) (xy 103.198507 -236.255153) (xy 103.19168 -236.282678)
			(xy 103.192705 -236.311018) (xy 103.196644 -236.324648) (xy 103.204112 -236.349382) (xy 103.21215 -236.400416)
			(xy 103.212646 -236.426248) (xy 103.212115 -236.452802) (xy 103.203626 -236.505228) (xy 103.186874 -236.555625)
			(xy 103.175054 -236.57941) (xy 103.168619 -236.592866) (xy 103.163045 -236.622154) (xy 103.166167 -236.651804)
			(xy 103.177716 -236.679289) (xy 103.196711 -236.702269) (xy 103.221531 -236.718785) (xy 103.250064 -236.72743)
			(xy 103.26497 -236.728)
		)
		(stroke
			(width 0)
			(type solid)
		)
		(fill yes)
		(layer "In11.Cu")
		(net "PVNN_MAIN_CPU1")
	)
	(gr_poly
		(pts
			(xy 469.65108 -76.647548) (xy 469.65108 -55.926228) (xy 460.8322 -47.107348) (xy 441.005214 -47.107348)
			(xy 440.990736 -47.134272) (xy 440.977411 -47.158418) (xy 440.944869 -47.202943) (xy 440.906253 -47.242315)
			(xy 440.862367 -47.275714) (xy 440.814127 -47.302442) (xy 440.762541 -47.321942) (xy 440.708683 -47.333807)
			(xy 440.653678 -47.33779) (xy 440.598673 -47.333807) (xy 440.544815 -47.321942) (xy 440.493229 -47.302442)
			(xy 440.444989 -47.275714) (xy 440.401103 -47.242315) (xy 440.362487 -47.202943) (xy 440.329945 -47.158418)
			(xy 440.31662 -47.134272) (xy 440.302142 -47.107348) (xy 438.084976 -47.107348) (xy 438.07987 -47.133992)
			(xy 438.063196 -47.185614) (xy 438.039492 -47.234411) (xy 438.009221 -47.279429) (xy 437.972973 -47.319791)
			(xy 437.931456 -47.354709) (xy 437.885479 -47.383503) (xy 437.835938 -47.40561) (xy 437.783801 -47.4206)
			(xy 437.730084 -47.42818) (xy 437.70296 -47.428658) (xy 437.675832 -47.428208) (xy 437.622104 -47.420651)
			(xy 437.569954 -47.405675) (xy 437.520403 -47.383575) (xy 437.474417 -47.354781) (xy 437.432895 -47.319855)
			(xy 437.39665 -47.279481) (xy 437.366388 -47.234448) (xy 437.342701 -47.185635) (xy 437.326052 -47.133995)
			(xy 437.320944 -47.107348) (xy 435.4322 -47.107348) (xy 433.96154 -48.578008) (xy 436.577232 -48.578008)
			(xy 436.577787 -48.549327) (xy 436.586396 -48.492615) (xy 436.603391 -48.437828) (xy 436.62839 -48.3862)
			(xy 436.66083 -48.338892) (xy 436.699982 -48.296969) (xy 436.744964 -48.261374) (xy 436.794764 -48.232907)
			(xy 436.848262 -48.212211) (xy 436.904254 -48.199749) (xy 436.932832 -48.197262) (xy 436.947352 -48.195752)
			(xy 436.974693 -48.18556) (xy 436.998039 -48.168055) (xy 437.015484 -48.144666) (xy 437.025607 -48.117298)
			(xy 437.027066 -48.102774) (xy 437.029521 -48.074186) (xy 437.041948 -48.018171) (xy 437.062623 -47.964649)
			(xy 437.091079 -47.914826) (xy 437.126675 -47.869826) (xy 437.168609 -47.830663) (xy 437.215933 -47.798221)
			(xy 437.267582 -47.773231) (xy 437.322391 -47.756258) (xy 437.379123 -47.747683) (xy 437.407812 -47.747174)
			(xy 437.435063 -47.747667) (xy 437.489009 -47.755424) (xy 437.541303 -47.77078) (xy 437.590879 -47.793421)
			(xy 437.636728 -47.822887) (xy 437.677918 -47.858578) (xy 437.713609 -47.899767) (xy 437.743076 -47.945616)
			(xy 437.765718 -47.995192) (xy 437.781074 -48.047485) (xy 437.788833 -48.101431) (xy 437.78932 -48.128682)
			(xy 437.7888 -48.157365) (xy 437.780192 -48.214081) (xy 437.763195 -48.268871) (xy 437.738194 -48.320502)
			(xy 437.70575 -48.367812) (xy 437.666594 -48.409736) (xy 437.621606 -48.445331) (xy 437.574339 -48.472344)
			(xy 445.193418 -48.472344) (xy 445.197489 -48.416722) (xy 445.209615 -48.362285) (xy 445.229538 -48.310194)
			(xy 445.256834 -48.261559) (xy 445.29092 -48.217416) (xy 445.331069 -48.178707) (xy 445.376427 -48.146256)
			(xy 445.426027 -48.120755) (xy 445.478811 -48.102748) (xy 445.533654 -48.092618) (xy 445.589388 -48.090581)
			(xy 445.644825 -48.096681) (xy 445.698782 -48.110787) (xy 445.750111 -48.132599) (xy 445.797717 -48.161653)
			(xy 445.840585 -48.197328) (xy 445.877802 -48.238865) (xy 445.908575 -48.285378) (xy 445.932247 -48.335875)
			(xy 445.948315 -48.389282) (xy 445.956435 -48.444458) (xy 445.956944 -48.472344) (xy 445.956435 -48.50023)
			(xy 445.948315 -48.555406) (xy 445.932247 -48.608813) (xy 445.908575 -48.65931) (xy 445.877802 -48.705823)
			(xy 445.840585 -48.74736) (xy 445.797717 -48.783035) (xy 445.750111 -48.812089) (xy 445.698782 -48.833901)
			(xy 445.644825 -48.848007) (xy 445.589388 -48.854107) (xy 445.533654 -48.85207) (xy 445.478811 -48.84194)
			(xy 445.426027 -48.823933) (xy 445.376427 -48.798432) (xy 445.331069 -48.765981) (xy 445.29092 -48.727272)
			(xy 445.256834 -48.683129) (xy 445.229538 -48.634494) (xy 445.209615 -48.582403) (xy 445.197489 -48.527966)
			(xy 445.193418 -48.472344) (xy 437.574339 -48.472344) (xy 437.5718 -48.473795) (xy 437.518297 -48.494488)
			(xy 437.4623 -48.506944) (xy 437.43372 -48.509428) (xy 437.419197 -48.510909) (xy 437.391856 -48.521112)
			(xy 437.368513 -48.538625) (xy 437.351069 -48.56202) (xy 437.340946 -48.58939) (xy 437.339486 -48.603916)
			(xy 437.336971 -48.632497) (xy 437.324548 -48.688507) (xy 437.303878 -48.742026) (xy 437.275428 -48.791846)
			(xy 437.239838 -48.836845) (xy 437.197912 -48.876008) (xy 437.150595 -48.908451) (xy 437.098954 -48.933444)
			(xy 437.044152 -48.950422) (xy 436.987426 -48.959004) (xy 436.95874 -48.959516) (xy 436.931488 -48.959008)
			(xy 436.87754 -48.951256) (xy 436.825243 -48.935906) (xy 436.775664 -48.913268) (xy 436.729811 -48.883805)
			(xy 436.688618 -48.848116) (xy 436.652924 -48.806928) (xy 436.623455 -48.761079) (xy 436.600811 -48.711502)
			(xy 436.585454 -48.659207) (xy 436.577696 -48.605259) (xy 436.577232 -48.578008) (xy 433.96154 -48.578008)
			(xy 433.063142 -49.476406) (xy 448.662047 -49.476406) (xy 448.666083 -49.392959) (xy 448.678155 -49.310291)
			(xy 448.698148 -49.229174) (xy 448.725877 -49.150365) (xy 448.761083 -49.0746) (xy 448.803437 -49.002587)
			(xy 448.852543 -48.934998) (xy 448.907944 -48.872464) (xy 448.969121 -48.815569) (xy 449.035504 -48.764843)
			(xy 449.106472 -48.720762) (xy 449.181364 -48.683736) (xy 449.25948 -48.65411) (xy 449.34009 -48.632162)
			(xy 449.422442 -48.618097) (xy 449.505768 -48.612045) (xy 449.589288 -48.614064) (xy 449.672224 -48.624134)
			(xy 449.7538 -48.642162) (xy 449.833256 -48.667979) (xy 449.909849 -48.701344) (xy 449.982865 -48.741945)
			(xy 450.051621 -48.789404) (xy 450.115475 -48.843277) (xy 450.173832 -48.903062) (xy 450.226147 -48.968199)
			(xy 450.27193 -49.038082) (xy 450.310755 -49.112057) (xy 450.34226 -49.189434) (xy 450.366149 -49.269491)
			(xy 450.3822 -49.351479) (xy 450.390263 -49.434634) (xy 450.390768 -49.476406) (xy 456.170287 -49.476406)
			(xy 456.174323 -49.392959) (xy 456.186395 -49.310291) (xy 456.206388 -49.229174) (xy 456.234117 -49.150365)
			(xy 456.269323 -49.0746) (xy 456.311677 -49.002587) (xy 456.360783 -48.934998) (xy 456.416184 -48.872464)
			(xy 456.477361 -48.815569) (xy 456.543744 -48.764843) (xy 456.614712 -48.720762) (xy 456.689604 -48.683736)
			(xy 456.76772 -48.65411) (xy 456.84833 -48.632162) (xy 456.930682 -48.618097) (xy 457.014008 -48.612045)
			(xy 457.097528 -48.614064) (xy 457.180464 -48.624134) (xy 457.26204 -48.642162) (xy 457.341496 -48.667979)
			(xy 457.418089 -48.701344) (xy 457.491105 -48.741945) (xy 457.559861 -48.789404) (xy 457.623715 -48.843277)
			(xy 457.682072 -48.903062) (xy 457.734387 -48.968199) (xy 457.78017 -49.038082) (xy 457.818995 -49.112057)
			(xy 457.8505 -49.189434) (xy 457.874389 -49.269491) (xy 457.89044 -49.351479) (xy 457.898503 -49.434634)
			(xy 457.899008 -49.476406) (xy 457.898503 -49.518178) (xy 457.89044 -49.601333) (xy 457.874389 -49.683321)
			(xy 457.8505 -49.763378) (xy 457.818995 -49.840755) (xy 457.78017 -49.91473) (xy 457.734387 -49.984613)
			(xy 457.682072 -50.04975) (xy 457.623715 -50.109535) (xy 457.559861 -50.163408) (xy 457.491105 -50.210867)
			(xy 457.418089 -50.251468) (xy 457.341496 -50.284833) (xy 457.26204 -50.31065) (xy 457.180464 -50.328678)
			(xy 457.097528 -50.338748) (xy 457.014008 -50.340767) (xy 456.930682 -50.334715) (xy 456.84833 -50.32065)
			(xy 456.76772 -50.298702) (xy 456.689604 -50.269076) (xy 456.614712 -50.23205) (xy 456.543744 -50.187969)
			(xy 456.477361 -50.137243) (xy 456.416184 -50.080348) (xy 456.360783 -50.017814) (xy 456.311677 -49.950225)
			(xy 456.269323 -49.878212) (xy 456.234117 -49.802447) (xy 456.206388 -49.723638) (xy 456.186395 -49.642521)
			(xy 456.174323 -49.559853) (xy 456.170287 -49.476406) (xy 450.390768 -49.476406) (xy 450.390263 -49.518178)
			(xy 450.3822 -49.601333) (xy 450.366149 -49.683321) (xy 450.34226 -49.763378) (xy 450.310755 -49.840755)
			(xy 450.27193 -49.91473) (xy 450.226147 -49.984613) (xy 450.173832 -50.04975) (xy 450.115475 -50.109535)
			(xy 450.051621 -50.163408) (xy 449.982865 -50.210867) (xy 449.909849 -50.251468) (xy 449.833256 -50.284833)
			(xy 449.7538 -50.31065) (xy 449.672224 -50.328678) (xy 449.589288 -50.338748) (xy 449.505768 -50.340767)
			(xy 449.422442 -50.334715) (xy 449.34009 -50.32065) (xy 449.25948 -50.298702) (xy 449.181364 -50.269076)
			(xy 449.106472 -50.23205) (xy 449.035504 -50.187969) (xy 448.969121 -50.137243) (xy 448.907944 -50.080348)
			(xy 448.852543 -50.017814) (xy 448.803437 -49.950225) (xy 448.761083 -49.878212) (xy 448.725877 -49.802447)
			(xy 448.698148 -49.723638) (xy 448.678155 -49.642521) (xy 448.666083 -49.559853) (xy 448.662047 -49.476406)
			(xy 433.063142 -49.476406) (xy 430.525428 -52.01412) (xy 432.050442 -52.01412) (xy 432.054513 -51.958498)
			(xy 432.066639 -51.904061) (xy 432.086562 -51.85197) (xy 432.113858 -51.803335) (xy 432.147944 -51.759192)
			(xy 432.188093 -51.720483) (xy 432.233451 -51.688032) (xy 432.283051 -51.662531) (xy 432.335835 -51.644524)
			(xy 432.390678 -51.634394) (xy 432.446412 -51.632357) (xy 432.501849 -51.638457) (xy 432.555806 -51.652563)
			(xy 432.607135 -51.674375) (xy 432.654741 -51.703429) (xy 432.697609 -51.739104) (xy 432.734826 -51.780641)
			(xy 432.765599 -51.827154) (xy 432.789271 -51.877651) (xy 432.805339 -51.931058) (xy 432.813459 -51.986234)
			(xy 432.813968 -52.01412) (xy 432.813881 -52.018876) (xy 448.637656 -52.018876) (xy 448.637656 -51.93418)
			(xy 448.645707 -51.849866) (xy 448.661736 -51.7667) (xy 448.685597 -51.685433) (xy 448.717076 -51.606803)
			(xy 448.755887 -51.531522) (xy 448.801677 -51.46027) (xy 448.854033 -51.393694) (xy 448.912481 -51.332396)
			(xy 448.976491 -51.276931) (xy 449.045483 -51.227802) (xy 449.118833 -51.185453) (xy 449.195876 -51.150269)
			(xy 449.275915 -51.122567) (xy 449.358224 -51.102599) (xy 449.442059 -51.090546) (xy 449.52666 -51.086516)
			(xy 449.611261 -51.090546) (xy 449.695096 -51.102599) (xy 449.777405 -51.122567) (xy 449.857444 -51.150269)
			(xy 449.934487 -51.185453) (xy 450.007837 -51.227802) (xy 450.076829 -51.276931) (xy 450.140839 -51.332396)
			(xy 450.199287 -51.393694) (xy 450.251643 -51.46027) (xy 450.297433 -51.531522) (xy 450.336244 -51.606803)
			(xy 450.367723 -51.685433) (xy 450.391584 -51.7667) (xy 450.407613 -51.849866) (xy 450.415664 -51.93418)
			(xy 450.416168 -51.976528) (xy 450.415664 -52.018876) (xy 456.145896 -52.018876) (xy 456.145896 -51.93418)
			(xy 456.153947 -51.849866) (xy 456.169976 -51.7667) (xy 456.193837 -51.685433) (xy 456.225316 -51.606803)
			(xy 456.264127 -51.531522) (xy 456.309917 -51.46027) (xy 456.362273 -51.393694) (xy 456.420721 -51.332396)
			(xy 456.484731 -51.276931) (xy 456.553723 -51.227802) (xy 456.627073 -51.185453) (xy 456.704116 -51.150269)
			(xy 456.784155 -51.122567) (xy 456.866464 -51.102599) (xy 456.950299 -51.090546) (xy 457.0349 -51.086516)
			(xy 457.119501 -51.090546) (xy 457.203336 -51.102599) (xy 457.285645 -51.122567) (xy 457.365684 -51.150269)
			(xy 457.442727 -51.185453) (xy 457.516077 -51.227802) (xy 457.585069 -51.276931) (xy 457.649079 -51.332396)
			(xy 457.707527 -51.393694) (xy 457.759883 -51.46027) (xy 457.805673 -51.531522) (xy 457.844484 -51.606803)
			(xy 457.875963 -51.685433) (xy 457.899824 -51.7667) (xy 457.915853 -51.849866) (xy 457.923904 -51.93418)
			(xy 457.924408 -51.976528) (xy 457.923904 -52.018876) (xy 457.915853 -52.10319) (xy 457.899824 -52.186356)
			(xy 457.875963 -52.267623) (xy 457.844484 -52.346253) (xy 457.805673 -52.421534) (xy 457.759883 -52.492786)
			(xy 457.707527 -52.559362) (xy 457.649079 -52.62066) (xy 457.585069 -52.676125) (xy 457.516077 -52.725254)
			(xy 457.442727 -52.767603) (xy 457.365684 -52.802787) (xy 457.285645 -52.830489) (xy 457.203336 -52.850457)
			(xy 457.119501 -52.86251) (xy 457.0349 -52.866541) (xy 456.950299 -52.86251) (xy 456.866464 -52.850457)
			(xy 456.784155 -52.830489) (xy 456.704116 -52.802787) (xy 456.627073 -52.767603) (xy 456.553723 -52.725254)
			(xy 456.484731 -52.676125) (xy 456.420721 -52.62066) (xy 456.362273 -52.559362) (xy 456.309917 -52.492786)
			(xy 456.264127 -52.421534) (xy 456.225316 -52.346253) (xy 456.193837 -52.267623) (xy 456.169976 -52.186356)
			(xy 456.153947 -52.10319) (xy 456.145896 -52.018876) (xy 450.415664 -52.018876) (xy 450.407613 -52.10319)
			(xy 450.391584 -52.186356) (xy 450.367723 -52.267623) (xy 450.336244 -52.346253) (xy 450.297433 -52.421534)
			(xy 450.251643 -52.492786) (xy 450.199287 -52.559362) (xy 450.140839 -52.62066) (xy 450.076829 -52.676125)
			(xy 450.007837 -52.725254) (xy 449.934487 -52.767603) (xy 449.857444 -52.802787) (xy 449.777405 -52.830489)
			(xy 449.695096 -52.850457) (xy 449.611261 -52.86251) (xy 449.52666 -52.866541) (xy 449.442059 -52.86251)
			(xy 449.358224 -52.850457) (xy 449.275915 -52.830489) (xy 449.195876 -52.802787) (xy 449.118833 -52.767603)
			(xy 449.045483 -52.725254) (xy 448.976491 -52.676125) (xy 448.912481 -52.62066) (xy 448.854033 -52.559362)
			(xy 448.801677 -52.492786) (xy 448.755887 -52.421534) (xy 448.717076 -52.346253) (xy 448.685597 -52.267623)
			(xy 448.661736 -52.186356) (xy 448.645707 -52.10319) (xy 448.637656 -52.018876) (xy 432.813881 -52.018876)
			(xy 432.813459 -52.042006) (xy 432.805339 -52.097182) (xy 432.789271 -52.150589) (xy 432.765599 -52.201086)
			(xy 432.734826 -52.247599) (xy 432.697609 -52.289136) (xy 432.654741 -52.324811) (xy 432.607135 -52.353865)
			(xy 432.555806 -52.375677) (xy 432.501849 -52.389783) (xy 432.446412 -52.395883) (xy 432.390678 -52.393846)
			(xy 432.335835 -52.383716) (xy 432.283051 -52.365709) (xy 432.233451 -52.340208) (xy 432.188093 -52.307757)
			(xy 432.147944 -52.269048) (xy 432.113858 -52.224905) (xy 432.086562 -52.17627) (xy 432.066639 -52.124179)
			(xy 432.054513 -52.069742) (xy 432.050442 -52.01412) (xy 430.525428 -52.01412) (xy 429.38446 -53.155088)
			(xy 429.38446 -54.534816) (xy 429.758856 -54.534816) (xy 429.759318 -54.507445) (xy 429.767135 -54.453266)
			(xy 429.782624 -54.400762) (xy 429.805467 -54.351015) (xy 429.835194 -54.305049) (xy 429.852836 -54.284118)
			(xy 429.862055 -54.272778) (xy 429.874229 -54.246224) (xy 429.878403 -54.217312) (xy 429.874236 -54.188399)
			(xy 429.862068 -54.161842) (xy 429.852836 -54.150514) (xy 429.835196 -54.129583) (xy 429.805483 -54.08361)
			(xy 429.782646 -54.033863) (xy 429.767156 -53.981362) (xy 429.759329 -53.927185) (xy 429.758856 -53.899816)
			(xy 429.759435 -53.869693) (xy 429.768914 -53.810197) (xy 429.787623 -53.752929) (xy 429.815097 -53.699312)
			(xy 429.850654 -53.650677) (xy 429.871632 -53.629052) (xy 429.880834 -53.619316) (xy 429.89428 -53.596158)
			(xy 429.901244 -53.570301) (xy 429.901247 -53.543522) (xy 429.894288 -53.517663) (xy 429.880847 -53.494502)
			(xy 429.871632 -53.48478) (xy 429.850671 -53.463138) (xy 429.815099 -53.414514) (xy 429.787614 -53.360902)
			(xy 429.768902 -53.303636) (xy 429.759426 -53.244139) (xy 429.758856 -53.214016) (xy 429.759393 -53.186767)
			(xy 429.767146 -53.132823) (xy 429.782498 -53.080531) (xy 429.805134 -53.030957) (xy 429.834596 -52.985108)
			(xy 429.870282 -52.943918) (xy 429.911466 -52.908227) (xy 429.957311 -52.878759) (xy 430.006883 -52.856116)
			(xy 430.059172 -52.840757) (xy 430.113115 -52.832997) (xy 430.140364 -52.832508) (xy 430.166824 -52.832931)
			(xy 430.219233 -52.840271) (xy 430.270124 -52.854787) (xy 430.318518 -52.876201) (xy 430.363487 -52.904102)
			(xy 430.404166 -52.937952) (xy 430.422304 -52.957222) (xy 430.433109 -52.968182) (xy 430.459663 -52.983704)
			(xy 430.489627 -52.990644) (xy 430.520301 -52.988377) (xy 430.54892 -52.977108) (xy 430.561242 -52.96789)
			(xy 430.581659 -52.951937) (xy 430.62602 -52.925161) (xy 430.673598 -52.904638) (xy 430.723516 -52.890745)
			(xy 430.774856 -52.883738) (xy 430.800764 -52.883308) (xy 430.828134 -52.883793) (xy 430.882312 -52.891606)
			(xy 430.934815 -52.907091) (xy 430.984562 -52.929928) (xy 431.03053 -52.959649) (xy 431.051462 -52.977288)
			(xy 431.06279 -52.986524) (xy 431.089347 -52.9987) (xy 431.118264 -53.002873) (xy 431.147181 -52.9987)
			(xy 431.173738 -52.986524) (xy 431.185066 -52.977288) (xy 431.205999 -52.95965) (xy 431.251971 -52.929938)
			(xy 431.301719 -52.907102) (xy 431.354219 -52.891611) (xy 431.408395 -52.883782) (xy 431.435764 -52.883308)
			(xy 431.465276 -52.883875) (xy 431.523597 -52.892961) (xy 431.579823 -52.910922) (xy 431.632611 -52.937328)
			(xy 431.680702 -52.97155) (xy 431.70221 -52.991766) (xy 431.713589 -53.002006) (xy 431.740854 -53.015882)
			(xy 431.771003 -53.021076) (xy 431.801339 -53.017123) (xy 431.82915 -53.004375) (xy 431.840894 -52.99456)
			(xy 431.861973 -52.976257) (xy 431.908518 -52.945435) (xy 431.959057 -52.921725) (xy 432.012513 -52.905634)
			(xy 432.067743 -52.897506) (xy 432.095656 -52.897024) (xy 432.124842 -52.897613) (xy 432.182533 -52.906505)
			(xy 432.238198 -52.924075) (xy 432.29054 -52.949912) (xy 432.338341 -52.983414) (xy 432.380485 -53.023801)
			(xy 432.398678 -53.04663) (xy 432.407273 -53.057141) (xy 432.428869 -53.073581) (xy 432.454033 -53.083755)
			(xy 432.480987 -53.086942) (xy 432.507829 -53.082919) (xy 432.532664 -53.071969) (xy 432.553739 -53.054866)
			(xy 432.562 -53.04409) (xy 432.577449 -53.023253) (xy 432.613004 -52.985486) (xy 432.653348 -52.952885)
			(xy 432.697737 -52.926051) (xy 432.745353 -52.905477) (xy 432.795316 -52.891545) (xy 432.846707 -52.884509)
			(xy 432.872642 -52.88407) (xy 432.900387 -52.884563) (xy 432.955291 -52.892607) (xy 433.008451 -52.90852)
			(xy 433.058744 -52.931966) (xy 433.105111 -52.96245) (xy 433.146573 -52.999329) (xy 433.182255 -53.041825)
			(xy 433.197254 -53.065172) (xy 433.205615 -53.077809) (xy 433.228365 -53.097807) (xy 433.255973 -53.110268)
			(xy 433.286019 -53.1141) (xy 433.315871 -53.108968) (xy 433.342913 -53.095322) (xy 433.354226 -53.085238)
			(xy 433.375661 -53.065403) (xy 433.423454 -53.031843) (xy 433.475799 -53.00595) (xy 433.531476 -52.988329)
			(xy 433.589187 -52.97939) (xy 433.618386 -52.978812) (xy 433.645641 -52.979234) (xy 433.699596 -52.98699)
			(xy 433.751899 -53.002345) (xy 433.801483 -53.024988) (xy 433.847341 -53.054457) (xy 433.888537 -53.090153)
			(xy 433.924234 -53.131348) (xy 433.953705 -53.177205) (xy 433.97635 -53.226788) (xy 433.991707 -53.27909)
			(xy 433.999465 -53.333045) (xy 433.999465 -53.387555) (xy 433.991707 -53.44151) (xy 433.97635 -53.493812)
			(xy 433.953705 -53.543395) (xy 433.924234 -53.589252) (xy 433.888537 -53.630447) (xy 433.847341 -53.666143)
			(xy 433.801483 -53.695612) (xy 433.751899 -53.718255) (xy 433.699596 -53.73361) (xy 433.645641 -53.741366)
			(xy 433.618386 -53.741828) (xy 433.590229 -53.741343) (xy 433.534526 -53.733076) (xy 433.480643 -53.716709)
			(xy 433.429753 -53.692597) (xy 433.38296 -53.661266) (xy 433.341282 -53.623395) (xy 433.305626 -53.579808)
			(xy 433.276765 -53.531453) (xy 433.26558 -53.505608) (xy 433.261051 -53.495825) (xy 433.245429 -53.480995)
			(xy 433.225106 -53.473859) (xy 433.203641 -53.475669) (xy 433.184799 -53.486106) (xy 433.17795 -53.494432)
			(xy 433.16017 -53.516276) (xy 433.150957 -53.52762) (xy 433.13878 -53.554172) (xy 433.134605 -53.583083)
			(xy 433.138771 -53.611996) (xy 433.150939 -53.638552) (xy 433.16017 -53.64988) (xy 433.177809 -53.670813)
			(xy 433.207521 -53.716785) (xy 433.230358 -53.766532) (xy 433.245849 -53.819033) (xy 433.253677 -53.873209)
			(xy 433.25415 -53.900578) (xy 433.253591 -53.930883) (xy 433.243998 -53.990728) (xy 433.225064 -54.048304)
			(xy 433.197268 -54.102163) (xy 433.161306 -54.150952) (xy 433.140104 -54.172612) (xy 433.130665 -54.182541)
			(xy 433.11702 -54.206286) (xy 433.110167 -54.232801) (xy 433.110597 -54.260184) (xy 433.11828 -54.28647)
			(xy 433.132664 -54.309775) (xy 433.14239 -54.319424) (xy 433.15353 -54.329979) (xy 433.174256 -54.352613)
			(xy 433.183792 -54.364636) (xy 433.193277 -54.375863) (xy 433.217199 -54.392905) (xy 433.244978 -54.402451)
			(xy 433.274324 -54.403712) (xy 433.302819 -54.396586) (xy 433.328116 -54.381659) (xy 433.338478 -54.37124)
			(xy 433.356615 -54.352319) (xy 433.397123 -54.319063) (xy 433.441807 -54.291672) (xy 433.489823 -54.270663)
			(xy 433.540265 -54.256433) (xy 433.592181 -54.249248) (xy 433.618386 -54.248812) (xy 433.645639 -54.249268)
			(xy 433.699592 -54.257024) (xy 433.751891 -54.272379) (xy 433.801472 -54.295022) (xy 433.847326 -54.32449)
			(xy 433.88852 -54.360185) (xy 433.924214 -54.401378) (xy 433.953681 -54.447233) (xy 433.976323 -54.496815)
			(xy 433.991677 -54.549114) (xy 433.999432 -54.603067) (xy 433.999894 -54.63032) (xy 433.999441 -54.657691)
			(xy 433.99162 -54.71187) (xy 433.976128 -54.764374) (xy 433.953284 -54.81412) (xy 433.923556 -54.860087)
			(xy 433.905914 -54.881018) (xy 433.896657 -54.89233) (xy 433.88448 -54.918893) (xy 433.880311 -54.947815)
			(xy 433.884489 -54.976736) (xy 433.896673 -55.003295) (xy 433.905914 -55.014622) (xy 433.923573 -55.03554)
			(xy 433.953293 -55.081511) (xy 433.976135 -55.13126) (xy 433.991628 -55.183764) (xy 433.999454 -55.237944)
			(xy 433.999452 -55.292686) (xy 433.991622 -55.346865) (xy 433.976125 -55.399368) (xy 433.953279 -55.449115)
			(xy 433.923554 -55.495084) (xy 433.905914 -55.516018) (xy 433.896657 -55.52733) (xy 433.88448 -55.553893)
			(xy 433.880311 -55.582815) (xy 433.884489 -55.611736) (xy 433.896673 -55.638295) (xy 433.905914 -55.649622)
			(xy 433.923573 -55.67054) (xy 433.953293 -55.716511) (xy 433.976135 -55.76626) (xy 433.991628 -55.818764)
			(xy 433.999454 -55.872944) (xy 433.999452 -55.927686) (xy 433.991622 -55.981865) (xy 433.976125 -56.034368)
			(xy 433.953279 -56.084115) (xy 433.923554 -56.130084) (xy 433.905914 -56.151018) (xy 433.896657 -56.16233)
			(xy 433.88448 -56.188893) (xy 433.880311 -56.217815) (xy 433.884489 -56.246736) (xy 433.896673 -56.273295)
			(xy 433.905914 -56.284622) (xy 433.923573 -56.30554) (xy 433.953293 -56.351511) (xy 433.976135 -56.40126)
			(xy 433.991628 -56.453764) (xy 433.999454 -56.507944) (xy 433.999452 -56.562686) (xy 433.991622 -56.616865)
			(xy 433.976125 -56.669368) (xy 433.953279 -56.719115) (xy 433.923554 -56.765084) (xy 433.905914 -56.786018)
			(xy 433.896657 -56.79733) (xy 433.88448 -56.823893) (xy 433.880311 -56.852815) (xy 433.884489 -56.881736)
			(xy 433.896673 -56.908295) (xy 433.905914 -56.919622) (xy 433.923532 -56.940571) (xy 433.953247 -56.986539)
			(xy 433.976086 -57.036283) (xy 433.991582 -57.088779) (xy 433.999417 -57.142952) (xy 433.999894 -57.17032)
			(xy 433.999408 -57.197571) (xy 433.991652 -57.251519) (xy 433.976297 -57.303814) (xy 433.953655 -57.353391)
			(xy 433.924189 -57.399241) (xy 433.888498 -57.440432) (xy 433.847307 -57.476123) (xy 433.801457 -57.505589)
			(xy 433.75188 -57.528231) (xy 433.699585 -57.543586) (xy 433.645637 -57.551342) (xy 433.591135 -57.551342)
			(xy 433.537187 -57.543586) (xy 433.484892 -57.528231) (xy 433.435315 -57.505589) (xy 433.389465 -57.476123)
			(xy 433.348274 -57.440432) (xy 433.312583 -57.399241) (xy 433.283117 -57.353391) (xy 433.260475 -57.303814)
			(xy 433.24512 -57.251519) (xy 433.237364 -57.197571) (xy 433.236878 -57.17032) (xy 433.237337 -57.142949)
			(xy 433.245153 -57.088769) (xy 433.260643 -57.036265) (xy 433.283487 -56.986518) (xy 433.313215 -56.940553)
			(xy 433.330858 -56.919622) (xy 433.340071 -56.908278) (xy 433.352244 -56.881726) (xy 433.356417 -56.852815)
			(xy 433.352252 -56.823904) (xy 433.340087 -56.797347) (xy 433.330858 -56.786018) (xy 433.330604 -56.785764)
			(xy 433.320196 -56.774568) (xy 433.294269 -56.758405) (xy 433.264722 -56.750633) (xy 433.234198 -56.751946)
			(xy 433.205427 -56.762227) (xy 433.180983 -56.780556) (xy 433.1716 -56.792622) (xy 433.156153 -56.813153)
			(xy 433.120646 -56.850289) (xy 433.080475 -56.882323) (xy 433.036368 -56.908674) (xy 432.989122 -56.928866)
			(xy 432.939594 -56.942534) (xy 432.88868 -56.949429) (xy 432.86299 -56.949848) (xy 432.83574 -56.949332)
			(xy 432.781796 -56.941575) (xy 432.729504 -56.92622) (xy 432.679929 -56.903581) (xy 432.634081 -56.874117)
			(xy 432.592892 -56.838429) (xy 432.557201 -56.797243) (xy 432.527733 -56.751397) (xy 432.50509 -56.701824)
			(xy 432.489732 -56.649534) (xy 432.481971 -56.59559) (xy 432.481482 -56.56834) (xy 432.481903 -56.541695)
			(xy 432.489309 -56.488921) (xy 432.503997 -56.437695) (xy 432.525678 -56.389015) (xy 432.553931 -56.34383)
			(xy 432.588205 -56.303023) (xy 432.60772 -56.284876) (xy 432.617643 -56.275375) (xy 432.632425 -56.252231)
			(xy 432.64051 -56.225985) (xy 432.641313 -56.198534) (xy 432.634776 -56.171861) (xy 432.621371 -56.147892)
			(xy 432.612038 -56.13781) (xy 432.604111 -56.129693) (xy 432.589114 -56.112665) (xy 432.582066 -56.103774)
			(xy 432.572169 -56.091969) (xy 432.546845 -56.07445) (xy 432.517452 -56.065274) (xy 432.48666 -56.065274)
			(xy 432.457267 -56.07445) (xy 432.431943 -56.091969) (xy 432.422046 -56.103774) (xy 432.403822 -56.12623)
			(xy 432.36181 -56.165968) (xy 432.314282 -56.198911) (xy 432.262327 -56.224304) (xy 432.207135 -56.241566)
			(xy 432.14997 -56.250302) (xy 432.121056 -56.25084) (xy 432.092423 -56.250308) (xy 432.035799 -56.241768)
			(xy 431.981088 -56.224857) (xy 431.929522 -56.199954) (xy 431.882259 -56.167621) (xy 431.86096 -56.148478)
			(xy 431.849747 -56.13867) (xy 431.823058 -56.125462) (xy 431.793693 -56.120517) (xy 431.76415 -56.124254)
			(xy 431.736942 -56.136357) (xy 431.725324 -56.145684) (xy 431.704466 -56.1631) (xy 431.658712 -56.192416)
			(xy 431.609259 -56.214937) (xy 431.55711 -56.230207) (xy 431.50332 -56.237916) (xy 431.47615 -56.238394)
			(xy 431.448781 -56.2379) (xy 431.394603 -56.230089) (xy 431.3421 -56.214607) (xy 431.292353 -56.191771)
			(xy 431.246385 -56.162052) (xy 431.225452 -56.144414) (xy 431.214124 -56.135178) (xy 431.187567 -56.123002)
			(xy 431.15865 -56.118829) (xy 431.129733 -56.123002) (xy 431.103176 -56.135178) (xy 431.091848 -56.144414)
			(xy 431.070915 -56.162055) (xy 431.024947 -56.191779) (xy 430.975201 -56.214625) (xy 430.922699 -56.230121)
			(xy 430.868521 -56.23795) (xy 430.813779 -56.23795) (xy 430.759601 -56.230121) (xy 430.707099 -56.214625)
			(xy 430.657353 -56.191779) (xy 430.611385 -56.162055) (xy 430.590452 -56.144414) (xy 430.579124 -56.135178)
			(xy 430.552567 -56.123002) (xy 430.52365 -56.118829) (xy 430.494733 -56.123002) (xy 430.468176 -56.135178)
			(xy 430.456848 -56.144414) (xy 430.43591 -56.162046) (xy 430.389939 -56.191759) (xy 430.340193 -56.214596)
			(xy 430.287693 -56.230088) (xy 430.233519 -56.237919) (xy 430.20615 -56.238394) (xy 430.178898 -56.237898)
			(xy 430.124947 -56.230148) (xy 430.072649 -56.214797) (xy 430.023068 -56.19216) (xy 429.977214 -56.162695)
			(xy 429.936021 -56.127005) (xy 429.900326 -56.085815) (xy 429.870858 -56.039963) (xy 429.848215 -55.990385)
			(xy 429.83286 -55.938088) (xy 429.825104 -55.884138) (xy 429.824642 -55.856886) (xy 429.82509 -55.829515)
			(xy 429.83291 -55.775335) (xy 429.848403 -55.722831) (xy 429.871249 -55.673084) (xy 429.900978 -55.627119)
			(xy 429.918622 -55.606188) (xy 429.927871 -55.59487) (xy 429.940044 -55.568309) (xy 429.944213 -55.539389)
			(xy 429.940038 -55.510471) (xy 429.927859 -55.483912) (xy 429.918622 -55.472584) (xy 429.901012 -55.451628)
			(xy 429.871295 -55.405662) (xy 429.848453 -55.355921) (xy 429.832955 -55.303425) (xy 429.82512 -55.249254)
			(xy 429.824642 -55.221886) (xy 429.825083 -55.195161) (xy 429.832537 -55.142234) (xy 429.847296 -55.090863)
			(xy 429.869073 -55.042052) (xy 429.897442 -54.996753) (xy 429.914304 -54.976014) (xy 429.922662 -54.9654)
			(xy 429.934098 -54.940939) (xy 429.938707 -54.914332) (xy 429.936164 -54.88745) (xy 429.926649 -54.862179)
			(xy 429.910829 -54.840296) (xy 429.900588 -54.831488) (xy 429.878857 -54.813288) (xy 429.840524 -54.771532)
			(xy 429.808792 -54.724563) (xy 429.78436 -54.673416) (xy 429.767766 -54.619216) (xy 429.759375 -54.563158)
			(xy 429.758856 -54.534816) (xy 429.38446 -54.534816) (xy 429.38446 -59.14644) (xy 433.233322 -62.995048)
			(xy 433.253726 -63.016222) (xy 433.288424 -63.063693) (xy 433.315414 -63.115933) (xy 433.32527 -63.143638)
			(xy 433.32908 -63.155068) (xy 434.120544 -63.946532) (xy 434.131527 -63.956713) (xy 434.157956 -63.970768)
			(xy 434.187323 -63.976561) (xy 434.217109 -63.973594) (xy 434.244757 -63.962124) (xy 434.267895 -63.943133)
			(xy 434.284536 -63.918252) (xy 434.293253 -63.889616) (xy 434.293772 -63.87465) (xy 434.293772 -53.547518)
			(xy 435.52491 -52.31638) (xy 442.36513 -52.31638) (xy 442.566196 -52.517548) (xy 444.575182 -52.517548)
			(xy 444.579253 -52.461926) (xy 444.591379 -52.407489) (xy 444.611302 -52.355398) (xy 444.638598 -52.306763)
			(xy 444.672684 -52.26262) (xy 444.712833 -52.223911) (xy 444.758191 -52.19146) (xy 444.807791 -52.165959)
			(xy 444.860575 -52.147952) (xy 444.915418 -52.137822) (xy 444.971152 -52.135785) (xy 445.026589 -52.141885)
			(xy 445.080546 -52.155991) (xy 445.131875 -52.177803) (xy 445.179481 -52.206857) (xy 445.222349 -52.242532)
			(xy 445.259566 -52.284069) (xy 445.290339 -52.330582) (xy 445.314011 -52.381079) (xy 445.330079 -52.434486)
			(xy 445.338199 -52.489662) (xy 445.338708 -52.517548) (xy 445.338199 -52.545434) (xy 445.330079 -52.60061)
			(xy 445.314011 -52.654017) (xy 445.290339 -52.704514) (xy 445.259566 -52.751027) (xy 445.222349 -52.792564)
			(xy 445.179481 -52.828239) (xy 445.131875 -52.857293) (xy 445.080546 -52.879105) (xy 445.026589 -52.893211)
			(xy 444.971152 -52.899311) (xy 444.915418 -52.897274) (xy 444.860575 -52.887144) (xy 444.807791 -52.869137)
			(xy 444.758191 -52.843636) (xy 444.712833 -52.811185) (xy 444.672684 -52.772476) (xy 444.638598 -52.728333)
			(xy 444.611302 -52.679698) (xy 444.591379 -52.627607) (xy 444.579253 -52.57317) (xy 444.575182 -52.517548)
			(xy 442.566196 -52.517548) (xy 442.86805 -52.819554) (xy 442.903102 -52.7939) (xy 442.927759 -52.776546)
			(xy 442.981402 -52.749018) (xy 443.03871 -52.730281) (xy 443.098253 -52.720802) (xy 443.1284 -52.72024)
			(xy 443.157316 -52.720774) (xy 443.214486 -52.729502) (xy 443.269685 -52.746757) (xy 443.321647 -52.772145)
			(xy 443.369183 -52.805084) (xy 443.411203 -52.844819) (xy 443.42939 -52.867306) (xy 443.439287 -52.879111)
			(xy 443.464611 -52.89663) (xy 443.494004 -52.905806) (xy 443.524796 -52.905806) (xy 443.554189 -52.89663)
			(xy 443.579513 -52.879111) (xy 443.58941 -52.867306) (xy 443.607599 -52.844819) (xy 443.649615 -52.805075)
			(xy 443.697148 -52.772128) (xy 443.74911 -52.746733) (xy 443.80431 -52.729473) (xy 443.861482 -52.720743)
			(xy 443.8904 -52.72024) (xy 443.917648 -52.720726) (xy 443.971589 -52.728482) (xy 444.023877 -52.743835)
			(xy 444.073448 -52.766473) (xy 444.119292 -52.795936) (xy 444.160477 -52.831623) (xy 444.196164 -52.872808)
			(xy 444.225627 -52.918652) (xy 444.248265 -52.968223) (xy 444.263618 -53.020511) (xy 444.271374 -53.074452)
			(xy 444.271374 -53.128948) (xy 444.263618 -53.182889) (xy 444.248265 -53.235177) (xy 444.225627 -53.284748)
			(xy 444.196164 -53.330592) (xy 444.160477 -53.371777) (xy 444.119292 -53.407464) (xy 444.073448 -53.436927)
			(xy 444.023877 -53.459565) (xy 443.971589 -53.474918) (xy 443.917648 -53.482674) (xy 443.8904 -53.483256)
			(xy 443.861484 -53.482722) (xy 443.804314 -53.473994) (xy 443.749115 -53.456739) (xy 443.697153 -53.431351)
			(xy 443.649618 -53.398412) (xy 443.607598 -53.358676) (xy 443.58941 -53.33619) (xy 443.579513 -53.324385)
			(xy 443.554189 -53.306866) (xy 443.524796 -53.29769) (xy 443.494004 -53.29769) (xy 443.464611 -53.306866)
			(xy 443.439287 -53.324385) (xy 443.42939 -53.33619) (xy 443.411201 -53.358677) (xy 443.369186 -53.398422)
			(xy 443.321652 -53.431369) (xy 443.26969 -53.456764) (xy 443.21449 -53.474024) (xy 443.157318 -53.482754)
			(xy 443.1284 -53.483256) (xy 443.101556 -53.4828) (xy 443.048399 -53.475278) (xy 443.022482 -53.46827)
			(xy 443.009437 -53.464935) (xy 442.982524 -53.464488) (xy 442.95643 -53.47109) (xy 442.932968 -53.484282)
			(xy 442.91377 -53.503147) (xy 442.900168 -53.526374) (xy 442.89311 -53.552348) (xy 442.892688 -53.565806)
			(xy 442.892688 -54.371748) (xy 447.038982 -54.371748) (xy 447.043053 -54.316126) (xy 447.055179 -54.261689)
			(xy 447.075102 -54.209598) (xy 447.102398 -54.160963) (xy 447.136484 -54.11682) (xy 447.176633 -54.078111)
			(xy 447.221991 -54.04566) (xy 447.271591 -54.020159) (xy 447.324375 -54.002152) (xy 447.379218 -53.992022)
			(xy 447.434952 -53.989985) (xy 447.490389 -53.996085) (xy 447.544346 -54.010191) (xy 447.595675 -54.032003)
			(xy 447.643281 -54.061057) (xy 447.686149 -54.096732) (xy 447.723366 -54.138269) (xy 447.754139 -54.184782)
			(xy 447.777811 -54.235279) (xy 447.793879 -54.288686) (xy 447.801999 -54.343862) (xy 447.802508 -54.371748)
			(xy 447.927982 -54.371748) (xy 447.932053 -54.316126) (xy 447.944179 -54.261689) (xy 447.964102 -54.209598)
			(xy 447.991398 -54.160963) (xy 448.025484 -54.11682) (xy 448.065633 -54.078111) (xy 448.110991 -54.04566)
			(xy 448.160591 -54.020159) (xy 448.213375 -54.002152) (xy 448.268218 -53.992022) (xy 448.323952 -53.989985)
			(xy 448.379389 -53.996085) (xy 448.433346 -54.010191) (xy 448.484675 -54.032003) (xy 448.532281 -54.061057)
			(xy 448.575149 -54.096732) (xy 448.612366 -54.138269) (xy 448.643139 -54.184782) (xy 448.666811 -54.235279)
			(xy 448.682879 -54.288686) (xy 448.690999 -54.343862) (xy 448.691508 -54.371748) (xy 448.816982 -54.371748)
			(xy 448.821053 -54.316126) (xy 448.833179 -54.261689) (xy 448.853102 -54.209598) (xy 448.880398 -54.160963)
			(xy 448.914484 -54.11682) (xy 448.954633 -54.078111) (xy 448.999991 -54.04566) (xy 449.049591 -54.020159)
			(xy 449.102375 -54.002152) (xy 449.157218 -53.992022) (xy 449.212952 -53.989985) (xy 449.268389 -53.996085)
			(xy 449.322346 -54.010191) (xy 449.373675 -54.032003) (xy 449.421281 -54.061057) (xy 449.464149 -54.096732)
			(xy 449.501366 -54.138269) (xy 449.532139 -54.184782) (xy 449.555811 -54.235279) (xy 449.571879 -54.288686)
			(xy 449.579999 -54.343862) (xy 449.580508 -54.371748) (xy 449.705982 -54.371748) (xy 449.710053 -54.316126)
			(xy 449.722179 -54.261689) (xy 449.742102 -54.209598) (xy 449.769398 -54.160963) (xy 449.803484 -54.11682)
			(xy 449.843633 -54.078111) (xy 449.888991 -54.04566) (xy 449.938591 -54.020159) (xy 449.991375 -54.002152)
			(xy 450.046218 -53.992022) (xy 450.101952 -53.989985) (xy 450.157389 -53.996085) (xy 450.211346 -54.010191)
			(xy 450.262675 -54.032003) (xy 450.310281 -54.061057) (xy 450.353149 -54.096732) (xy 450.390366 -54.138269)
			(xy 450.421139 -54.184782) (xy 450.444811 -54.235279) (xy 450.460879 -54.288686) (xy 450.468999 -54.343862)
			(xy 450.469508 -54.371748) (xy 450.468999 -54.399634) (xy 450.460879 -54.45481) (xy 450.444811 -54.508217)
			(xy 450.421139 -54.558714) (xy 450.390366 -54.605227) (xy 450.353149 -54.646764) (xy 450.310281 -54.682439)
			(xy 450.262675 -54.711493) (xy 450.211346 -54.733305) (xy 450.157389 -54.747411) (xy 450.101952 -54.753511)
			(xy 450.046218 -54.751474) (xy 449.991375 -54.741344) (xy 449.938591 -54.723337) (xy 449.888991 -54.697836)
			(xy 449.843633 -54.665385) (xy 449.803484 -54.626676) (xy 449.769398 -54.582533) (xy 449.742102 -54.533898)
			(xy 449.722179 -54.481807) (xy 449.710053 -54.42737) (xy 449.705982 -54.371748) (xy 449.580508 -54.371748)
			(xy 449.579999 -54.399634) (xy 449.571879 -54.45481) (xy 449.555811 -54.508217) (xy 449.532139 -54.558714)
			(xy 449.501366 -54.605227) (xy 449.464149 -54.646764) (xy 449.421281 -54.682439) (xy 449.373675 -54.711493)
			(xy 449.322346 -54.733305) (xy 449.268389 -54.747411) (xy 449.212952 -54.753511) (xy 449.157218 -54.751474)
			(xy 449.102375 -54.741344) (xy 449.049591 -54.723337) (xy 448.999991 -54.697836) (xy 448.954633 -54.665385)
			(xy 448.914484 -54.626676) (xy 448.880398 -54.582533) (xy 448.853102 -54.533898) (xy 448.833179 -54.481807)
			(xy 448.821053 -54.42737) (xy 448.816982 -54.371748) (xy 448.691508 -54.371748) (xy 448.690999 -54.399634)
			(xy 448.682879 -54.45481) (xy 448.666811 -54.508217) (xy 448.643139 -54.558714) (xy 448.612366 -54.605227)
			(xy 448.575149 -54.646764) (xy 448.532281 -54.682439) (xy 448.484675 -54.711493) (xy 448.433346 -54.733305)
			(xy 448.379389 -54.747411) (xy 448.323952 -54.753511) (xy 448.268218 -54.751474) (xy 448.213375 -54.741344)
			(xy 448.160591 -54.723337) (xy 448.110991 -54.697836) (xy 448.065633 -54.665385) (xy 448.025484 -54.626676)
			(xy 447.991398 -54.582533) (xy 447.964102 -54.533898) (xy 447.944179 -54.481807) (xy 447.932053 -54.42737)
			(xy 447.927982 -54.371748) (xy 447.802508 -54.371748) (xy 447.801999 -54.399634) (xy 447.793879 -54.45481)
			(xy 447.777811 -54.508217) (xy 447.754139 -54.558714) (xy 447.723366 -54.605227) (xy 447.686149 -54.646764)
			(xy 447.643281 -54.682439) (xy 447.595675 -54.711493) (xy 447.544346 -54.733305) (xy 447.490389 -54.747411)
			(xy 447.434952 -54.753511) (xy 447.379218 -54.751474) (xy 447.324375 -54.741344) (xy 447.271591 -54.723337)
			(xy 447.221991 -54.697836) (xy 447.176633 -54.665385) (xy 447.136484 -54.626676) (xy 447.102398 -54.582533)
			(xy 447.075102 -54.533898) (xy 447.055179 -54.481807) (xy 447.043053 -54.42737) (xy 447.038982 -54.371748)
			(xy 442.892688 -54.371748) (xy 442.892688 -57.588912) (xy 444.646304 -57.588912) (xy 444.646776 -57.561542)
			(xy 444.654592 -57.507363) (xy 444.67008 -57.45486) (xy 444.69292 -57.405113) (xy 444.722643 -57.359146)
			(xy 444.740284 -57.338214) (xy 444.749511 -57.326879) (xy 444.761691 -57.300324) (xy 444.765867 -57.271409)
			(xy 444.761696 -57.242493) (xy 444.74952 -57.215937) (xy 444.740284 -57.20461) (xy 444.722657 -57.183667)
			(xy 444.692935 -57.1377) (xy 444.670091 -57.087955) (xy 444.654596 -57.035455) (xy 444.646767 -56.981279)
			(xy 444.646766 -56.926539) (xy 444.654592 -56.872363) (xy 444.670085 -56.819862) (xy 444.692926 -56.770116)
			(xy 444.722646 -56.724148) (xy 444.740284 -56.703214) (xy 444.749511 -56.691879) (xy 444.761691 -56.665324)
			(xy 444.765867 -56.636409) (xy 444.761696 -56.607493) (xy 444.74952 -56.580937) (xy 444.740284 -56.56961)
			(xy 444.722657 -56.548667) (xy 444.692935 -56.5027) (xy 444.670091 -56.452955) (xy 444.654596 -56.400455)
			(xy 444.646767 -56.346279) (xy 444.646766 -56.291539) (xy 444.654592 -56.237363) (xy 444.670085 -56.184862)
			(xy 444.692926 -56.135116) (xy 444.722646 -56.089148) (xy 444.740284 -56.068214) (xy 444.749511 -56.056879)
			(xy 444.761691 -56.030324) (xy 444.765867 -56.001409) (xy 444.761696 -55.972493) (xy 444.74952 -55.945937)
			(xy 444.740284 -55.93461) (xy 444.722657 -55.913667) (xy 444.692935 -55.8677) (xy 444.670091 -55.817955)
			(xy 444.654596 -55.765455) (xy 444.646767 -55.711279) (xy 444.646766 -55.656539) (xy 444.654592 -55.602363)
			(xy 444.670085 -55.549862) (xy 444.692926 -55.500116) (xy 444.722646 -55.454148) (xy 444.740284 -55.433214)
			(xy 444.749511 -55.421879) (xy 444.761691 -55.395324) (xy 444.765867 -55.366409) (xy 444.761696 -55.337493)
			(xy 444.74952 -55.310937) (xy 444.740284 -55.29961) (xy 444.722634 -55.278687) (xy 444.692924 -55.232711)
			(xy 444.670091 -55.182962) (xy 444.654602 -55.130459) (xy 444.646777 -55.076282) (xy 444.646304 -55.048912)
			(xy 444.646767 -55.021659) (xy 444.654522 -54.967707) (xy 444.669877 -54.915409) (xy 444.692519 -54.865828)
			(xy 444.721987 -54.819974) (xy 444.757681 -54.778781) (xy 444.798874 -54.743087) (xy 444.844728 -54.713619)
			(xy 444.894309 -54.690977) (xy 444.946607 -54.675622) (xy 445.000559 -54.667867) (xy 445.027812 -54.667404)
			(xy 445.054483 -54.66783) (xy 445.107306 -54.67525) (xy 445.158579 -54.689958) (xy 445.207304 -54.711667)
			(xy 445.252528 -54.739952) (xy 445.29337 -54.774263) (xy 445.329032 -54.81393) (xy 445.344296 -54.835806)
			(xy 445.35343 -54.848302) (xy 445.377599 -54.867612) (xy 445.406436 -54.87881) (xy 445.437302 -54.88087)
			(xy 445.467372 -54.873605) (xy 445.493892 -54.857678) (xy 445.50457 -54.846474) (xy 445.522735 -54.826673)
			(xy 445.563685 -54.791879) (xy 445.609115 -54.76318) (xy 445.658124 -54.741143) (xy 445.709741 -54.726205)
			(xy 445.762944 -54.718663) (xy 445.789812 -54.718204) (xy 445.817064 -54.718667) (xy 445.871013 -54.726425)
			(xy 445.923309 -54.741782) (xy 445.972887 -54.764426) (xy 446.018738 -54.793894) (xy 446.059929 -54.829588)
			(xy 446.09562 -54.870781) (xy 446.125086 -54.916634) (xy 446.147726 -54.966213) (xy 446.16308 -55.01851)
			(xy 446.170835 -55.07246) (xy 446.17132 -55.099712) (xy 446.17088 -55.127083) (xy 446.163059 -55.181264)
			(xy 446.147565 -55.233769) (xy 446.124717 -55.283515) (xy 446.094985 -55.32948) (xy 446.07734 -55.35041)
			(xy 446.068088 -55.361727) (xy 446.055908 -55.388288) (xy 446.051735 -55.417209) (xy 446.055913 -55.44613)
			(xy 446.068098 -55.472688) (xy 446.07734 -55.484014) (xy 446.094994 -55.504937) (xy 446.124721 -55.550905)
			(xy 446.147567 -55.600653) (xy 446.163064 -55.653157) (xy 446.170892 -55.707337) (xy 446.170891 -55.762081)
			(xy 446.16306 -55.816261) (xy 446.147561 -55.868764) (xy 446.124712 -55.918511) (xy 446.094983 -55.964478)
			(xy 446.07734 -55.98541) (xy 446.068088 -55.996727) (xy 446.055908 -56.023288) (xy 446.051735 -56.052209)
			(xy 446.055913 -56.08113) (xy 446.068098 -56.107688) (xy 446.07734 -56.119014) (xy 446.094994 -56.139937)
			(xy 446.124721 -56.185905) (xy 446.147567 -56.235653) (xy 446.163064 -56.288157) (xy 446.170892 -56.342337)
			(xy 446.170891 -56.369712) (xy 451.428104 -56.369712) (xy 451.428576 -56.342342) (xy 451.436392 -56.288163)
			(xy 451.45188 -56.23566) (xy 451.47472 -56.185913) (xy 451.504443 -56.139946) (xy 451.522084 -56.119014)
			(xy 451.531311 -56.107679) (xy 451.543491 -56.081124) (xy 451.547667 -56.052209) (xy 451.543496 -56.023293)
			(xy 451.53132 -55.996737) (xy 451.522084 -55.98541) (xy 451.504457 -55.964467) (xy 451.474735 -55.9185)
			(xy 451.451891 -55.868755) (xy 451.436396 -55.816255) (xy 451.428567 -55.762079) (xy 451.428566 -55.707339)
			(xy 451.436392 -55.653163) (xy 451.451885 -55.600662) (xy 451.474726 -55.550916) (xy 451.504446 -55.504948)
			(xy 451.522084 -55.484014) (xy 451.531311 -55.472679) (xy 451.543491 -55.446124) (xy 451.547667 -55.417209)
			(xy 451.543496 -55.388293) (xy 451.53132 -55.361737) (xy 451.522084 -55.35041) (xy 451.504434 -55.329487)
			(xy 451.474724 -55.283511) (xy 451.451891 -55.233762) (xy 451.436402 -55.181259) (xy 451.428577 -55.127082)
			(xy 451.428104 -55.099712) (xy 451.42859 -55.072461) (xy 451.436346 -55.018513) (xy 451.451701 -54.966218)
			(xy 451.474343 -54.916641) (xy 451.503809 -54.870791) (xy 451.5395 -54.8296) (xy 451.580691 -54.793909)
			(xy 451.626541 -54.764443) (xy 451.676118 -54.741801) (xy 451.728413 -54.726446) (xy 451.782361 -54.71869)
			(xy 451.836863 -54.71869) (xy 451.890811 -54.726446) (xy 451.943106 -54.741801) (xy 451.992683 -54.764443)
			(xy 452.038533 -54.793909) (xy 452.079724 -54.8296) (xy 452.115415 -54.870791) (xy 452.144881 -54.916641)
			(xy 452.167523 -54.966218) (xy 452.182878 -55.018513) (xy 452.190634 -55.072461) (xy 452.19112 -55.099712)
			(xy 452.19068 -55.127083) (xy 452.182859 -55.181264) (xy 452.167365 -55.233769) (xy 452.144517 -55.283515)
			(xy 452.114785 -55.32948) (xy 452.09714 -55.35041) (xy 452.087888 -55.361727) (xy 452.075708 -55.388288)
			(xy 452.071535 -55.417209) (xy 452.075713 -55.44613) (xy 452.087898 -55.472688) (xy 452.09714 -55.484014)
			(xy 452.114794 -55.504937) (xy 452.144521 -55.550905) (xy 452.167367 -55.600653) (xy 452.182864 -55.653157)
			(xy 452.190692 -55.707337) (xy 452.190691 -55.762081) (xy 452.18286 -55.816261) (xy 452.167361 -55.868764)
			(xy 452.144512 -55.918511) (xy 452.114783 -55.964478) (xy 452.09714 -55.98541) (xy 452.087888 -55.996727)
			(xy 452.075708 -56.023288) (xy 452.071535 -56.052209) (xy 452.075713 -56.08113) (xy 452.087898 -56.107688)
			(xy 452.09714 -56.119014) (xy 452.114759 -56.139962) (xy 452.144472 -56.185931) (xy 452.167312 -56.235675)
			(xy 452.182808 -56.288172) (xy 452.190643 -56.342344) (xy 452.19112 -56.369712) (xy 452.190634 -56.396963)
			(xy 452.182878 -56.450911) (xy 452.167523 -56.503206) (xy 452.144881 -56.552783) (xy 452.115415 -56.598633)
			(xy 452.079724 -56.639824) (xy 452.038533 -56.675515) (xy 451.992683 -56.704981) (xy 451.943106 -56.727623)
			(xy 451.890811 -56.742978) (xy 451.836863 -56.750734) (xy 451.782361 -56.750734) (xy 451.728413 -56.742978)
			(xy 451.676118 -56.727623) (xy 451.626541 -56.704981) (xy 451.580691 -56.675515) (xy 451.5395 -56.639824)
			(xy 451.503809 -56.598633) (xy 451.474343 -56.552783) (xy 451.451701 -56.503206) (xy 451.436346 -56.450911)
			(xy 451.42859 -56.396963) (xy 451.428104 -56.369712) (xy 446.170891 -56.369712) (xy 446.170891 -56.397081)
			(xy 446.16306 -56.451261) (xy 446.147561 -56.503764) (xy 446.124712 -56.553511) (xy 446.094983 -56.599478)
			(xy 446.07734 -56.62041) (xy 446.068088 -56.631727) (xy 446.055908 -56.658288) (xy 446.051735 -56.687209)
			(xy 446.055913 -56.71613) (xy 446.068098 -56.742688) (xy 446.07734 -56.754014) (xy 446.094959 -56.774962)
			(xy 446.124672 -56.820931) (xy 446.147512 -56.870675) (xy 446.163008 -56.923172) (xy 446.170843 -56.977344)
			(xy 446.17132 -57.004712) (xy 446.170833 -57.031963) (xy 446.163076 -57.08591) (xy 446.14772 -57.138204)
			(xy 446.125078 -57.187781) (xy 446.095611 -57.23363) (xy 446.05992 -57.27482) (xy 446.01873 -57.310511)
			(xy 445.972881 -57.339978) (xy 445.923304 -57.36262) (xy 445.87101 -57.377976) (xy 445.817063 -57.385733)
			(xy 445.789812 -57.38622) (xy 445.762381 -57.385755) (xy 445.708084 -57.377911) (xy 445.65547 -57.362369)
			(xy 445.605626 -57.339449) (xy 445.55958 -57.309624) (xy 445.518282 -57.27351) (xy 445.482584 -57.231852)
			(xy 445.453222 -57.185509) (xy 445.441578 -57.160668) (xy 445.436517 -57.15084) (xy 445.419862 -57.13635)
			(xy 445.398659 -57.130199) (xy 445.376835 -57.133527) (xy 445.358428 -57.145717) (xy 445.35217 -57.154826)
			(xy 445.343856 -57.167909) (xy 445.325419 -57.192833) (xy 445.31534 -57.20461) (xy 445.306088 -57.215927)
			(xy 445.293908 -57.242488) (xy 445.289735 -57.271409) (xy 445.293913 -57.30033) (xy 445.306098 -57.326888)
			(xy 445.31534 -57.338214) (xy 445.332959 -57.359162) (xy 445.362672 -57.405131) (xy 445.385512 -57.454875)
			(xy 445.401008 -57.507372) (xy 445.408843 -57.561544) (xy 445.40932 -57.588912) (xy 445.408834 -57.616163)
			(xy 445.405448 -57.639712) (xy 452.723504 -57.639712) (xy 452.723976 -57.612342) (xy 452.731792 -57.558163)
			(xy 452.74728 -57.50566) (xy 452.77012 -57.455913) (xy 452.799843 -57.409946) (xy 452.817484 -57.389014)
			(xy 452.826711 -57.377679) (xy 452.838891 -57.351124) (xy 452.843067 -57.322209) (xy 452.838896 -57.293293)
			(xy 452.82672 -57.266737) (xy 452.817484 -57.25541) (xy 452.799857 -57.234467) (xy 452.770135 -57.1885)
			(xy 452.747291 -57.138755) (xy 452.731796 -57.086255) (xy 452.723967 -57.032079) (xy 452.723966 -56.977339)
			(xy 452.731792 -56.923163) (xy 452.747285 -56.870662) (xy 452.770126 -56.820916) (xy 452.799846 -56.774948)
			(xy 452.817484 -56.754014) (xy 452.826711 -56.742679) (xy 452.838891 -56.716124) (xy 452.843067 -56.687209)
			(xy 452.838896 -56.658293) (xy 452.82672 -56.631737) (xy 452.817484 -56.62041) (xy 452.799857 -56.599467)
			(xy 452.770135 -56.5535) (xy 452.747291 -56.503755) (xy 452.731796 -56.451255) (xy 452.723967 -56.397079)
			(xy 452.723966 -56.342339) (xy 452.731792 -56.288163) (xy 452.747285 -56.235662) (xy 452.770126 -56.185916)
			(xy 452.799846 -56.139948) (xy 452.817484 -56.119014) (xy 452.826711 -56.107679) (xy 452.838891 -56.081124)
			(xy 452.843067 -56.052209) (xy 452.838896 -56.023293) (xy 452.82672 -55.996737) (xy 452.817484 -55.98541)
			(xy 452.799857 -55.964467) (xy 452.770135 -55.9185) (xy 452.747291 -55.868755) (xy 452.731796 -55.816255)
			(xy 452.723967 -55.762079) (xy 452.723966 -55.707339) (xy 452.731792 -55.653163) (xy 452.747285 -55.600662)
			(xy 452.770126 -55.550916) (xy 452.799846 -55.504948) (xy 452.817484 -55.484014) (xy 452.826711 -55.472679)
			(xy 452.838891 -55.446124) (xy 452.843067 -55.417209) (xy 452.838896 -55.388293) (xy 452.82672 -55.361737)
			(xy 452.817484 -55.35041) (xy 452.799834 -55.329487) (xy 452.770124 -55.283511) (xy 452.747291 -55.233762)
			(xy 452.731802 -55.181259) (xy 452.723977 -55.127082) (xy 452.723504 -55.099712) (xy 452.72399 -55.072461)
			(xy 452.731746 -55.018513) (xy 452.747101 -54.966218) (xy 452.769743 -54.916641) (xy 452.799209 -54.870791)
			(xy 452.8349 -54.8296) (xy 452.876091 -54.793909) (xy 452.921941 -54.764443) (xy 452.971518 -54.741801)
			(xy 453.023813 -54.726446) (xy 453.077761 -54.71869) (xy 453.132263 -54.71869) (xy 453.186211 -54.726446)
			(xy 453.238506 -54.741801) (xy 453.288083 -54.764443) (xy 453.333933 -54.793909) (xy 453.375124 -54.8296)
			(xy 453.410815 -54.870791) (xy 453.440281 -54.916641) (xy 453.462923 -54.966218) (xy 453.478278 -55.018513)
			(xy 453.486034 -55.072461) (xy 453.48652 -55.099712) (xy 453.48608 -55.127083) (xy 453.478259 -55.181264)
			(xy 453.462765 -55.233769) (xy 453.439917 -55.283515) (xy 453.410185 -55.32948) (xy 453.39254 -55.35041)
			(xy 453.383288 -55.361727) (xy 453.371108 -55.388288) (xy 453.366935 -55.417209) (xy 453.371113 -55.44613)
			(xy 453.383298 -55.472688) (xy 453.39254 -55.484014) (xy 453.410194 -55.504937) (xy 453.439921 -55.550905)
			(xy 453.462767 -55.600653) (xy 453.478264 -55.653157) (xy 453.486092 -55.707337) (xy 453.486091 -55.762081)
			(xy 453.47826 -55.816261) (xy 453.462761 -55.868764) (xy 453.439912 -55.918511) (xy 453.410183 -55.964478)
			(xy 453.39254 -55.98541) (xy 453.383288 -55.996727) (xy 453.371108 -56.023288) (xy 453.366935 -56.052209)
			(xy 453.371113 -56.08113) (xy 453.383298 -56.107688) (xy 453.39254 -56.119014) (xy 453.410194 -56.139937)
			(xy 453.439921 -56.185905) (xy 453.462767 -56.235653) (xy 453.478264 -56.288157) (xy 453.486092 -56.342337)
			(xy 453.486091 -56.397081) (xy 453.47826 -56.451261) (xy 453.462761 -56.503764) (xy 453.439912 -56.553511)
			(xy 453.410183 -56.599478) (xy 453.39254 -56.62041) (xy 453.383288 -56.631727) (xy 453.371108 -56.658288)
			(xy 453.366935 -56.687209) (xy 453.371113 -56.71613) (xy 453.383298 -56.742688) (xy 453.39254 -56.754014)
			(xy 453.410194 -56.774937) (xy 453.439921 -56.820905) (xy 453.462767 -56.870653) (xy 453.478264 -56.923157)
			(xy 453.486092 -56.977337) (xy 453.486091 -57.032081) (xy 453.47826 -57.086261) (xy 453.462761 -57.138764)
			(xy 453.439912 -57.188511) (xy 453.410183 -57.234478) (xy 453.39254 -57.25541) (xy 453.383288 -57.266727)
			(xy 453.371108 -57.293288) (xy 453.366935 -57.322209) (xy 453.371113 -57.35113) (xy 453.383298 -57.377688)
			(xy 453.39254 -57.389014) (xy 453.410159 -57.409962) (xy 453.439872 -57.455931) (xy 453.462712 -57.505675)
			(xy 453.478208 -57.558172) (xy 453.486043 -57.612344) (xy 453.48652 -57.639712) (xy 453.486034 -57.666963)
			(xy 453.478278 -57.720911) (xy 453.462923 -57.773206) (xy 453.440281 -57.822783) (xy 453.410815 -57.868633)
			(xy 453.375124 -57.909824) (xy 453.333933 -57.945515) (xy 453.288083 -57.974981) (xy 453.238506 -57.997623)
			(xy 453.186211 -58.012978) (xy 453.132263 -58.020734) (xy 453.077761 -58.020734) (xy 453.023813 -58.012978)
			(xy 452.971518 -57.997623) (xy 452.921941 -57.974981) (xy 452.876091 -57.945515) (xy 452.8349 -57.909824)
			(xy 452.799209 -57.868633) (xy 452.769743 -57.822783) (xy 452.747101 -57.773206) (xy 452.731746 -57.720911)
			(xy 452.72399 -57.666963) (xy 452.723504 -57.639712) (xy 445.405448 -57.639712) (xy 445.401078 -57.670111)
			(xy 445.385723 -57.722406) (xy 445.363081 -57.771983) (xy 445.333615 -57.817833) (xy 445.297924 -57.859024)
			(xy 445.256733 -57.894715) (xy 445.210883 -57.924181) (xy 445.161306 -57.946823) (xy 445.109011 -57.962178)
			(xy 445.055063 -57.969934) (xy 445.000561 -57.969934) (xy 444.946613 -57.962178) (xy 444.894318 -57.946823)
			(xy 444.844741 -57.924181) (xy 444.798891 -57.894715) (xy 444.7577 -57.859024) (xy 444.722009 -57.817833)
			(xy 444.692543 -57.771983) (xy 444.669901 -57.722406) (xy 444.654546 -57.670111) (xy 444.64679 -57.616163)
			(xy 444.646304 -57.588912) (xy 442.892688 -57.588912) (xy 442.892688 -59.418982) (xy 462.938622 -59.418982)
			(xy 462.939072 -59.391611) (xy 462.946893 -59.337431) (xy 462.962386 -59.284928) (xy 462.985231 -59.235181)
			(xy 463.014959 -59.189215) (xy 463.032602 -59.168284) (xy 463.041856 -59.15697) (xy 463.054031 -59.130407)
			(xy 463.0582 -59.101486) (xy 463.054023 -59.072567) (xy 463.041841 -59.046007) (xy 463.032602 -59.03468)
			(xy 463.014945 -59.013761) (xy 462.985223 -58.96779) (xy 462.96238 -58.918042) (xy 462.946886 -58.865538)
			(xy 462.93906 -58.811358) (xy 462.939062 -58.756615) (xy 462.946892 -58.702436) (xy 462.962389 -58.649933)
			(xy 462.985236 -58.600186) (xy 463.014961 -58.554217) (xy 463.032602 -58.533284) (xy 463.041856 -58.52197)
			(xy 463.054031 -58.495407) (xy 463.0582 -58.466486) (xy 463.054023 -58.437567) (xy 463.041841 -58.411007)
			(xy 463.032602 -58.39968) (xy 463.014987 -58.378728) (xy 462.985272 -58.332761) (xy 462.962431 -58.283018)
			(xy 462.946934 -58.230522) (xy 462.9391 -58.17635) (xy 462.938622 -58.148982) (xy 462.939156 -58.120244)
			(xy 462.947779 -58.063418) (xy 462.964828 -58.008528) (xy 462.989917 -57.956816) (xy 463.022478 -57.909452)
			(xy 463.041746 -57.888124) (xy 463.051837 -57.876605) (xy 463.065181 -57.849054) (xy 463.069763 -57.818787)
			(xy 463.065173 -57.788521) (xy 463.051822 -57.760973) (xy 463.041746 -57.74944) (xy 463.022456 -57.728129)
			(xy 462.98989 -57.680765) (xy 462.964798 -57.62905) (xy 462.947748 -57.574157) (xy 462.939127 -57.517327)
			(xy 462.939129 -57.459847) (xy 462.947754 -57.403017) (xy 462.964807 -57.348125) (xy 462.989903 -57.296413)
			(xy 463.022473 -57.24905) (xy 463.041746 -57.227724) (xy 463.051837 -57.216205) (xy 463.065181 -57.188654)
			(xy 463.069763 -57.158387) (xy 463.065173 -57.128121) (xy 463.051822 -57.100573) (xy 463.041746 -57.08904)
			(xy 463.022468 -57.067719) (xy 462.989902 -57.020356) (xy 462.964811 -56.968642) (xy 462.947762 -56.91375)
			(xy 462.939142 -56.856921) (xy 462.938622 -56.828182) (xy 462.939038 -56.800927) (xy 462.946798 -56.746973)
			(xy 462.962158 -56.694672) (xy 462.984805 -56.64509) (xy 463.014278 -56.599236) (xy 463.049976 -56.558042)
			(xy 463.091174 -56.522349) (xy 463.137032 -56.492882) (xy 463.186618 -56.470241) (xy 463.23892 -56.454888)
			(xy 463.292875 -56.447135) (xy 463.32013 -56.446674) (xy 463.349046 -56.447215) (xy 463.406218 -56.455935)
			(xy 463.461417 -56.473187) (xy 463.51338 -56.498574) (xy 463.560914 -56.531515) (xy 463.60293 -56.571255)
			(xy 463.62112 -56.59374) (xy 463.631017 -56.605545) (xy 463.656341 -56.623064) (xy 463.685734 -56.63224)
			(xy 463.716526 -56.63224) (xy 463.745919 -56.623064) (xy 463.771243 -56.605545) (xy 463.78114 -56.59374)
			(xy 463.799319 -56.571246) (xy 463.84134 -56.531509) (xy 463.888877 -56.49857) (xy 463.940841 -56.473184)
			(xy 463.996041 -56.45593) (xy 464.053213 -56.447206) (xy 464.08213 -56.446674) (xy 464.110869 -56.447186)
			(xy 464.167697 -56.455813) (xy 464.222587 -56.472866) (xy 464.274299 -56.49796) (xy 464.321661 -56.530527)
			(xy 464.342988 -56.549798) (xy 464.354522 -56.55987) (xy 464.382068 -56.573212) (xy 464.41233 -56.577797)
			(xy 464.442592 -56.573212) (xy 464.470138 -56.55987) (xy 464.481672 -56.549798) (xy 464.502999 -56.530528)
			(xy 464.550362 -56.497963) (xy 464.602073 -56.472872) (xy 464.656964 -56.455822) (xy 464.713791 -56.4472)
			(xy 464.771269 -56.4472) (xy 464.828096 -56.455822) (xy 464.882987 -56.472872) (xy 464.934698 -56.497963)
			(xy 464.982061 -56.530528) (xy 465.003388 -56.549798) (xy 465.014922 -56.55987) (xy 465.042468 -56.573212)
			(xy 465.07273 -56.577797) (xy 465.102992 -56.573212) (xy 465.130538 -56.55987) (xy 465.142072 -56.549798)
			(xy 465.163399 -56.530528) (xy 465.210762 -56.497963) (xy 465.262473 -56.472872) (xy 465.317364 -56.455822)
			(xy 465.374191 -56.4472) (xy 465.431669 -56.4472) (xy 465.488496 -56.455822) (xy 465.543387 -56.472872)
			(xy 465.595098 -56.497963) (xy 465.642461 -56.530528) (xy 465.663788 -56.549798) (xy 465.675322 -56.55987)
			(xy 465.702868 -56.573212) (xy 465.73313 -56.577797) (xy 465.763392 -56.573212) (xy 465.790938 -56.55987)
			(xy 465.802472 -56.549798) (xy 465.823796 -56.530523) (xy 465.871158 -56.497955) (xy 465.92287 -56.472863)
			(xy 465.977762 -56.455813) (xy 466.034591 -56.447193) (xy 466.06333 -56.446674) (xy 466.092246 -56.447215)
			(xy 466.149418 -56.455935) (xy 466.204617 -56.473187) (xy 466.25658 -56.498574) (xy 466.304114 -56.531515)
			(xy 466.34613 -56.571255) (xy 466.36432 -56.59374) (xy 466.374217 -56.605545) (xy 466.399541 -56.623064)
			(xy 466.428934 -56.63224) (xy 466.459726 -56.63224) (xy 466.489119 -56.623064) (xy 466.514443 -56.605545)
			(xy 466.52434 -56.59374) (xy 466.542519 -56.571246) (xy 466.58454 -56.531509) (xy 466.632077 -56.49857)
			(xy 466.684041 -56.473184) (xy 466.739241 -56.45593) (xy 466.796413 -56.447206) (xy 466.82533 -56.446674)
			(xy 466.852581 -56.44715) (xy 466.906528 -56.45491) (xy 466.958822 -56.470268) (xy 467.008398 -56.492911)
			(xy 467.054248 -56.522379) (xy 467.095437 -56.558071) (xy 467.131128 -56.599262) (xy 467.160594 -56.645112)
			(xy 467.183236 -56.694689) (xy 467.198593 -56.746983) (xy 467.206351 -56.800931) (xy 467.206838 -56.828182)
			(xy 467.206293 -56.85692) (xy 467.197674 -56.913746) (xy 467.180628 -56.968636) (xy 467.155542 -57.020348)
			(xy 467.122982 -57.067712) (xy 467.103714 -57.08904) (xy 467.093661 -57.100589) (xy 467.080319 -57.12813)
			(xy 467.075732 -57.158387) (xy 467.080311 -57.188645) (xy 467.093646 -57.21619) (xy 467.103714 -57.227724)
			(xy 467.122965 -57.249067) (xy 467.155528 -57.296428) (xy 467.180618 -57.348137) (xy 467.197667 -57.403025)
			(xy 467.206291 -57.459849) (xy 467.206293 -57.517324) (xy 467.197673 -57.574149) (xy 467.180628 -57.629038)
			(xy 467.155541 -57.680749) (xy 467.122982 -57.728112) (xy 467.103714 -57.74944) (xy 467.093661 -57.760989)
			(xy 467.080319 -57.78853) (xy 467.075732 -57.818787) (xy 467.080311 -57.849045) (xy 467.093646 -57.87659)
			(xy 467.103714 -57.888124) (xy 467.122968 -57.909465) (xy 467.155539 -57.956823) (xy 467.180635 -58.008531)
			(xy 467.197689 -58.063418) (xy 467.206316 -58.120244) (xy 467.206838 -58.148982) (xy 467.206376 -58.176353)
			(xy 467.19856 -58.230532) (xy 467.183071 -58.283036) (xy 467.160227 -58.332783) (xy 467.130501 -58.378749)
			(xy 467.112858 -58.39968) (xy 467.103642 -58.411022) (xy 467.091467 -58.437575) (xy 467.087293 -58.466486)
			(xy 467.09146 -58.495399) (xy 467.103627 -58.521955) (xy 467.112858 -58.533284) (xy 467.130482 -58.554231)
			(xy 467.160208 -58.600196) (xy 467.183056 -58.64994) (xy 467.198554 -58.70244) (xy 467.206385 -58.756617)
			(xy 467.206387 -58.811356) (xy 467.19856 -58.865534) (xy 467.183065 -58.918035) (xy 467.160221 -58.96778)
			(xy 467.130498 -59.013748) (xy 467.112858 -59.03468) (xy 467.103642 -59.046022) (xy 467.091467 -59.072575)
			(xy 467.087293 -59.101486) (xy 467.09146 -59.130399) (xy 467.103627 -59.156955) (xy 467.112858 -59.168284)
			(xy 467.130497 -59.189217) (xy 467.16021 -59.235189) (xy 467.183047 -59.284936) (xy 467.198538 -59.337437)
			(xy 467.206365 -59.391613) (xy 467.206838 -59.418982) (xy 467.206305 -59.446231) (xy 467.198552 -59.500176)
			(xy 467.1832 -59.552468) (xy 467.160564 -59.602043) (xy 467.131102 -59.647892) (xy 467.095416 -59.689082)
			(xy 467.05423 -59.724773) (xy 467.008385 -59.754241) (xy 466.958813 -59.776884) (xy 466.906523 -59.792242)
			(xy 466.852579 -59.800002) (xy 466.82533 -59.80049) (xy 466.796414 -59.799954) (xy 466.739243 -59.791229)
			(xy 466.684045 -59.773975) (xy 466.632083 -59.748587) (xy 466.584548 -59.715646) (xy 466.542531 -59.675908)
			(xy 466.52434 -59.653424) (xy 466.514443 -59.641619) (xy 466.489119 -59.6241) (xy 466.459726 -59.614924)
			(xy 466.428934 -59.614924) (xy 466.399541 -59.6241) (xy 466.374217 -59.641619) (xy 466.36432 -59.653424)
			(xy 466.346124 -59.675903) (xy 466.304104 -59.715637) (xy 466.25657 -59.748576) (xy 466.20461 -59.773965)
			(xy 466.149414 -59.791223) (xy 466.092246 -59.799954) (xy 466.06333 -59.80049) (xy 466.034592 -59.799951)
			(xy 465.977765 -59.791332) (xy 465.922874 -59.774286) (xy 465.871162 -59.749198) (xy 465.823799 -59.716636)
			(xy 465.802472 -59.697366) (xy 465.790938 -59.687294) (xy 465.763392 -59.673952) (xy 465.73313 -59.669367)
			(xy 465.702868 -59.673952) (xy 465.675322 -59.687294) (xy 465.663788 -59.697366) (xy 465.642461 -59.716636)
			(xy 465.595098 -59.749201) (xy 465.543387 -59.774292) (xy 465.488496 -59.791342) (xy 465.431669 -59.799964)
			(xy 465.374191 -59.799964) (xy 465.317364 -59.791342) (xy 465.262473 -59.774292) (xy 465.210762 -59.749201)
			(xy 465.163399 -59.716636) (xy 465.142072 -59.697366) (xy 465.130538 -59.687294) (xy 465.102992 -59.673952)
			(xy 465.07273 -59.669367) (xy 465.042468 -59.673952) (xy 465.014922 -59.687294) (xy 465.003388 -59.697366)
			(xy 464.982061 -59.716636) (xy 464.934698 -59.749201) (xy 464.882987 -59.774292) (xy 464.828096 -59.791342)
			(xy 464.771269 -59.799964) (xy 464.713791 -59.799964) (xy 464.656964 -59.791342) (xy 464.602073 -59.774292)
			(xy 464.550362 -59.749201) (xy 464.502999 -59.716636) (xy 464.481672 -59.697366) (xy 464.470138 -59.687294)
			(xy 464.442592 -59.673952) (xy 464.41233 -59.669367) (xy 464.382068 -59.673952) (xy 464.354522 -59.687294)
			(xy 464.342988 -59.697366) (xy 464.321649 -59.716623) (xy 464.27429 -59.749191) (xy 464.222582 -59.774286)
			(xy 464.167694 -59.79134) (xy 464.110868 -59.799967) (xy 464.08213 -59.80049) (xy 464.053214 -59.799954)
			(xy 463.996043 -59.791229) (xy 463.940845 -59.773975) (xy 463.888883 -59.748587) (xy 463.841348 -59.715646)
			(xy 463.799331 -59.675908) (xy 463.78114 -59.653424) (xy 463.771243 -59.641619) (xy 463.745919 -59.6241)
			(xy 463.716526 -59.614924) (xy 463.685734 -59.614924) (xy 463.656341 -59.6241) (xy 463.631017 -59.641619)
			(xy 463.62112 -59.653424) (xy 463.602924 -59.675903) (xy 463.560904 -59.715637) (xy 463.51337 -59.748576)
			(xy 463.46141 -59.773965) (xy 463.406214 -59.791223) (xy 463.349046 -59.799954) (xy 463.32013 -59.80049)
			(xy 463.292877 -59.800017) (xy 463.238926 -59.792263) (xy 463.186627 -59.77691) (xy 463.137046 -59.75427)
			(xy 463.091191 -59.724803) (xy 463.049998 -59.689111) (xy 463.014304 -59.647918) (xy 462.984836 -59.602065)
			(xy 462.962194 -59.552484) (xy 462.946839 -59.500186) (xy 462.939084 -59.446235) (xy 462.938622 -59.418982)
			(xy 442.892688 -59.418982) (xy 442.892688 -68.56215) (xy 463.017866 -68.56215) (xy 463.017866 -68.477454)
			(xy 463.025917 -68.39314) (xy 463.041946 -68.309974) (xy 463.065807 -68.228707) (xy 463.097286 -68.150077)
			(xy 463.136097 -68.074796) (xy 463.181887 -68.003544) (xy 463.234243 -67.936968) (xy 463.292691 -67.87567)
			(xy 463.356701 -67.820205) (xy 463.425693 -67.771076) (xy 463.499043 -67.728727) (xy 463.576086 -67.693543)
			(xy 463.656125 -67.665841) (xy 463.738434 -67.645873) (xy 463.822269 -67.63382) (xy 463.90687 -67.62979)
			(xy 463.991471 -67.63382) (xy 464.075306 -67.645873) (xy 464.157615 -67.665841) (xy 464.237654 -67.693543)
			(xy 464.314697 -67.728727) (xy 464.388047 -67.771076) (xy 464.457039 -67.820205) (xy 464.521049 -67.87567)
			(xy 464.579497 -67.936968) (xy 464.631853 -68.003544) (xy 464.677643 -68.074796) (xy 464.716454 -68.150077)
			(xy 464.747933 -68.228707) (xy 464.771794 -68.309974) (xy 464.787823 -68.39314) (xy 464.795874 -68.477454)
			(xy 464.796378 -68.519802) (xy 465.542379 -68.519802) (xy 465.546415 -68.436355) (xy 465.558487 -68.353687)
			(xy 465.57848 -68.27257) (xy 465.606209 -68.193761) (xy 465.641415 -68.117996) (xy 465.683769 -68.045983)
			(xy 465.732875 -67.978394) (xy 465.788276 -67.91586) (xy 465.849453 -67.858965) (xy 465.915836 -67.808239)
			(xy 465.986804 -67.764158) (xy 466.061696 -67.727132) (xy 466.139812 -67.697506) (xy 466.220422 -67.675558)
			(xy 466.302774 -67.661493) (xy 466.3861 -67.655441) (xy 466.46962 -67.65746) (xy 466.552556 -67.66753)
			(xy 466.634132 -67.685558) (xy 466.713588 -67.711375) (xy 466.790181 -67.74474) (xy 466.863197 -67.785341)
			(xy 466.931953 -67.8328) (xy 466.995807 -67.886673) (xy 467.054164 -67.946458) (xy 467.106479 -68.011595)
			(xy 467.152262 -68.081478) (xy 467.191087 -68.155453) (xy 467.222592 -68.23283) (xy 467.246481 -68.312887)
			(xy 467.262532 -68.394875) (xy 467.270595 -68.47803) (xy 467.2711 -68.519802) (xy 467.270595 -68.561574)
			(xy 467.262532 -68.644729) (xy 467.246481 -68.726717) (xy 467.222592 -68.806774) (xy 467.191087 -68.884151)
			(xy 467.152262 -68.958126) (xy 467.106479 -69.028009) (xy 467.054164 -69.093146) (xy 466.995807 -69.152931)
			(xy 466.931953 -69.206804) (xy 466.863197 -69.254263) (xy 466.790181 -69.294864) (xy 466.713588 -69.328229)
			(xy 466.634132 -69.354046) (xy 466.552556 -69.372074) (xy 466.46962 -69.382144) (xy 466.3861 -69.384163)
			(xy 466.302774 -69.378111) (xy 466.220422 -69.364046) (xy 466.139812 -69.342098) (xy 466.061696 -69.312472)
			(xy 465.986804 -69.275446) (xy 465.915836 -69.231365) (xy 465.849453 -69.180639) (xy 465.788276 -69.123744)
			(xy 465.732875 -69.06121) (xy 465.683769 -68.993621) (xy 465.641415 -68.921608) (xy 465.606209 -68.845843)
			(xy 465.57848 -68.767034) (xy 465.558487 -68.685917) (xy 465.546415 -68.603249) (xy 465.542379 -68.519802)
			(xy 464.796378 -68.519802) (xy 464.795874 -68.56215) (xy 464.787823 -68.646464) (xy 464.771794 -68.72963)
			(xy 464.747933 -68.810897) (xy 464.716454 -68.889527) (xy 464.677643 -68.964808) (xy 464.631853 -69.03606)
			(xy 464.579497 -69.102636) (xy 464.521049 -69.163934) (xy 464.457039 -69.219399) (xy 464.388047 -69.268528)
			(xy 464.314697 -69.310877) (xy 464.237654 -69.346061) (xy 464.157615 -69.373763) (xy 464.075306 -69.393731)
			(xy 463.991471 -69.405784) (xy 463.90687 -69.409815) (xy 463.822269 -69.405784) (xy 463.738434 -69.393731)
			(xy 463.656125 -69.373763) (xy 463.576086 -69.346061) (xy 463.499043 -69.310877) (xy 463.425693 -69.268528)
			(xy 463.356701 -69.219399) (xy 463.292691 -69.163934) (xy 463.234243 -69.102636) (xy 463.181887 -69.03606)
			(xy 463.136097 -68.964808) (xy 463.097286 -68.889527) (xy 463.065807 -68.810897) (xy 463.041946 -68.72963)
			(xy 463.025917 -68.646464) (xy 463.017866 -68.56215) (xy 442.892688 -68.56215) (xy 442.892688 -71.039228)
			(xy 443.224918 -71.039228) (xy 443.228989 -70.983606) (xy 443.241115 -70.929169) (xy 443.261038 -70.877078)
			(xy 443.288334 -70.828443) (xy 443.32242 -70.7843) (xy 443.362569 -70.745591) (xy 443.407927 -70.71314)
			(xy 443.457527 -70.687639) (xy 443.510311 -70.669632) (xy 443.565154 -70.659502) (xy 443.620888 -70.657465)
			(xy 443.676325 -70.663565) (xy 443.730282 -70.677671) (xy 443.781611 -70.699483) (xy 443.829217 -70.728537)
			(xy 443.872085 -70.764212) (xy 443.909302 -70.805749) (xy 443.940075 -70.852262) (xy 443.963747 -70.902759)
			(xy 443.979815 -70.956166) (xy 443.987935 -71.011342) (xy 443.988444 -71.039228) (xy 443.987935 -71.067114)
			(xy 443.979815 -71.12229) (xy 443.963747 -71.175697) (xy 443.940075 -71.226194) (xy 443.909302 -71.272707)
			(xy 443.872085 -71.314244) (xy 443.829217 -71.349919) (xy 443.781611 -71.378973) (xy 443.730282 -71.400785)
			(xy 443.676325 -71.414891) (xy 443.620888 -71.420991) (xy 443.565154 -71.418954) (xy 443.510311 -71.408824)
			(xy 443.457527 -71.390817) (xy 443.407927 -71.365316) (xy 443.362569 -71.332865) (xy 443.32242 -71.294156)
			(xy 443.288334 -71.250013) (xy 443.261038 -71.201378) (xy 443.241115 -71.149287) (xy 443.228989 -71.09485)
			(xy 443.224918 -71.039228) (xy 442.892688 -71.039228) (xy 442.892688 -73.088052) (xy 452.643969 -73.088052)
			(xy 452.643969 -73.033548) (xy 452.651726 -72.979599) (xy 452.667082 -72.927303) (xy 452.689723 -72.877724)
			(xy 452.719191 -72.831873) (xy 452.754883 -72.790682) (xy 452.796074 -72.754989) (xy 452.841926 -72.725522)
			(xy 452.891505 -72.702881) (xy 452.943801 -72.687526) (xy 452.99775 -72.679769) (xy 453.025002 -72.679306)
			(xy 453.052711 -72.679821) (xy 453.107544 -72.687844) (xy 453.160639 -72.703721) (xy 453.210876 -72.727117)
			(xy 453.257196 -72.75754) (xy 453.27824 -72.775572) (xy 453.289642 -72.78504) (xy 453.316492 -72.797557)
			(xy 453.345804 -72.80185) (xy 453.375116 -72.797557) (xy 453.401966 -72.78504) (xy 453.413368 -72.775572)
			(xy 453.434411 -72.757537) (xy 453.480729 -72.727108) (xy 453.530966 -72.703707) (xy 453.584061 -72.687827)
			(xy 453.638896 -72.679803) (xy 453.666606 -72.679306) (xy 453.693858 -72.679764) (xy 453.747807 -72.687522)
			(xy 453.800103 -72.702878) (xy 453.849681 -72.72552) (xy 453.895533 -72.754988) (xy 453.936724 -72.790681)
			(xy 453.972416 -72.831872) (xy 454.001883 -72.877724) (xy 454.024524 -72.927303) (xy 454.03988 -72.979599)
			(xy 454.047636 -73.033548) (xy 454.047636 -73.088052) (xy 454.047636 -73.088053) (xy 454.467669 -73.088053)
			(xy 454.467669 -73.033547) (xy 454.475427 -72.979596) (xy 454.490783 -72.927299) (xy 454.513426 -72.877719)
			(xy 454.542895 -72.831866) (xy 454.57859 -72.790675) (xy 454.619784 -72.754982) (xy 454.665638 -72.725516)
			(xy 454.715219 -72.702876) (xy 454.767518 -72.687522) (xy 454.821469 -72.679768) (xy 454.848722 -72.679306)
			(xy 454.876431 -72.679809) (xy 454.931265 -72.687835) (xy 454.98436 -72.703715) (xy 455.034596 -72.727113)
			(xy 455.080916 -72.757538) (xy 455.10196 -72.775572) (xy 455.113362 -72.78504) (xy 455.140212 -72.797557)
			(xy 455.169524 -72.80185) (xy 455.198836 -72.797557) (xy 455.225686 -72.78504) (xy 455.237088 -72.775572)
			(xy 455.258124 -72.757528) (xy 455.304444 -72.7271) (xy 455.354682 -72.703701) (xy 455.407779 -72.687823)
			(xy 455.462616 -72.679801) (xy 455.490326 -72.679306) (xy 455.517577 -72.679766) (xy 455.571524 -72.687525)
			(xy 455.623817 -72.702883) (xy 455.673393 -72.725527) (xy 455.719242 -72.754995) (xy 455.760431 -72.790688)
			(xy 455.796121 -72.831879) (xy 455.825586 -72.87773) (xy 455.848226 -72.927307) (xy 455.86358 -72.979602)
			(xy 455.871336 -73.033549) (xy 455.871336 -73.088051) (xy 455.86358 -73.141998) (xy 455.848226 -73.194293)
			(xy 455.825586 -73.24387) (xy 455.796121 -73.289721) (xy 455.760431 -73.330912) (xy 455.719242 -73.366605)
			(xy 455.673393 -73.396073) (xy 455.623817 -73.418717) (xy 455.571524 -73.434075) (xy 455.517577 -73.441834)
			(xy 455.490326 -73.442322) (xy 455.462616 -73.441843) (xy 455.407781 -73.43381) (xy 455.354686 -73.417924)
			(xy 455.30445 -73.39452) (xy 455.258131 -73.364091) (xy 455.237088 -73.346056) (xy 455.225686 -73.336588)
			(xy 455.198836 -73.324071) (xy 455.169524 -73.319778) (xy 455.140212 -73.324071) (xy 455.113362 -73.336588)
			(xy 455.10196 -73.346056) (xy 455.08091 -73.364082) (xy 455.034593 -73.394511) (xy 454.984358 -73.417914)
			(xy 454.931265 -73.433796) (xy 454.876431 -73.441823) (xy 454.848722 -73.442322) (xy 454.821469 -73.441832)
			(xy 454.767518 -73.434078) (xy 454.715219 -73.418724) (xy 454.665638 -73.396084) (xy 454.619784 -73.366618)
			(xy 454.57859 -73.330925) (xy 454.542895 -73.289734) (xy 454.513426 -73.243881) (xy 454.490783 -73.194301)
			(xy 454.475427 -73.142004) (xy 454.467669 -73.088053) (xy 454.047636 -73.088053) (xy 454.03988 -73.142001)
			(xy 454.024524 -73.194297) (xy 454.001883 -73.243876) (xy 453.972416 -73.289728) (xy 453.936724 -73.330919)
			(xy 453.895533 -73.366612) (xy 453.849681 -73.39608) (xy 453.800103 -73.418722) (xy 453.747807 -73.434078)
			(xy 453.693858 -73.441836) (xy 453.666606 -73.442322) (xy 453.638898 -73.441795) (xy 453.584065 -73.433774)
			(xy 453.530971 -73.4179) (xy 453.480734 -73.394506) (xy 453.434413 -73.364087) (xy 453.413368 -73.346056)
			(xy 453.401966 -73.336588) (xy 453.375116 -73.324071) (xy 453.345804 -73.319778) (xy 453.316492 -73.324071)
			(xy 453.289642 -73.336588) (xy 453.27824 -73.346056) (xy 453.257197 -73.364091) (xy 453.210879 -73.394519)
			(xy 453.160642 -73.41792) (xy 453.107547 -73.4338) (xy 453.052712 -73.441825) (xy 453.025002 -73.442322)
			(xy 452.99775 -73.441831) (xy 452.943801 -73.434074) (xy 452.891505 -73.418719) (xy 452.841926 -73.396078)
			(xy 452.796074 -73.366611) (xy 452.754883 -73.330918) (xy 452.719191 -73.289727) (xy 452.689723 -73.243876)
			(xy 452.667082 -73.194297) (xy 452.651726 -73.142001) (xy 452.643969 -73.088052) (xy 442.892688 -73.088052)
			(xy 442.892688 -73.181718) (xy 444.084456 -74.373486) (xy 444.120016 -74.344784) (xy 444.140483 -74.328727)
			(xy 444.184944 -74.301723) (xy 444.232663 -74.281014) (xy 444.282756 -74.266986) (xy 444.33429 -74.2599)
			(xy 444.3603 -74.25944) (xy 444.387552 -74.259903) (xy 444.4415 -74.267661) (xy 444.493795 -74.283017)
			(xy 444.543372 -74.30566) (xy 444.589222 -74.335129) (xy 444.630411 -74.370823) (xy 444.6661 -74.412017)
			(xy 444.695563 -74.45787) (xy 444.7182 -74.50745) (xy 444.73355 -74.559747) (xy 444.7413 -74.613696)
			(xy 444.741808 -74.640948) (xy 444.741345 -74.666955) (xy 444.734236 -74.718483) (xy 444.720198 -74.768569)
			(xy 444.69949 -74.816285) (xy 444.672495 -74.860747) (xy 444.656464 -74.881232) (xy 444.627762 -74.916792)
			(xy 444.76504 -75.054206) (xy 451.065898 -75.054206) (xy 451.069969 -74.998584) (xy 451.082095 -74.944147)
			(xy 451.102018 -74.892056) (xy 451.129314 -74.843421) (xy 451.1634 -74.799278) (xy 451.203549 -74.760569)
			(xy 451.248907 -74.728118) (xy 451.298507 -74.702617) (xy 451.351291 -74.68461) (xy 451.406134 -74.67448)
			(xy 451.461868 -74.672443) (xy 451.517305 -74.678543) (xy 451.571262 -74.692649) (xy 451.622591 -74.714461)
			(xy 451.670197 -74.743515) (xy 451.713065 -74.77919) (xy 451.745377 -74.815253) (xy 454.048569 -74.815253)
			(xy 454.048569 -74.760747) (xy 454.056327 -74.706796) (xy 454.071683 -74.654499) (xy 454.094326 -74.604919)
			(xy 454.123795 -74.559066) (xy 454.15949 -74.517875) (xy 454.200684 -74.482182) (xy 454.246538 -74.452716)
			(xy 454.296119 -74.430076) (xy 454.348418 -74.414722) (xy 454.402369 -74.406968) (xy 454.429622 -74.406506)
			(xy 454.457331 -74.407009) (xy 454.512165 -74.415035) (xy 454.56526 -74.430915) (xy 454.615496 -74.454313)
			(xy 454.661816 -74.484738) (xy 454.68286 -74.502772) (xy 454.694262 -74.51224) (xy 454.721112 -74.524757)
			(xy 454.750424 -74.52905) (xy 454.779736 -74.524757) (xy 454.806586 -74.51224) (xy 454.817988 -74.502772)
			(xy 454.839024 -74.484728) (xy 454.885344 -74.4543) (xy 454.935582 -74.430901) (xy 454.988679 -74.415023)
			(xy 455.043516 -74.407001) (xy 455.071226 -74.406506) (xy 455.098477 -74.406966) (xy 455.152424 -74.414725)
			(xy 455.204717 -74.430083) (xy 455.254293 -74.452727) (xy 455.300142 -74.482195) (xy 455.341331 -74.517888)
			(xy 455.377021 -74.559079) (xy 455.406486 -74.60493) (xy 455.429126 -74.654507) (xy 455.44448 -74.706802)
			(xy 455.452236 -74.760749) (xy 455.452236 -74.815251) (xy 455.44448 -74.869198) (xy 455.429126 -74.921493)
			(xy 455.406486 -74.97107) (xy 455.377021 -75.016921) (xy 455.341331 -75.058112) (xy 455.300142 -75.093805)
			(xy 455.254293 -75.123273) (xy 455.204717 -75.145917) (xy 455.152424 -75.161275) (xy 455.098477 -75.169034)
			(xy 455.071226 -75.169522) (xy 455.043516 -75.169043) (xy 454.988681 -75.16101) (xy 454.935586 -75.145124)
			(xy 454.88535 -75.12172) (xy 454.839031 -75.091291) (xy 454.817988 -75.073256) (xy 454.806586 -75.063788)
			(xy 454.779736 -75.051271) (xy 454.750424 -75.046978) (xy 454.721112 -75.051271) (xy 454.694262 -75.063788)
			(xy 454.68286 -75.073256) (xy 454.66181 -75.091282) (xy 454.615493 -75.121711) (xy 454.565258 -75.145114)
			(xy 454.512165 -75.160996) (xy 454.457331 -75.169023) (xy 454.429622 -75.169522) (xy 454.402369 -75.169032)
			(xy 454.348418 -75.161278) (xy 454.296119 -75.145924) (xy 454.246538 -75.123284) (xy 454.200684 -75.093818)
			(xy 454.15949 -75.058125) (xy 454.123795 -75.016934) (xy 454.094326 -74.971081) (xy 454.071683 -74.921501)
			(xy 454.056327 -74.869204) (xy 454.048569 -74.815253) (xy 451.745377 -74.815253) (xy 451.750282 -74.820727)
			(xy 451.781055 -74.86724) (xy 451.804727 -74.917737) (xy 451.820795 -74.971144) (xy 451.828915 -75.02632)
			(xy 451.829424 -75.054206) (xy 451.828915 -75.082092) (xy 451.820795 -75.137268) (xy 451.804727 -75.190675)
			(xy 451.781055 -75.241172) (xy 451.750282 -75.287685) (xy 451.713065 -75.329222) (xy 451.670197 -75.364897)
			(xy 451.622591 -75.393951) (xy 451.571262 -75.415763) (xy 451.517305 -75.429869) (xy 451.461868 -75.435969)
			(xy 451.406134 -75.433932) (xy 451.351291 -75.423802) (xy 451.298507 -75.405795) (xy 451.248907 -75.380294)
			(xy 451.203549 -75.347843) (xy 451.1634 -75.309134) (xy 451.129314 -75.264991) (xy 451.102018 -75.216356)
			(xy 451.082095 -75.164265) (xy 451.069969 -75.109828) (xy 451.065898 -75.054206) (xy 444.76504 -75.054206)
			(xy 444.885064 -75.174348) (xy 445.1223 -75.174348) (xy 445.58712 -75.639168) (xy 445.58712 -76.002572)
			(xy 463.017866 -76.002572) (xy 463.017866 -75.917876) (xy 463.025917 -75.833562) (xy 463.041946 -75.750396)
			(xy 463.065807 -75.669129) (xy 463.097286 -75.590499) (xy 463.136097 -75.515218) (xy 463.181887 -75.443966)
			(xy 463.234243 -75.37739) (xy 463.292691 -75.316092) (xy 463.356701 -75.260627) (xy 463.425693 -75.211498)
			(xy 463.499043 -75.169149) (xy 463.576086 -75.133965) (xy 463.656125 -75.106263) (xy 463.738434 -75.086295)
			(xy 463.822269 -75.074242) (xy 463.90687 -75.070212) (xy 463.991471 -75.074242) (xy 464.075306 -75.086295)
			(xy 464.157615 -75.106263) (xy 464.237654 -75.133965) (xy 464.314697 -75.169149) (xy 464.388047 -75.211498)
			(xy 464.457039 -75.260627) (xy 464.521049 -75.316092) (xy 464.579497 -75.37739) (xy 464.631853 -75.443966)
			(xy 464.677643 -75.515218) (xy 464.716454 -75.590499) (xy 464.747933 -75.669129) (xy 464.771794 -75.750396)
			(xy 464.787823 -75.833562) (xy 464.795874 -75.917876) (xy 464.796378 -75.960224) (xy 465.542379 -75.960224)
			(xy 465.546415 -75.876777) (xy 465.558487 -75.794109) (xy 465.57848 -75.712992) (xy 465.606209 -75.634183)
			(xy 465.641415 -75.558418) (xy 465.683769 -75.486405) (xy 465.732875 -75.418816) (xy 465.788276 -75.356282)
			(xy 465.849453 -75.299387) (xy 465.915836 -75.248661) (xy 465.986804 -75.20458) (xy 466.061696 -75.167554)
			(xy 466.139812 -75.137928) (xy 466.220422 -75.11598) (xy 466.302774 -75.101915) (xy 466.3861 -75.095863)
			(xy 466.46962 -75.097882) (xy 466.552556 -75.107952) (xy 466.634132 -75.12598) (xy 466.713588 -75.151797)
			(xy 466.790181 -75.185162) (xy 466.863197 -75.225763) (xy 466.931953 -75.273222) (xy 466.995807 -75.327095)
			(xy 467.054164 -75.38688) (xy 467.106479 -75.452017) (xy 467.152262 -75.5219) (xy 467.191087 -75.595875)
			(xy 467.222592 -75.673252) (xy 467.246481 -75.753309) (xy 467.262532 -75.835297) (xy 467.270595 -75.918452)
			(xy 467.2711 -75.960224) (xy 467.270595 -76.001996) (xy 467.262532 -76.085151) (xy 467.246481 -76.167139)
			(xy 467.222592 -76.247196) (xy 467.191087 -76.324573) (xy 467.152262 -76.398548) (xy 467.106479 -76.468431)
			(xy 467.054164 -76.533568) (xy 466.995807 -76.593353) (xy 466.931953 -76.647226) (xy 466.863197 -76.694685)
			(xy 466.790181 -76.735286) (xy 466.713588 -76.768651) (xy 466.634132 -76.794468) (xy 466.552556 -76.812496)
			(xy 466.46962 -76.822566) (xy 466.3861 -76.824585) (xy 466.302774 -76.818533) (xy 466.220422 -76.804468)
			(xy 466.139812 -76.78252) (xy 466.061696 -76.752894) (xy 465.986804 -76.715868) (xy 465.915836 -76.671787)
			(xy 465.849453 -76.621061) (xy 465.788276 -76.564166) (xy 465.732875 -76.501632) (xy 465.683769 -76.434043)
			(xy 465.641415 -76.36203) (xy 465.606209 -76.286265) (xy 465.57848 -76.207456) (xy 465.558487 -76.126339)
			(xy 465.546415 -76.043671) (xy 465.542379 -75.960224) (xy 464.796378 -75.960224) (xy 464.795874 -76.002572)
			(xy 464.787823 -76.086886) (xy 464.771794 -76.170052) (xy 464.747933 -76.251319) (xy 464.716454 -76.329949)
			(xy 464.677643 -76.40523) (xy 464.631853 -76.476482) (xy 464.579497 -76.543058) (xy 464.521049 -76.604356)
			(xy 464.457039 -76.659821) (xy 464.388047 -76.70895) (xy 464.314697 -76.751299) (xy 464.237654 -76.786483)
			(xy 464.157615 -76.814185) (xy 464.075306 -76.834153) (xy 463.991471 -76.846206) (xy 463.90687 -76.850237)
			(xy 463.822269 -76.846206) (xy 463.738434 -76.834153) (xy 463.656125 -76.814185) (xy 463.576086 -76.786483)
			(xy 463.499043 -76.751299) (xy 463.425693 -76.70895) (xy 463.356701 -76.659821) (xy 463.292691 -76.604356)
			(xy 463.234243 -76.543058) (xy 463.181887 -76.476482) (xy 463.136097 -76.40523) (xy 463.097286 -76.329949)
			(xy 463.065807 -76.251319) (xy 463.041946 -76.170052) (xy 463.025917 -76.086886) (xy 463.017866 -76.002572)
			(xy 445.58712 -76.002572) (xy 445.58712 -76.63053) (xy 445.693798 -76.63053) (xy 445.697869 -76.574908)
			(xy 445.709995 -76.520471) (xy 445.729918 -76.46838) (xy 445.757214 -76.419745) (xy 445.7913 -76.375602)
			(xy 445.831449 -76.336893) (xy 445.876807 -76.304442) (xy 445.926407 -76.278941) (xy 445.979191 -76.260934)
			(xy 446.034034 -76.250804) (xy 446.089768 -76.248767) (xy 446.145205 -76.254867) (xy 446.199162 -76.268973)
			(xy 446.250491 -76.290785) (xy 446.298097 -76.319839) (xy 446.340965 -76.355514) (xy 446.378182 -76.397051)
			(xy 446.408955 -76.443564) (xy 446.432627 -76.494061) (xy 446.448695 -76.547468) (xy 446.456815 -76.602644)
			(xy 446.457106 -76.618592) (xy 446.684398 -76.618592) (xy 446.688469 -76.56297) (xy 446.700595 -76.508533)
			(xy 446.720518 -76.456442) (xy 446.747814 -76.407807) (xy 446.7819 -76.363664) (xy 446.822049 -76.324955)
			(xy 446.867407 -76.292504) (xy 446.917007 -76.267003) (xy 446.969791 -76.248996) (xy 447.024634 -76.238866)
			(xy 447.080368 -76.236829) (xy 447.135805 -76.242929) (xy 447.189762 -76.257035) (xy 447.241091 -76.278847)
			(xy 447.288697 -76.307901) (xy 447.331565 -76.343576) (xy 447.368782 -76.385113) (xy 447.399555 -76.431626)
			(xy 447.423227 -76.482123) (xy 447.439295 -76.53553) (xy 447.447415 -76.590706) (xy 447.447924 -76.618592)
			(xy 447.447548 -76.639166) (xy 452.504554 -76.639166) (xy 452.508625 -76.583544) (xy 452.520751 -76.529107)
			(xy 452.540674 -76.477016) (xy 452.56797 -76.428381) (xy 452.602056 -76.384238) (xy 452.642205 -76.345529)
			(xy 452.687563 -76.313078) (xy 452.737163 -76.287577) (xy 452.789947 -76.26957) (xy 452.84479 -76.25944)
			(xy 452.900524 -76.257403) (xy 452.955961 -76.263503) (xy 453.009918 -76.277609) (xy 453.061247 -76.299421)
			(xy 453.108853 -76.328475) (xy 453.151721 -76.36415) (xy 453.188938 -76.405687) (xy 453.219711 -76.4522)
			(xy 453.243383 -76.502697) (xy 453.259451 -76.556104) (xy 453.267571 -76.61128) (xy 453.26808 -76.639166)
			(xy 453.267571 -76.667052) (xy 453.259451 -76.722228) (xy 453.243383 -76.775635) (xy 453.219711 -76.826132)
			(xy 453.188938 -76.872645) (xy 453.151721 -76.914182) (xy 453.108853 -76.949857) (xy 453.061247 -76.978911)
			(xy 453.009918 -77.000723) (xy 452.955961 -77.014829) (xy 452.900524 -77.020929) (xy 452.84479 -77.018892)
			(xy 452.789947 -77.008762) (xy 452.737163 -76.990755) (xy 452.687563 -76.965254) (xy 452.642205 -76.932803)
			(xy 452.602056 -76.894094) (xy 452.56797 -76.849951) (xy 452.540674 -76.801316) (xy 452.520751 -76.749225)
			(xy 452.508625 -76.694788) (xy 452.504554 -76.639166) (xy 447.447548 -76.639166) (xy 447.447415 -76.646478)
			(xy 447.439295 -76.701654) (xy 447.423227 -76.755061) (xy 447.399555 -76.805558) (xy 447.368782 -76.852071)
			(xy 447.331565 -76.893608) (xy 447.288697 -76.929283) (xy 447.241091 -76.958337) (xy 447.189762 -76.980149)
			(xy 447.135805 -76.994255) (xy 447.080368 -77.000355) (xy 447.024634 -76.998318) (xy 446.969791 -76.988188)
			(xy 446.917007 -76.970181) (xy 446.867407 -76.94468) (xy 446.822049 -76.912229) (xy 446.7819 -76.87352)
			(xy 446.747814 -76.829377) (xy 446.720518 -76.780742) (xy 446.700595 -76.728651) (xy 446.688469 -76.674214)
			(xy 446.684398 -76.618592) (xy 446.457106 -76.618592) (xy 446.457324 -76.63053) (xy 446.456815 -76.658416)
			(xy 446.448695 -76.713592) (xy 446.432627 -76.766999) (xy 446.408955 -76.817496) (xy 446.378182 -76.864009)
			(xy 446.340965 -76.905546) (xy 446.298097 -76.941221) (xy 446.250491 -76.970275) (xy 446.199162 -76.992087)
			(xy 446.145205 -77.006193) (xy 446.089768 -77.012293) (xy 446.034034 -77.010256) (xy 445.979191 -77.000126)
			(xy 445.926407 -76.982119) (xy 445.876807 -76.956618) (xy 445.831449 -76.924167) (xy 445.7913 -76.885458)
			(xy 445.757214 -76.841315) (xy 445.729918 -76.79268) (xy 445.709995 -76.740589) (xy 445.697869 -76.686152)
			(xy 445.693798 -76.63053) (xy 445.58712 -76.63053) (xy 445.58712 -78.920086) (xy 447.149726 -78.920086)
			(xy 447.153797 -78.864464) (xy 447.165923 -78.810027) (xy 447.185846 -78.757936) (xy 447.213142 -78.709301)
			(xy 447.247228 -78.665158) (xy 447.287377 -78.626449) (xy 447.332735 -78.593998) (xy 447.382335 -78.568497)
			(xy 447.435119 -78.55049) (xy 447.489962 -78.54036) (xy 447.545696 -78.538323) (xy 447.601133 -78.544423)
			(xy 447.65509 -78.558529) (xy 447.706419 -78.580341) (xy 447.754025 -78.609395) (xy 447.796893 -78.64507)
			(xy 447.83411 -78.686607) (xy 447.864883 -78.73312) (xy 447.888555 -78.783617) (xy 447.904623 -78.837024)
			(xy 447.908212 -78.861412) (xy 449.002402 -78.861412) (xy 449.006473 -78.80579) (xy 449.018599 -78.751353)
			(xy 449.038522 -78.699262) (xy 449.065818 -78.650627) (xy 449.099904 -78.606484) (xy 449.140053 -78.567775)
			(xy 449.185411 -78.535324) (xy 449.235011 -78.509823) (xy 449.287795 -78.491816) (xy 449.342638 -78.481686)
			(xy 449.398372 -78.479649) (xy 449.453809 -78.485749) (xy 449.507766 -78.499855) (xy 449.559095 -78.521667)
			(xy 449.606701 -78.550721) (xy 449.649569 -78.586396) (xy 449.686786 -78.627933) (xy 449.717559 -78.674446)
			(xy 449.741231 -78.724943) (xy 449.757299 -78.77835) (xy 449.765419 -78.833526) (xy 449.765928 -78.861412)
			(xy 449.765419 -78.889298) (xy 449.757299 -78.944474) (xy 449.741231 -78.997881) (xy 449.717559 -79.048378)
			(xy 449.686786 -79.094891) (xy 449.649569 -79.136428) (xy 449.606701 -79.172103) (xy 449.559095 -79.201157)
			(xy 449.507766 -79.222969) (xy 449.453809 -79.237075) (xy 449.398372 -79.243175) (xy 449.342638 -79.241138)
			(xy 449.287795 -79.231008) (xy 449.235011 -79.213001) (xy 449.185411 -79.1875) (xy 449.140053 -79.155049)
			(xy 449.099904 -79.11634) (xy 449.065818 -79.072197) (xy 449.038522 -79.023562) (xy 449.018599 -78.971471)
			(xy 449.006473 -78.917034) (xy 449.002402 -78.861412) (xy 447.908212 -78.861412) (xy 447.912743 -78.8922)
			(xy 447.913252 -78.920086) (xy 447.912743 -78.947972) (xy 447.904623 -79.003148) (xy 447.888555 -79.056555)
			(xy 447.864883 -79.107052) (xy 447.83411 -79.153565) (xy 447.796893 -79.195102) (xy 447.754025 -79.230777)
			(xy 447.706419 -79.259831) (xy 447.65509 -79.281643) (xy 447.601133 -79.295749) (xy 447.545696 -79.301849)
			(xy 447.489962 -79.299812) (xy 447.435119 -79.289682) (xy 447.382335 -79.271675) (xy 447.332735 -79.246174)
			(xy 447.287377 -79.213723) (xy 447.247228 -79.175014) (xy 447.213142 -79.130871) (xy 447.185846 -79.082236)
			(xy 447.165923 -79.030145) (xy 447.153797 -78.975708) (xy 447.149726 -78.920086) (xy 445.58712 -78.920086)
			(xy 445.58712 -79.230728) (xy 446.48374 -80.127348) (xy 466.17128 -80.127348)
		)
		(stroke
			(width 0)
			(type solid)
		)
		(fill yes)
		(layer "In11.Cu")
		(net "GND")
	)
	(gr_poly
		(pts
			(xy 135.026654 -155.768294) (xy 135.026654 -147.688554) (xy 135.026208 -147.6788) (xy 135.018915 -147.660706)
			(xy 135.0054 -147.646637) (xy 134.987613 -147.638625) (xy 134.977886 -147.637754) (xy 134.950139 -147.636086)
			(xy 134.895529 -147.625721) (xy 134.843 -147.607541) (xy 134.793665 -147.581933) (xy 134.748567 -147.549438)
			(xy 134.708661 -147.510744) (xy 134.674792 -147.466669) (xy 134.647676 -147.418146) (xy 134.627886 -147.366203)
			(xy 134.615842 -147.311938) (xy 134.611799 -147.2565) (xy 134.615842 -147.201062) (xy 134.627886 -147.146797)
			(xy 134.647676 -147.094854) (xy 134.674792 -147.046331) (xy 134.708661 -147.002256) (xy 134.748567 -146.963562)
			(xy 134.793665 -146.931067) (xy 134.843 -146.905459) (xy 134.895529 -146.887279) (xy 134.950139 -146.876914)
			(xy 134.977886 -146.875246) (xy 134.987627 -146.874424) (xy 135.005441 -146.866419) (xy 135.018972 -146.852334)
			(xy 135.026254 -146.834212) (xy 135.026654 -146.824446) (xy 135.026654 -128.872996) (xy 135.026076 -128.857304)
			(xy 135.016559 -128.827396) (xy 134.998422 -128.801783) (xy 134.973373 -128.782873) (xy 134.94377 -128.772449)
			(xy 134.928102 -128.771396) (xy 134.900124 -128.770067) (xy 134.844986 -128.760225) (xy 134.79188 -128.742426)
			(xy 134.741947 -128.717052) (xy 134.696261 -128.68465) (xy 134.655805 -128.645916) (xy 134.621447 -128.601683)
			(xy 134.593926 -128.5529) (xy 134.573835 -128.500618) (xy 134.561605 -128.44596) (xy 134.557499 -128.390101)
			(xy 134.561605 -128.334242) (xy 134.573834 -128.279584) (xy 134.593925 -128.227302) (xy 134.621445 -128.178519)
			(xy 134.655803 -128.134286) (xy 134.696259 -128.095551) (xy 134.741945 -128.063149) (xy 134.791878 -128.037775)
			(xy 134.844984 -128.019976) (xy 134.900122 -128.010134) (xy 134.928102 -128.008888) (xy 134.943773 -128.007844)
			(xy 134.973386 -127.997435) (xy 134.998441 -127.978525) (xy 135.016573 -127.952902) (xy 135.02607 -127.922984)
			(xy 135.026654 -127.907288) (xy 135.026654 -124.413264) (xy 130.934968 -120.321578) (xy 130.924473 -120.311761)
			(xy 130.89932 -120.297888) (xy 130.871297 -120.291574) (xy 130.842625 -120.29332) (xy 130.815575 -120.302986)
			(xy 130.79229 -120.319807) (xy 130.774615 -120.34245) (xy 130.768852 -120.355614) (xy 130.757801 -120.381743)
			(xy 130.729099 -120.430677) (xy 130.693465 -120.47482) (xy 130.651687 -120.513198) (xy 130.604684 -120.544964)
			(xy 130.553495 -120.569419) (xy 130.499249 -120.586021) (xy 130.443141 -120.594406) (xy 130.414776 -120.594882)
			(xy 130.387525 -120.594417) (xy 130.333578 -120.586657) (xy 130.281285 -120.571299) (xy 130.231709 -120.548655)
			(xy 130.185861 -120.519185) (xy 130.144673 -120.483491) (xy 130.108985 -120.442299) (xy 130.079521 -120.396447)
			(xy 130.056884 -120.346869) (xy 130.041532 -120.294573) (xy 130.033779 -120.240625) (xy 130.033268 -120.213374)
			(xy 130.033789 -120.185012) (xy 130.042187 -120.128912) (xy 130.058794 -120.074672) (xy 130.083245 -120.023488)
			(xy 130.115001 -119.976485) (xy 130.153363 -119.934699) (xy 130.197487 -119.89905) (xy 130.2464 -119.870323)
			(xy 130.272536 -119.859298) (xy 130.285664 -119.853488) (xy 130.308258 -119.835798) (xy 130.32504 -119.812521)
			(xy 130.334688 -119.785496) (xy 130.33644 -119.756854) (xy 130.330158 -119.728855) (xy 130.316337 -119.703707)
			(xy 130.306572 -119.693182) (xy 129.278126 -118.664736) (xy 114.456718 -118.664736) (xy 114.14506 -118.976394)
			(xy 114.14506 -120.989598) (xy 115.574062 -120.989598) (xy 115.578133 -120.933976) (xy 115.590259 -120.879539)
			(xy 115.610182 -120.827448) (xy 115.637478 -120.778813) (xy 115.671564 -120.73467) (xy 115.711713 -120.695961)
			(xy 115.757071 -120.66351) (xy 115.806671 -120.638009) (xy 115.859455 -120.620002) (xy 115.914298 -120.609872)
			(xy 115.970032 -120.607835) (xy 116.025469 -120.613935) (xy 116.079426 -120.628041) (xy 116.130755 -120.649853)
			(xy 116.178361 -120.678907) (xy 116.221229 -120.714582) (xy 116.258446 -120.756119) (xy 116.289219 -120.802632)
			(xy 116.312891 -120.853129) (xy 116.328959 -120.906536) (xy 116.337079 -120.961712) (xy 116.337588 -120.989598)
			(xy 116.844062 -120.989598) (xy 116.848133 -120.933976) (xy 116.860259 -120.879539) (xy 116.880182 -120.827448)
			(xy 116.907478 -120.778813) (xy 116.941564 -120.73467) (xy 116.981713 -120.695961) (xy 117.027071 -120.66351)
			(xy 117.076671 -120.638009) (xy 117.129455 -120.620002) (xy 117.184298 -120.609872) (xy 117.240032 -120.607835)
			(xy 117.295469 -120.613935) (xy 117.349426 -120.628041) (xy 117.400755 -120.649853) (xy 117.448361 -120.678907)
			(xy 117.491229 -120.714582) (xy 117.528446 -120.756119) (xy 117.559219 -120.802632) (xy 117.582891 -120.853129)
			(xy 117.583829 -120.856248) (xy 118.114062 -120.856248) (xy 118.118133 -120.800626) (xy 118.130259 -120.746189)
			(xy 118.150182 -120.694098) (xy 118.177478 -120.645463) (xy 118.211564 -120.60132) (xy 118.251713 -120.562611)
			(xy 118.297071 -120.53016) (xy 118.346671 -120.504659) (xy 118.399455 -120.486652) (xy 118.454298 -120.476522)
			(xy 118.510032 -120.474485) (xy 118.565469 -120.480585) (xy 118.619426 -120.494691) (xy 118.670755 -120.516503)
			(xy 118.718361 -120.545557) (xy 118.761229 -120.581232) (xy 118.798446 -120.622769) (xy 118.829219 -120.669282)
			(xy 118.852891 -120.719779) (xy 118.868959 -120.773186) (xy 118.877079 -120.828362) (xy 118.877588 -120.856248)
			(xy 118.877079 -120.884134) (xy 118.868959 -120.93931) (xy 118.864604 -120.953784) (xy 120.056908 -120.953784)
			(xy 120.060979 -120.898162) (xy 120.073105 -120.843725) (xy 120.093028 -120.791634) (xy 120.120324 -120.742999)
			(xy 120.15441 -120.698856) (xy 120.194559 -120.660147) (xy 120.239917 -120.627696) (xy 120.289517 -120.602195)
			(xy 120.342301 -120.584188) (xy 120.397144 -120.574058) (xy 120.452878 -120.572021) (xy 120.508315 -120.578121)
			(xy 120.562272 -120.592227) (xy 120.613601 -120.614039) (xy 120.661207 -120.643093) (xy 120.704075 -120.678768)
			(xy 120.741292 -120.720305) (xy 120.772065 -120.766818) (xy 120.795737 -120.817315) (xy 120.811805 -120.870722)
			(xy 120.819925 -120.925898) (xy 120.820434 -120.953784) (xy 121.326908 -120.953784) (xy 121.330979 -120.898162)
			(xy 121.343105 -120.843725) (xy 121.363028 -120.791634) (xy 121.390324 -120.742999) (xy 121.42441 -120.698856)
			(xy 121.464559 -120.660147) (xy 121.509917 -120.627696) (xy 121.559517 -120.602195) (xy 121.612301 -120.584188)
			(xy 121.667144 -120.574058) (xy 121.722878 -120.572021) (xy 121.778315 -120.578121) (xy 121.832272 -120.592227)
			(xy 121.883601 -120.614039) (xy 121.931207 -120.643093) (xy 121.974075 -120.678768) (xy 122.011292 -120.720305)
			(xy 122.042065 -120.766818) (xy 122.065737 -120.817315) (xy 122.081805 -120.870722) (xy 122.089925 -120.925898)
			(xy 122.090434 -120.953784) (xy 124.882908 -120.953784) (xy 124.886979 -120.898162) (xy 124.899105 -120.843725)
			(xy 124.919028 -120.791634) (xy 124.946324 -120.742999) (xy 124.98041 -120.698856) (xy 125.020559 -120.660147)
			(xy 125.065917 -120.627696) (xy 125.115517 -120.602195) (xy 125.168301 -120.584188) (xy 125.223144 -120.574058)
			(xy 125.278878 -120.572021) (xy 125.334315 -120.578121) (xy 125.388272 -120.592227) (xy 125.439601 -120.614039)
			(xy 125.487207 -120.643093) (xy 125.530075 -120.678768) (xy 125.567292 -120.720305) (xy 125.598065 -120.766818)
			(xy 125.621737 -120.817315) (xy 125.637805 -120.870722) (xy 125.645925 -120.925898) (xy 125.646434 -120.953784)
			(xy 126.152908 -120.953784) (xy 126.156979 -120.898162) (xy 126.169105 -120.843725) (xy 126.189028 -120.791634)
			(xy 126.216324 -120.742999) (xy 126.25041 -120.698856) (xy 126.290559 -120.660147) (xy 126.335917 -120.627696)
			(xy 126.385517 -120.602195) (xy 126.438301 -120.584188) (xy 126.493144 -120.574058) (xy 126.548878 -120.572021)
			(xy 126.604315 -120.578121) (xy 126.658272 -120.592227) (xy 126.709601 -120.614039) (xy 126.757207 -120.643093)
			(xy 126.800075 -120.678768) (xy 126.837292 -120.720305) (xy 126.868065 -120.766818) (xy 126.891737 -120.817315)
			(xy 126.892675 -120.820434) (xy 127.422908 -120.820434) (xy 127.426979 -120.764812) (xy 127.439105 -120.710375)
			(xy 127.459028 -120.658284) (xy 127.486324 -120.609649) (xy 127.52041 -120.565506) (xy 127.560559 -120.526797)
			(xy 127.605917 -120.494346) (xy 127.655517 -120.468845) (xy 127.708301 -120.450838) (xy 127.763144 -120.440708)
			(xy 127.818878 -120.438671) (xy 127.874315 -120.444771) (xy 127.928272 -120.458877) (xy 127.979601 -120.480689)
			(xy 128.027207 -120.509743) (xy 128.070075 -120.545418) (xy 128.107292 -120.586955) (xy 128.138065 -120.633468)
			(xy 128.161737 -120.683965) (xy 128.177805 -120.737372) (xy 128.185925 -120.792548) (xy 128.186434 -120.820434)
			(xy 128.185925 -120.84832) (xy 128.177805 -120.903496) (xy 128.161737 -120.956903) (xy 128.138065 -121.0074)
			(xy 128.107292 -121.053913) (xy 128.070075 -121.09545) (xy 128.027207 -121.131125) (xy 127.979601 -121.160179)
			(xy 127.928272 -121.181991) (xy 127.874315 -121.196097) (xy 127.818878 -121.202197) (xy 127.763144 -121.20016)
			(xy 127.708301 -121.19003) (xy 127.655517 -121.172023) (xy 127.605917 -121.146522) (xy 127.560559 -121.114071)
			(xy 127.52041 -121.075362) (xy 127.486324 -121.031219) (xy 127.459028 -120.982584) (xy 127.439105 -120.930493)
			(xy 127.426979 -120.876056) (xy 127.422908 -120.820434) (xy 126.892675 -120.820434) (xy 126.907805 -120.870722)
			(xy 126.915925 -120.925898) (xy 126.916434 -120.953784) (xy 126.915925 -120.98167) (xy 126.907805 -121.036846)
			(xy 126.891737 -121.090253) (xy 126.868065 -121.14075) (xy 126.837292 -121.187263) (xy 126.800075 -121.2288)
			(xy 126.757207 -121.264475) (xy 126.709601 -121.293529) (xy 126.658272 -121.315341) (xy 126.604315 -121.329447)
			(xy 126.548878 -121.335547) (xy 126.493144 -121.33351) (xy 126.438301 -121.32338) (xy 126.385517 -121.305373)
			(xy 126.335917 -121.279872) (xy 126.290559 -121.247421) (xy 126.25041 -121.208712) (xy 126.216324 -121.164569)
			(xy 126.189028 -121.115934) (xy 126.169105 -121.063843) (xy 126.156979 -121.009406) (xy 126.152908 -120.953784)
			(xy 125.646434 -120.953784) (xy 125.645925 -120.98167) (xy 125.637805 -121.036846) (xy 125.621737 -121.090253)
			(xy 125.598065 -121.14075) (xy 125.567292 -121.187263) (xy 125.530075 -121.2288) (xy 125.487207 -121.264475)
			(xy 125.439601 -121.293529) (xy 125.388272 -121.315341) (xy 125.334315 -121.329447) (xy 125.278878 -121.335547)
			(xy 125.223144 -121.33351) (xy 125.168301 -121.32338) (xy 125.115517 -121.305373) (xy 125.065917 -121.279872)
			(xy 125.020559 -121.247421) (xy 124.98041 -121.208712) (xy 124.946324 -121.164569) (xy 124.919028 -121.115934)
			(xy 124.899105 -121.063843) (xy 124.886979 -121.009406) (xy 124.882908 -120.953784) (xy 122.090434 -120.953784)
			(xy 122.089925 -120.98167) (xy 122.081805 -121.036846) (xy 122.065737 -121.090253) (xy 122.042065 -121.14075)
			(xy 122.011292 -121.187263) (xy 121.974075 -121.2288) (xy 121.931207 -121.264475) (xy 121.883601 -121.293529)
			(xy 121.832272 -121.315341) (xy 121.778315 -121.329447) (xy 121.722878 -121.335547) (xy 121.667144 -121.33351)
			(xy 121.612301 -121.32338) (xy 121.559517 -121.305373) (xy 121.509917 -121.279872) (xy 121.464559 -121.247421)
			(xy 121.42441 -121.208712) (xy 121.390324 -121.164569) (xy 121.363028 -121.115934) (xy 121.343105 -121.063843)
			(xy 121.330979 -121.009406) (xy 121.326908 -120.953784) (xy 120.820434 -120.953784) (xy 120.819925 -120.98167)
			(xy 120.811805 -121.036846) (xy 120.795737 -121.090253) (xy 120.772065 -121.14075) (xy 120.741292 -121.187263)
			(xy 120.704075 -121.2288) (xy 120.661207 -121.264475) (xy 120.613601 -121.293529) (xy 120.562272 -121.315341)
			(xy 120.508315 -121.329447) (xy 120.452878 -121.335547) (xy 120.397144 -121.33351) (xy 120.342301 -121.32338)
			(xy 120.289517 -121.305373) (xy 120.239917 -121.279872) (xy 120.194559 -121.247421) (xy 120.15441 -121.208712)
			(xy 120.120324 -121.164569) (xy 120.093028 -121.115934) (xy 120.073105 -121.063843) (xy 120.060979 -121.009406)
			(xy 120.056908 -120.953784) (xy 118.864604 -120.953784) (xy 118.852891 -120.992717) (xy 118.829219 -121.043214)
			(xy 118.798446 -121.089727) (xy 118.761229 -121.131264) (xy 118.718361 -121.166939) (xy 118.670755 -121.195993)
			(xy 118.619426 -121.217805) (xy 118.565469 -121.231911) (xy 118.510032 -121.238011) (xy 118.454298 -121.235974)
			(xy 118.399455 -121.225844) (xy 118.346671 -121.207837) (xy 118.297071 -121.182336) (xy 118.251713 -121.149885)
			(xy 118.211564 -121.111176) (xy 118.177478 -121.067033) (xy 118.150182 -121.018398) (xy 118.130259 -120.966307)
			(xy 118.118133 -120.91187) (xy 118.114062 -120.856248) (xy 117.583829 -120.856248) (xy 117.598959 -120.906536)
			(xy 117.607079 -120.961712) (xy 117.607588 -120.989598) (xy 117.607079 -121.017484) (xy 117.598959 -121.07266)
			(xy 117.582891 -121.126067) (xy 117.559219 -121.176564) (xy 117.528446 -121.223077) (xy 117.491229 -121.264614)
			(xy 117.448361 -121.300289) (xy 117.400755 -121.329343) (xy 117.349426 -121.351155) (xy 117.295469 -121.365261)
			(xy 117.240032 -121.371361) (xy 117.184298 -121.369324) (xy 117.129455 -121.359194) (xy 117.076671 -121.341187)
			(xy 117.027071 -121.315686) (xy 116.981713 -121.283235) (xy 116.941564 -121.244526) (xy 116.907478 -121.200383)
			(xy 116.880182 -121.151748) (xy 116.860259 -121.099657) (xy 116.848133 -121.04522) (xy 116.844062 -120.989598)
			(xy 116.337588 -120.989598) (xy 116.337079 -121.017484) (xy 116.328959 -121.07266) (xy 116.312891 -121.126067)
			(xy 116.289219 -121.176564) (xy 116.258446 -121.223077) (xy 116.221229 -121.264614) (xy 116.178361 -121.300289)
			(xy 116.130755 -121.329343) (xy 116.079426 -121.351155) (xy 116.025469 -121.365261) (xy 115.970032 -121.371361)
			(xy 115.914298 -121.369324) (xy 115.859455 -121.359194) (xy 115.806671 -121.341187) (xy 115.757071 -121.315686)
			(xy 115.711713 -121.283235) (xy 115.671564 -121.244526) (xy 115.637478 -121.200383) (xy 115.610182 -121.151748)
			(xy 115.590259 -121.099657) (xy 115.578133 -121.04522) (xy 115.574062 -120.989598) (xy 114.14506 -120.989598)
			(xy 114.14506 -123.148598) (xy 114.304062 -123.148598) (xy 114.308133 -123.092976) (xy 114.320259 -123.038539)
			(xy 114.340182 -122.986448) (xy 114.367478 -122.937813) (xy 114.401564 -122.89367) (xy 114.441713 -122.854961)
			(xy 114.487071 -122.82251) (xy 114.536671 -122.797009) (xy 114.589455 -122.779002) (xy 114.644298 -122.768872)
			(xy 114.700032 -122.766835) (xy 114.755469 -122.772935) (xy 114.809426 -122.787041) (xy 114.860755 -122.808853)
			(xy 114.908361 -122.837907) (xy 114.951229 -122.873582) (xy 114.988446 -122.915119) (xy 115.019219 -122.961632)
			(xy 115.042891 -123.012129) (xy 115.058959 -123.065536) (xy 115.067079 -123.120712) (xy 115.067588 -123.148598)
			(xy 115.574062 -123.148598) (xy 115.578133 -123.092976) (xy 115.590259 -123.038539) (xy 115.610182 -122.986448)
			(xy 115.637478 -122.937813) (xy 115.671564 -122.89367) (xy 115.711713 -122.854961) (xy 115.757071 -122.82251)
			(xy 115.806671 -122.797009) (xy 115.859455 -122.779002) (xy 115.914298 -122.768872) (xy 115.970032 -122.766835)
			(xy 116.025469 -122.772935) (xy 116.079426 -122.787041) (xy 116.130755 -122.808853) (xy 116.178361 -122.837907)
			(xy 116.221229 -122.873582) (xy 116.258446 -122.915119) (xy 116.289219 -122.961632) (xy 116.312891 -123.012129)
			(xy 116.328959 -123.065536) (xy 116.337079 -123.120712) (xy 116.337588 -123.148598) (xy 116.844062 -123.148598)
			(xy 116.848133 -123.092976) (xy 116.860259 -123.038539) (xy 116.880182 -122.986448) (xy 116.907478 -122.937813)
			(xy 116.941564 -122.89367) (xy 116.981713 -122.854961) (xy 117.027071 -122.82251) (xy 117.076671 -122.797009)
			(xy 117.129455 -122.779002) (xy 117.184298 -122.768872) (xy 117.240032 -122.766835) (xy 117.295469 -122.772935)
			(xy 117.349426 -122.787041) (xy 117.400755 -122.808853) (xy 117.448361 -122.837907) (xy 117.491229 -122.873582)
			(xy 117.528446 -122.915119) (xy 117.559219 -122.961632) (xy 117.582891 -123.012129) (xy 117.598959 -123.065536)
			(xy 117.605912 -123.112784) (xy 120.056908 -123.112784) (xy 120.060979 -123.057162) (xy 120.073105 -123.002725)
			(xy 120.093028 -122.950634) (xy 120.120324 -122.901999) (xy 120.15441 -122.857856) (xy 120.194559 -122.819147)
			(xy 120.239917 -122.786696) (xy 120.289517 -122.761195) (xy 120.342301 -122.743188) (xy 120.397144 -122.733058)
			(xy 120.452878 -122.731021) (xy 120.508315 -122.737121) (xy 120.562272 -122.751227) (xy 120.613601 -122.773039)
			(xy 120.661207 -122.802093) (xy 120.704075 -122.837768) (xy 120.741292 -122.879305) (xy 120.772065 -122.925818)
			(xy 120.795737 -122.976315) (xy 120.811805 -123.029722) (xy 120.819925 -123.084898) (xy 120.820434 -123.112784)
			(xy 121.326908 -123.112784) (xy 121.330979 -123.057162) (xy 121.343105 -123.002725) (xy 121.363028 -122.950634)
			(xy 121.390324 -122.901999) (xy 121.42441 -122.857856) (xy 121.464559 -122.819147) (xy 121.509917 -122.786696)
			(xy 121.559517 -122.761195) (xy 121.612301 -122.743188) (xy 121.667144 -122.733058) (xy 121.722878 -122.731021)
			(xy 121.778315 -122.737121) (xy 121.832272 -122.751227) (xy 121.883601 -122.773039) (xy 121.931207 -122.802093)
			(xy 121.974075 -122.837768) (xy 122.011292 -122.879305) (xy 122.042065 -122.925818) (xy 122.065737 -122.976315)
			(xy 122.081805 -123.029722) (xy 122.089925 -123.084898) (xy 122.090434 -123.112784) (xy 122.596908 -123.112784)
			(xy 122.600979 -123.057162) (xy 122.613105 -123.002725) (xy 122.633028 -122.950634) (xy 122.660324 -122.901999)
			(xy 122.69441 -122.857856) (xy 122.734559 -122.819147) (xy 122.779917 -122.786696) (xy 122.829517 -122.761195)
			(xy 122.882301 -122.743188) (xy 122.937144 -122.733058) (xy 122.992878 -122.731021) (xy 123.048315 -122.737121)
			(xy 123.102272 -122.751227) (xy 123.153601 -122.773039) (xy 123.201207 -122.802093) (xy 123.244075 -122.837768)
			(xy 123.281292 -122.879305) (xy 123.312065 -122.925818) (xy 123.335737 -122.976315) (xy 123.351805 -123.029722)
			(xy 123.359925 -123.084898) (xy 123.360434 -123.112784) (xy 123.612908 -123.112784) (xy 123.616979 -123.057162)
			(xy 123.629105 -123.002725) (xy 123.649028 -122.950634) (xy 123.676324 -122.901999) (xy 123.71041 -122.857856)
			(xy 123.750559 -122.819147) (xy 123.795917 -122.786696) (xy 123.845517 -122.761195) (xy 123.898301 -122.743188)
			(xy 123.953144 -122.733058) (xy 124.008878 -122.731021) (xy 124.064315 -122.737121) (xy 124.118272 -122.751227)
			(xy 124.169601 -122.773039) (xy 124.217207 -122.802093) (xy 124.260075 -122.837768) (xy 124.297292 -122.879305)
			(xy 124.328065 -122.925818) (xy 124.351737 -122.976315) (xy 124.367805 -123.029722) (xy 124.375925 -123.084898)
			(xy 124.376434 -123.112784) (xy 124.882908 -123.112784) (xy 124.886979 -123.057162) (xy 124.899105 -123.002725)
			(xy 124.919028 -122.950634) (xy 124.946324 -122.901999) (xy 124.98041 -122.857856) (xy 125.020559 -122.819147)
			(xy 125.065917 -122.786696) (xy 125.115517 -122.761195) (xy 125.168301 -122.743188) (xy 125.223144 -122.733058)
			(xy 125.278878 -122.731021) (xy 125.334315 -122.737121) (xy 125.388272 -122.751227) (xy 125.439601 -122.773039)
			(xy 125.487207 -122.802093) (xy 125.530075 -122.837768) (xy 125.567292 -122.879305) (xy 125.598065 -122.925818)
			(xy 125.621737 -122.976315) (xy 125.637805 -123.029722) (xy 125.645925 -123.084898) (xy 125.646434 -123.112784)
			(xy 126.152908 -123.112784) (xy 126.156979 -123.057162) (xy 126.169105 -123.002725) (xy 126.189028 -122.950634)
			(xy 126.216324 -122.901999) (xy 126.25041 -122.857856) (xy 126.290559 -122.819147) (xy 126.335917 -122.786696)
			(xy 126.385517 -122.761195) (xy 126.438301 -122.743188) (xy 126.493144 -122.733058) (xy 126.548878 -122.731021)
			(xy 126.604315 -122.737121) (xy 126.658272 -122.751227) (xy 126.709601 -122.773039) (xy 126.757207 -122.802093)
			(xy 126.800075 -122.837768) (xy 126.837292 -122.879305) (xy 126.868065 -122.925818) (xy 126.891737 -122.976315)
			(xy 126.907805 -123.029722) (xy 126.915925 -123.084898) (xy 126.916434 -123.112784) (xy 126.915925 -123.14067)
			(xy 126.907805 -123.195846) (xy 126.891737 -123.249253) (xy 126.868065 -123.29975) (xy 126.837292 -123.346263)
			(xy 126.800075 -123.3878) (xy 126.757207 -123.423475) (xy 126.709601 -123.452529) (xy 126.658272 -123.474341)
			(xy 126.604315 -123.488447) (xy 126.548878 -123.494547) (xy 126.493144 -123.49251) (xy 126.438301 -123.48238)
			(xy 126.385517 -123.464373) (xy 126.335917 -123.438872) (xy 126.290559 -123.406421) (xy 126.25041 -123.367712)
			(xy 126.216324 -123.323569) (xy 126.189028 -123.274934) (xy 126.169105 -123.222843) (xy 126.156979 -123.168406)
			(xy 126.152908 -123.112784) (xy 125.646434 -123.112784) (xy 125.645925 -123.14067) (xy 125.637805 -123.195846)
			(xy 125.621737 -123.249253) (xy 125.598065 -123.29975) (xy 125.567292 -123.346263) (xy 125.530075 -123.3878)
			(xy 125.487207 -123.423475) (xy 125.439601 -123.452529) (xy 125.388272 -123.474341) (xy 125.334315 -123.488447)
			(xy 125.278878 -123.494547) (xy 125.223144 -123.49251) (xy 125.168301 -123.48238) (xy 125.115517 -123.464373)
			(xy 125.065917 -123.438872) (xy 125.020559 -123.406421) (xy 124.98041 -123.367712) (xy 124.946324 -123.323569)
			(xy 124.919028 -123.274934) (xy 124.899105 -123.222843) (xy 124.886979 -123.168406) (xy 124.882908 -123.112784)
			(xy 124.376434 -123.112784) (xy 124.375925 -123.14067) (xy 124.367805 -123.195846) (xy 124.351737 -123.249253)
			(xy 124.328065 -123.29975) (xy 124.297292 -123.346263) (xy 124.260075 -123.3878) (xy 124.217207 -123.423475)
			(xy 124.169601 -123.452529) (xy 124.118272 -123.474341) (xy 124.064315 -123.488447) (xy 124.008878 -123.494547)
			(xy 123.953144 -123.49251) (xy 123.898301 -123.48238) (xy 123.845517 -123.464373) (xy 123.795917 -123.438872)
			(xy 123.750559 -123.406421) (xy 123.71041 -123.367712) (xy 123.676324 -123.323569) (xy 123.649028 -123.274934)
			(xy 123.629105 -123.222843) (xy 123.616979 -123.168406) (xy 123.612908 -123.112784) (xy 123.360434 -123.112784)
			(xy 123.359925 -123.14067) (xy 123.351805 -123.195846) (xy 123.335737 -123.249253) (xy 123.312065 -123.29975)
			(xy 123.281292 -123.346263) (xy 123.244075 -123.3878) (xy 123.201207 -123.423475) (xy 123.153601 -123.452529)
			(xy 123.102272 -123.474341) (xy 123.048315 -123.488447) (xy 122.992878 -123.494547) (xy 122.937144 -123.49251)
			(xy 122.882301 -123.48238) (xy 122.829517 -123.464373) (xy 122.779917 -123.438872) (xy 122.734559 -123.406421)
			(xy 122.69441 -123.367712) (xy 122.660324 -123.323569) (xy 122.633028 -123.274934) (xy 122.613105 -123.222843)
			(xy 122.600979 -123.168406) (xy 122.596908 -123.112784) (xy 122.090434 -123.112784) (xy 122.089925 -123.14067)
			(xy 122.081805 -123.195846) (xy 122.065737 -123.249253) (xy 122.042065 -123.29975) (xy 122.011292 -123.346263)
			(xy 121.974075 -123.3878) (xy 121.931207 -123.423475) (xy 121.883601 -123.452529) (xy 121.832272 -123.474341)
			(xy 121.778315 -123.488447) (xy 121.722878 -123.494547) (xy 121.667144 -123.49251) (xy 121.612301 -123.48238)
			(xy 121.559517 -123.464373) (xy 121.509917 -123.438872) (xy 121.464559 -123.406421) (xy 121.42441 -123.367712)
			(xy 121.390324 -123.323569) (xy 121.363028 -123.274934) (xy 121.343105 -123.222843) (xy 121.330979 -123.168406)
			(xy 121.326908 -123.112784) (xy 120.820434 -123.112784) (xy 120.819925 -123.14067) (xy 120.811805 -123.195846)
			(xy 120.795737 -123.249253) (xy 120.772065 -123.29975) (xy 120.741292 -123.346263) (xy 120.704075 -123.3878)
			(xy 120.661207 -123.423475) (xy 120.613601 -123.452529) (xy 120.562272 -123.474341) (xy 120.508315 -123.488447)
			(xy 120.452878 -123.494547) (xy 120.397144 -123.49251) (xy 120.342301 -123.48238) (xy 120.289517 -123.464373)
			(xy 120.239917 -123.438872) (xy 120.194559 -123.406421) (xy 120.15441 -123.367712) (xy 120.120324 -123.323569)
			(xy 120.093028 -123.274934) (xy 120.073105 -123.222843) (xy 120.060979 -123.168406) (xy 120.056908 -123.112784)
			(xy 117.605912 -123.112784) (xy 117.607079 -123.120712) (xy 117.607588 -123.148598) (xy 117.607079 -123.176484)
			(xy 117.598959 -123.23166) (xy 117.582891 -123.285067) (xy 117.559219 -123.335564) (xy 117.528446 -123.382077)
			(xy 117.491229 -123.423614) (xy 117.448361 -123.459289) (xy 117.400755 -123.488343) (xy 117.349426 -123.510155)
			(xy 117.295469 -123.524261) (xy 117.240032 -123.530361) (xy 117.184298 -123.528324) (xy 117.129455 -123.518194)
			(xy 117.076671 -123.500187) (xy 117.027071 -123.474686) (xy 116.981713 -123.442235) (xy 116.941564 -123.403526)
			(xy 116.907478 -123.359383) (xy 116.880182 -123.310748) (xy 116.860259 -123.258657) (xy 116.848133 -123.20422)
			(xy 116.844062 -123.148598) (xy 116.337588 -123.148598) (xy 116.337079 -123.176484) (xy 116.328959 -123.23166)
			(xy 116.312891 -123.285067) (xy 116.289219 -123.335564) (xy 116.258446 -123.382077) (xy 116.221229 -123.423614)
			(xy 116.178361 -123.459289) (xy 116.130755 -123.488343) (xy 116.079426 -123.510155) (xy 116.025469 -123.524261)
			(xy 115.970032 -123.530361) (xy 115.914298 -123.528324) (xy 115.859455 -123.518194) (xy 115.806671 -123.500187)
			(xy 115.757071 -123.474686) (xy 115.711713 -123.442235) (xy 115.671564 -123.403526) (xy 115.637478 -123.359383)
			(xy 115.610182 -123.310748) (xy 115.590259 -123.258657) (xy 115.578133 -123.20422) (xy 115.574062 -123.148598)
			(xy 115.067588 -123.148598) (xy 115.067079 -123.176484) (xy 115.058959 -123.23166) (xy 115.042891 -123.285067)
			(xy 115.019219 -123.335564) (xy 114.988446 -123.382077) (xy 114.951229 -123.423614) (xy 114.908361 -123.459289)
			(xy 114.860755 -123.488343) (xy 114.809426 -123.510155) (xy 114.755469 -123.524261) (xy 114.700032 -123.530361)
			(xy 114.644298 -123.528324) (xy 114.589455 -123.518194) (xy 114.536671 -123.500187) (xy 114.487071 -123.474686)
			(xy 114.441713 -123.442235) (xy 114.401564 -123.403526) (xy 114.367478 -123.359383) (xy 114.340182 -123.310748)
			(xy 114.320259 -123.258657) (xy 114.308133 -123.20422) (xy 114.304062 -123.148598) (xy 114.14506 -123.148598)
			(xy 114.14506 -124.234448) (xy 130.281932 -124.234448) (xy 130.286003 -124.178826) (xy 130.298129 -124.124389)
			(xy 130.318052 -124.072298) (xy 130.345348 -124.023663) (xy 130.379434 -123.97952) (xy 130.419583 -123.940811)
			(xy 130.464941 -123.90836) (xy 130.514541 -123.882859) (xy 130.567325 -123.864852) (xy 130.622168 -123.854722)
			(xy 130.677902 -123.852685) (xy 130.733339 -123.858785) (xy 130.787296 -123.872891) (xy 130.838625 -123.894703)
			(xy 130.886231 -123.923757) (xy 130.929099 -123.959432) (xy 130.966316 -124.000969) (xy 130.997089 -124.047482)
			(xy 131.020761 -124.097979) (xy 131.036829 -124.151386) (xy 131.044949 -124.206562) (xy 131.045458 -124.234448)
			(xy 131.044949 -124.262334) (xy 131.036829 -124.31751) (xy 131.020761 -124.370917) (xy 130.997089 -124.421414)
			(xy 130.966316 -124.467927) (xy 130.929099 -124.509464) (xy 130.886231 -124.545139) (xy 130.838625 -124.574193)
			(xy 130.787296 -124.596005) (xy 130.733339 -124.610111) (xy 130.677902 -124.616211) (xy 130.622168 -124.614174)
			(xy 130.567325 -124.604044) (xy 130.514541 -124.586037) (xy 130.464941 -124.560536) (xy 130.419583 -124.528085)
			(xy 130.379434 -124.489376) (xy 130.345348 -124.445233) (xy 130.318052 -124.396598) (xy 130.298129 -124.344507)
			(xy 130.286003 -124.29007) (xy 130.281932 -124.234448) (xy 114.14506 -124.234448) (xy 114.14506 -125.140466)
			(xy 114.763042 -125.758448) (xy 130.281932 -125.758448) (xy 130.286003 -125.702826) (xy 130.298129 -125.648389)
			(xy 130.318052 -125.596298) (xy 130.345348 -125.547663) (xy 130.379434 -125.50352) (xy 130.419583 -125.464811)
			(xy 130.464941 -125.43236) (xy 130.514541 -125.406859) (xy 130.567325 -125.388852) (xy 130.622168 -125.378722)
			(xy 130.677902 -125.376685) (xy 130.733339 -125.382785) (xy 130.787296 -125.396891) (xy 130.838625 -125.418703)
			(xy 130.886231 -125.447757) (xy 130.929099 -125.483432) (xy 130.966316 -125.524969) (xy 130.997089 -125.571482)
			(xy 131.020761 -125.621979) (xy 131.036829 -125.675386) (xy 131.044949 -125.730562) (xy 131.045458 -125.758448)
			(xy 131.044949 -125.786334) (xy 131.036829 -125.84151) (xy 131.020761 -125.894917) (xy 130.997089 -125.945414)
			(xy 130.966316 -125.991927) (xy 130.929099 -126.033464) (xy 130.886231 -126.069139) (xy 130.838625 -126.098193)
			(xy 130.787296 -126.120005) (xy 130.733339 -126.134111) (xy 130.677902 -126.140211) (xy 130.622168 -126.138174)
			(xy 130.567325 -126.128044) (xy 130.514541 -126.110037) (xy 130.464941 -126.084536) (xy 130.419583 -126.052085)
			(xy 130.379434 -126.013376) (xy 130.345348 -125.969233) (xy 130.318052 -125.920598) (xy 130.298129 -125.868507)
			(xy 130.286003 -125.81407) (xy 130.281932 -125.758448) (xy 114.763042 -125.758448) (xy 116.096542 -127.091948)
			(xy 132.769862 -127.091948) (xy 132.773933 -127.036326) (xy 132.786059 -126.981889) (xy 132.805982 -126.929798)
			(xy 132.833278 -126.881163) (xy 132.867364 -126.83702) (xy 132.907513 -126.798311) (xy 132.952871 -126.76586)
			(xy 133.002471 -126.740359) (xy 133.055255 -126.722352) (xy 133.110098 -126.712222) (xy 133.165832 -126.710185)
			(xy 133.221269 -126.716285) (xy 133.275226 -126.730391) (xy 133.326555 -126.752203) (xy 133.374161 -126.781257)
			(xy 133.417029 -126.816932) (xy 133.454246 -126.858469) (xy 133.485019 -126.904982) (xy 133.508691 -126.955479)
			(xy 133.524759 -127.008886) (xy 133.532879 -127.064062) (xy 133.533388 -127.091948) (xy 133.532879 -127.119834)
			(xy 133.524759 -127.17501) (xy 133.508691 -127.228417) (xy 133.485019 -127.278914) (xy 133.454246 -127.325427)
			(xy 133.417029 -127.366964) (xy 133.374161 -127.402639) (xy 133.326555 -127.431693) (xy 133.275226 -127.453505)
			(xy 133.221269 -127.467611) (xy 133.165832 -127.473711) (xy 133.110098 -127.471674) (xy 133.055255 -127.461544)
			(xy 133.002471 -127.443537) (xy 132.952871 -127.418036) (xy 132.907513 -127.385585) (xy 132.867364 -127.346876)
			(xy 132.833278 -127.302733) (xy 132.805982 -127.254098) (xy 132.786059 -127.202007) (xy 132.773933 -127.14757)
			(xy 132.769862 -127.091948) (xy 116.096542 -127.091948) (xy 116.153438 -127.148844) (xy 116.153438 -128.681988)
			(xy 119.981472 -128.681988) (xy 119.982037 -128.65248) (xy 119.991101 -128.594165) (xy 120.009042 -128.537942)
			(xy 120.03543 -128.485155) (xy 120.069637 -128.437065) (xy 120.110845 -128.394818) (xy 120.134126 -128.37668)
			(xy 120.145667 -128.367513) (xy 120.163266 -128.343882) (xy 120.173377 -128.316207) (xy 120.175158 -128.286797)
			(xy 120.16846 -128.258104) (xy 120.153841 -128.232522) (xy 120.143524 -128.221994) (xy 120.125219 -128.203948)
			(xy 120.093183 -128.163749) (xy 120.066831 -128.119615) (xy 120.04664 -128.072344) (xy 120.032975 -128.02279)
			(xy 120.026084 -127.971852) (xy 120.025668 -127.94615) (xy 120.026154 -127.918899) (xy 120.03391 -127.864951)
			(xy 120.049265 -127.812656) (xy 120.071907 -127.763079) (xy 120.101373 -127.717229) (xy 120.137064 -127.676038)
			(xy 120.178255 -127.640347) (xy 120.224105 -127.610881) (xy 120.273682 -127.588239) (xy 120.325977 -127.572884)
			(xy 120.379925 -127.565128) (xy 120.434427 -127.565128) (xy 120.488375 -127.572884) (xy 120.54067 -127.588239)
			(xy 120.590247 -127.610881) (xy 120.636097 -127.640347) (xy 120.677288 -127.676038) (xy 120.712979 -127.717229)
			(xy 120.742445 -127.763079) (xy 120.765087 -127.812656) (xy 120.780442 -127.864951) (xy 120.788198 -127.918899)
			(xy 120.788684 -127.94615) (xy 120.788164 -127.97566) (xy 120.779093 -128.033978) (xy 120.761144 -128.090202)
			(xy 120.734747 -128.142989) (xy 120.700532 -128.191079) (xy 120.659315 -128.233322) (xy 120.63603 -128.251458)
			(xy 120.624549 -128.260692) (xy 120.606956 -128.284307) (xy 120.596844 -128.311964) (xy 120.595053 -128.341358)
			(xy 120.601733 -128.370038) (xy 120.616328 -128.395615) (xy 120.626632 -128.406144) (xy 120.644898 -128.424227)
			(xy 120.67694 -128.464417) (xy 120.703298 -128.508543) (xy 120.706548 -128.516147) (xy 132.770926 -128.516147)
			(xy 132.770926 -128.461653) (xy 132.778681 -128.407714) (xy 132.794033 -128.355427) (xy 132.81667 -128.305858)
			(xy 132.846131 -128.260014) (xy 132.881816 -128.21883) (xy 132.922998 -128.183143) (xy 132.96884 -128.15368)
			(xy 133.018409 -128.13104) (xy 133.070694 -128.115685) (xy 133.124633 -128.107928) (xy 133.15188 -128.10744)
			(xy 133.178105 -128.107884) (xy 133.230062 -128.115062) (xy 133.280546 -128.129285) (xy 133.328609 -128.150286)
			(xy 133.373343 -128.177669) (xy 133.413908 -128.210918) (xy 133.432042 -128.229868) (xy 133.442033 -128.239918)
			(xy 133.466228 -128.254643) (xy 133.493537 -128.262154) (xy 133.521859 -128.261874) (xy 133.549015 -128.253825)
			(xy 133.572914 -128.238626) (xy 133.582664 -128.228344) (xy 133.600869 -128.208456) (xy 133.641882 -128.173459)
			(xy 133.687413 -128.144586) (xy 133.736557 -128.12241) (xy 133.788333 -128.107375) (xy 133.841711 -128.09978)
			(xy 133.868668 -128.099312) (xy 133.895924 -128.099733) (xy 133.949881 -128.107486) (xy 134.002186 -128.12284)
			(xy 134.051772 -128.145482) (xy 134.097632 -128.174951) (xy 134.138831 -128.210647) (xy 134.17453 -128.251842)
			(xy 134.204002 -128.297699) (xy 134.226648 -128.347284) (xy 134.242007 -128.399588) (xy 134.249765 -128.453544)
			(xy 134.249765 -128.508056) (xy 134.242007 -128.562012) (xy 134.226648 -128.614316) (xy 134.204002 -128.663901)
			(xy 134.17453 -128.709758) (xy 134.138831 -128.750953) (xy 134.097632 -128.786649) (xy 134.051772 -128.816118)
			(xy 134.002186 -128.83876) (xy 133.949881 -128.854114) (xy 133.895924 -128.861867) (xy 133.868668 -128.862328)
			(xy 133.842441 -128.861929) (xy 133.790482 -128.854743) (xy 133.739996 -128.840512) (xy 133.691934 -128.819503)
			(xy 133.647201 -128.792111) (xy 133.606639 -128.758854) (xy 133.588506 -128.7399) (xy 133.578562 -128.729801)
			(xy 133.554353 -128.715084) (xy 133.527032 -128.707581) (xy 133.498701 -128.707871) (xy 133.47154 -128.715929)
			(xy 133.447635 -128.731138) (xy 133.437884 -128.741424) (xy 133.419699 -128.761331) (xy 133.378683 -128.796327)
			(xy 133.333147 -128.825199) (xy 133.283999 -128.847372) (xy 133.232219 -128.862402) (xy 133.178839 -128.869992)
			(xy 133.15188 -128.870456) (xy 133.124633 -128.869872) (xy 133.070694 -128.862115) (xy 133.018409 -128.84676)
			(xy 132.96884 -128.82412) (xy 132.922998 -128.794657) (xy 132.881816 -128.75897) (xy 132.846131 -128.717786)
			(xy 132.81667 -128.671942) (xy 132.794033 -128.622373) (xy 132.778681 -128.570086) (xy 132.770926 -128.516147)
			(xy 120.706548 -128.516147) (xy 120.723496 -128.555807) (xy 120.737169 -128.605354) (xy 120.744068 -128.656288)
			(xy 120.744488 -128.681988) (xy 120.744002 -128.709239) (xy 120.736246 -128.763187) (xy 120.720891 -128.815482)
			(xy 120.698249 -128.865059) (xy 120.668783 -128.910909) (xy 120.633092 -128.9521) (xy 120.591901 -128.987791)
			(xy 120.546051 -129.017257) (xy 120.496474 -129.039899) (xy 120.444179 -129.055254) (xy 120.390231 -129.06301)
			(xy 120.335729 -129.06301) (xy 120.281781 -129.055254) (xy 120.229486 -129.039899) (xy 120.179909 -129.017257)
			(xy 120.134059 -128.987791) (xy 120.092868 -128.9521) (xy 120.057177 -128.910909) (xy 120.027711 -128.865059)
			(xy 120.005069 -128.815482) (xy 119.989714 -128.763187) (xy 119.981958 -128.709239) (xy 119.981472 -128.681988)
			(xy 116.153438 -128.681988) (xy 116.153438 -129.586482) (xy 116.540024 -129.586482) (xy 116.544095 -129.53086)
			(xy 116.556221 -129.476423) (xy 116.576144 -129.424332) (xy 116.60344 -129.375697) (xy 116.637526 -129.331554)
			(xy 116.677675 -129.292845) (xy 116.723033 -129.260394) (xy 116.772633 -129.234893) (xy 116.825417 -129.216886)
			(xy 116.88026 -129.206756) (xy 116.935994 -129.204719) (xy 116.991431 -129.210819) (xy 117.045388 -129.224925)
			(xy 117.096717 -129.246737) (xy 117.144323 -129.275791) (xy 117.187191 -129.311466) (xy 117.224408 -129.353003)
			(xy 117.255181 -129.399516) (xy 117.278853 -129.450013) (xy 117.294921 -129.50342) (xy 117.303041 -129.558596)
			(xy 117.30355 -129.586482) (xy 117.303041 -129.614368) (xy 117.294921 -129.669544) (xy 117.278853 -129.722951)
			(xy 117.255181 -129.773448) (xy 117.224408 -129.819961) (xy 117.187191 -129.861498) (xy 117.144323 -129.897173)
			(xy 117.118149 -129.913147) (xy 132.770926 -129.913147) (xy 132.770926 -129.858653) (xy 132.778681 -129.804714)
			(xy 132.794033 -129.752427) (xy 132.81667 -129.702858) (xy 132.846131 -129.657014) (xy 132.881816 -129.61583)
			(xy 132.922998 -129.580143) (xy 132.96884 -129.55068) (xy 133.018409 -129.52804) (xy 133.070694 -129.512685)
			(xy 133.124633 -129.504928) (xy 133.15188 -129.50444) (xy 133.180584 -129.504951) (xy 133.237344 -129.51355)
			(xy 133.292175 -129.530558) (xy 133.343838 -129.55559) (xy 133.391167 -129.588081) (xy 133.412484 -129.60731)
			(xy 133.424184 -129.617621) (xy 133.452282 -129.631124) (xy 133.483143 -129.635533) (xy 133.513897 -129.630436)
			(xy 133.541686 -129.616308) (xy 133.5532 -129.605786) (xy 133.574735 -129.585441) (xy 133.622919 -129.550978)
			(xy 133.675852 -129.524379) (xy 133.73226 -129.506283) (xy 133.790788 -129.497126) (xy 133.820408 -129.496566)
			(xy 133.847657 -129.497105) (xy 133.9016 -129.504862) (xy 133.95389 -129.520216) (xy 134.003463 -129.542856)
			(xy 134.049309 -129.572321) (xy 134.090496 -129.60801) (xy 134.126184 -129.649197) (xy 134.155647 -129.695044)
			(xy 134.178286 -129.744617) (xy 134.19364 -129.796908) (xy 134.201396 -129.850851) (xy 134.201396 -129.905349)
			(xy 134.19364 -129.959292) (xy 134.178286 -130.011583) (xy 134.155647 -130.061156) (xy 134.126184 -130.107003)
			(xy 134.090496 -130.14819) (xy 134.049309 -130.183879) (xy 134.003463 -130.213344) (xy 133.95389 -130.235984)
			(xy 133.9016 -130.251338) (xy 133.847657 -130.259095) (xy 133.820408 -130.259582) (xy 133.791704 -130.259073)
			(xy 133.734944 -130.250472) (xy 133.680113 -130.233464) (xy 133.62845 -130.208432) (xy 133.581121 -130.175941)
			(xy 133.559804 -130.156712) (xy 133.548035 -130.146486) (xy 133.519963 -130.13297) (xy 133.489122 -130.128545)
			(xy 133.458381 -130.13362) (xy 133.4306 -130.147726) (xy 133.419088 -130.158236) (xy 133.397562 -130.178591)
			(xy 133.349375 -130.213051) (xy 133.29644 -130.239648) (xy 133.24003 -130.257742) (xy 133.181501 -130.266898)
			(xy 133.15188 -130.267456) (xy 133.124633 -130.266872) (xy 133.070694 -130.259115) (xy 133.018409 -130.24376)
			(xy 132.96884 -130.22112) (xy 132.922998 -130.191657) (xy 132.881816 -130.15597) (xy 132.846131 -130.114786)
			(xy 132.81667 -130.068942) (xy 132.794033 -130.019373) (xy 132.778681 -129.967086) (xy 132.770926 -129.913147)
			(xy 117.118149 -129.913147) (xy 117.096717 -129.926227) (xy 117.045388 -129.948039) (xy 116.991431 -129.962145)
			(xy 116.935994 -129.968245) (xy 116.88026 -129.966208) (xy 116.825417 -129.956078) (xy 116.772633 -129.938071)
			(xy 116.723033 -129.91257) (xy 116.677675 -129.880119) (xy 116.637526 -129.84141) (xy 116.60344 -129.797267)
			(xy 116.576144 -129.748632) (xy 116.556221 -129.696541) (xy 116.544095 -129.642104) (xy 116.540024 -129.586482)
			(xy 116.153438 -129.586482) (xy 116.153438 -131.282948) (xy 132.770372 -131.282948) (xy 132.7709 -131.255697)
			(xy 132.77865 -131.20175) (xy 132.793999 -131.149454) (xy 132.816634 -131.099876) (xy 132.846095 -131.054023)
			(xy 132.881782 -131.01283) (xy 132.922969 -130.977136) (xy 132.968816 -130.947667) (xy 133.01839 -130.925023)
			(xy 133.070683 -130.909664) (xy 133.124629 -130.901905) (xy 133.15188 -130.90144) (xy 133.180417 -130.901982)
			(xy 133.236853 -130.910489) (xy 133.291389 -130.927317) (xy 133.342807 -130.952088) (xy 133.389956 -130.98425)
			(xy 133.411214 -131.003294) (xy 133.423003 -131.013494) (xy 133.451201 -131.026757) (xy 133.482082 -131.03093)
			(xy 133.512788 -131.025626) (xy 133.54048 -131.011336) (xy 133.55193 -131.000754) (xy 133.573488 -130.98012)
			(xy 133.621868 -130.945188) (xy 133.675098 -130.918218) (xy 133.731879 -130.899867) (xy 133.790825 -130.890583)
			(xy 133.820662 -130.89001) (xy 133.847918 -130.890434) (xy 133.901876 -130.898187) (xy 133.954181 -130.913541)
			(xy 134.003768 -130.936182) (xy 134.049628 -130.965651) (xy 134.090827 -131.001346) (xy 134.126527 -131.042542)
			(xy 134.156 -131.088399) (xy 134.178646 -131.137984) (xy 134.194005 -131.190287) (xy 134.201763 -131.244244)
			(xy 134.201763 -131.298756) (xy 134.194005 -131.352713) (xy 134.178646 -131.405016) (xy 134.156 -131.454601)
			(xy 134.126527 -131.500458) (xy 134.090827 -131.541654) (xy 134.049628 -131.577349) (xy 134.003768 -131.606818)
			(xy 133.954181 -131.629459) (xy 133.901876 -131.644813) (xy 133.847918 -131.652566) (xy 133.820662 -131.653026)
			(xy 133.793057 -131.652536) (xy 133.738422 -131.644585) (xy 133.685504 -131.628839) (xy 133.635409 -131.605629)
			(xy 133.589184 -131.575438) (xy 133.547795 -131.538899) (xy 133.529578 -131.518152) (xy 133.521839 -131.509941)
			(xy 133.501269 -131.500723) (xy 133.478732 -131.501171) (xy 133.458544 -131.5112) (xy 133.451092 -131.519676)
			(xy 133.442456 -131.53009) (xy 133.433244 -131.541785) (xy 133.421292 -131.569032) (xy 133.417699 -131.598568)
			(xy 133.422772 -131.627885) (xy 133.436079 -131.654497) (xy 133.456491 -131.676144) (xy 133.469126 -131.684014)
			(xy 133.493677 -131.698684) (xy 133.538433 -131.734292) (xy 133.577374 -131.77618) (xy 133.609627 -131.823411)
			(xy 133.634471 -131.874927) (xy 133.651347 -131.929573) (xy 133.65988 -131.986126) (xy 133.660388 -132.014722)
			(xy 133.659902 -132.041973) (xy 133.652146 -132.095921) (xy 133.636791 -132.148216) (xy 133.614149 -132.197793)
			(xy 133.584683 -132.243643) (xy 133.548992 -132.284834) (xy 133.507801 -132.320525) (xy 133.461951 -132.349991)
			(xy 133.412374 -132.372633) (xy 133.360079 -132.387988) (xy 133.306131 -132.395744) (xy 133.251629 -132.395744)
			(xy 133.197681 -132.387988) (xy 133.145386 -132.372633) (xy 133.095809 -132.349991) (xy 133.049959 -132.320525)
			(xy 133.008768 -132.284834) (xy 132.973077 -132.243643) (xy 132.943611 -132.197793) (xy 132.920969 -132.148216)
			(xy 132.905614 -132.095921) (xy 132.897858 -132.041973) (xy 132.897372 -132.014722) (xy 132.897802 -131.987821)
			(xy 132.905365 -131.934553) (xy 132.920343 -131.882877) (xy 132.94244 -131.833822) (xy 132.971215 -131.788361)
			(xy 132.988304 -131.76758) (xy 132.997562 -131.755917) (xy 133.009517 -131.728659) (xy 133.013106 -131.699113)
			(xy 133.008025 -131.669786) (xy 132.994705 -131.643169) (xy 132.974277 -131.621523) (xy 132.961634 -131.613656)
			(xy 132.937128 -131.598914) (xy 132.892369 -131.563321) (xy 132.853423 -131.521446) (xy 132.821164 -131.474227)
			(xy 132.796313 -131.422722) (xy 132.779428 -131.368086) (xy 132.770885 -131.311541) (xy 132.770372 -131.282948)
			(xy 116.153438 -131.282948) (xy 116.153438 -132.28701) (xy 116.153947 -132.296824) (xy 116.161424 -132.314977)
			(xy 116.175167 -132.328999) (xy 116.193167 -132.33684) (xy 116.202968 -132.337556) (xy 116.231073 -132.338733)
			(xy 116.286499 -132.348323) (xy 116.339917 -132.365945) (xy 116.390171 -132.391217) (xy 116.43617 -132.423592)
			(xy 116.47692 -132.462367) (xy 116.511536 -132.506704) (xy 116.53927 -132.555641) (xy 116.559521 -132.608119)
			(xy 116.57185 -132.663002) (xy 116.575989 -132.719099) (xy 116.57185 -132.775197) (xy 116.559522 -132.830079)
			(xy 116.539271 -132.882557) (xy 116.511537 -132.931495) (xy 116.476921 -132.975832) (xy 116.436172 -133.014607)
			(xy 116.390172 -133.046982) (xy 116.339919 -133.072254) (xy 116.286501 -133.089876) (xy 116.231075 -133.099467)
			(xy 116.202968 -133.100572) (xy 116.193161 -133.101263) (xy 116.175146 -133.109093) (xy 116.161401 -133.123126)
			(xy 116.153946 -133.141298) (xy 116.153438 -133.151118) (xy 116.153438 -133.424422) (xy 132.896862 -133.424422)
			(xy 132.900933 -133.3688) (xy 132.913059 -133.314363) (xy 132.932982 -133.262272) (xy 132.960278 -133.213637)
			(xy 132.994364 -133.169494) (xy 133.034513 -133.130785) (xy 133.079871 -133.098334) (xy 133.129471 -133.072833)
			(xy 133.182255 -133.054826) (xy 133.237098 -133.044696) (xy 133.292832 -133.042659) (xy 133.348269 -133.048759)
			(xy 133.402226 -133.062865) (xy 133.453555 -133.084677) (xy 133.501161 -133.113731) (xy 133.544029 -133.149406)
			(xy 133.581246 -133.190943) (xy 133.612019 -133.237456) (xy 133.635691 -133.287953) (xy 133.651759 -133.34136)
			(xy 133.659879 -133.396536) (xy 133.660388 -133.424422) (xy 133.659879 -133.452308) (xy 133.651759 -133.507484)
			(xy 133.635691 -133.560891) (xy 133.612019 -133.611388) (xy 133.581246 -133.657901) (xy 133.544029 -133.699438)
			(xy 133.501161 -133.735113) (xy 133.453555 -133.764167) (xy 133.402226 -133.785979) (xy 133.348269 -133.800085)
			(xy 133.292832 -133.806185) (xy 133.237098 -133.804148) (xy 133.182255 -133.794018) (xy 133.129471 -133.776011)
			(xy 133.079871 -133.75051) (xy 133.034513 -133.718059) (xy 132.994364 -133.67935) (xy 132.960278 -133.635207)
			(xy 132.932982 -133.586572) (xy 132.913059 -133.534481) (xy 132.900933 -133.480044) (xy 132.896862 -133.424422)
			(xy 116.153438 -133.424422) (xy 116.153438 -135.321548) (xy 115.426236 -136.04875) (xy 113.486946 -136.04875)
			(xy 112.86363 -135.425434) (xy 112.86363 -130.022854) (xy 110.682278 -127.841502) (xy 109.74705 -127.841502)
			(xy 109.05109 -128.537462) (xy 109.05617 -128.564132) (xy 109.059397 -128.581991) (xy 109.062831 -128.618121)
			(xy 109.063028 -128.636268) (xy 109.062567 -128.663523) (xy 109.054814 -128.717478) (xy 109.039461 -128.769781)
			(xy 109.019124 -128.814322) (xy 109.147862 -128.814322) (xy 109.151933 -128.7587) (xy 109.164059 -128.704263)
			(xy 109.183982 -128.652172) (xy 109.211278 -128.603537) (xy 109.245364 -128.559394) (xy 109.285513 -128.520685)
			(xy 109.330871 -128.488234) (xy 109.380471 -128.462733) (xy 109.433255 -128.444726) (xy 109.488098 -128.434596)
			(xy 109.543832 -128.432559) (xy 109.599269 -128.438659) (xy 109.653226 -128.452765) (xy 109.704555 -128.474577)
			(xy 109.752161 -128.503631) (xy 109.795029 -128.539306) (xy 109.832246 -128.580843) (xy 109.863019 -128.627356)
			(xy 109.886691 -128.677853) (xy 109.902759 -128.73126) (xy 109.910879 -128.786436) (xy 109.911388 -128.814322)
			(xy 109.910879 -128.842208) (xy 109.902759 -128.897384) (xy 109.886691 -128.950791) (xy 109.863019 -129.001288)
			(xy 109.832246 -129.047801) (xy 109.795029 -129.089338) (xy 109.752161 -129.125013) (xy 109.704555 -129.154067)
			(xy 109.653226 -129.175879) (xy 109.599269 -129.189985) (xy 109.543832 -129.196085) (xy 109.488098 -129.194048)
			(xy 109.433255 -129.183918) (xy 109.380471 -129.165911) (xy 109.330871 -129.14041) (xy 109.285513 -129.107959)
			(xy 109.245364 -129.06925) (xy 109.211278 -129.025107) (xy 109.183982 -128.976472) (xy 109.164059 -128.924381)
			(xy 109.151933 -128.869944) (xy 109.147862 -128.814322) (xy 109.019124 -128.814322) (xy 109.016821 -128.819367)
			(xy 108.987354 -128.865225) (xy 108.95166 -128.906424) (xy 108.910467 -128.942123) (xy 108.864612 -128.971596)
			(xy 108.81503 -128.994243) (xy 108.762729 -129.009603) (xy 108.708775 -129.017364) (xy 108.68152 -129.017776)
			(xy 108.663374 -129.017562) (xy 108.627245 -129.014131) (xy 108.609384 -129.010918) (xy 108.582714 -129.005838)
			(xy 108.223558 -129.364994) (xy 108.223558 -130.206242) (xy 109.147862 -130.206242) (xy 109.151933 -130.15062)
			(xy 109.164059 -130.096183) (xy 109.183982 -130.044092) (xy 109.211278 -129.995457) (xy 109.245364 -129.951314)
			(xy 109.285513 -129.912605) (xy 109.330871 -129.880154) (xy 109.380471 -129.854653) (xy 109.433255 -129.836646)
			(xy 109.488098 -129.826516) (xy 109.543832 -129.824479) (xy 109.599269 -129.830579) (xy 109.653226 -129.844685)
			(xy 109.704555 -129.866497) (xy 109.752161 -129.895551) (xy 109.795029 -129.931226) (xy 109.832246 -129.972763)
			(xy 109.863019 -130.019276) (xy 109.886691 -130.069773) (xy 109.902759 -130.12318) (xy 109.910879 -130.178356)
			(xy 109.911388 -130.206242) (xy 109.910879 -130.234128) (xy 109.902759 -130.289304) (xy 109.886691 -130.342711)
			(xy 109.863019 -130.393208) (xy 109.832246 -130.439721) (xy 109.795029 -130.481258) (xy 109.752161 -130.516933)
			(xy 109.704555 -130.545987) (xy 109.653226 -130.567799) (xy 109.599269 -130.581905) (xy 109.543832 -130.588005)
			(xy 109.488098 -130.585968) (xy 109.433255 -130.575838) (xy 109.380471 -130.557831) (xy 109.330871 -130.53233)
			(xy 109.285513 -130.499879) (xy 109.245364 -130.46117) (xy 109.211278 -130.417027) (xy 109.183982 -130.368392)
			(xy 109.164059 -130.316301) (xy 109.151933 -130.261864) (xy 109.147862 -130.206242) (xy 108.223558 -130.206242)
			(xy 108.223558 -131.023868) (xy 108.459522 -131.023868) (xy 108.463593 -130.968246) (xy 108.475719 -130.913809)
			(xy 108.495642 -130.861718) (xy 108.522938 -130.813083) (xy 108.557024 -130.76894) (xy 108.597173 -130.730231)
			(xy 108.642531 -130.69778) (xy 108.692131 -130.672279) (xy 108.744915 -130.654272) (xy 108.799758 -130.644142)
			(xy 108.855492 -130.642105) (xy 108.910929 -130.648205) (xy 108.964886 -130.662311) (xy 109.016215 -130.684123)
			(xy 109.063821 -130.713177) (xy 109.106689 -130.748852) (xy 109.143906 -130.790389) (xy 109.174679 -130.836902)
			(xy 109.198351 -130.887399) (xy 109.214419 -130.940806) (xy 109.222539 -130.995982) (xy 109.223048 -131.023868)
			(xy 109.222539 -131.051754) (xy 109.214419 -131.10693) (xy 109.198351 -131.160337) (xy 109.174679 -131.210834)
			(xy 109.143906 -131.257347) (xy 109.106689 -131.298884) (xy 109.063821 -131.334559) (xy 109.016215 -131.363613)
			(xy 108.964886 -131.385425) (xy 108.910929 -131.399531) (xy 108.855492 -131.405631) (xy 108.799758 -131.403594)
			(xy 108.744915 -131.393464) (xy 108.692131 -131.375457) (xy 108.642531 -131.349956) (xy 108.597173 -131.317505)
			(xy 108.557024 -131.278796) (xy 108.522938 -131.234653) (xy 108.495642 -131.186018) (xy 108.475719 -131.133927)
			(xy 108.463593 -131.07949) (xy 108.459522 -131.023868) (xy 108.223558 -131.023868) (xy 108.223558 -131.605782)
			(xy 109.147862 -131.605782) (xy 109.151933 -131.55016) (xy 109.164059 -131.495723) (xy 109.183982 -131.443632)
			(xy 109.211278 -131.394997) (xy 109.245364 -131.350854) (xy 109.285513 -131.312145) (xy 109.330871 -131.279694)
			(xy 109.380471 -131.254193) (xy 109.433255 -131.236186) (xy 109.488098 -131.226056) (xy 109.543832 -131.224019)
			(xy 109.599269 -131.230119) (xy 109.653226 -131.244225) (xy 109.704555 -131.266037) (xy 109.752161 -131.295091)
			(xy 109.795029 -131.330766) (xy 109.832246 -131.372303) (xy 109.863019 -131.418816) (xy 109.886691 -131.469313)
			(xy 109.902759 -131.52272) (xy 109.910879 -131.577896) (xy 109.911388 -131.605782) (xy 109.910879 -131.633668)
			(xy 109.902759 -131.688844) (xy 109.886691 -131.742251) (xy 109.863019 -131.792748) (xy 109.832246 -131.839261)
			(xy 109.795029 -131.880798) (xy 109.752161 -131.916473) (xy 109.704555 -131.945527) (xy 109.653226 -131.967339)
			(xy 109.599269 -131.981445) (xy 109.543832 -131.987545) (xy 109.488098 -131.985508) (xy 109.433255 -131.975378)
			(xy 109.380471 -131.957371) (xy 109.330871 -131.93187) (xy 109.285513 -131.899419) (xy 109.245364 -131.86071)
			(xy 109.211278 -131.816567) (xy 109.183982 -131.767932) (xy 109.164059 -131.715841) (xy 109.151933 -131.661404)
			(xy 109.147862 -131.605782) (xy 108.223558 -131.605782) (xy 108.223558 -132.933948) (xy 109.147862 -132.933948)
			(xy 109.151933 -132.878326) (xy 109.164059 -132.823889) (xy 109.183982 -132.771798) (xy 109.211278 -132.723163)
			(xy 109.245364 -132.67902) (xy 109.285513 -132.640311) (xy 109.330871 -132.60786) (xy 109.380471 -132.582359)
			(xy 109.433255 -132.564352) (xy 109.488098 -132.554222) (xy 109.543832 -132.552185) (xy 109.599269 -132.558285)
			(xy 109.653226 -132.572391) (xy 109.704555 -132.594203) (xy 109.752161 -132.623257) (xy 109.795029 -132.658932)
			(xy 109.832246 -132.700469) (xy 109.863019 -132.746982) (xy 109.886691 -132.797479) (xy 109.902759 -132.850886)
			(xy 109.910879 -132.906062) (xy 109.911388 -132.933948) (xy 109.910879 -132.961834) (xy 109.902759 -133.01701)
			(xy 109.886691 -133.070417) (xy 109.863019 -133.120914) (xy 109.832246 -133.167427) (xy 109.795029 -133.208964)
			(xy 109.752161 -133.244639) (xy 109.704555 -133.273693) (xy 109.653226 -133.295505) (xy 109.599269 -133.309611)
			(xy 109.543832 -133.315711) (xy 109.488098 -133.313674) (xy 109.433255 -133.303544) (xy 109.380471 -133.285537)
			(xy 109.330871 -133.260036) (xy 109.285513 -133.227585) (xy 109.245364 -133.188876) (xy 109.211278 -133.144733)
			(xy 109.183982 -133.096098) (xy 109.164059 -133.044007) (xy 109.151933 -132.98957) (xy 109.147862 -132.933948)
			(xy 108.223558 -132.933948) (xy 108.223558 -136.083548) (xy 110.011462 -136.083548) (xy 110.015533 -136.027926)
			(xy 110.027659 -135.973489) (xy 110.047582 -135.921398) (xy 110.074878 -135.872763) (xy 110.108964 -135.82862)
			(xy 110.149113 -135.789911) (xy 110.194471 -135.75746) (xy 110.244071 -135.731959) (xy 110.296855 -135.713952)
			(xy 110.351698 -135.703822) (xy 110.407432 -135.701785) (xy 110.462869 -135.707885) (xy 110.516826 -135.721991)
			(xy 110.568155 -135.743803) (xy 110.615761 -135.772857) (xy 110.658629 -135.808532) (xy 110.695846 -135.850069)
			(xy 110.726619 -135.896582) (xy 110.750291 -135.947079) (xy 110.766359 -136.000486) (xy 110.774479 -136.055662)
			(xy 110.774988 -136.083548) (xy 110.774479 -136.111434) (xy 110.766359 -136.16661) (xy 110.750291 -136.220017)
			(xy 110.726619 -136.270514) (xy 110.695846 -136.317027) (xy 110.658629 -136.358564) (xy 110.615761 -136.394239)
			(xy 110.568155 -136.423293) (xy 110.516826 -136.445105) (xy 110.462869 -136.459211) (xy 110.407432 -136.465311)
			(xy 110.351698 -136.463274) (xy 110.296855 -136.453144) (xy 110.244071 -136.435137) (xy 110.194471 -136.409636)
			(xy 110.149113 -136.377185) (xy 110.108964 -136.338476) (xy 110.074878 -136.294333) (xy 110.047582 -136.245698)
			(xy 110.027659 -136.193607) (xy 110.015533 -136.13917) (xy 110.011462 -136.083548) (xy 108.223558 -136.083548)
			(xy 108.223558 -137.198862) (xy 109.935262 -137.198862) (xy 109.939333 -137.14324) (xy 109.951459 -137.088803)
			(xy 109.971382 -137.036712) (xy 109.998678 -136.988077) (xy 110.032764 -136.943934) (xy 110.072913 -136.905225)
			(xy 110.118271 -136.872774) (xy 110.167871 -136.847273) (xy 110.220655 -136.829266) (xy 110.275498 -136.819136)
			(xy 110.331232 -136.817099) (xy 110.386669 -136.823199) (xy 110.440626 -136.837305) (xy 110.491955 -136.859117)
			(xy 110.539561 -136.888171) (xy 110.582429 -136.923846) (xy 110.619646 -136.965383) (xy 110.650419 -137.011896)
			(xy 110.674091 -137.062393) (xy 110.689625 -137.114026) (xy 129.029204 -137.114026) (xy 129.033275 -137.058404)
			(xy 129.045401 -137.003967) (xy 129.065324 -136.951876) (xy 129.09262 -136.903241) (xy 129.126706 -136.859098)
			(xy 129.166855 -136.820389) (xy 129.212213 -136.787938) (xy 129.261813 -136.762437) (xy 129.314597 -136.74443)
			(xy 129.36944 -136.7343) (xy 129.425174 -136.732263) (xy 129.480611 -136.738363) (xy 129.534568 -136.752469)
			(xy 129.585897 -136.774281) (xy 129.633503 -136.803335) (xy 129.676371 -136.83901) (xy 129.713588 -136.880547)
			(xy 129.744361 -136.92706) (xy 129.768033 -136.977557) (xy 129.784101 -137.030964) (xy 129.792221 -137.08614)
			(xy 129.79273 -137.114026) (xy 132.947662 -137.114026) (xy 132.951733 -137.058404) (xy 132.963859 -137.003967)
			(xy 132.983782 -136.951876) (xy 133.011078 -136.903241) (xy 133.045164 -136.859098) (xy 133.085313 -136.820389)
			(xy 133.130671 -136.787938) (xy 133.180271 -136.762437) (xy 133.233055 -136.74443) (xy 133.287898 -136.7343)
			(xy 133.343632 -136.732263) (xy 133.399069 -136.738363) (xy 133.453026 -136.752469) (xy 133.504355 -136.774281)
			(xy 133.551961 -136.803335) (xy 133.594829 -136.83901) (xy 133.632046 -136.880547) (xy 133.662819 -136.92706)
			(xy 133.686491 -136.977557) (xy 133.702559 -137.030964) (xy 133.710679 -137.08614) (xy 133.711188 -137.114026)
			(xy 133.710679 -137.141912) (xy 133.702559 -137.197088) (xy 133.686491 -137.250495) (xy 133.662819 -137.300992)
			(xy 133.632046 -137.347505) (xy 133.594829 -137.389042) (xy 133.551961 -137.424717) (xy 133.504355 -137.453771)
			(xy 133.453026 -137.475583) (xy 133.399069 -137.489689) (xy 133.343632 -137.495789) (xy 133.287898 -137.493752)
			(xy 133.233055 -137.483622) (xy 133.180271 -137.465615) (xy 133.130671 -137.440114) (xy 133.085313 -137.407663)
			(xy 133.045164 -137.368954) (xy 133.011078 -137.324811) (xy 132.983782 -137.276176) (xy 132.963859 -137.224085)
			(xy 132.951733 -137.169648) (xy 132.947662 -137.114026) (xy 129.79273 -137.114026) (xy 129.792221 -137.141912)
			(xy 129.784101 -137.197088) (xy 129.768033 -137.250495) (xy 129.744361 -137.300992) (xy 129.713588 -137.347505)
			(xy 129.676371 -137.389042) (xy 129.633503 -137.424717) (xy 129.585897 -137.453771) (xy 129.534568 -137.475583)
			(xy 129.480611 -137.489689) (xy 129.425174 -137.495789) (xy 129.36944 -137.493752) (xy 129.314597 -137.483622)
			(xy 129.261813 -137.465615) (xy 129.212213 -137.440114) (xy 129.166855 -137.407663) (xy 129.126706 -137.368954)
			(xy 129.09262 -137.324811) (xy 129.065324 -137.276176) (xy 129.045401 -137.224085) (xy 129.033275 -137.169648)
			(xy 129.029204 -137.114026) (xy 110.689625 -137.114026) (xy 110.690159 -137.1158) (xy 110.698279 -137.170976)
			(xy 110.698788 -137.198862) (xy 110.698279 -137.226748) (xy 110.690159 -137.281924) (xy 110.674091 -137.335331)
			(xy 110.650419 -137.385828) (xy 110.619646 -137.432341) (xy 110.582429 -137.473878) (xy 110.539561 -137.509553)
			(xy 110.491955 -137.538607) (xy 110.440626 -137.560419) (xy 110.386669 -137.574525) (xy 110.331232 -137.580625)
			(xy 110.275498 -137.578588) (xy 110.220655 -137.568458) (xy 110.167871 -137.550451) (xy 110.118271 -137.52495)
			(xy 110.072913 -137.492499) (xy 110.032764 -137.45379) (xy 109.998678 -137.409647) (xy 109.971382 -137.361012)
			(xy 109.951459 -137.308921) (xy 109.939333 -137.254484) (xy 109.935262 -137.198862) (xy 108.223558 -137.198862)
			(xy 108.223558 -137.799826) (xy 112.102644 -137.799826) (xy 112.106715 -137.744204) (xy 112.118841 -137.689767)
			(xy 112.138764 -137.637676) (xy 112.16606 -137.589041) (xy 112.200146 -137.544898) (xy 112.240295 -137.506189)
			(xy 112.285653 -137.473738) (xy 112.335253 -137.448237) (xy 112.388037 -137.43023) (xy 112.44288 -137.4201)
			(xy 112.498614 -137.418063) (xy 112.554051 -137.424163) (xy 112.608008 -137.438269) (xy 112.659337 -137.460081)
			(xy 112.706943 -137.489135) (xy 112.749811 -137.52481) (xy 112.787028 -137.566347) (xy 112.817801 -137.61286)
			(xy 112.841473 -137.663357) (xy 112.857541 -137.716764) (xy 112.865661 -137.77194) (xy 112.86617 -137.799826)
			(xy 112.865661 -137.827712) (xy 112.857541 -137.882888) (xy 112.841473 -137.936295) (xy 112.817801 -137.986792)
			(xy 112.787028 -138.033305) (xy 112.749811 -138.074842) (xy 112.706943 -138.110517) (xy 112.659337 -138.139571)
			(xy 112.608008 -138.161383) (xy 112.554051 -138.175489) (xy 112.498614 -138.181589) (xy 112.44288 -138.179552)
			(xy 112.388037 -138.169422) (xy 112.335253 -138.151415) (xy 112.285653 -138.125914) (xy 112.240295 -138.093463)
			(xy 112.200146 -138.054754) (xy 112.16606 -138.010611) (xy 112.138764 -137.961976) (xy 112.118841 -137.909885)
			(xy 112.106715 -137.855448) (xy 112.102644 -137.799826) (xy 108.223558 -137.799826) (xy 108.223558 -138.511026)
			(xy 132.922262 -138.511026) (xy 132.926333 -138.455404) (xy 132.938459 -138.400967) (xy 132.958382 -138.348876)
			(xy 132.985678 -138.300241) (xy 133.019764 -138.256098) (xy 133.059913 -138.217389) (xy 133.105271 -138.184938)
			(xy 133.154871 -138.159437) (xy 133.207655 -138.14143) (xy 133.262498 -138.1313) (xy 133.318232 -138.129263)
			(xy 133.373669 -138.135363) (xy 133.427626 -138.149469) (xy 133.478955 -138.171281) (xy 133.526561 -138.200335)
			(xy 133.569429 -138.23601) (xy 133.606646 -138.277547) (xy 133.637419 -138.32406) (xy 133.661091 -138.374557)
			(xy 133.677159 -138.427964) (xy 133.685279 -138.48314) (xy 133.685788 -138.511026) (xy 133.685279 -138.538912)
			(xy 133.677159 -138.594088) (xy 133.661091 -138.647495) (xy 133.637419 -138.697992) (xy 133.606646 -138.744505)
			(xy 133.569429 -138.786042) (xy 133.526561 -138.821717) (xy 133.478955 -138.850771) (xy 133.427626 -138.872583)
			(xy 133.373669 -138.886689) (xy 133.318232 -138.892789) (xy 133.262498 -138.890752) (xy 133.207655 -138.880622)
			(xy 133.154871 -138.862615) (xy 133.105271 -138.837114) (xy 133.059913 -138.804663) (xy 133.019764 -138.765954)
			(xy 132.985678 -138.721811) (xy 132.958382 -138.673176) (xy 132.938459 -138.621085) (xy 132.926333 -138.566648)
			(xy 132.922262 -138.511026) (xy 108.223558 -138.511026) (xy 108.223558 -139.069826) (xy 112.102644 -139.069826)
			(xy 112.106715 -139.014204) (xy 112.118841 -138.959767) (xy 112.138764 -138.907676) (xy 112.16606 -138.859041)
			(xy 112.200146 -138.814898) (xy 112.240295 -138.776189) (xy 112.285653 -138.743738) (xy 112.335253 -138.718237)
			(xy 112.388037 -138.70023) (xy 112.44288 -138.6901) (xy 112.498614 -138.688063) (xy 112.554051 -138.694163)
			(xy 112.608008 -138.708269) (xy 112.659337 -138.730081) (xy 112.706943 -138.759135) (xy 112.749811 -138.79481)
			(xy 112.787028 -138.836347) (xy 112.817801 -138.88286) (xy 112.841473 -138.933357) (xy 112.857541 -138.986764)
			(xy 112.865661 -139.04194) (xy 112.86617 -139.069826) (xy 112.865661 -139.097712) (xy 112.857541 -139.152888)
			(xy 112.841473 -139.206295) (xy 112.817801 -139.256792) (xy 112.787028 -139.303305) (xy 112.749811 -139.344842)
			(xy 112.706943 -139.380517) (xy 112.659337 -139.409571) (xy 112.608008 -139.431383) (xy 112.554051 -139.445489)
			(xy 112.498614 -139.451589) (xy 112.44288 -139.449552) (xy 112.388037 -139.439422) (xy 112.335253 -139.421415)
			(xy 112.285653 -139.395914) (xy 112.240295 -139.363463) (xy 112.200146 -139.324754) (xy 112.16606 -139.280611)
			(xy 112.138764 -139.231976) (xy 112.118841 -139.179885) (xy 112.106715 -139.125448) (xy 112.102644 -139.069826)
			(xy 108.223558 -139.069826) (xy 108.223558 -139.813538) (xy 125.143004 -139.813538) (xy 125.147075 -139.757916)
			(xy 125.159201 -139.703479) (xy 125.179124 -139.651388) (xy 125.20642 -139.602753) (xy 125.240506 -139.55861)
			(xy 125.280655 -139.519901) (xy 125.326013 -139.48745) (xy 125.375613 -139.461949) (xy 125.428397 -139.443942)
			(xy 125.48324 -139.433812) (xy 125.538974 -139.431775) (xy 125.594411 -139.437875) (xy 125.648368 -139.451981)
			(xy 125.699697 -139.473793) (xy 125.747303 -139.502847) (xy 125.790171 -139.538522) (xy 125.827388 -139.580059)
			(xy 125.858161 -139.626572) (xy 125.881833 -139.677069) (xy 125.897901 -139.730476) (xy 125.906021 -139.785652)
			(xy 125.90653 -139.813538) (xy 125.906021 -139.841424) (xy 125.897901 -139.8966) (xy 125.894463 -139.908026)
			(xy 132.094476 -139.908026) (xy 132.098547 -139.852404) (xy 132.110673 -139.797967) (xy 132.130596 -139.745876)
			(xy 132.157892 -139.697241) (xy 132.191978 -139.653098) (xy 132.232127 -139.614389) (xy 132.277485 -139.581938)
			(xy 132.327085 -139.556437) (xy 132.379869 -139.53843) (xy 132.434712 -139.5283) (xy 132.490446 -139.526263)
			(xy 132.545883 -139.532363) (xy 132.59984 -139.546469) (xy 132.651169 -139.568281) (xy 132.698775 -139.597335)
			(xy 132.741643 -139.63301) (xy 132.77886 -139.674547) (xy 132.809633 -139.72106) (xy 132.833305 -139.771557)
			(xy 132.849373 -139.824964) (xy 132.857493 -139.88014) (xy 132.858002 -139.908026) (xy 132.857493 -139.935912)
			(xy 132.849373 -139.991088) (xy 132.833305 -140.044495) (xy 132.809633 -140.094992) (xy 132.77886 -140.141505)
			(xy 132.741643 -140.183042) (xy 132.698775 -140.218717) (xy 132.651169 -140.247771) (xy 132.59984 -140.269583)
			(xy 132.545883 -140.283689) (xy 132.490446 -140.289789) (xy 132.434712 -140.287752) (xy 132.379869 -140.277622)
			(xy 132.327085 -140.259615) (xy 132.277485 -140.234114) (xy 132.232127 -140.201663) (xy 132.191978 -140.162954)
			(xy 132.157892 -140.118811) (xy 132.130596 -140.070176) (xy 132.110673 -140.018085) (xy 132.098547 -139.963648)
			(xy 132.094476 -139.908026) (xy 125.894463 -139.908026) (xy 125.881833 -139.950007) (xy 125.858161 -140.000504)
			(xy 125.827388 -140.047017) (xy 125.790171 -140.088554) (xy 125.747303 -140.124229) (xy 125.699697 -140.153283)
			(xy 125.648368 -140.175095) (xy 125.594411 -140.189201) (xy 125.538974 -140.195301) (xy 125.48324 -140.193264)
			(xy 125.428397 -140.183134) (xy 125.375613 -140.165127) (xy 125.326013 -140.139626) (xy 125.280655 -140.107175)
			(xy 125.240506 -140.068466) (xy 125.20642 -140.024323) (xy 125.179124 -139.975688) (xy 125.159201 -139.923597)
			(xy 125.147075 -139.86916) (xy 125.143004 -139.813538) (xy 108.223558 -139.813538) (xy 108.223558 -141.277848)
			(xy 123.188982 -141.277848) (xy 123.193053 -141.222226) (xy 123.205179 -141.167789) (xy 123.225102 -141.115698)
			(xy 123.252398 -141.067063) (xy 123.286484 -141.02292) (xy 123.326633 -140.984211) (xy 123.371991 -140.95176)
			(xy 123.421591 -140.926259) (xy 123.474375 -140.908252) (xy 123.529218 -140.898122) (xy 123.584952 -140.896085)
			(xy 123.640389 -140.902185) (xy 123.694346 -140.916291) (xy 123.745675 -140.938103) (xy 123.793281 -140.967157)
			(xy 123.836149 -141.002832) (xy 123.873366 -141.044369) (xy 123.904139 -141.090882) (xy 123.927811 -141.141379)
			(xy 123.943879 -141.194786) (xy 123.951999 -141.249962) (xy 123.952508 -141.277848) (xy 123.951999 -141.305734)
			(xy 123.943879 -141.36091) (xy 123.927811 -141.414317) (xy 123.904139 -141.464814) (xy 123.873366 -141.511327)
			(xy 123.836149 -141.552864) (xy 123.793281 -141.588539) (xy 123.745675 -141.617593) (xy 123.694346 -141.639405)
			(xy 123.640389 -141.653511) (xy 123.584952 -141.659611) (xy 123.529218 -141.657574) (xy 123.474375 -141.647444)
			(xy 123.421591 -141.629437) (xy 123.371991 -141.603936) (xy 123.326633 -141.571485) (xy 123.286484 -141.532776)
			(xy 123.252398 -141.488633) (xy 123.225102 -141.439998) (xy 123.205179 -141.387907) (xy 123.193053 -141.33347)
			(xy 123.188982 -141.277848) (xy 108.223558 -141.277848) (xy 108.223558 -144.584245) (xy 133.294042 -144.584245)
			(xy 133.294044 -144.529736) (xy 133.301802 -144.475783) (xy 133.317161 -144.423483) (xy 133.339806 -144.373901)
			(xy 133.369277 -144.328047) (xy 133.404974 -144.286853) (xy 133.44617 -144.251159) (xy 133.492027 -144.221692)
			(xy 133.541611 -144.19905) (xy 133.593912 -144.183696) (xy 133.647866 -144.175941) (xy 133.67512 -144.17548)
			(xy 133.695147 -144.175734) (xy 133.734982 -144.179935) (xy 133.754622 -144.183862) (xy 133.769466 -144.186438)
			(xy 133.799468 -144.183912) (xy 133.827427 -144.172742) (xy 133.850909 -144.153898) (xy 133.867871 -144.129023)
			(xy 133.876836 -144.100281) (xy 133.877023 -144.070173) (xy 133.87324 -144.055592) (xy 133.865882 -144.029149)
			(xy 133.857983 -143.974832) (xy 133.857492 -143.947388) (xy 133.857991 -143.920138) (xy 133.865749 -143.866192)
			(xy 133.881105 -143.8139) (xy 133.903747 -143.764326) (xy 133.933213 -143.718478) (xy 133.968904 -143.67729)
			(xy 134.010094 -143.641601) (xy 134.055943 -143.612137) (xy 134.105519 -143.589498) (xy 134.157812 -143.574145)
			(xy 134.211758 -143.56639) (xy 134.266258 -143.566391) (xy 134.320204 -143.574148) (xy 134.372496 -143.589504)
			(xy 134.422071 -143.612145) (xy 134.467919 -143.641611) (xy 134.509107 -143.677301) (xy 134.544797 -143.718491)
			(xy 134.574261 -143.76434) (xy 134.596901 -143.813915) (xy 134.612254 -143.866208) (xy 134.62001 -143.920154)
			(xy 134.620009 -143.974654) (xy 134.612253 -144.0286) (xy 134.596898 -144.080892) (xy 134.574257 -144.130467)
			(xy 134.544792 -144.176316) (xy 134.509101 -144.217504) (xy 134.467913 -144.253194) (xy 134.422064 -144.282659)
			(xy 134.372489 -144.305299) (xy 134.320196 -144.320654) (xy 134.26625 -144.32841) (xy 134.239 -144.328896)
			(xy 134.218973 -144.328637) (xy 134.179139 -144.324439) (xy 134.159498 -144.320514) (xy 134.144664 -144.317887)
			(xy 134.114661 -144.320432) (xy 134.086705 -144.331616) (xy 134.063226 -144.350468) (xy 134.046265 -144.375347)
			(xy 134.037298 -144.404091) (xy 134.037103 -144.4342) (xy 134.04088 -144.448784) (xy 134.048233 -144.475229)
			(xy 134.056135 -144.529544) (xy 134.056628 -144.556988) (xy 134.056158 -144.584242) (xy 134.048402 -144.638196)
			(xy 134.033047 -144.690497) (xy 134.010404 -144.74008) (xy 133.980936 -144.785936) (xy 133.945241 -144.827132)
			(xy 133.904047 -144.862828) (xy 133.858192 -144.892298) (xy 133.80861 -144.914942) (xy 133.756309 -144.930299)
			(xy 133.702356 -144.938057) (xy 133.647847 -144.938057) (xy 133.593893 -144.9303) (xy 133.541593 -144.914943)
			(xy 133.49201 -144.892299) (xy 133.446155 -144.862829) (xy 133.404961 -144.827134) (xy 133.369266 -144.785938)
			(xy 133.339797 -144.740083) (xy 133.317154 -144.690499) (xy 133.301798 -144.638199) (xy 133.294042 -144.584245)
			(xy 108.223558 -144.584245) (xy 108.223558 -145.491056) (xy 119.222423 -145.491056) (xy 119.222423 -145.436544)
			(xy 119.230181 -145.382587) (xy 119.245539 -145.330283) (xy 119.268185 -145.280697) (xy 119.297658 -145.234839)
			(xy 119.333357 -145.193642) (xy 119.374555 -145.157946) (xy 119.420415 -145.128476) (xy 119.470002 -145.105832)
			(xy 119.522306 -145.090477) (xy 119.576264 -145.082722) (xy 119.60352 -145.08226) (xy 119.629742 -145.082722)
			(xy 119.68169 -145.08992) (xy 119.732163 -145.104163) (xy 119.780211 -145.125184) (xy 119.824927 -145.152586)
			(xy 119.86547 -145.185853) (xy 119.901075 -145.224359) (xy 119.931073 -145.267377) (xy 119.943372 -145.29054)
			(xy 119.950018 -145.302465) (xy 119.968424 -145.322607) (xy 119.991504 -145.337162) (xy 120.017611 -145.345092)
			(xy 120.044887 -145.345833) (xy 120.071387 -145.339332) (xy 120.095222 -145.326051) (xy 120.114695 -145.306938)
			(xy 120.121934 -145.295366) (xy 120.136706 -145.270989) (xy 120.172279 -145.226458) (xy 120.214086 -145.187719)
			(xy 120.261195 -145.155638) (xy 120.312555 -145.130928) (xy 120.367023 -145.114142) (xy 120.423382 -145.105652)
			(xy 120.45188 -145.10512) (xy 120.479136 -145.105526) (xy 120.533093 -145.113281) (xy 120.585397 -145.128636)
			(xy 120.634983 -145.151279) (xy 120.667897 -145.17243) (xy 132.637528 -145.17243) (xy 132.641599 -145.116808)
			(xy 132.653725 -145.062371) (xy 132.673648 -145.01028) (xy 132.700944 -144.961645) (xy 132.73503 -144.917502)
			(xy 132.775179 -144.878793) (xy 132.820537 -144.846342) (xy 132.870137 -144.820841) (xy 132.922921 -144.802834)
			(xy 132.977764 -144.792704) (xy 133.033498 -144.790667) (xy 133.088935 -144.796767) (xy 133.142892 -144.810873)
			(xy 133.194221 -144.832685) (xy 133.241827 -144.861739) (xy 133.284695 -144.897414) (xy 133.321912 -144.938951)
			(xy 133.352685 -144.985464) (xy 133.376357 -145.035961) (xy 133.392425 -145.089368) (xy 133.400545 -145.144544)
			(xy 133.401054 -145.17243) (xy 133.400545 -145.200316) (xy 133.392425 -145.255492) (xy 133.376357 -145.308899)
			(xy 133.352685 -145.359396) (xy 133.321912 -145.405909) (xy 133.284695 -145.447446) (xy 133.241827 -145.483121)
			(xy 133.194221 -145.512175) (xy 133.142892 -145.533987) (xy 133.088935 -145.548093) (xy 133.033498 -145.554193)
			(xy 132.977764 -145.552156) (xy 132.922921 -145.542026) (xy 132.870137 -145.524019) (xy 132.820537 -145.498518)
			(xy 132.775179 -145.466067) (xy 132.73503 -145.427358) (xy 132.700944 -145.383215) (xy 132.673648 -145.33458)
			(xy 132.653725 -145.282489) (xy 132.641599 -145.228052) (xy 132.637528 -145.17243) (xy 120.667897 -145.17243)
			(xy 120.680842 -145.180749) (xy 120.722041 -145.216445) (xy 120.757739 -145.257642) (xy 120.787211 -145.303499)
			(xy 120.809857 -145.353084) (xy 120.825215 -145.405388) (xy 120.832973 -145.459344) (xy 120.832973 -145.513856)
			(xy 120.825215 -145.567812) (xy 120.809857 -145.620116) (xy 120.787211 -145.669701) (xy 120.757739 -145.715558)
			(xy 120.722041 -145.756755) (xy 120.680842 -145.792451) (xy 120.634983 -145.821921) (xy 120.585397 -145.844564)
			(xy 120.533093 -145.859919) (xy 120.479136 -145.867674) (xy 120.45188 -145.868136) (xy 120.425658 -145.867676)
			(xy 120.373709 -145.860478) (xy 120.323236 -145.846235) (xy 120.275189 -145.825214) (xy 120.230472 -145.797811)
			(xy 120.18993 -145.764544) (xy 120.154324 -145.726038) (xy 120.124327 -145.683019) (xy 120.112028 -145.659856)
			(xy 120.105383 -145.647931) (xy 120.086976 -145.62779) (xy 120.063896 -145.613235) (xy 120.037789 -145.605305)
			(xy 120.010513 -145.604564) (xy 119.984014 -145.611065) (xy 119.960178 -145.624345) (xy 119.940705 -145.643458)
			(xy 119.933466 -145.65503) (xy 119.918692 -145.679406) (xy 119.88312 -145.723938) (xy 119.841313 -145.762676)
			(xy 119.794205 -145.794758) (xy 119.742844 -145.819468) (xy 119.688377 -145.836254) (xy 119.632018 -145.844744)
			(xy 119.60352 -145.845276) (xy 119.576264 -145.844878) (xy 119.522306 -145.837123) (xy 119.470002 -145.821768)
			(xy 119.420415 -145.799124) (xy 119.374555 -145.769654) (xy 119.333357 -145.733958) (xy 119.297658 -145.692761)
			(xy 119.268185 -145.646903) (xy 119.245539 -145.597317) (xy 119.230181 -145.545013) (xy 119.222423 -145.491056)
			(xy 108.223558 -145.491056) (xy 108.223558 -150.607268) (xy 130.928362 -150.607268) (xy 130.932433 -150.551646)
			(xy 130.944559 -150.497209) (xy 130.964482 -150.445118) (xy 130.991778 -150.396483) (xy 131.025864 -150.35234)
			(xy 131.066013 -150.313631) (xy 131.111371 -150.28118) (xy 131.160971 -150.255679) (xy 131.213755 -150.237672)
			(xy 131.268598 -150.227542) (xy 131.324332 -150.225505) (xy 131.379769 -150.231605) (xy 131.433726 -150.245711)
			(xy 131.485055 -150.267523) (xy 131.532661 -150.296577) (xy 131.575529 -150.332252) (xy 131.612746 -150.373789)
			(xy 131.643519 -150.420302) (xy 131.667191 -150.470799) (xy 131.683259 -150.524206) (xy 131.684914 -150.535454)
			(xy 131.879263 -150.535454) (xy 131.879263 -150.480946) (xy 131.887021 -150.426993) (xy 131.902379 -150.374693)
			(xy 131.925024 -150.325111) (xy 131.954495 -150.279257) (xy 131.990192 -150.238064) (xy 132.031389 -150.202371)
			(xy 132.077246 -150.172905) (xy 132.12683 -150.150265) (xy 132.179132 -150.134913) (xy 132.233086 -150.127161)
			(xy 132.26034 -150.1267) (xy 132.290242 -150.127251) (xy 132.349313 -150.136575) (xy 132.406206 -150.155004)
			(xy 132.459526 -150.182086) (xy 132.507965 -150.217157) (xy 132.550338 -150.259359) (xy 132.568442 -150.283164)
			(xy 132.577353 -150.294524) (xy 132.600181 -150.312179) (xy 132.627037 -150.32274) (xy 132.655775 -150.325365)
			(xy 132.6841 -150.319844) (xy 132.709748 -150.306618) (xy 132.730671 -150.286743) (xy 132.738368 -150.274528)
			(xy 132.753149 -150.250203) (xy 132.78874 -150.205787) (xy 132.830537 -150.167154) (xy 132.877612 -150.135163)
			(xy 132.928919 -150.110525) (xy 132.983319 -150.093787) (xy 133.039602 -150.08532) (xy 133.06806 -150.08479)
			(xy 133.095315 -150.085255) (xy 133.14927 -150.093007) (xy 133.201572 -150.108359) (xy 133.251157 -150.130999)
			(xy 133.297015 -150.160466) (xy 133.338212 -150.19616) (xy 133.37391 -150.237353) (xy 133.403381 -150.283208)
			(xy 133.426027 -150.332791) (xy 133.441385 -150.385091) (xy 133.449143 -150.439045) (xy 133.449143 -150.493555)
			(xy 133.441385 -150.547509) (xy 133.426027 -150.599809) (xy 133.403381 -150.649392) (xy 133.37391 -150.695247)
			(xy 133.338212 -150.73644) (xy 133.297015 -150.772134) (xy 133.251157 -150.801601) (xy 133.201572 -150.824241)
			(xy 133.14927 -150.839593) (xy 133.095315 -150.847345) (xy 133.06806 -150.847806) (xy 133.038159 -150.847252)
			(xy 132.979087 -150.837928) (xy 132.922194 -150.8195) (xy 132.868875 -150.792418) (xy 132.820435 -150.757348)
			(xy 132.778062 -150.715147) (xy 132.759958 -150.691342) (xy 132.751047 -150.679981) (xy 132.72822 -150.662326)
			(xy 132.701364 -150.651763) (xy 132.672625 -150.649138) (xy 132.6443 -150.65466) (xy 132.618651 -150.667887)
			(xy 132.597729 -150.687763) (xy 132.590032 -150.699978) (xy 132.575253 -150.724304) (xy 132.539662 -150.76872)
			(xy 132.497865 -150.807353) (xy 132.450789 -150.839344) (xy 132.399482 -150.863982) (xy 132.345082 -150.88072)
			(xy 132.288798 -150.889186) (xy 132.26034 -150.889716) (xy 132.233086 -150.889239) (xy 132.179132 -150.881487)
			(xy 132.12683 -150.866135) (xy 132.077246 -150.843495) (xy 132.031389 -150.814029) (xy 131.990192 -150.778336)
			(xy 131.954495 -150.737143) (xy 131.925024 -150.691289) (xy 131.902379 -150.641707) (xy 131.887021 -150.589407)
			(xy 131.879263 -150.535454) (xy 131.684914 -150.535454) (xy 131.691379 -150.579382) (xy 131.691888 -150.607268)
			(xy 131.691379 -150.635154) (xy 131.683259 -150.69033) (xy 131.667191 -150.743737) (xy 131.643519 -150.794234)
			(xy 131.612746 -150.840747) (xy 131.575529 -150.882284) (xy 131.532661 -150.917959) (xy 131.485055 -150.947013)
			(xy 131.433726 -150.968825) (xy 131.379769 -150.982931) (xy 131.324332 -150.989031) (xy 131.268598 -150.986994)
			(xy 131.213755 -150.976864) (xy 131.160971 -150.958857) (xy 131.111371 -150.933356) (xy 131.066013 -150.900905)
			(xy 131.025864 -150.862196) (xy 130.991778 -150.818053) (xy 130.964482 -150.769418) (xy 130.944559 -150.717327)
			(xy 130.932433 -150.66289) (xy 130.928362 -150.607268) (xy 108.223558 -150.607268) (xy 108.223558 -151.773128)
			(xy 119.490742 -151.773128) (xy 119.494813 -151.717506) (xy 119.506939 -151.663069) (xy 119.526862 -151.610978)
			(xy 119.554158 -151.562343) (xy 119.588244 -151.5182) (xy 119.628393 -151.479491) (xy 119.673751 -151.44704)
			(xy 119.723351 -151.421539) (xy 119.776135 -151.403532) (xy 119.830978 -151.393402) (xy 119.886712 -151.391365)
			(xy 119.942149 -151.397465) (xy 119.996106 -151.411571) (xy 120.047435 -151.433383) (xy 120.095041 -151.462437)
			(xy 120.137909 -151.498112) (xy 120.175126 -151.539649) (xy 120.205899 -151.586162) (xy 120.229571 -151.636659)
			(xy 120.245639 -151.690066) (xy 120.253759 -151.745242) (xy 120.254268 -151.773128) (xy 120.253759 -151.801014)
			(xy 120.245639 -151.85619) (xy 120.229571 -151.909597) (xy 120.205899 -151.960094) (xy 120.175126 -152.006607)
			(xy 120.137909 -152.048144) (xy 120.095041 -152.083819) (xy 120.047435 -152.112873) (xy 119.996106 -152.134685)
			(xy 119.942149 -152.148791) (xy 119.886712 -152.154891) (xy 119.830978 -152.152854) (xy 119.776135 -152.142724)
			(xy 119.723351 -152.124717) (xy 119.673751 -152.099216) (xy 119.628393 -152.066765) (xy 119.588244 -152.028056)
			(xy 119.554158 -151.983913) (xy 119.526862 -151.935278) (xy 119.506939 -151.883187) (xy 119.494813 -151.82875)
			(xy 119.490742 -151.773128) (xy 108.223558 -151.773128) (xy 108.223558 -152.430988) (xy 118.269002 -152.430988)
			(xy 118.273073 -152.375366) (xy 118.285199 -152.320929) (xy 118.305122 -152.268838) (xy 118.332418 -152.220203)
			(xy 118.366504 -152.17606) (xy 118.406653 -152.137351) (xy 118.452011 -152.1049) (xy 118.501611 -152.079399)
			(xy 118.554395 -152.061392) (xy 118.609238 -152.051262) (xy 118.664972 -152.049225) (xy 118.720409 -152.055325)
			(xy 118.774366 -152.069431) (xy 118.825695 -152.091243) (xy 118.873301 -152.120297) (xy 118.916169 -152.155972)
			(xy 118.953386 -152.197509) (xy 118.984159 -152.244022) (xy 119.007831 -152.294519) (xy 119.023899 -152.347926)
			(xy 119.032019 -152.403102) (xy 119.032528 -152.430988) (xy 119.032019 -152.458874) (xy 119.023899 -152.51405)
			(xy 119.007831 -152.567457) (xy 118.984159 -152.617954) (xy 118.953386 -152.664467) (xy 118.916169 -152.706004)
			(xy 118.873301 -152.741679) (xy 118.825695 -152.770733) (xy 118.774366 -152.792545) (xy 118.720409 -152.806651)
			(xy 118.664972 -152.812751) (xy 118.609238 -152.810714) (xy 118.554395 -152.800584) (xy 118.501611 -152.782577)
			(xy 118.452011 -152.757076) (xy 118.406653 -152.724625) (xy 118.366504 -152.685916) (xy 118.332418 -152.641773)
			(xy 118.305122 -152.593138) (xy 118.285199 -152.541047) (xy 118.273073 -152.48661) (xy 118.269002 -152.430988)
			(xy 108.223558 -152.430988) (xy 108.223558 -152.892506) (xy 108.27766 -152.946608) (xy 119.749822 -152.946608)
			(xy 119.753893 -152.890986) (xy 119.766019 -152.836549) (xy 119.785942 -152.784458) (xy 119.813238 -152.735823)
			(xy 119.847324 -152.69168) (xy 119.887473 -152.652971) (xy 119.932831 -152.62052) (xy 119.982431 -152.595019)
			(xy 120.035215 -152.577012) (xy 120.090058 -152.566882) (xy 120.145792 -152.564845) (xy 120.201229 -152.570945)
			(xy 120.255186 -152.585051) (xy 120.306515 -152.606863) (xy 120.354121 -152.635917) (xy 120.396989 -152.671592)
			(xy 120.434206 -152.713129) (xy 120.464979 -152.759642) (xy 120.488651 -152.810139) (xy 120.504719 -152.863546)
			(xy 120.512839 -152.918722) (xy 120.513348 -152.946608) (xy 120.512839 -152.974494) (xy 120.504719 -153.02967)
			(xy 120.488651 -153.083077) (xy 120.464979 -153.133574) (xy 120.455919 -153.147268) (xy 121.159522 -153.147268)
			(xy 121.163593 -153.091646) (xy 121.175719 -153.037209) (xy 121.195642 -152.985118) (xy 121.222938 -152.936483)
			(xy 121.257024 -152.89234) (xy 121.297173 -152.853631) (xy 121.342531 -152.82118) (xy 121.392131 -152.795679)
			(xy 121.444915 -152.777672) (xy 121.499758 -152.767542) (xy 121.555492 -152.765505) (xy 121.610929 -152.771605)
			(xy 121.664886 -152.785711) (xy 121.716215 -152.807523) (xy 121.763821 -152.836577) (xy 121.806689 -152.872252)
			(xy 121.843906 -152.913789) (xy 121.874679 -152.960302) (xy 121.898351 -153.010799) (xy 121.914419 -153.064206)
			(xy 121.922539 -153.119382) (xy 121.923048 -153.147268) (xy 121.922539 -153.175154) (xy 121.914419 -153.23033)
			(xy 121.898351 -153.283737) (xy 121.874679 -153.334234) (xy 121.843906 -153.380747) (xy 121.806689 -153.422284)
			(xy 121.763821 -153.457959) (xy 121.716215 -153.487013) (xy 121.664886 -153.508825) (xy 121.610929 -153.522931)
			(xy 121.555492 -153.529031) (xy 121.499758 -153.526994) (xy 121.444915 -153.516864) (xy 121.392131 -153.498857)
			(xy 121.342531 -153.473356) (xy 121.297173 -153.440905) (xy 121.257024 -153.402196) (xy 121.222938 -153.358053)
			(xy 121.195642 -153.309418) (xy 121.175719 -153.257327) (xy 121.163593 -153.20289) (xy 121.159522 -153.147268)
			(xy 120.455919 -153.147268) (xy 120.434206 -153.180087) (xy 120.396989 -153.221624) (xy 120.354121 -153.257299)
			(xy 120.306515 -153.286353) (xy 120.255186 -153.308165) (xy 120.201229 -153.322271) (xy 120.145792 -153.328371)
			(xy 120.090058 -153.326334) (xy 120.035215 -153.316204) (xy 119.982431 -153.298197) (xy 119.932831 -153.272696)
			(xy 119.887473 -153.240245) (xy 119.847324 -153.201536) (xy 119.813238 -153.157393) (xy 119.785942 -153.108758)
			(xy 119.766019 -153.056667) (xy 119.753893 -153.00223) (xy 119.749822 -152.946608) (xy 108.27766 -152.946608)
			(xy 109.5121 -154.181048) (xy 122.244102 -154.181048) (xy 122.248173 -154.125426) (xy 122.260299 -154.070989)
			(xy 122.280222 -154.018898) (xy 122.307518 -153.970263) (xy 122.341604 -153.92612) (xy 122.381753 -153.887411)
			(xy 122.427111 -153.85496) (xy 122.476711 -153.829459) (xy 122.529495 -153.811452) (xy 122.584338 -153.801322)
			(xy 122.640072 -153.799285) (xy 122.695509 -153.805385) (xy 122.749466 -153.819491) (xy 122.800795 -153.841303)
			(xy 122.848401 -153.870357) (xy 122.891269 -153.906032) (xy 122.928486 -153.947569) (xy 122.959259 -153.994082)
			(xy 122.982931 -154.044579) (xy 122.998999 -154.097986) (xy 123.007119 -154.153162) (xy 123.007628 -154.181048)
			(xy 123.007373 -154.195018) (xy 125.732298 -154.195018) (xy 125.736264 -154.110487) (xy 125.748129 -154.0267)
			(xy 125.767787 -153.944391) (xy 125.795067 -153.864285) (xy 125.829728 -153.787086) (xy 125.871466 -153.713471)
			(xy 125.919913 -153.644088) (xy 125.974645 -153.579547) (xy 126.035181 -153.520415) (xy 126.100987 -153.467211)
			(xy 126.171487 -153.420403) (xy 126.246059 -153.380402) (xy 126.32405 -153.34756) (xy 126.404774 -153.322166)
			(xy 126.487521 -153.304443) (xy 126.571563 -153.294545) (xy 126.656164 -153.292562) (xy 126.740578 -153.298509)
			(xy 126.824065 -153.312334) (xy 126.90589 -153.333917) (xy 126.985334 -153.363067) (xy 127.0617 -153.399528)
			(xy 127.134316 -153.44298) (xy 127.202544 -153.493041) (xy 127.265784 -153.549271) (xy 127.323481 -153.611176)
			(xy 127.375128 -153.678212) (xy 127.42027 -153.749789) (xy 127.458512 -153.825279) (xy 127.489516 -153.904018)
			(xy 127.513011 -153.985315) (xy 127.52879 -154.068454) (xy 127.536714 -154.152706) (xy 127.53721 -154.195018)
			(xy 128.272298 -154.195018) (xy 128.276264 -154.110487) (xy 128.288129 -154.0267) (xy 128.307787 -153.944391)
			(xy 128.335067 -153.864285) (xy 128.369728 -153.787086) (xy 128.411466 -153.713471) (xy 128.459913 -153.644088)
			(xy 128.514645 -153.579547) (xy 128.575181 -153.520415) (xy 128.640987 -153.467211) (xy 128.711487 -153.420403)
			(xy 128.786059 -153.380402) (xy 128.86405 -153.34756) (xy 128.944774 -153.322166) (xy 129.027521 -153.304443)
			(xy 129.111563 -153.294545) (xy 129.196164 -153.292562) (xy 129.280578 -153.298509) (xy 129.364065 -153.312334)
			(xy 129.44589 -153.333917) (xy 129.525334 -153.363067) (xy 129.6017 -153.399528) (xy 129.674316 -153.44298)
			(xy 129.742544 -153.493041) (xy 129.805784 -153.549271) (xy 129.863481 -153.611176) (xy 129.915128 -153.678212)
			(xy 129.96027 -153.749789) (xy 129.998512 -153.825279) (xy 130.029516 -153.904018) (xy 130.053011 -153.985315)
			(xy 130.06879 -154.068454) (xy 130.076714 -154.152706) (xy 130.07721 -154.195018) (xy 130.812298 -154.195018)
			(xy 130.816264 -154.110487) (xy 130.828129 -154.0267) (xy 130.847787 -153.944391) (xy 130.875067 -153.864285)
			(xy 130.909728 -153.787086) (xy 130.951466 -153.713471) (xy 130.999913 -153.644088) (xy 131.054645 -153.579547)
			(xy 131.115181 -153.520415) (xy 131.180987 -153.467211) (xy 131.251487 -153.420403) (xy 131.326059 -153.380402)
			(xy 131.40405 -153.34756) (xy 131.484774 -153.322166) (xy 131.567521 -153.304443) (xy 131.651563 -153.294545)
			(xy 131.736164 -153.292562) (xy 131.820578 -153.298509) (xy 131.904065 -153.312334) (xy 131.98589 -153.333917)
			(xy 132.065334 -153.363067) (xy 132.1417 -153.399528) (xy 132.214316 -153.44298) (xy 132.282544 -153.493041)
			(xy 132.345784 -153.549271) (xy 132.403481 -153.611176) (xy 132.455128 -153.678212) (xy 132.50027 -153.749789)
			(xy 132.538512 -153.825279) (xy 132.569516 -153.904018) (xy 132.593011 -153.985315) (xy 132.60879 -154.068454)
			(xy 132.616714 -154.152706) (xy 132.61721 -154.195018) (xy 132.616714 -154.23733) (xy 132.60879 -154.321582)
			(xy 132.593011 -154.404721) (xy 132.569516 -154.486018) (xy 132.538512 -154.564757) (xy 132.50027 -154.640247)
			(xy 132.455128 -154.711824) (xy 132.403481 -154.77886) (xy 132.345784 -154.840765) (xy 132.282544 -154.896995)
			(xy 132.214316 -154.947056) (xy 132.1417 -154.990508) (xy 132.065334 -155.026969) (xy 131.98589 -155.056119)
			(xy 131.904065 -155.077702) (xy 131.820578 -155.091527) (xy 131.736164 -155.097474) (xy 131.651563 -155.095491)
			(xy 131.567521 -155.085593) (xy 131.484774 -155.06787) (xy 131.40405 -155.042476) (xy 131.326059 -155.009634)
			(xy 131.251487 -154.969633) (xy 131.180987 -154.922825) (xy 131.115181 -154.869621) (xy 131.054645 -154.810489)
			(xy 130.999913 -154.745948) (xy 130.951466 -154.676565) (xy 130.909728 -154.60295) (xy 130.875067 -154.525751)
			(xy 130.847787 -154.445645) (xy 130.828129 -154.363336) (xy 130.816264 -154.279549) (xy 130.812298 -154.195018)
			(xy 130.07721 -154.195018) (xy 130.076714 -154.23733) (xy 130.06879 -154.321582) (xy 130.053011 -154.404721)
			(xy 130.029516 -154.486018) (xy 129.998512 -154.564757) (xy 129.96027 -154.640247) (xy 129.915128 -154.711824)
			(xy 129.863481 -154.77886) (xy 129.805784 -154.840765) (xy 129.742544 -154.896995) (xy 129.674316 -154.947056)
			(xy 129.6017 -154.990508) (xy 129.525334 -155.026969) (xy 129.44589 -155.056119) (xy 129.364065 -155.077702)
			(xy 129.280578 -155.091527) (xy 129.196164 -155.097474) (xy 129.111563 -155.095491) (xy 129.027521 -155.085593)
			(xy 128.944774 -155.06787) (xy 128.86405 -155.042476) (xy 128.786059 -155.009634) (xy 128.711487 -154.969633)
			(xy 128.640987 -154.922825) (xy 128.575181 -154.869621) (xy 128.514645 -154.810489) (xy 128.459913 -154.745948)
			(xy 128.411466 -154.676565) (xy 128.369728 -154.60295) (xy 128.335067 -154.525751) (xy 128.307787 -154.445645)
			(xy 128.288129 -154.363336) (xy 128.276264 -154.279549) (xy 128.272298 -154.195018) (xy 127.53721 -154.195018)
			(xy 127.536714 -154.23733) (xy 127.52879 -154.321582) (xy 127.513011 -154.404721) (xy 127.489516 -154.486018)
			(xy 127.458512 -154.564757) (xy 127.42027 -154.640247) (xy 127.375128 -154.711824) (xy 127.323481 -154.77886)
			(xy 127.265784 -154.840765) (xy 127.202544 -154.896995) (xy 127.134316 -154.947056) (xy 127.0617 -154.990508)
			(xy 126.985334 -155.026969) (xy 126.90589 -155.056119) (xy 126.824065 -155.077702) (xy 126.740578 -155.091527)
			(xy 126.656164 -155.097474) (xy 126.571563 -155.095491) (xy 126.487521 -155.085593) (xy 126.404774 -155.06787)
			(xy 126.32405 -155.042476) (xy 126.246059 -155.009634) (xy 126.171487 -154.969633) (xy 126.100987 -154.922825)
			(xy 126.035181 -154.869621) (xy 125.974645 -154.810489) (xy 125.919913 -154.745948) (xy 125.871466 -154.676565)
			(xy 125.829728 -154.60295) (xy 125.795067 -154.525751) (xy 125.767787 -154.445645) (xy 125.748129 -154.363336)
			(xy 125.736264 -154.279549) (xy 125.732298 -154.195018) (xy 123.007373 -154.195018) (xy 123.007119 -154.208934)
			(xy 122.998999 -154.26411) (xy 122.982931 -154.317517) (xy 122.959259 -154.368014) (xy 122.928486 -154.414527)
			(xy 122.891269 -154.456064) (xy 122.848401 -154.491739) (xy 122.800795 -154.520793) (xy 122.749466 -154.542605)
			(xy 122.695509 -154.556711) (xy 122.640072 -154.562811) (xy 122.584338 -154.560774) (xy 122.529495 -154.550644)
			(xy 122.476711 -154.532637) (xy 122.427111 -154.507136) (xy 122.381753 -154.474685) (xy 122.341604 -154.435976)
			(xy 122.307518 -154.391833) (xy 122.280222 -154.343198) (xy 122.260299 -154.291107) (xy 122.248173 -154.23667)
			(xy 122.244102 -154.181048) (xy 109.5121 -154.181048) (xy 111.72952 -156.398468) (xy 129.926332 -156.398468)
			(xy 129.930403 -156.342846) (xy 129.942529 -156.288409) (xy 129.962452 -156.236318) (xy 129.989748 -156.187683)
			(xy 130.023834 -156.14354) (xy 130.063983 -156.104831) (xy 130.109341 -156.07238) (xy 130.158941 -156.046879)
			(xy 130.211725 -156.028872) (xy 130.266568 -156.018742) (xy 130.322302 -156.016705) (xy 130.377739 -156.022805)
			(xy 130.431696 -156.036911) (xy 130.483025 -156.058723) (xy 130.530631 -156.087777) (xy 130.573499 -156.123452)
			(xy 130.610716 -156.164989) (xy 130.641489 -156.211502) (xy 130.665161 -156.261999) (xy 130.681229 -156.315406)
			(xy 130.689349 -156.370582) (xy 130.689858 -156.398468) (xy 130.689349 -156.426354) (xy 130.681229 -156.48153)
			(xy 130.665161 -156.534937) (xy 130.641489 -156.585434) (xy 130.610716 -156.631947) (xy 130.573499 -156.673484)
			(xy 130.530631 -156.709159) (xy 130.483025 -156.738213) (xy 130.431696 -156.760025) (xy 130.377739 -156.774131)
			(xy 130.322302 -156.780231) (xy 130.266568 -156.778194) (xy 130.211725 -156.768064) (xy 130.158941 -156.750057)
			(xy 130.109341 -156.724556) (xy 130.063983 -156.692105) (xy 130.023834 -156.653396) (xy 129.989748 -156.609253)
			(xy 129.962452 -156.560618) (xy 129.942529 -156.508527) (xy 129.930403 -156.45409) (xy 129.926332 -156.398468)
			(xy 111.72952 -156.398468) (xy 112.9538 -157.622748) (xy 133.1722 -157.622748)
		)
		(stroke
			(width 0)
			(type solid)
		)
		(fill yes)
		(layer "In11.Cu")
		(net "P3V3_AUX")
	)
	(gr_poly
		(pts
			(xy 436.78475 -34.635948) (xy 436.798648 -34.635469) (xy 436.825412 -34.62796) (xy 436.849159 -34.613513)
			(xy 436.868131 -34.593198) (xy 436.880923 -34.568519) (xy 436.886586 -34.541305) (xy 436.8847 -34.513572)
			(xy 436.880508 -34.500312) (xy 436.870296 -34.469496) (xy 436.859313 -34.405516) (xy 436.858664 -34.373058)
			(xy 436.85915 -34.345807) (xy 436.866906 -34.291859) (xy 436.882261 -34.239564) (xy 436.904903 -34.189987)
			(xy 436.934369 -34.144137) (xy 436.97006 -34.102946) (xy 437.011251 -34.067255) (xy 437.057101 -34.037789)
			(xy 437.106678 -34.015147) (xy 437.158973 -33.999792) (xy 437.212921 -33.992036) (xy 437.267423 -33.992036)
			(xy 437.321371 -33.999792) (xy 437.373666 -34.015147) (xy 437.423243 -34.037789) (xy 437.469093 -34.067255)
			(xy 437.510284 -34.102946) (xy 437.545975 -34.144137) (xy 437.575441 -34.189987) (xy 437.598083 -34.239564)
			(xy 437.613438 -34.291859) (xy 437.621194 -34.345807) (xy 437.62168 -34.373058) (xy 437.621024 -34.405515)
			(xy 437.610035 -34.469492) (xy 437.599836 -34.500312) (xy 437.595574 -34.513566) (xy 437.593663 -34.541332)
			(xy 437.599315 -34.568583) (xy 437.612112 -34.593298) (xy 437.631103 -34.613643) (xy 437.65488 -34.628108)
			(xy 437.681678 -34.63562) (xy 437.695594 -34.635948) (xy 456.74788 -34.635948) (xy 459.66888 -31.714948)
			(xy 459.66888 -23.506938) (xy 459.646099 -23.408037) (xy 459.60723 -23.208815) (xy 459.576061 -23.008244)
			(xy 459.552639 -22.806621) (xy 459.536998 -22.604246) (xy 459.529161 -22.401419) (xy 459.528672 -22.29993)
			(xy 459.529176 -22.198441) (xy 459.537021 -21.995615) (xy 459.552666 -21.793241) (xy 459.576088 -21.591619)
			(xy 459.607252 -21.391048) (xy 459.646112 -21.191825) (xy 459.66888 -21.092922) (xy 459.66888 -15.331948)
			(xy 459.004162 -14.66723) (xy 458.993748 -14.66342) (xy 458.96991 -14.654124) (xy 458.924963 -14.629678)
			(xy 458.883977 -14.599053) (xy 458.847795 -14.562877) (xy 458.817161 -14.521897) (xy 458.792706 -14.476955)
			(xy 458.783436 -14.453108) (xy 458.779626 -14.442694) (xy 457.76388 -13.426948) (xy 457.557124 -13.426948)
			(xy 457.546456 -13.463778) (xy 457.538466 -13.489991) (xy 457.516013 -13.53998) (xy 457.486638 -13.586241)
			(xy 457.450947 -13.627824) (xy 457.409672 -13.663871) (xy 457.363665 -13.693642) (xy 457.313871 -13.716523)
			(xy 457.261315 -13.732044) (xy 457.20708 -13.739885) (xy 457.15228 -13.739885) (xy 457.098045 -13.732044)
			(xy 457.045489 -13.716523) (xy 456.995695 -13.693642) (xy 456.949688 -13.663871) (xy 456.908413 -13.627824)
			(xy 456.872722 -13.586241) (xy 456.843347 -13.53998) (xy 456.820894 -13.489991) (xy 456.812904 -13.463778)
			(xy 456.802236 -13.426948) (xy 452.9455 -13.426948) (xy 452.93117 -13.427435) (xy 452.903638 -13.435395)
			(xy 452.8794 -13.450687) (xy 452.860362 -13.47211) (xy 452.848023 -13.497977) (xy 452.843352 -13.526253)
			(xy 452.846719 -13.554714) (xy 452.857857 -13.581121) (xy 452.866506 -13.592556) (xy 452.882614 -13.613058)
			(xy 452.909707 -13.657604) (xy 452.930483 -13.705424) (xy 452.944555 -13.755627) (xy 452.951661 -13.807279)
			(xy 452.952104 -13.833348) (xy 452.951618 -13.860599) (xy 452.943862 -13.914547) (xy 452.928507 -13.966842)
			(xy 452.905865 -14.016419) (xy 452.876399 -14.062269) (xy 452.840708 -14.10346) (xy 452.799517 -14.139151)
			(xy 452.753667 -14.168617) (xy 452.70409 -14.191259) (xy 452.651795 -14.206614) (xy 452.597847 -14.21437)
			(xy 452.543345 -14.21437) (xy 452.489397 -14.206614) (xy 452.437102 -14.191259) (xy 452.387525 -14.168617)
			(xy 452.341675 -14.139151) (xy 452.300484 -14.10346) (xy 452.264793 -14.062269) (xy 452.235327 -14.016419)
			(xy 452.212685 -13.966842) (xy 452.19733 -13.914547) (xy 452.189574 -13.860599) (xy 452.189088 -13.833348)
			(xy 452.18951 -13.807277) (xy 452.196607 -13.755619) (xy 452.210674 -13.70541) (xy 452.23145 -13.657585)
			(xy 452.258548 -13.613036) (xy 452.274686 -13.592556) (xy 452.283329 -13.581119) (xy 452.294477 -13.554723)
			(xy 452.29785 -13.526268) (xy 452.293181 -13.497997) (xy 452.280839 -13.472138) (xy 452.261796 -13.450727)
			(xy 452.237553 -13.435453) (xy 452.21002 -13.427518) (xy 452.195692 -13.426948) (xy 451.761352 -13.426948)
			(xy 451.74669 -13.42744) (xy 451.718577 -13.435786) (xy 451.693996 -13.451778) (xy 451.674972 -13.474096)
			(xy 451.663075 -13.500899) (xy 451.659285 -13.529979) (xy 451.661022 -13.54455) (xy 451.66327 -13.559498)
			(xy 451.665684 -13.589633) (xy 451.665848 -13.604748) (xy 451.665362 -13.631999) (xy 451.657606 -13.685947)
			(xy 451.642251 -13.738242) (xy 451.619609 -13.787819) (xy 451.590143 -13.833669) (xy 451.554452 -13.87486)
			(xy 451.513261 -13.910551) (xy 451.467411 -13.940017) (xy 451.417834 -13.962659) (xy 451.365539 -13.978014)
			(xy 451.311591 -13.98577) (xy 451.257089 -13.98577) (xy 451.203141 -13.978014) (xy 451.150846 -13.962659)
			(xy 451.101269 -13.940017) (xy 451.055419 -13.910551) (xy 451.014228 -13.87486) (xy 450.978537 -13.833669)
			(xy 450.949071 -13.787819) (xy 450.926429 -13.738242) (xy 450.911074 -13.685947) (xy 450.903318 -13.631999)
			(xy 450.902832 -13.604748) (xy 450.902992 -13.589633) (xy 450.90541 -13.559498) (xy 450.907658 -13.54455)
			(xy 450.909497 -13.529981) (xy 450.905703 -13.500875) (xy 450.893794 -13.474047) (xy 450.87475 -13.45171)
			(xy 450.850144 -13.435706) (xy 450.822004 -13.427356) (xy 450.807328 -13.426948) (xy 450.501766 -13.426948)
			(xy 450.486555 -13.427504) (xy 450.457477 -13.436446) (xy 450.432324 -13.453556) (xy 450.413326 -13.477317)
			(xy 450.402171 -13.505619) (xy 450.399847 -13.535952) (xy 450.402706 -13.5509) (xy 450.407104 -13.571704)
			(xy 450.41181 -13.613966) (xy 450.412104 -13.635228) (xy 450.411618 -13.662479) (xy 450.403862 -13.716427)
			(xy 450.388507 -13.768722) (xy 450.365865 -13.818299) (xy 450.336399 -13.864149) (xy 450.300708 -13.90534)
			(xy 450.259517 -13.941031) (xy 450.213667 -13.970497) (xy 450.16409 -13.993139) (xy 450.111795 -14.008494)
			(xy 450.057847 -14.01625) (xy 450.003345 -14.01625) (xy 449.949397 -14.008494) (xy 449.897102 -13.993139)
			(xy 449.847525 -13.970497) (xy 449.801675 -13.941031) (xy 449.760484 -13.90534) (xy 449.724793 -13.864149)
			(xy 449.695327 -13.818299) (xy 449.672685 -13.768722) (xy 449.65733 -13.716427) (xy 449.649574 -13.662479)
			(xy 449.649088 -13.635228) (xy 449.649365 -13.613965) (xy 449.654076 -13.571702) (xy 449.658486 -13.5509)
			(xy 449.661273 -13.535952) (xy 449.658927 -13.505652) (xy 449.647769 -13.477384) (xy 449.628788 -13.45365)
			(xy 449.603664 -13.436552) (xy 449.574621 -13.427603) (xy 449.559426 -13.426948) (xy 449.35648 -13.426948)
			(xy 449.342803 -13.427383) (xy 449.31643 -13.434644) (xy 449.292942 -13.448663) (xy 449.274032 -13.468428)
			(xy 449.261067 -13.492514) (xy 449.254981 -13.519182) (xy 449.255134 -13.532866) (xy 449.255388 -13.548868)
			(xy 449.254902 -13.576119) (xy 449.247146 -13.630067) (xy 449.231791 -13.682362) (xy 449.209149 -13.731939)
			(xy 449.179683 -13.777789) (xy 449.143992 -13.81898) (xy 449.102801 -13.854671) (xy 449.056951 -13.884137)
			(xy 449.007374 -13.906779) (xy 448.955079 -13.922134) (xy 448.901131 -13.92989) (xy 448.846629 -13.92989)
			(xy 448.792681 -13.922134) (xy 448.740386 -13.906779) (xy 448.690809 -13.884137) (xy 448.644959 -13.854671)
			(xy 448.603768 -13.81898) (xy 448.568077 -13.777789) (xy 448.538611 -13.731939) (xy 448.515969 -13.682362)
			(xy 448.500614 -13.630067) (xy 448.492858 -13.576119) (xy 448.492372 -13.548868) (xy 448.492626 -13.532866)
			(xy 448.492759 -13.51919) (xy 448.486623 -13.492548) (xy 448.473643 -13.468486) (xy 448.454748 -13.448727)
			(xy 448.43129 -13.434684) (xy 448.404949 -13.427363) (xy 448.39128 -13.426948) (xy 448.21856 -13.426948)
			(xy 448.205242 -13.427349) (xy 448.179516 -13.434253) (xy 448.156454 -13.447581) (xy 448.137627 -13.466424)
			(xy 448.124319 -13.489498) (xy 448.117437 -13.51523) (xy 448.11696 -13.528548) (xy 448.116474 -13.555799)
			(xy 448.108718 -13.609747) (xy 448.093363 -13.662042) (xy 448.070721 -13.711619) (xy 448.041255 -13.757469)
			(xy 448.005564 -13.79866) (xy 447.964373 -13.834351) (xy 447.918523 -13.863817) (xy 447.868946 -13.886459)
			(xy 447.816651 -13.901814) (xy 447.762703 -13.90957) (xy 447.708201 -13.90957) (xy 447.654253 -13.901814)
			(xy 447.601958 -13.886459) (xy 447.552381 -13.863817) (xy 447.506531 -13.834351) (xy 447.46534 -13.79866)
			(xy 447.429649 -13.757469) (xy 447.400183 -13.711619) (xy 447.377541 -13.662042) (xy 447.362186 -13.609747)
			(xy 447.35443 -13.555799) (xy 447.353944 -13.528548) (xy 447.353555 -13.515218) (xy 447.346667 -13.489463)
			(xy 447.333347 -13.466369) (xy 447.314504 -13.447509) (xy 447.291422 -13.434169) (xy 447.265674 -13.427257)
			(xy 447.252344 -13.426948) (xy 440.50458 -13.426948) (xy 440.492388 -13.460476) (xy 440.481921 -13.487713)
			(xy 440.45391 -13.538898) (xy 440.418432 -13.585221) (xy 440.376314 -13.625602) (xy 440.32854 -13.659099)
			(xy 440.276222 -13.684932) (xy 440.220581 -13.702499) (xy 440.162914 -13.711388) (xy 440.13374 -13.711936)
			(xy 440.105038 -13.711413) (xy 440.048284 -13.702805) (xy 439.993459 -13.685791) (xy 439.941802 -13.660756)
			(xy 439.894478 -13.628265) (xy 439.873136 -13.609066) (xy 439.863215 -13.600336) (xy 439.839954 -13.587812)
			(xy 439.814259 -13.581677) (xy 439.787849 -13.582342) (xy 439.762495 -13.589761) (xy 439.739893 -13.603438)
			(xy 439.730388 -13.612622) (xy 439.71236 -13.630789) (xy 439.67228 -13.662618) (xy 439.628302 -13.688799)
			(xy 439.581216 -13.70886) (xy 439.53187 -13.72244) (xy 439.48115 -13.729296) (xy 439.45556 -13.729716)
			(xy 439.428098 -13.729237) (xy 439.37374 -13.721363) (xy 439.321071 -13.705784) (xy 439.271177 -13.68282)
			(xy 439.225087 -13.652946) (xy 439.2041 -13.635228) (xy 439.192576 -13.625783) (xy 439.165485 -13.61341)
			(xy 439.135976 -13.609388) (xy 439.106562 -13.614059) (xy 439.079751 -13.627027) (xy 439.068464 -13.636752)
			(xy 439.047236 -13.655564) (xy 439.000256 -13.687342) (xy 438.949085 -13.711808) (xy 438.894854 -13.728419)
			(xy 438.838759 -13.73681) (xy 438.8104 -13.737336) (xy 438.78316 -13.736851) (xy 438.729235 -13.729102)
			(xy 438.67696 -13.71376) (xy 438.627398 -13.691139) (xy 438.581559 -13.661698) (xy 438.540373 -13.626036)
			(xy 438.504679 -13.584878) (xy 438.475203 -13.539062) (xy 438.452543 -13.489518) (xy 438.444386 -13.463524)
			(xy 438.433718 -13.426948) (xy 437.82488 -13.426948) (xy 435.25313 -15.998698) (xy 450.297804 -15.998698)
			(xy 450.298267 -15.971123) (xy 450.30622 -15.91655) (xy 450.321945 -15.86369) (xy 450.345116 -15.813644)
			(xy 450.375249 -15.767455) (xy 450.411717 -15.726084) (xy 450.432424 -15.707868) (xy 450.443321 -15.69797)
			(xy 450.459389 -15.673319) (xy 450.46777 -15.645112) (xy 450.467769 -15.615686) (xy 450.459388 -15.587479)
			(xy 450.443319 -15.562828) (xy 450.432424 -15.552928) (xy 450.411728 -15.5347) (xy 450.375256 -15.493336)
			(xy 450.345121 -15.447149) (xy 450.321952 -15.397105) (xy 450.306233 -15.344245) (xy 450.298291 -15.289672)
			(xy 450.297804 -15.262098) (xy 450.29829 -15.234847) (xy 450.306046 -15.180899) (xy 450.321401 -15.128604)
			(xy 450.344043 -15.079027) (xy 450.373509 -15.033177) (xy 450.4092 -14.991986) (xy 450.450391 -14.956295)
			(xy 450.496241 -14.926829) (xy 450.545818 -14.904187) (xy 450.598113 -14.888832) (xy 450.652061 -14.881076)
			(xy 450.706563 -14.881076) (xy 450.760511 -14.888832) (xy 450.812806 -14.904187) (xy 450.862383 -14.926829)
			(xy 450.908233 -14.956295) (xy 450.949424 -14.991986) (xy 450.985115 -15.033177) (xy 451.014581 -15.079027)
			(xy 451.037223 -15.128604) (xy 451.052578 -15.180899) (xy 451.060334 -15.234847) (xy 451.06082 -15.262098)
			(xy 451.060346 -15.289672) (xy 451.052394 -15.344244) (xy 451.03667 -15.397104) (xy 451.013502 -15.44715)
			(xy 450.983371 -15.493339) (xy 450.946906 -15.534711) (xy 450.9262 -15.552928) (xy 450.915305 -15.562829)
			(xy 450.899233 -15.587479) (xy 450.890849 -15.615685) (xy 450.890849 -15.645112) (xy 450.899232 -15.673319)
			(xy 450.915304 -15.697969) (xy 450.9262 -15.707868) (xy 450.946899 -15.726092) (xy 450.98337 -15.767458)
			(xy 451.013504 -15.813646) (xy 451.036672 -15.863691) (xy 451.052391 -15.916551) (xy 451.060333 -15.971124)
			(xy 451.06082 -15.998698) (xy 451.060334 -16.025949) (xy 451.052578 -16.079897) (xy 451.037223 -16.132192)
			(xy 451.014581 -16.181769) (xy 450.985115 -16.227619) (xy 450.949424 -16.26881) (xy 450.908233 -16.304501)
			(xy 450.862383 -16.333967) (xy 450.812806 -16.356609) (xy 450.760511 -16.371964) (xy 450.706563 -16.37972)
			(xy 450.652061 -16.37972) (xy 450.598113 -16.371964) (xy 450.545818 -16.356609) (xy 450.496241 -16.333967)
			(xy 450.450391 -16.304501) (xy 450.4092 -16.26881) (xy 450.373509 -16.227619) (xy 450.344043 -16.181769)
			(xy 450.321401 -16.132192) (xy 450.306046 -16.079897) (xy 450.29829 -16.025949) (xy 450.297804 -15.998698)
			(xy 435.25313 -15.998698) (xy 434.90388 -16.347948) (xy 434.90388 -17.265142) (xy 434.919224 -17.287748)
			(xy 435.704232 -17.287748) (xy 435.708303 -17.232126) (xy 435.720429 -17.177689) (xy 435.740352 -17.125598)
			(xy 435.767648 -17.076963) (xy 435.801734 -17.03282) (xy 435.841883 -16.994111) (xy 435.887241 -16.96166)
			(xy 435.936841 -16.936159) (xy 435.989625 -16.918152) (xy 436.044468 -16.908022) (xy 436.100202 -16.905985)
			(xy 436.155639 -16.912085) (xy 436.209596 -16.926191) (xy 436.260925 -16.948003) (xy 436.308531 -16.977057)
			(xy 436.351399 -17.012732) (xy 436.388616 -17.054269) (xy 436.419389 -17.100782) (xy 436.443061 -17.151279)
			(xy 436.459129 -17.204686) (xy 436.467249 -17.259862) (xy 436.467758 -17.287748) (xy 436.725312 -17.287748)
			(xy 436.729383 -17.232126) (xy 436.741509 -17.177689) (xy 436.761432 -17.125598) (xy 436.788728 -17.076963)
			(xy 436.822814 -17.03282) (xy 436.862963 -16.994111) (xy 436.908321 -16.96166) (xy 436.957921 -16.936159)
			(xy 437.010705 -16.918152) (xy 437.065548 -16.908022) (xy 437.121282 -16.905985) (xy 437.176719 -16.912085)
			(xy 437.230676 -16.926191) (xy 437.282005 -16.948003) (xy 437.329611 -16.977057) (xy 437.372479 -17.012732)
			(xy 437.409696 -17.054269) (xy 437.440469 -17.100782) (xy 437.464141 -17.151279) (xy 437.480209 -17.204686)
			(xy 437.488329 -17.259862) (xy 437.488374 -17.262348) (xy 437.849262 -17.262348) (xy 437.853333 -17.206726)
			(xy 437.865459 -17.152289) (xy 437.885382 -17.100198) (xy 437.912678 -17.051563) (xy 437.946764 -17.00742)
			(xy 437.986913 -16.968711) (xy 438.032271 -16.93626) (xy 438.081871 -16.910759) (xy 438.134655 -16.892752)
			(xy 438.189498 -16.882622) (xy 438.245232 -16.880585) (xy 438.300669 -16.886685) (xy 438.354626 -16.900791)
			(xy 438.405955 -16.922603) (xy 438.453561 -16.951657) (xy 438.496429 -16.987332) (xy 438.533646 -17.028869)
			(xy 438.564419 -17.075382) (xy 438.588091 -17.125879) (xy 438.604159 -17.179286) (xy 438.612279 -17.234462)
			(xy 438.612788 -17.262348) (xy 438.612279 -17.290234) (xy 438.604159 -17.34541) (xy 438.588091 -17.398817)
			(xy 438.564419 -17.449314) (xy 438.533646 -17.495827) (xy 438.496429 -17.537364) (xy 438.453561 -17.573039)
			(xy 438.405955 -17.602093) (xy 438.354626 -17.623905) (xy 438.300669 -17.638011) (xy 438.245232 -17.644111)
			(xy 438.189498 -17.642074) (xy 438.134655 -17.631944) (xy 438.081871 -17.613937) (xy 438.032271 -17.588436)
			(xy 437.986913 -17.555985) (xy 437.946764 -17.517276) (xy 437.912678 -17.473133) (xy 437.885382 -17.424498)
			(xy 437.865459 -17.372407) (xy 437.853333 -17.31797) (xy 437.849262 -17.262348) (xy 437.488374 -17.262348)
			(xy 437.488838 -17.287748) (xy 437.488329 -17.315634) (xy 437.480209 -17.37081) (xy 437.464141 -17.424217)
			(xy 437.440469 -17.474714) (xy 437.409696 -17.521227) (xy 437.372479 -17.562764) (xy 437.329611 -17.598439)
			(xy 437.282005 -17.627493) (xy 437.230676 -17.649305) (xy 437.176719 -17.663411) (xy 437.121282 -17.669511)
			(xy 437.065548 -17.667474) (xy 437.010705 -17.657344) (xy 436.957921 -17.639337) (xy 436.908321 -17.613836)
			(xy 436.862963 -17.581385) (xy 436.822814 -17.542676) (xy 436.788728 -17.498533) (xy 436.761432 -17.449898)
			(xy 436.741509 -17.397807) (xy 436.729383 -17.34337) (xy 436.725312 -17.287748) (xy 436.467758 -17.287748)
			(xy 436.467249 -17.315634) (xy 436.459129 -17.37081) (xy 436.443061 -17.424217) (xy 436.419389 -17.474714)
			(xy 436.388616 -17.521227) (xy 436.351399 -17.562764) (xy 436.308531 -17.598439) (xy 436.260925 -17.627493)
			(xy 436.209596 -17.649305) (xy 436.155639 -17.663411) (xy 436.100202 -17.669511) (xy 436.044468 -17.667474)
			(xy 435.989625 -17.657344) (xy 435.936841 -17.639337) (xy 435.887241 -17.613836) (xy 435.841883 -17.581385)
			(xy 435.801734 -17.542676) (xy 435.767648 -17.498533) (xy 435.740352 -17.449898) (xy 435.720429 -17.397807)
			(xy 435.708303 -17.34337) (xy 435.704232 -17.287748) (xy 434.919224 -17.287748) (xy 435.487826 -18.12544)
			(xy 435.511132 -18.160533) (xy 435.552372 -18.233999) (xy 435.587216 -18.310706) (xy 435.615411 -18.390097)
			(xy 435.636754 -18.471599) (xy 435.65109 -18.55462) (xy 435.658314 -18.638559) (xy 435.658768 -18.680684)
			(xy 435.658768 -19.00682) (xy 441.796424 -19.00682) (xy 441.796896 -18.97945) (xy 441.804711 -18.925271)
			(xy 441.820199 -18.872768) (xy 441.843039 -18.823021) (xy 441.872763 -18.777054) (xy 441.890404 -18.756122)
			(xy 441.899621 -18.74478) (xy 441.911801 -18.718228) (xy 441.915977 -18.689315) (xy 441.911809 -18.660401)
			(xy 441.899638 -18.633845) (xy 441.890404 -18.622518) (xy 441.872761 -18.601589) (xy 441.843049 -18.555616)
			(xy 441.820214 -18.505867) (xy 441.804724 -18.453366) (xy 441.796897 -18.399189) (xy 441.796424 -18.37182)
			(xy 441.79691 -18.344569) (xy 441.804666 -18.290621) (xy 441.820021 -18.238326) (xy 441.842663 -18.188749)
			(xy 441.872129 -18.142899) (xy 441.90782 -18.101708) (xy 441.949011 -18.066017) (xy 441.994861 -18.036551)
			(xy 442.044438 -18.013909) (xy 442.096733 -17.998554) (xy 442.150681 -17.990798) (xy 442.205183 -17.990798)
			(xy 442.259131 -17.998554) (xy 442.311426 -18.013909) (xy 442.361003 -18.036551) (xy 442.406853 -18.066017)
			(xy 442.448044 -18.101708) (xy 442.483735 -18.142899) (xy 442.513201 -18.188749) (xy 442.535843 -18.238326)
			(xy 442.551198 -18.290621) (xy 442.558954 -18.344569) (xy 442.55944 -18.37182) (xy 442.559 -18.399191)
			(xy 442.552207 -18.446242) (xy 446.165984 -18.446242) (xy 446.170055 -18.39062) (xy 446.182181 -18.336183)
			(xy 446.202104 -18.284092) (xy 446.2294 -18.235457) (xy 446.263486 -18.191314) (xy 446.303635 -18.152605)
			(xy 446.348993 -18.120154) (xy 446.398593 -18.094653) (xy 446.451377 -18.076646) (xy 446.50622 -18.066516)
			(xy 446.561954 -18.064479) (xy 446.617391 -18.070579) (xy 446.671348 -18.084685) (xy 446.722677 -18.106497)
			(xy 446.770283 -18.135551) (xy 446.813151 -18.171226) (xy 446.850368 -18.212763) (xy 446.881141 -18.259276)
			(xy 446.904813 -18.309773) (xy 446.920881 -18.36318) (xy 446.929001 -18.418356) (xy 446.92951 -18.446242)
			(xy 446.929195 -18.463514) (xy 449.291454 -18.463514) (xy 449.295525 -18.407892) (xy 449.307651 -18.353455)
			(xy 449.327574 -18.301364) (xy 449.35487 -18.252729) (xy 449.388956 -18.208586) (xy 449.429105 -18.169877)
			(xy 449.474463 -18.137426) (xy 449.524063 -18.111925) (xy 449.576847 -18.093918) (xy 449.63169 -18.083788)
			(xy 449.687424 -18.081751) (xy 449.742861 -18.087851) (xy 449.796818 -18.101957) (xy 449.848147 -18.123769)
			(xy 449.895753 -18.152823) (xy 449.938621 -18.188498) (xy 449.975838 -18.230035) (xy 450.006611 -18.276548)
			(xy 450.030283 -18.327045) (xy 450.046351 -18.380452) (xy 450.054471 -18.435628) (xy 450.05498 -18.463514)
			(xy 450.054471 -18.4914) (xy 450.046351 -18.546576) (xy 450.030283 -18.599983) (xy 450.018171 -18.62582)
			(xy 450.615302 -18.62582) (xy 450.619373 -18.570198) (xy 450.631499 -18.515761) (xy 450.651422 -18.46367)
			(xy 450.678718 -18.415035) (xy 450.712804 -18.370892) (xy 450.752953 -18.332183) (xy 450.798311 -18.299732)
			(xy 450.847911 -18.274231) (xy 450.900695 -18.256224) (xy 450.955538 -18.246094) (xy 451.011272 -18.244057)
			(xy 451.066709 -18.250157) (xy 451.120666 -18.264263) (xy 451.171995 -18.286075) (xy 451.219601 -18.315129)
			(xy 451.262469 -18.350804) (xy 451.299686 -18.392341) (xy 451.330459 -18.438854) (xy 451.354131 -18.489351)
			(xy 451.364392 -18.523458) (xy 451.682104 -18.523458) (xy 451.682608 -18.495885) (xy 451.690553 -18.441314)
			(xy 451.70627 -18.388454) (xy 451.729433 -18.338408) (xy 451.759559 -18.292218) (xy 451.79602 -18.250845)
			(xy 451.816724 -18.232628) (xy 451.827661 -18.222771) (xy 451.843728 -18.198108) (xy 451.852104 -18.16989)
			(xy 451.852096 -18.140456) (xy 451.843705 -18.112242) (xy 451.827625 -18.087588) (xy 451.816724 -18.077688)
			(xy 451.796009 -18.059481) (xy 451.759538 -18.018112) (xy 451.729405 -17.971922) (xy 451.70624 -17.921873)
			(xy 451.690525 -17.869009) (xy 451.682588 -17.814433) (xy 451.682104 -17.786858) (xy 451.68259 -17.759607)
			(xy 451.690346 -17.705659) (xy 451.705701 -17.653364) (xy 451.728343 -17.603787) (xy 451.757809 -17.557937)
			(xy 451.7935 -17.516746) (xy 451.834691 -17.481055) (xy 451.880541 -17.451589) (xy 451.930118 -17.428947)
			(xy 451.982413 -17.413592) (xy 452.036361 -17.405836) (xy 452.090863 -17.405836) (xy 452.144811 -17.413592)
			(xy 452.197106 -17.428947) (xy 452.246683 -17.451589) (xy 452.292533 -17.481055) (xy 452.333724 -17.516746)
			(xy 452.369415 -17.557937) (xy 452.398881 -17.603787) (xy 452.421523 -17.653364) (xy 452.436878 -17.705659)
			(xy 452.444634 -17.759607) (xy 452.44512 -17.786858) (xy 452.444618 -17.814431) (xy 452.436672 -17.869002)
			(xy 452.420954 -17.921861) (xy 452.39779 -17.971907) (xy 452.367665 -18.018098) (xy 452.331204 -18.059471)
			(xy 452.3105 -18.077688) (xy 452.299645 -18.087629) (xy 452.283572 -18.112268) (xy 452.275183 -18.140464)
			(xy 452.275176 -18.169882) (xy 452.283549 -18.198083) (xy 452.299609 -18.222729) (xy 452.3105 -18.232628)
			(xy 452.331228 -18.250821) (xy 452.367697 -18.292194) (xy 452.397827 -18.338387) (xy 452.42099 -18.388439)
			(xy 452.436703 -18.441305) (xy 452.444637 -18.495882) (xy 452.44512 -18.523458) (xy 452.444634 -18.550709)
			(xy 452.436878 -18.604657) (xy 452.421523 -18.656952) (xy 452.398881 -18.706529) (xy 452.369415 -18.752379)
			(xy 452.333724 -18.79357) (xy 452.292533 -18.829261) (xy 452.246683 -18.858727) (xy 452.197106 -18.881369)
			(xy 452.144811 -18.896724) (xy 452.090863 -18.90448) (xy 452.036361 -18.90448) (xy 451.982413 -18.896724)
			(xy 451.930118 -18.881369) (xy 451.880541 -18.858727) (xy 451.834691 -18.829261) (xy 451.7935 -18.79357)
			(xy 451.757809 -18.752379) (xy 451.728343 -18.706529) (xy 451.705701 -18.656952) (xy 451.690346 -18.604657)
			(xy 451.68259 -18.550709) (xy 451.682104 -18.523458) (xy 451.364392 -18.523458) (xy 451.370199 -18.542758)
			(xy 451.378319 -18.597934) (xy 451.378828 -18.62582) (xy 451.378319 -18.653706) (xy 451.370199 -18.708882)
			(xy 451.354131 -18.762289) (xy 451.330459 -18.812786) (xy 451.299686 -18.859299) (xy 451.262469 -18.900836)
			(xy 451.219601 -18.936511) (xy 451.171995 -18.965565) (xy 451.120666 -18.987377) (xy 451.066709 -19.001483)
			(xy 451.011272 -19.007583) (xy 450.955538 -19.005546) (xy 450.900695 -18.995416) (xy 450.847911 -18.977409)
			(xy 450.798311 -18.951908) (xy 450.752953 -18.919457) (xy 450.712804 -18.880748) (xy 450.678718 -18.836605)
			(xy 450.651422 -18.78797) (xy 450.631499 -18.735879) (xy 450.619373 -18.681442) (xy 450.615302 -18.62582)
			(xy 450.018171 -18.62582) (xy 450.006611 -18.65048) (xy 449.975838 -18.696993) (xy 449.938621 -18.73853)
			(xy 449.895753 -18.774205) (xy 449.848147 -18.803259) (xy 449.796818 -18.825071) (xy 449.742861 -18.839177)
			(xy 449.687424 -18.845277) (xy 449.63169 -18.84324) (xy 449.576847 -18.83311) (xy 449.524063 -18.815103)
			(xy 449.474463 -18.789602) (xy 449.429105 -18.757151) (xy 449.388956 -18.718442) (xy 449.35487 -18.674299)
			(xy 449.327574 -18.625664) (xy 449.307651 -18.573573) (xy 449.295525 -18.519136) (xy 449.291454 -18.463514)
			(xy 446.929195 -18.463514) (xy 446.929001 -18.474128) (xy 446.920881 -18.529304) (xy 446.904813 -18.582711)
			(xy 446.881141 -18.633208) (xy 446.850368 -18.679721) (xy 446.813151 -18.721258) (xy 446.770283 -18.756933)
			(xy 446.722677 -18.785987) (xy 446.671348 -18.807799) (xy 446.617391 -18.821905) (xy 446.561954 -18.828005)
			(xy 446.50622 -18.825968) (xy 446.451377 -18.815838) (xy 446.398593 -18.797831) (xy 446.348993 -18.77233)
			(xy 446.303635 -18.739879) (xy 446.263486 -18.70117) (xy 446.2294 -18.657027) (xy 446.202104 -18.608392)
			(xy 446.182181 -18.556301) (xy 446.170055 -18.501864) (xy 446.165984 -18.446242) (xy 442.552207 -18.446242)
			(xy 442.551178 -18.453372) (xy 442.535684 -18.505876) (xy 442.512836 -18.555623) (xy 442.483105 -18.601588)
			(xy 442.46546 -18.622518) (xy 442.456207 -18.633832) (xy 442.444037 -18.660395) (xy 442.43987 -18.689315)
			(xy 442.444046 -18.718234) (xy 442.456224 -18.744793) (xy 442.46546 -18.756122) (xy 442.48307 -18.777078)
			(xy 442.512787 -18.823043) (xy 442.53563 -18.872785) (xy 442.551127 -18.925281) (xy 442.558963 -18.979452)
			(xy 442.55944 -19.00682) (xy 442.558954 -19.034071) (xy 442.551198 -19.088019) (xy 442.535843 -19.140314)
			(xy 442.513201 -19.189891) (xy 442.483735 -19.235741) (xy 442.448044 -19.276932) (xy 442.406853 -19.312623)
			(xy 442.361003 -19.342089) (xy 442.311426 -19.364731) (xy 442.259131 -19.380086) (xy 442.205183 -19.387842)
			(xy 442.150681 -19.387842) (xy 442.096733 -19.380086) (xy 442.044438 -19.364731) (xy 441.994861 -19.342089)
			(xy 441.949011 -19.312623) (xy 441.90782 -19.276932) (xy 441.872129 -19.235741) (xy 441.842663 -19.189891)
			(xy 441.820021 -19.140314) (xy 441.804666 -19.088019) (xy 441.79691 -19.034071) (xy 441.796424 -19.00682)
			(xy 435.658768 -19.00682) (xy 435.658768 -19.304508) (xy 435.658179 -19.353069) (xy 435.64863 -19.44972)
			(xy 435.637324 -19.506438) (xy 448.687442 -19.506438) (xy 448.691513 -19.450816) (xy 448.703639 -19.396379)
			(xy 448.723562 -19.344288) (xy 448.750858 -19.295653) (xy 448.784944 -19.25151) (xy 448.825093 -19.212801)
			(xy 448.870451 -19.18035) (xy 448.920051 -19.154849) (xy 448.972835 -19.136842) (xy 449.027678 -19.126712)
			(xy 449.083412 -19.124675) (xy 449.138849 -19.130775) (xy 449.192806 -19.144881) (xy 449.244135 -19.166693)
			(xy 449.291741 -19.195747) (xy 449.334609 -19.231422) (xy 449.371826 -19.272959) (xy 449.402599 -19.319472)
			(xy 449.411916 -19.339348) (xy 453.045106 -19.339348) (xy 453.045106 -19.284852) (xy 453.052861 -19.230911)
			(xy 453.068214 -19.178623) (xy 453.090851 -19.129052) (xy 453.120312 -19.083206) (xy 453.155997 -19.04202)
			(xy 453.197181 -19.006331) (xy 453.243024 -18.976866) (xy 453.292593 -18.954225) (xy 453.34488 -18.938868)
			(xy 453.39882 -18.931108) (xy 453.426068 -18.93062) (xy 453.452759 -18.931048) (xy 453.505623 -18.938468)
			(xy 453.556937 -18.953181) (xy 453.6057 -18.9749) (xy 453.650961 -19.003203) (xy 453.671686 -19.020028)
			(xy 453.683668 -19.029415) (xy 453.711676 -19.041295) (xy 453.741941 -19.044396) (xy 453.771777 -19.038442)
			(xy 453.798534 -19.023963) (xy 453.819837 -19.002243) (xy 453.833796 -18.97521) (xy 453.83704 -18.960338)
			(xy 453.84216 -18.934245) (xy 453.858715 -18.883713) (xy 453.882129 -18.83597) (xy 453.911946 -18.791942)
			(xy 453.94759 -18.752482) (xy 453.988368 -18.718356) (xy 454.033492 -18.690223) (xy 454.082085 -18.668631)
			(xy 454.133206 -18.653996) (xy 454.185865 -18.646604) (xy 454.212452 -18.64614) (xy 454.239706 -18.6466)
			(xy 454.293659 -18.654352) (xy 454.34596 -18.669704) (xy 454.395543 -18.692345) (xy 454.441399 -18.721812)
			(xy 454.482594 -18.757506) (xy 454.518288 -18.798701) (xy 454.547755 -18.844557) (xy 454.570396 -18.89414)
			(xy 454.585748 -18.946441) (xy 454.5935 -19.000394) (xy 454.59396 -19.027648) (xy 454.593489 -19.054251)
			(xy 454.586114 -19.106944) (xy 454.571485 -19.1581) (xy 454.549886 -19.206726) (xy 454.521737 -19.251877)
			(xy 454.487586 -19.292676) (xy 454.448093 -19.328331) (xy 454.42632 -19.343624) (xy 454.41484 -19.35196)
			(xy 454.396633 -19.373702) (xy 454.385114 -19.399615) (xy 454.381172 -19.427699) (xy 454.385113 -19.455782)
			(xy 454.396632 -19.481696) (xy 454.414838 -19.503439) (xy 454.42632 -19.511772) (xy 454.448077 -19.527085)
			(xy 454.487558 -19.562747) (xy 454.521704 -19.603547) (xy 454.549852 -19.648694) (xy 454.571456 -19.697312)
			(xy 454.586099 -19.748461) (xy 454.593495 -19.801147) (xy 454.59396 -19.827748) (xy 454.593474 -19.854999)
			(xy 454.585718 -19.908947) (xy 454.570363 -19.961242) (xy 454.547721 -20.010819) (xy 454.518255 -20.056669)
			(xy 454.482564 -20.09786) (xy 454.441373 -20.133551) (xy 454.395523 -20.163017) (xy 454.345946 -20.185659)
			(xy 454.293651 -20.201014) (xy 454.239703 -20.20877) (xy 454.185201 -20.20877) (xy 454.131253 -20.201014)
			(xy 454.078958 -20.185659) (xy 454.029381 -20.163017) (xy 453.983531 -20.133551) (xy 453.94234 -20.09786)
			(xy 453.906649 -20.056669) (xy 453.877183 -20.010819) (xy 453.854541 -19.961242) (xy 453.839186 -19.908947)
			(xy 453.83143 -19.854999) (xy 453.830944 -19.827748) (xy 453.83141 -19.801144) (xy 453.838786 -19.748451)
			(xy 453.853416 -19.697295) (xy 453.875015 -19.64867) (xy 453.903165 -19.603519) (xy 453.937317 -19.56272)
			(xy 453.97681 -19.527064) (xy 453.998584 -19.511772) (xy 454.010068 -19.503441) (xy 454.028274 -19.481698)
			(xy 454.039793 -19.455783) (xy 454.043733 -19.427699) (xy 454.039792 -19.399615) (xy 454.028273 -19.3737)
			(xy 454.010066 -19.351958) (xy 453.998584 -19.343624) (xy 453.99038 -19.338018) (xy 453.974496 -19.326074)
			(xy 453.966834 -19.319748) (xy 453.954892 -19.310292) (xy 453.926864 -19.298389) (xy 453.896573 -19.295278)
			(xy 453.866711 -19.301235) (xy 453.839932 -19.31573) (xy 453.818617 -19.337476) (xy 453.80466 -19.36454)
			(xy 453.80148 -19.379438) (xy 453.796323 -19.405524) (xy 453.779772 -19.456054) (xy 453.756363 -19.503796)
			(xy 453.72655 -19.547823) (xy 453.690911 -19.587284) (xy 453.650136 -19.621411) (xy 453.605017 -19.649545)
			(xy 453.556427 -19.671139) (xy 453.505309 -19.685776) (xy 453.452654 -19.69317) (xy 453.426068 -19.693636)
			(xy 453.39882 -19.693092) (xy 453.34488 -19.685332) (xy 453.292593 -19.669975) (xy 453.243024 -19.647334)
			(xy 453.197181 -19.617869) (xy 453.155997 -19.58218) (xy 453.120312 -19.540994) (xy 453.090851 -19.495148)
			(xy 453.068214 -19.445577) (xy 453.052861 -19.393289) (xy 453.045106 -19.339348) (xy 449.411916 -19.339348)
			(xy 449.426271 -19.369969) (xy 449.442339 -19.423376) (xy 449.450459 -19.478552) (xy 449.450968 -19.506438)
			(xy 449.450459 -19.534324) (xy 449.442339 -19.5895) (xy 449.426271 -19.642907) (xy 449.402599 -19.693404)
			(xy 449.371826 -19.739917) (xy 449.334609 -19.781454) (xy 449.291741 -19.817129) (xy 449.244135 -19.846183)
			(xy 449.192806 -19.867995) (xy 449.138849 -19.882101) (xy 449.083412 -19.888201) (xy 449.027678 -19.886164)
			(xy 448.972835 -19.876034) (xy 448.920051 -19.858027) (xy 448.870451 -19.832526) (xy 448.825093 -19.800075)
			(xy 448.784944 -19.761366) (xy 448.750858 -19.717223) (xy 448.723562 -19.668588) (xy 448.703639 -19.616497)
			(xy 448.691513 -19.56206) (xy 448.687442 -19.506438) (xy 435.637324 -19.506438) (xy 435.629644 -19.544967)
			(xy 435.601404 -19.637892) (xy 435.58333 -19.682968) (xy 435.292246 -20.385532) (xy 435.275385 -20.425042)
			(xy 435.235751 -20.501261) (xy 435.189648 -20.573752) (xy 435.137424 -20.641965) (xy 435.079474 -20.705385)
			(xy 435.048152 -20.734782) (xy 434.929534 -20.843748) (xy 434.929788 -20.8661) (xy 434.929788 -20.869148)
			(xy 434.929069 -20.901088) (xy 434.927126 -20.91182) (xy 441.796424 -20.91182) (xy 441.796896 -20.88445)
			(xy 441.804711 -20.830271) (xy 441.820199 -20.777768) (xy 441.843039 -20.728021) (xy 441.872763 -20.682054)
			(xy 441.890404 -20.661122) (xy 441.899621 -20.64978) (xy 441.911801 -20.623228) (xy 441.915977 -20.594315)
			(xy 441.911809 -20.565401) (xy 441.899638 -20.538845) (xy 441.890404 -20.527518) (xy 441.872761 -20.506589)
			(xy 441.843049 -20.460616) (xy 441.820214 -20.410867) (xy 441.804724 -20.358366) (xy 441.796897 -20.304189)
			(xy 441.796424 -20.27682) (xy 441.79691 -20.249569) (xy 441.804666 -20.195621) (xy 441.820021 -20.143326)
			(xy 441.842663 -20.093749) (xy 441.872129 -20.047899) (xy 441.90782 -20.006708) (xy 441.949011 -19.971017)
			(xy 441.994861 -19.941551) (xy 442.044438 -19.918909) (xy 442.096733 -19.903554) (xy 442.150681 -19.895798)
			(xy 442.205183 -19.895798) (xy 442.259131 -19.903554) (xy 442.311426 -19.918909) (xy 442.361003 -19.941551)
			(xy 442.406853 -19.971017) (xy 442.448044 -20.006708) (xy 442.483735 -20.047899) (xy 442.513201 -20.093749)
			(xy 442.535843 -20.143326) (xy 442.551198 -20.195621) (xy 442.558954 -20.249569) (xy 442.55944 -20.27682)
			(xy 442.559 -20.304191) (xy 442.551178 -20.358372) (xy 442.535684 -20.410876) (xy 442.512836 -20.460623)
			(xy 442.483105 -20.506588) (xy 442.46546 -20.527518) (xy 442.456207 -20.538832) (xy 442.444037 -20.565395)
			(xy 442.43987 -20.594315) (xy 442.444046 -20.623234) (xy 442.456224 -20.649793) (xy 442.46546 -20.661122)
			(xy 442.48307 -20.682078) (xy 442.512787 -20.728043) (xy 442.53563 -20.777785) (xy 442.551127 -20.830281)
			(xy 442.558963 -20.884452) (xy 442.55944 -20.91182) (xy 442.558954 -20.939071) (xy 442.551198 -20.993019)
			(xy 442.535843 -21.045314) (xy 442.513201 -21.094891) (xy 442.483735 -21.140741) (xy 442.448044 -21.181932)
			(xy 442.406853 -21.217623) (xy 442.377981 -21.236178) (xy 448.479162 -21.236178) (xy 448.483233 -21.180556)
			(xy 448.495359 -21.126119) (xy 448.515282 -21.074028) (xy 448.542578 -21.025393) (xy 448.576664 -20.98125)
			(xy 448.616813 -20.942541) (xy 448.662171 -20.91009) (xy 448.711771 -20.884589) (xy 448.764555 -20.866582)
			(xy 448.819398 -20.856452) (xy 448.875132 -20.854415) (xy 448.930569 -20.860515) (xy 448.984526 -20.874621)
			(xy 449.035855 -20.896433) (xy 449.083461 -20.925487) (xy 449.126329 -20.961162) (xy 449.163546 -21.002699)
			(xy 449.194319 -21.049212) (xy 449.217991 -21.099709) (xy 449.234059 -21.153116) (xy 449.242179 -21.208292)
			(xy 449.242688 -21.236178) (xy 449.242179 -21.264064) (xy 449.234059 -21.31924) (xy 449.217991 -21.372647)
			(xy 449.194319 -21.423144) (xy 449.163546 -21.469657) (xy 449.126329 -21.511194) (xy 449.083461 -21.546869)
			(xy 449.035855 -21.575923) (xy 448.984526 -21.597735) (xy 448.930569 -21.611841) (xy 448.875132 -21.617941)
			(xy 448.819398 -21.615904) (xy 448.764555 -21.605774) (xy 448.711771 -21.587767) (xy 448.662171 -21.562266)
			(xy 448.616813 -21.529815) (xy 448.576664 -21.491106) (xy 448.542578 -21.446963) (xy 448.515282 -21.398328)
			(xy 448.495359 -21.346237) (xy 448.483233 -21.2918) (xy 448.479162 -21.236178) (xy 442.377981 -21.236178)
			(xy 442.361003 -21.247089) (xy 442.311426 -21.269731) (xy 442.259131 -21.285086) (xy 442.205183 -21.292842)
			(xy 442.150681 -21.292842) (xy 442.096733 -21.285086) (xy 442.044438 -21.269731) (xy 441.994861 -21.247089)
			(xy 441.949011 -21.217623) (xy 441.90782 -21.181932) (xy 441.872129 -21.140741) (xy 441.842663 -21.094891)
			(xy 441.820021 -21.045314) (xy 441.804666 -20.993019) (xy 441.79691 -20.939071) (xy 441.796424 -20.91182)
			(xy 434.927126 -20.91182) (xy 434.917691 -20.963946) (xy 434.907182 -20.994116) (xy 434.90388 -21.002752)
			(xy 434.90388 -21.623528) (xy 453.717152 -21.623528) (xy 453.717637 -21.595899) (xy 453.725599 -21.541219)
			(xy 453.741363 -21.488258) (xy 453.764597 -21.438123) (xy 453.794816 -21.391861) (xy 453.83139 -21.35044)
			(xy 453.873553 -21.314725) (xy 453.89673 -21.299678) (xy 453.908805 -21.291585) (xy 453.928135 -21.269892)
			(xy 453.940583 -21.243638) (xy 453.945145 -21.214942) (xy 453.941451 -21.186121) (xy 453.9298 -21.159504)
			(xy 453.92086 -21.14804) (xy 453.90395 -21.127324) (xy 453.875493 -21.082051) (xy 453.85365 -21.033242)
			(xy 453.838851 -20.981856) (xy 453.831387 -20.928905) (xy 453.830944 -20.902168) (xy 453.83143 -20.874917)
			(xy 453.839186 -20.820969) (xy 453.854541 -20.768674) (xy 453.877183 -20.719097) (xy 453.906649 -20.673247)
			(xy 453.94234 -20.632056) (xy 453.983531 -20.596365) (xy 454.029381 -20.566899) (xy 454.078958 -20.544257)
			(xy 454.131253 -20.528902) (xy 454.185201 -20.521146) (xy 454.239703 -20.521146) (xy 454.293651 -20.528902)
			(xy 454.345946 -20.544257) (xy 454.395523 -20.566899) (xy 454.441373 -20.596365) (xy 454.482564 -20.632056)
			(xy 454.518255 -20.673247) (xy 454.547721 -20.719097) (xy 454.570363 -20.768674) (xy 454.585718 -20.820969)
			(xy 454.593474 -20.874917) (xy 454.59396 -20.902168) (xy 454.593513 -20.929798) (xy 454.585549 -20.984482)
			(xy 454.569782 -21.037446) (xy 454.546543 -21.087583) (xy 454.516317 -21.133844) (xy 454.479735 -21.175263)
			(xy 454.437563 -21.210974) (xy 454.414382 -21.226018) (xy 454.402311 -21.234117) (xy 454.382979 -21.255808)
			(xy 454.370529 -21.282061) (xy 454.365967 -21.310756) (xy 454.369661 -21.339576) (xy 454.381312 -21.366193)
			(xy 454.390252 -21.377656) (xy 454.407162 -21.398372) (xy 454.435619 -21.443645) (xy 454.457462 -21.492455)
			(xy 454.472261 -21.54384) (xy 454.479725 -21.596791) (xy 454.480168 -21.623528) (xy 454.479682 -21.650779)
			(xy 454.471926 -21.704727) (xy 454.456571 -21.757022) (xy 454.433929 -21.806599) (xy 454.404463 -21.852449)
			(xy 454.368772 -21.89364) (xy 454.327581 -21.929331) (xy 454.281731 -21.958797) (xy 454.232154 -21.981439)
			(xy 454.179859 -21.996794) (xy 454.125911 -22.00455) (xy 454.071409 -22.00455) (xy 454.017461 -21.996794)
			(xy 453.965166 -21.981439) (xy 453.915589 -21.958797) (xy 453.869739 -21.929331) (xy 453.828548 -21.89364)
			(xy 453.792857 -21.852449) (xy 453.763391 -21.806599) (xy 453.740749 -21.757022) (xy 453.725394 -21.704727)
			(xy 453.717638 -21.650779) (xy 453.717152 -21.623528) (xy 434.90388 -21.623528) (xy 434.90388 -22.426422)
			(xy 450.115176 -22.426422) (xy 450.119247 -22.3708) (xy 450.131373 -22.316363) (xy 450.151296 -22.264272)
			(xy 450.178592 -22.215637) (xy 450.212678 -22.171494) (xy 450.252827 -22.132785) (xy 450.298185 -22.100334)
			(xy 450.347785 -22.074833) (xy 450.400569 -22.056826) (xy 450.455412 -22.046696) (xy 450.511146 -22.044659)
			(xy 450.566583 -22.050759) (xy 450.62054 -22.064865) (xy 450.671869 -22.086677) (xy 450.719475 -22.115731)
			(xy 450.762343 -22.151406) (xy 450.79956 -22.192943) (xy 450.830333 -22.239456) (xy 450.854005 -22.289953)
			(xy 450.870073 -22.34336) (xy 450.878193 -22.398536) (xy 450.878234 -22.400768) (xy 452.115172 -22.400768)
			(xy 452.119243 -22.345146) (xy 452.131369 -22.290709) (xy 452.151292 -22.238618) (xy 452.178588 -22.189983)
			(xy 452.212674 -22.14584) (xy 452.252823 -22.107131) (xy 452.298181 -22.07468) (xy 452.347781 -22.049179)
			(xy 452.400565 -22.031172) (xy 452.455408 -22.021042) (xy 452.511142 -22.019005) (xy 452.566579 -22.025105)
			(xy 452.620536 -22.039211) (xy 452.671865 -22.061023) (xy 452.719471 -22.090077) (xy 452.762339 -22.125752)
			(xy 452.799556 -22.167289) (xy 452.830329 -22.213802) (xy 452.854001 -22.264299) (xy 452.870069 -22.317706)
			(xy 452.878189 -22.372882) (xy 452.878698 -22.400768) (xy 452.878189 -22.428654) (xy 452.870069 -22.48383)
			(xy 452.854001 -22.537237) (xy 452.830329 -22.587734) (xy 452.799556 -22.634247) (xy 452.762339 -22.675784)
			(xy 452.719471 -22.711459) (xy 452.671865 -22.740513) (xy 452.620536 -22.762325) (xy 452.566579 -22.776431)
			(xy 452.511142 -22.782531) (xy 452.455408 -22.780494) (xy 452.400565 -22.770364) (xy 452.347781 -22.752357)
			(xy 452.298181 -22.726856) (xy 452.252823 -22.694405) (xy 452.212674 -22.655696) (xy 452.178588 -22.611553)
			(xy 452.151292 -22.562918) (xy 452.131369 -22.510827) (xy 452.119243 -22.45639) (xy 452.115172 -22.400768)
			(xy 450.878234 -22.400768) (xy 450.878702 -22.426422) (xy 450.878193 -22.454308) (xy 450.870073 -22.509484)
			(xy 450.854005 -22.562891) (xy 450.830333 -22.613388) (xy 450.79956 -22.659901) (xy 450.762343 -22.701438)
			(xy 450.719475 -22.737113) (xy 450.671869 -22.766167) (xy 450.62054 -22.787979) (xy 450.566583 -22.802085)
			(xy 450.511146 -22.808185) (xy 450.455412 -22.806148) (xy 450.400569 -22.796018) (xy 450.347785 -22.778011)
			(xy 450.298185 -22.75251) (xy 450.252827 -22.720059) (xy 450.212678 -22.68135) (xy 450.178592 -22.637207)
			(xy 450.151296 -22.588572) (xy 450.131373 -22.536481) (xy 450.119247 -22.482044) (xy 450.115176 -22.426422)
			(xy 434.90388 -22.426422) (xy 434.90388 -22.866858) (xy 446.779394 -22.866858) (xy 446.783465 -22.811236)
			(xy 446.795591 -22.756799) (xy 446.815514 -22.704708) (xy 446.84281 -22.656073) (xy 446.876896 -22.61193)
			(xy 446.917045 -22.573221) (xy 446.962403 -22.54077) (xy 447.012003 -22.515269) (xy 447.064787 -22.497262)
			(xy 447.11963 -22.487132) (xy 447.175364 -22.485095) (xy 447.230801 -22.491195) (xy 447.284758 -22.505301)
			(xy 447.336087 -22.527113) (xy 447.383693 -22.556167) (xy 447.426561 -22.591842) (xy 447.463778 -22.633379)
			(xy 447.494551 -22.679892) (xy 447.518223 -22.730389) (xy 447.534291 -22.783796) (xy 447.542411 -22.838972)
			(xy 447.54292 -22.866858) (xy 447.542411 -22.894744) (xy 447.534291 -22.94992) (xy 447.518223 -23.003327)
			(xy 447.510755 -23.019258) (xy 451.351394 -23.019258) (xy 451.355465 -22.963636) (xy 451.367591 -22.909199)
			(xy 451.387514 -22.857108) (xy 451.41481 -22.808473) (xy 451.448896 -22.76433) (xy 451.489045 -22.725621)
			(xy 451.534403 -22.69317) (xy 451.584003 -22.667669) (xy 451.636787 -22.649662) (xy 451.69163 -22.639532)
			(xy 451.747364 -22.637495) (xy 451.802801 -22.643595) (xy 451.856758 -22.657701) (xy 451.908087 -22.679513)
			(xy 451.955693 -22.708567) (xy 451.998561 -22.744242) (xy 452.035778 -22.785779) (xy 452.066551 -22.832292)
			(xy 452.090223 -22.882789) (xy 452.106291 -22.936196) (xy 452.114411 -22.991372) (xy 452.11492 -23.019258)
			(xy 452.114411 -23.047144) (xy 452.106291 -23.10232) (xy 452.090223 -23.155727) (xy 452.066551 -23.206224)
			(xy 452.035778 -23.252737) (xy 451.998561 -23.294274) (xy 451.955693 -23.329949) (xy 451.908087 -23.359003)
			(xy 451.856758 -23.380815) (xy 451.802801 -23.394921) (xy 451.747364 -23.401021) (xy 451.69163 -23.398984)
			(xy 451.636787 -23.388854) (xy 451.584003 -23.370847) (xy 451.534403 -23.345346) (xy 451.489045 -23.312895)
			(xy 451.448896 -23.274186) (xy 451.41481 -23.230043) (xy 451.387514 -23.181408) (xy 451.367591 -23.129317)
			(xy 451.355465 -23.07488) (xy 451.351394 -23.019258) (xy 447.510755 -23.019258) (xy 447.494551 -23.053824)
			(xy 447.463778 -23.100337) (xy 447.426561 -23.141874) (xy 447.383693 -23.177549) (xy 447.336087 -23.206603)
			(xy 447.284758 -23.228415) (xy 447.230801 -23.242521) (xy 447.175364 -23.248621) (xy 447.11963 -23.246584)
			(xy 447.064787 -23.236454) (xy 447.012003 -23.218447) (xy 446.962403 -23.192946) (xy 446.917045 -23.160495)
			(xy 446.876896 -23.121786) (xy 446.84281 -23.077643) (xy 446.815514 -23.029008) (xy 446.795591 -22.976917)
			(xy 446.783465 -22.92248) (xy 446.779394 -22.866858) (xy 434.90388 -22.866858) (xy 434.90388 -23.689818)
			(xy 437.315354 -23.689818) (xy 437.319425 -23.634196) (xy 437.331551 -23.579759) (xy 437.351474 -23.527668)
			(xy 437.37877 -23.479033) (xy 437.412856 -23.43489) (xy 437.453005 -23.396181) (xy 437.498363 -23.36373)
			(xy 437.547963 -23.338229) (xy 437.600747 -23.320222) (xy 437.65559 -23.310092) (xy 437.711324 -23.308055)
			(xy 437.766761 -23.314155) (xy 437.820718 -23.328261) (xy 437.872047 -23.350073) (xy 437.919653 -23.379127)
			(xy 437.962521 -23.414802) (xy 437.999738 -23.456339) (xy 438.030511 -23.502852) (xy 438.054183 -23.553349)
			(xy 438.070251 -23.606756) (xy 438.078371 -23.661932) (xy 438.07888 -23.689818) (xy 438.078371 -23.717704)
			(xy 438.070251 -23.77288) (xy 438.054183 -23.826287) (xy 438.030511 -23.876784) (xy 437.999738 -23.923297)
			(xy 437.962521 -23.964834) (xy 437.919653 -24.000509) (xy 437.872047 -24.029563) (xy 437.820718 -24.051375)
			(xy 437.766761 -24.065481) (xy 437.711324 -24.071581) (xy 437.65559 -24.069544) (xy 437.600747 -24.059414)
			(xy 437.547963 -24.041407) (xy 437.498363 -24.015906) (xy 437.453005 -23.983455) (xy 437.412856 -23.944746)
			(xy 437.37877 -23.900603) (xy 437.351474 -23.851968) (xy 437.331551 -23.799877) (xy 437.319425 -23.74544)
			(xy 437.315354 -23.689818) (xy 434.90388 -23.689818) (xy 434.90388 -25.823418) (xy 437.264554 -25.823418)
			(xy 437.268625 -25.767796) (xy 437.280751 -25.713359) (xy 437.300674 -25.661268) (xy 437.32797 -25.612633)
			(xy 437.362056 -25.56849) (xy 437.402205 -25.529781) (xy 437.447563 -25.49733) (xy 437.497163 -25.471829)
			(xy 437.549947 -25.453822) (xy 437.60479 -25.443692) (xy 437.660524 -25.441655) (xy 437.715961 -25.447755)
			(xy 437.769918 -25.461861) (xy 437.821247 -25.483673) (xy 437.868853 -25.512727) (xy 437.911721 -25.548402)
			(xy 437.948938 -25.589939) (xy 437.979711 -25.636452) (xy 438.003383 -25.686949) (xy 438.019451 -25.740356)
			(xy 438.027571 -25.795532) (xy 438.02808 -25.823418) (xy 438.027571 -25.851304) (xy 438.024386 -25.872948)
			(xy 440.745372 -25.872948) (xy 440.745911 -25.846179) (xy 440.753416 -25.793169) (xy 440.768258 -25.74173)
			(xy 440.790146 -25.69287) (xy 440.818649 -25.647549) (xy 440.853207 -25.606658) (xy 440.893142 -25.571)
			(xy 440.937671 -25.541275) (xy 440.985917 -25.518066) (xy 441.036934 -25.501829) (xy 441.08972 -25.492884)
			(xy 441.116466 -25.491694) (xy 441.130171 -25.490836) (xy 441.156404 -25.482755) (xy 441.179535 -25.467978)
			(xy 441.197895 -25.447573) (xy 441.210156 -25.423014) (xy 441.215431 -25.396077) (xy 441.21334 -25.368708)
			(xy 441.204034 -25.342885) (xy 441.196476 -25.33142) (xy 441.179919 -25.307123) (xy 441.153727 -25.254482)
			(xy 441.135917 -25.198448) (xy 441.12691 -25.140346) (xy 441.126372 -25.110948) (xy 441.126858 -25.083697)
			(xy 441.134614 -25.029749) (xy 441.149969 -24.977454) (xy 441.172611 -24.927877) (xy 441.202077 -24.882027)
			(xy 441.237768 -24.840836) (xy 441.278959 -24.805145) (xy 441.324809 -24.775679) (xy 441.374386 -24.753037)
			(xy 441.426681 -24.737682) (xy 441.480629 -24.729926) (xy 441.535131 -24.729926) (xy 441.589079 -24.737682)
			(xy 441.641374 -24.753037) (xy 441.690951 -24.775679) (xy 441.736801 -24.805145) (xy 441.777992 -24.840836)
			(xy 441.813683 -24.882027) (xy 441.843149 -24.927877) (xy 441.865791 -24.977454) (xy 441.881146 -25.029749)
			(xy 441.888902 -25.083697) (xy 441.889388 -25.110948) (xy 441.888884 -25.137719) (xy 441.881378 -25.190731)
			(xy 441.866535 -25.242174) (xy 441.844645 -25.291037) (xy 441.816139 -25.336359) (xy 441.781577 -25.377251)
			(xy 441.741637 -25.412909) (xy 441.697104 -25.442634) (xy 441.648854 -25.465841) (xy 441.597832 -25.482074)
			(xy 441.545042 -25.491014) (xy 441.518294 -25.492202) (xy 441.504588 -25.49304) (xy 441.478358 -25.501129)
			(xy 441.45523 -25.515911) (xy 441.436873 -25.536319) (xy 441.424614 -25.560878) (xy 441.419339 -25.587815)
			(xy 441.421427 -25.615185) (xy 441.430729 -25.64101) (xy 441.438284 -25.652476) (xy 441.454835 -25.676778)
			(xy 441.481029 -25.729416) (xy 441.498841 -25.785449) (xy 441.50785 -25.84355) (xy 441.508388 -25.872948)
			(xy 441.634372 -25.872948) (xy 441.634911 -25.846179) (xy 441.642416 -25.793169) (xy 441.657258 -25.74173)
			(xy 441.679146 -25.69287) (xy 441.707649 -25.647549) (xy 441.742207 -25.606658) (xy 441.782142 -25.571)
			(xy 441.826671 -25.541275) (xy 441.874917 -25.518066) (xy 441.925934 -25.501829) (xy 441.97872 -25.492884)
			(xy 442.005466 -25.491694) (xy 442.019171 -25.490836) (xy 442.045404 -25.482755) (xy 442.068535 -25.467978)
			(xy 442.086895 -25.447573) (xy 442.099156 -25.423014) (xy 442.104431 -25.396077) (xy 442.10234 -25.368708)
			(xy 442.093034 -25.342885) (xy 442.085476 -25.33142) (xy 442.068919 -25.307123) (xy 442.042727 -25.254482)
			(xy 442.024917 -25.198448) (xy 442.01591 -25.140346) (xy 442.015372 -25.110948) (xy 442.015858 -25.083697)
			(xy 442.023614 -25.029749) (xy 442.038969 -24.977454) (xy 442.061611 -24.927877) (xy 442.091077 -24.882027)
			(xy 442.126768 -24.840836) (xy 442.167959 -24.805145) (xy 442.213809 -24.775679) (xy 442.263386 -24.753037)
			(xy 442.315681 -24.737682) (xy 442.369629 -24.729926) (xy 442.424131 -24.729926) (xy 442.478079 -24.737682)
			(xy 442.530374 -24.753037) (xy 442.579951 -24.775679) (xy 442.625801 -24.805145) (xy 442.666992 -24.840836)
			(xy 442.702683 -24.882027) (xy 442.732149 -24.927877) (xy 442.754791 -24.977454) (xy 442.770146 -25.029749)
			(xy 442.777902 -25.083697) (xy 442.778388 -25.110948) (xy 442.777884 -25.137719) (xy 442.770378 -25.190731)
			(xy 442.755535 -25.242174) (xy 442.733645 -25.291037) (xy 442.705139 -25.336359) (xy 442.670577 -25.377251)
			(xy 442.630637 -25.412909) (xy 442.586104 -25.442634) (xy 442.537854 -25.465841) (xy 442.486832 -25.482074)
			(xy 442.434042 -25.491014) (xy 442.407294 -25.492202) (xy 442.393588 -25.49304) (xy 442.367358 -25.501129)
			(xy 442.34423 -25.515911) (xy 442.325873 -25.536319) (xy 442.313614 -25.560878) (xy 442.308339 -25.587815)
			(xy 442.310427 -25.615185) (xy 442.319729 -25.64101) (xy 442.327284 -25.652476) (xy 442.343835 -25.676778)
			(xy 442.370029 -25.729416) (xy 442.387841 -25.785449) (xy 442.39685 -25.84355) (xy 442.397388 -25.872948)
			(xy 442.523372 -25.872948) (xy 442.523911 -25.846179) (xy 442.531416 -25.793169) (xy 442.546258 -25.74173)
			(xy 442.568146 -25.69287) (xy 442.596649 -25.647549) (xy 442.631207 -25.606658) (xy 442.671142 -25.571)
			(xy 442.715671 -25.541275) (xy 442.763917 -25.518066) (xy 442.814934 -25.501829) (xy 442.86772 -25.492884)
			(xy 442.894466 -25.491694) (xy 442.908171 -25.490836) (xy 442.934404 -25.482755) (xy 442.957535 -25.467978)
			(xy 442.975895 -25.447573) (xy 442.988156 -25.423014) (xy 442.993431 -25.396077) (xy 442.99134 -25.368708)
			(xy 442.982034 -25.342885) (xy 442.974476 -25.33142) (xy 442.957919 -25.307123) (xy 442.931727 -25.254482)
			(xy 442.913917 -25.198448) (xy 442.90491 -25.140346) (xy 442.904372 -25.110948) (xy 442.904858 -25.083697)
			(xy 442.912614 -25.029749) (xy 442.927969 -24.977454) (xy 442.950611 -24.927877) (xy 442.980077 -24.882027)
			(xy 443.015768 -24.840836) (xy 443.056959 -24.805145) (xy 443.102809 -24.775679) (xy 443.152386 -24.753037)
			(xy 443.204681 -24.737682) (xy 443.258629 -24.729926) (xy 443.313131 -24.729926) (xy 443.313284 -24.729948)
			(xy 443.792862 -24.729948) (xy 443.796933 -24.674326) (xy 443.809059 -24.619889) (xy 443.828982 -24.567798)
			(xy 443.856278 -24.519163) (xy 443.890364 -24.47502) (xy 443.930513 -24.436311) (xy 443.975871 -24.40386)
			(xy 444.025471 -24.378359) (xy 444.078255 -24.360352) (xy 444.133098 -24.350222) (xy 444.188832 -24.348185)
			(xy 444.244269 -24.354285) (xy 444.298226 -24.368391) (xy 444.349555 -24.390203) (xy 444.397161 -24.419257)
			(xy 444.440029 -24.454932) (xy 444.477246 -24.496469) (xy 444.508019 -24.542982) (xy 444.531691 -24.593479)
			(xy 444.547759 -24.646886) (xy 444.555879 -24.702062) (xy 444.556388 -24.729948) (xy 444.555879 -24.757834)
			(xy 444.547759 -24.81301) (xy 444.531691 -24.866417) (xy 444.52839 -24.873458) (xy 451.376794 -24.873458)
			(xy 451.380865 -24.817836) (xy 451.392991 -24.763399) (xy 451.412914 -24.711308) (xy 451.44021 -24.662673)
			(xy 451.474296 -24.61853) (xy 451.514445 -24.579821) (xy 451.559803 -24.54737) (xy 451.609403 -24.521869)
			(xy 451.662187 -24.503862) (xy 451.71703 -24.493732) (xy 451.772764 -24.491695) (xy 451.828201 -24.497795)
			(xy 451.882158 -24.511901) (xy 451.933487 -24.533713) (xy 451.981093 -24.562767) (xy 452.023961 -24.598442)
			(xy 452.061178 -24.639979) (xy 452.091951 -24.686492) (xy 452.115623 -24.736989) (xy 452.131691 -24.790396)
			(xy 452.139811 -24.845572) (xy 452.14032 -24.873458) (xy 452.139811 -24.901344) (xy 452.131691 -24.95652)
			(xy 452.115623 -25.009927) (xy 452.091951 -25.060424) (xy 452.061178 -25.106937) (xy 452.023961 -25.148474)
			(xy 451.981093 -25.184149) (xy 451.933487 -25.213203) (xy 451.882158 -25.235015) (xy 451.828201 -25.249121)
			(xy 451.772764 -25.255221) (xy 451.71703 -25.253184) (xy 451.662187 -25.243054) (xy 451.609403 -25.225047)
			(xy 451.559803 -25.199546) (xy 451.514445 -25.167095) (xy 451.474296 -25.128386) (xy 451.44021 -25.084243)
			(xy 451.412914 -25.035608) (xy 451.392991 -24.983517) (xy 451.380865 -24.92908) (xy 451.376794 -24.873458)
			(xy 444.52839 -24.873458) (xy 444.508019 -24.916914) (xy 444.477246 -24.963427) (xy 444.440029 -25.004964)
			(xy 444.397161 -25.040639) (xy 444.349555 -25.069693) (xy 444.298226 -25.091505) (xy 444.244269 -25.105611)
			(xy 444.188832 -25.111711) (xy 444.133098 -25.109674) (xy 444.078255 -25.099544) (xy 444.025471 -25.081537)
			(xy 443.975871 -25.056036) (xy 443.930513 -25.023585) (xy 443.890364 -24.984876) (xy 443.856278 -24.940733)
			(xy 443.828982 -24.892098) (xy 443.809059 -24.840007) (xy 443.796933 -24.78557) (xy 443.792862 -24.729948)
			(xy 443.313284 -24.729948) (xy 443.367079 -24.737682) (xy 443.419374 -24.753037) (xy 443.468951 -24.775679)
			(xy 443.514801 -24.805145) (xy 443.555992 -24.840836) (xy 443.591683 -24.882027) (xy 443.621149 -24.927877)
			(xy 443.643791 -24.977454) (xy 443.659146 -25.029749) (xy 443.666902 -25.083697) (xy 443.667388 -25.110948)
			(xy 443.666884 -25.137719) (xy 443.659378 -25.190731) (xy 443.644535 -25.242174) (xy 443.622645 -25.291037)
			(xy 443.594139 -25.336359) (xy 443.559577 -25.377251) (xy 443.519637 -25.412909) (xy 443.475104 -25.442634)
			(xy 443.426854 -25.465841) (xy 443.375832 -25.482074) (xy 443.323042 -25.491014) (xy 443.296294 -25.492202)
			(xy 443.282588 -25.49304) (xy 443.256358 -25.501129) (xy 443.23323 -25.515911) (xy 443.214873 -25.536319)
			(xy 443.202614 -25.560878) (xy 443.197339 -25.587815) (xy 443.199427 -25.615185) (xy 443.208729 -25.64101)
			(xy 443.216284 -25.652476) (xy 443.232835 -25.676778) (xy 443.259029 -25.729416) (xy 443.276841 -25.785449)
			(xy 443.28585 -25.84355) (xy 443.286388 -25.872948) (xy 443.285902 -25.900199) (xy 443.278146 -25.954147)
			(xy 443.262791 -26.006442) (xy 443.240149 -26.056019) (xy 443.210683 -26.101869) (xy 443.174992 -26.14306)
			(xy 443.133801 -26.178751) (xy 443.087951 -26.208217) (xy 443.038374 -26.230859) (xy 442.986079 -26.246214)
			(xy 442.932131 -26.25397) (xy 442.877629 -26.25397) (xy 442.823681 -26.246214) (xy 442.771386 -26.230859)
			(xy 442.721809 -26.208217) (xy 442.675959 -26.178751) (xy 442.634768 -26.14306) (xy 442.599077 -26.101869)
			(xy 442.569611 -26.056019) (xy 442.546969 -26.006442) (xy 442.531614 -25.954147) (xy 442.523858 -25.900199)
			(xy 442.523372 -25.872948) (xy 442.397388 -25.872948) (xy 442.396902 -25.900199) (xy 442.389146 -25.954147)
			(xy 442.373791 -26.006442) (xy 442.351149 -26.056019) (xy 442.321683 -26.101869) (xy 442.285992 -26.14306)
			(xy 442.244801 -26.178751) (xy 442.198951 -26.208217) (xy 442.149374 -26.230859) (xy 442.097079 -26.246214)
			(xy 442.043131 -26.25397) (xy 441.988629 -26.25397) (xy 441.934681 -26.246214) (xy 441.882386 -26.230859)
			(xy 441.832809 -26.208217) (xy 441.786959 -26.178751) (xy 441.745768 -26.14306) (xy 441.710077 -26.101869)
			(xy 441.680611 -26.056019) (xy 441.657969 -26.006442) (xy 441.642614 -25.954147) (xy 441.634858 -25.900199)
			(xy 441.634372 -25.872948) (xy 441.508388 -25.872948) (xy 441.507902 -25.900199) (xy 441.500146 -25.954147)
			(xy 441.484791 -26.006442) (xy 441.462149 -26.056019) (xy 441.432683 -26.101869) (xy 441.396992 -26.14306)
			(xy 441.355801 -26.178751) (xy 441.309951 -26.208217) (xy 441.260374 -26.230859) (xy 441.208079 -26.246214)
			(xy 441.154131 -26.25397) (xy 441.099629 -26.25397) (xy 441.045681 -26.246214) (xy 440.993386 -26.230859)
			(xy 440.943809 -26.208217) (xy 440.897959 -26.178751) (xy 440.856768 -26.14306) (xy 440.821077 -26.101869)
			(xy 440.791611 -26.056019) (xy 440.768969 -26.006442) (xy 440.753614 -25.954147) (xy 440.745858 -25.900199)
			(xy 440.745372 -25.872948) (xy 438.024386 -25.872948) (xy 438.019451 -25.90648) (xy 438.003383 -25.959887)
			(xy 437.979711 -26.010384) (xy 437.948938 -26.056897) (xy 437.911721 -26.098434) (xy 437.868853 -26.134109)
			(xy 437.821247 -26.163163) (xy 437.769918 -26.184975) (xy 437.715961 -26.199081) (xy 437.660524 -26.205181)
			(xy 437.60479 -26.203144) (xy 437.549947 -26.193014) (xy 437.497163 -26.175007) (xy 437.447563 -26.149506)
			(xy 437.402205 -26.117055) (xy 437.362056 -26.078346) (xy 437.32797 -26.034203) (xy 437.300674 -25.985568)
			(xy 437.280751 -25.933477) (xy 437.268625 -25.87904) (xy 437.264554 -25.823418) (xy 434.90388 -25.823418)
			(xy 434.90388 -26.983556) (xy 446.780313 -26.983556) (xy 446.780313 -26.929044) (xy 446.788071 -26.875086)
			(xy 446.803429 -26.822781) (xy 446.826075 -26.773195) (xy 446.855548 -26.727336) (xy 446.891247 -26.686138)
			(xy 446.932445 -26.650441) (xy 446.978305 -26.62097) (xy 447.027892 -26.598325) (xy 447.080197 -26.582969)
			(xy 447.134156 -26.575212) (xy 447.161412 -26.57475) (xy 447.18867 -26.575219) (xy 447.24263 -26.582987)
			(xy 447.294937 -26.598351) (xy 447.344526 -26.620998) (xy 447.390392 -26.650466) (xy 447.4316 -26.686158)
			(xy 447.467313 -26.727348) (xy 447.482468 -26.75001) (xy 447.490749 -26.761937) (xy 447.512685 -26.780941)
			(xy 447.539085 -26.792996) (xy 447.567812 -26.797126) (xy 447.596539 -26.792996) (xy 447.622939 -26.780941)
			(xy 447.644875 -26.761937) (xy 447.653156 -26.75001) (xy 447.668315 -26.727351) (xy 447.704021 -26.686155)
			(xy 447.745226 -26.650459) (xy 447.791091 -26.620989) (xy 447.840683 -26.598347) (xy 447.892992 -26.582991)
			(xy 447.946954 -26.575235) (xy 447.974212 -26.57475) (xy 448.00146 -26.575321) (xy 448.0554 -26.583078)
			(xy 448.107688 -26.598432) (xy 448.157258 -26.621072) (xy 448.203102 -26.650535) (xy 448.244286 -26.686223)
			(xy 448.279972 -26.727408) (xy 448.309434 -26.773253) (xy 448.332072 -26.822824) (xy 448.347425 -26.875112)
			(xy 448.35518 -26.929052) (xy 448.35518 -26.983548) (xy 448.347425 -27.037488) (xy 448.332072 -27.089776)
			(xy 448.309434 -27.139347) (xy 448.279972 -27.185192) (xy 448.244286 -27.226377) (xy 448.203102 -27.262065)
			(xy 448.157258 -27.291528) (xy 448.107688 -27.314168) (xy 448.0554 -27.329522) (xy 448.00146 -27.337279)
			(xy 447.974212 -27.337766) (xy 447.946955 -27.337272) (xy 447.892997 -27.329506) (xy 447.840691 -27.314147)
			(xy 447.791101 -27.291504) (xy 447.745236 -27.26204) (xy 447.704027 -27.226352) (xy 447.668312 -27.185166)
			(xy 447.653156 -27.162506) (xy 447.644875 -27.150579) (xy 447.622939 -27.131575) (xy 447.596539 -27.11952)
			(xy 447.567812 -27.11539) (xy 447.539085 -27.11952) (xy 447.512685 -27.131575) (xy 447.490749 -27.150579)
			(xy 447.482468 -27.162506) (xy 447.467298 -27.185158) (xy 447.431593 -27.226353) (xy 447.39039 -27.262049)
			(xy 447.344527 -27.291519) (xy 447.294937 -27.314163) (xy 447.24263 -27.329521) (xy 447.18867 -27.337279)
			(xy 447.161412 -27.337766) (xy 447.134156 -27.337388) (xy 447.080197 -27.329631) (xy 447.027892 -27.314275)
			(xy 446.978305 -27.29163) (xy 446.932445 -27.262159) (xy 446.891247 -27.226462) (xy 446.855548 -27.185264)
			(xy 446.826075 -27.139405) (xy 446.803429 -27.089819) (xy 446.788071 -27.037514) (xy 446.780313 -26.983556)
			(xy 434.90388 -26.983556) (xy 434.90388 -27.930602) (xy 434.904324 -27.944369) (xy 434.911669 -27.970903)
			(xy 434.925851 -27.994503) (xy 434.945832 -28.013444) (xy 434.970155 -28.026344) (xy 434.997044 -28.032262)
			(xy 435.010814 -28.031948) (xy 435.03088 -28.03144) (xy 435.05813 -28.031902) (xy 435.112077 -28.039656)
			(xy 435.16437 -28.055008) (xy 435.213947 -28.077646) (xy 435.259797 -28.10711) (xy 435.300986 -28.142799)
			(xy 435.336678 -28.183987) (xy 435.366144 -28.229836) (xy 435.388785 -28.279411) (xy 435.40414 -28.331704)
			(xy 435.411897 -28.38565) (xy 435.411897 -28.44015) (xy 435.40414 -28.494096) (xy 435.388785 -28.546389)
			(xy 435.366144 -28.595964) (xy 435.352356 -28.617418) (xy 436.483504 -28.617418) (xy 436.487575 -28.561796)
			(xy 436.499701 -28.507359) (xy 436.519624 -28.455268) (xy 436.54692 -28.406633) (xy 436.581006 -28.36249)
			(xy 436.621155 -28.323781) (xy 436.666513 -28.29133) (xy 436.716113 -28.265829) (xy 436.768897 -28.247822)
			(xy 436.82374 -28.237692) (xy 436.879474 -28.235655) (xy 436.934911 -28.241755) (xy 436.988868 -28.255861)
			(xy 437.040197 -28.277673) (xy 437.087803 -28.306727) (xy 437.130671 -28.342402) (xy 437.167888 -28.383939)
			(xy 437.198661 -28.430452) (xy 437.222333 -28.480949) (xy 437.238401 -28.534356) (xy 437.246521 -28.589532)
			(xy 437.24703 -28.617418) (xy 437.246521 -28.645304) (xy 437.242102 -28.67533) (xy 438.783728 -28.67533)
			(xy 438.787799 -28.619708) (xy 438.799925 -28.565271) (xy 438.819848 -28.51318) (xy 438.847144 -28.464545)
			(xy 438.88123 -28.420402) (xy 438.921379 -28.381693) (xy 438.966737 -28.349242) (xy 439.016337 -28.323741)
			(xy 439.069121 -28.305734) (xy 439.123964 -28.295604) (xy 439.179698 -28.293567) (xy 439.235135 -28.299667)
			(xy 439.289092 -28.313773) (xy 439.340421 -28.335585) (xy 439.388027 -28.364639) (xy 439.430895 -28.400314)
			(xy 439.468112 -28.441851) (xy 439.498885 -28.488364) (xy 439.501039 -28.492958) (xy 440.846972 -28.492958)
			(xy 440.847475 -28.465637) (xy 440.855819 -28.411635) (xy 440.872304 -28.359538) (xy 440.896546 -28.310567)
			(xy 440.927975 -28.265868) (xy 440.94654 -28.245816) (xy 440.956979 -28.234228) (xy 440.970801 -28.206283)
			(xy 440.975549 -28.17547) (xy 440.970782 -28.144659) (xy 440.956944 -28.116722) (xy 440.94654 -28.1051)
			(xy 440.927942 -28.085073) (xy 440.896482 -28.040385) (xy 440.872229 -27.991409) (xy 440.855754 -27.9393)
			(xy 440.847445 -27.885284) (xy 440.846972 -27.857958) (xy 440.84747 -27.831309) (xy 440.855413 -27.778605)
			(xy 440.871123 -27.727675) (xy 440.894249 -27.679654) (xy 440.924273 -27.635617) (xy 440.960525 -27.596546)
			(xy 441.002196 -27.563315) (xy 441.048354 -27.536666) (xy 441.097968 -27.517194) (xy 441.14993 -27.505334)
			(xy 441.20308 -27.501351) (xy 441.25623 -27.505334) (xy 441.308192 -27.517194) (xy 441.357806 -27.536666)
			(xy 441.403964 -27.563315) (xy 441.445635 -27.596546) (xy 441.481887 -27.635617) (xy 441.511911 -27.679654)
			(xy 441.535037 -27.727675) (xy 441.550747 -27.778605) (xy 441.55869 -27.831309) (xy 441.559188 -27.857958)
			(xy 441.558644 -27.885278) (xy 441.550312 -27.939278) (xy 441.533837 -27.991375) (xy 441.509604 -28.040347)
			(xy 441.478182 -28.085047) (xy 441.45962 -28.1051) (xy 441.449267 -28.116757) (xy 441.435442 -28.144679)
			(xy 441.43068 -28.17547) (xy 441.435424 -28.206263) (xy 441.449232 -28.234193) (xy 441.45962 -28.245816)
			(xy 441.478236 -28.265827) (xy 441.509691 -28.310521) (xy 441.533939 -28.3595) (xy 441.55041 -28.411612)
			(xy 441.558716 -28.465631) (xy 441.559188 -28.492958) (xy 441.746894 -28.492958) (xy 441.747391 -28.465636)
			(xy 441.755735 -28.411634) (xy 441.772222 -28.359537) (xy 441.796465 -28.310566) (xy 441.827896 -28.265868)
			(xy 441.846462 -28.245816) (xy 441.856899 -28.234227) (xy 441.870718 -28.206282) (xy 441.875465 -28.17547)
			(xy 441.8707 -28.14466) (xy 441.856864 -28.116723) (xy 441.846462 -28.1051) (xy 441.827868 -28.08507)
			(xy 441.796407 -28.040383) (xy 441.772153 -27.991408) (xy 441.755677 -27.9393) (xy 441.747368 -27.885284)
			(xy 441.746894 -27.857958) (xy 441.747392 -27.831309) (xy 441.755335 -27.778605) (xy 441.771045 -27.727675)
			(xy 441.794171 -27.679654) (xy 441.824195 -27.635617) (xy 441.860447 -27.596546) (xy 441.902118 -27.563315)
			(xy 441.948276 -27.536666) (xy 441.99789 -27.517194) (xy 442.049852 -27.505334) (xy 442.103002 -27.501351)
			(xy 442.156152 -27.505334) (xy 442.208114 -27.517194) (xy 442.257728 -27.536666) (xy 442.303886 -27.563315)
			(xy 442.345557 -27.596546) (xy 442.381809 -27.635617) (xy 442.411833 -27.679654) (xy 442.434959 -27.727675)
			(xy 442.450669 -27.778605) (xy 442.458612 -27.831309) (xy 442.45911 -27.857958) (xy 442.45856 -27.885278)
			(xy 442.450229 -27.939278) (xy 442.433754 -27.991374) (xy 442.409523 -28.040346) (xy 442.378102 -28.085047)
			(xy 442.359542 -28.1051) (xy 442.349187 -28.116756) (xy 442.335359 -28.144678) (xy 442.330596 -28.17547)
			(xy 442.335341 -28.206264) (xy 442.349152 -28.234194) (xy 442.359542 -28.245816) (xy 442.378144 -28.265839)
			(xy 442.409604 -28.310528) (xy 442.433857 -28.359504) (xy 442.450331 -28.411614) (xy 442.458638 -28.465631)
			(xy 442.45911 -28.492958) (xy 442.646816 -28.492958) (xy 442.647307 -28.465636) (xy 442.655652 -28.411633)
			(xy 442.672139 -28.359536) (xy 442.696384 -28.310565) (xy 442.727817 -28.265867) (xy 442.746384 -28.245816)
			(xy 442.756819 -28.234226) (xy 442.770635 -28.206281) (xy 442.775381 -28.17547) (xy 442.770617 -28.144661)
			(xy 442.756784 -28.116724) (xy 442.746384 -28.1051) (xy 442.727777 -28.085082) (xy 442.69632 -28.04039)
			(xy 442.67207 -27.991412) (xy 442.655597 -27.939302) (xy 442.647289 -27.885285) (xy 442.646816 -27.857958)
			(xy 442.647314 -27.831309) (xy 442.655257 -27.778605) (xy 442.670967 -27.727675) (xy 442.694093 -27.679654)
			(xy 442.724117 -27.635617) (xy 442.760369 -27.596546) (xy 442.80204 -27.563315) (xy 442.848198 -27.536666)
			(xy 442.897812 -27.517194) (xy 442.949774 -27.505334) (xy 443.002924 -27.501351) (xy 443.056074 -27.505334)
			(xy 443.108036 -27.517194) (xy 443.15765 -27.536666) (xy 443.203808 -27.563315) (xy 443.245479 -27.596546)
			(xy 443.281731 -27.635617) (xy 443.311755 -27.679654) (xy 443.334881 -27.727675) (xy 443.350591 -27.778605)
			(xy 443.358534 -27.831309) (xy 443.359032 -27.857958) (xy 443.358476 -27.885277) (xy 443.350145 -27.939277)
			(xy 443.333672 -27.991373) (xy 443.309442 -28.040345) (xy 443.278023 -28.085046) (xy 443.259464 -28.1051)
			(xy 443.249107 -28.116755) (xy 443.235276 -28.144677) (xy 443.230512 -28.17547) (xy 443.235258 -28.206265)
			(xy 443.249072 -28.234195) (xy 443.259464 -28.245816) (xy 443.27807 -28.265836) (xy 443.309529 -28.310526)
			(xy 443.33378 -28.359503) (xy 443.350253 -28.411614) (xy 443.35856 -28.465631) (xy 443.359032 -28.492958)
			(xy 443.546992 -28.492958) (xy 443.547489 -28.465636) (xy 443.555834 -28.411634) (xy 443.57232 -28.359537)
			(xy 443.596563 -28.310566) (xy 443.627995 -28.265868) (xy 443.64656 -28.245816) (xy 443.656998 -28.234228)
			(xy 443.670816 -28.206282) (xy 443.675564 -28.17547) (xy 443.670798 -28.14466) (xy 443.656963 -28.116723)
			(xy 443.64656 -28.1051) (xy 443.627966 -28.08507) (xy 443.596504 -28.040383) (xy 443.57225 -27.991408)
			(xy 443.555775 -27.9393) (xy 443.547466 -27.885284) (xy 443.546992 -27.857958) (xy 443.54749 -27.831309)
			(xy 443.555433 -27.778605) (xy 443.571143 -27.727675) (xy 443.594269 -27.679654) (xy 443.624293 -27.635617)
			(xy 443.660545 -27.596546) (xy 443.702216 -27.563315) (xy 443.748374 -27.536666) (xy 443.797988 -27.517194)
			(xy 443.84995 -27.505334) (xy 443.9031 -27.501351) (xy 443.95625 -27.505334) (xy 444.008212 -27.517194)
			(xy 444.057826 -27.536666) (xy 444.103984 -27.563315) (xy 444.145655 -27.596546) (xy 444.181907 -27.635617)
			(xy 444.211931 -27.679654) (xy 444.235057 -27.727675) (xy 444.250767 -27.778605) (xy 444.25871 -27.831309)
			(xy 444.259208 -27.857958) (xy 444.258659 -27.885278) (xy 444.250327 -27.939278) (xy 444.233853 -27.991374)
			(xy 444.209621 -28.040346) (xy 444.178201 -28.085047) (xy 444.15964 -28.1051) (xy 444.149285 -28.116756)
			(xy 444.135458 -28.144678) (xy 444.130695 -28.17547) (xy 444.134607 -28.200858) (xy 445.636904 -28.200858)
			(xy 445.637401 -28.172118) (xy 445.64603 -28.11529) (xy 445.663086 -28.060398) (xy 445.688184 -28.008687)
			(xy 445.720755 -27.961326) (xy 445.740028 -27.94) (xy 445.750145 -27.928501) (xy 445.763488 -27.900943)
			(xy 445.768067 -27.870669) (xy 445.76347 -27.840398) (xy 445.75011 -27.812849) (xy 445.740028 -27.801316)
			(xy 445.720736 -27.780008) (xy 445.688173 -27.73264) (xy 445.663085 -27.680924) (xy 445.646039 -27.626029)
			(xy 445.637422 -27.569198) (xy 445.636904 -27.540458) (xy 445.63739 -27.513207) (xy 445.645146 -27.459259)
			(xy 445.660501 -27.406964) (xy 445.683143 -27.357387) (xy 445.712609 -27.311537) (xy 445.7483 -27.270346)
			(xy 445.789491 -27.234655) (xy 445.835341 -27.205189) (xy 445.884918 -27.182547) (xy 445.937213 -27.167192)
			(xy 445.991161 -27.159436) (xy 446.045663 -27.159436) (xy 446.099611 -27.167192) (xy 446.151906 -27.182547)
			(xy 446.201483 -27.205189) (xy 446.247333 -27.234655) (xy 446.288524 -27.270346) (xy 446.324215 -27.311537)
			(xy 446.353681 -27.357387) (xy 446.376323 -27.406964) (xy 446.391678 -27.459259) (xy 446.399434 -27.513207)
			(xy 446.39992 -27.540458) (xy 446.399426 -27.569198) (xy 446.390795 -27.626026) (xy 446.373738 -27.680917)
			(xy 446.34864 -27.732628) (xy 446.316069 -27.77999) (xy 446.296796 -27.801316) (xy 446.286768 -27.812884)
			(xy 446.273426 -27.840419) (xy 446.268835 -27.870669) (xy 446.273408 -27.900922) (xy 446.286733 -27.928465)
			(xy 446.296796 -27.94) (xy 446.316083 -27.961313) (xy 446.348649 -28.008678) (xy 446.37374 -28.060393)
			(xy 446.390786 -28.115287) (xy 446.399403 -28.172118) (xy 446.39992 -28.200858) (xy 446.399434 -28.228109)
			(xy 446.391678 -28.282057) (xy 446.376323 -28.334352) (xy 446.353681 -28.383929) (xy 446.324215 -28.429779)
			(xy 446.288524 -28.47097) (xy 446.247333 -28.506661) (xy 446.201483 -28.536127) (xy 446.151906 -28.558769)
			(xy 446.099611 -28.574124) (xy 446.045663 -28.58188) (xy 445.991161 -28.58188) (xy 445.937213 -28.574124)
			(xy 445.884918 -28.558769) (xy 445.835341 -28.536127) (xy 445.789491 -28.506661) (xy 445.7483 -28.47097)
			(xy 445.712609 -28.429779) (xy 445.683143 -28.383929) (xy 445.660501 -28.334352) (xy 445.645146 -28.282057)
			(xy 445.63739 -28.228109) (xy 445.636904 -28.200858) (xy 444.134607 -28.200858) (xy 444.13544 -28.206264)
			(xy 444.14925 -28.234194) (xy 444.15964 -28.245816) (xy 444.178242 -28.265839) (xy 444.209702 -28.310528)
			(xy 444.233955 -28.359504) (xy 444.250428 -28.411614) (xy 444.258736 -28.465631) (xy 444.259208 -28.492958)
			(xy 444.25871 -28.519607) (xy 444.250767 -28.572311) (xy 444.235057 -28.623241) (xy 444.211931 -28.671262)
			(xy 444.181907 -28.715299) (xy 444.145655 -28.75437) (xy 444.103984 -28.787601) (xy 444.057826 -28.81425)
			(xy 444.008212 -28.833722) (xy 443.95625 -28.845582) (xy 443.9031 -28.849566) (xy 443.84995 -28.845582)
			(xy 443.797988 -28.833722) (xy 443.748374 -28.81425) (xy 443.702216 -28.787601) (xy 443.660545 -28.75437)
			(xy 443.624293 -28.715299) (xy 443.594269 -28.671262) (xy 443.571143 -28.623241) (xy 443.555433 -28.572311)
			(xy 443.54749 -28.519607) (xy 443.546992 -28.492958) (xy 443.359032 -28.492958) (xy 443.358534 -28.519607)
			(xy 443.350591 -28.572311) (xy 443.334881 -28.623241) (xy 443.311755 -28.671262) (xy 443.281731 -28.715299)
			(xy 443.245479 -28.75437) (xy 443.203808 -28.787601) (xy 443.15765 -28.81425) (xy 443.108036 -28.833722)
			(xy 443.056074 -28.845582) (xy 443.002924 -28.849566) (xy 442.949774 -28.845582) (xy 442.897812 -28.833722)
			(xy 442.848198 -28.81425) (xy 442.80204 -28.787601) (xy 442.760369 -28.75437) (xy 442.724117 -28.715299)
			(xy 442.694093 -28.671262) (xy 442.670967 -28.623241) (xy 442.655257 -28.572311) (xy 442.647314 -28.519607)
			(xy 442.646816 -28.492958) (xy 442.45911 -28.492958) (xy 442.458612 -28.519607) (xy 442.450669 -28.572311)
			(xy 442.434959 -28.623241) (xy 442.411833 -28.671262) (xy 442.381809 -28.715299) (xy 442.345557 -28.75437)
			(xy 442.303886 -28.787601) (xy 442.257728 -28.81425) (xy 442.208114 -28.833722) (xy 442.156152 -28.845582)
			(xy 442.103002 -28.849566) (xy 442.049852 -28.845582) (xy 441.99789 -28.833722) (xy 441.948276 -28.81425)
			(xy 441.902118 -28.787601) (xy 441.860447 -28.75437) (xy 441.824195 -28.715299) (xy 441.794171 -28.671262)
			(xy 441.771045 -28.623241) (xy 441.755335 -28.572311) (xy 441.747392 -28.519607) (xy 441.746894 -28.492958)
			(xy 441.559188 -28.492958) (xy 441.55869 -28.519607) (xy 441.550747 -28.572311) (xy 441.535037 -28.623241)
			(xy 441.511911 -28.671262) (xy 441.481887 -28.715299) (xy 441.445635 -28.75437) (xy 441.403964 -28.787601)
			(xy 441.357806 -28.81425) (xy 441.308192 -28.833722) (xy 441.25623 -28.845582) (xy 441.20308 -28.849566)
			(xy 441.14993 -28.845582) (xy 441.097968 -28.833722) (xy 441.048354 -28.81425) (xy 441.002196 -28.787601)
			(xy 440.960525 -28.75437) (xy 440.924273 -28.715299) (xy 440.894249 -28.671262) (xy 440.871123 -28.623241)
			(xy 440.855413 -28.572311) (xy 440.84747 -28.519607) (xy 440.846972 -28.492958) (xy 439.501039 -28.492958)
			(xy 439.522557 -28.538861) (xy 439.538625 -28.592268) (xy 439.546745 -28.647444) (xy 439.547254 -28.67533)
			(xy 439.546745 -28.703216) (xy 439.538625 -28.758392) (xy 439.522557 -28.811799) (xy 439.498885 -28.862296)
			(xy 439.482767 -28.886658) (xy 449.015104 -28.886658) (xy 449.015548 -28.860342) (xy 449.02277 -28.808207)
			(xy 449.037085 -28.757559) (xy 449.058221 -28.709357) (xy 449.085778 -28.664515) (xy 449.119233 -28.623884)
			(xy 449.138294 -28.605734) (xy 449.148357 -28.595962) (xy 449.163053 -28.572078) (xy 449.170686 -28.545093)
			(xy 449.170678 -28.51705) (xy 449.16303 -28.49007) (xy 449.148321 -28.466194) (xy 449.138294 -28.456382)
			(xy 449.119205 -28.438257) (xy 449.085728 -28.397635) (xy 449.058159 -28.352792) (xy 449.037022 -28.304583)
			(xy 449.02272 -28.253923) (xy 449.015523 -28.201778) (xy 449.015104 -28.175458) (xy 449.015608 -28.147885)
			(xy 449.023553 -28.093314) (xy 449.03927 -28.040454) (xy 449.062433 -27.990408) (xy 449.092559 -27.944218)
			(xy 449.12902 -27.902845) (xy 449.149724 -27.884628) (xy 449.160661 -27.874771) (xy 449.176728 -27.850108)
			(xy 449.185104 -27.82189) (xy 449.185096 -27.792456) (xy 449.176705 -27.764242) (xy 449.160625 -27.739588)
			(xy 449.149724 -27.729688) (xy 449.129009 -27.711481) (xy 449.092538 -27.670112) (xy 449.062405 -27.623922)
			(xy 449.03924 -27.573873) (xy 449.023525 -27.521009) (xy 449.015588 -27.466433) (xy 449.015104 -27.438858)
			(xy 449.01559 -27.411607) (xy 449.023346 -27.357659) (xy 449.038701 -27.305364) (xy 449.061343 -27.255787)
			(xy 449.090809 -27.209937) (xy 449.1265 -27.168746) (xy 449.167691 -27.133055) (xy 449.213541 -27.103589)
			(xy 449.263118 -27.080947) (xy 449.315413 -27.065592) (xy 449.369361 -27.057836) (xy 449.423863 -27.057836)
			(xy 449.477811 -27.065592) (xy 449.530106 -27.080947) (xy 449.579683 -27.103589) (xy 449.625533 -27.133055)
			(xy 449.666724 -27.168746) (xy 449.702415 -27.209937) (xy 449.731881 -27.255787) (xy 449.754523 -27.305364)
			(xy 449.769878 -27.357659) (xy 449.777634 -27.411607) (xy 449.77812 -27.438858) (xy 449.777618 -27.466431)
			(xy 449.769672 -27.521002) (xy 449.753954 -27.573861) (xy 449.73079 -27.623907) (xy 449.700665 -27.670098)
			(xy 449.664204 -27.711471) (xy 449.6435 -27.729688) (xy 449.632645 -27.739629) (xy 449.616572 -27.764268)
			(xy 449.608183 -27.792464) (xy 449.608176 -27.821882) (xy 449.616549 -27.850083) (xy 449.632609 -27.874729)
			(xy 449.6435 -27.884628) (xy 449.664228 -27.902821) (xy 449.700697 -27.944194) (xy 449.730827 -27.990387)
			(xy 449.75399 -28.040439) (xy 449.769703 -28.093305) (xy 449.777637 -28.147882) (xy 449.77812 -28.175458)
			(xy 449.777679 -28.201774) (xy 449.770455 -28.253909) (xy 449.75614 -28.304557) (xy 449.735003 -28.352759)
			(xy 449.707446 -28.3976) (xy 449.673991 -28.438232) (xy 449.65493 -28.456382) (xy 449.64495 -28.466233)
			(xy 449.630245 -28.490093) (xy 449.6226 -28.517058) (xy 449.622592 -28.545085) (xy 449.630222 -28.572054)
			(xy 449.644913 -28.595923) (xy 449.65493 -28.605734) (xy 449.674013 -28.623866) (xy 449.707493 -28.664485)
			(xy 449.735065 -28.709326) (xy 449.756203 -28.757534) (xy 449.770506 -28.808193) (xy 449.777701 -28.860338)
			(xy 449.77812 -28.886658) (xy 449.777634 -28.913909) (xy 449.774248 -28.937458) (xy 452.799704 -28.937458)
			(xy 452.800148 -28.911142) (xy 452.80737 -28.859007) (xy 452.821685 -28.808359) (xy 452.842821 -28.760157)
			(xy 452.870378 -28.715315) (xy 452.903833 -28.674684) (xy 452.922894 -28.656534) (xy 452.932957 -28.646762)
			(xy 452.947653 -28.622878) (xy 452.955286 -28.595893) (xy 452.955278 -28.56785) (xy 452.94763 -28.54087)
			(xy 452.932921 -28.516994) (xy 452.922894 -28.507182) (xy 452.903805 -28.489057) (xy 452.870328 -28.448435)
			(xy 452.842759 -28.403592) (xy 452.821622 -28.355383) (xy 452.80732 -28.304723) (xy 452.800123 -28.252578)
			(xy 452.799704 -28.226258) (xy 452.800208 -28.198685) (xy 452.808153 -28.144114) (xy 452.82387 -28.091254)
			(xy 452.847033 -28.041208) (xy 452.877159 -27.995018) (xy 452.91362 -27.953645) (xy 452.934324 -27.935428)
			(xy 452.945261 -27.925571) (xy 452.961328 -27.900908) (xy 452.969704 -27.87269) (xy 452.969696 -27.843256)
			(xy 452.961305 -27.815042) (xy 452.945225 -27.790388) (xy 452.934324 -27.780488) (xy 452.913609 -27.762281)
			(xy 452.877138 -27.720912) (xy 452.847005 -27.674722) (xy 452.82384 -27.624673) (xy 452.808125 -27.571809)
			(xy 452.800188 -27.517233) (xy 452.799704 -27.489658) (xy 452.80019 -27.462407) (xy 452.807946 -27.408459)
			(xy 452.823301 -27.356164) (xy 452.845943 -27.306587) (xy 452.875409 -27.260737) (xy 452.9111 -27.219546)
			(xy 452.952291 -27.183855) (xy 452.998141 -27.154389) (xy 453.047718 -27.131747) (xy 453.100013 -27.116392)
			(xy 453.153961 -27.108636) (xy 453.208463 -27.108636) (xy 453.262411 -27.116392) (xy 453.314706 -27.131747)
			(xy 453.364283 -27.154389) (xy 453.410133 -27.183855) (xy 453.451324 -27.219546) (xy 453.487015 -27.260737)
			(xy 453.516481 -27.306587) (xy 453.539123 -27.356164) (xy 453.554478 -27.408459) (xy 453.562234 -27.462407)
			(xy 453.56272 -27.489658) (xy 453.562218 -27.517231) (xy 453.554272 -27.571802) (xy 453.538554 -27.624661)
			(xy 453.51539 -27.674707) (xy 453.485265 -27.720898) (xy 453.448804 -27.762271) (xy 453.4281 -27.780488)
			(xy 453.417245 -27.790429) (xy 453.401172 -27.815068) (xy 453.392783 -27.843264) (xy 453.392776 -27.872682)
			(xy 453.401149 -27.900883) (xy 453.417209 -27.925529) (xy 453.4281 -27.935428) (xy 453.448828 -27.953621)
			(xy 453.485297 -27.994994) (xy 453.515427 -28.041187) (xy 453.53859 -28.091239) (xy 453.554303 -28.144105)
			(xy 453.562237 -28.198682) (xy 453.56272 -28.226258) (xy 453.562279 -28.252574) (xy 453.555055 -28.304709)
			(xy 453.54074 -28.355357) (xy 453.519603 -28.403559) (xy 453.492046 -28.4484) (xy 453.458591 -28.489032)
			(xy 453.43953 -28.507182) (xy 453.42955 -28.517033) (xy 453.414845 -28.540893) (xy 453.4072 -28.567858)
			(xy 453.407192 -28.595885) (xy 453.414822 -28.622854) (xy 453.429513 -28.646723) (xy 453.43953 -28.656534)
			(xy 453.458613 -28.674666) (xy 453.492093 -28.715285) (xy 453.519665 -28.760126) (xy 453.540803 -28.808334)
			(xy 453.555106 -28.858993) (xy 453.562301 -28.911138) (xy 453.56272 -28.937458) (xy 453.562234 -28.964709)
			(xy 453.554478 -29.018657) (xy 453.539123 -29.070952) (xy 453.516481 -29.120529) (xy 453.487015 -29.166379)
			(xy 453.451324 -29.20757) (xy 453.410133 -29.243261) (xy 453.364283 -29.272727) (xy 453.314706 -29.295369)
			(xy 453.262411 -29.310724) (xy 453.208463 -29.31848) (xy 453.153961 -29.31848) (xy 453.100013 -29.310724)
			(xy 453.047718 -29.295369) (xy 452.998141 -29.272727) (xy 452.952291 -29.243261) (xy 452.9111 -29.20757)
			(xy 452.875409 -29.166379) (xy 452.845943 -29.120529) (xy 452.823301 -29.070952) (xy 452.807946 -29.018657)
			(xy 452.80019 -28.964709) (xy 452.799704 -28.937458) (xy 449.774248 -28.937458) (xy 449.769878 -28.967857)
			(xy 449.754523 -29.020152) (xy 449.731881 -29.069729) (xy 449.702415 -29.115579) (xy 449.666724 -29.15677)
			(xy 449.625533 -29.192461) (xy 449.579683 -29.221927) (xy 449.530106 -29.244569) (xy 449.477811 -29.259924)
			(xy 449.423863 -29.26768) (xy 449.369361 -29.26768) (xy 449.315413 -29.259924) (xy 449.263118 -29.244569)
			(xy 449.213541 -29.221927) (xy 449.167691 -29.192461) (xy 449.1265 -29.15677) (xy 449.090809 -29.115579)
			(xy 449.061343 -29.069729) (xy 449.038701 -29.020152) (xy 449.023346 -28.967857) (xy 449.01559 -28.913909)
			(xy 449.015104 -28.886658) (xy 439.482767 -28.886658) (xy 439.468112 -28.908809) (xy 439.430895 -28.950346)
			(xy 439.388027 -28.986021) (xy 439.340421 -29.015075) (xy 439.289092 -29.036887) (xy 439.235135 -29.050993)
			(xy 439.179698 -29.057093) (xy 439.123964 -29.055056) (xy 439.069121 -29.044926) (xy 439.016337 -29.026919)
			(xy 438.966737 -29.001418) (xy 438.921379 -28.968967) (xy 438.88123 -28.930258) (xy 438.847144 -28.886115)
			(xy 438.819848 -28.83748) (xy 438.799925 -28.785389) (xy 438.787799 -28.730952) (xy 438.783728 -28.67533)
			(xy 437.242102 -28.67533) (xy 437.238401 -28.70048) (xy 437.222333 -28.753887) (xy 437.198661 -28.804384)
			(xy 437.167888 -28.850897) (xy 437.130671 -28.892434) (xy 437.087803 -28.928109) (xy 437.040197 -28.957163)
			(xy 436.988868 -28.978975) (xy 436.934911 -28.993081) (xy 436.879474 -28.999181) (xy 436.82374 -28.997144)
			(xy 436.768897 -28.987014) (xy 436.716113 -28.969007) (xy 436.666513 -28.943506) (xy 436.621155 -28.911055)
			(xy 436.581006 -28.872346) (xy 436.54692 -28.828203) (xy 436.519624 -28.779568) (xy 436.499701 -28.727477)
			(xy 436.487575 -28.67304) (xy 436.483504 -28.617418) (xy 435.352356 -28.617418) (xy 435.336678 -28.641813)
			(xy 435.300986 -28.683001) (xy 435.259797 -28.71869) (xy 435.213947 -28.748154) (xy 435.16437 -28.770792)
			(xy 435.112077 -28.786144) (xy 435.05813 -28.793898) (xy 435.03088 -28.794456) (xy 435.010814 -28.793948)
			(xy 434.997049 -28.793681) (xy 434.97018 -28.79963) (xy 434.945874 -28.812535) (xy 434.925894 -28.831459)
			(xy 434.911689 -28.855029) (xy 434.90429 -28.881535) (xy 434.90388 -28.895294) (xy 434.90388 -29.454602)
			(xy 434.904411 -29.470064) (xy 434.913644 -29.499576) (xy 434.931293 -29.524968) (xy 434.955736 -29.543908)
			(xy 434.98473 -29.554658) (xy 435.000146 -29.555948) (xy 435.027675 -29.557885) (xy 435.081791 -29.568695)
			(xy 435.133784 -29.58719) (xy 435.18257 -29.612984) (xy 435.21054 -29.633418) (xy 436.483504 -29.633418)
			(xy 436.487575 -29.577796) (xy 436.499701 -29.523359) (xy 436.519624 -29.471268) (xy 436.54692 -29.422633)
			(xy 436.581006 -29.37849) (xy 436.621155 -29.339781) (xy 436.666513 -29.30733) (xy 436.716113 -29.281829)
			(xy 436.768897 -29.263822) (xy 436.82374 -29.253692) (xy 436.879474 -29.251655) (xy 436.934911 -29.257755)
			(xy 436.988868 -29.271861) (xy 437.040197 -29.293673) (xy 437.087803 -29.322727) (xy 437.130671 -29.358402)
			(xy 437.167888 -29.399939) (xy 437.198661 -29.446452) (xy 437.222333 -29.496949) (xy 437.238401 -29.550356)
			(xy 437.246521 -29.605532) (xy 437.24703 -29.633418) (xy 437.246521 -29.661304) (xy 437.238401 -29.71648)
			(xy 437.222333 -29.769887) (xy 437.198661 -29.820384) (xy 437.167888 -29.866897) (xy 437.130671 -29.908434)
			(xy 437.087803 -29.944109) (xy 437.040197 -29.973163) (xy 436.988868 -29.994975) (xy 436.948502 -30.005528)
			(xy 438.804302 -30.005528) (xy 438.808373 -29.949906) (xy 438.820499 -29.895469) (xy 438.840422 -29.843378)
			(xy 438.867718 -29.794743) (xy 438.901804 -29.7506) (xy 438.941953 -29.711891) (xy 438.987311 -29.67944)
			(xy 439.036911 -29.653939) (xy 439.089695 -29.635932) (xy 439.144538 -29.625802) (xy 439.200272 -29.623765)
			(xy 439.255709 -29.629865) (xy 439.309666 -29.643971) (xy 439.360995 -29.665783) (xy 439.377664 -29.675956)
			(xy 446.145313 -29.675956) (xy 446.145313 -29.621444) (xy 446.153071 -29.567486) (xy 446.168429 -29.515181)
			(xy 446.191075 -29.465595) (xy 446.220548 -29.419736) (xy 446.256247 -29.378538) (xy 446.297445 -29.342841)
			(xy 446.343305 -29.31337) (xy 446.392892 -29.290725) (xy 446.445197 -29.275369) (xy 446.499156 -29.267612)
			(xy 446.526412 -29.26715) (xy 446.555327 -29.267713) (xy 446.612497 -29.27643) (xy 446.667696 -29.293678)
			(xy 446.719659 -29.319061) (xy 446.767193 -29.351998) (xy 446.809211 -29.391733) (xy 446.827402 -29.414216)
			(xy 446.837299 -29.426021) (xy 446.862623 -29.44354) (xy 446.892016 -29.452716) (xy 446.922808 -29.452716)
			(xy 446.952201 -29.44354) (xy 446.977525 -29.426021) (xy 446.987422 -29.414216) (xy 447.005605 -29.391725)
			(xy 447.047626 -29.35199) (xy 447.095162 -29.319051) (xy 447.147125 -29.293664) (xy 447.202324 -29.27641)
			(xy 447.259495 -29.267683) (xy 447.288412 -29.26715) (xy 447.31566 -29.267721) (xy 447.3696 -29.275478)
			(xy 447.421888 -29.290832) (xy 447.471458 -29.313472) (xy 447.517302 -29.342935) (xy 447.558486 -29.378623)
			(xy 447.594172 -29.419808) (xy 447.623634 -29.465653) (xy 447.646272 -29.515224) (xy 447.661625 -29.567512)
			(xy 447.66938 -29.621452) (xy 447.66938 -29.675948) (xy 447.661625 -29.729888) (xy 447.646272 -29.782176)
			(xy 447.623634 -29.831747) (xy 447.594172 -29.877592) (xy 447.558486 -29.918777) (xy 447.517302 -29.954465)
			(xy 447.471458 -29.983928) (xy 447.421888 -30.006568) (xy 447.3696 -30.021922) (xy 447.31566 -30.029679)
			(xy 447.288412 -30.030166) (xy 447.259495 -30.029652) (xy 447.202323 -30.020924) (xy 447.147123 -30.003666)
			(xy 447.095161 -29.978273) (xy 447.047628 -29.945329) (xy 447.005612 -29.905586) (xy 446.987422 -29.8831)
			(xy 446.977525 -29.871295) (xy 446.952201 -29.853776) (xy 446.922808 -29.8446) (xy 446.892016 -29.8446)
			(xy 446.862623 -29.853776) (xy 446.837299 -29.871295) (xy 446.827402 -29.8831) (xy 446.80921 -29.905583)
			(xy 446.76719 -29.945318) (xy 446.719656 -29.978257) (xy 446.667695 -30.003645) (xy 446.612497 -30.020902)
			(xy 446.555328 -30.029631) (xy 446.526412 -30.030166) (xy 446.499156 -30.029788) (xy 446.445197 -30.022031)
			(xy 446.392892 -30.006675) (xy 446.343305 -29.98403) (xy 446.297445 -29.954559) (xy 446.256247 -29.918862)
			(xy 446.220548 -29.877664) (xy 446.191075 -29.831805) (xy 446.168429 -29.782219) (xy 446.153071 -29.729914)
			(xy 446.145313 -29.675956) (xy 439.377664 -29.675956) (xy 439.408601 -29.694837) (xy 439.451469 -29.730512)
			(xy 439.488686 -29.772049) (xy 439.519459 -29.818562) (xy 439.543131 -29.869059) (xy 439.559199 -29.922466)
			(xy 439.567319 -29.977642) (xy 439.567828 -30.005528) (xy 439.567319 -30.033414) (xy 439.559199 -30.08859)
			(xy 439.543131 -30.141997) (xy 439.519459 -30.192494) (xy 439.488686 -30.239007) (xy 439.451469 -30.280544)
			(xy 439.408601 -30.316219) (xy 439.360995 -30.345273) (xy 439.309666 -30.367085) (xy 439.255709 -30.381191)
			(xy 439.200272 -30.387291) (xy 439.144538 -30.385254) (xy 439.089695 -30.375124) (xy 439.036911 -30.357117)
			(xy 438.987311 -30.331616) (xy 438.941953 -30.299165) (xy 438.901804 -30.260456) (xy 438.867718 -30.216313)
			(xy 438.840422 -30.167678) (xy 438.820499 -30.115587) (xy 438.808373 -30.06115) (xy 438.804302 -30.005528)
			(xy 436.948502 -30.005528) (xy 436.934911 -30.009081) (xy 436.879474 -30.015181) (xy 436.82374 -30.013144)
			(xy 436.768897 -30.003014) (xy 436.716113 -29.985007) (xy 436.666513 -29.959506) (xy 436.621155 -29.927055)
			(xy 436.581006 -29.888346) (xy 436.54692 -29.844203) (xy 436.519624 -29.795568) (xy 436.499701 -29.743477)
			(xy 436.487575 -29.68904) (xy 436.483504 -29.633418) (xy 435.21054 -29.633418) (xy 435.22713 -29.645538)
			(xy 435.266535 -29.684173) (xy 435.299961 -29.728083) (xy 435.326712 -29.776351) (xy 435.346228 -29.82797)
			(xy 435.358103 -29.881862) (xy 435.362089 -29.936903) (xy 435.358102 -29.991943) (xy 435.346227 -30.045835)
			(xy 435.326709 -30.097454) (xy 435.299958 -30.145721) (xy 435.266531 -30.189631) (xy 435.227126 -30.228265)
			(xy 435.182566 -30.260819) (xy 435.133779 -30.286612) (xy 435.081786 -30.305106) (xy 435.02767 -30.315916)
			(xy 435.000146 -30.317948) (xy 434.984752 -30.319314) (xy 434.955805 -30.3301) (xy 434.931396 -30.349032)
			(xy 434.913749 -30.374385) (xy 434.904471 -30.40385) (xy 434.90388 -30.419294) (xy 434.90388 -30.706568)
			(xy 441.506862 -30.706568) (xy 441.510933 -30.650946) (xy 441.523059 -30.596509) (xy 441.542982 -30.544418)
			(xy 441.570278 -30.495783) (xy 441.604364 -30.45164) (xy 441.644513 -30.412931) (xy 441.689871 -30.38048)
			(xy 441.739471 -30.354979) (xy 441.792255 -30.336972) (xy 441.847098 -30.326842) (xy 441.902832 -30.324805)
			(xy 441.958269 -30.330905) (xy 442.012226 -30.345011) (xy 442.063555 -30.366823) (xy 442.111161 -30.395877)
			(xy 442.154029 -30.431552) (xy 442.191066 -30.472888) (xy 444.326262 -30.472888) (xy 444.330333 -30.417266)
			(xy 444.342459 -30.362829) (xy 444.362382 -30.310738) (xy 444.389678 -30.262103) (xy 444.423764 -30.21796)
			(xy 444.463913 -30.179251) (xy 444.509271 -30.1468) (xy 444.558871 -30.121299) (xy 444.611655 -30.103292)
			(xy 444.666498 -30.093162) (xy 444.722232 -30.091125) (xy 444.777669 -30.097225) (xy 444.831626 -30.111331)
			(xy 444.882955 -30.133143) (xy 444.930561 -30.162197) (xy 444.973429 -30.197872) (xy 445.010646 -30.239409)
			(xy 445.041419 -30.285922) (xy 445.065091 -30.336419) (xy 445.081159 -30.389826) (xy 445.089279 -30.445002)
			(xy 445.089788 -30.472888) (xy 445.089279 -30.500774) (xy 445.081159 -30.55595) (xy 445.065091 -30.609357)
			(xy 445.041419 -30.659854) (xy 445.010646 -30.706367) (xy 444.973429 -30.747904) (xy 444.930561 -30.783579)
			(xy 444.882955 -30.812633) (xy 444.831626 -30.834445) (xy 444.777669 -30.848551) (xy 444.722232 -30.854651)
			(xy 444.666498 -30.852614) (xy 444.611655 -30.842484) (xy 444.558871 -30.824477) (xy 444.509271 -30.798976)
			(xy 444.463913 -30.766525) (xy 444.423764 -30.727816) (xy 444.389678 -30.683673) (xy 444.362382 -30.635038)
			(xy 444.342459 -30.582947) (xy 444.330333 -30.52851) (xy 444.326262 -30.472888) (xy 442.191066 -30.472888)
			(xy 442.191246 -30.473089) (xy 442.222019 -30.519602) (xy 442.245691 -30.570099) (xy 442.261759 -30.623506)
			(xy 442.269879 -30.678682) (xy 442.270388 -30.706568) (xy 442.269879 -30.734454) (xy 442.261759 -30.78963)
			(xy 442.245691 -30.843037) (xy 442.222019 -30.893534) (xy 442.191246 -30.940047) (xy 442.154029 -30.981584)
			(xy 442.111161 -31.017259) (xy 442.063555 -31.046313) (xy 442.012226 -31.068125) (xy 441.958269 -31.082231)
			(xy 441.902832 -31.088331) (xy 441.847098 -31.086294) (xy 441.792255 -31.076164) (xy 441.739471 -31.058157)
			(xy 441.689871 -31.032656) (xy 441.644513 -31.000205) (xy 441.604364 -30.961496) (xy 441.570278 -30.917353)
			(xy 441.542982 -30.868718) (xy 441.523059 -30.816627) (xy 441.510933 -30.76219) (xy 441.506862 -30.706568)
			(xy 434.90388 -30.706568) (xy 434.90388 -31.229808) (xy 442.850522 -31.229808) (xy 442.854593 -31.174186)
			(xy 442.866719 -31.119749) (xy 442.886642 -31.067658) (xy 442.913938 -31.019023) (xy 442.948024 -30.97488)
			(xy 442.988173 -30.936171) (xy 443.033531 -30.90372) (xy 443.083131 -30.878219) (xy 443.135915 -30.860212)
			(xy 443.190758 -30.850082) (xy 443.246492 -30.848045) (xy 443.301929 -30.854145) (xy 443.355886 -30.868251)
			(xy 443.407215 -30.890063) (xy 443.454821 -30.919117) (xy 443.497689 -30.954792) (xy 443.534906 -30.996329)
			(xy 443.565679 -31.042842) (xy 443.589351 -31.093339) (xy 443.605419 -31.146746) (xy 443.613539 -31.201922)
			(xy 443.614048 -31.229808) (xy 443.613539 -31.257694) (xy 443.605419 -31.31287) (xy 443.589351 -31.366277)
			(xy 443.565679 -31.416774) (xy 443.534906 -31.463287) (xy 443.497689 -31.504824) (xy 443.454821 -31.540499)
			(xy 443.407215 -31.569553) (xy 443.355886 -31.591365) (xy 443.301929 -31.605471) (xy 443.246492 -31.611571)
			(xy 443.190758 -31.609534) (xy 443.135915 -31.599404) (xy 443.083131 -31.581397) (xy 443.033531 -31.555896)
			(xy 442.988173 -31.523445) (xy 442.948024 -31.484736) (xy 442.913938 -31.440593) (xy 442.886642 -31.391958)
			(xy 442.866719 -31.339867) (xy 442.854593 -31.28543) (xy 442.850522 -31.229808) (xy 434.90388 -31.229808)
			(xy 434.90388 -32.573468) (xy 446.226182 -32.573468) (xy 446.230253 -32.517846) (xy 446.242379 -32.463409)
			(xy 446.262302 -32.411318) (xy 446.289598 -32.362683) (xy 446.323684 -32.31854) (xy 446.363833 -32.279831)
			(xy 446.409191 -32.24738) (xy 446.458791 -32.221879) (xy 446.511575 -32.203872) (xy 446.566418 -32.193742)
			(xy 446.622152 -32.191705) (xy 446.677589 -32.197805) (xy 446.731546 -32.211911) (xy 446.782875 -32.233723)
			(xy 446.830481 -32.262777) (xy 446.873349 -32.298452) (xy 446.910566 -32.339989) (xy 446.941339 -32.386502)
			(xy 446.965011 -32.436999) (xy 446.981079 -32.490406) (xy 446.989199 -32.545582) (xy 446.989708 -32.573468)
			(xy 446.989199 -32.601354) (xy 446.981079 -32.65653) (xy 446.965011 -32.709937) (xy 446.941339 -32.760434)
			(xy 446.910566 -32.806947) (xy 446.873349 -32.848484) (xy 446.830481 -32.884159) (xy 446.782875 -32.913213)
			(xy 446.731546 -32.935025) (xy 446.677589 -32.949131) (xy 446.622152 -32.955231) (xy 446.566418 -32.953194)
			(xy 446.511575 -32.943064) (xy 446.458791 -32.925057) (xy 446.409191 -32.899556) (xy 446.363833 -32.867105)
			(xy 446.323684 -32.828396) (xy 446.289598 -32.784253) (xy 446.262302 -32.735618) (xy 446.242379 -32.683527)
			(xy 446.230253 -32.62909) (xy 446.226182 -32.573468) (xy 434.90388 -32.573468) (xy 434.90388 -32.800544)
			(xy 434.904357 -32.815118) (xy 434.912598 -32.843078) (xy 434.928398 -32.867574) (xy 434.95047 -32.886612)
			(xy 434.97702 -32.898645) (xy 435.005887 -32.902693) (xy 435.034722 -32.898427) (xy 435.048152 -32.892746)
			(xy 435.073346 -32.881615) (xy 435.126134 -32.8659) (xy 435.180633 -32.857936) (xy 435.208172 -32.85744)
			(xy 435.235425 -32.857901) (xy 435.289376 -32.865655) (xy 435.341675 -32.88101) (xy 435.391255 -32.903651)
			(xy 435.437109 -32.933119) (xy 435.478301 -32.968814) (xy 435.513993 -33.010007) (xy 435.543458 -33.055862)
			(xy 435.566097 -33.105444) (xy 435.581449 -33.157743) (xy 435.5892 -33.211695) (xy 435.58968 -33.238948)
			(xy 435.589227 -33.265488) (xy 435.581879 -33.318058) (xy 435.567317 -33.369102) (xy 435.545823 -33.417636)
			(xy 435.517812 -33.462724) (xy 435.483822 -33.503495) (xy 435.464458 -33.52165) (xy 435.45455 -33.531182)
			(xy 435.439786 -33.554361) (xy 435.431754 -33.580643) (xy 435.431041 -33.608115) (xy 435.437697 -33.634779)
			(xy 435.451238 -33.658693) (xy 435.460648 -33.668716) (xy 435.924198 -34.132266) (xy 435.960012 -34.097722)
			(xy 435.981469 -34.077926) (xy 436.029273 -34.044422) (xy 436.081619 -34.018585) (xy 436.137289 -34.001016)
			(xy 436.194984 -33.992126) (xy 436.224172 -33.99155) (xy 436.251426 -33.992034) (xy 436.305379 -33.999787)
			(xy 436.357679 -34.015139) (xy 436.407263 -34.037778) (xy 436.45312 -34.067243) (xy 436.494317 -34.102934)
			(xy 436.530015 -34.144124) (xy 436.559488 -34.189976) (xy 436.582136 -34.239555) (xy 436.597498 -34.291853)
			(xy 436.605261 -34.345804) (xy 436.60568 -34.373058) (xy 436.605024 -34.405515) (xy 436.594035 -34.469492)
			(xy 436.583836 -34.500312) (xy 436.579574 -34.513566) (xy 436.577663 -34.541332) (xy 436.583315 -34.568583)
			(xy 436.596112 -34.593298) (xy 436.615103 -34.613643) (xy 436.63888 -34.628108) (xy 436.665678 -34.63562)
			(xy 436.679594 -34.635948)
		)
		(stroke
			(width 0)
			(type solid)
		)
		(fill yes)
		(layer "In11.Cu")
		(net "GND")
	)
	(gr_poly
		(pts
			(xy 336.73669 -222.60052) (xy 336.749315 -222.578852) (xy 336.78009 -222.539259) (xy 336.816493 -222.504771)
			(xy 336.85769 -222.476179) (xy 336.902733 -222.454139) (xy 336.95059 -222.439159) (xy 337.000161 -222.431582)
			(xy 337.050307 -222.431582) (xy 337.099878 -222.439159) (xy 337.147735 -222.454139) (xy 337.192778 -222.476179)
			(xy 337.233975 -222.504771) (xy 337.270378 -222.539259) (xy 337.301153 -222.578852) (xy 337.313778 -222.60052)
			(xy 337.328256 -222.626428) (xy 337.662012 -222.626428) (xy 337.67649 -222.60052) (xy 337.689115 -222.578852)
			(xy 337.71989 -222.539259) (xy 337.756293 -222.504771) (xy 337.79749 -222.476179) (xy 337.842533 -222.454139)
			(xy 337.89039 -222.439159) (xy 337.939961 -222.431582) (xy 337.990107 -222.431582) (xy 338.039678 -222.439159)
			(xy 338.087535 -222.454139) (xy 338.132578 -222.476179) (xy 338.173775 -222.504771) (xy 338.210178 -222.539259)
			(xy 338.240953 -222.578852) (xy 338.253578 -222.60052) (xy 338.268056 -222.626428) (xy 338.601812 -222.626428)
			(xy 338.61629 -222.60052) (xy 338.628915 -222.578852) (xy 338.65969 -222.539259) (xy 338.696093 -222.504771)
			(xy 338.73729 -222.476179) (xy 338.782333 -222.454139) (xy 338.83019 -222.439159) (xy 338.879761 -222.431582)
			(xy 338.929907 -222.431582) (xy 338.979478 -222.439159) (xy 339.027335 -222.454139) (xy 339.072378 -222.476179)
			(xy 339.113575 -222.504771) (xy 339.149978 -222.539259) (xy 339.180753 -222.578852) (xy 339.193378 -222.60052)
			(xy 339.207856 -222.626428) (xy 339.541612 -222.626428) (xy 339.55609 -222.60052) (xy 339.568715 -222.578852)
			(xy 339.59949 -222.539259) (xy 339.635893 -222.504771) (xy 339.67709 -222.476179) (xy 339.722133 -222.454139)
			(xy 339.76999 -222.439159) (xy 339.819561 -222.431582) (xy 339.869707 -222.431582) (xy 339.919278 -222.439159)
			(xy 339.967135 -222.454139) (xy 340.012178 -222.476179) (xy 340.053375 -222.504771) (xy 340.089778 -222.539259)
			(xy 340.120553 -222.578852) (xy 340.133178 -222.60052) (xy 340.147656 -222.626428) (xy 340.481412 -222.626428)
			(xy 340.49589 -222.60052) (xy 340.508515 -222.578852) (xy 340.53929 -222.539259) (xy 340.575693 -222.504771)
			(xy 340.61689 -222.476179) (xy 340.661933 -222.454139) (xy 340.70979 -222.439159) (xy 340.759361 -222.431582)
			(xy 340.809507 -222.431582) (xy 340.859078 -222.439159) (xy 340.906935 -222.454139) (xy 340.951978 -222.476179)
			(xy 340.993175 -222.504771) (xy 341.029578 -222.539259) (xy 341.060353 -222.578852) (xy 341.072978 -222.60052)
			(xy 341.087456 -222.626428) (xy 341.421212 -222.626428) (xy 341.43569 -222.60052) (xy 341.448315 -222.578852)
			(xy 341.47909 -222.539259) (xy 341.515493 -222.504771) (xy 341.55669 -222.476179) (xy 341.601733 -222.454139)
			(xy 341.64959 -222.439159) (xy 341.699161 -222.431582) (xy 341.749307 -222.431582) (xy 341.798878 -222.439159)
			(xy 341.846735 -222.454139) (xy 341.891778 -222.476179) (xy 341.932975 -222.504771) (xy 341.969378 -222.539259)
			(xy 342.000153 -222.578852) (xy 342.012778 -222.60052) (xy 342.027256 -222.626428) (xy 342.361012 -222.626428)
			(xy 342.37549 -222.60052) (xy 342.388115 -222.578852) (xy 342.41889 -222.539259) (xy 342.455293 -222.504771)
			(xy 342.49649 -222.476179) (xy 342.541533 -222.454139) (xy 342.58939 -222.439159) (xy 342.638961 -222.431582)
			(xy 342.689107 -222.431582) (xy 342.738678 -222.439159) (xy 342.786535 -222.454139) (xy 342.831578 -222.476179)
			(xy 342.872775 -222.504771) (xy 342.909178 -222.539259) (xy 342.939953 -222.578852) (xy 342.952578 -222.60052)
			(xy 342.967056 -222.626428) (xy 343.300812 -222.626428) (xy 343.31529 -222.60052) (xy 343.327915 -222.578852)
			(xy 343.35869 -222.539259) (xy 343.395093 -222.504771) (xy 343.43629 -222.476179) (xy 343.481333 -222.454139)
			(xy 343.52919 -222.439159) (xy 343.578761 -222.431582) (xy 343.628907 -222.431582) (xy 343.678478 -222.439159)
			(xy 343.726335 -222.454139) (xy 343.771378 -222.476179) (xy 343.812575 -222.504771) (xy 343.848978 -222.539259)
			(xy 343.879753 -222.578852) (xy 343.892378 -222.60052) (xy 343.906856 -222.626428) (xy 344.240612 -222.626428)
			(xy 344.25509 -222.60052) (xy 344.267715 -222.578852) (xy 344.29849 -222.539259) (xy 344.334893 -222.504771)
			(xy 344.37609 -222.476179) (xy 344.421133 -222.454139) (xy 344.46899 -222.439159) (xy 344.518561 -222.431582)
			(xy 344.568707 -222.431582) (xy 344.618278 -222.439159) (xy 344.666135 -222.454139) (xy 344.711178 -222.476179)
			(xy 344.752375 -222.504771) (xy 344.788778 -222.539259) (xy 344.819553 -222.578852) (xy 344.832178 -222.60052)
			(xy 344.846656 -222.626428) (xy 345.180412 -222.626428) (xy 345.19489 -222.60052) (xy 345.207515 -222.578852)
			(xy 345.23829 -222.539259) (xy 345.274693 -222.504771) (xy 345.31589 -222.476179) (xy 345.360933 -222.454139)
			(xy 345.40879 -222.439159) (xy 345.458361 -222.431582) (xy 345.508507 -222.431582) (xy 345.558078 -222.439159)
			(xy 345.605935 -222.454139) (xy 345.650978 -222.476179) (xy 345.692175 -222.504771) (xy 345.728578 -222.539259)
			(xy 345.759353 -222.578852) (xy 345.771978 -222.60052) (xy 345.786456 -222.626428) (xy 346.120212 -222.626428)
			(xy 346.13469 -222.60052) (xy 346.147315 -222.578852) (xy 346.17809 -222.539259) (xy 346.214493 -222.504771)
			(xy 346.25569 -222.476179) (xy 346.300733 -222.454139) (xy 346.34859 -222.439159) (xy 346.398161 -222.431582)
			(xy 346.448307 -222.431582) (xy 346.497878 -222.439159) (xy 346.545735 -222.454139) (xy 346.590778 -222.476179)
			(xy 346.631975 -222.504771) (xy 346.668378 -222.539259) (xy 346.699153 -222.578852) (xy 346.711778 -222.60052)
			(xy 346.726256 -222.626428) (xy 347.060012 -222.626428) (xy 347.07449 -222.60052) (xy 347.087115 -222.578852)
			(xy 347.11789 -222.539259) (xy 347.154293 -222.504771) (xy 347.19549 -222.476179) (xy 347.240533 -222.454139)
			(xy 347.28839 -222.439159) (xy 347.337961 -222.431582) (xy 347.388107 -222.431582) (xy 347.437678 -222.439159)
			(xy 347.485535 -222.454139) (xy 347.530578 -222.476179) (xy 347.571775 -222.504771) (xy 347.608178 -222.539259)
			(xy 347.638953 -222.578852) (xy 347.651578 -222.60052) (xy 347.666056 -222.626428) (xy 347.999812 -222.626428)
			(xy 348.01429 -222.60052) (xy 348.026916 -222.578852) (xy 348.05769 -222.539257) (xy 348.094093 -222.504765)
			(xy 348.135289 -222.476169) (xy 348.180332 -222.454124) (xy 348.228189 -222.439137) (xy 348.27776 -222.431551)
			(xy 348.302834 -222.431102) (xy 348.330738 -222.431709) (xy 348.385747 -222.44113) (xy 348.438395 -222.459648)
			(xy 348.487189 -222.486739) (xy 348.530744 -222.521634) (xy 348.549722 -222.5421) (xy 348.559256 -222.552121)
			(xy 348.5825 -222.567094) (xy 348.608908 -222.575286) (xy 348.636545 -222.576099) (xy 348.663388 -222.569471)
			(xy 348.687471 -222.555889) (xy 348.69755 -222.546418) (xy 348.795086 -222.448882) (xy 348.804848 -222.438469)
			(xy 348.818682 -222.413517) (xy 348.825067 -222.385711) (xy 348.823505 -222.357224) (xy 348.814117 -222.330283)
			(xy 348.797638 -222.306994) (xy 348.775355 -222.289177) (xy 348.74901 -222.278226) (xy 348.734888 -222.276162)
			(xy 348.708354 -222.272607) (xy 348.656843 -222.25803) (xy 348.608359 -222.235336) (xy 348.564168 -222.205121)
			(xy 348.525428 -222.168174) (xy 348.493154 -222.125464) (xy 348.46819 -222.078108) (xy 348.45119 -222.027346)
			(xy 348.442598 -221.974507) (xy 348.442026 -221.94774) (xy 348.442636 -221.919759) (xy 348.452082 -221.8646)
			(xy 348.460822 -221.838012) (xy 348.468442 -221.815914) (xy 348.264734 -221.463108) (xy 348.241874 -221.45879)
			(xy 348.216943 -221.453641) (xy 348.168938 -221.436703) (xy 348.1241 -221.412601) (xy 348.08349 -221.381906)
			(xy 348.048069 -221.345344) (xy 348.018677 -221.303782) (xy 347.996009 -221.258202) (xy 347.980601 -221.209684)
			(xy 347.972818 -221.159377) (xy 347.97238 -221.133924) (xy 347.972889 -221.107957) (xy 347.981014 -221.056662)
			(xy 347.997062 -221.007269) (xy 348.02064 -220.960995) (xy 348.051166 -220.918979) (xy 348.087889 -220.882256)
			(xy 348.129905 -220.85173) (xy 348.176179 -220.828152) (xy 348.225572 -220.812104) (xy 348.276867 -220.803979)
			(xy 348.328801 -220.803979) (xy 348.380096 -220.812104) (xy 348.429489 -220.828152) (xy 348.475763 -220.85173)
			(xy 348.517779 -220.882256) (xy 348.554502 -220.918979) (xy 348.585028 -220.960995) (xy 348.608606 -221.007269)
			(xy 348.624654 -221.056662) (xy 348.632779 -221.107957) (xy 348.633288 -221.133924) (xy 348.632673 -221.161904)
			(xy 348.623217 -221.21706) (xy 348.614492 -221.243652) (xy 348.606872 -221.26575) (xy 348.81058 -221.618556)
			(xy 348.83344 -221.622874) (xy 348.858651 -221.628106) (xy 348.907172 -221.645332) (xy 348.952438 -221.669867)
			(xy 348.993356 -221.701119) (xy 349.011494 -221.719394) (xy 349.022345 -221.729942) (xy 349.048733 -221.744722)
			(xy 349.078292 -221.751125) (xy 349.108431 -221.748592) (xy 349.136507 -221.737343) (xy 349.160057 -221.718366)
			(xy 349.177017 -221.693323) (xy 349.1859 -221.664412) (xy 349.1865 -221.64929) (xy 349.1865 -221.461838)
			(xy 349.149924 -221.45117) (xy 349.12603 -221.44371) (xy 349.080648 -221.422591) (xy 349.038969 -221.39487)
			(xy 349.001947 -221.361182) (xy 348.970428 -221.322296) (xy 348.945132 -221.279103) (xy 348.926639 -221.232589)
			(xy 348.915371 -221.183819) (xy 348.911585 -221.133907) (xy 348.915369 -221.083995) (xy 348.926635 -221.035224)
			(xy 348.945126 -220.988709) (xy 348.97042 -220.945515) (xy 349.001938 -220.906628) (xy 349.038959 -220.872938)
			(xy 349.080636 -220.845216) (xy 349.126017 -220.824095) (xy 349.149924 -220.816678) (xy 349.1865 -220.80601)
			(xy 349.1865 -220.618558) (xy 349.185943 -220.603426) (xy 349.177074 -220.574491) (xy 349.160125 -220.549418)
			(xy 349.136581 -220.530403) (xy 349.108503 -220.51911) (xy 349.078349 -220.516529) (xy 349.04876 -220.522886)
			(xy 349.022327 -220.537623) (xy 349.011494 -220.5482) (xy 348.992676 -220.567156) (xy 348.950048 -220.599338)
			(xy 348.902797 -220.62424) (xy 348.852154 -220.641213) (xy 348.79944 -220.649814) (xy 348.772734 -220.650308)
			(xy 348.746767 -220.649828) (xy 348.69547 -220.641708) (xy 348.646076 -220.625664) (xy 348.5998 -220.602089)
			(xy 348.557782 -220.571565) (xy 348.521057 -220.534844) (xy 348.490529 -220.492829) (xy 348.466949 -220.446555)
			(xy 348.4509 -220.397163) (xy 348.442775 -220.345867) (xy 348.442775 -220.293933) (xy 348.4509 -220.242637)
			(xy 348.466949 -220.193245) (xy 348.490529 -220.146971) (xy 348.521057 -220.104956) (xy 348.557782 -220.068235)
			(xy 348.5998 -220.037711) (xy 348.646076 -220.014136) (xy 348.69547 -219.998092) (xy 348.746767 -219.989972)
			(xy 348.772734 -219.9894) (xy 348.799438 -219.989916) (xy 348.852148 -219.998517) (xy 348.902788 -220.015489)
			(xy 348.950035 -220.04039) (xy 348.99266 -220.07257) (xy 349.011494 -220.091508) (xy 349.022364 -220.102058)
			(xy 349.048792 -220.116829) (xy 349.078388 -220.123211) (xy 349.108555 -220.120644) (xy 349.136646 -220.109353)
			(xy 349.160198 -220.090329) (xy 349.177145 -220.06524) (xy 349.185999 -220.036288) (xy 349.1865 -220.02115)
			(xy 349.1865 -219.833952) (xy 349.149924 -219.823284) (xy 349.126028 -219.815824) (xy 349.080645 -219.794704)
			(xy 349.038964 -219.766983) (xy 349.00194 -219.733294) (xy 348.970419 -219.694407) (xy 348.945122 -219.651212)
			(xy 348.926627 -219.604697) (xy 348.915358 -219.555925) (xy 348.911572 -219.506011) (xy 348.915355 -219.456096)
			(xy 348.926621 -219.407323) (xy 348.945113 -219.360807) (xy 348.970407 -219.31761) (xy 349.001925 -219.278722)
			(xy 349.038947 -219.24503) (xy 349.080626 -219.217306) (xy 349.126009 -219.196184) (xy 349.149924 -219.188792)
			(xy 349.1865 -219.178124) (xy 349.1865 -218.990672) (xy 349.185956 -218.975537) (xy 349.177099 -218.946593)
			(xy 349.160144 -218.921519) (xy 349.136581 -218.902519) (xy 349.108483 -218.891265) (xy 349.078319 -218.888746)
			(xy 349.048743 -218.895184) (xy 349.022355 -218.910012) (xy 349.011494 -218.920568) (xy 348.992649 -218.939529)
			(xy 348.949968 -218.971713) (xy 348.902664 -218.99661) (xy 348.85197 -219.01357) (xy 348.799208 -219.022153)
			(xy 348.77248 -219.022676) (xy 348.746513 -219.022165) (xy 348.695219 -219.014039) (xy 348.645828 -218.997988)
			(xy 348.599555 -218.97441) (xy 348.55754 -218.943884) (xy 348.520818 -218.907161) (xy 348.490291 -218.865146)
			(xy 348.466712 -218.818874) (xy 348.450662 -218.769483) (xy 348.442535 -218.718189) (xy 348.442026 -218.692222)
			(xy 348.442637 -218.664242) (xy 348.452086 -218.609083) (xy 348.460822 -218.582494) (xy 348.468442 -218.560396)
			(xy 348.264734 -218.20759) (xy 348.241874 -218.203272) (xy 348.216944 -218.198123) (xy 348.16894 -218.181185)
			(xy 348.124103 -218.157082) (xy 348.083495 -218.126387) (xy 348.048076 -218.089825) (xy 348.018686 -218.048262)
			(xy 347.99602 -218.002682) (xy 347.980614 -217.954165) (xy 347.972835 -217.903858) (xy 347.97238 -217.878406)
			(xy 347.972889 -217.852439) (xy 347.981014 -217.801144) (xy 347.997062 -217.751751) (xy 348.02064 -217.705477)
			(xy 348.051166 -217.663461) (xy 348.087889 -217.626738) (xy 348.129905 -217.596212) (xy 348.176179 -217.572634)
			(xy 348.225572 -217.556586) (xy 348.276867 -217.548461) (xy 348.328801 -217.548461) (xy 348.380096 -217.556586)
			(xy 348.429489 -217.572634) (xy 348.475763 -217.596212) (xy 348.517779 -217.626738) (xy 348.554502 -217.663461)
			(xy 348.585028 -217.705477) (xy 348.608606 -217.751751) (xy 348.624654 -217.801144) (xy 348.632779 -217.852439)
			(xy 348.633288 -217.878406) (xy 348.632674 -217.906386) (xy 348.623221 -217.961543) (xy 348.614492 -217.988134)
			(xy 348.606872 -218.010232) (xy 348.81058 -218.363038) (xy 348.83344 -218.367356) (xy 348.858652 -218.372588)
			(xy 348.907173 -218.389813) (xy 348.952439 -218.414347) (xy 348.993358 -218.445598) (xy 349.011494 -218.463876)
			(xy 349.022343 -218.474425) (xy 349.04873 -218.489207) (xy 349.07829 -218.495613) (xy 349.108429 -218.49308)
			(xy 349.136504 -218.48183) (xy 349.160053 -218.462851) (xy 349.177011 -218.437807) (xy 349.18589 -218.408894)
			(xy 349.1865 -218.393772) (xy 349.1865 -218.20632) (xy 349.149924 -218.195652) (xy 349.124547 -218.18769)
			(xy 349.076541 -218.164802) (xy 349.032821 -218.134519) (xy 348.994517 -218.097624) (xy 348.962617 -218.05507)
			(xy 348.937947 -218.007955) (xy 348.921142 -217.957496) (xy 348.912638 -217.904998) (xy 348.91218 -217.878406)
			(xy 348.912807 -217.849564) (xy 348.922819 -217.792756) (xy 348.94254 -217.738548) (xy 348.97137 -217.688587)
			(xy 348.989396 -217.666062) (xy 348.998674 -217.654143) (xy 349.01047 -217.626353) (xy 349.013643 -217.59633)
			(xy 349.007919 -217.566688) (xy 348.993796 -217.540006) (xy 348.983554 -217.528902) (xy 348.842838 -217.388186)
			(xy 348.817946 -217.391742) (xy 348.806698 -217.393179) (xy 348.784073 -217.394706) (xy 348.772734 -217.39479)
			(xy 348.747234 -217.394327) (xy 348.696837 -217.386508) (xy 348.648241 -217.371035) (xy 348.602601 -217.348277)
			(xy 348.561002 -217.318774) (xy 348.524432 -217.283227) (xy 348.49376 -217.242481) (xy 348.469716 -217.197505)
			(xy 348.452871 -217.149368) (xy 348.443626 -217.099213) (xy 348.442534 -217.073734) (xy 348.441523 -217.058036)
			(xy 348.431155 -217.028355) (xy 348.412255 -217.00323) (xy 348.386613 -216.985038) (xy 348.356654 -216.975501)
			(xy 348.340934 -216.974928) (xy 348.26448 -216.974928) (xy 348.248763 -216.975512) (xy 348.218814 -216.985062)
			(xy 348.193179 -217.003253) (xy 348.174277 -217.02837) (xy 348.163892 -217.058039) (xy 348.16288 -217.073734)
			(xy 348.161711 -217.098629) (xy 348.152818 -217.147667) (xy 348.13667 -217.194816) (xy 348.113633 -217.239009)
			(xy 348.084227 -217.279247) (xy 348.049118 -217.314618) (xy 348.0091 -217.344323) (xy 347.96508 -217.367689)
			(xy 347.918052 -217.384188) (xy 347.89364 -217.389202) (xy 347.87078 -217.39352) (xy 347.667072 -217.74658)
			(xy 347.674692 -217.768678) (xy 347.683485 -217.795252) (xy 347.692934 -217.85042) (xy 347.693488 -217.878406)
			(xy 347.692979 -217.904373) (xy 347.684854 -217.955668) (xy 347.668806 -218.005061) (xy 347.645228 -218.051335)
			(xy 347.614702 -218.093351) (xy 347.577979 -218.130074) (xy 347.535963 -218.1606) (xy 347.489689 -218.184178)
			(xy 347.440296 -218.200226) (xy 347.389001 -218.208351) (xy 347.337067 -218.208351) (xy 347.285772 -218.200226)
			(xy 347.236379 -218.184178) (xy 347.190105 -218.1606) (xy 347.148089 -218.130074) (xy 347.111366 -218.093351)
			(xy 347.08084 -218.051335) (xy 347.057262 -218.005061) (xy 347.041214 -217.955668) (xy 347.033089 -217.904373)
			(xy 347.03258 -217.878406) (xy 347.033055 -217.85296) (xy 347.040868 -217.802672) (xy 347.056295 -217.754174)
			(xy 347.078971 -217.708614) (xy 347.10836 -217.667066) (xy 347.143769 -217.630512) (xy 347.184362 -217.599816)
			(xy 347.229178 -217.575703) (xy 347.27716 -217.558742) (xy 347.302074 -217.55354) (xy 347.324934 -217.549222)
			(xy 347.528642 -217.196162) (xy 347.521022 -217.174064) (xy 347.512987 -217.149728) (xy 347.503676 -217.099334)
			(xy 347.50248 -217.073734) (xy 347.50147 -217.058033) (xy 347.491103 -217.028346) (xy 347.472204 -217.003213)
			(xy 347.446563 -216.985011) (xy 347.416603 -216.975462) (xy 347.40088 -216.974928) (xy 347.324934 -216.974928)
			(xy 347.309222 -216.975519) (xy 347.279285 -216.985076) (xy 347.253662 -217.00327) (xy 347.23477 -217.028383)
			(xy 347.224391 -217.058045) (xy 347.223334 -217.073734) (xy 347.222136 -217.099199) (xy 347.212875 -217.149327)
			(xy 347.196023 -217.197438) (xy 347.17198 -217.242389) (xy 347.141317 -217.283113) (xy 347.104761 -217.318642)
			(xy 347.063182 -217.348135) (xy 347.017565 -217.370889) (xy 346.968994 -217.386366) (xy 346.918622 -217.394197)
			(xy 346.867646 -217.394197) (xy 346.817274 -217.386366) (xy 346.768703 -217.370889) (xy 346.723086 -217.348135)
			(xy 346.681507 -217.318642) (xy 346.644951 -217.283113) (xy 346.614288 -217.242389) (xy 346.590245 -217.197438)
			(xy 346.573393 -217.149327) (xy 346.564132 -217.099199) (xy 346.562934 -217.073734) (xy 346.561923 -217.058036)
			(xy 346.551555 -217.028355) (xy 346.532655 -217.00323) (xy 346.507013 -216.985038) (xy 346.477054 -216.975501)
			(xy 346.461334 -216.974928) (xy 346.38488 -216.974928) (xy 346.369163 -216.975512) (xy 346.339214 -216.985062)
			(xy 346.313579 -217.003253) (xy 346.294677 -217.02837) (xy 346.284292 -217.058039) (xy 346.28328 -217.073734)
			(xy 346.282111 -217.098629) (xy 346.273218 -217.147667) (xy 346.25707 -217.194816) (xy 346.234033 -217.239009)
			(xy 346.204627 -217.279247) (xy 346.169518 -217.314618) (xy 346.1295 -217.344323) (xy 346.08548 -217.367689)
			(xy 346.038452 -217.384188) (xy 346.01404 -217.389202) (xy 345.99118 -217.39352) (xy 345.787472 -217.74658)
			(xy 345.795092 -217.768678) (xy 345.803885 -217.795252) (xy 345.813334 -217.85042) (xy 345.813888 -217.878406)
			(xy 346.09278 -217.878406) (xy 346.093289 -217.852439) (xy 346.101414 -217.801144) (xy 346.117462 -217.751751)
			(xy 346.14104 -217.705477) (xy 346.171566 -217.663461) (xy 346.208289 -217.626738) (xy 346.250305 -217.596212)
			(xy 346.296579 -217.572634) (xy 346.345972 -217.556586) (xy 346.397267 -217.548461) (xy 346.449201 -217.548461)
			(xy 346.500496 -217.556586) (xy 346.549889 -217.572634) (xy 346.596163 -217.596212) (xy 346.638179 -217.626738)
			(xy 346.674902 -217.663461) (xy 346.705428 -217.705477) (xy 346.729006 -217.751751) (xy 346.745054 -217.801144)
			(xy 346.753179 -217.852439) (xy 346.753688 -217.878406) (xy 346.753137 -217.906392) (xy 346.743686 -217.96156)
			(xy 346.734892 -217.988134) (xy 346.727272 -218.010232) (xy 346.93098 -218.363038) (xy 346.95384 -218.367356)
			(xy 346.978759 -218.372533) (xy 347.026743 -218.389497) (xy 347.07156 -218.413614) (xy 347.112152 -218.444313)
			(xy 347.147561 -218.48087) (xy 347.17695 -218.522421) (xy 347.199624 -218.567984) (xy 347.215049 -218.616484)
			(xy 347.22286 -218.666775) (xy 347.223334 -218.692222) (xy 347.222825 -218.718189) (xy 347.2147 -218.769484)
			(xy 347.198652 -218.818877) (xy 347.175074 -218.865151) (xy 347.144548 -218.907167) (xy 347.107825 -218.94389)
			(xy 347.065809 -218.974416) (xy 347.019535 -218.997994) (xy 346.970142 -219.014042) (xy 346.918847 -219.022167)
			(xy 346.866913 -219.022167) (xy 346.815618 -219.014042) (xy 346.766225 -218.997994) (xy 346.719951 -218.974416)
			(xy 346.677935 -218.94389) (xy 346.641212 -218.907167) (xy 346.610686 -218.865151) (xy 346.587108 -218.818877)
			(xy 346.57106 -218.769484) (xy 346.562935 -218.718189) (xy 346.562426 -218.692222) (xy 346.562983 -218.664236)
			(xy 346.57243 -218.609068) (xy 346.581222 -218.582494) (xy 346.588842 -218.560396) (xy 346.385134 -218.20759)
			(xy 346.362274 -218.203272) (xy 346.337363 -218.198058) (xy 346.289382 -218.181098) (xy 346.244566 -218.156986)
			(xy 346.203974 -218.126292) (xy 346.168565 -218.08974) (xy 346.139175 -218.048193) (xy 346.116498 -218.002634)
			(xy 346.101071 -217.954138) (xy 346.093256 -217.903851) (xy 346.09278 -217.878406) (xy 345.813888 -217.878406)
			(xy 345.813379 -217.904373) (xy 345.805254 -217.955668) (xy 345.789206 -218.005061) (xy 345.765628 -218.051335)
			(xy 345.735102 -218.093351) (xy 345.698379 -218.130074) (xy 345.656363 -218.1606) (xy 345.610089 -218.184178)
			(xy 345.560696 -218.200226) (xy 345.509401 -218.208351) (xy 345.457467 -218.208351) (xy 345.406172 -218.200226)
			(xy 345.356779 -218.184178) (xy 345.310505 -218.1606) (xy 345.268489 -218.130074) (xy 345.231766 -218.093351)
			(xy 345.20124 -218.051335) (xy 345.177662 -218.005061) (xy 345.161614 -217.955668) (xy 345.153489 -217.904373)
			(xy 345.15298 -217.878406) (xy 345.153455 -217.85296) (xy 345.161268 -217.802672) (xy 345.176695 -217.754174)
			(xy 345.199371 -217.708614) (xy 345.22876 -217.667066) (xy 345.264169 -217.630512) (xy 345.304762 -217.599816)
			(xy 345.349578 -217.575703) (xy 345.39756 -217.558742) (xy 345.422474 -217.55354) (xy 345.445334 -217.549222)
			(xy 345.649042 -217.196162) (xy 345.641422 -217.174064) (xy 345.633387 -217.149728) (xy 345.624076 -217.099334)
			(xy 345.62288 -217.073734) (xy 345.62187 -217.058033) (xy 345.611503 -217.028346) (xy 345.592604 -217.003213)
			(xy 345.566963 -216.985011) (xy 345.537003 -216.975462) (xy 345.52128 -216.974928) (xy 345.445334 -216.974928)
			(xy 345.429622 -216.975519) (xy 345.399685 -216.985076) (xy 345.374062 -217.00327) (xy 345.35517 -217.028383)
			(xy 345.344791 -217.058045) (xy 345.343734 -217.073734) (xy 345.342536 -217.099199) (xy 345.333275 -217.149327)
			(xy 345.316423 -217.197438) (xy 345.29238 -217.242389) (xy 345.261717 -217.283113) (xy 345.225161 -217.318642)
			(xy 345.183582 -217.348135) (xy 345.137965 -217.370889) (xy 345.089394 -217.386366) (xy 345.039022 -217.394197)
			(xy 344.988046 -217.394197) (xy 344.937674 -217.386366) (xy 344.889103 -217.370889) (xy 344.843486 -217.348135)
			(xy 344.801907 -217.318642) (xy 344.765351 -217.283113) (xy 344.734688 -217.242389) (xy 344.710645 -217.197438)
			(xy 344.693793 -217.149327) (xy 344.684532 -217.099199) (xy 344.683334 -217.073734) (xy 344.682323 -217.058036)
			(xy 344.671955 -217.028355) (xy 344.653055 -217.00323) (xy 344.627413 -216.985038) (xy 344.597454 -216.975501)
			(xy 344.581734 -216.974928) (xy 344.50528 -216.974928) (xy 344.489563 -216.975512) (xy 344.459614 -216.985062)
			(xy 344.433979 -217.003253) (xy 344.415077 -217.02837) (xy 344.404692 -217.058039) (xy 344.40368 -217.073734)
			(xy 344.402511 -217.098629) (xy 344.393618 -217.147667) (xy 344.37747 -217.194816) (xy 344.354433 -217.239009)
			(xy 344.325027 -217.279247) (xy 344.289918 -217.314618) (xy 344.2499 -217.344323) (xy 344.20588 -217.367689)
			(xy 344.158852 -217.384188) (xy 344.13444 -217.389202) (xy 344.11158 -217.39352) (xy 343.907872 -217.74658)
			(xy 343.915492 -217.768678) (xy 343.924285 -217.795252) (xy 343.933734 -217.85042) (xy 343.934288 -217.878406)
			(xy 344.21318 -217.878406) (xy 344.213689 -217.852439) (xy 344.221814 -217.801144) (xy 344.237862 -217.751751)
			(xy 344.26144 -217.705477) (xy 344.291966 -217.663461) (xy 344.328689 -217.626738) (xy 344.370705 -217.596212)
			(xy 344.416979 -217.572634) (xy 344.466372 -217.556586) (xy 344.517667 -217.548461) (xy 344.569601 -217.548461)
			(xy 344.620896 -217.556586) (xy 344.670289 -217.572634) (xy 344.716563 -217.596212) (xy 344.758579 -217.626738)
			(xy 344.795302 -217.663461) (xy 344.825828 -217.705477) (xy 344.849406 -217.751751) (xy 344.865454 -217.801144)
			(xy 344.873579 -217.852439) (xy 344.874088 -217.878406) (xy 344.873537 -217.906392) (xy 344.864086 -217.96156)
			(xy 344.855292 -217.988134) (xy 344.847672 -218.010232) (xy 345.05138 -218.363038) (xy 345.07424 -218.367356)
			(xy 345.099159 -218.372533) (xy 345.147143 -218.389497) (xy 345.19196 -218.413614) (xy 345.232552 -218.444313)
			(xy 345.267961 -218.48087) (xy 345.29735 -218.522421) (xy 345.320024 -218.567984) (xy 345.335449 -218.616484)
			(xy 345.34326 -218.666775) (xy 345.343734 -218.692222) (xy 345.343225 -218.718189) (xy 345.3351 -218.769484)
			(xy 345.319052 -218.818877) (xy 345.295474 -218.865151) (xy 345.264948 -218.907167) (xy 345.228225 -218.94389)
			(xy 345.186209 -218.974416) (xy 345.139935 -218.997994) (xy 345.090542 -219.014042) (xy 345.039247 -219.022167)
			(xy 344.987313 -219.022167) (xy 344.936018 -219.014042) (xy 344.886625 -218.997994) (xy 344.840351 -218.974416)
			(xy 344.798335 -218.94389) (xy 344.761612 -218.907167) (xy 344.731086 -218.865151) (xy 344.707508 -218.818877)
			(xy 344.69146 -218.769484) (xy 344.683335 -218.718189) (xy 344.682826 -218.692222) (xy 344.683383 -218.664236)
			(xy 344.69283 -218.609068) (xy 344.701622 -218.582494) (xy 344.709242 -218.560396) (xy 344.505534 -218.20759)
			(xy 344.482674 -218.203272) (xy 344.457763 -218.198058) (xy 344.409782 -218.181098) (xy 344.364966 -218.156986)
			(xy 344.324374 -218.126292) (xy 344.288965 -218.08974) (xy 344.259575 -218.048193) (xy 344.236898 -218.002634)
			(xy 344.221471 -217.954138) (xy 344.213656 -217.903851) (xy 344.21318 -217.878406) (xy 343.934288 -217.878406)
			(xy 343.933779 -217.904373) (xy 343.925654 -217.955668) (xy 343.909606 -218.005061) (xy 343.886028 -218.051335)
			(xy 343.855502 -218.093351) (xy 343.818779 -218.130074) (xy 343.776763 -218.1606) (xy 343.730489 -218.184178)
			(xy 343.681096 -218.200226) (xy 343.629801 -218.208351) (xy 343.577867 -218.208351) (xy 343.526572 -218.200226)
			(xy 343.477179 -218.184178) (xy 343.430905 -218.1606) (xy 343.388889 -218.130074) (xy 343.352166 -218.093351)
			(xy 343.32164 -218.051335) (xy 343.298062 -218.005061) (xy 343.282014 -217.955668) (xy 343.273889 -217.904373)
			(xy 343.27338 -217.878406) (xy 343.273855 -217.85296) (xy 343.281668 -217.802672) (xy 343.297095 -217.754174)
			(xy 343.319771 -217.708614) (xy 343.34916 -217.667066) (xy 343.384569 -217.630512) (xy 343.425162 -217.599816)
			(xy 343.469978 -217.575703) (xy 343.51796 -217.558742) (xy 343.542874 -217.55354) (xy 343.565734 -217.549222)
			(xy 343.769442 -217.196162) (xy 343.761822 -217.174064) (xy 343.753787 -217.149728) (xy 343.744476 -217.099334)
			(xy 343.74328 -217.073734) (xy 343.74227 -217.058033) (xy 343.731903 -217.028346) (xy 343.713004 -217.003213)
			(xy 343.687363 -216.985011) (xy 343.657403 -216.975462) (xy 343.64168 -216.974928) (xy 343.565734 -216.974928)
			(xy 343.550022 -216.975519) (xy 343.520085 -216.985076) (xy 343.494462 -217.00327) (xy 343.47557 -217.028383)
			(xy 343.465191 -217.058045) (xy 343.464134 -217.073734) (xy 343.462936 -217.099199) (xy 343.453675 -217.149327)
			(xy 343.436823 -217.197438) (xy 343.41278 -217.242389) (xy 343.382117 -217.283113) (xy 343.345561 -217.318642)
			(xy 343.303982 -217.348135) (xy 343.258365 -217.370889) (xy 343.209794 -217.386366) (xy 343.159422 -217.394197)
			(xy 343.108446 -217.394197) (xy 343.058074 -217.386366) (xy 343.009503 -217.370889) (xy 342.963886 -217.348135)
			(xy 342.922307 -217.318642) (xy 342.885751 -217.283113) (xy 342.855088 -217.242389) (xy 342.831045 -217.197438)
			(xy 342.814193 -217.149327) (xy 342.804932 -217.099199) (xy 342.803734 -217.073734) (xy 342.802723 -217.058036)
			(xy 342.792355 -217.028355) (xy 342.773455 -217.00323) (xy 342.747813 -216.985038) (xy 342.717854 -216.975501)
			(xy 342.702134 -216.974928) (xy 342.62568 -216.974928) (xy 342.609963 -216.975512) (xy 342.580014 -216.985062)
			(xy 342.554379 -217.003253) (xy 342.535477 -217.02837) (xy 342.525092 -217.058039) (xy 342.52408 -217.073734)
			(xy 342.522911 -217.098629) (xy 342.514018 -217.147667) (xy 342.49787 -217.194816) (xy 342.474833 -217.239009)
			(xy 342.445427 -217.279247) (xy 342.410318 -217.314618) (xy 342.3703 -217.344323) (xy 342.32628 -217.367689)
			(xy 342.279252 -217.384188) (xy 342.25484 -217.389202) (xy 342.23198 -217.39352) (xy 342.028272 -217.74658)
			(xy 342.035892 -217.768678) (xy 342.044685 -217.795252) (xy 342.054134 -217.85042) (xy 342.054688 -217.878406)
			(xy 342.33358 -217.878406) (xy 342.334089 -217.852439) (xy 342.342214 -217.801144) (xy 342.358262 -217.751751)
			(xy 342.38184 -217.705477) (xy 342.412366 -217.663461) (xy 342.449089 -217.626738) (xy 342.491105 -217.596212)
			(xy 342.537379 -217.572634) (xy 342.586772 -217.556586) (xy 342.638067 -217.548461) (xy 342.690001 -217.548461)
			(xy 342.741296 -217.556586) (xy 342.790689 -217.572634) (xy 342.836963 -217.596212) (xy 342.878979 -217.626738)
			(xy 342.915702 -217.663461) (xy 342.946228 -217.705477) (xy 342.969806 -217.751751) (xy 342.985854 -217.801144)
			(xy 342.993979 -217.852439) (xy 342.994488 -217.878406) (xy 342.993937 -217.906392) (xy 342.984486 -217.96156)
			(xy 342.975692 -217.988134) (xy 342.968072 -218.010232) (xy 343.17178 -218.363038) (xy 343.19464 -218.367356)
			(xy 343.219559 -218.372533) (xy 343.267543 -218.389497) (xy 343.31236 -218.413614) (xy 343.352952 -218.444313)
			(xy 343.388361 -218.48087) (xy 343.41775 -218.522421) (xy 343.440424 -218.567984) (xy 343.455849 -218.616484)
			(xy 343.46366 -218.666775) (xy 343.464134 -218.692222) (xy 343.463625 -218.718189) (xy 343.4555 -218.769484)
			(xy 343.439452 -218.818877) (xy 343.415874 -218.865151) (xy 343.385348 -218.907167) (xy 343.348625 -218.94389)
			(xy 343.306609 -218.974416) (xy 343.260335 -218.997994) (xy 343.210942 -219.014042) (xy 343.159647 -219.022167)
			(xy 343.107713 -219.022167) (xy 343.056418 -219.014042) (xy 343.007025 -218.997994) (xy 342.960751 -218.974416)
			(xy 342.918735 -218.94389) (xy 342.882012 -218.907167) (xy 342.851486 -218.865151) (xy 342.827908 -218.818877)
			(xy 342.81186 -218.769484) (xy 342.803735 -218.718189) (xy 342.803226 -218.692222) (xy 342.803783 -218.664236)
			(xy 342.81323 -218.609068) (xy 342.822022 -218.582494) (xy 342.829642 -218.560396) (xy 342.625934 -218.20759)
			(xy 342.603074 -218.203272) (xy 342.578163 -218.198058) (xy 342.530182 -218.181098) (xy 342.485366 -218.156986)
			(xy 342.444774 -218.126292) (xy 342.409365 -218.08974) (xy 342.379975 -218.048193) (xy 342.357298 -218.002634)
			(xy 342.341871 -217.954138) (xy 342.334056 -217.903851) (xy 342.33358 -217.878406) (xy 342.054688 -217.878406)
			(xy 342.054179 -217.904373) (xy 342.046054 -217.955668) (xy 342.030006 -218.005061) (xy 342.006428 -218.051335)
			(xy 341.975902 -218.093351) (xy 341.939179 -218.130074) (xy 341.897163 -218.1606) (xy 341.850889 -218.184178)
			(xy 341.801496 -218.200226) (xy 341.750201 -218.208351) (xy 341.698267 -218.208351) (xy 341.646972 -218.200226)
			(xy 341.597579 -218.184178) (xy 341.551305 -218.1606) (xy 341.509289 -218.130074) (xy 341.472566 -218.093351)
			(xy 341.44204 -218.051335) (xy 341.418462 -218.005061) (xy 341.402414 -217.955668) (xy 341.394289 -217.904373)
			(xy 341.39378 -217.878406) (xy 341.394255 -217.85296) (xy 341.402068 -217.802672) (xy 341.417495 -217.754174)
			(xy 341.440171 -217.708614) (xy 341.46956 -217.667066) (xy 341.504969 -217.630512) (xy 341.545562 -217.599816)
			(xy 341.590378 -217.575703) (xy 341.63836 -217.558742) (xy 341.663274 -217.55354) (xy 341.686134 -217.549222)
			(xy 341.889842 -217.196162) (xy 341.882222 -217.174064) (xy 341.874187 -217.149728) (xy 341.864876 -217.099334)
			(xy 341.86368 -217.073734) (xy 341.86267 -217.058033) (xy 341.852303 -217.028346) (xy 341.833404 -217.003213)
			(xy 341.807763 -216.985011) (xy 341.777803 -216.975462) (xy 341.76208 -216.974928) (xy 341.686134 -216.974928)
			(xy 341.670422 -216.975519) (xy 341.640485 -216.985076) (xy 341.614862 -217.00327) (xy 341.59597 -217.028383)
			(xy 341.585591 -217.058045) (xy 341.584534 -217.073734) (xy 341.583336 -217.099199) (xy 341.574075 -217.149327)
			(xy 341.557223 -217.197438) (xy 341.53318 -217.242389) (xy 341.502517 -217.283113) (xy 341.465961 -217.318642)
			(xy 341.424382 -217.348135) (xy 341.378765 -217.370889) (xy 341.330194 -217.386366) (xy 341.279822 -217.394197)
			(xy 341.228846 -217.394197) (xy 341.178474 -217.386366) (xy 341.129903 -217.370889) (xy 341.084286 -217.348135)
			(xy 341.042707 -217.318642) (xy 341.006151 -217.283113) (xy 340.975488 -217.242389) (xy 340.951445 -217.197438)
			(xy 340.934593 -217.149327) (xy 340.925332 -217.099199) (xy 340.924134 -217.073734) (xy 340.923123 -217.058036)
			(xy 340.912755 -217.028355) (xy 340.893855 -217.00323) (xy 340.868213 -216.985038) (xy 340.838254 -216.975501)
			(xy 340.822534 -216.974928) (xy 340.74608 -216.974928) (xy 340.730363 -216.975512) (xy 340.700414 -216.985062)
			(xy 340.674779 -217.003253) (xy 340.655877 -217.02837) (xy 340.645492 -217.058039) (xy 340.64448 -217.073734)
			(xy 340.643311 -217.098629) (xy 340.634418 -217.147667) (xy 340.61827 -217.194816) (xy 340.595233 -217.239009)
			(xy 340.565827 -217.279247) (xy 340.530718 -217.314618) (xy 340.4907 -217.344323) (xy 340.44668 -217.367689)
			(xy 340.399652 -217.384188) (xy 340.37524 -217.389202) (xy 340.35238 -217.39352) (xy 340.148672 -217.74658)
			(xy 340.156292 -217.768678) (xy 340.165085 -217.795252) (xy 340.174534 -217.85042) (xy 340.175088 -217.878406)
			(xy 340.45398 -217.878406) (xy 340.454489 -217.852439) (xy 340.462614 -217.801144) (xy 340.478662 -217.751751)
			(xy 340.50224 -217.705477) (xy 340.532766 -217.663461) (xy 340.569489 -217.626738) (xy 340.611505 -217.596212)
			(xy 340.657779 -217.572634) (xy 340.707172 -217.556586) (xy 340.758467 -217.548461) (xy 340.810401 -217.548461)
			(xy 340.861696 -217.556586) (xy 340.911089 -217.572634) (xy 340.957363 -217.596212) (xy 340.999379 -217.626738)
			(xy 341.036102 -217.663461) (xy 341.066628 -217.705477) (xy 341.090206 -217.751751) (xy 341.106254 -217.801144)
			(xy 341.114379 -217.852439) (xy 341.114888 -217.878406) (xy 341.114337 -217.906392) (xy 341.104886 -217.96156)
			(xy 341.096092 -217.988134) (xy 341.088472 -218.010232) (xy 341.29218 -218.363038) (xy 341.31504 -218.367356)
			(xy 341.339959 -218.372533) (xy 341.387943 -218.389497) (xy 341.43276 -218.413614) (xy 341.473352 -218.444313)
			(xy 341.508761 -218.48087) (xy 341.53815 -218.522421) (xy 341.560824 -218.567984) (xy 341.576249 -218.616484)
			(xy 341.58406 -218.666775) (xy 341.584534 -218.692222) (xy 341.584025 -218.718189) (xy 341.5759 -218.769484)
			(xy 341.559852 -218.818877) (xy 341.536274 -218.865151) (xy 341.505748 -218.907167) (xy 341.469025 -218.94389)
			(xy 341.427009 -218.974416) (xy 341.380735 -218.997994) (xy 341.331342 -219.014042) (xy 341.280047 -219.022167)
			(xy 341.228113 -219.022167) (xy 341.176818 -219.014042) (xy 341.127425 -218.997994) (xy 341.081151 -218.974416)
			(xy 341.039135 -218.94389) (xy 341.002412 -218.907167) (xy 340.971886 -218.865151) (xy 340.948308 -218.818877)
			(xy 340.93226 -218.769484) (xy 340.924135 -218.718189) (xy 340.923626 -218.692222) (xy 340.924183 -218.664236)
			(xy 340.93363 -218.609068) (xy 340.942422 -218.582494) (xy 340.950042 -218.560396) (xy 340.746334 -218.20759)
			(xy 340.723474 -218.203272) (xy 340.698563 -218.198058) (xy 340.650582 -218.181098) (xy 340.605766 -218.156986)
			(xy 340.565174 -218.126292) (xy 340.529765 -218.08974) (xy 340.500375 -218.048193) (xy 340.477698 -218.002634)
			(xy 340.462271 -217.954138) (xy 340.454456 -217.903851) (xy 340.45398 -217.878406) (xy 340.175088 -217.878406)
			(xy 340.174579 -217.904373) (xy 340.166454 -217.955668) (xy 340.150406 -218.005061) (xy 340.126828 -218.051335)
			(xy 340.096302 -218.093351) (xy 340.059579 -218.130074) (xy 340.017563 -218.1606) (xy 339.971289 -218.184178)
			(xy 339.921896 -218.200226) (xy 339.870601 -218.208351) (xy 339.818667 -218.208351) (xy 339.767372 -218.200226)
			(xy 339.717979 -218.184178) (xy 339.671705 -218.1606) (xy 339.629689 -218.130074) (xy 339.592966 -218.093351)
			(xy 339.56244 -218.051335) (xy 339.538862 -218.005061) (xy 339.522814 -217.955668) (xy 339.514689 -217.904373)
			(xy 339.51418 -217.878406) (xy 339.514655 -217.85296) (xy 339.522468 -217.802672) (xy 339.537895 -217.754174)
			(xy 339.560571 -217.708614) (xy 339.58996 -217.667066) (xy 339.625369 -217.630512) (xy 339.665962 -217.599816)
			(xy 339.710778 -217.575703) (xy 339.75876 -217.558742) (xy 339.783674 -217.55354) (xy 339.806534 -217.549222)
			(xy 340.010242 -217.196162) (xy 340.002622 -217.174064) (xy 339.994587 -217.149728) (xy 339.985276 -217.099334)
			(xy 339.98408 -217.073734) (xy 339.98307 -217.058033) (xy 339.972703 -217.028346) (xy 339.953804 -217.003213)
			(xy 339.928163 -216.985011) (xy 339.898203 -216.975462) (xy 339.88248 -216.974928) (xy 339.806534 -216.974928)
			(xy 339.790822 -216.975519) (xy 339.760885 -216.985076) (xy 339.735262 -217.00327) (xy 339.71637 -217.028383)
			(xy 339.705991 -217.058045) (xy 339.704934 -217.073734) (xy 339.703736 -217.099199) (xy 339.694475 -217.149327)
			(xy 339.677623 -217.197438) (xy 339.65358 -217.242389) (xy 339.622917 -217.283113) (xy 339.586361 -217.318642)
			(xy 339.544782 -217.348135) (xy 339.499165 -217.370889) (xy 339.450594 -217.386366) (xy 339.400222 -217.394197)
			(xy 339.349246 -217.394197) (xy 339.298874 -217.386366) (xy 339.250303 -217.370889) (xy 339.204686 -217.348135)
			(xy 339.163107 -217.318642) (xy 339.126551 -217.283113) (xy 339.095888 -217.242389) (xy 339.071845 -217.197438)
			(xy 339.054993 -217.149327) (xy 339.045732 -217.099199) (xy 339.044534 -217.073734) (xy 339.043523 -217.058036)
			(xy 339.033155 -217.028355) (xy 339.014255 -217.00323) (xy 338.988613 -216.985038) (xy 338.958654 -216.975501)
			(xy 338.942934 -216.974928) (xy 338.86648 -216.974928) (xy 338.850763 -216.975512) (xy 338.820814 -216.985062)
			(xy 338.795179 -217.003253) (xy 338.776277 -217.02837) (xy 338.765892 -217.058039) (xy 338.76488 -217.073734)
			(xy 338.763711 -217.098629) (xy 338.754818 -217.147667) (xy 338.73867 -217.194816) (xy 338.715633 -217.239009)
			(xy 338.686227 -217.279247) (xy 338.651118 -217.314618) (xy 338.6111 -217.344323) (xy 338.56708 -217.367689)
			(xy 338.520052 -217.384188) (xy 338.49564 -217.389202) (xy 338.47278 -217.39352) (xy 338.269072 -217.74658)
			(xy 338.276692 -217.768678) (xy 338.285485 -217.795252) (xy 338.294934 -217.85042) (xy 338.295488 -217.878406)
			(xy 338.57438 -217.878406) (xy 338.574889 -217.852439) (xy 338.583014 -217.801144) (xy 338.599062 -217.751751)
			(xy 338.62264 -217.705477) (xy 338.653166 -217.663461) (xy 338.689889 -217.626738) (xy 338.731905 -217.596212)
			(xy 338.778179 -217.572634) (xy 338.827572 -217.556586) (xy 338.878867 -217.548461) (xy 338.930801 -217.548461)
			(xy 338.982096 -217.556586) (xy 339.031489 -217.572634) (xy 339.077763 -217.596212) (xy 339.119779 -217.626738)
			(xy 339.156502 -217.663461) (xy 339.187028 -217.705477) (xy 339.210606 -217.751751) (xy 339.226654 -217.801144)
			(xy 339.234779 -217.852439) (xy 339.235288 -217.878406) (xy 339.234737 -217.906392) (xy 339.225286 -217.96156)
			(xy 339.216492 -217.988134) (xy 339.208872 -218.010232) (xy 339.41258 -218.363038) (xy 339.43544 -218.367356)
			(xy 339.460359 -218.372533) (xy 339.508343 -218.389497) (xy 339.55316 -218.413614) (xy 339.593752 -218.444313)
			(xy 339.629161 -218.48087) (xy 339.65855 -218.522421) (xy 339.681224 -218.567984) (xy 339.696649 -218.616484)
			(xy 339.70446 -218.666775) (xy 339.704934 -218.692222) (xy 339.704425 -218.718189) (xy 339.6963 -218.769484)
			(xy 339.680252 -218.818877) (xy 339.656674 -218.865151) (xy 339.626148 -218.907167) (xy 339.589425 -218.94389)
			(xy 339.547409 -218.974416) (xy 339.501135 -218.997994) (xy 339.451742 -219.014042) (xy 339.400447 -219.022167)
			(xy 339.348513 -219.022167) (xy 339.297218 -219.014042) (xy 339.247825 -218.997994) (xy 339.201551 -218.974416)
			(xy 339.159535 -218.94389) (xy 339.122812 -218.907167) (xy 339.092286 -218.865151) (xy 339.068708 -218.818877)
			(xy 339.05266 -218.769484) (xy 339.044535 -218.718189) (xy 339.044026 -218.692222) (xy 339.044583 -218.664236)
			(xy 339.05403 -218.609068) (xy 339.062822 -218.582494) (xy 339.070442 -218.560396) (xy 338.866734 -218.20759)
			(xy 338.843874 -218.203272) (xy 338.818963 -218.198058) (xy 338.770982 -218.181098) (xy 338.726166 -218.156986)
			(xy 338.685574 -218.126292) (xy 338.650165 -218.08974) (xy 338.620775 -218.048193) (xy 338.598098 -218.002634)
			(xy 338.582671 -217.954138) (xy 338.574856 -217.903851) (xy 338.57438 -217.878406) (xy 338.295488 -217.878406)
			(xy 338.294979 -217.904373) (xy 338.286854 -217.955668) (xy 338.270806 -218.005061) (xy 338.247228 -218.051335)
			(xy 338.216702 -218.093351) (xy 338.179979 -218.130074) (xy 338.137963 -218.1606) (xy 338.091689 -218.184178)
			(xy 338.042296 -218.200226) (xy 337.991001 -218.208351) (xy 337.939067 -218.208351) (xy 337.887772 -218.200226)
			(xy 337.838379 -218.184178) (xy 337.792105 -218.1606) (xy 337.750089 -218.130074) (xy 337.713366 -218.093351)
			(xy 337.68284 -218.051335) (xy 337.659262 -218.005061) (xy 337.643214 -217.955668) (xy 337.635089 -217.904373)
			(xy 337.63458 -217.878406) (xy 337.635055 -217.85296) (xy 337.642868 -217.802672) (xy 337.658295 -217.754174)
			(xy 337.680971 -217.708614) (xy 337.71036 -217.667066) (xy 337.745769 -217.630512) (xy 337.786362 -217.599816)
			(xy 337.831178 -217.575703) (xy 337.87916 -217.558742) (xy 337.904074 -217.55354) (xy 337.926934 -217.549222)
			(xy 338.130642 -217.196162) (xy 338.123022 -217.174064) (xy 338.114987 -217.149728) (xy 338.105676 -217.099334)
			(xy 338.10448 -217.073734) (xy 338.10347 -217.058033) (xy 338.093103 -217.028346) (xy 338.074204 -217.003213)
			(xy 338.048563 -216.985011) (xy 338.018603 -216.975462) (xy 338.00288 -216.974928) (xy 337.926934 -216.974928)
			(xy 337.911222 -216.975519) (xy 337.881285 -216.985076) (xy 337.855662 -217.00327) (xy 337.83677 -217.028383)
			(xy 337.826391 -217.058045) (xy 337.825334 -217.073734) (xy 337.824136 -217.099199) (xy 337.814875 -217.149327)
			(xy 337.798023 -217.197438) (xy 337.77398 -217.242389) (xy 337.743317 -217.283113) (xy 337.706761 -217.318642)
			(xy 337.665182 -217.348135) (xy 337.619565 -217.370889) (xy 337.570994 -217.386366) (xy 337.520622 -217.394197)
			(xy 337.469646 -217.394197) (xy 337.419274 -217.386366) (xy 337.370703 -217.370889) (xy 337.325086 -217.348135)
			(xy 337.283507 -217.318642) (xy 337.246951 -217.283113) (xy 337.216288 -217.242389) (xy 337.192245 -217.197438)
			(xy 337.175393 -217.149327) (xy 337.166132 -217.099199) (xy 337.164934 -217.073734) (xy 337.163923 -217.058036)
			(xy 337.153555 -217.028355) (xy 337.134655 -217.00323) (xy 337.109013 -216.985038) (xy 337.079054 -216.975501)
			(xy 337.063334 -216.974928) (xy 336.98688 -216.974928) (xy 336.971163 -216.975512) (xy 336.941214 -216.985062)
			(xy 336.915579 -217.003253) (xy 336.896677 -217.02837) (xy 336.886292 -217.058039) (xy 336.88528 -217.073734)
			(xy 336.884073 -217.099197) (xy 336.874798 -217.14932) (xy 336.857936 -217.197425) (xy 336.833889 -217.242371)
			(xy 336.803227 -217.283092) (xy 336.766676 -217.318622) (xy 336.725104 -217.34812) (xy 336.679495 -217.370885)
			(xy 336.630933 -217.386378) (xy 336.580567 -217.394232) (xy 336.55508 -217.39479) (xy 336.528877 -217.394287)
			(xy 336.477128 -217.386011) (xy 336.427335 -217.369669) (xy 336.380746 -217.345671) (xy 336.338529 -217.31462)
			(xy 336.301744 -217.277294) (xy 336.271312 -217.234628) (xy 336.25917 -217.211402) (xy 336.252627 -217.199282)
			(xy 336.234216 -217.178811) (xy 336.211005 -217.164004) (xy 336.184681 -217.155937) (xy 336.157159 -217.155197)
			(xy 336.13044 -217.161837) (xy 336.106467 -217.175375) (xy 336.096356 -217.184732) (xy 335.54924 -217.731848)
			(xy 335.54924 -217.904373) (xy 335.755489 -217.904373) (xy 335.755489 -217.852439) (xy 335.763614 -217.801144)
			(xy 335.779662 -217.751751) (xy 335.80324 -217.705477) (xy 335.833766 -217.663461) (xy 335.870489 -217.626738)
			(xy 335.912505 -217.596212) (xy 335.958779 -217.572634) (xy 336.008172 -217.556586) (xy 336.059467 -217.548461)
			(xy 336.111401 -217.548461) (xy 336.162696 -217.556586) (xy 336.212089 -217.572634) (xy 336.258363 -217.596212)
			(xy 336.300379 -217.626738) (xy 336.337102 -217.663461) (xy 336.367628 -217.705477) (xy 336.391206 -217.751751)
			(xy 336.407254 -217.801144) (xy 336.415379 -217.852439) (xy 336.415888 -217.878406) (xy 336.69478 -217.878406)
			(xy 336.695289 -217.852439) (xy 336.703414 -217.801144) (xy 336.719462 -217.751751) (xy 336.74304 -217.705477)
			(xy 336.773566 -217.663461) (xy 336.810289 -217.626738) (xy 336.852305 -217.596212) (xy 336.898579 -217.572634)
			(xy 336.947972 -217.556586) (xy 336.999267 -217.548461) (xy 337.051201 -217.548461) (xy 337.102496 -217.556586)
			(xy 337.151889 -217.572634) (xy 337.198163 -217.596212) (xy 337.240179 -217.626738) (xy 337.276902 -217.663461)
			(xy 337.307428 -217.705477) (xy 337.331006 -217.751751) (xy 337.347054 -217.801144) (xy 337.355179 -217.852439)
			(xy 337.355688 -217.878406) (xy 337.355137 -217.906392) (xy 337.345686 -217.96156) (xy 337.336892 -217.988134)
			(xy 337.329272 -218.010232) (xy 337.53298 -218.363038) (xy 337.55584 -218.367356) (xy 337.580759 -218.372533)
			(xy 337.628743 -218.389497) (xy 337.67356 -218.413614) (xy 337.714152 -218.444313) (xy 337.749561 -218.48087)
			(xy 337.77895 -218.522421) (xy 337.801624 -218.567984) (xy 337.817049 -218.616484) (xy 337.82486 -218.666775)
			(xy 337.825334 -218.692222) (xy 337.824825 -218.718189) (xy 337.8167 -218.769484) (xy 337.800652 -218.818877)
			(xy 337.777074 -218.865151) (xy 337.746548 -218.907167) (xy 337.709825 -218.94389) (xy 337.667809 -218.974416)
			(xy 337.621535 -218.997994) (xy 337.572142 -219.014042) (xy 337.520847 -219.022167) (xy 337.468913 -219.022167)
			(xy 337.417618 -219.014042) (xy 337.368225 -218.997994) (xy 337.321951 -218.974416) (xy 337.279935 -218.94389)
			(xy 337.243212 -218.907167) (xy 337.212686 -218.865151) (xy 337.189108 -218.818877) (xy 337.17306 -218.769484)
			(xy 337.164935 -218.718189) (xy 337.164426 -218.692222) (xy 337.164983 -218.664236) (xy 337.17443 -218.609068)
			(xy 337.183222 -218.582494) (xy 337.190842 -218.560396) (xy 336.987134 -218.20759) (xy 336.964274 -218.203272)
			(xy 336.939363 -218.198058) (xy 336.891382 -218.181098) (xy 336.846566 -218.156986) (xy 336.805974 -218.126292)
			(xy 336.770565 -218.08974) (xy 336.741175 -218.048193) (xy 336.718498 -218.002634) (xy 336.703071 -217.954138)
			(xy 336.695256 -217.903851) (xy 336.69478 -217.878406) (xy 336.415888 -217.878406) (xy 336.415379 -217.904373)
			(xy 336.407254 -217.955668) (xy 336.391206 -218.005061) (xy 336.367628 -218.051335) (xy 336.337102 -218.093351)
			(xy 336.300379 -218.130074) (xy 336.258363 -218.1606) (xy 336.212089 -218.184178) (xy 336.162696 -218.200226)
			(xy 336.111401 -218.208351) (xy 336.059467 -218.208351) (xy 336.008172 -218.200226) (xy 335.958779 -218.184178)
			(xy 335.912505 -218.1606) (xy 335.870489 -218.130074) (xy 335.833766 -218.093351) (xy 335.80324 -218.051335)
			(xy 335.779662 -218.005061) (xy 335.763614 -217.955668) (xy 335.755489 -217.904373) (xy 335.54924 -217.904373)
			(xy 335.54924 -218.261692) (xy 335.549833 -218.27682) (xy 335.558765 -218.305731) (xy 335.575761 -218.330766)
			(xy 335.599335 -218.349736) (xy 335.627427 -218.360983) (xy 335.642458 -218.362784) (xy 335.668249 -218.365401)
			(xy 335.718619 -218.377643) (xy 335.76646 -218.397598) (xy 335.8106 -218.424776) (xy 335.849956 -218.458512)
			(xy 335.883563 -218.497979) (xy 335.910597 -218.542208) (xy 335.930394 -218.590114) (xy 335.94247 -218.640525)
			(xy 335.946528 -218.692202) (xy 335.942469 -218.743879) (xy 335.930393 -218.794289) (xy 335.910595 -218.842196)
			(xy 335.883561 -218.886424) (xy 335.849954 -218.92589) (xy 335.810597 -218.959626) (xy 335.766457 -218.986804)
			(xy 335.718615 -219.006758) (xy 335.668245 -219.018999) (xy 335.642458 -219.02166) (xy 335.627424 -219.023457)
			(xy 335.599321 -219.034678) (xy 335.575744 -219.053647) (xy 335.558766 -219.078696) (xy 335.549879 -219.107622)
			(xy 335.54924 -219.122752) (xy 335.54924 -219.532005) (xy 335.755489 -219.532005) (xy 335.755489 -219.480071)
			(xy 335.763614 -219.428776) (xy 335.779662 -219.379383) (xy 335.80324 -219.333109) (xy 335.833766 -219.291093)
			(xy 335.870489 -219.25437) (xy 335.912505 -219.223844) (xy 335.958779 -219.200266) (xy 336.008172 -219.184218)
			(xy 336.059467 -219.176093) (xy 336.111401 -219.176093) (xy 336.162696 -219.184218) (xy 336.212089 -219.200266)
			(xy 336.258363 -219.223844) (xy 336.300379 -219.25437) (xy 336.337102 -219.291093) (xy 336.367628 -219.333109)
			(xy 336.391206 -219.379383) (xy 336.407254 -219.428776) (xy 336.415379 -219.480071) (xy 336.415888 -219.506038)
			(xy 336.415379 -219.532005) (xy 336.695289 -219.532005) (xy 336.695289 -219.480071) (xy 336.703414 -219.428776)
			(xy 336.719462 -219.379383) (xy 336.74304 -219.333109) (xy 336.773566 -219.291093) (xy 336.810289 -219.25437)
			(xy 336.852305 -219.223844) (xy 336.898579 -219.200266) (xy 336.947972 -219.184218) (xy 336.999267 -219.176093)
			(xy 337.051201 -219.176093) (xy 337.102496 -219.184218) (xy 337.151889 -219.200266) (xy 337.198163 -219.223844)
			(xy 337.240179 -219.25437) (xy 337.276902 -219.291093) (xy 337.307428 -219.333109) (xy 337.331006 -219.379383)
			(xy 337.347054 -219.428776) (xy 337.355179 -219.480071) (xy 337.355688 -219.506038) (xy 337.355179 -219.532005)
			(xy 337.635089 -219.532005) (xy 337.635089 -219.480071) (xy 337.643214 -219.428776) (xy 337.659262 -219.379383)
			(xy 337.68284 -219.333109) (xy 337.713366 -219.291093) (xy 337.750089 -219.25437) (xy 337.792105 -219.223844)
			(xy 337.838379 -219.200266) (xy 337.887772 -219.184218) (xy 337.939067 -219.176093) (xy 337.991001 -219.176093)
			(xy 338.042296 -219.184218) (xy 338.091689 -219.200266) (xy 338.137963 -219.223844) (xy 338.179979 -219.25437)
			(xy 338.216702 -219.291093) (xy 338.247228 -219.333109) (xy 338.270806 -219.379383) (xy 338.286854 -219.428776)
			(xy 338.294979 -219.480071) (xy 338.295488 -219.506038) (xy 338.294979 -219.532005) (xy 338.574889 -219.532005)
			(xy 338.574889 -219.480071) (xy 338.583014 -219.428776) (xy 338.599062 -219.379383) (xy 338.62264 -219.333109)
			(xy 338.653166 -219.291093) (xy 338.689889 -219.25437) (xy 338.731905 -219.223844) (xy 338.778179 -219.200266)
			(xy 338.827572 -219.184218) (xy 338.878867 -219.176093) (xy 338.930801 -219.176093) (xy 338.982096 -219.184218)
			(xy 339.031489 -219.200266) (xy 339.077763 -219.223844) (xy 339.119779 -219.25437) (xy 339.156502 -219.291093)
			(xy 339.187028 -219.333109) (xy 339.210606 -219.379383) (xy 339.226654 -219.428776) (xy 339.234779 -219.480071)
			(xy 339.235288 -219.506038) (xy 339.234779 -219.532005) (xy 339.514689 -219.532005) (xy 339.514689 -219.480071)
			(xy 339.522814 -219.428776) (xy 339.538862 -219.379383) (xy 339.56244 -219.333109) (xy 339.592966 -219.291093)
			(xy 339.629689 -219.25437) (xy 339.671705 -219.223844) (xy 339.717979 -219.200266) (xy 339.767372 -219.184218)
			(xy 339.818667 -219.176093) (xy 339.870601 -219.176093) (xy 339.921896 -219.184218) (xy 339.971289 -219.200266)
			(xy 340.017563 -219.223844) (xy 340.059579 -219.25437) (xy 340.096302 -219.291093) (xy 340.126828 -219.333109)
			(xy 340.150406 -219.379383) (xy 340.166454 -219.428776) (xy 340.174579 -219.480071) (xy 340.175088 -219.506038)
			(xy 340.174579 -219.532005) (xy 340.454489 -219.532005) (xy 340.454489 -219.480071) (xy 340.462614 -219.428776)
			(xy 340.478662 -219.379383) (xy 340.50224 -219.333109) (xy 340.532766 -219.291093) (xy 340.569489 -219.25437)
			(xy 340.611505 -219.223844) (xy 340.657779 -219.200266) (xy 340.707172 -219.184218) (xy 340.758467 -219.176093)
			(xy 340.810401 -219.176093) (xy 340.861696 -219.184218) (xy 340.911089 -219.200266) (xy 340.957363 -219.223844)
			(xy 340.999379 -219.25437) (xy 341.036102 -219.291093) (xy 341.066628 -219.333109) (xy 341.090206 -219.379383)
			(xy 341.106254 -219.428776) (xy 341.114379 -219.480071) (xy 341.114888 -219.506038) (xy 341.114379 -219.532005)
			(xy 341.394289 -219.532005) (xy 341.394289 -219.480071) (xy 341.402414 -219.428776) (xy 341.418462 -219.379383)
			(xy 341.44204 -219.333109) (xy 341.472566 -219.291093) (xy 341.509289 -219.25437) (xy 341.551305 -219.223844)
			(xy 341.597579 -219.200266) (xy 341.646972 -219.184218) (xy 341.698267 -219.176093) (xy 341.750201 -219.176093)
			(xy 341.801496 -219.184218) (xy 341.850889 -219.200266) (xy 341.897163 -219.223844) (xy 341.939179 -219.25437)
			(xy 341.975902 -219.291093) (xy 342.006428 -219.333109) (xy 342.030006 -219.379383) (xy 342.046054 -219.428776)
			(xy 342.054179 -219.480071) (xy 342.054688 -219.506038) (xy 342.054179 -219.532005) (xy 342.334089 -219.532005)
			(xy 342.334089 -219.480071) (xy 342.342214 -219.428776) (xy 342.358262 -219.379383) (xy 342.38184 -219.333109)
			(xy 342.412366 -219.291093) (xy 342.449089 -219.25437) (xy 342.491105 -219.223844) (xy 342.537379 -219.200266)
			(xy 342.586772 -219.184218) (xy 342.638067 -219.176093) (xy 342.690001 -219.176093) (xy 342.741296 -219.184218)
			(xy 342.790689 -219.200266) (xy 342.836963 -219.223844) (xy 342.878979 -219.25437) (xy 342.915702 -219.291093)
			(xy 342.946228 -219.333109) (xy 342.969806 -219.379383) (xy 342.985854 -219.428776) (xy 342.993979 -219.480071)
			(xy 342.994488 -219.506038) (xy 342.993979 -219.532005) (xy 343.273889 -219.532005) (xy 343.273889 -219.480071)
			(xy 343.282014 -219.428776) (xy 343.298062 -219.379383) (xy 343.32164 -219.333109) (xy 343.352166 -219.291093)
			(xy 343.388889 -219.25437) (xy 343.430905 -219.223844) (xy 343.477179 -219.200266) (xy 343.526572 -219.184218)
			(xy 343.577867 -219.176093) (xy 343.629801 -219.176093) (xy 343.681096 -219.184218) (xy 343.730489 -219.200266)
			(xy 343.776763 -219.223844) (xy 343.818779 -219.25437) (xy 343.855502 -219.291093) (xy 343.886028 -219.333109)
			(xy 343.909606 -219.379383) (xy 343.925654 -219.428776) (xy 343.933779 -219.480071) (xy 343.934288 -219.506038)
			(xy 343.933779 -219.532005) (xy 344.213689 -219.532005) (xy 344.213689 -219.480071) (xy 344.221814 -219.428776)
			(xy 344.237862 -219.379383) (xy 344.26144 -219.333109) (xy 344.291966 -219.291093) (xy 344.328689 -219.25437)
			(xy 344.370705 -219.223844) (xy 344.416979 -219.200266) (xy 344.466372 -219.184218) (xy 344.517667 -219.176093)
			(xy 344.569601 -219.176093) (xy 344.620896 -219.184218) (xy 344.670289 -219.200266) (xy 344.716563 -219.223844)
			(xy 344.758579 -219.25437) (xy 344.795302 -219.291093) (xy 344.825828 -219.333109) (xy 344.849406 -219.379383)
			(xy 344.865454 -219.428776) (xy 344.873579 -219.480071) (xy 344.874088 -219.506038) (xy 344.873579 -219.532005)
			(xy 345.153489 -219.532005) (xy 345.153489 -219.480071) (xy 345.161614 -219.428776) (xy 345.177662 -219.379383)
			(xy 345.20124 -219.333109) (xy 345.231766 -219.291093) (xy 345.268489 -219.25437) (xy 345.310505 -219.223844)
			(xy 345.356779 -219.200266) (xy 345.406172 -219.184218) (xy 345.457467 -219.176093) (xy 345.509401 -219.176093)
			(xy 345.560696 -219.184218) (xy 345.610089 -219.200266) (xy 345.656363 -219.223844) (xy 345.698379 -219.25437)
			(xy 345.735102 -219.291093) (xy 345.765628 -219.333109) (xy 345.789206 -219.379383) (xy 345.805254 -219.428776)
			(xy 345.813379 -219.480071) (xy 345.813888 -219.506038) (xy 345.813379 -219.532005) (xy 346.093289 -219.532005)
			(xy 346.093289 -219.480071) (xy 346.101414 -219.428776) (xy 346.117462 -219.379383) (xy 346.14104 -219.333109)
			(xy 346.171566 -219.291093) (xy 346.208289 -219.25437) (xy 346.250305 -219.223844) (xy 346.296579 -219.200266)
			(xy 346.345972 -219.184218) (xy 346.397267 -219.176093) (xy 346.449201 -219.176093) (xy 346.500496 -219.184218)
			(xy 346.549889 -219.200266) (xy 346.596163 -219.223844) (xy 346.638179 -219.25437) (xy 346.674902 -219.291093)
			(xy 346.705428 -219.333109) (xy 346.729006 -219.379383) (xy 346.745054 -219.428776) (xy 346.753179 -219.480071)
			(xy 346.753688 -219.506038) (xy 346.753179 -219.532005) (xy 347.033089 -219.532005) (xy 347.033089 -219.480071)
			(xy 347.041214 -219.428776) (xy 347.057262 -219.379383) (xy 347.08084 -219.333109) (xy 347.111366 -219.291093)
			(xy 347.148089 -219.25437) (xy 347.190105 -219.223844) (xy 347.236379 -219.200266) (xy 347.285772 -219.184218)
			(xy 347.337067 -219.176093) (xy 347.389001 -219.176093) (xy 347.440296 -219.184218) (xy 347.489689 -219.200266)
			(xy 347.535963 -219.223844) (xy 347.577979 -219.25437) (xy 347.614702 -219.291093) (xy 347.645228 -219.333109)
			(xy 347.668806 -219.379383) (xy 347.684854 -219.428776) (xy 347.692979 -219.480071) (xy 347.693488 -219.506038)
			(xy 347.692979 -219.532005) (xy 347.972889 -219.532005) (xy 347.972889 -219.480071) (xy 347.981014 -219.428776)
			(xy 347.997062 -219.379383) (xy 348.02064 -219.333109) (xy 348.051166 -219.291093) (xy 348.087889 -219.25437)
			(xy 348.129905 -219.223844) (xy 348.176179 -219.200266) (xy 348.225572 -219.184218) (xy 348.276867 -219.176093)
			(xy 348.328801 -219.176093) (xy 348.380096 -219.184218) (xy 348.429489 -219.200266) (xy 348.475763 -219.223844)
			(xy 348.517779 -219.25437) (xy 348.554502 -219.291093) (xy 348.585028 -219.333109) (xy 348.608606 -219.379383)
			(xy 348.624654 -219.428776) (xy 348.632779 -219.480071) (xy 348.633288 -219.506038) (xy 348.632779 -219.532005)
			(xy 348.624654 -219.5833) (xy 348.608606 -219.632693) (xy 348.585028 -219.678967) (xy 348.554502 -219.720983)
			(xy 348.517779 -219.757706) (xy 348.475763 -219.788232) (xy 348.429489 -219.81181) (xy 348.380096 -219.827858)
			(xy 348.328801 -219.835983) (xy 348.276867 -219.835983) (xy 348.225572 -219.827858) (xy 348.176179 -219.81181)
			(xy 348.129905 -219.788232) (xy 348.087889 -219.757706) (xy 348.051166 -219.720983) (xy 348.02064 -219.678967)
			(xy 347.997062 -219.632693) (xy 347.981014 -219.5833) (xy 347.972889 -219.532005) (xy 347.692979 -219.532005)
			(xy 347.684854 -219.5833) (xy 347.668806 -219.632693) (xy 347.645228 -219.678967) (xy 347.614702 -219.720983)
			(xy 347.577979 -219.757706) (xy 347.535963 -219.788232) (xy 347.489689 -219.81181) (xy 347.440296 -219.827858)
			(xy 347.389001 -219.835983) (xy 347.337067 -219.835983) (xy 347.285772 -219.827858) (xy 347.236379 -219.81181)
			(xy 347.190105 -219.788232) (xy 347.148089 -219.757706) (xy 347.111366 -219.720983) (xy 347.08084 -219.678967)
			(xy 347.057262 -219.632693) (xy 347.041214 -219.5833) (xy 347.033089 -219.532005) (xy 346.753179 -219.532005)
			(xy 346.745054 -219.5833) (xy 346.729006 -219.632693) (xy 346.705428 -219.678967) (xy 346.674902 -219.720983)
			(xy 346.638179 -219.757706) (xy 346.596163 -219.788232) (xy 346.549889 -219.81181) (xy 346.500496 -219.827858)
			(xy 346.449201 -219.835983) (xy 346.397267 -219.835983) (xy 346.345972 -219.827858) (xy 346.296579 -219.81181)
			(xy 346.250305 -219.788232) (xy 346.208289 -219.757706) (xy 346.171566 -219.720983) (xy 346.14104 -219.678967)
			(xy 346.117462 -219.632693) (xy 346.101414 -219.5833) (xy 346.093289 -219.532005) (xy 345.813379 -219.532005)
			(xy 345.805254 -219.5833) (xy 345.789206 -219.632693) (xy 345.765628 -219.678967) (xy 345.735102 -219.720983)
			(xy 345.698379 -219.757706) (xy 345.656363 -219.788232) (xy 345.610089 -219.81181) (xy 345.560696 -219.827858)
			(xy 345.509401 -219.835983) (xy 345.457467 -219.835983) (xy 345.406172 -219.827858) (xy 345.356779 -219.81181)
			(xy 345.310505 -219.788232) (xy 345.268489 -219.757706) (xy 345.231766 -219.720983) (xy 345.20124 -219.678967)
			(xy 345.177662 -219.632693) (xy 345.161614 -219.5833) (xy 345.153489 -219.532005) (xy 344.873579 -219.532005)
			(xy 344.865454 -219.5833) (xy 344.849406 -219.632693) (xy 344.825828 -219.678967) (xy 344.795302 -219.720983)
			(xy 344.758579 -219.757706) (xy 344.716563 -219.788232) (xy 344.670289 -219.81181) (xy 344.620896 -219.827858)
			(xy 344.569601 -219.835983) (xy 344.517667 -219.835983) (xy 344.466372 -219.827858) (xy 344.416979 -219.81181)
			(xy 344.370705 -219.788232) (xy 344.328689 -219.757706) (xy 344.291966 -219.720983) (xy 344.26144 -219.678967)
			(xy 344.237862 -219.632693) (xy 344.221814 -219.5833) (xy 344.213689 -219.532005) (xy 343.933779 -219.532005)
			(xy 343.925654 -219.5833) (xy 343.909606 -219.632693) (xy 343.886028 -219.678967) (xy 343.855502 -219.720983)
			(xy 343.818779 -219.757706) (xy 343.776763 -219.788232) (xy 343.730489 -219.81181) (xy 343.681096 -219.827858)
			(xy 343.629801 -219.835983) (xy 343.577867 -219.835983) (xy 343.526572 -219.827858) (xy 343.477179 -219.81181)
			(xy 343.430905 -219.788232) (xy 343.388889 -219.757706) (xy 343.352166 -219.720983) (xy 343.32164 -219.678967)
			(xy 343.298062 -219.632693) (xy 343.282014 -219.5833) (xy 343.273889 -219.532005) (xy 342.993979 -219.532005)
			(xy 342.985854 -219.5833) (xy 342.969806 -219.632693) (xy 342.946228 -219.678967) (xy 342.915702 -219.720983)
			(xy 342.878979 -219.757706) (xy 342.836963 -219.788232) (xy 342.790689 -219.81181) (xy 342.741296 -219.827858)
			(xy 342.690001 -219.835983) (xy 342.638067 -219.835983) (xy 342.586772 -219.827858) (xy 342.537379 -219.81181)
			(xy 342.491105 -219.788232) (xy 342.449089 -219.757706) (xy 342.412366 -219.720983) (xy 342.38184 -219.678967)
			(xy 342.358262 -219.632693) (xy 342.342214 -219.5833) (xy 342.334089 -219.532005) (xy 342.054179 -219.532005)
			(xy 342.046054 -219.5833) (xy 342.030006 -219.632693) (xy 342.006428 -219.678967) (xy 341.975902 -219.720983)
			(xy 341.939179 -219.757706) (xy 341.897163 -219.788232) (xy 341.850889 -219.81181) (xy 341.801496 -219.827858)
			(xy 341.750201 -219.835983) (xy 341.698267 -219.835983) (xy 341.646972 -219.827858) (xy 341.597579 -219.81181)
			(xy 341.551305 -219.788232) (xy 341.509289 -219.757706) (xy 341.472566 -219.720983) (xy 341.44204 -219.678967)
			(xy 341.418462 -219.632693) (xy 341.402414 -219.5833) (xy 341.394289 -219.532005) (xy 341.114379 -219.532005)
			(xy 341.106254 -219.5833) (xy 341.090206 -219.632693) (xy 341.066628 -219.678967) (xy 341.036102 -219.720983)
			(xy 340.999379 -219.757706) (xy 340.957363 -219.788232) (xy 340.911089 -219.81181) (xy 340.861696 -219.827858)
			(xy 340.810401 -219.835983) (xy 340.758467 -219.835983) (xy 340.707172 -219.827858) (xy 340.657779 -219.81181)
			(xy 340.611505 -219.788232) (xy 340.569489 -219.757706) (xy 340.532766 -219.720983) (xy 340.50224 -219.678967)
			(xy 340.478662 -219.632693) (xy 340.462614 -219.5833) (xy 340.454489 -219.532005) (xy 340.174579 -219.532005)
			(xy 340.166454 -219.5833) (xy 340.150406 -219.632693) (xy 340.126828 -219.678967) (xy 340.096302 -219.720983)
			(xy 340.059579 -219.757706) (xy 340.017563 -219.788232) (xy 339.971289 -219.81181) (xy 339.921896 -219.827858)
			(xy 339.870601 -219.835983) (xy 339.818667 -219.835983) (xy 339.767372 -219.827858) (xy 339.717979 -219.81181)
			(xy 339.671705 -219.788232) (xy 339.629689 -219.757706) (xy 339.592966 -219.720983) (xy 339.56244 -219.678967)
			(xy 339.538862 -219.632693) (xy 339.522814 -219.5833) (xy 339.514689 -219.532005) (xy 339.234779 -219.532005)
			(xy 339.226654 -219.5833) (xy 339.210606 -219.632693) (xy 339.187028 -219.678967) (xy 339.156502 -219.720983)
			(xy 339.119779 -219.757706) (xy 339.077763 -219.788232) (xy 339.031489 -219.81181) (xy 338.982096 -219.827858)
			(xy 338.930801 -219.835983) (xy 338.878867 -219.835983) (xy 338.827572 -219.827858) (xy 338.778179 -219.81181)
			(xy 338.731905 -219.788232) (xy 338.689889 -219.757706) (xy 338.653166 -219.720983) (xy 338.62264 -219.678967)
			(xy 338.599062 -219.632693) (xy 338.583014 -219.5833) (xy 338.574889 -219.532005) (xy 338.294979 -219.532005)
			(xy 338.286854 -219.5833) (xy 338.270806 -219.632693) (xy 338.247228 -219.678967) (xy 338.216702 -219.720983)
			(xy 338.179979 -219.757706) (xy 338.137963 -219.788232) (xy 338.091689 -219.81181) (xy 338.042296 -219.827858)
			(xy 337.991001 -219.835983) (xy 337.939067 -219.835983) (xy 337.887772 -219.827858) (xy 337.838379 -219.81181)
			(xy 337.792105 -219.788232) (xy 337.750089 -219.757706) (xy 337.713366 -219.720983) (xy 337.68284 -219.678967)
			(xy 337.659262 -219.632693) (xy 337.643214 -219.5833) (xy 337.635089 -219.532005) (xy 337.355179 -219.532005)
			(xy 337.347054 -219.5833) (xy 337.331006 -219.632693) (xy 337.307428 -219.678967) (xy 337.276902 -219.720983)
			(xy 337.240179 -219.757706) (xy 337.198163 -219.788232) (xy 337.151889 -219.81181) (xy 337.102496 -219.827858)
			(xy 337.051201 -219.835983) (xy 336.999267 -219.835983) (xy 336.947972 -219.827858) (xy 336.898579 -219.81181)
			(xy 336.852305 -219.788232) (xy 336.810289 -219.757706) (xy 336.773566 -219.720983) (xy 336.74304 -219.678967)
			(xy 336.719462 -219.632693) (xy 336.703414 -219.5833) (xy 336.695289 -219.532005) (xy 336.415379 -219.532005)
			(xy 336.407254 -219.5833) (xy 336.391206 -219.632693) (xy 336.367628 -219.678967) (xy 336.337102 -219.720983)
			(xy 336.300379 -219.757706) (xy 336.258363 -219.788232) (xy 336.212089 -219.81181) (xy 336.162696 -219.827858)
			(xy 336.111401 -219.835983) (xy 336.059467 -219.835983) (xy 336.008172 -219.827858) (xy 335.958779 -219.81181)
			(xy 335.912505 -219.788232) (xy 335.870489 -219.757706) (xy 335.833766 -219.720983) (xy 335.80324 -219.678967)
			(xy 335.779662 -219.632693) (xy 335.763614 -219.5833) (xy 335.755489 -219.532005) (xy 335.54924 -219.532005)
			(xy 335.54924 -220.345821) (xy 336.225389 -220.345821) (xy 336.225389 -220.293887) (xy 336.233514 -220.242592)
			(xy 336.249562 -220.193199) (xy 336.27314 -220.146925) (xy 336.303666 -220.104909) (xy 336.340389 -220.068186)
			(xy 336.382405 -220.03766) (xy 336.428679 -220.014082) (xy 336.478072 -219.998034) (xy 336.529367 -219.989909)
			(xy 336.581301 -219.989909) (xy 336.632596 -219.998034) (xy 336.681989 -220.014082) (xy 336.728263 -220.03766)
			(xy 336.770279 -220.068186) (xy 336.807002 -220.104909) (xy 336.837528 -220.146925) (xy 336.861106 -220.193199)
			(xy 336.877154 -220.242592) (xy 336.885279 -220.293887) (xy 336.885788 -220.319854) (xy 336.885279 -220.345821)
			(xy 337.165189 -220.345821) (xy 337.165189 -220.293887) (xy 337.173314 -220.242592) (xy 337.189362 -220.193199)
			(xy 337.21294 -220.146925) (xy 337.243466 -220.104909) (xy 337.280189 -220.068186) (xy 337.322205 -220.03766)
			(xy 337.368479 -220.014082) (xy 337.417872 -219.998034) (xy 337.469167 -219.989909) (xy 337.521101 -219.989909)
			(xy 337.572396 -219.998034) (xy 337.621789 -220.014082) (xy 337.668063 -220.03766) (xy 337.710079 -220.068186)
			(xy 337.746802 -220.104909) (xy 337.777328 -220.146925) (xy 337.800906 -220.193199) (xy 337.816954 -220.242592)
			(xy 337.825079 -220.293887) (xy 337.825588 -220.319854) (xy 337.825079 -220.345821) (xy 337.816954 -220.397116)
			(xy 337.800906 -220.446509) (xy 337.777328 -220.492783) (xy 337.746802 -220.534799) (xy 337.710079 -220.571522)
			(xy 337.668063 -220.602048) (xy 337.621789 -220.625626) (xy 337.572396 -220.641674) (xy 337.521101 -220.649799)
			(xy 337.469167 -220.649799) (xy 337.417872 -220.641674) (xy 337.368479 -220.625626) (xy 337.322205 -220.602048)
			(xy 337.280189 -220.571522) (xy 337.243466 -220.534799) (xy 337.21294 -220.492783) (xy 337.189362 -220.446509)
			(xy 337.173314 -220.397116) (xy 337.165189 -220.345821) (xy 336.885279 -220.345821) (xy 336.877154 -220.397116)
			(xy 336.861106 -220.446509) (xy 336.837528 -220.492783) (xy 336.807002 -220.534799) (xy 336.770279 -220.571522)
			(xy 336.728263 -220.602048) (xy 336.681989 -220.625626) (xy 336.632596 -220.641674) (xy 336.581301 -220.649799)
			(xy 336.529367 -220.649799) (xy 336.478072 -220.641674) (xy 336.428679 -220.625626) (xy 336.382405 -220.602048)
			(xy 336.340389 -220.571522) (xy 336.303666 -220.534799) (xy 336.27314 -220.492783) (xy 336.249562 -220.446509)
			(xy 336.233514 -220.397116) (xy 336.225389 -220.345821) (xy 335.54924 -220.345821) (xy 335.54924 -221.159891)
			(xy 335.755489 -221.159891) (xy 335.755489 -221.107957) (xy 335.763614 -221.056662) (xy 335.779662 -221.007269)
			(xy 335.80324 -220.960995) (xy 335.833766 -220.918979) (xy 335.870489 -220.882256) (xy 335.912505 -220.85173)
			(xy 335.958779 -220.828152) (xy 336.008172 -220.812104) (xy 336.059467 -220.803979) (xy 336.111401 -220.803979)
			(xy 336.162696 -220.812104) (xy 336.212089 -220.828152) (xy 336.258363 -220.85173) (xy 336.300379 -220.882256)
			(xy 336.337102 -220.918979) (xy 336.367628 -220.960995) (xy 336.391206 -221.007269) (xy 336.407254 -221.056662)
			(xy 336.415379 -221.107957) (xy 336.415888 -221.133924) (xy 336.69478 -221.133924) (xy 336.695289 -221.107957)
			(xy 336.703414 -221.056662) (xy 336.719462 -221.007269) (xy 336.74304 -220.960995) (xy 336.773566 -220.918979)
			(xy 336.810289 -220.882256) (xy 336.852305 -220.85173) (xy 336.898579 -220.828152) (xy 336.947972 -220.812104)
			(xy 336.999267 -220.803979) (xy 337.051201 -220.803979) (xy 337.102496 -220.812104) (xy 337.151889 -220.828152)
			(xy 337.198163 -220.85173) (xy 337.240179 -220.882256) (xy 337.276902 -220.918979) (xy 337.307428 -220.960995)
			(xy 337.331006 -221.007269) (xy 337.347054 -221.056662) (xy 337.355179 -221.107957) (xy 337.355688 -221.133924)
			(xy 337.63458 -221.133924) (xy 337.634971 -221.108469) (xy 337.642761 -221.05816) (xy 337.658176 -221.009641)
			(xy 337.680851 -220.964061) (xy 337.710249 -220.922499) (xy 337.745675 -220.885938) (xy 337.78629 -220.855244)
			(xy 337.831132 -220.831143) (xy 337.879141 -220.814206) (xy 337.904074 -220.809058) (xy 337.926934 -220.80474)
			(xy 338.130642 -220.45168) (xy 338.123022 -220.429582) (xy 338.114281 -220.402995) (xy 338.104835 -220.347835)
			(xy 338.104226 -220.319854) (xy 338.104735 -220.293887) (xy 338.11286 -220.242592) (xy 338.128908 -220.193199)
			(xy 338.152486 -220.146925) (xy 338.183012 -220.104909) (xy 338.219735 -220.068186) (xy 338.261751 -220.03766)
			(xy 338.308025 -220.014082) (xy 338.357418 -219.998034) (xy 338.408713 -219.989909) (xy 338.460647 -219.989909)
			(xy 338.511942 -219.998034) (xy 338.561335 -220.014082) (xy 338.607609 -220.03766) (xy 338.649625 -220.068186)
			(xy 338.686348 -220.104909) (xy 338.716874 -220.146925) (xy 338.740452 -220.193199) (xy 338.7565 -220.242592)
			(xy 338.764625 -220.293887) (xy 338.765134 -220.319854) (xy 338.764712 -220.345307) (xy 338.764632 -220.345821)
			(xy 339.044789 -220.345821) (xy 339.044789 -220.293887) (xy 339.052914 -220.242592) (xy 339.068962 -220.193199)
			(xy 339.09254 -220.146925) (xy 339.123066 -220.104909) (xy 339.159789 -220.068186) (xy 339.201805 -220.03766)
			(xy 339.248079 -220.014082) (xy 339.297472 -219.998034) (xy 339.348767 -219.989909) (xy 339.400701 -219.989909)
			(xy 339.451996 -219.998034) (xy 339.501389 -220.014082) (xy 339.547663 -220.03766) (xy 339.589679 -220.068186)
			(xy 339.626402 -220.104909) (xy 339.656928 -220.146925) (xy 339.680506 -220.193199) (xy 339.696554 -220.242592)
			(xy 339.704679 -220.293887) (xy 339.705188 -220.319854) (xy 339.704679 -220.345821) (xy 339.696554 -220.397116)
			(xy 339.680506 -220.446509) (xy 339.656928 -220.492783) (xy 339.626402 -220.534799) (xy 339.589679 -220.571522)
			(xy 339.547663 -220.602048) (xy 339.501389 -220.625626) (xy 339.451996 -220.641674) (xy 339.400701 -220.649799)
			(xy 339.348767 -220.649799) (xy 339.297472 -220.641674) (xy 339.248079 -220.625626) (xy 339.201805 -220.602048)
			(xy 339.159789 -220.571522) (xy 339.123066 -220.534799) (xy 339.09254 -220.492783) (xy 339.068962 -220.446509)
			(xy 339.052914 -220.397116) (xy 339.044789 -220.345821) (xy 338.764632 -220.345821) (xy 338.756926 -220.395615)
			(xy 338.741514 -220.444132) (xy 338.718843 -220.489711) (xy 338.689449 -220.531273) (xy 338.654027 -220.567835)
			(xy 338.613416 -220.59853) (xy 338.568577 -220.622632) (xy 338.520571 -220.639571) (xy 338.49564 -220.64472)
			(xy 338.47278 -220.649038) (xy 338.269072 -221.002098) (xy 338.276692 -221.024196) (xy 338.285429 -221.050785)
			(xy 338.294877 -221.105944) (xy 338.295488 -221.133924) (xy 338.57438 -221.133924) (xy 338.574889 -221.107957)
			(xy 338.583014 -221.056662) (xy 338.599062 -221.007269) (xy 338.62264 -220.960995) (xy 338.653166 -220.918979)
			(xy 338.689889 -220.882256) (xy 338.731905 -220.85173) (xy 338.778179 -220.828152) (xy 338.827572 -220.812104)
			(xy 338.878867 -220.803979) (xy 338.930801 -220.803979) (xy 338.982096 -220.812104) (xy 339.031489 -220.828152)
			(xy 339.077763 -220.85173) (xy 339.119779 -220.882256) (xy 339.156502 -220.918979) (xy 339.187028 -220.960995)
			(xy 339.210606 -221.007269) (xy 339.226654 -221.056662) (xy 339.234779 -221.107957) (xy 339.235288 -221.133924)
			(xy 339.51418 -221.133924) (xy 339.514571 -221.108469) (xy 339.522361 -221.05816) (xy 339.537776 -221.009641)
			(xy 339.560451 -220.964061) (xy 339.589849 -220.922499) (xy 339.625275 -220.885938) (xy 339.66589 -220.855244)
			(xy 339.710732 -220.831143) (xy 339.758741 -220.814206) (xy 339.783674 -220.809058) (xy 339.806534 -220.80474)
			(xy 340.010242 -220.45168) (xy 340.002622 -220.429582) (xy 339.993881 -220.402995) (xy 339.984435 -220.347835)
			(xy 339.983826 -220.319854) (xy 339.984335 -220.293887) (xy 339.99246 -220.242592) (xy 340.008508 -220.193199)
			(xy 340.032086 -220.146925) (xy 340.062612 -220.104909) (xy 340.099335 -220.068186) (xy 340.141351 -220.03766)
			(xy 340.187625 -220.014082) (xy 340.237018 -219.998034) (xy 340.288313 -219.989909) (xy 340.340247 -219.989909)
			(xy 340.391542 -219.998034) (xy 340.440935 -220.014082) (xy 340.487209 -220.03766) (xy 340.529225 -220.068186)
			(xy 340.565948 -220.104909) (xy 340.596474 -220.146925) (xy 340.620052 -220.193199) (xy 340.6361 -220.242592)
			(xy 340.644225 -220.293887) (xy 340.644734 -220.319854) (xy 340.644312 -220.345307) (xy 340.644232 -220.345821)
			(xy 340.924389 -220.345821) (xy 340.924389 -220.293887) (xy 340.932514 -220.242592) (xy 340.948562 -220.193199)
			(xy 340.97214 -220.146925) (xy 341.002666 -220.104909) (xy 341.039389 -220.068186) (xy 341.081405 -220.03766)
			(xy 341.127679 -220.014082) (xy 341.177072 -219.998034) (xy 341.228367 -219.989909) (xy 341.280301 -219.989909)
			(xy 341.331596 -219.998034) (xy 341.380989 -220.014082) (xy 341.427263 -220.03766) (xy 341.469279 -220.068186)
			(xy 341.506002 -220.104909) (xy 341.536528 -220.146925) (xy 341.560106 -220.193199) (xy 341.576154 -220.242592)
			(xy 341.584279 -220.293887) (xy 341.584788 -220.319854) (xy 341.584279 -220.345821) (xy 341.576154 -220.397116)
			(xy 341.560106 -220.446509) (xy 341.536528 -220.492783) (xy 341.506002 -220.534799) (xy 341.469279 -220.571522)
			(xy 341.427263 -220.602048) (xy 341.380989 -220.625626) (xy 341.331596 -220.641674) (xy 341.280301 -220.649799)
			(xy 341.228367 -220.649799) (xy 341.177072 -220.641674) (xy 341.127679 -220.625626) (xy 341.081405 -220.602048)
			(xy 341.039389 -220.571522) (xy 341.002666 -220.534799) (xy 340.97214 -220.492783) (xy 340.948562 -220.446509)
			(xy 340.932514 -220.397116) (xy 340.924389 -220.345821) (xy 340.644232 -220.345821) (xy 340.636526 -220.395615)
			(xy 340.621114 -220.444132) (xy 340.598443 -220.489711) (xy 340.569049 -220.531273) (xy 340.533627 -220.567835)
			(xy 340.493016 -220.59853) (xy 340.448177 -220.622632) (xy 340.400171 -220.639571) (xy 340.37524 -220.64472)
			(xy 340.35238 -220.649038) (xy 340.148672 -221.002098) (xy 340.156292 -221.024196) (xy 340.165029 -221.050785)
			(xy 340.174477 -221.105944) (xy 340.175088 -221.133924) (xy 340.45398 -221.133924) (xy 340.454489 -221.107957)
			(xy 340.462614 -221.056662) (xy 340.478662 -221.007269) (xy 340.50224 -220.960995) (xy 340.532766 -220.918979)
			(xy 340.569489 -220.882256) (xy 340.611505 -220.85173) (xy 340.657779 -220.828152) (xy 340.707172 -220.812104)
			(xy 340.758467 -220.803979) (xy 340.810401 -220.803979) (xy 340.861696 -220.812104) (xy 340.911089 -220.828152)
			(xy 340.957363 -220.85173) (xy 340.999379 -220.882256) (xy 341.036102 -220.918979) (xy 341.066628 -220.960995)
			(xy 341.090206 -221.007269) (xy 341.106254 -221.056662) (xy 341.114379 -221.107957) (xy 341.114888 -221.133924)
			(xy 341.39378 -221.133924) (xy 341.394171 -221.108469) (xy 341.401961 -221.05816) (xy 341.417376 -221.009641)
			(xy 341.440051 -220.964061) (xy 341.469449 -220.922499) (xy 341.504875 -220.885938) (xy 341.54549 -220.855244)
			(xy 341.590332 -220.831143) (xy 341.638341 -220.814206) (xy 341.663274 -220.809058) (xy 341.686134 -220.80474)
			(xy 341.889842 -220.45168) (xy 341.882222 -220.429582) (xy 341.873481 -220.402995) (xy 341.864035 -220.347835)
			(xy 341.863426 -220.319854) (xy 341.863935 -220.293887) (xy 341.87206 -220.242592) (xy 341.888108 -220.193199)
			(xy 341.911686 -220.146925) (xy 341.942212 -220.104909) (xy 341.978935 -220.068186) (xy 342.020951 -220.03766)
			(xy 342.067225 -220.014082) (xy 342.116618 -219.998034) (xy 342.167913 -219.989909) (xy 342.219847 -219.989909)
			(xy 342.271142 -219.998034) (xy 342.320535 -220.014082) (xy 342.366809 -220.03766) (xy 342.408825 -220.068186)
			(xy 342.445548 -220.104909) (xy 342.476074 -220.146925) (xy 342.499652 -220.193199) (xy 342.5157 -220.242592)
			(xy 342.523825 -220.293887) (xy 342.524334 -220.319854) (xy 342.523912 -220.345307) (xy 342.523832 -220.345821)
			(xy 342.803989 -220.345821) (xy 342.803989 -220.293887) (xy 342.812114 -220.242592) (xy 342.828162 -220.193199)
			(xy 342.85174 -220.146925) (xy 342.882266 -220.104909) (xy 342.918989 -220.068186) (xy 342.961005 -220.03766)
			(xy 343.007279 -220.014082) (xy 343.056672 -219.998034) (xy 343.107967 -219.989909) (xy 343.159901 -219.989909)
			(xy 343.211196 -219.998034) (xy 343.260589 -220.014082) (xy 343.306863 -220.03766) (xy 343.348879 -220.068186)
			(xy 343.385602 -220.104909) (xy 343.416128 -220.146925) (xy 343.439706 -220.193199) (xy 343.455754 -220.242592)
			(xy 343.463879 -220.293887) (xy 343.464388 -220.319854) (xy 343.463879 -220.345821) (xy 343.455754 -220.397116)
			(xy 343.439706 -220.446509) (xy 343.416128 -220.492783) (xy 343.385602 -220.534799) (xy 343.348879 -220.571522)
			(xy 343.306863 -220.602048) (xy 343.260589 -220.625626) (xy 343.211196 -220.641674) (xy 343.159901 -220.649799)
			(xy 343.107967 -220.649799) (xy 343.056672 -220.641674) (xy 343.007279 -220.625626) (xy 342.961005 -220.602048)
			(xy 342.918989 -220.571522) (xy 342.882266 -220.534799) (xy 342.85174 -220.492783) (xy 342.828162 -220.446509)
			(xy 342.812114 -220.397116) (xy 342.803989 -220.345821) (xy 342.523832 -220.345821) (xy 342.516126 -220.395615)
			(xy 342.500714 -220.444132) (xy 342.478043 -220.489711) (xy 342.448649 -220.531273) (xy 342.413227 -220.567835)
			(xy 342.372616 -220.59853) (xy 342.327777 -220.622632) (xy 342.279771 -220.639571) (xy 342.25484 -220.64472)
			(xy 342.23198 -220.649038) (xy 342.028272 -221.002098) (xy 342.035892 -221.024196) (xy 342.044629 -221.050785)
			(xy 342.054077 -221.105944) (xy 342.054688 -221.133924) (xy 342.33358 -221.133924) (xy 342.334089 -221.107957)
			(xy 342.342214 -221.056662) (xy 342.358262 -221.007269) (xy 342.38184 -220.960995) (xy 342.412366 -220.918979)
			(xy 342.449089 -220.882256) (xy 342.491105 -220.85173) (xy 342.537379 -220.828152) (xy 342.586772 -220.812104)
			(xy 342.638067 -220.803979) (xy 342.690001 -220.803979) (xy 342.741296 -220.812104) (xy 342.790689 -220.828152)
			(xy 342.836963 -220.85173) (xy 342.878979 -220.882256) (xy 342.915702 -220.918979) (xy 342.946228 -220.960995)
			(xy 342.969806 -221.007269) (xy 342.985854 -221.056662) (xy 342.993979 -221.107957) (xy 342.994488 -221.133924)
			(xy 343.27338 -221.133924) (xy 343.273771 -221.108469) (xy 343.281561 -221.05816) (xy 343.296976 -221.009641)
			(xy 343.319651 -220.964061) (xy 343.349049 -220.922499) (xy 343.384475 -220.885938) (xy 343.42509 -220.855244)
			(xy 343.469932 -220.831143) (xy 343.517941 -220.814206) (xy 343.542874 -220.809058) (xy 343.565734 -220.80474)
			(xy 343.769442 -220.45168) (xy 343.761822 -220.429582) (xy 343.753081 -220.402995) (xy 343.743635 -220.347835)
			(xy 343.743026 -220.319854) (xy 343.743535 -220.293887) (xy 343.75166 -220.242592) (xy 343.767708 -220.193199)
			(xy 343.791286 -220.146925) (xy 343.821812 -220.104909) (xy 343.858535 -220.068186) (xy 343.900551 -220.03766)
			(xy 343.946825 -220.014082) (xy 343.996218 -219.998034) (xy 344.047513 -219.989909) (xy 344.099447 -219.989909)
			(xy 344.150742 -219.998034) (xy 344.200135 -220.014082) (xy 344.246409 -220.03766) (xy 344.288425 -220.068186)
			(xy 344.325148 -220.104909) (xy 344.355674 -220.146925) (xy 344.379252 -220.193199) (xy 344.3953 -220.242592)
			(xy 344.403425 -220.293887) (xy 344.403934 -220.319854) (xy 344.403512 -220.345307) (xy 344.403432 -220.345821)
			(xy 344.683589 -220.345821) (xy 344.683589 -220.293887) (xy 344.691714 -220.242592) (xy 344.707762 -220.193199)
			(xy 344.73134 -220.146925) (xy 344.761866 -220.104909) (xy 344.798589 -220.068186) (xy 344.840605 -220.03766)
			(xy 344.886879 -220.014082) (xy 344.936272 -219.998034) (xy 344.987567 -219.989909) (xy 345.039501 -219.989909)
			(xy 345.090796 -219.998034) (xy 345.140189 -220.014082) (xy 345.186463 -220.03766) (xy 345.228479 -220.068186)
			(xy 345.265202 -220.104909) (xy 345.295728 -220.146925) (xy 345.319306 -220.193199) (xy 345.335354 -220.242592)
			(xy 345.343479 -220.293887) (xy 345.343988 -220.319854) (xy 345.343479 -220.345821) (xy 345.335354 -220.397116)
			(xy 345.319306 -220.446509) (xy 345.295728 -220.492783) (xy 345.265202 -220.534799) (xy 345.228479 -220.571522)
			(xy 345.186463 -220.602048) (xy 345.140189 -220.625626) (xy 345.090796 -220.641674) (xy 345.039501 -220.649799)
			(xy 344.987567 -220.649799) (xy 344.936272 -220.641674) (xy 344.886879 -220.625626) (xy 344.840605 -220.602048)
			(xy 344.798589 -220.571522) (xy 344.761866 -220.534799) (xy 344.73134 -220.492783) (xy 344.707762 -220.446509)
			(xy 344.691714 -220.397116) (xy 344.683589 -220.345821) (xy 344.403432 -220.345821) (xy 344.395726 -220.395615)
			(xy 344.380314 -220.444132) (xy 344.357643 -220.489711) (xy 344.328249 -220.531273) (xy 344.292827 -220.567835)
			(xy 344.252216 -220.59853) (xy 344.207377 -220.622632) (xy 344.159371 -220.639571) (xy 344.13444 -220.64472)
			(xy 344.11158 -220.649038) (xy 343.907872 -221.002098) (xy 343.915492 -221.024196) (xy 343.924229 -221.050785)
			(xy 343.933677 -221.105944) (xy 343.934288 -221.133924) (xy 344.21318 -221.133924) (xy 344.213689 -221.107957)
			(xy 344.221814 -221.056662) (xy 344.237862 -221.007269) (xy 344.26144 -220.960995) (xy 344.291966 -220.918979)
			(xy 344.328689 -220.882256) (xy 344.370705 -220.85173) (xy 344.416979 -220.828152) (xy 344.466372 -220.812104)
			(xy 344.517667 -220.803979) (xy 344.569601 -220.803979) (xy 344.620896 -220.812104) (xy 344.670289 -220.828152)
			(xy 344.716563 -220.85173) (xy 344.758579 -220.882256) (xy 344.795302 -220.918979) (xy 344.825828 -220.960995)
			(xy 344.849406 -221.007269) (xy 344.865454 -221.056662) (xy 344.873579 -221.107957) (xy 344.874088 -221.133924)
			(xy 345.15298 -221.133924) (xy 345.153371 -221.108469) (xy 345.161161 -221.05816) (xy 345.176576 -221.009641)
			(xy 345.199251 -220.964061) (xy 345.228649 -220.922499) (xy 345.264075 -220.885938) (xy 345.30469 -220.855244)
			(xy 345.349532 -220.831143) (xy 345.397541 -220.814206) (xy 345.422474 -220.809058) (xy 345.445334 -220.80474)
			(xy 345.649042 -220.45168) (xy 345.641422 -220.429582) (xy 345.632681 -220.402995) (xy 345.623235 -220.347835)
			(xy 345.622626 -220.319854) (xy 345.623135 -220.293887) (xy 345.63126 -220.242592) (xy 345.647308 -220.193199)
			(xy 345.670886 -220.146925) (xy 345.701412 -220.104909) (xy 345.738135 -220.068186) (xy 345.780151 -220.03766)
			(xy 345.826425 -220.014082) (xy 345.875818 -219.998034) (xy 345.927113 -219.989909) (xy 345.979047 -219.989909)
			(xy 346.030342 -219.998034) (xy 346.079735 -220.014082) (xy 346.126009 -220.03766) (xy 346.168025 -220.068186)
			(xy 346.204748 -220.104909) (xy 346.235274 -220.146925) (xy 346.258852 -220.193199) (xy 346.2749 -220.242592)
			(xy 346.283025 -220.293887) (xy 346.283534 -220.319854) (xy 346.283112 -220.345307) (xy 346.283032 -220.345821)
			(xy 346.563189 -220.345821) (xy 346.563189 -220.293887) (xy 346.571314 -220.242592) (xy 346.587362 -220.193199)
			(xy 346.61094 -220.146925) (xy 346.641466 -220.104909) (xy 346.678189 -220.068186) (xy 346.720205 -220.03766)
			(xy 346.766479 -220.014082) (xy 346.815872 -219.998034) (xy 346.867167 -219.989909) (xy 346.919101 -219.989909)
			(xy 346.970396 -219.998034) (xy 347.019789 -220.014082) (xy 347.066063 -220.03766) (xy 347.108079 -220.068186)
			(xy 347.144802 -220.104909) (xy 347.175328 -220.146925) (xy 347.198906 -220.193199) (xy 347.214954 -220.242592)
			(xy 347.223079 -220.293887) (xy 347.223588 -220.319854) (xy 347.223079 -220.345821) (xy 347.214954 -220.397116)
			(xy 347.198906 -220.446509) (xy 347.175328 -220.492783) (xy 347.144802 -220.534799) (xy 347.108079 -220.571522)
			(xy 347.066063 -220.602048) (xy 347.019789 -220.625626) (xy 346.970396 -220.641674) (xy 346.919101 -220.649799)
			(xy 346.867167 -220.649799) (xy 346.815872 -220.641674) (xy 346.766479 -220.625626) (xy 346.720205 -220.602048)
			(xy 346.678189 -220.571522) (xy 346.641466 -220.534799) (xy 346.61094 -220.492783) (xy 346.587362 -220.446509)
			(xy 346.571314 -220.397116) (xy 346.563189 -220.345821) (xy 346.283032 -220.345821) (xy 346.275326 -220.395615)
			(xy 346.259914 -220.444132) (xy 346.237243 -220.489711) (xy 346.207849 -220.531273) (xy 346.172427 -220.567835)
			(xy 346.131816 -220.59853) (xy 346.086977 -220.622632) (xy 346.038971 -220.639571) (xy 346.01404 -220.64472)
			(xy 345.99118 -220.649038) (xy 345.787472 -221.002098) (xy 345.795092 -221.024196) (xy 345.803829 -221.050785)
			(xy 345.813277 -221.105944) (xy 345.813888 -221.133924) (xy 346.09278 -221.133924) (xy 346.093289 -221.107957)
			(xy 346.101414 -221.056662) (xy 346.117462 -221.007269) (xy 346.14104 -220.960995) (xy 346.171566 -220.918979)
			(xy 346.208289 -220.882256) (xy 346.250305 -220.85173) (xy 346.296579 -220.828152) (xy 346.345972 -220.812104)
			(xy 346.397267 -220.803979) (xy 346.449201 -220.803979) (xy 346.500496 -220.812104) (xy 346.549889 -220.828152)
			(xy 346.596163 -220.85173) (xy 346.638179 -220.882256) (xy 346.674902 -220.918979) (xy 346.705428 -220.960995)
			(xy 346.729006 -221.007269) (xy 346.745054 -221.056662) (xy 346.753179 -221.107957) (xy 346.753688 -221.133924)
			(xy 347.03258 -221.133924) (xy 347.032971 -221.108469) (xy 347.040761 -221.05816) (xy 347.056176 -221.009641)
			(xy 347.078851 -220.964061) (xy 347.108249 -220.922499) (xy 347.143675 -220.885938) (xy 347.18429 -220.855244)
			(xy 347.229132 -220.831143) (xy 347.277141 -220.814206) (xy 347.302074 -220.809058) (xy 347.324934 -220.80474)
			(xy 347.528642 -220.45168) (xy 347.521022 -220.429582) (xy 347.512281 -220.402995) (xy 347.502835 -220.347835)
			(xy 347.502226 -220.319854) (xy 347.502735 -220.293887) (xy 347.51086 -220.242592) (xy 347.526908 -220.193199)
			(xy 347.550486 -220.146925) (xy 347.581012 -220.104909) (xy 347.617735 -220.068186) (xy 347.659751 -220.03766)
			(xy 347.706025 -220.014082) (xy 347.755418 -219.998034) (xy 347.806713 -219.989909) (xy 347.858647 -219.989909)
			(xy 347.909942 -219.998034) (xy 347.959335 -220.014082) (xy 348.005609 -220.03766) (xy 348.047625 -220.068186)
			(xy 348.084348 -220.104909) (xy 348.114874 -220.146925) (xy 348.138452 -220.193199) (xy 348.1545 -220.242592)
			(xy 348.162625 -220.293887) (xy 348.163134 -220.319854) (xy 348.162712 -220.345307) (xy 348.154926 -220.395615)
			(xy 348.139514 -220.444132) (xy 348.116843 -220.489711) (xy 348.087449 -220.531273) (xy 348.052027 -220.567835)
			(xy 348.011416 -220.59853) (xy 347.966577 -220.622632) (xy 347.918571 -220.639571) (xy 347.89364 -220.64472)
			(xy 347.87078 -220.649038) (xy 347.667072 -221.002098) (xy 347.674692 -221.024196) (xy 347.683429 -221.050785)
			(xy 347.692877 -221.105944) (xy 347.693488 -221.133924) (xy 347.692979 -221.159891) (xy 347.684854 -221.211186)
			(xy 347.668806 -221.260579) (xy 347.645228 -221.306853) (xy 347.614702 -221.348869) (xy 347.577979 -221.385592)
			(xy 347.535963 -221.416118) (xy 347.489689 -221.439696) (xy 347.440296 -221.455744) (xy 347.389001 -221.463869)
			(xy 347.337067 -221.463869) (xy 347.285772 -221.455744) (xy 347.236379 -221.439696) (xy 347.190105 -221.416118)
			(xy 347.148089 -221.385592) (xy 347.111366 -221.348869) (xy 347.08084 -221.306853) (xy 347.057262 -221.260579)
			(xy 347.041214 -221.211186) (xy 347.033089 -221.159891) (xy 347.03258 -221.133924) (xy 346.753688 -221.133924)
			(xy 346.753142 -221.16191) (xy 346.743687 -221.217078) (xy 346.734892 -221.243652) (xy 346.727272 -221.26575)
			(xy 346.93098 -221.618556) (xy 346.95384 -221.622874) (xy 346.978763 -221.628034) (xy 347.026748 -221.644999)
			(xy 347.071566 -221.669118) (xy 347.112159 -221.699819) (xy 347.147568 -221.736378) (xy 347.176956 -221.777931)
			(xy 347.19963 -221.823497) (xy 347.215053 -221.871999) (xy 347.222861 -221.922292) (xy 347.223334 -221.94774)
			(xy 347.222825 -221.973707) (xy 347.2147 -222.025002) (xy 347.198652 -222.074395) (xy 347.175074 -222.120669)
			(xy 347.144548 -222.162685) (xy 347.107825 -222.199408) (xy 347.065809 -222.229934) (xy 347.019535 -222.253512)
			(xy 346.970142 -222.26956) (xy 346.918847 -222.277685) (xy 346.866913 -222.277685) (xy 346.815618 -222.26956)
			(xy 346.766225 -222.253512) (xy 346.719951 -222.229934) (xy 346.677935 -222.199408) (xy 346.641212 -222.162685)
			(xy 346.610686 -222.120669) (xy 346.587108 -222.074395) (xy 346.57106 -222.025002) (xy 346.562935 -221.973707)
			(xy 346.562426 -221.94774) (xy 346.562987 -221.919755) (xy 346.572431 -221.864587) (xy 346.581222 -221.838012)
			(xy 346.588842 -221.815914) (xy 346.385134 -221.463108) (xy 346.362274 -221.45879) (xy 346.337345 -221.453653)
			(xy 346.289358 -221.436688) (xy 346.244537 -221.412568) (xy 346.203943 -221.381864) (xy 346.168534 -221.345302)
			(xy 346.139146 -221.303745) (xy 346.116474 -221.258175) (xy 346.101054 -221.209669) (xy 346.09325 -221.159373)
			(xy 346.09278 -221.133924) (xy 345.813888 -221.133924) (xy 345.813379 -221.159891) (xy 345.805254 -221.211186)
			(xy 345.789206 -221.260579) (xy 345.765628 -221.306853) (xy 345.735102 -221.348869) (xy 345.698379 -221.385592)
			(xy 345.656363 -221.416118) (xy 345.610089 -221.439696) (xy 345.560696 -221.455744) (xy 345.509401 -221.463869)
			(xy 345.457467 -221.463869) (xy 345.406172 -221.455744) (xy 345.356779 -221.439696) (xy 345.310505 -221.416118)
			(xy 345.268489 -221.385592) (xy 345.231766 -221.348869) (xy 345.20124 -221.306853) (xy 345.177662 -221.260579)
			(xy 345.161614 -221.211186) (xy 345.153489 -221.159891) (xy 345.15298 -221.133924) (xy 344.874088 -221.133924)
			(xy 344.873542 -221.16191) (xy 344.864087 -221.217078) (xy 344.855292 -221.243652) (xy 344.847672 -221.26575)
			(xy 345.05138 -221.618556) (xy 345.07424 -221.622874) (xy 345.099163 -221.628034) (xy 345.147148 -221.644999)
			(xy 345.191966 -221.669118) (xy 345.232559 -221.699819) (xy 345.267968 -221.736378) (xy 345.297356 -221.777931)
			(xy 345.32003 -221.823497) (xy 345.335453 -221.871999) (xy 345.343261 -221.922292) (xy 345.343734 -221.94774)
			(xy 345.343225 -221.973707) (xy 345.3351 -222.025002) (xy 345.319052 -222.074395) (xy 345.295474 -222.120669)
			(xy 345.264948 -222.162685) (xy 345.228225 -222.199408) (xy 345.186209 -222.229934) (xy 345.139935 -222.253512)
			(xy 345.090542 -222.26956) (xy 345.039247 -222.277685) (xy 344.987313 -222.277685) (xy 344.936018 -222.26956)
			(xy 344.886625 -222.253512) (xy 344.840351 -222.229934) (xy 344.798335 -222.199408) (xy 344.761612 -222.162685)
			(xy 344.731086 -222.120669) (xy 344.707508 -222.074395) (xy 344.69146 -222.025002) (xy 344.683335 -221.973707)
			(xy 344.682826 -221.94774) (xy 344.683387 -221.919755) (xy 344.692831 -221.864587) (xy 344.701622 -221.838012)
			(xy 344.709242 -221.815914) (xy 344.505534 -221.463108) (xy 344.482674 -221.45879) (xy 344.457745 -221.453653)
			(xy 344.409758 -221.436688) (xy 344.364937 -221.412568) (xy 344.324343 -221.381864) (xy 344.288934 -221.345302)
			(xy 344.259546 -221.303745) (xy 344.236874 -221.258175) (xy 344.221454 -221.209669) (xy 344.21365 -221.159373)
			(xy 344.21318 -221.133924) (xy 343.934288 -221.133924) (xy 343.933779 -221.159891) (xy 343.925654 -221.211186)
			(xy 343.909606 -221.260579) (xy 343.886028 -221.306853) (xy 343.855502 -221.348869) (xy 343.818779 -221.385592)
			(xy 343.776763 -221.416118) (xy 343.730489 -221.439696) (xy 343.681096 -221.455744) (xy 343.629801 -221.463869)
			(xy 343.577867 -221.463869) (xy 343.526572 -221.455744) (xy 343.477179 -221.439696) (xy 343.430905 -221.416118)
			(xy 343.388889 -221.385592) (xy 343.352166 -221.348869) (xy 343.32164 -221.306853) (xy 343.298062 -221.260579)
			(xy 343.282014 -221.211186) (xy 343.273889 -221.159891) (xy 343.27338 -221.133924) (xy 342.994488 -221.133924)
			(xy 342.993942 -221.16191) (xy 342.984487 -221.217078) (xy 342.975692 -221.243652) (xy 342.968072 -221.26575)
			(xy 343.17178 -221.618556) (xy 343.19464 -221.622874) (xy 343.219563 -221.628034) (xy 343.267548 -221.644999)
			(xy 343.312366 -221.669118) (xy 343.352959 -221.699819) (xy 343.388368 -221.736378) (xy 343.417756 -221.777931)
			(xy 343.44043 -221.823497) (xy 343.455853 -221.871999) (xy 343.463661 -221.922292) (xy 343.464134 -221.94774)
			(xy 343.463625 -221.973707) (xy 343.4555 -222.025002) (xy 343.439452 -222.074395) (xy 343.415874 -222.120669)
			(xy 343.385348 -222.162685) (xy 343.348625 -222.199408) (xy 343.306609 -222.229934) (xy 343.260335 -222.253512)
			(xy 343.210942 -222.26956) (xy 343.159647 -222.277685) (xy 343.107713 -222.277685) (xy 343.056418 -222.26956)
			(xy 343.007025 -222.253512) (xy 342.960751 -222.229934) (xy 342.918735 -222.199408) (xy 342.882012 -222.162685)
			(xy 342.851486 -222.120669) (xy 342.827908 -222.074395) (xy 342.81186 -222.025002) (xy 342.803735 -221.973707)
			(xy 342.803226 -221.94774) (xy 342.803787 -221.919755) (xy 342.813231 -221.864587) (xy 342.822022 -221.838012)
			(xy 342.829642 -221.815914) (xy 342.625934 -221.463108) (xy 342.603074 -221.45879) (xy 342.578145 -221.453653)
			(xy 342.530158 -221.436688) (xy 342.485337 -221.412568) (xy 342.444743 -221.381864) (xy 342.409334 -221.345302)
			(xy 342.379946 -221.303745) (xy 342.357274 -221.258175) (xy 342.341854 -221.209669) (xy 342.33405 -221.159373)
			(xy 342.33358 -221.133924) (xy 342.054688 -221.133924) (xy 342.054179 -221.159891) (xy 342.046054 -221.211186)
			(xy 342.030006 -221.260579) (xy 342.006428 -221.306853) (xy 341.975902 -221.348869) (xy 341.939179 -221.385592)
			(xy 341.897163 -221.416118) (xy 341.850889 -221.439696) (xy 341.801496 -221.455744) (xy 341.750201 -221.463869)
			(xy 341.698267 -221.463869) (xy 341.646972 -221.455744) (xy 341.597579 -221.439696) (xy 341.551305 -221.416118)
			(xy 341.509289 -221.385592) (xy 341.472566 -221.348869) (xy 341.44204 -221.306853) (xy 341.418462 -221.260579)
			(xy 341.402414 -221.211186) (xy 341.394289 -221.159891) (xy 341.39378 -221.133924) (xy 341.114888 -221.133924)
			(xy 341.114342 -221.16191) (xy 341.104887 -221.217078) (xy 341.096092 -221.243652) (xy 341.088472 -221.26575)
			(xy 341.29218 -221.618556) (xy 341.31504 -221.622874) (xy 341.339963 -221.628034) (xy 341.387948 -221.644999)
			(xy 341.432766 -221.669118) (xy 341.473359 -221.699819) (xy 341.508768 -221.736378) (xy 341.538156 -221.777931)
			(xy 341.56083 -221.823497) (xy 341.576253 -221.871999) (xy 341.584061 -221.922292) (xy 341.584534 -221.94774)
			(xy 341.584025 -221.973707) (xy 341.5759 -222.025002) (xy 341.559852 -222.074395) (xy 341.536274 -222.120669)
			(xy 341.505748 -222.162685) (xy 341.469025 -222.199408) (xy 341.427009 -222.229934) (xy 341.380735 -222.253512)
			(xy 341.331342 -222.26956) (xy 341.280047 -222.277685) (xy 341.228113 -222.277685) (xy 341.176818 -222.26956)
			(xy 341.127425 -222.253512) (xy 341.081151 -222.229934) (xy 341.039135 -222.199408) (xy 341.002412 -222.162685)
			(xy 340.971886 -222.120669) (xy 340.948308 -222.074395) (xy 340.93226 -222.025002) (xy 340.924135 -221.973707)
			(xy 340.923626 -221.94774) (xy 340.924187 -221.919755) (xy 340.933631 -221.864587) (xy 340.942422 -221.838012)
			(xy 340.950042 -221.815914) (xy 340.746334 -221.463108) (xy 340.723474 -221.45879) (xy 340.698545 -221.453653)
			(xy 340.650558 -221.436688) (xy 340.605737 -221.412568) (xy 340.565143 -221.381864) (xy 340.529734 -221.345302)
			(xy 340.500346 -221.303745) (xy 340.477674 -221.258175) (xy 340.462254 -221.209669) (xy 340.45445 -221.159373)
			(xy 340.45398 -221.133924) (xy 340.175088 -221.133924) (xy 340.174579 -221.159891) (xy 340.166454 -221.211186)
			(xy 340.150406 -221.260579) (xy 340.126828 -221.306853) (xy 340.096302 -221.348869) (xy 340.059579 -221.385592)
			(xy 340.017563 -221.416118) (xy 339.971289 -221.439696) (xy 339.921896 -221.455744) (xy 339.870601 -221.463869)
			(xy 339.818667 -221.463869) (xy 339.767372 -221.455744) (xy 339.717979 -221.439696) (xy 339.671705 -221.416118)
			(xy 339.629689 -221.385592) (xy 339.592966 -221.348869) (xy 339.56244 -221.306853) (xy 339.538862 -221.260579)
			(xy 339.522814 -221.211186) (xy 339.514689 -221.159891) (xy 339.51418 -221.133924) (xy 339.235288 -221.133924)
			(xy 339.234742 -221.16191) (xy 339.225287 -221.217078) (xy 339.216492 -221.243652) (xy 339.208872 -221.26575)
			(xy 339.41258 -221.618556) (xy 339.43544 -221.622874) (xy 339.460363 -221.628034) (xy 339.508348 -221.644999)
			(xy 339.553166 -221.669118) (xy 339.593759 -221.699819) (xy 339.629168 -221.736378) (xy 339.658556 -221.777931)
			(xy 339.68123 -221.823497) (xy 339.696653 -221.871999) (xy 339.704461 -221.922292) (xy 339.704934 -221.94774)
			(xy 339.704425 -221.973707) (xy 339.6963 -222.025002) (xy 339.680252 -222.074395) (xy 339.656674 -222.120669)
			(xy 339.626148 -222.162685) (xy 339.589425 -222.199408) (xy 339.547409 -222.229934) (xy 339.501135 -222.253512)
			(xy 339.451742 -222.26956) (xy 339.400447 -222.277685) (xy 339.348513 -222.277685) (xy 339.297218 -222.26956)
			(xy 339.247825 -222.253512) (xy 339.201551 -222.229934) (xy 339.159535 -222.199408) (xy 339.122812 -222.162685)
			(xy 339.092286 -222.120669) (xy 339.068708 -222.074395) (xy 339.05266 -222.025002) (xy 339.044535 -221.973707)
			(xy 339.044026 -221.94774) (xy 339.044587 -221.919755) (xy 339.054031 -221.864587) (xy 339.062822 -221.838012)
			(xy 339.070442 -221.815914) (xy 338.866734 -221.463108) (xy 338.843874 -221.45879) (xy 338.818945 -221.453653)
			(xy 338.770958 -221.436688) (xy 338.726137 -221.412568) (xy 338.685543 -221.381864) (xy 338.650134 -221.345302)
			(xy 338.620746 -221.303745) (xy 338.598074 -221.258175) (xy 338.582654 -221.209669) (xy 338.57485 -221.159373)
			(xy 338.57438 -221.133924) (xy 338.295488 -221.133924) (xy 338.294979 -221.159891) (xy 338.286854 -221.211186)
			(xy 338.270806 -221.260579) (xy 338.247228 -221.306853) (xy 338.216702 -221.348869) (xy 338.179979 -221.385592)
			(xy 338.137963 -221.416118) (xy 338.091689 -221.439696) (xy 338.042296 -221.455744) (xy 337.991001 -221.463869)
			(xy 337.939067 -221.463869) (xy 337.887772 -221.455744) (xy 337.838379 -221.439696) (xy 337.792105 -221.416118)
			(xy 337.750089 -221.385592) (xy 337.713366 -221.348869) (xy 337.68284 -221.306853) (xy 337.659262 -221.260579)
			(xy 337.643214 -221.211186) (xy 337.635089 -221.159891) (xy 337.63458 -221.133924) (xy 337.355688 -221.133924)
			(xy 337.355142 -221.16191) (xy 337.345687 -221.217078) (xy 337.336892 -221.243652) (xy 337.329272 -221.26575)
			(xy 337.53298 -221.618556) (xy 337.55584 -221.622874) (xy 337.580763 -221.628034) (xy 337.628748 -221.644999)
			(xy 337.673566 -221.669118) (xy 337.714159 -221.699819) (xy 337.749568 -221.736378) (xy 337.778956 -221.777931)
			(xy 337.80163 -221.823497) (xy 337.817053 -221.871999) (xy 337.824861 -221.922292) (xy 337.825334 -221.94774)
			(xy 337.824825 -221.973707) (xy 337.8167 -222.025002) (xy 337.800652 -222.074395) (xy 337.777074 -222.120669)
			(xy 337.746548 -222.162685) (xy 337.709825 -222.199408) (xy 337.667809 -222.229934) (xy 337.621535 -222.253512)
			(xy 337.572142 -222.26956) (xy 337.520847 -222.277685) (xy 337.468913 -222.277685) (xy 337.417618 -222.26956)
			(xy 337.368225 -222.253512) (xy 337.321951 -222.229934) (xy 337.279935 -222.199408) (xy 337.243212 -222.162685)
			(xy 337.212686 -222.120669) (xy 337.189108 -222.074395) (xy 337.17306 -222.025002) (xy 337.164935 -221.973707)
			(xy 337.164426 -221.94774) (xy 337.164987 -221.919755) (xy 337.174431 -221.864587) (xy 337.183222 -221.838012)
			(xy 337.190842 -221.815914) (xy 336.987134 -221.463108) (xy 336.964274 -221.45879) (xy 336.939345 -221.453653)
			(xy 336.891358 -221.436688) (xy 336.846537 -221.412568) (xy 336.805943 -221.381864) (xy 336.770534 -221.345302)
			(xy 336.741146 -221.303745) (xy 336.718474 -221.258175) (xy 336.703054 -221.209669) (xy 336.69525 -221.159373)
			(xy 336.69478 -221.133924) (xy 336.415888 -221.133924) (xy 336.415379 -221.159891) (xy 336.407254 -221.211186)
			(xy 336.391206 -221.260579) (xy 336.367628 -221.306853) (xy 336.337102 -221.348869) (xy 336.300379 -221.385592)
			(xy 336.258363 -221.416118) (xy 336.212089 -221.439696) (xy 336.162696 -221.455744) (xy 336.111401 -221.463869)
			(xy 336.059467 -221.463869) (xy 336.008172 -221.455744) (xy 335.958779 -221.439696) (xy 335.912505 -221.416118)
			(xy 335.870489 -221.385592) (xy 335.833766 -221.348869) (xy 335.80324 -221.306853) (xy 335.779662 -221.260579)
			(xy 335.763614 -221.211186) (xy 335.755489 -221.159891) (xy 335.54924 -221.159891) (xy 335.54924 -221.51721)
			(xy 335.549836 -221.532336) (xy 335.558771 -221.561242) (xy 335.575768 -221.586273) (xy 335.599341 -221.605239)
			(xy 335.62743 -221.616484) (xy 335.642458 -221.618302) (xy 335.666963 -221.620757) (xy 335.714908 -221.632001)
			(xy 335.760654 -221.650238) (xy 335.803185 -221.675063) (xy 335.841561 -221.705926) (xy 335.87493 -221.742143)
			(xy 335.902554 -221.782912) (xy 335.92382 -221.82733) (xy 335.938258 -221.874413) (xy 335.945547 -221.923117)
			(xy 335.945988 -221.94774) (xy 335.945419 -221.976017) (xy 335.935799 -222.031747) (xy 335.916813 -222.085019)
			(xy 335.889018 -222.134272) (xy 335.871566 -222.156528) (xy 335.862516 -222.168462) (xy 335.851127 -222.196149)
			(xy 335.848241 -222.225947) (xy 335.854107 -222.255305) (xy 335.868221 -222.281706) (xy 335.878424 -222.292672)
			(xy 336.021934 -222.436182) (xy 336.046572 -222.433388) (xy 336.056251 -222.432312) (xy 336.075695 -222.431166)
			(xy 336.085434 -222.431102) (xy 336.110506 -222.43157) (xy 336.160074 -222.439152) (xy 336.207928 -222.454138)
			(xy 336.252967 -222.476183) (xy 336.294157 -222.504781) (xy 336.330553 -222.539275) (xy 336.361319 -222.578872)
			(xy 336.373978 -222.60052) (xy 336.388456 -222.626428) (xy 336.722212 -222.626428)
		)
		(stroke
			(width 0)
			(type solid)
		)
		(fill yes)
		(layer "In11.Cu")
		(net "PVCCFA_EHV_FIVRA_CPU0")
	)
	(gr_poly
		(pts
			(xy 100.561902 -223.120966) (xy 100.503482 -223.062292) (xy 100.473256 -223.07296) (xy 100.446502 -223.081846)
			(xy 100.390951 -223.091426) (xy 100.362766 -223.09201) (xy 100.337019 -223.091515) (xy 100.28615 -223.083521)
			(xy 100.237136 -223.067733) (xy 100.191166 -223.044532) (xy 100.149351 -223.01448) (xy 100.112704 -222.978305)
			(xy 100.082114 -222.936882) (xy 100.058319 -222.891216) (xy 100.041898 -222.842411) (xy 100.033246 -222.791649)
			(xy 100.032574 -222.74016) (xy 100.039898 -222.68919) (xy 100.055041 -222.639973) (xy 100.077636 -222.593701)
			(xy 100.107135 -222.551495) (xy 100.142825 -222.514376) (xy 100.183842 -222.483243) (xy 100.229192 -222.45885)
			(xy 100.277776 -222.441788) (xy 100.32842 -222.43247) (xy 100.379896 -222.431121) (xy 100.430958 -222.437774)
			(xy 100.48037 -222.452268) (xy 100.526935 -222.474253) (xy 100.569525 -222.503195) (xy 100.60711 -222.538393)
			(xy 100.63878 -222.578997) (xy 100.663767 -222.624022) (xy 100.681466 -222.672378) (xy 100.69145 -222.722895)
			(xy 100.692966 -222.748602) (xy 100.694002 -222.763322) (xy 100.703461 -222.79126) (xy 100.720514 -222.815327)
			(xy 100.743736 -222.833514) (xy 100.771189 -222.844301) (xy 100.80058 -222.846787) (xy 100.829455 -222.840766)
			(xy 100.855403 -222.82674) (xy 100.866194 -222.816674) (xy 100.97643 -222.706438) (xy 100.979478 -222.69196)
			(xy 100.985095 -222.668015) (xy 101.002474 -222.622005) (xy 101.026502 -222.579093) (xy 101.0412 -222.559372)
			(xy 101.0412 -222.366332) (xy 101.04065 -222.350881) (xy 101.031406 -222.321393) (xy 101.01378 -222.29601)
			(xy 100.98938 -222.277046) (xy 100.960432 -222.26623) (xy 100.929575 -222.264548) (xy 100.914454 -222.26778)
			(xy 100.89429 -222.272631) (xy 100.853148 -222.277856) (xy 100.832412 -222.278194) (xy 100.806443 -222.277686)
			(xy 100.755144 -222.269563) (xy 100.705747 -222.253516) (xy 100.659469 -222.22994) (xy 100.617448 -222.199414)
			(xy 100.58072 -222.162691) (xy 100.550188 -222.120675) (xy 100.526604 -222.074401) (xy 100.510549 -222.025006)
			(xy 100.502418 -221.973709) (xy 100.501958 -221.94774) (xy 100.502568 -221.919759) (xy 100.512015 -221.8646)
			(xy 100.520754 -221.838012) (xy 100.528374 -221.815914) (xy 100.324666 -221.463108) (xy 100.301806 -221.45879)
			(xy 100.276879 -221.453638) (xy 100.228882 -221.436693) (xy 100.184052 -221.412586) (xy 100.143451 -221.381889)
			(xy 100.108038 -221.345327) (xy 100.078652 -221.303766) (xy 100.055989 -221.258189) (xy 100.040585 -221.209676)
			(xy 100.032805 -221.159374) (xy 100.032312 -221.133924) (xy 100.032821 -221.107957) (xy 100.040946 -221.056662)
			(xy 100.056994 -221.007269) (xy 100.080572 -220.960995) (xy 100.111098 -220.918979) (xy 100.147821 -220.882256)
			(xy 100.189837 -220.85173) (xy 100.236111 -220.828152) (xy 100.285504 -220.812104) (xy 100.336799 -220.803979)
			(xy 100.388733 -220.803979) (xy 100.440028 -220.812104) (xy 100.489421 -220.828152) (xy 100.535695 -220.85173)
			(xy 100.577711 -220.882256) (xy 100.614434 -220.918979) (xy 100.64496 -220.960995) (xy 100.668538 -221.007269)
			(xy 100.684586 -221.056662) (xy 100.692711 -221.107957) (xy 100.69322 -221.133924) (xy 100.692605 -221.161904)
			(xy 100.68315 -221.21706) (xy 100.674424 -221.243652) (xy 100.666804 -221.26575) (xy 100.870512 -221.618556)
			(xy 100.893372 -221.622874) (xy 100.914454 -221.6277) (xy 100.929568 -221.631002) (xy 100.960446 -221.629346)
			(xy 100.989416 -221.618531) (xy 101.013824 -221.599547) (xy 101.031437 -221.574131) (xy 101.040642 -221.54461)
			(xy 101.0412 -221.529148) (xy 101.0412 -221.336108) (xy 101.024988 -221.314245) (xy 100.999191 -221.266322)
			(xy 100.981594 -221.21482) (xy 100.972674 -221.161131) (xy 100.972671 -221.106706) (xy 100.981585 -221.053016)
			(xy 100.999176 -221.001513) (xy 101.024967 -220.953587) (xy 101.0412 -220.93174) (xy 101.0412 -220.738446)
			(xy 101.040663 -220.722999) (xy 101.03143 -220.693517) (xy 101.013797 -220.66815) (xy 100.989379 -220.649224)
			(xy 100.960417 -220.638473) (xy 100.929564 -220.636883) (xy 100.914454 -220.640148) (xy 100.894345 -220.64492)
			(xy 100.853331 -220.650013) (xy 100.832666 -220.650308) (xy 100.806704 -220.649796) (xy 100.75542 -220.641669)
			(xy 100.706039 -220.62562) (xy 100.659776 -220.602043) (xy 100.617771 -220.571521) (xy 100.581057 -220.534803)
			(xy 100.550539 -220.492795) (xy 100.526967 -220.446529) (xy 100.510923 -220.397147) (xy 100.502801 -220.345862)
			(xy 100.502801 -220.293938) (xy 100.510923 -220.242653) (xy 100.526967 -220.193271) (xy 100.550539 -220.147005)
			(xy 100.581057 -220.104997) (xy 100.617771 -220.068279) (xy 100.659776 -220.037757) (xy 100.706039 -220.01418)
			(xy 100.75542 -219.998131) (xy 100.806704 -219.990004) (xy 100.832666 -219.9894) (xy 100.853331 -219.989688)
			(xy 100.894346 -219.994784) (xy 100.914454 -219.99956) (xy 100.92955 -220.002859) (xy 100.960392 -220.001218)
			(xy 100.989337 -219.990442) (xy 101.013744 -219.971516) (xy 101.031387 -219.946166) (xy 101.040656 -219.916704)
			(xy 101.0412 -219.901262) (xy 101.0412 -219.708222) (xy 101.024987 -219.686359) (xy 100.999187 -219.638436)
			(xy 100.981589 -219.586933) (xy 100.972666 -219.533243) (xy 100.972661 -219.478817) (xy 100.981574 -219.425125)
			(xy 100.999163 -219.373619) (xy 101.024954 -219.325692) (xy 101.0412 -219.303854) (xy 101.0412 -219.110814)
			(xy 101.040648 -219.095365) (xy 101.0314 -219.065882) (xy 101.013774 -219.040504) (xy 100.989376 -219.021543)
			(xy 100.960431 -219.010729) (xy 100.929578 -219.009048) (xy 100.914454 -219.012262) (xy 100.89429 -219.017113)
			(xy 100.853148 -219.022338) (xy 100.832412 -219.022676) (xy 100.806444 -219.022168) (xy 100.755146 -219.014045)
			(xy 100.70575 -218.997998) (xy 100.659473 -218.974421) (xy 100.617454 -218.943895) (xy 100.580727 -218.907172)
			(xy 100.550197 -218.865156) (xy 100.526615 -218.818881) (xy 100.510563 -218.769487) (xy 100.502435 -218.71819)
			(xy 100.501958 -218.692222) (xy 100.50257 -218.664242) (xy 100.512019 -218.609083) (xy 100.520754 -218.582494)
			(xy 100.528374 -218.560396) (xy 100.324666 -218.20759) (xy 100.301806 -218.203272) (xy 100.276879 -218.198119)
			(xy 100.228884 -218.181174) (xy 100.184056 -218.157067) (xy 100.143456 -218.126369) (xy 100.108045 -218.089807)
			(xy 100.078662 -218.048246) (xy 100.056001 -218.00267) (xy 100.0406 -217.954157) (xy 100.032822 -217.903856)
			(xy 100.032312 -217.878406) (xy 100.032821 -217.852439) (xy 100.040946 -217.801144) (xy 100.056994 -217.751751)
			(xy 100.080572 -217.705477) (xy 100.111098 -217.663461) (xy 100.147821 -217.626738) (xy 100.189837 -217.596212)
			(xy 100.236111 -217.572634) (xy 100.285504 -217.556586) (xy 100.336799 -217.548461) (xy 100.388733 -217.548461)
			(xy 100.440028 -217.556586) (xy 100.489421 -217.572634) (xy 100.535695 -217.596212) (xy 100.577711 -217.626738)
			(xy 100.614434 -217.663461) (xy 100.64496 -217.705477) (xy 100.668538 -217.751751) (xy 100.684586 -217.801144)
			(xy 100.692711 -217.852439) (xy 100.69322 -217.878406) (xy 100.692606 -217.906386) (xy 100.683154 -217.961544)
			(xy 100.674424 -217.988134) (xy 100.666804 -218.010232) (xy 100.870512 -218.363038) (xy 100.893372 -218.367356)
			(xy 100.914454 -218.372182) (xy 100.929567 -218.375484) (xy 100.960444 -218.373829) (xy 100.989412 -218.363014)
			(xy 101.013818 -218.344028) (xy 101.031427 -218.318612) (xy 101.040627 -218.289091) (xy 101.0412 -218.27363)
			(xy 101.0412 -218.08059) (xy 101.024987 -218.058727) (xy 100.999186 -218.010806) (xy 100.981583 -217.959306)
			(xy 100.972651 -217.905619) (xy 100.972112 -217.878406) (xy 100.972559 -217.852946) (xy 100.98033 -217.802622)
			(xy 100.995734 -217.754089) (xy 101.006656 -217.731086) (xy 101.022912 -217.69832) (xy 100.68433 -217.359738)
			(xy 100.677472 -217.356182) (xy 100.656027 -217.344272) (xy 100.616596 -217.315092) (xy 100.58191 -217.280406)
			(xy 100.55273 -217.240976) (xy 100.54082 -217.21953) (xy 100.537264 -217.212672) (xy 100.37826 -217.053668)
			(xy 100.226114 -217.053668) (xy 100.221288 -217.099134) (xy 100.217982 -217.125383) (xy 100.204099 -217.176431)
			(xy 100.182262 -217.224615) (xy 100.153028 -217.268706) (xy 100.117145 -217.307578) (xy 100.075529 -217.340238)
			(xy 100.029241 -217.365853) (xy 99.979465 -217.383767) (xy 99.953572 -217.389202) (xy 99.930712 -217.39352)
			(xy 99.727004 -217.74658) (xy 99.734624 -217.768678) (xy 99.743416 -217.795252) (xy 99.752865 -217.85042)
			(xy 99.75342 -217.878406) (xy 99.752911 -217.904373) (xy 99.744786 -217.955668) (xy 99.728738 -218.005061)
			(xy 99.70516 -218.051335) (xy 99.674634 -218.093351) (xy 99.637911 -218.130074) (xy 99.595895 -218.1606)
			(xy 99.549621 -218.184178) (xy 99.500228 -218.200226) (xy 99.448933 -218.208351) (xy 99.396999 -218.208351)
			(xy 99.345704 -218.200226) (xy 99.296311 -218.184178) (xy 99.250037 -218.1606) (xy 99.208021 -218.130074)
			(xy 99.171298 -218.093351) (xy 99.140772 -218.051335) (xy 99.117194 -218.005061) (xy 99.101146 -217.955668)
			(xy 99.093021 -217.904373) (xy 99.092512 -217.878406) (xy 99.092987 -217.852961) (xy 99.1008 -217.802674)
			(xy 99.116228 -217.754178) (xy 99.138904 -217.70862) (xy 99.168295 -217.667074) (xy 99.203705 -217.630524)
			(xy 99.244298 -217.599831) (xy 99.289115 -217.575722) (xy 99.337097 -217.558766) (xy 99.362006 -217.55354)
			(xy 99.384866 -217.549222) (xy 99.588574 -217.196162) (xy 99.580954 -217.174064) (xy 99.574786 -217.155817)
			(xy 99.566256 -217.118255) (xy 99.563936 -217.099134) (xy 99.55911 -217.053668) (xy 99.286568 -217.053668)
			(xy 99.281742 -217.099134) (xy 99.278587 -217.124446) (xy 99.265487 -217.173743) (xy 99.244969 -217.220443)
			(xy 99.217521 -217.263435) (xy 99.183793 -217.301701) (xy 99.144587 -217.33433) (xy 99.100833 -217.360548)
			(xy 99.053571 -217.379734) (xy 99.003922 -217.39143) (xy 98.953066 -217.39536) (xy 98.90221 -217.39143)
			(xy 98.852561 -217.379734) (xy 98.805299 -217.360548) (xy 98.761545 -217.33433) (xy 98.722339 -217.301701)
			(xy 98.688611 -217.263435) (xy 98.661163 -217.220443) (xy 98.640645 -217.173743) (xy 98.627545 -217.124446)
			(xy 98.62439 -217.099134) (xy 98.619564 -217.053668) (xy 98.346514 -217.053668) (xy 98.341688 -217.099134)
			(xy 98.338382 -217.125383) (xy 98.324499 -217.176431) (xy 98.302662 -217.224615) (xy 98.273428 -217.268706)
			(xy 98.237545 -217.307578) (xy 98.195929 -217.340238) (xy 98.149641 -217.365853) (xy 98.099865 -217.383767)
			(xy 98.073972 -217.389202) (xy 98.051112 -217.39352) (xy 97.847404 -217.74658) (xy 97.855024 -217.768678)
			(xy 97.863816 -217.795252) (xy 97.873265 -217.85042) (xy 97.87382 -217.878406) (xy 98.152712 -217.878406)
			(xy 98.153221 -217.852439) (xy 98.161346 -217.801144) (xy 98.177394 -217.751751) (xy 98.200972 -217.705477)
			(xy 98.231498 -217.663461) (xy 98.268221 -217.626738) (xy 98.310237 -217.596212) (xy 98.356511 -217.572634)
			(xy 98.405904 -217.556586) (xy 98.457199 -217.548461) (xy 98.509133 -217.548461) (xy 98.560428 -217.556586)
			(xy 98.609821 -217.572634) (xy 98.656095 -217.596212) (xy 98.698111 -217.626738) (xy 98.734834 -217.663461)
			(xy 98.76536 -217.705477) (xy 98.788938 -217.751751) (xy 98.804986 -217.801144) (xy 98.813111 -217.852439)
			(xy 98.81362 -217.878406) (xy 98.813068 -217.906392) (xy 98.803617 -217.96156) (xy 98.794824 -217.988134)
			(xy 98.787204 -218.010232) (xy 98.990912 -218.363038) (xy 99.013772 -218.367356) (xy 99.038696 -218.37251)
			(xy 99.08668 -218.389479) (xy 99.131496 -218.413599) (xy 99.172088 -218.444302) (xy 99.207496 -218.480861)
			(xy 99.236884 -218.522415) (xy 99.259557 -218.56798) (xy 99.274982 -218.616482) (xy 99.282792 -218.666774)
			(xy 99.283266 -218.692222) (xy 99.282757 -218.718189) (xy 99.274632 -218.769484) (xy 99.258584 -218.818877)
			(xy 99.235006 -218.865151) (xy 99.20448 -218.907167) (xy 99.167757 -218.94389) (xy 99.125741 -218.974416)
			(xy 99.079467 -218.997994) (xy 99.030074 -219.014042) (xy 98.978779 -219.022167) (xy 98.926845 -219.022167)
			(xy 98.87555 -219.014042) (xy 98.826157 -218.997994) (xy 98.779883 -218.974416) (xy 98.737867 -218.94389)
			(xy 98.701144 -218.907167) (xy 98.670618 -218.865151) (xy 98.64704 -218.818877) (xy 98.630992 -218.769484)
			(xy 98.622867 -218.718189) (xy 98.622358 -218.692222) (xy 98.622913 -218.664236) (xy 98.632361 -218.609068)
			(xy 98.641154 -218.582494) (xy 98.648774 -218.560396) (xy 98.445066 -218.20759) (xy 98.422206 -218.203272)
			(xy 98.3973 -218.198035) (xy 98.349319 -218.18108) (xy 98.304502 -218.156972) (xy 98.263909 -218.12628)
			(xy 98.228499 -218.089731) (xy 98.199108 -218.048187) (xy 98.176431 -218.00263) (xy 98.161003 -217.954136)
			(xy 98.153188 -217.90385) (xy 98.152712 -217.878406) (xy 97.87382 -217.878406) (xy 97.873311 -217.904373)
			(xy 97.865186 -217.955668) (xy 97.849138 -218.005061) (xy 97.82556 -218.051335) (xy 97.795034 -218.093351)
			(xy 97.758311 -218.130074) (xy 97.716295 -218.1606) (xy 97.670021 -218.184178) (xy 97.620628 -218.200226)
			(xy 97.569333 -218.208351) (xy 97.517399 -218.208351) (xy 97.466104 -218.200226) (xy 97.416711 -218.184178)
			(xy 97.370437 -218.1606) (xy 97.328421 -218.130074) (xy 97.291698 -218.093351) (xy 97.261172 -218.051335)
			(xy 97.237594 -218.005061) (xy 97.221546 -217.955668) (xy 97.213421 -217.904373) (xy 97.212912 -217.878406)
			(xy 97.213387 -217.852961) (xy 97.2212 -217.802674) (xy 97.236628 -217.754178) (xy 97.259304 -217.70862)
			(xy 97.288695 -217.667074) (xy 97.324105 -217.630524) (xy 97.364698 -217.599831) (xy 97.409515 -217.575722)
			(xy 97.457497 -217.558766) (xy 97.482406 -217.55354) (xy 97.505266 -217.549222) (xy 97.708974 -217.196162)
			(xy 97.701354 -217.174064) (xy 97.695186 -217.155817) (xy 97.686656 -217.118255) (xy 97.684336 -217.099134)
			(xy 97.67951 -217.053668) (xy 97.406968 -217.053668) (xy 97.402142 -217.099134) (xy 97.398987 -217.124446)
			(xy 97.385887 -217.173743) (xy 97.365369 -217.220443) (xy 97.337921 -217.263435) (xy 97.304193 -217.301701)
			(xy 97.264987 -217.33433) (xy 97.221233 -217.360548) (xy 97.173971 -217.379734) (xy 97.124322 -217.39143)
			(xy 97.073466 -217.39536) (xy 97.02261 -217.39143) (xy 96.972961 -217.379734) (xy 96.925699 -217.360548)
			(xy 96.881945 -217.33433) (xy 96.842739 -217.301701) (xy 96.809011 -217.263435) (xy 96.781563 -217.220443)
			(xy 96.761045 -217.173743) (xy 96.747945 -217.124446) (xy 96.74479 -217.099134) (xy 96.739964 -217.053668)
			(xy 96.466914 -217.053668) (xy 96.462088 -217.099134) (xy 96.458782 -217.125383) (xy 96.444899 -217.176431)
			(xy 96.423062 -217.224615) (xy 96.393828 -217.268706) (xy 96.357945 -217.307578) (xy 96.316329 -217.340238)
			(xy 96.270041 -217.365853) (xy 96.220265 -217.383767) (xy 96.194372 -217.389202) (xy 96.171512 -217.39352)
			(xy 95.967804 -217.74658) (xy 95.975424 -217.768678) (xy 95.984216 -217.795252) (xy 95.993665 -217.85042)
			(xy 95.99422 -217.878406) (xy 96.273112 -217.878406) (xy 96.273621 -217.852439) (xy 96.281746 -217.801144)
			(xy 96.297794 -217.751751) (xy 96.321372 -217.705477) (xy 96.351898 -217.663461) (xy 96.388621 -217.626738)
			(xy 96.430637 -217.596212) (xy 96.476911 -217.572634) (xy 96.526304 -217.556586) (xy 96.577599 -217.548461)
			(xy 96.629533 -217.548461) (xy 96.680828 -217.556586) (xy 96.730221 -217.572634) (xy 96.776495 -217.596212)
			(xy 96.818511 -217.626738) (xy 96.855234 -217.663461) (xy 96.88576 -217.705477) (xy 96.909338 -217.751751)
			(xy 96.925386 -217.801144) (xy 96.933511 -217.852439) (xy 96.93402 -217.878406) (xy 96.933468 -217.906392)
			(xy 96.924017 -217.96156) (xy 96.915224 -217.988134) (xy 96.907604 -218.010232) (xy 97.111312 -218.363038)
			(xy 97.134172 -218.367356) (xy 97.159096 -218.37251) (xy 97.20708 -218.389479) (xy 97.251896 -218.413599)
			(xy 97.292488 -218.444302) (xy 97.327896 -218.480861) (xy 97.357284 -218.522415) (xy 97.379957 -218.56798)
			(xy 97.395382 -218.616482) (xy 97.403192 -218.666774) (xy 97.403666 -218.692222) (xy 97.403157 -218.718189)
			(xy 97.395032 -218.769484) (xy 97.378984 -218.818877) (xy 97.355406 -218.865151) (xy 97.32488 -218.907167)
			(xy 97.288157 -218.94389) (xy 97.246141 -218.974416) (xy 97.199867 -218.997994) (xy 97.150474 -219.014042)
			(xy 97.099179 -219.022167) (xy 97.047245 -219.022167) (xy 96.99595 -219.014042) (xy 96.946557 -218.997994)
			(xy 96.900283 -218.974416) (xy 96.858267 -218.94389) (xy 96.821544 -218.907167) (xy 96.791018 -218.865151)
			(xy 96.76744 -218.818877) (xy 96.751392 -218.769484) (xy 96.743267 -218.718189) (xy 96.742758 -218.692222)
			(xy 96.743313 -218.664236) (xy 96.752761 -218.609068) (xy 96.761554 -218.582494) (xy 96.769174 -218.560396)
			(xy 96.565466 -218.20759) (xy 96.542606 -218.203272) (xy 96.5177 -218.198035) (xy 96.469719 -218.18108)
			(xy 96.424902 -218.156972) (xy 96.384309 -218.12628) (xy 96.348899 -218.089731) (xy 96.319508 -218.048187)
			(xy 96.296831 -218.00263) (xy 96.281403 -217.954136) (xy 96.273588 -217.90385) (xy 96.273112 -217.878406)
			(xy 95.99422 -217.878406) (xy 95.993711 -217.904373) (xy 95.985586 -217.955668) (xy 95.969538 -218.005061)
			(xy 95.94596 -218.051335) (xy 95.915434 -218.093351) (xy 95.878711 -218.130074) (xy 95.836695 -218.1606)
			(xy 95.790421 -218.184178) (xy 95.741028 -218.200226) (xy 95.689733 -218.208351) (xy 95.637799 -218.208351)
			(xy 95.586504 -218.200226) (xy 95.537111 -218.184178) (xy 95.490837 -218.1606) (xy 95.448821 -218.130074)
			(xy 95.412098 -218.093351) (xy 95.381572 -218.051335) (xy 95.357994 -218.005061) (xy 95.341946 -217.955668)
			(xy 95.333821 -217.904373) (xy 95.333312 -217.878406) (xy 95.333787 -217.852961) (xy 95.3416 -217.802674)
			(xy 95.357028 -217.754178) (xy 95.379704 -217.70862) (xy 95.409095 -217.667074) (xy 95.444505 -217.630524)
			(xy 95.485098 -217.599831) (xy 95.529915 -217.575722) (xy 95.577897 -217.558766) (xy 95.602806 -217.55354)
			(xy 95.625666 -217.549222) (xy 95.829374 -217.196162) (xy 95.821754 -217.174064) (xy 95.815586 -217.155817)
			(xy 95.807056 -217.118255) (xy 95.804736 -217.099134) (xy 95.79991 -217.053668) (xy 95.527368 -217.053668)
			(xy 95.522542 -217.099134) (xy 95.519387 -217.124446) (xy 95.506287 -217.173743) (xy 95.485769 -217.220443)
			(xy 95.458321 -217.263435) (xy 95.424593 -217.301701) (xy 95.385387 -217.33433) (xy 95.341633 -217.360548)
			(xy 95.294371 -217.379734) (xy 95.244722 -217.39143) (xy 95.193866 -217.39536) (xy 95.14301 -217.39143)
			(xy 95.093361 -217.379734) (xy 95.046099 -217.360548) (xy 95.002345 -217.33433) (xy 94.963139 -217.301701)
			(xy 94.929411 -217.263435) (xy 94.901963 -217.220443) (xy 94.881445 -217.173743) (xy 94.868345 -217.124446)
			(xy 94.86519 -217.099134) (xy 94.860364 -217.053668) (xy 94.587314 -217.053668) (xy 94.582488 -217.099134)
			(xy 94.579182 -217.125383) (xy 94.565299 -217.176431) (xy 94.543462 -217.224615) (xy 94.514228 -217.268706)
			(xy 94.478345 -217.307578) (xy 94.436729 -217.340238) (xy 94.390441 -217.365853) (xy 94.340665 -217.383767)
			(xy 94.314772 -217.389202) (xy 94.291912 -217.39352) (xy 94.088204 -217.74658) (xy 94.095824 -217.768678)
			(xy 94.104616 -217.795252) (xy 94.114065 -217.85042) (xy 94.11462 -217.878406) (xy 94.393512 -217.878406)
			(xy 94.394021 -217.852439) (xy 94.402146 -217.801144) (xy 94.418194 -217.751751) (xy 94.441772 -217.705477)
			(xy 94.472298 -217.663461) (xy 94.509021 -217.626738) (xy 94.551037 -217.596212) (xy 94.597311 -217.572634)
			(xy 94.646704 -217.556586) (xy 94.697999 -217.548461) (xy 94.749933 -217.548461) (xy 94.801228 -217.556586)
			(xy 94.850621 -217.572634) (xy 94.896895 -217.596212) (xy 94.938911 -217.626738) (xy 94.975634 -217.663461)
			(xy 95.00616 -217.705477) (xy 95.029738 -217.751751) (xy 95.045786 -217.801144) (xy 95.053911 -217.852439)
			(xy 95.05442 -217.878406) (xy 95.053868 -217.906392) (xy 95.044417 -217.96156) (xy 95.035624 -217.988134)
			(xy 95.028004 -218.010232) (xy 95.231712 -218.363038) (xy 95.254572 -218.367356) (xy 95.279496 -218.37251)
			(xy 95.32748 -218.389479) (xy 95.372296 -218.413599) (xy 95.412888 -218.444302) (xy 95.448296 -218.480861)
			(xy 95.477684 -218.522415) (xy 95.500357 -218.56798) (xy 95.515782 -218.616482) (xy 95.523592 -218.666774)
			(xy 95.524066 -218.692222) (xy 95.523557 -218.718189) (xy 95.515432 -218.769484) (xy 95.499384 -218.818877)
			(xy 95.475806 -218.865151) (xy 95.44528 -218.907167) (xy 95.408557 -218.94389) (xy 95.366541 -218.974416)
			(xy 95.320267 -218.997994) (xy 95.270874 -219.014042) (xy 95.219579 -219.022167) (xy 95.167645 -219.022167)
			(xy 95.11635 -219.014042) (xy 95.066957 -218.997994) (xy 95.020683 -218.974416) (xy 94.978667 -218.94389)
			(xy 94.941944 -218.907167) (xy 94.911418 -218.865151) (xy 94.88784 -218.818877) (xy 94.871792 -218.769484)
			(xy 94.863667 -218.718189) (xy 94.863158 -218.692222) (xy 94.863713 -218.664236) (xy 94.873161 -218.609068)
			(xy 94.881954 -218.582494) (xy 94.889574 -218.560396) (xy 94.685866 -218.20759) (xy 94.663006 -218.203272)
			(xy 94.6381 -218.198035) (xy 94.590119 -218.18108) (xy 94.545302 -218.156972) (xy 94.504709 -218.12628)
			(xy 94.469299 -218.089731) (xy 94.439908 -218.048187) (xy 94.417231 -218.00263) (xy 94.401803 -217.954136)
			(xy 94.393988 -217.90385) (xy 94.393512 -217.878406) (xy 94.11462 -217.878406) (xy 94.114111 -217.904373)
			(xy 94.105986 -217.955668) (xy 94.089938 -218.005061) (xy 94.06636 -218.051335) (xy 94.035834 -218.093351)
			(xy 93.999111 -218.130074) (xy 93.957095 -218.1606) (xy 93.910821 -218.184178) (xy 93.861428 -218.200226)
			(xy 93.810133 -218.208351) (xy 93.758199 -218.208351) (xy 93.706904 -218.200226) (xy 93.657511 -218.184178)
			(xy 93.611237 -218.1606) (xy 93.569221 -218.130074) (xy 93.532498 -218.093351) (xy 93.501972 -218.051335)
			(xy 93.478394 -218.005061) (xy 93.462346 -217.955668) (xy 93.454221 -217.904373) (xy 93.453712 -217.878406)
			(xy 93.454187 -217.852961) (xy 93.462 -217.802674) (xy 93.477428 -217.754178) (xy 93.500104 -217.70862)
			(xy 93.529495 -217.667074) (xy 93.564905 -217.630524) (xy 93.605498 -217.599831) (xy 93.650315 -217.575722)
			(xy 93.698297 -217.558766) (xy 93.723206 -217.55354) (xy 93.746066 -217.549222) (xy 93.949774 -217.196162)
			(xy 93.942154 -217.174064) (xy 93.935986 -217.155817) (xy 93.927456 -217.118255) (xy 93.925136 -217.099134)
			(xy 93.92031 -217.053668) (xy 93.647768 -217.053668) (xy 93.642942 -217.099134) (xy 93.639787 -217.124446)
			(xy 93.626687 -217.173743) (xy 93.606169 -217.220443) (xy 93.578721 -217.263435) (xy 93.544993 -217.301701)
			(xy 93.505787 -217.33433) (xy 93.462033 -217.360548) (xy 93.414771 -217.379734) (xy 93.365122 -217.39143)
			(xy 93.314266 -217.39536) (xy 93.26341 -217.39143) (xy 93.213761 -217.379734) (xy 93.166499 -217.360548)
			(xy 93.122745 -217.33433) (xy 93.083539 -217.301701) (xy 93.049811 -217.263435) (xy 93.022363 -217.220443)
			(xy 93.001845 -217.173743) (xy 92.988745 -217.124446) (xy 92.98559 -217.099134) (xy 92.980764 -217.053668)
			(xy 92.707714 -217.053668) (xy 92.702888 -217.099134) (xy 92.699582 -217.125383) (xy 92.685699 -217.176431)
			(xy 92.663862 -217.224615) (xy 92.634628 -217.268706) (xy 92.598745 -217.307578) (xy 92.557129 -217.340238)
			(xy 92.510841 -217.365853) (xy 92.461065 -217.383767) (xy 92.435172 -217.389202) (xy 92.412312 -217.39352)
			(xy 92.208604 -217.74658) (xy 92.216224 -217.768678) (xy 92.225016 -217.795252) (xy 92.234465 -217.85042)
			(xy 92.23502 -217.878406) (xy 92.513912 -217.878406) (xy 92.514421 -217.852439) (xy 92.522546 -217.801144)
			(xy 92.538594 -217.751751) (xy 92.562172 -217.705477) (xy 92.592698 -217.663461) (xy 92.629421 -217.626738)
			(xy 92.671437 -217.596212) (xy 92.717711 -217.572634) (xy 92.767104 -217.556586) (xy 92.818399 -217.548461)
			(xy 92.870333 -217.548461) (xy 92.921628 -217.556586) (xy 92.971021 -217.572634) (xy 93.017295 -217.596212)
			(xy 93.059311 -217.626738) (xy 93.096034 -217.663461) (xy 93.12656 -217.705477) (xy 93.150138 -217.751751)
			(xy 93.166186 -217.801144) (xy 93.174311 -217.852439) (xy 93.17482 -217.878406) (xy 93.174268 -217.906392)
			(xy 93.164817 -217.96156) (xy 93.156024 -217.988134) (xy 93.148404 -218.010232) (xy 93.352112 -218.363038)
			(xy 93.374972 -218.367356) (xy 93.399896 -218.37251) (xy 93.44788 -218.389479) (xy 93.492696 -218.413599)
			(xy 93.533288 -218.444302) (xy 93.568696 -218.480861) (xy 93.598084 -218.522415) (xy 93.620757 -218.56798)
			(xy 93.636182 -218.616482) (xy 93.643992 -218.666774) (xy 93.644466 -218.692222) (xy 93.643957 -218.718189)
			(xy 93.635832 -218.769484) (xy 93.619784 -218.818877) (xy 93.596206 -218.865151) (xy 93.56568 -218.907167)
			(xy 93.528957 -218.94389) (xy 93.486941 -218.974416) (xy 93.440667 -218.997994) (xy 93.391274 -219.014042)
			(xy 93.339979 -219.022167) (xy 93.288045 -219.022167) (xy 93.23675 -219.014042) (xy 93.187357 -218.997994)
			(xy 93.141083 -218.974416) (xy 93.099067 -218.94389) (xy 93.062344 -218.907167) (xy 93.031818 -218.865151)
			(xy 93.00824 -218.818877) (xy 92.992192 -218.769484) (xy 92.984067 -218.718189) (xy 92.983558 -218.692222)
			(xy 92.984113 -218.664236) (xy 92.993561 -218.609068) (xy 93.002354 -218.582494) (xy 93.009974 -218.560396)
			(xy 92.806266 -218.20759) (xy 92.783406 -218.203272) (xy 92.7585 -218.198035) (xy 92.710519 -218.18108)
			(xy 92.665702 -218.156972) (xy 92.625109 -218.12628) (xy 92.589699 -218.089731) (xy 92.560308 -218.048187)
			(xy 92.537631 -218.00263) (xy 92.522203 -217.954136) (xy 92.514388 -217.90385) (xy 92.513912 -217.878406)
			(xy 92.23502 -217.878406) (xy 92.234511 -217.904373) (xy 92.226386 -217.955668) (xy 92.210338 -218.005061)
			(xy 92.18676 -218.051335) (xy 92.156234 -218.093351) (xy 92.119511 -218.130074) (xy 92.077495 -218.1606)
			(xy 92.031221 -218.184178) (xy 91.981828 -218.200226) (xy 91.930533 -218.208351) (xy 91.878599 -218.208351)
			(xy 91.827304 -218.200226) (xy 91.777911 -218.184178) (xy 91.731637 -218.1606) (xy 91.689621 -218.130074)
			(xy 91.652898 -218.093351) (xy 91.622372 -218.051335) (xy 91.598794 -218.005061) (xy 91.582746 -217.955668)
			(xy 91.574621 -217.904373) (xy 91.574112 -217.878406) (xy 91.574587 -217.852961) (xy 91.5824 -217.802674)
			(xy 91.597828 -217.754178) (xy 91.620504 -217.70862) (xy 91.649895 -217.667074) (xy 91.685305 -217.630524)
			(xy 91.725898 -217.599831) (xy 91.770715 -217.575722) (xy 91.818697 -217.558766) (xy 91.843606 -217.55354)
			(xy 91.866466 -217.549222) (xy 92.070174 -217.196162) (xy 92.062554 -217.174064) (xy 92.056386 -217.155817)
			(xy 92.047856 -217.118255) (xy 92.045536 -217.099134) (xy 92.04071 -217.053668) (xy 91.768168 -217.053668)
			(xy 91.763342 -217.099134) (xy 91.760187 -217.124446) (xy 91.747087 -217.173743) (xy 91.726569 -217.220443)
			(xy 91.699121 -217.263435) (xy 91.665393 -217.301701) (xy 91.626187 -217.33433) (xy 91.582433 -217.360548)
			(xy 91.535171 -217.379734) (xy 91.485522 -217.39143) (xy 91.434666 -217.39536) (xy 91.38381 -217.39143)
			(xy 91.334161 -217.379734) (xy 91.286899 -217.360548) (xy 91.243145 -217.33433) (xy 91.203939 -217.301701)
			(xy 91.170211 -217.263435) (xy 91.142763 -217.220443) (xy 91.122245 -217.173743) (xy 91.109145 -217.124446)
			(xy 91.10599 -217.099134) (xy 91.101164 -217.053668) (xy 90.828114 -217.053668) (xy 90.823288 -217.099134)
			(xy 90.819982 -217.125383) (xy 90.806099 -217.176431) (xy 90.784262 -217.224615) (xy 90.755028 -217.268706)
			(xy 90.719145 -217.307578) (xy 90.677529 -217.340238) (xy 90.631241 -217.365853) (xy 90.581465 -217.383767)
			(xy 90.555572 -217.389202) (xy 90.532712 -217.39352) (xy 90.329004 -217.74658) (xy 90.336624 -217.768678)
			(xy 90.345416 -217.795252) (xy 90.354865 -217.85042) (xy 90.35542 -217.878406) (xy 90.634312 -217.878406)
			(xy 90.634821 -217.852439) (xy 90.642946 -217.801144) (xy 90.658994 -217.751751) (xy 90.682572 -217.705477)
			(xy 90.713098 -217.663461) (xy 90.749821 -217.626738) (xy 90.791837 -217.596212) (xy 90.838111 -217.572634)
			(xy 90.887504 -217.556586) (xy 90.938799 -217.548461) (xy 90.990733 -217.548461) (xy 91.042028 -217.556586)
			(xy 91.091421 -217.572634) (xy 91.137695 -217.596212) (xy 91.179711 -217.626738) (xy 91.216434 -217.663461)
			(xy 91.24696 -217.705477) (xy 91.270538 -217.751751) (xy 91.286586 -217.801144) (xy 91.294711 -217.852439)
			(xy 91.29522 -217.878406) (xy 91.294668 -217.906392) (xy 91.285217 -217.96156) (xy 91.276424 -217.988134)
			(xy 91.268804 -218.010232) (xy 91.472512 -218.363038) (xy 91.495372 -218.367356) (xy 91.520296 -218.37251)
			(xy 91.56828 -218.389479) (xy 91.613096 -218.413599) (xy 91.653688 -218.444302) (xy 91.689096 -218.480861)
			(xy 91.718484 -218.522415) (xy 91.741157 -218.56798) (xy 91.756582 -218.616482) (xy 91.764392 -218.666774)
			(xy 91.764866 -218.692222) (xy 91.764357 -218.718189) (xy 91.756232 -218.769484) (xy 91.740184 -218.818877)
			(xy 91.716606 -218.865151) (xy 91.68608 -218.907167) (xy 91.649357 -218.94389) (xy 91.607341 -218.974416)
			(xy 91.561067 -218.997994) (xy 91.511674 -219.014042) (xy 91.460379 -219.022167) (xy 91.408445 -219.022167)
			(xy 91.35715 -219.014042) (xy 91.307757 -218.997994) (xy 91.261483 -218.974416) (xy 91.219467 -218.94389)
			(xy 91.182744 -218.907167) (xy 91.152218 -218.865151) (xy 91.12864 -218.818877) (xy 91.112592 -218.769484)
			(xy 91.104467 -218.718189) (xy 91.103958 -218.692222) (xy 91.104513 -218.664236) (xy 91.113961 -218.609068)
			(xy 91.122754 -218.582494) (xy 91.130374 -218.560396) (xy 90.926666 -218.20759) (xy 90.903806 -218.203272)
			(xy 90.8789 -218.198035) (xy 90.830919 -218.18108) (xy 90.786102 -218.156972) (xy 90.745509 -218.12628)
			(xy 90.710099 -218.089731) (xy 90.680708 -218.048187) (xy 90.658031 -218.00263) (xy 90.642603 -217.954136)
			(xy 90.634788 -217.90385) (xy 90.634312 -217.878406) (xy 90.35542 -217.878406) (xy 90.354911 -217.904373)
			(xy 90.346786 -217.955668) (xy 90.330738 -218.005061) (xy 90.30716 -218.051335) (xy 90.276634 -218.093351)
			(xy 90.239911 -218.130074) (xy 90.197895 -218.1606) (xy 90.151621 -218.184178) (xy 90.102228 -218.200226)
			(xy 90.050933 -218.208351) (xy 89.998999 -218.208351) (xy 89.947704 -218.200226) (xy 89.898311 -218.184178)
			(xy 89.852037 -218.1606) (xy 89.810021 -218.130074) (xy 89.773298 -218.093351) (xy 89.742772 -218.051335)
			(xy 89.719194 -218.005061) (xy 89.703146 -217.955668) (xy 89.695021 -217.904373) (xy 89.694512 -217.878406)
			(xy 89.694987 -217.852961) (xy 89.7028 -217.802674) (xy 89.718228 -217.754178) (xy 89.740904 -217.70862)
			(xy 89.770295 -217.667074) (xy 89.805705 -217.630524) (xy 89.846298 -217.599831) (xy 89.891115 -217.575722)
			(xy 89.939097 -217.558766) (xy 89.964006 -217.55354) (xy 89.986866 -217.549222) (xy 90.190574 -217.196162)
			(xy 90.182954 -217.174064) (xy 90.176786 -217.155817) (xy 90.168256 -217.118255) (xy 90.165936 -217.099134)
			(xy 90.16111 -217.053668) (xy 89.888568 -217.053668) (xy 89.883742 -217.099134) (xy 89.880587 -217.124446)
			(xy 89.867487 -217.173743) (xy 89.846969 -217.220443) (xy 89.819521 -217.263435) (xy 89.785793 -217.301701)
			(xy 89.746587 -217.33433) (xy 89.702833 -217.360548) (xy 89.655571 -217.379734) (xy 89.605922 -217.39143)
			(xy 89.555066 -217.39536) (xy 89.50421 -217.39143) (xy 89.454561 -217.379734) (xy 89.407299 -217.360548)
			(xy 89.363545 -217.33433) (xy 89.324339 -217.301701) (xy 89.290611 -217.263435) (xy 89.263163 -217.220443)
			(xy 89.242645 -217.173743) (xy 89.229545 -217.124446) (xy 89.22639 -217.099134) (xy 89.221564 -217.053668)
			(xy 88.948514 -217.053668) (xy 88.943688 -217.099134) (xy 88.94033 -217.125851) (xy 88.926063 -217.177772)
			(xy 88.903565 -217.226692) (xy 88.873434 -217.271316) (xy 88.836466 -217.310465) (xy 88.793639 -217.343102)
			(xy 88.746088 -217.368362) (xy 88.695069 -217.385579) (xy 88.641935 -217.394295) (xy 88.615012 -217.39479)
			(xy 88.587559 -217.394249) (xy 88.533408 -217.38518) (xy 88.4815 -217.367289) (xy 88.43326 -217.341068)
			(xy 88.390016 -217.307237) (xy 88.352954 -217.266727) (xy 88.323095 -217.220651) (xy 88.311736 -217.195654)
			(xy 88.305686 -217.182832) (xy 88.287718 -217.160914) (xy 88.264413 -217.144788) (xy 88.237569 -217.135699)
			(xy 88.209261 -217.134347) (xy 88.181673 -217.140839) (xy 88.156938 -217.154672) (xy 88.146636 -217.164412)
			(xy 87.68842 -217.622628) (xy 87.68842 -217.904373) (xy 87.815421 -217.904373) (xy 87.815421 -217.852439)
			(xy 87.823546 -217.801144) (xy 87.839594 -217.751751) (xy 87.863172 -217.705477) (xy 87.893698 -217.663461)
			(xy 87.930421 -217.626738) (xy 87.972437 -217.596212) (xy 88.018711 -217.572634) (xy 88.068104 -217.556586)
			(xy 88.119399 -217.548461) (xy 88.171333 -217.548461) (xy 88.222628 -217.556586) (xy 88.272021 -217.572634)
			(xy 88.318295 -217.596212) (xy 88.360311 -217.626738) (xy 88.397034 -217.663461) (xy 88.42756 -217.705477)
			(xy 88.451138 -217.751751) (xy 88.467186 -217.801144) (xy 88.475311 -217.852439) (xy 88.47582 -217.878406)
			(xy 88.754712 -217.878406) (xy 88.755221 -217.852439) (xy 88.763346 -217.801144) (xy 88.779394 -217.751751)
			(xy 88.802972 -217.705477) (xy 88.833498 -217.663461) (xy 88.870221 -217.626738) (xy 88.912237 -217.596212)
			(xy 88.958511 -217.572634) (xy 89.007904 -217.556586) (xy 89.059199 -217.548461) (xy 89.111133 -217.548461)
			(xy 89.162428 -217.556586) (xy 89.211821 -217.572634) (xy 89.258095 -217.596212) (xy 89.300111 -217.626738)
			(xy 89.336834 -217.663461) (xy 89.36736 -217.705477) (xy 89.390938 -217.751751) (xy 89.406986 -217.801144)
			(xy 89.415111 -217.852439) (xy 89.41562 -217.878406) (xy 89.415068 -217.906392) (xy 89.405617 -217.96156)
			(xy 89.396824 -217.988134) (xy 89.389204 -218.010232) (xy 89.592912 -218.363038) (xy 89.615772 -218.367356)
			(xy 89.640696 -218.37251) (xy 89.68868 -218.389479) (xy 89.733496 -218.413599) (xy 89.774088 -218.444302)
			(xy 89.809496 -218.480861) (xy 89.838884 -218.522415) (xy 89.861557 -218.56798) (xy 89.876982 -218.616482)
			(xy 89.884792 -218.666774) (xy 89.885266 -218.692222) (xy 89.884757 -218.718189) (xy 89.876632 -218.769484)
			(xy 89.860584 -218.818877) (xy 89.837006 -218.865151) (xy 89.80648 -218.907167) (xy 89.769757 -218.94389)
			(xy 89.727741 -218.974416) (xy 89.681467 -218.997994) (xy 89.632074 -219.014042) (xy 89.580779 -219.022167)
			(xy 89.528845 -219.022167) (xy 89.47755 -219.014042) (xy 89.428157 -218.997994) (xy 89.381883 -218.974416)
			(xy 89.339867 -218.94389) (xy 89.303144 -218.907167) (xy 89.272618 -218.865151) (xy 89.24904 -218.818877)
			(xy 89.232992 -218.769484) (xy 89.224867 -218.718189) (xy 89.224358 -218.692222) (xy 89.224913 -218.664236)
			(xy 89.234361 -218.609068) (xy 89.243154 -218.582494) (xy 89.250774 -218.560396) (xy 89.047066 -218.20759)
			(xy 89.024206 -218.203272) (xy 88.9993 -218.198035) (xy 88.951319 -218.18108) (xy 88.906502 -218.156972)
			(xy 88.865909 -218.12628) (xy 88.830499 -218.089731) (xy 88.801108 -218.048187) (xy 88.778431 -218.00263)
			(xy 88.763003 -217.954136) (xy 88.755188 -217.90385) (xy 88.754712 -217.878406) (xy 88.47582 -217.878406)
			(xy 88.475311 -217.904373) (xy 88.467186 -217.955668) (xy 88.451138 -218.005061) (xy 88.42756 -218.051335)
			(xy 88.397034 -218.093351) (xy 88.360311 -218.130074) (xy 88.318295 -218.1606) (xy 88.272021 -218.184178)
			(xy 88.222628 -218.200226) (xy 88.171333 -218.208351) (xy 88.119399 -218.208351) (xy 88.068104 -218.200226)
			(xy 88.018711 -218.184178) (xy 87.972437 -218.1606) (xy 87.930421 -218.130074) (xy 87.893698 -218.093351)
			(xy 87.863172 -218.051335) (xy 87.839594 -218.005061) (xy 87.823546 -217.955668) (xy 87.815421 -217.904373)
			(xy 87.68842 -217.904373) (xy 87.68842 -218.359228) (xy 87.730838 -218.36634) (xy 87.75616 -218.371141)
			(xy 87.805016 -218.387551) (xy 87.850732 -218.411346) (xy 87.8922 -218.441948) (xy 87.928416 -218.478616)
			(xy 87.958503 -218.52046) (xy 87.981729 -218.566467) (xy 87.997533 -218.615522) (xy 88.005532 -218.666435)
			(xy 88.005532 -218.717973) (xy 87.997532 -218.768885) (xy 87.981726 -218.81794) (xy 87.958499 -218.863946)
			(xy 87.928412 -218.90579) (xy 87.892195 -218.942457) (xy 87.850725 -218.973058) (xy 87.805009 -218.996852)
			(xy 87.756153 -219.013261) (xy 87.730838 -219.018104) (xy 87.68842 -219.025216) (xy 87.68842 -219.532005)
			(xy 87.815421 -219.532005) (xy 87.815421 -219.480071) (xy 87.823546 -219.428776) (xy 87.839594 -219.379383)
			(xy 87.863172 -219.333109) (xy 87.893698 -219.291093) (xy 87.930421 -219.25437) (xy 87.972437 -219.223844)
			(xy 88.018711 -219.200266) (xy 88.068104 -219.184218) (xy 88.119399 -219.176093) (xy 88.171333 -219.176093)
			(xy 88.222628 -219.184218) (xy 88.272021 -219.200266) (xy 88.318295 -219.223844) (xy 88.360311 -219.25437)
			(xy 88.397034 -219.291093) (xy 88.42756 -219.333109) (xy 88.451138 -219.379383) (xy 88.467186 -219.428776)
			(xy 88.475311 -219.480071) (xy 88.47582 -219.506038) (xy 88.475311 -219.532005) (xy 88.755221 -219.532005)
			(xy 88.755221 -219.480071) (xy 88.763346 -219.428776) (xy 88.779394 -219.379383) (xy 88.802972 -219.333109)
			(xy 88.833498 -219.291093) (xy 88.870221 -219.25437) (xy 88.912237 -219.223844) (xy 88.958511 -219.200266)
			(xy 89.007904 -219.184218) (xy 89.059199 -219.176093) (xy 89.111133 -219.176093) (xy 89.162428 -219.184218)
			(xy 89.211821 -219.200266) (xy 89.258095 -219.223844) (xy 89.300111 -219.25437) (xy 89.336834 -219.291093)
			(xy 89.36736 -219.333109) (xy 89.390938 -219.379383) (xy 89.406986 -219.428776) (xy 89.415111 -219.480071)
			(xy 89.41562 -219.506038) (xy 89.415111 -219.532005) (xy 89.695021 -219.532005) (xy 89.695021 -219.480071)
			(xy 89.703146 -219.428776) (xy 89.719194 -219.379383) (xy 89.742772 -219.333109) (xy 89.773298 -219.291093)
			(xy 89.810021 -219.25437) (xy 89.852037 -219.223844) (xy 89.898311 -219.200266) (xy 89.947704 -219.184218)
			(xy 89.998999 -219.176093) (xy 90.050933 -219.176093) (xy 90.102228 -219.184218) (xy 90.151621 -219.200266)
			(xy 90.197895 -219.223844) (xy 90.239911 -219.25437) (xy 90.276634 -219.291093) (xy 90.30716 -219.333109)
			(xy 90.330738 -219.379383) (xy 90.346786 -219.428776) (xy 90.354911 -219.480071) (xy 90.35542 -219.506038)
			(xy 90.354911 -219.532005) (xy 90.634821 -219.532005) (xy 90.634821 -219.480071) (xy 90.642946 -219.428776)
			(xy 90.658994 -219.379383) (xy 90.682572 -219.333109) (xy 90.713098 -219.291093) (xy 90.749821 -219.25437)
			(xy 90.791837 -219.223844) (xy 90.838111 -219.200266) (xy 90.887504 -219.184218) (xy 90.938799 -219.176093)
			(xy 90.990733 -219.176093) (xy 91.042028 -219.184218) (xy 91.091421 -219.200266) (xy 91.137695 -219.223844)
			(xy 91.179711 -219.25437) (xy 91.216434 -219.291093) (xy 91.24696 -219.333109) (xy 91.270538 -219.379383)
			(xy 91.286586 -219.428776) (xy 91.294711 -219.480071) (xy 91.29522 -219.506038) (xy 91.294711 -219.532005)
			(xy 91.574621 -219.532005) (xy 91.574621 -219.480071) (xy 91.582746 -219.428776) (xy 91.598794 -219.379383)
			(xy 91.622372 -219.333109) (xy 91.652898 -219.291093) (xy 91.689621 -219.25437) (xy 91.731637 -219.223844)
			(xy 91.777911 -219.200266) (xy 91.827304 -219.184218) (xy 91.878599 -219.176093) (xy 91.930533 -219.176093)
			(xy 91.981828 -219.184218) (xy 92.031221 -219.200266) (xy 92.077495 -219.223844) (xy 92.119511 -219.25437)
			(xy 92.156234 -219.291093) (xy 92.18676 -219.333109) (xy 92.210338 -219.379383) (xy 92.226386 -219.428776)
			(xy 92.234511 -219.480071) (xy 92.23502 -219.506038) (xy 92.234511 -219.532005) (xy 92.514421 -219.532005)
			(xy 92.514421 -219.480071) (xy 92.522546 -219.428776) (xy 92.538594 -219.379383) (xy 92.562172 -219.333109)
			(xy 92.592698 -219.291093) (xy 92.629421 -219.25437) (xy 92.671437 -219.223844) (xy 92.717711 -219.200266)
			(xy 92.767104 -219.184218) (xy 92.818399 -219.176093) (xy 92.870333 -219.176093) (xy 92.921628 -219.184218)
			(xy 92.971021 -219.200266) (xy 93.017295 -219.223844) (xy 93.059311 -219.25437) (xy 93.096034 -219.291093)
			(xy 93.12656 -219.333109) (xy 93.150138 -219.379383) (xy 93.166186 -219.428776) (xy 93.174311 -219.480071)
			(xy 93.17482 -219.506038) (xy 93.174311 -219.532005) (xy 93.454221 -219.532005) (xy 93.454221 -219.480071)
			(xy 93.462346 -219.428776) (xy 93.478394 -219.379383) (xy 93.501972 -219.333109) (xy 93.532498 -219.291093)
			(xy 93.569221 -219.25437) (xy 93.611237 -219.223844) (xy 93.657511 -219.200266) (xy 93.706904 -219.184218)
			(xy 93.758199 -219.176093) (xy 93.810133 -219.176093) (xy 93.861428 -219.184218) (xy 93.910821 -219.200266)
			(xy 93.957095 -219.223844) (xy 93.999111 -219.25437) (xy 94.035834 -219.291093) (xy 94.06636 -219.333109)
			(xy 94.089938 -219.379383) (xy 94.105986 -219.428776) (xy 94.114111 -219.480071) (xy 94.11462 -219.506038)
			(xy 94.114111 -219.532005) (xy 94.394021 -219.532005) (xy 94.394021 -219.480071) (xy 94.402146 -219.428776)
			(xy 94.418194 -219.379383) (xy 94.441772 -219.333109) (xy 94.472298 -219.291093) (xy 94.509021 -219.25437)
			(xy 94.551037 -219.223844) (xy 94.597311 -219.200266) (xy 94.646704 -219.184218) (xy 94.697999 -219.176093)
			(xy 94.749933 -219.176093) (xy 94.801228 -219.184218) (xy 94.850621 -219.200266) (xy 94.896895 -219.223844)
			(xy 94.938911 -219.25437) (xy 94.975634 -219.291093) (xy 95.00616 -219.333109) (xy 95.029738 -219.379383)
			(xy 95.045786 -219.428776) (xy 95.053911 -219.480071) (xy 95.05442 -219.506038) (xy 95.053911 -219.532005)
			(xy 95.333821 -219.532005) (xy 95.333821 -219.480071) (xy 95.341946 -219.428776) (xy 95.357994 -219.379383)
			(xy 95.381572 -219.333109) (xy 95.412098 -219.291093) (xy 95.448821 -219.25437) (xy 95.490837 -219.223844)
			(xy 95.537111 -219.200266) (xy 95.586504 -219.184218) (xy 95.637799 -219.176093) (xy 95.689733 -219.176093)
			(xy 95.741028 -219.184218) (xy 95.790421 -219.200266) (xy 95.836695 -219.223844) (xy 95.878711 -219.25437)
			(xy 95.915434 -219.291093) (xy 95.94596 -219.333109) (xy 95.969538 -219.379383) (xy 95.985586 -219.428776)
			(xy 95.993711 -219.480071) (xy 95.99422 -219.506038) (xy 95.993711 -219.532005) (xy 96.273621 -219.532005)
			(xy 96.273621 -219.480071) (xy 96.281746 -219.428776) (xy 96.297794 -219.379383) (xy 96.321372 -219.333109)
			(xy 96.351898 -219.291093) (xy 96.388621 -219.25437) (xy 96.430637 -219.223844) (xy 96.476911 -219.200266)
			(xy 96.526304 -219.184218) (xy 96.577599 -219.176093) (xy 96.629533 -219.176093) (xy 96.680828 -219.184218)
			(xy 96.730221 -219.200266) (xy 96.776495 -219.223844) (xy 96.818511 -219.25437) (xy 96.855234 -219.291093)
			(xy 96.88576 -219.333109) (xy 96.909338 -219.379383) (xy 96.925386 -219.428776) (xy 96.933511 -219.480071)
			(xy 96.93402 -219.506038) (xy 96.933511 -219.532005) (xy 97.213421 -219.532005) (xy 97.213421 -219.480071)
			(xy 97.221546 -219.428776) (xy 97.237594 -219.379383) (xy 97.261172 -219.333109) (xy 97.291698 -219.291093)
			(xy 97.328421 -219.25437) (xy 97.370437 -219.223844) (xy 97.416711 -219.200266) (xy 97.466104 -219.184218)
			(xy 97.517399 -219.176093) (xy 97.569333 -219.176093) (xy 97.620628 -219.184218) (xy 97.670021 -219.200266)
			(xy 97.716295 -219.223844) (xy 97.758311 -219.25437) (xy 97.795034 -219.291093) (xy 97.82556 -219.333109)
			(xy 97.849138 -219.379383) (xy 97.865186 -219.428776) (xy 97.873311 -219.480071) (xy 97.87382 -219.506038)
			(xy 97.873311 -219.532005) (xy 98.153221 -219.532005) (xy 98.153221 -219.480071) (xy 98.161346 -219.428776)
			(xy 98.177394 -219.379383) (xy 98.200972 -219.333109) (xy 98.231498 -219.291093) (xy 98.268221 -219.25437)
			(xy 98.310237 -219.223844) (xy 98.356511 -219.200266) (xy 98.405904 -219.184218) (xy 98.457199 -219.176093)
			(xy 98.509133 -219.176093) (xy 98.560428 -219.184218) (xy 98.609821 -219.200266) (xy 98.656095 -219.223844)
			(xy 98.698111 -219.25437) (xy 98.734834 -219.291093) (xy 98.76536 -219.333109) (xy 98.788938 -219.379383)
			(xy 98.804986 -219.428776) (xy 98.813111 -219.480071) (xy 98.81362 -219.506038) (xy 98.813111 -219.532005)
			(xy 99.093021 -219.532005) (xy 99.093021 -219.480071) (xy 99.101146 -219.428776) (xy 99.117194 -219.379383)
			(xy 99.140772 -219.333109) (xy 99.171298 -219.291093) (xy 99.208021 -219.25437) (xy 99.250037 -219.223844)
			(xy 99.296311 -219.200266) (xy 99.345704 -219.184218) (xy 99.396999 -219.176093) (xy 99.448933 -219.176093)
			(xy 99.500228 -219.184218) (xy 99.549621 -219.200266) (xy 99.595895 -219.223844) (xy 99.637911 -219.25437)
			(xy 99.674634 -219.291093) (xy 99.70516 -219.333109) (xy 99.728738 -219.379383) (xy 99.744786 -219.428776)
			(xy 99.752911 -219.480071) (xy 99.75342 -219.506038) (xy 99.752911 -219.532005) (xy 100.032821 -219.532005)
			(xy 100.032821 -219.480071) (xy 100.040946 -219.428776) (xy 100.056994 -219.379383) (xy 100.080572 -219.333109)
			(xy 100.111098 -219.291093) (xy 100.147821 -219.25437) (xy 100.189837 -219.223844) (xy 100.236111 -219.200266)
			(xy 100.285504 -219.184218) (xy 100.336799 -219.176093) (xy 100.388733 -219.176093) (xy 100.440028 -219.184218)
			(xy 100.489421 -219.200266) (xy 100.535695 -219.223844) (xy 100.577711 -219.25437) (xy 100.614434 -219.291093)
			(xy 100.64496 -219.333109) (xy 100.668538 -219.379383) (xy 100.684586 -219.428776) (xy 100.692711 -219.480071)
			(xy 100.69322 -219.506038) (xy 100.692711 -219.532005) (xy 100.684586 -219.5833) (xy 100.668538 -219.632693)
			(xy 100.64496 -219.678967) (xy 100.614434 -219.720983) (xy 100.577711 -219.757706) (xy 100.535695 -219.788232)
			(xy 100.489421 -219.81181) (xy 100.440028 -219.827858) (xy 100.388733 -219.835983) (xy 100.336799 -219.835983)
			(xy 100.285504 -219.827858) (xy 100.236111 -219.81181) (xy 100.189837 -219.788232) (xy 100.147821 -219.757706)
			(xy 100.111098 -219.720983) (xy 100.080572 -219.678967) (xy 100.056994 -219.632693) (xy 100.040946 -219.5833)
			(xy 100.032821 -219.532005) (xy 99.752911 -219.532005) (xy 99.744786 -219.5833) (xy 99.728738 -219.632693)
			(xy 99.70516 -219.678967) (xy 99.674634 -219.720983) (xy 99.637911 -219.757706) (xy 99.595895 -219.788232)
			(xy 99.549621 -219.81181) (xy 99.500228 -219.827858) (xy 99.448933 -219.835983) (xy 99.396999 -219.835983)
			(xy 99.345704 -219.827858) (xy 99.296311 -219.81181) (xy 99.250037 -219.788232) (xy 99.208021 -219.757706)
			(xy 99.171298 -219.720983) (xy 99.140772 -219.678967) (xy 99.117194 -219.632693) (xy 99.101146 -219.5833)
			(xy 99.093021 -219.532005) (xy 98.813111 -219.532005) (xy 98.804986 -219.5833) (xy 98.788938 -219.632693)
			(xy 98.76536 -219.678967) (xy 98.734834 -219.720983) (xy 98.698111 -219.757706) (xy 98.656095 -219.788232)
			(xy 98.609821 -219.81181) (xy 98.560428 -219.827858) (xy 98.509133 -219.835983) (xy 98.457199 -219.835983)
			(xy 98.405904 -219.827858) (xy 98.356511 -219.81181) (xy 98.310237 -219.788232) (xy 98.268221 -219.757706)
			(xy 98.231498 -219.720983) (xy 98.200972 -219.678967) (xy 98.177394 -219.632693) (xy 98.161346 -219.5833)
			(xy 98.153221 -219.532005) (xy 97.873311 -219.532005) (xy 97.865186 -219.5833) (xy 97.849138 -219.632693)
			(xy 97.82556 -219.678967) (xy 97.795034 -219.720983) (xy 97.758311 -219.757706) (xy 97.716295 -219.788232)
			(xy 97.670021 -219.81181) (xy 97.620628 -219.827858) (xy 97.569333 -219.835983) (xy 97.517399 -219.835983)
			(xy 97.466104 -219.827858) (xy 97.416711 -219.81181) (xy 97.370437 -219.788232) (xy 97.328421 -219.757706)
			(xy 97.291698 -219.720983) (xy 97.261172 -219.678967) (xy 97.237594 -219.632693) (xy 97.221546 -219.5833)
			(xy 97.213421 -219.532005) (xy 96.933511 -219.532005) (xy 96.925386 -219.5833) (xy 96.909338 -219.632693)
			(xy 96.88576 -219.678967) (xy 96.855234 -219.720983) (xy 96.818511 -219.757706) (xy 96.776495 -219.788232)
			(xy 96.730221 -219.81181) (xy 96.680828 -219.827858) (xy 96.629533 -219.835983) (xy 96.577599 -219.835983)
			(xy 96.526304 -219.827858) (xy 96.476911 -219.81181) (xy 96.430637 -219.788232) (xy 96.388621 -219.757706)
			(xy 96.351898 -219.720983) (xy 96.321372 -219.678967) (xy 96.297794 -219.632693) (xy 96.281746 -219.5833)
			(xy 96.273621 -219.532005) (xy 95.993711 -219.532005) (xy 95.985586 -219.5833) (xy 95.969538 -219.632693)
			(xy 95.94596 -219.678967) (xy 95.915434 -219.720983) (xy 95.878711 -219.757706) (xy 95.836695 -219.788232)
			(xy 95.790421 -219.81181) (xy 95.741028 -219.827858) (xy 95.689733 -219.835983) (xy 95.637799 -219.835983)
			(xy 95.586504 -219.827858) (xy 95.537111 -219.81181) (xy 95.490837 -219.788232) (xy 95.448821 -219.757706)
			(xy 95.412098 -219.720983) (xy 95.381572 -219.678967) (xy 95.357994 -219.632693) (xy 95.341946 -219.5833)
			(xy 95.333821 -219.532005) (xy 95.053911 -219.532005) (xy 95.045786 -219.5833) (xy 95.029738 -219.632693)
			(xy 95.00616 -219.678967) (xy 94.975634 -219.720983) (xy 94.938911 -219.757706) (xy 94.896895 -219.788232)
			(xy 94.850621 -219.81181) (xy 94.801228 -219.827858) (xy 94.749933 -219.835983) (xy 94.697999 -219.835983)
			(xy 94.646704 -219.827858) (xy 94.597311 -219.81181) (xy 94.551037 -219.788232) (xy 94.509021 -219.757706)
			(xy 94.472298 -219.720983) (xy 94.441772 -219.678967) (xy 94.418194 -219.632693) (xy 94.402146 -219.5833)
			(xy 94.394021 -219.532005) (xy 94.114111 -219.532005) (xy 94.105986 -219.5833) (xy 94.089938 -219.632693)
			(xy 94.06636 -219.678967) (xy 94.035834 -219.720983) (xy 93.999111 -219.757706) (xy 93.957095 -219.788232)
			(xy 93.910821 -219.81181) (xy 93.861428 -219.827858) (xy 93.810133 -219.835983) (xy 93.758199 -219.835983)
			(xy 93.706904 -219.827858) (xy 93.657511 -219.81181) (xy 93.611237 -219.788232) (xy 93.569221 -219.757706)
			(xy 93.532498 -219.720983) (xy 93.501972 -219.678967) (xy 93.478394 -219.632693) (xy 93.462346 -219.5833)
			(xy 93.454221 -219.532005) (xy 93.174311 -219.532005) (xy 93.166186 -219.5833) (xy 93.150138 -219.632693)
			(xy 93.12656 -219.678967) (xy 93.096034 -219.720983) (xy 93.059311 -219.757706) (xy 93.017295 -219.788232)
			(xy 92.971021 -219.81181) (xy 92.921628 -219.827858) (xy 92.870333 -219.835983) (xy 92.818399 -219.835983)
			(xy 92.767104 -219.827858) (xy 92.717711 -219.81181) (xy 92.671437 -219.788232) (xy 92.629421 -219.757706)
			(xy 92.592698 -219.720983) (xy 92.562172 -219.678967) (xy 92.538594 -219.632693) (xy 92.522546 -219.5833)
			(xy 92.514421 -219.532005) (xy 92.234511 -219.532005) (xy 92.226386 -219.5833) (xy 92.210338 -219.632693)
			(xy 92.18676 -219.678967) (xy 92.156234 -219.720983) (xy 92.119511 -219.757706) (xy 92.077495 -219.788232)
			(xy 92.031221 -219.81181) (xy 91.981828 -219.827858) (xy 91.930533 -219.835983) (xy 91.878599 -219.835983)
			(xy 91.827304 -219.827858) (xy 91.777911 -219.81181) (xy 91.731637 -219.788232) (xy 91.689621 -219.757706)
			(xy 91.652898 -219.720983) (xy 91.622372 -219.678967) (xy 91.598794 -219.632693) (xy 91.582746 -219.5833)
			(xy 91.574621 -219.532005) (xy 91.294711 -219.532005) (xy 91.286586 -219.5833) (xy 91.270538 -219.632693)
			(xy 91.24696 -219.678967) (xy 91.216434 -219.720983) (xy 91.179711 -219.757706) (xy 91.137695 -219.788232)
			(xy 91.091421 -219.81181) (xy 91.042028 -219.827858) (xy 90.990733 -219.835983) (xy 90.938799 -219.835983)
			(xy 90.887504 -219.827858) (xy 90.838111 -219.81181) (xy 90.791837 -219.788232) (xy 90.749821 -219.757706)
			(xy 90.713098 -219.720983) (xy 90.682572 -219.678967) (xy 90.658994 -219.632693) (xy 90.642946 -219.5833)
			(xy 90.634821 -219.532005) (xy 90.354911 -219.532005) (xy 90.346786 -219.5833) (xy 90.330738 -219.632693)
			(xy 90.30716 -219.678967) (xy 90.276634 -219.720983) (xy 90.239911 -219.757706) (xy 90.197895 -219.788232)
			(xy 90.151621 -219.81181) (xy 90.102228 -219.827858) (xy 90.050933 -219.835983) (xy 89.998999 -219.835983)
			(xy 89.947704 -219.827858) (xy 89.898311 -219.81181) (xy 89.852037 -219.788232) (xy 89.810021 -219.757706)
			(xy 89.773298 -219.720983) (xy 89.742772 -219.678967) (xy 89.719194 -219.632693) (xy 89.703146 -219.5833)
			(xy 89.695021 -219.532005) (xy 89.415111 -219.532005) (xy 89.406986 -219.5833) (xy 89.390938 -219.632693)
			(xy 89.36736 -219.678967) (xy 89.336834 -219.720983) (xy 89.300111 -219.757706) (xy 89.258095 -219.788232)
			(xy 89.211821 -219.81181) (xy 89.162428 -219.827858) (xy 89.111133 -219.835983) (xy 89.059199 -219.835983)
			(xy 89.007904 -219.827858) (xy 88.958511 -219.81181) (xy 88.912237 -219.788232) (xy 88.870221 -219.757706)
			(xy 88.833498 -219.720983) (xy 88.802972 -219.678967) (xy 88.779394 -219.632693) (xy 88.763346 -219.5833)
			(xy 88.755221 -219.532005) (xy 88.475311 -219.532005) (xy 88.467186 -219.5833) (xy 88.451138 -219.632693)
			(xy 88.42756 -219.678967) (xy 88.397034 -219.720983) (xy 88.360311 -219.757706) (xy 88.318295 -219.788232)
			(xy 88.272021 -219.81181) (xy 88.222628 -219.827858) (xy 88.171333 -219.835983) (xy 88.119399 -219.835983)
			(xy 88.068104 -219.827858) (xy 88.018711 -219.81181) (xy 87.972437 -219.788232) (xy 87.930421 -219.757706)
			(xy 87.893698 -219.720983) (xy 87.863172 -219.678967) (xy 87.839594 -219.632693) (xy 87.823546 -219.5833)
			(xy 87.815421 -219.532005) (xy 87.68842 -219.532005) (xy 87.68842 -220.345821) (xy 88.285321 -220.345821)
			(xy 88.285321 -220.293887) (xy 88.293446 -220.242592) (xy 88.309494 -220.193199) (xy 88.333072 -220.146925)
			(xy 88.363598 -220.104909) (xy 88.400321 -220.068186) (xy 88.442337 -220.03766) (xy 88.488611 -220.014082)
			(xy 88.538004 -219.998034) (xy 88.589299 -219.989909) (xy 88.641233 -219.989909) (xy 88.692528 -219.998034)
			(xy 88.741921 -220.014082) (xy 88.788195 -220.03766) (xy 88.830211 -220.068186) (xy 88.866934 -220.104909)
			(xy 88.89746 -220.146925) (xy 88.921038 -220.193199) (xy 88.937086 -220.242592) (xy 88.945211 -220.293887)
			(xy 88.94572 -220.319854) (xy 88.945211 -220.345821) (xy 89.225121 -220.345821) (xy 89.225121 -220.293887)
			(xy 89.233246 -220.242592) (xy 89.249294 -220.193199) (xy 89.272872 -220.146925) (xy 89.303398 -220.104909)
			(xy 89.340121 -220.068186) (xy 89.382137 -220.03766) (xy 89.428411 -220.014082) (xy 89.477804 -219.998034)
			(xy 89.529099 -219.989909) (xy 89.581033 -219.989909) (xy 89.632328 -219.998034) (xy 89.681721 -220.014082)
			(xy 89.727995 -220.03766) (xy 89.770011 -220.068186) (xy 89.806734 -220.104909) (xy 89.83726 -220.146925)
			(xy 89.860838 -220.193199) (xy 89.876886 -220.242592) (xy 89.885011 -220.293887) (xy 89.88552 -220.319854)
			(xy 89.885011 -220.345821) (xy 89.876886 -220.397116) (xy 89.860838 -220.446509) (xy 89.83726 -220.492783)
			(xy 89.806734 -220.534799) (xy 89.770011 -220.571522) (xy 89.727995 -220.602048) (xy 89.681721 -220.625626)
			(xy 89.632328 -220.641674) (xy 89.581033 -220.649799) (xy 89.529099 -220.649799) (xy 89.477804 -220.641674)
			(xy 89.428411 -220.625626) (xy 89.382137 -220.602048) (xy 89.340121 -220.571522) (xy 89.303398 -220.534799)
			(xy 89.272872 -220.492783) (xy 89.249294 -220.446509) (xy 89.233246 -220.397116) (xy 89.225121 -220.345821)
			(xy 88.945211 -220.345821) (xy 88.937086 -220.397116) (xy 88.921038 -220.446509) (xy 88.89746 -220.492783)
			(xy 88.866934 -220.534799) (xy 88.830211 -220.571522) (xy 88.788195 -220.602048) (xy 88.741921 -220.625626)
			(xy 88.692528 -220.641674) (xy 88.641233 -220.649799) (xy 88.589299 -220.649799) (xy 88.538004 -220.641674)
			(xy 88.488611 -220.625626) (xy 88.442337 -220.602048) (xy 88.400321 -220.571522) (xy 88.363598 -220.534799)
			(xy 88.333072 -220.492783) (xy 88.309494 -220.446509) (xy 88.293446 -220.397116) (xy 88.285321 -220.345821)
			(xy 87.68842 -220.345821) (xy 87.68842 -221.159891) (xy 87.815421 -221.159891) (xy 87.815421 -221.107957)
			(xy 87.823546 -221.056662) (xy 87.839594 -221.007269) (xy 87.863172 -220.960995) (xy 87.893698 -220.918979)
			(xy 87.930421 -220.882256) (xy 87.972437 -220.85173) (xy 88.018711 -220.828152) (xy 88.068104 -220.812104)
			(xy 88.119399 -220.803979) (xy 88.171333 -220.803979) (xy 88.222628 -220.812104) (xy 88.272021 -220.828152)
			(xy 88.318295 -220.85173) (xy 88.360311 -220.882256) (xy 88.397034 -220.918979) (xy 88.42756 -220.960995)
			(xy 88.451138 -221.007269) (xy 88.467186 -221.056662) (xy 88.475311 -221.107957) (xy 88.47582 -221.133924)
			(xy 88.754712 -221.133924) (xy 88.755221 -221.107957) (xy 88.763346 -221.056662) (xy 88.779394 -221.007269)
			(xy 88.802972 -220.960995) (xy 88.833498 -220.918979) (xy 88.870221 -220.882256) (xy 88.912237 -220.85173)
			(xy 88.958511 -220.828152) (xy 89.007904 -220.812104) (xy 89.059199 -220.803979) (xy 89.111133 -220.803979)
			(xy 89.162428 -220.812104) (xy 89.211821 -220.828152) (xy 89.258095 -220.85173) (xy 89.300111 -220.882256)
			(xy 89.336834 -220.918979) (xy 89.36736 -220.960995) (xy 89.390938 -221.007269) (xy 89.406986 -221.056662)
			(xy 89.415111 -221.107957) (xy 89.41562 -221.133924) (xy 89.694512 -221.133924) (xy 89.694958 -221.108472)
			(xy 89.702746 -221.058168) (xy 89.718157 -221.009654) (xy 89.740827 -220.964077) (xy 89.770218 -220.922517)
			(xy 89.805636 -220.885956) (xy 89.846243 -220.855259) (xy 89.891076 -220.831154) (xy 89.939077 -220.81421)
			(xy 89.964006 -220.809058) (xy 89.986866 -220.80474) (xy 90.190574 -220.45168) (xy 90.182954 -220.429582)
			(xy 90.174214 -220.402995) (xy 90.164768 -220.347835) (xy 90.164158 -220.319854) (xy 90.164667 -220.293887)
			(xy 90.172792 -220.242592) (xy 90.18884 -220.193199) (xy 90.212418 -220.146925) (xy 90.242944 -220.104909)
			(xy 90.279667 -220.068186) (xy 90.321683 -220.03766) (xy 90.367957 -220.014082) (xy 90.41735 -219.998034)
			(xy 90.468645 -219.989909) (xy 90.520579 -219.989909) (xy 90.571874 -219.998034) (xy 90.621267 -220.014082)
			(xy 90.667541 -220.03766) (xy 90.709557 -220.068186) (xy 90.74628 -220.104909) (xy 90.776806 -220.146925)
			(xy 90.800384 -220.193199) (xy 90.816432 -220.242592) (xy 90.824557 -220.293887) (xy 90.825066 -220.319854)
			(xy 90.824618 -220.345306) (xy 90.824538 -220.345821) (xy 91.104721 -220.345821) (xy 91.104721 -220.293887)
			(xy 91.112846 -220.242592) (xy 91.128894 -220.193199) (xy 91.152472 -220.146925) (xy 91.182998 -220.104909)
			(xy 91.219721 -220.068186) (xy 91.261737 -220.03766) (xy 91.308011 -220.014082) (xy 91.357404 -219.998034)
			(xy 91.408699 -219.989909) (xy 91.460633 -219.989909) (xy 91.511928 -219.998034) (xy 91.561321 -220.014082)
			(xy 91.607595 -220.03766) (xy 91.649611 -220.068186) (xy 91.686334 -220.104909) (xy 91.71686 -220.146925)
			(xy 91.740438 -220.193199) (xy 91.756486 -220.242592) (xy 91.764611 -220.293887) (xy 91.76512 -220.319854)
			(xy 91.764611 -220.345821) (xy 91.756486 -220.397116) (xy 91.740438 -220.446509) (xy 91.71686 -220.492783)
			(xy 91.686334 -220.534799) (xy 91.649611 -220.571522) (xy 91.607595 -220.602048) (xy 91.561321 -220.625626)
			(xy 91.511928 -220.641674) (xy 91.460633 -220.649799) (xy 91.408699 -220.649799) (xy 91.357404 -220.641674)
			(xy 91.308011 -220.625626) (xy 91.261737 -220.602048) (xy 91.219721 -220.571522) (xy 91.182998 -220.534799)
			(xy 91.152472 -220.492783) (xy 91.128894 -220.446509) (xy 91.112846 -220.397116) (xy 91.104721 -220.345821)
			(xy 90.824538 -220.345821) (xy 90.816833 -220.395611) (xy 90.801423 -220.444126) (xy 90.778755 -220.489704)
			(xy 90.749363 -220.531265) (xy 90.713945 -220.567826) (xy 90.673338 -220.598523) (xy 90.628503 -220.622627)
			(xy 90.580502 -220.639569) (xy 90.555572 -220.64472) (xy 90.532712 -220.649038) (xy 90.329004 -221.002098)
			(xy 90.336624 -221.024196) (xy 90.345361 -221.050784) (xy 90.354809 -221.105943) (xy 90.35542 -221.133924)
			(xy 90.634312 -221.133924) (xy 90.634821 -221.107957) (xy 90.642946 -221.056662) (xy 90.658994 -221.007269)
			(xy 90.682572 -220.960995) (xy 90.713098 -220.918979) (xy 90.749821 -220.882256) (xy 90.791837 -220.85173)
			(xy 90.838111 -220.828152) (xy 90.887504 -220.812104) (xy 90.938799 -220.803979) (xy 90.990733 -220.803979)
			(xy 91.042028 -220.812104) (xy 91.091421 -220.828152) (xy 91.137695 -220.85173) (xy 91.179711 -220.882256)
			(xy 91.216434 -220.918979) (xy 91.24696 -220.960995) (xy 91.270538 -221.007269) (xy 91.286586 -221.056662)
			(xy 91.294711 -221.107957) (xy 91.29522 -221.133924) (xy 91.574112 -221.133924) (xy 91.574558 -221.108472)
			(xy 91.582346 -221.058168) (xy 91.597757 -221.009654) (xy 91.620427 -220.964077) (xy 91.649818 -220.922517)
			(xy 91.685236 -220.885956) (xy 91.725843 -220.855259) (xy 91.770676 -220.831154) (xy 91.818677 -220.81421)
			(xy 91.843606 -220.809058) (xy 91.866466 -220.80474) (xy 92.070174 -220.45168) (xy 92.062554 -220.429582)
			(xy 92.053814 -220.402995) (xy 92.044368 -220.347835) (xy 92.043758 -220.319854) (xy 92.044267 -220.293887)
			(xy 92.052392 -220.242592) (xy 92.06844 -220.193199) (xy 92.092018 -220.146925) (xy 92.122544 -220.104909)
			(xy 92.159267 -220.068186) (xy 92.201283 -220.03766) (xy 92.247557 -220.014082) (xy 92.29695 -219.998034)
			(xy 92.348245 -219.989909) (xy 92.400179 -219.989909) (xy 92.451474 -219.998034) (xy 92.500867 -220.014082)
			(xy 92.547141 -220.03766) (xy 92.589157 -220.068186) (xy 92.62588 -220.104909) (xy 92.656406 -220.146925)
			(xy 92.679984 -220.193199) (xy 92.696032 -220.242592) (xy 92.704157 -220.293887) (xy 92.704666 -220.319854)
			(xy 92.704218 -220.345306) (xy 92.704138 -220.345821) (xy 92.984321 -220.345821) (xy 92.984321 -220.293887)
			(xy 92.992446 -220.242592) (xy 93.008494 -220.193199) (xy 93.032072 -220.146925) (xy 93.062598 -220.104909)
			(xy 93.099321 -220.068186) (xy 93.141337 -220.03766) (xy 93.187611 -220.014082) (xy 93.237004 -219.998034)
			(xy 93.288299 -219.989909) (xy 93.340233 -219.989909) (xy 93.391528 -219.998034) (xy 93.440921 -220.014082)
			(xy 93.487195 -220.03766) (xy 93.529211 -220.068186) (xy 93.565934 -220.104909) (xy 93.59646 -220.146925)
			(xy 93.620038 -220.193199) (xy 93.636086 -220.242592) (xy 93.644211 -220.293887) (xy 93.64472 -220.319854)
			(xy 93.644211 -220.345821) (xy 93.636086 -220.397116) (xy 93.620038 -220.446509) (xy 93.59646 -220.492783)
			(xy 93.565934 -220.534799) (xy 93.529211 -220.571522) (xy 93.487195 -220.602048) (xy 93.440921 -220.625626)
			(xy 93.391528 -220.641674) (xy 93.340233 -220.649799) (xy 93.288299 -220.649799) (xy 93.237004 -220.641674)
			(xy 93.187611 -220.625626) (xy 93.141337 -220.602048) (xy 93.099321 -220.571522) (xy 93.062598 -220.534799)
			(xy 93.032072 -220.492783) (xy 93.008494 -220.446509) (xy 92.992446 -220.397116) (xy 92.984321 -220.345821)
			(xy 92.704138 -220.345821) (xy 92.696433 -220.395611) (xy 92.681023 -220.444126) (xy 92.658355 -220.489704)
			(xy 92.628963 -220.531265) (xy 92.593545 -220.567826) (xy 92.552938 -220.598523) (xy 92.508103 -220.622627)
			(xy 92.460102 -220.639569) (xy 92.435172 -220.64472) (xy 92.412312 -220.649038) (xy 92.208604 -221.002098)
			(xy 92.216224 -221.024196) (xy 92.224961 -221.050784) (xy 92.234409 -221.105943) (xy 92.23502 -221.133924)
			(xy 92.513912 -221.133924) (xy 92.514421 -221.107957) (xy 92.522546 -221.056662) (xy 92.538594 -221.007269)
			(xy 92.562172 -220.960995) (xy 92.592698 -220.918979) (xy 92.629421 -220.882256) (xy 92.671437 -220.85173)
			(xy 92.717711 -220.828152) (xy 92.767104 -220.812104) (xy 92.818399 -220.803979) (xy 92.870333 -220.803979)
			(xy 92.921628 -220.812104) (xy 92.971021 -220.828152) (xy 93.017295 -220.85173) (xy 93.059311 -220.882256)
			(xy 93.096034 -220.918979) (xy 93.12656 -220.960995) (xy 93.150138 -221.007269) (xy 93.166186 -221.056662)
			(xy 93.174311 -221.107957) (xy 93.17482 -221.133924) (xy 93.453712 -221.133924) (xy 93.454158 -221.108472)
			(xy 93.461946 -221.058168) (xy 93.477357 -221.009654) (xy 93.500027 -220.964077) (xy 93.529418 -220.922517)
			(xy 93.564836 -220.885956) (xy 93.605443 -220.855259) (xy 93.650276 -220.831154) (xy 93.698277 -220.81421)
			(xy 93.723206 -220.809058) (xy 93.746066 -220.80474) (xy 93.949774 -220.45168) (xy 93.942154 -220.429582)
			(xy 93.933414 -220.402995) (xy 93.923968 -220.347835) (xy 93.923358 -220.319854) (xy 93.923867 -220.293887)
			(xy 93.931992 -220.242592) (xy 93.94804 -220.193199) (xy 93.971618 -220.146925) (xy 94.002144 -220.104909)
			(xy 94.038867 -220.068186) (xy 94.080883 -220.03766) (xy 94.127157 -220.014082) (xy 94.17655 -219.998034)
			(xy 94.227845 -219.989909) (xy 94.279779 -219.989909) (xy 94.331074 -219.998034) (xy 94.380467 -220.014082)
			(xy 94.426741 -220.03766) (xy 94.468757 -220.068186) (xy 94.50548 -220.104909) (xy 94.536006 -220.146925)
			(xy 94.559584 -220.193199) (xy 94.575632 -220.242592) (xy 94.583757 -220.293887) (xy 94.584266 -220.319854)
			(xy 94.583818 -220.345306) (xy 94.583738 -220.345821) (xy 94.863921 -220.345821) (xy 94.863921 -220.293887)
			(xy 94.872046 -220.242592) (xy 94.888094 -220.193199) (xy 94.911672 -220.146925) (xy 94.942198 -220.104909)
			(xy 94.978921 -220.068186) (xy 95.020937 -220.03766) (xy 95.067211 -220.014082) (xy 95.116604 -219.998034)
			(xy 95.167899 -219.989909) (xy 95.219833 -219.989909) (xy 95.271128 -219.998034) (xy 95.320521 -220.014082)
			(xy 95.366795 -220.03766) (xy 95.408811 -220.068186) (xy 95.445534 -220.104909) (xy 95.47606 -220.146925)
			(xy 95.499638 -220.193199) (xy 95.515686 -220.242592) (xy 95.523811 -220.293887) (xy 95.52432 -220.319854)
			(xy 95.523811 -220.345821) (xy 95.515686 -220.397116) (xy 95.499638 -220.446509) (xy 95.47606 -220.492783)
			(xy 95.445534 -220.534799) (xy 95.408811 -220.571522) (xy 95.366795 -220.602048) (xy 95.320521 -220.625626)
			(xy 95.271128 -220.641674) (xy 95.219833 -220.649799) (xy 95.167899 -220.649799) (xy 95.116604 -220.641674)
			(xy 95.067211 -220.625626) (xy 95.020937 -220.602048) (xy 94.978921 -220.571522) (xy 94.942198 -220.534799)
			(xy 94.911672 -220.492783) (xy 94.888094 -220.446509) (xy 94.872046 -220.397116) (xy 94.863921 -220.345821)
			(xy 94.583738 -220.345821) (xy 94.576033 -220.395611) (xy 94.560623 -220.444126) (xy 94.537955 -220.489704)
			(xy 94.508563 -220.531265) (xy 94.473145 -220.567826) (xy 94.432538 -220.598523) (xy 94.387703 -220.622627)
			(xy 94.339702 -220.639569) (xy 94.314772 -220.64472) (xy 94.291912 -220.649038) (xy 94.088204 -221.002098)
			(xy 94.095824 -221.024196) (xy 94.104561 -221.050784) (xy 94.114009 -221.105943) (xy 94.11462 -221.133924)
			(xy 94.393512 -221.133924) (xy 94.394021 -221.107957) (xy 94.402146 -221.056662) (xy 94.418194 -221.007269)
			(xy 94.441772 -220.960995) (xy 94.472298 -220.918979) (xy 94.509021 -220.882256) (xy 94.551037 -220.85173)
			(xy 94.597311 -220.828152) (xy 94.646704 -220.812104) (xy 94.697999 -220.803979) (xy 94.749933 -220.803979)
			(xy 94.801228 -220.812104) (xy 94.850621 -220.828152) (xy 94.896895 -220.85173) (xy 94.938911 -220.882256)
			(xy 94.975634 -220.918979) (xy 95.00616 -220.960995) (xy 95.029738 -221.007269) (xy 95.045786 -221.056662)
			(xy 95.053911 -221.107957) (xy 95.05442 -221.133924) (xy 95.333312 -221.133924) (xy 95.333758 -221.108472)
			(xy 95.341546 -221.058168) (xy 95.356957 -221.009654) (xy 95.379627 -220.964077) (xy 95.409018 -220.922517)
			(xy 95.444436 -220.885956) (xy 95.485043 -220.855259) (xy 95.529876 -220.831154) (xy 95.577877 -220.81421)
			(xy 95.602806 -220.809058) (xy 95.625666 -220.80474) (xy 95.829374 -220.45168) (xy 95.821754 -220.429582)
			(xy 95.813014 -220.402995) (xy 95.803568 -220.347835) (xy 95.802958 -220.319854) (xy 95.803467 -220.293887)
			(xy 95.811592 -220.242592) (xy 95.82764 -220.193199) (xy 95.851218 -220.146925) (xy 95.881744 -220.104909)
			(xy 95.918467 -220.068186) (xy 95.960483 -220.03766) (xy 96.006757 -220.014082) (xy 96.05615 -219.998034)
			(xy 96.107445 -219.989909) (xy 96.159379 -219.989909) (xy 96.210674 -219.998034) (xy 96.260067 -220.014082)
			(xy 96.306341 -220.03766) (xy 96.348357 -220.068186) (xy 96.38508 -220.104909) (xy 96.415606 -220.146925)
			(xy 96.439184 -220.193199) (xy 96.455232 -220.242592) (xy 96.463357 -220.293887) (xy 96.463866 -220.319854)
			(xy 96.463418 -220.345306) (xy 96.463338 -220.345821) (xy 96.743521 -220.345821) (xy 96.743521 -220.293887)
			(xy 96.751646 -220.242592) (xy 96.767694 -220.193199) (xy 96.791272 -220.146925) (xy 96.821798 -220.104909)
			(xy 96.858521 -220.068186) (xy 96.900537 -220.03766) (xy 96.946811 -220.014082) (xy 96.996204 -219.998034)
			(xy 97.047499 -219.989909) (xy 97.099433 -219.989909) (xy 97.150728 -219.998034) (xy 97.200121 -220.014082)
			(xy 97.246395 -220.03766) (xy 97.288411 -220.068186) (xy 97.325134 -220.104909) (xy 97.35566 -220.146925)
			(xy 97.379238 -220.193199) (xy 97.395286 -220.242592) (xy 97.403411 -220.293887) (xy 97.40392 -220.319854)
			(xy 97.403411 -220.345821) (xy 97.395286 -220.397116) (xy 97.379238 -220.446509) (xy 97.35566 -220.492783)
			(xy 97.325134 -220.534799) (xy 97.288411 -220.571522) (xy 97.246395 -220.602048) (xy 97.200121 -220.625626)
			(xy 97.150728 -220.641674) (xy 97.099433 -220.649799) (xy 97.047499 -220.649799) (xy 96.996204 -220.641674)
			(xy 96.946811 -220.625626) (xy 96.900537 -220.602048) (xy 96.858521 -220.571522) (xy 96.821798 -220.534799)
			(xy 96.791272 -220.492783) (xy 96.767694 -220.446509) (xy 96.751646 -220.397116) (xy 96.743521 -220.345821)
			(xy 96.463338 -220.345821) (xy 96.455633 -220.395611) (xy 96.440223 -220.444126) (xy 96.417555 -220.489704)
			(xy 96.388163 -220.531265) (xy 96.352745 -220.567826) (xy 96.312138 -220.598523) (xy 96.267303 -220.622627)
			(xy 96.219302 -220.639569) (xy 96.194372 -220.64472) (xy 96.171512 -220.649038) (xy 95.967804 -221.002098)
			(xy 95.975424 -221.024196) (xy 95.984161 -221.050784) (xy 95.993609 -221.105943) (xy 95.99422 -221.133924)
			(xy 96.273112 -221.133924) (xy 96.273621 -221.107957) (xy 96.281746 -221.056662) (xy 96.297794 -221.007269)
			(xy 96.321372 -220.960995) (xy 96.351898 -220.918979) (xy 96.388621 -220.882256) (xy 96.430637 -220.85173)
			(xy 96.476911 -220.828152) (xy 96.526304 -220.812104) (xy 96.577599 -220.803979) (xy 96.629533 -220.803979)
			(xy 96.680828 -220.812104) (xy 96.730221 -220.828152) (xy 96.776495 -220.85173) (xy 96.818511 -220.882256)
			(xy 96.855234 -220.918979) (xy 96.88576 -220.960995) (xy 96.909338 -221.007269) (xy 96.925386 -221.056662)
			(xy 96.933511 -221.107957) (xy 96.93402 -221.133924) (xy 97.212912 -221.133924) (xy 97.213358 -221.108472)
			(xy 97.221146 -221.058168) (xy 97.236557 -221.009654) (xy 97.259227 -220.964077) (xy 97.288618 -220.922517)
			(xy 97.324036 -220.885956) (xy 97.364643 -220.855259) (xy 97.409476 -220.831154) (xy 97.457477 -220.81421)
			(xy 97.482406 -220.809058) (xy 97.505266 -220.80474) (xy 97.708974 -220.45168) (xy 97.701354 -220.429582)
			(xy 97.692614 -220.402995) (xy 97.683168 -220.347835) (xy 97.682558 -220.319854) (xy 97.683067 -220.293887)
			(xy 97.691192 -220.242592) (xy 97.70724 -220.193199) (xy 97.730818 -220.146925) (xy 97.761344 -220.104909)
			(xy 97.798067 -220.068186) (xy 97.840083 -220.03766) (xy 97.886357 -220.014082) (xy 97.93575 -219.998034)
			(xy 97.987045 -219.989909) (xy 98.038979 -219.989909) (xy 98.090274 -219.998034) (xy 98.139667 -220.014082)
			(xy 98.185941 -220.03766) (xy 98.227957 -220.068186) (xy 98.26468 -220.104909) (xy 98.295206 -220.146925)
			(xy 98.318784 -220.193199) (xy 98.334832 -220.242592) (xy 98.342957 -220.293887) (xy 98.343466 -220.319854)
			(xy 98.343018 -220.345306) (xy 98.342938 -220.345821) (xy 98.623121 -220.345821) (xy 98.623121 -220.293887)
			(xy 98.631246 -220.242592) (xy 98.647294 -220.193199) (xy 98.670872 -220.146925) (xy 98.701398 -220.104909)
			(xy 98.738121 -220.068186) (xy 98.780137 -220.03766) (xy 98.826411 -220.014082) (xy 98.875804 -219.998034)
			(xy 98.927099 -219.989909) (xy 98.979033 -219.989909) (xy 99.030328 -219.998034) (xy 99.079721 -220.014082)
			(xy 99.125995 -220.03766) (xy 99.168011 -220.068186) (xy 99.204734 -220.104909) (xy 99.23526 -220.146925)
			(xy 99.258838 -220.193199) (xy 99.274886 -220.242592) (xy 99.283011 -220.293887) (xy 99.28352 -220.319854)
			(xy 99.283011 -220.345821) (xy 99.274886 -220.397116) (xy 99.258838 -220.446509) (xy 99.23526 -220.492783)
			(xy 99.204734 -220.534799) (xy 99.168011 -220.571522) (xy 99.125995 -220.602048) (xy 99.079721 -220.625626)
			(xy 99.030328 -220.641674) (xy 98.979033 -220.649799) (xy 98.927099 -220.649799) (xy 98.875804 -220.641674)
			(xy 98.826411 -220.625626) (xy 98.780137 -220.602048) (xy 98.738121 -220.571522) (xy 98.701398 -220.534799)
			(xy 98.670872 -220.492783) (xy 98.647294 -220.446509) (xy 98.631246 -220.397116) (xy 98.623121 -220.345821)
			(xy 98.342938 -220.345821) (xy 98.335233 -220.395611) (xy 98.319823 -220.444126) (xy 98.297155 -220.489704)
			(xy 98.267763 -220.531265) (xy 98.232345 -220.567826) (xy 98.191738 -220.598523) (xy 98.146903 -220.622627)
			(xy 98.098902 -220.639569) (xy 98.073972 -220.64472) (xy 98.051112 -220.649038) (xy 97.847404 -221.002098)
			(xy 97.855024 -221.024196) (xy 97.863761 -221.050784) (xy 97.873209 -221.105943) (xy 97.87382 -221.133924)
			(xy 98.152712 -221.133924) (xy 98.153221 -221.107957) (xy 98.161346 -221.056662) (xy 98.177394 -221.007269)
			(xy 98.200972 -220.960995) (xy 98.231498 -220.918979) (xy 98.268221 -220.882256) (xy 98.310237 -220.85173)
			(xy 98.356511 -220.828152) (xy 98.405904 -220.812104) (xy 98.457199 -220.803979) (xy 98.509133 -220.803979)
			(xy 98.560428 -220.812104) (xy 98.609821 -220.828152) (xy 98.656095 -220.85173) (xy 98.698111 -220.882256)
			(xy 98.734834 -220.918979) (xy 98.76536 -220.960995) (xy 98.788938 -221.007269) (xy 98.804986 -221.056662)
			(xy 98.813111 -221.107957) (xy 98.81362 -221.133924) (xy 99.092512 -221.133924) (xy 99.092958 -221.108472)
			(xy 99.100746 -221.058168) (xy 99.116157 -221.009654) (xy 99.138827 -220.964077) (xy 99.168218 -220.922517)
			(xy 99.203636 -220.885956) (xy 99.244243 -220.855259) (xy 99.289076 -220.831154) (xy 99.337077 -220.81421)
			(xy 99.362006 -220.809058) (xy 99.384866 -220.80474) (xy 99.588574 -220.45168) (xy 99.580954 -220.429582)
			(xy 99.572214 -220.402995) (xy 99.562768 -220.347835) (xy 99.562158 -220.319854) (xy 99.562667 -220.293887)
			(xy 99.570792 -220.242592) (xy 99.58684 -220.193199) (xy 99.610418 -220.146925) (xy 99.640944 -220.104909)
			(xy 99.677667 -220.068186) (xy 99.719683 -220.03766) (xy 99.765957 -220.014082) (xy 99.81535 -219.998034)
			(xy 99.866645 -219.989909) (xy 99.918579 -219.989909) (xy 99.969874 -219.998034) (xy 100.019267 -220.014082)
			(xy 100.065541 -220.03766) (xy 100.107557 -220.068186) (xy 100.14428 -220.104909) (xy 100.174806 -220.146925)
			(xy 100.198384 -220.193199) (xy 100.214432 -220.242592) (xy 100.222557 -220.293887) (xy 100.223066 -220.319854)
			(xy 100.222618 -220.345306) (xy 100.214833 -220.395611) (xy 100.199423 -220.444126) (xy 100.176755 -220.489704)
			(xy 100.147363 -220.531265) (xy 100.111945 -220.567826) (xy 100.071338 -220.598523) (xy 100.026503 -220.622627)
			(xy 99.978502 -220.639569) (xy 99.953572 -220.64472) (xy 99.930712 -220.649038) (xy 99.727004 -221.002098)
			(xy 99.734624 -221.024196) (xy 99.743361 -221.050784) (xy 99.752809 -221.105943) (xy 99.75342 -221.133924)
			(xy 99.752911 -221.159891) (xy 99.744786 -221.211186) (xy 99.728738 -221.260579) (xy 99.70516 -221.306853)
			(xy 99.674634 -221.348869) (xy 99.637911 -221.385592) (xy 99.595895 -221.416118) (xy 99.549621 -221.439696)
			(xy 99.500228 -221.455744) (xy 99.448933 -221.463869) (xy 99.396999 -221.463869) (xy 99.345704 -221.455744)
			(xy 99.296311 -221.439696) (xy 99.250037 -221.416118) (xy 99.208021 -221.385592) (xy 99.171298 -221.348869)
			(xy 99.140772 -221.306853) (xy 99.117194 -221.260579) (xy 99.101146 -221.211186) (xy 99.093021 -221.159891)
			(xy 99.092512 -221.133924) (xy 98.81362 -221.133924) (xy 98.813072 -221.16191) (xy 98.803619 -221.217078)
			(xy 98.794824 -221.243652) (xy 98.787204 -221.26575) (xy 98.990912 -221.618556) (xy 99.013772 -221.622874)
			(xy 99.0387 -221.628011) (xy 99.086685 -221.644981) (xy 99.131503 -221.669103) (xy 99.172095 -221.699808)
			(xy 99.207503 -221.736369) (xy 99.23689 -221.777925) (xy 99.259563 -221.823493) (xy 99.274985 -221.871997)
			(xy 99.282793 -221.922292) (xy 99.283266 -221.94774) (xy 99.282757 -221.973707) (xy 99.274632 -222.025002)
			(xy 99.258584 -222.074395) (xy 99.235006 -222.120669) (xy 99.20448 -222.162685) (xy 99.167757 -222.199408)
			(xy 99.125741 -222.229934) (xy 99.079467 -222.253512) (xy 99.030074 -222.26956) (xy 98.978779 -222.277685)
			(xy 98.926845 -222.277685) (xy 98.87555 -222.26956) (xy 98.826157 -222.253512) (xy 98.779883 -222.229934)
			(xy 98.737867 -222.199408) (xy 98.701144 -222.162685) (xy 98.670618 -222.120669) (xy 98.64704 -222.074395)
			(xy 98.630992 -222.025002) (xy 98.622867 -221.973707) (xy 98.622358 -221.94774) (xy 98.622918 -221.919754)
			(xy 98.632363 -221.864587) (xy 98.641154 -221.838012) (xy 98.648774 -221.815914) (xy 98.445066 -221.463108)
			(xy 98.422206 -221.45879) (xy 98.397282 -221.45363) (xy 98.349295 -221.436669) (xy 98.304474 -221.412553)
			(xy 98.263879 -221.381853) (xy 98.228468 -221.345294) (xy 98.19908 -221.303739) (xy 98.176407 -221.258171)
			(xy 98.160987 -221.209667) (xy 98.153182 -221.159372) (xy 98.152712 -221.133924) (xy 97.87382 -221.133924)
			(xy 97.873311 -221.159891) (xy 97.865186 -221.211186) (xy 97.849138 -221.260579) (xy 97.82556 -221.306853)
			(xy 97.795034 -221.348869) (xy 97.758311 -221.385592) (xy 97.716295 -221.416118) (xy 97.670021 -221.439696)
			(xy 97.620628 -221.455744) (xy 97.569333 -221.463869) (xy 97.517399 -221.463869) (xy 97.466104 -221.455744)
			(xy 97.416711 -221.439696) (xy 97.370437 -221.416118) (xy 97.328421 -221.385592) (xy 97.291698 -221.348869)
			(xy 97.261172 -221.306853) (xy 97.237594 -221.260579) (xy 97.221546 -221.211186) (xy 97.213421 -221.159891)
			(xy 97.212912 -221.133924) (xy 96.93402 -221.133924) (xy 96.933472 -221.16191) (xy 96.924019 -221.217078)
			(xy 96.915224 -221.243652) (xy 96.907604 -221.26575) (xy 97.111312 -221.618556) (xy 97.134172 -221.622874)
			(xy 97.1591 -221.628011) (xy 97.207085 -221.644981) (xy 97.251903 -221.669103) (xy 97.292495 -221.699808)
			(xy 97.327903 -221.736369) (xy 97.35729 -221.777925) (xy 97.379963 -221.823493) (xy 97.395385 -221.871997)
			(xy 97.403193 -221.922292) (xy 97.403666 -221.94774) (xy 97.403157 -221.973707) (xy 97.395032 -222.025002)
			(xy 97.378984 -222.074395) (xy 97.355406 -222.120669) (xy 97.32488 -222.162685) (xy 97.288157 -222.199408)
			(xy 97.246141 -222.229934) (xy 97.199867 -222.253512) (xy 97.150474 -222.26956) (xy 97.099179 -222.277685)
			(xy 97.047245 -222.277685) (xy 96.99595 -222.26956) (xy 96.946557 -222.253512) (xy 96.900283 -222.229934)
			(xy 96.858267 -222.199408) (xy 96.821544 -222.162685) (xy 96.791018 -222.120669) (xy 96.76744 -222.074395)
			(xy 96.751392 -222.025002) (xy 96.743267 -221.973707) (xy 96.742758 -221.94774) (xy 96.743318 -221.919754)
			(xy 96.752763 -221.864587) (xy 96.761554 -221.838012) (xy 96.769174 -221.815914) (xy 96.565466 -221.463108)
			(xy 96.542606 -221.45879) (xy 96.517682 -221.45363) (xy 96.469695 -221.436669) (xy 96.424874 -221.412553)
			(xy 96.384279 -221.381853) (xy 96.348868 -221.345294) (xy 96.31948 -221.303739) (xy 96.296807 -221.258171)
			(xy 96.281387 -221.209667) (xy 96.273582 -221.159372) (xy 96.273112 -221.133924) (xy 95.99422 -221.133924)
			(xy 95.993711 -221.159891) (xy 95.985586 -221.211186) (xy 95.969538 -221.260579) (xy 95.94596 -221.306853)
			(xy 95.915434 -221.348869) (xy 95.878711 -221.385592) (xy 95.836695 -221.416118) (xy 95.790421 -221.439696)
			(xy 95.741028 -221.455744) (xy 95.689733 -221.463869) (xy 95.637799 -221.463869) (xy 95.586504 -221.455744)
			(xy 95.537111 -221.439696) (xy 95.490837 -221.416118) (xy 95.448821 -221.385592) (xy 95.412098 -221.348869)
			(xy 95.381572 -221.306853) (xy 95.357994 -221.260579) (xy 95.341946 -221.211186) (xy 95.333821 -221.159891)
			(xy 95.333312 -221.133924) (xy 95.05442 -221.133924) (xy 95.053872 -221.16191) (xy 95.044419 -221.217078)
			(xy 95.035624 -221.243652) (xy 95.028004 -221.26575) (xy 95.231712 -221.618556) (xy 95.254572 -221.622874)
			(xy 95.2795 -221.628011) (xy 95.327485 -221.644981) (xy 95.372303 -221.669103) (xy 95.412895 -221.699808)
			(xy 95.448303 -221.736369) (xy 95.47769 -221.777925) (xy 95.500363 -221.823493) (xy 95.515785 -221.871997)
			(xy 95.523593 -221.922292) (xy 95.524066 -221.94774) (xy 95.523557 -221.973707) (xy 95.515432 -222.025002)
			(xy 95.499384 -222.074395) (xy 95.475806 -222.120669) (xy 95.44528 -222.162685) (xy 95.408557 -222.199408)
			(xy 95.366541 -222.229934) (xy 95.320267 -222.253512) (xy 95.270874 -222.26956) (xy 95.219579 -222.277685)
			(xy 95.167645 -222.277685) (xy 95.11635 -222.26956) (xy 95.066957 -222.253512) (xy 95.020683 -222.229934)
			(xy 94.978667 -222.199408) (xy 94.941944 -222.162685) (xy 94.911418 -222.120669) (xy 94.88784 -222.074395)
			(xy 94.871792 -222.025002) (xy 94.863667 -221.973707) (xy 94.863158 -221.94774) (xy 94.863718 -221.919754)
			(xy 94.873163 -221.864587) (xy 94.881954 -221.838012) (xy 94.889574 -221.815914) (xy 94.685866 -221.463108)
			(xy 94.663006 -221.45879) (xy 94.638082 -221.45363) (xy 94.590095 -221.436669) (xy 94.545274 -221.412553)
			(xy 94.504679 -221.381853) (xy 94.469268 -221.345294) (xy 94.43988 -221.303739) (xy 94.417207 -221.258171)
			(xy 94.401787 -221.209667) (xy 94.393982 -221.159372) (xy 94.393512 -221.133924) (xy 94.11462 -221.133924)
			(xy 94.114111 -221.159891) (xy 94.105986 -221.211186) (xy 94.089938 -221.260579) (xy 94.06636 -221.306853)
			(xy 94.035834 -221.348869) (xy 93.999111 -221.385592) (xy 93.957095 -221.416118) (xy 93.910821 -221.439696)
			(xy 93.861428 -221.455744) (xy 93.810133 -221.463869) (xy 93.758199 -221.463869) (xy 93.706904 -221.455744)
			(xy 93.657511 -221.439696) (xy 93.611237 -221.416118) (xy 93.569221 -221.385592) (xy 93.532498 -221.348869)
			(xy 93.501972 -221.306853) (xy 93.478394 -221.260579) (xy 93.462346 -221.211186) (xy 93.454221 -221.159891)
			(xy 93.453712 -221.133924) (xy 93.17482 -221.133924) (xy 93.174272 -221.16191) (xy 93.164819 -221.217078)
			(xy 93.156024 -221.243652) (xy 93.148404 -221.26575) (xy 93.352112 -221.618556) (xy 93.374972 -221.622874)
			(xy 93.3999 -221.628011) (xy 93.447885 -221.644981) (xy 93.492703 -221.669103) (xy 93.533295 -221.699808)
			(xy 93.568703 -221.736369) (xy 93.59809 -221.777925) (xy 93.620763 -221.823493) (xy 93.636185 -221.871997)
			(xy 93.643993 -221.922292) (xy 93.644466 -221.94774) (xy 93.643957 -221.973707) (xy 93.635832 -222.025002)
			(xy 93.619784 -222.074395) (xy 93.596206 -222.120669) (xy 93.56568 -222.162685) (xy 93.528957 -222.199408)
			(xy 93.486941 -222.229934) (xy 93.440667 -222.253512) (xy 93.391274 -222.26956) (xy 93.339979 -222.277685)
			(xy 93.288045 -222.277685) (xy 93.23675 -222.26956) (xy 93.187357 -222.253512) (xy 93.141083 -222.229934)
			(xy 93.099067 -222.199408) (xy 93.062344 -222.162685) (xy 93.031818 -222.120669) (xy 93.00824 -222.074395)
			(xy 92.992192 -222.025002) (xy 92.984067 -221.973707) (xy 92.983558 -221.94774) (xy 92.984118 -221.919754)
			(xy 92.993563 -221.864587) (xy 93.002354 -221.838012) (xy 93.009974 -221.815914) (xy 92.806266 -221.463108)
			(xy 92.783406 -221.45879) (xy 92.758482 -221.45363) (xy 92.710495 -221.436669) (xy 92.665674 -221.412553)
			(xy 92.625079 -221.381853) (xy 92.589668 -221.345294) (xy 92.56028 -221.303739) (xy 92.537607 -221.258171)
			(xy 92.522187 -221.209667) (xy 92.514382 -221.159372) (xy 92.513912 -221.133924) (xy 92.23502 -221.133924)
			(xy 92.234511 -221.159891) (xy 92.226386 -221.211186) (xy 92.210338 -221.260579) (xy 92.18676 -221.306853)
			(xy 92.156234 -221.348869) (xy 92.119511 -221.385592) (xy 92.077495 -221.416118) (xy 92.031221 -221.439696)
			(xy 91.981828 -221.455744) (xy 91.930533 -221.463869) (xy 91.878599 -221.463869) (xy 91.827304 -221.455744)
			(xy 91.777911 -221.439696) (xy 91.731637 -221.416118) (xy 91.689621 -221.385592) (xy 91.652898 -221.348869)
			(xy 91.622372 -221.306853) (xy 91.598794 -221.260579) (xy 91.582746 -221.211186) (xy 91.574621 -221.159891)
			(xy 91.574112 -221.133924) (xy 91.29522 -221.133924) (xy 91.294672 -221.16191) (xy 91.285219 -221.217078)
			(xy 91.276424 -221.243652) (xy 91.268804 -221.26575) (xy 91.472512 -221.618556) (xy 91.495372 -221.622874)
			(xy 91.5203 -221.628011) (xy 91.568285 -221.644981) (xy 91.613103 -221.669103) (xy 91.653695 -221.699808)
			(xy 91.689103 -221.736369) (xy 91.71849 -221.777925) (xy 91.741163 -221.823493) (xy 91.756585 -221.871997)
			(xy 91.764393 -221.922292) (xy 91.764866 -221.94774) (xy 91.764357 -221.973707) (xy 91.756232 -222.025002)
			(xy 91.740184 -222.074395) (xy 91.716606 -222.120669) (xy 91.68608 -222.162685) (xy 91.649357 -222.199408)
			(xy 91.607341 -222.229934) (xy 91.561067 -222.253512) (xy 91.511674 -222.26956) (xy 91.460379 -222.277685)
			(xy 91.408445 -222.277685) (xy 91.35715 -222.26956) (xy 91.307757 -222.253512) (xy 91.261483 -222.229934)
			(xy 91.219467 -222.199408) (xy 91.182744 -222.162685) (xy 91.152218 -222.120669) (xy 91.12864 -222.074395)
			(xy 91.112592 -222.025002) (xy 91.104467 -221.973707) (xy 91.103958 -221.94774) (xy 91.104518 -221.919754)
			(xy 91.113963 -221.864587) (xy 91.122754 -221.838012) (xy 91.130374 -221.815914) (xy 90.926666 -221.463108)
			(xy 90.903806 -221.45879) (xy 90.878882 -221.45363) (xy 90.830895 -221.436669) (xy 90.786074 -221.412553)
			(xy 90.745479 -221.381853) (xy 90.710068 -221.345294) (xy 90.68068 -221.303739) (xy 90.658007 -221.258171)
			(xy 90.642587 -221.209667) (xy 90.634782 -221.159372) (xy 90.634312 -221.133924) (xy 90.35542 -221.133924)
			(xy 90.354911 -221.159891) (xy 90.346786 -221.211186) (xy 90.330738 -221.260579) (xy 90.30716 -221.306853)
			(xy 90.276634 -221.348869) (xy 90.239911 -221.385592) (xy 90.197895 -221.416118) (xy 90.151621 -221.439696)
			(xy 90.102228 -221.455744) (xy 90.050933 -221.463869) (xy 89.998999 -221.463869) (xy 89.947704 -221.455744)
			(xy 89.898311 -221.439696) (xy 89.852037 -221.416118) (xy 89.810021 -221.385592) (xy 89.773298 -221.348869)
			(xy 89.742772 -221.306853) (xy 89.719194 -221.260579) (xy 89.703146 -221.211186) (xy 89.695021 -221.159891)
			(xy 89.694512 -221.133924) (xy 89.41562 -221.133924) (xy 89.415072 -221.16191) (xy 89.405619 -221.217078)
			(xy 89.396824 -221.243652) (xy 89.389204 -221.26575) (xy 89.592912 -221.618556) (xy 89.615772 -221.622874)
			(xy 89.6407 -221.628011) (xy 89.688685 -221.644981) (xy 89.733503 -221.669103) (xy 89.774095 -221.699808)
			(xy 89.809503 -221.736369) (xy 89.83889 -221.777925) (xy 89.861563 -221.823493) (xy 89.876985 -221.871997)
			(xy 89.884793 -221.922292) (xy 89.885266 -221.94774) (xy 89.884757 -221.973707) (xy 89.876632 -222.025002)
			(xy 89.860584 -222.074395) (xy 89.837006 -222.120669) (xy 89.80648 -222.162685) (xy 89.769757 -222.199408)
			(xy 89.727741 -222.229934) (xy 89.681467 -222.253512) (xy 89.632074 -222.26956) (xy 89.580779 -222.277685)
			(xy 89.528845 -222.277685) (xy 89.47755 -222.26956) (xy 89.428157 -222.253512) (xy 89.381883 -222.229934)
			(xy 89.339867 -222.199408) (xy 89.303144 -222.162685) (xy 89.272618 -222.120669) (xy 89.24904 -222.074395)
			(xy 89.232992 -222.025002) (xy 89.224867 -221.973707) (xy 89.224358 -221.94774) (xy 89.224918 -221.919754)
			(xy 89.234363 -221.864587) (xy 89.243154 -221.838012) (xy 89.250774 -221.815914) (xy 89.047066 -221.463108)
			(xy 89.024206 -221.45879) (xy 88.999282 -221.45363) (xy 88.951295 -221.436669) (xy 88.906474 -221.412553)
			(xy 88.865879 -221.381853) (xy 88.830468 -221.345294) (xy 88.80108 -221.303739) (xy 88.778407 -221.258171)
			(xy 88.762987 -221.209667) (xy 88.755182 -221.159372) (xy 88.754712 -221.133924) (xy 88.47582 -221.133924)
			(xy 88.475311 -221.159891) (xy 88.467186 -221.211186) (xy 88.451138 -221.260579) (xy 88.42756 -221.306853)
			(xy 88.397034 -221.348869) (xy 88.360311 -221.385592) (xy 88.318295 -221.416118) (xy 88.272021 -221.439696)
			(xy 88.222628 -221.455744) (xy 88.171333 -221.463869) (xy 88.119399 -221.463869) (xy 88.068104 -221.455744)
			(xy 88.018711 -221.439696) (xy 87.972437 -221.416118) (xy 87.930421 -221.385592) (xy 87.893698 -221.348869)
			(xy 87.863172 -221.306853) (xy 87.839594 -221.260579) (xy 87.823546 -221.211186) (xy 87.815421 -221.159891)
			(xy 87.68842 -221.159891) (xy 87.68842 -221.614746) (xy 87.730838 -221.621858) (xy 87.75616 -221.626655)
			(xy 87.805013 -221.64306) (xy 87.850726 -221.666854) (xy 87.892189 -221.697459) (xy 87.928395 -221.734132)
			(xy 87.958467 -221.775983) (xy 87.981673 -221.821997) (xy 87.997451 -221.871057) (xy 88.005418 -221.921972)
			(xy 88.00592 -221.94774) (xy 88.005482 -221.972199) (xy 87.998274 -222.020583) (xy 87.984007 -222.067374)
			(xy 87.962994 -222.111548) (xy 87.935694 -222.152139) (xy 87.902704 -222.188259) (xy 87.884 -222.204026)
			(xy 87.873304 -222.213359) (xy 87.857103 -222.236654) (xy 87.84793 -222.263505) (xy 87.846493 -222.291844)
			(xy 87.852903 -222.319485) (xy 87.866665 -222.344299) (xy 87.87638 -222.354648) (xy 87.989918 -222.468186)
			(xy 88.020906 -222.455486) (xy 88.050766 -222.444153) (xy 88.113437 -222.431881) (xy 88.145366 -222.431102)
			(xy 88.171336 -222.431609) (xy 88.222638 -222.439729) (xy 88.272038 -222.455774) (xy 88.31832 -222.479349)
			(xy 88.360344 -222.509874) (xy 88.397076 -222.546597) (xy 88.42761 -222.588614) (xy 88.451197 -222.63489)
			(xy 88.467253 -222.684286) (xy 88.475385 -222.735586) (xy 88.47582 -222.761556) (xy 88.47522 -222.787523)
			(xy 88.755221 -222.787523) (xy 88.755221 -222.735589) (xy 88.763346 -222.684294) (xy 88.779394 -222.634901)
			(xy 88.802972 -222.588627) (xy 88.833498 -222.546611) (xy 88.870221 -222.509888) (xy 88.912237 -222.479362)
			(xy 88.958511 -222.455784) (xy 89.007904 -222.439736) (xy 89.059199 -222.431611) (xy 89.111133 -222.431611)
			(xy 89.162428 -222.439736) (xy 89.211821 -222.455784) (xy 89.258095 -222.479362) (xy 89.300111 -222.509888)
			(xy 89.336834 -222.546611) (xy 89.36736 -222.588627) (xy 89.390938 -222.634901) (xy 89.406986 -222.684294)
			(xy 89.415111 -222.735589) (xy 89.41562 -222.761556) (xy 89.415111 -222.787523) (xy 89.695021 -222.787523)
			(xy 89.695021 -222.735589) (xy 89.703146 -222.684294) (xy 89.719194 -222.634901) (xy 89.742772 -222.588627)
			(xy 89.773298 -222.546611) (xy 89.810021 -222.509888) (xy 89.852037 -222.479362) (xy 89.898311 -222.455784)
			(xy 89.947704 -222.439736) (xy 89.998999 -222.431611) (xy 90.050933 -222.431611) (xy 90.102228 -222.439736)
			(xy 90.151621 -222.455784) (xy 90.197895 -222.479362) (xy 90.239911 -222.509888) (xy 90.276634 -222.546611)
			(xy 90.30716 -222.588627) (xy 90.330738 -222.634901) (xy 90.346786 -222.684294) (xy 90.354911 -222.735589)
			(xy 90.35542 -222.761556) (xy 90.354911 -222.787523) (xy 90.634821 -222.787523) (xy 90.634821 -222.735589)
			(xy 90.642946 -222.684294) (xy 90.658994 -222.634901) (xy 90.682572 -222.588627) (xy 90.713098 -222.546611)
			(xy 90.749821 -222.509888) (xy 90.791837 -222.479362) (xy 90.838111 -222.455784) (xy 90.887504 -222.439736)
			(xy 90.938799 -222.431611) (xy 90.990733 -222.431611) (xy 91.042028 -222.439736) (xy 91.091421 -222.455784)
			(xy 91.137695 -222.479362) (xy 91.179711 -222.509888) (xy 91.216434 -222.546611) (xy 91.24696 -222.588627)
			(xy 91.270538 -222.634901) (xy 91.286586 -222.684294) (xy 91.294711 -222.735589) (xy 91.29522 -222.761556)
			(xy 91.294711 -222.787523) (xy 91.574621 -222.787523) (xy 91.574621 -222.735589) (xy 91.582746 -222.684294)
			(xy 91.598794 -222.634901) (xy 91.622372 -222.588627) (xy 91.652898 -222.546611) (xy 91.689621 -222.509888)
			(xy 91.731637 -222.479362) (xy 91.777911 -222.455784) (xy 91.827304 -222.439736) (xy 91.878599 -222.431611)
			(xy 91.930533 -222.431611) (xy 91.981828 -222.439736) (xy 92.031221 -222.455784) (xy 92.077495 -222.479362)
			(xy 92.119511 -222.509888) (xy 92.156234 -222.546611) (xy 92.18676 -222.588627) (xy 92.210338 -222.634901)
			(xy 92.226386 -222.684294) (xy 92.234511 -222.735589) (xy 92.23502 -222.761556) (xy 92.234511 -222.787523)
			(xy 92.514421 -222.787523) (xy 92.514421 -222.735589) (xy 92.522546 -222.684294) (xy 92.538594 -222.634901)
			(xy 92.562172 -222.588627) (xy 92.592698 -222.546611) (xy 92.629421 -222.509888) (xy 92.671437 -222.479362)
			(xy 92.717711 -222.455784) (xy 92.767104 -222.439736) (xy 92.818399 -222.431611) (xy 92.870333 -222.431611)
			(xy 92.921628 -222.439736) (xy 92.971021 -222.455784) (xy 93.017295 -222.479362) (xy 93.059311 -222.509888)
			(xy 93.096034 -222.546611) (xy 93.12656 -222.588627) (xy 93.150138 -222.634901) (xy 93.166186 -222.684294)
			(xy 93.174311 -222.735589) (xy 93.17482 -222.761556) (xy 93.174311 -222.787523) (xy 93.454221 -222.787523)
			(xy 93.454221 -222.735589) (xy 93.462346 -222.684294) (xy 93.478394 -222.634901) (xy 93.501972 -222.588627)
			(xy 93.532498 -222.546611) (xy 93.569221 -222.509888) (xy 93.611237 -222.479362) (xy 93.657511 -222.455784)
			(xy 93.706904 -222.439736) (xy 93.758199 -222.431611) (xy 93.810133 -222.431611) (xy 93.861428 -222.439736)
			(xy 93.910821 -222.455784) (xy 93.957095 -222.479362) (xy 93.999111 -222.509888) (xy 94.035834 -222.546611)
			(xy 94.06636 -222.588627) (xy 94.089938 -222.634901) (xy 94.105986 -222.684294) (xy 94.114111 -222.735589)
			(xy 94.11462 -222.761556) (xy 94.114111 -222.787523) (xy 94.394021 -222.787523) (xy 94.394021 -222.735589)
			(xy 94.402146 -222.684294) (xy 94.418194 -222.634901) (xy 94.441772 -222.588627) (xy 94.472298 -222.546611)
			(xy 94.509021 -222.509888) (xy 94.551037 -222.479362) (xy 94.597311 -222.455784) (xy 94.646704 -222.439736)
			(xy 94.697999 -222.431611) (xy 94.749933 -222.431611) (xy 94.801228 -222.439736) (xy 94.850621 -222.455784)
			(xy 94.896895 -222.479362) (xy 94.938911 -222.509888) (xy 94.975634 -222.546611) (xy 95.00616 -222.588627)
			(xy 95.029738 -222.634901) (xy 95.045786 -222.684294) (xy 95.053911 -222.735589) (xy 95.05442 -222.761556)
			(xy 95.053911 -222.787523) (xy 95.333821 -222.787523) (xy 95.333821 -222.735589) (xy 95.341946 -222.684294)
			(xy 95.357994 -222.634901) (xy 95.381572 -222.588627) (xy 95.412098 -222.546611) (xy 95.448821 -222.509888)
			(xy 95.490837 -222.479362) (xy 95.537111 -222.455784) (xy 95.586504 -222.439736) (xy 95.637799 -222.431611)
			(xy 95.689733 -222.431611) (xy 95.741028 -222.439736) (xy 95.790421 -222.455784) (xy 95.836695 -222.479362)
			(xy 95.878711 -222.509888) (xy 95.915434 -222.546611) (xy 95.94596 -222.588627) (xy 95.969538 -222.634901)
			(xy 95.985586 -222.684294) (xy 95.993711 -222.735589) (xy 95.99422 -222.761556) (xy 95.993711 -222.787523)
			(xy 96.273621 -222.787523) (xy 96.273621 -222.735589) (xy 96.281746 -222.684294) (xy 96.297794 -222.634901)
			(xy 96.321372 -222.588627) (xy 96.351898 -222.546611) (xy 96.388621 -222.509888) (xy 96.430637 -222.479362)
			(xy 96.476911 -222.455784) (xy 96.526304 -222.439736) (xy 96.577599 -222.431611) (xy 96.629533 -222.431611)
			(xy 96.680828 -222.439736) (xy 96.730221 -222.455784) (xy 96.776495 -222.479362) (xy 96.818511 -222.509888)
			(xy 96.855234 -222.546611) (xy 96.88576 -222.588627) (xy 96.909338 -222.634901) (xy 96.925386 -222.684294)
			(xy 96.933511 -222.735589) (xy 96.93402 -222.761556) (xy 96.933511 -222.787523) (xy 97.213421 -222.787523)
			(xy 97.213421 -222.735589) (xy 97.221546 -222.684294) (xy 97.237594 -222.634901) (xy 97.261172 -222.588627)
			(xy 97.291698 -222.546611) (xy 97.328421 -222.509888) (xy 97.370437 -222.479362) (xy 97.416711 -222.455784)
			(xy 97.466104 -222.439736) (xy 97.517399 -222.431611) (xy 97.569333 -222.431611) (xy 97.620628 -222.439736)
			(xy 97.670021 -222.455784) (xy 97.716295 -222.479362) (xy 97.758311 -222.509888) (xy 97.795034 -222.546611)
			(xy 97.82556 -222.588627) (xy 97.849138 -222.634901) (xy 97.865186 -222.684294) (xy 97.873311 -222.735589)
			(xy 97.87382 -222.761556) (xy 97.873311 -222.787523) (xy 98.153221 -222.787523) (xy 98.153221 -222.735589)
			(xy 98.161346 -222.684294) (xy 98.177394 -222.634901) (xy 98.200972 -222.588627) (xy 98.231498 -222.546611)
			(xy 98.268221 -222.509888) (xy 98.310237 -222.479362) (xy 98.356511 -222.455784) (xy 98.405904 -222.439736)
			(xy 98.457199 -222.431611) (xy 98.509133 -222.431611) (xy 98.560428 -222.439736) (xy 98.609821 -222.455784)
			(xy 98.656095 -222.479362) (xy 98.698111 -222.509888) (xy 98.734834 -222.546611) (xy 98.76536 -222.588627)
			(xy 98.788938 -222.634901) (xy 98.804986 -222.684294) (xy 98.813111 -222.735589) (xy 98.81362 -222.761556)
			(xy 98.813111 -222.787523) (xy 99.093021 -222.787523) (xy 99.093021 -222.735589) (xy 99.101146 -222.684294)
			(xy 99.117194 -222.634901) (xy 99.140772 -222.588627) (xy 99.171298 -222.546611) (xy 99.208021 -222.509888)
			(xy 99.250037 -222.479362) (xy 99.296311 -222.455784) (xy 99.345704 -222.439736) (xy 99.396999 -222.431611)
			(xy 99.448933 -222.431611) (xy 99.500228 -222.439736) (xy 99.549621 -222.455784) (xy 99.595895 -222.479362)
			(xy 99.637911 -222.509888) (xy 99.674634 -222.546611) (xy 99.70516 -222.588627) (xy 99.728738 -222.634901)
			(xy 99.744786 -222.684294) (xy 99.752911 -222.735589) (xy 99.75342 -222.761556) (xy 99.752911 -222.787523)
			(xy 99.744786 -222.838818) (xy 99.728738 -222.888211) (xy 99.70516 -222.934485) (xy 99.674634 -222.976501)
			(xy 99.637911 -223.013224) (xy 99.595895 -223.04375) (xy 99.549621 -223.067328) (xy 99.500228 -223.083376)
			(xy 99.448933 -223.091501) (xy 99.396999 -223.091501) (xy 99.345704 -223.083376) (xy 99.296311 -223.067328)
			(xy 99.250037 -223.04375) (xy 99.208021 -223.013224) (xy 99.171298 -222.976501) (xy 99.140772 -222.934485)
			(xy 99.117194 -222.888211) (xy 99.101146 -222.838818) (xy 99.093021 -222.787523) (xy 98.813111 -222.787523)
			(xy 98.804986 -222.838818) (xy 98.788938 -222.888211) (xy 98.76536 -222.934485) (xy 98.734834 -222.976501)
			(xy 98.698111 -223.013224) (xy 98.656095 -223.04375) (xy 98.609821 -223.067328) (xy 98.560428 -223.083376)
			(xy 98.509133 -223.091501) (xy 98.457199 -223.091501) (xy 98.405904 -223.083376) (xy 98.356511 -223.067328)
			(xy 98.310237 -223.04375) (xy 98.268221 -223.013224) (xy 98.231498 -222.976501) (xy 98.200972 -222.934485)
			(xy 98.177394 -222.888211) (xy 98.161346 -222.838818) (xy 98.153221 -222.787523) (xy 97.873311 -222.787523)
			(xy 97.865186 -222.838818) (xy 97.849138 -222.888211) (xy 97.82556 -222.934485) (xy 97.795034 -222.976501)
			(xy 97.758311 -223.013224) (xy 97.716295 -223.04375) (xy 97.670021 -223.067328) (xy 97.620628 -223.083376)
			(xy 97.569333 -223.091501) (xy 97.517399 -223.091501) (xy 97.466104 -223.083376) (xy 97.416711 -223.067328)
			(xy 97.370437 -223.04375) (xy 97.328421 -223.013224) (xy 97.291698 -222.976501) (xy 97.261172 -222.934485)
			(xy 97.237594 -222.888211) (xy 97.221546 -222.838818) (xy 97.213421 -222.787523) (xy 96.933511 -222.787523)
			(xy 96.925386 -222.838818) (xy 96.909338 -222.888211) (xy 96.88576 -222.934485) (xy 96.855234 -222.976501)
			(xy 96.818511 -223.013224) (xy 96.776495 -223.04375) (xy 96.730221 -223.067328) (xy 96.680828 -223.083376)
			(xy 96.629533 -223.091501) (xy 96.577599 -223.091501) (xy 96.526304 -223.083376) (xy 96.476911 -223.067328)
			(xy 96.430637 -223.04375) (xy 96.388621 -223.013224) (xy 96.351898 -222.976501) (xy 96.321372 -222.934485)
			(xy 96.297794 -222.888211) (xy 96.281746 -222.838818) (xy 96.273621 -222.787523) (xy 95.993711 -222.787523)
			(xy 95.985586 -222.838818) (xy 95.969538 -222.888211) (xy 95.94596 -222.934485) (xy 95.915434 -222.976501)
			(xy 95.878711 -223.013224) (xy 95.836695 -223.04375) (xy 95.790421 -223.067328) (xy 95.741028 -223.083376)
			(xy 95.689733 -223.091501) (xy 95.637799 -223.091501) (xy 95.586504 -223.083376) (xy 95.537111 -223.067328)
			(xy 95.490837 -223.04375) (xy 95.448821 -223.013224) (xy 95.412098 -222.976501) (xy 95.381572 -222.934485)
			(xy 95.357994 -222.888211) (xy 95.341946 -222.838818) (xy 95.333821 -222.787523) (xy 95.053911 -222.787523)
			(xy 95.045786 -222.838818) (xy 95.029738 -222.888211) (xy 95.00616 -222.934485) (xy 94.975634 -222.976501)
			(xy 94.938911 -223.013224) (xy 94.896895 -223.04375) (xy 94.850621 -223.067328) (xy 94.801228 -223.083376)
			(xy 94.749933 -223.091501) (xy 94.697999 -223.091501) (xy 94.646704 -223.083376) (xy 94.597311 -223.067328)
			(xy 94.551037 -223.04375) (xy 94.509021 -223.013224) (xy 94.472298 -222.976501) (xy 94.441772 -222.934485)
			(xy 94.418194 -222.888211) (xy 94.402146 -222.838818) (xy 94.394021 -222.787523) (xy 94.114111 -222.787523)
			(xy 94.105986 -222.838818) (xy 94.089938 -222.888211) (xy 94.06636 -222.934485) (xy 94.035834 -222.976501)
			(xy 93.999111 -223.013224) (xy 93.957095 -223.04375) (xy 93.910821 -223.067328) (xy 93.861428 -223.083376)
			(xy 93.810133 -223.091501) (xy 93.758199 -223.091501) (xy 93.706904 -223.083376) (xy 93.657511 -223.067328)
			(xy 93.611237 -223.04375) (xy 93.569221 -223.013224) (xy 93.532498 -222.976501) (xy 93.501972 -222.934485)
			(xy 93.478394 -222.888211) (xy 93.462346 -222.838818) (xy 93.454221 -222.787523) (xy 93.174311 -222.787523)
			(xy 93.166186 -222.838818) (xy 93.150138 -222.888211) (xy 93.12656 -222.934485) (xy 93.096034 -222.976501)
			(xy 93.059311 -223.013224) (xy 93.017295 -223.04375) (xy 92.971021 -223.067328) (xy 92.921628 -223.083376)
			(xy 92.870333 -223.091501) (xy 92.818399 -223.091501) (xy 92.767104 -223.083376) (xy 92.717711 -223.067328)
			(xy 92.671437 -223.04375) (xy 92.629421 -223.013224) (xy 92.592698 -222.976501) (xy 92.562172 -222.934485)
			(xy 92.538594 -222.888211) (xy 92.522546 -222.838818) (xy 92.514421 -222.787523) (xy 92.234511 -222.787523)
			(xy 92.226386 -222.838818) (xy 92.210338 -222.888211) (xy 92.18676 -222.934485) (xy 92.156234 -222.976501)
			(xy 92.119511 -223.013224) (xy 92.077495 -223.04375) (xy 92.031221 -223.067328) (xy 91.981828 -223.083376)
			(xy 91.930533 -223.091501) (xy 91.878599 -223.091501) (xy 91.827304 -223.083376) (xy 91.777911 -223.067328)
			(xy 91.731637 -223.04375) (xy 91.689621 -223.013224) (xy 91.652898 -222.976501) (xy 91.622372 -222.934485)
			(xy 91.598794 -222.888211) (xy 91.582746 -222.838818) (xy 91.574621 -222.787523) (xy 91.294711 -222.787523)
			(xy 91.286586 -222.838818) (xy 91.270538 -222.888211) (xy 91.24696 -222.934485) (xy 91.216434 -222.976501)
			(xy 91.179711 -223.013224) (xy 91.137695 -223.04375) (xy 91.091421 -223.067328) (xy 91.042028 -223.083376)
			(xy 90.990733 -223.091501) (xy 90.938799 -223.091501) (xy 90.887504 -223.083376) (xy 90.838111 -223.067328)
			(xy 90.791837 -223.04375) (xy 90.749821 -223.013224) (xy 90.713098 -222.976501) (xy 90.682572 -222.934485)
			(xy 90.658994 -222.888211) (xy 90.642946 -222.838818) (xy 90.634821 -222.787523) (xy 90.354911 -222.787523)
			(xy 90.346786 -222.838818) (xy 90.330738 -222.888211) (xy 90.30716 -222.934485) (xy 90.276634 -222.976501)
			(xy 90.239911 -223.013224) (xy 90.197895 -223.04375) (xy 90.151621 -223.067328) (xy 90.102228 -223.083376)
			(xy 90.050933 -223.091501) (xy 89.998999 -223.091501) (xy 89.947704 -223.083376) (xy 89.898311 -223.067328)
			(xy 89.852037 -223.04375) (xy 89.810021 -223.013224) (xy 89.773298 -222.976501) (xy 89.742772 -222.934485)
			(xy 89.719194 -222.888211) (xy 89.703146 -222.838818) (xy 89.695021 -222.787523) (xy 89.415111 -222.787523)
			(xy 89.406986 -222.838818) (xy 89.390938 -222.888211) (xy 89.36736 -222.934485) (xy 89.336834 -222.976501)
			(xy 89.300111 -223.013224) (xy 89.258095 -223.04375) (xy 89.211821 -223.067328) (xy 89.162428 -223.083376)
			(xy 89.111133 -223.091501) (xy 89.059199 -223.091501) (xy 89.007904 -223.083376) (xy 88.958511 -223.067328)
			(xy 88.912237 -223.04375) (xy 88.870221 -223.013224) (xy 88.833498 -222.976501) (xy 88.802972 -222.934485)
			(xy 88.779394 -222.888211) (xy 88.763346 -222.838818) (xy 88.755221 -222.787523) (xy 88.47522 -222.787523)
			(xy 88.475082 -222.79349) (xy 88.462807 -222.856166) (xy 88.451436 -222.886016) (xy 88.438736 -222.917004)
			(xy 88.73236 -223.210628) (xy 100.47224 -223.210628)
		)
		(stroke
			(width 0)
			(type solid)
		)
		(fill yes)
		(layer "In11.Cu")
		(net "PVCCFA_EHV_FIVRA_CPU1")
	)
	(gr_poly
		(pts
			(xy 176.238916 -125.796548) (xy 176.250689 -125.771981) (xy 176.280169 -125.726172) (xy 176.315865 -125.68502)
			(xy 176.357051 -125.649365) (xy 176.402889 -125.619929) (xy 176.452448 -125.597312) (xy 176.50472 -125.581974)
			(xy 176.558642 -125.574226) (xy 176.613118 -125.574226) (xy 176.66704 -125.581974) (xy 176.719312 -125.597312)
			(xy 176.768871 -125.619929) (xy 176.814709 -125.649365) (xy 176.855895 -125.68502) (xy 176.891591 -125.726172)
			(xy 176.921071 -125.771981) (xy 176.932844 -125.796548) (xy 181.045104 -125.796548) (xy 181.062783 -125.772627)
			(xy 181.104324 -125.730057) (xy 181.15197 -125.694452) (xy 181.204566 -125.666676) (xy 181.260836 -125.647402)
			(xy 181.319417 -125.637097) (xy 181.349142 -125.63602) (xy 181.369462 -125.635766) (xy 181.782212 -125.222762)
			(xy 181.782212 -124.455682) (xy 181.781761 -124.441871) (xy 181.77437 -124.415256) (xy 181.760109 -124.3916)
			(xy 181.740023 -124.372639) (xy 181.715586 -124.359763) (xy 181.68859 -124.353917) (xy 181.661016 -124.355529)
			(xy 181.634885 -124.364481) (xy 181.612114 -124.380116) (xy 181.602888 -124.390404) (xy 181.584662 -124.411404)
			(xy 181.543169 -124.448416) (xy 181.49674 -124.479011) (xy 181.44636 -124.502538) (xy 181.393097 -124.5185)
			(xy 181.338082 -124.526557) (xy 181.31028 -124.527056) (xy 181.283026 -124.526569) (xy 181.229074 -124.518809)
			(xy 181.176775 -124.50345) (xy 181.127194 -124.480805) (xy 181.08134 -124.451334) (xy 181.040147 -124.415638)
			(xy 181.004454 -124.374444) (xy 180.974985 -124.328588) (xy 180.952343 -124.279006) (xy 180.936987 -124.226707)
			(xy 180.92923 -124.172754) (xy 180.92923 -124.118246) (xy 180.936987 -124.064293) (xy 180.952343 -124.011994)
			(xy 180.974985 -123.962412) (xy 181.004454 -123.916556) (xy 181.040147 -123.875362) (xy 181.08134 -123.839666)
			(xy 181.127194 -123.810195) (xy 181.176775 -123.78755) (xy 181.229074 -123.772191) (xy 181.283026 -123.764431)
			(xy 181.31028 -123.76404) (xy 181.338078 -123.764548) (xy 181.393085 -123.772626) (xy 181.446338 -123.7886)
			(xy 181.49671 -123.812131) (xy 181.543134 -123.842721) (xy 181.584629 -123.879724) (xy 181.602888 -123.900692)
			(xy 181.612122 -123.910952) (xy 181.634892 -123.926532) (xy 181.661004 -123.935442) (xy 181.688549 -123.937032)
			(xy 181.715513 -123.931183) (xy 181.739924 -123.918325) (xy 181.759998 -123.899397) (xy 181.774268 -123.875783)
			(xy 181.781689 -123.849209) (xy 181.782212 -123.835414) (xy 181.782212 -123.414282) (xy 181.781761 -123.400471)
			(xy 181.77437 -123.373856) (xy 181.760109 -123.3502) (xy 181.740023 -123.331239) (xy 181.715586 -123.318363)
			(xy 181.68859 -123.312517) (xy 181.661016 -123.314129) (xy 181.634885 -123.323081) (xy 181.612114 -123.338716)
			(xy 181.602888 -123.349004) (xy 181.584662 -123.370004) (xy 181.543169 -123.407016) (xy 181.49674 -123.437611)
			(xy 181.44636 -123.461138) (xy 181.393097 -123.4771) (xy 181.338082 -123.485157) (xy 181.31028 -123.485656)
			(xy 181.283026 -123.485169) (xy 181.229074 -123.477409) (xy 181.176775 -123.46205) (xy 181.127194 -123.439405)
			(xy 181.08134 -123.409934) (xy 181.040147 -123.374238) (xy 181.004454 -123.333044) (xy 180.974985 -123.287188)
			(xy 180.952343 -123.237606) (xy 180.936987 -123.185307) (xy 180.92923 -123.131354) (xy 180.92923 -123.076846)
			(xy 180.936987 -123.022893) (xy 180.952343 -122.970594) (xy 180.974985 -122.921012) (xy 181.004454 -122.875156)
			(xy 181.040147 -122.833962) (xy 181.08134 -122.798266) (xy 181.127194 -122.768795) (xy 181.176775 -122.74615)
			(xy 181.229074 -122.730791) (xy 181.283026 -122.723031) (xy 181.31028 -122.72264) (xy 181.338078 -122.723148)
			(xy 181.393085 -122.731226) (xy 181.446338 -122.7472) (xy 181.49671 -122.770731) (xy 181.543134 -122.801321)
			(xy 181.584629 -122.838324) (xy 181.602888 -122.859292) (xy 181.612122 -122.869552) (xy 181.634892 -122.885132)
			(xy 181.661004 -122.894042) (xy 181.688549 -122.895632) (xy 181.715513 -122.889783) (xy 181.739924 -122.876925)
			(xy 181.759998 -122.857997) (xy 181.774268 -122.834383) (xy 181.781689 -122.807809) (xy 181.782212 -122.794014)
			(xy 181.782212 -120.956324) (xy 181.781794 -120.94672) (xy 181.77473 -120.928858) (xy 181.761614 -120.914826)
			(xy 181.744268 -120.906574) (xy 181.734714 -120.905524) (xy 181.708563 -120.903349) (xy 181.657384 -120.891772)
			(xy 181.608675 -120.872256) (xy 181.563661 -120.845291) (xy 181.523472 -120.811554) (xy 181.489117 -120.771892)
			(xy 181.461458 -120.727301) (xy 181.44119 -120.6789) (xy 181.428822 -120.627906) (xy 181.424665 -120.575599)
			(xy 181.428823 -120.523291) (xy 181.441191 -120.472297) (xy 181.461459 -120.423897) (xy 181.489118 -120.379306)
			(xy 181.523474 -120.339644) (xy 181.563664 -120.305907) (xy 181.608678 -120.278943) (xy 181.657386 -120.259427)
			(xy 181.708566 -120.247851) (xy 181.734714 -120.245632) (xy 181.744285 -120.24461) (xy 181.761679 -120.236399)
			(xy 181.774818 -120.222352) (xy 181.781852 -120.20445) (xy 181.782212 -120.194832) (xy 181.782212 -120.156224)
			(xy 181.781794 -120.14662) (xy 181.77473 -120.128758) (xy 181.761614 -120.114726) (xy 181.744268 -120.106474)
			(xy 181.734714 -120.105424) (xy 181.708563 -120.103249) (xy 181.657384 -120.091672) (xy 181.608675 -120.072156)
			(xy 181.563661 -120.045191) (xy 181.523472 -120.011454) (xy 181.489117 -119.971792) (xy 181.461458 -119.927201)
			(xy 181.44119 -119.8788) (xy 181.428822 -119.827806) (xy 181.424665 -119.775499) (xy 181.428823 -119.723191)
			(xy 181.441191 -119.672197) (xy 181.461459 -119.623797) (xy 181.489118 -119.579206) (xy 181.523474 -119.539544)
			(xy 181.563664 -119.505807) (xy 181.608678 -119.478843) (xy 181.657386 -119.459327) (xy 181.708566 -119.447751)
			(xy 181.734714 -119.445532) (xy 181.744285 -119.44451) (xy 181.761679 -119.436299) (xy 181.774818 -119.422252)
			(xy 181.781852 -119.40435) (xy 181.782212 -119.394732) (xy 181.782212 -119.356124) (xy 181.781794 -119.34652)
			(xy 181.77473 -119.328658) (xy 181.761614 -119.314626) (xy 181.744268 -119.306374) (xy 181.734714 -119.305324)
			(xy 181.708563 -119.303149) (xy 181.657384 -119.291572) (xy 181.608675 -119.272056) (xy 181.563661 -119.245091)
			(xy 181.523472 -119.211354) (xy 181.489117 -119.171692) (xy 181.461458 -119.127101) (xy 181.44119 -119.0787)
			(xy 181.428822 -119.027706) (xy 181.424665 -118.975399) (xy 181.428823 -118.923091) (xy 181.441191 -118.872097)
			(xy 181.461459 -118.823697) (xy 181.489118 -118.779106) (xy 181.523474 -118.739444) (xy 181.563664 -118.705707)
			(xy 181.608678 -118.678743) (xy 181.657386 -118.659227) (xy 181.708566 -118.647651) (xy 181.734714 -118.645432)
			(xy 181.744285 -118.64441) (xy 181.761679 -118.636199) (xy 181.774818 -118.622152) (xy 181.781852 -118.60425)
			(xy 181.782212 -118.594632) (xy 181.782212 -118.556278) (xy 181.781786 -118.54668) (xy 181.774714 -118.528833)
			(xy 181.761598 -118.514814) (xy 181.74426 -118.506571) (xy 181.734714 -118.505478) (xy 181.708559 -118.503302)
			(xy 181.657371 -118.491724) (xy 181.608654 -118.472206) (xy 181.563633 -118.445237) (xy 181.523437 -118.411495)
			(xy 181.489075 -118.371826) (xy 181.461411 -118.327228) (xy 181.44114 -118.278821) (xy 181.428769 -118.227818)
			(xy 181.424611 -118.175502) (xy 181.428769 -118.123186) (xy 181.441139 -118.072183) (xy 181.46141 -118.023775)
			(xy 181.489073 -117.979177) (xy 181.523434 -117.939508) (xy 181.56363 -117.905766) (xy 181.608651 -117.878796)
			(xy 181.657367 -117.859277) (xy 181.708555 -117.847698) (xy 181.734714 -117.845586) (xy 181.744282 -117.844563)
			(xy 181.761667 -117.83635) (xy 181.774795 -117.822302) (xy 181.781814 -117.804401) (xy 181.782212 -117.794786)
			(xy 181.782212 -117.756178) (xy 181.781786 -117.74658) (xy 181.774714 -117.728733) (xy 181.761598 -117.714714)
			(xy 181.74426 -117.706471) (xy 181.734714 -117.705378) (xy 181.708559 -117.703202) (xy 181.657371 -117.691624)
			(xy 181.608654 -117.672106) (xy 181.563633 -117.645137) (xy 181.523437 -117.611395) (xy 181.489075 -117.571726)
			(xy 181.461411 -117.527128) (xy 181.44114 -117.478721) (xy 181.428769 -117.427718) (xy 181.424611 -117.375402)
			(xy 181.428769 -117.323086) (xy 181.441139 -117.272083) (xy 181.46141 -117.223675) (xy 181.489073 -117.179077)
			(xy 181.523434 -117.139408) (xy 181.56363 -117.105666) (xy 181.608651 -117.078696) (xy 181.657367 -117.059177)
			(xy 181.708555 -117.047598) (xy 181.734714 -117.045486) (xy 181.744282 -117.044463) (xy 181.761667 -117.03625)
			(xy 181.774795 -117.022202) (xy 181.781814 -117.004301) (xy 181.782212 -116.994686) (xy 181.782212 -116.956332)
			(xy 181.781795 -116.946728) (xy 181.774733 -116.928863) (xy 181.761617 -116.914828) (xy 181.74427 -116.906574)
			(xy 181.734714 -116.905532) (xy 181.708563 -116.903357) (xy 181.657382 -116.89178) (xy 181.608672 -116.872263)
			(xy 181.563657 -116.845298) (xy 181.523467 -116.81156) (xy 181.48911 -116.771897) (xy 181.461451 -116.727305)
			(xy 181.441183 -116.678903) (xy 181.428814 -116.627908) (xy 181.424657 -116.575599) (xy 181.428815 -116.52329)
			(xy 181.441183 -116.472295) (xy 181.461452 -116.423894) (xy 181.489112 -116.379302) (xy 181.523468 -116.339639)
			(xy 181.563659 -116.305901) (xy 181.608674 -116.278936) (xy 181.657383 -116.25942) (xy 181.708564 -116.247843)
			(xy 181.734714 -116.24564) (xy 181.744286 -116.244618) (xy 181.761681 -116.236407) (xy 181.774822 -116.222361)
			(xy 181.781858 -116.204459) (xy 181.782212 -116.19484) (xy 181.782212 -116.156232) (xy 181.781795 -116.146628)
			(xy 181.774733 -116.128763) (xy 181.761617 -116.114728) (xy 181.74427 -116.106474) (xy 181.734714 -116.105432)
			(xy 181.708563 -116.103257) (xy 181.657382 -116.09168) (xy 181.608672 -116.072163) (xy 181.563657 -116.045198)
			(xy 181.523467 -116.01146) (xy 181.48911 -115.971797) (xy 181.461451 -115.927205) (xy 181.441183 -115.878803)
			(xy 181.428814 -115.827808) (xy 181.424657 -115.775499) (xy 181.428815 -115.72319) (xy 181.441183 -115.672195)
			(xy 181.461452 -115.623794) (xy 181.489112 -115.579202) (xy 181.523468 -115.539539) (xy 181.563659 -115.505801)
			(xy 181.608674 -115.478836) (xy 181.657383 -115.45932) (xy 181.708564 -115.447743) (xy 181.734714 -115.44554)
			(xy 181.744286 -115.444518) (xy 181.761681 -115.436307) (xy 181.774822 -115.422261) (xy 181.781858 -115.404359)
			(xy 181.782212 -115.39474) (xy 181.782212 -115.356132) (xy 181.781795 -115.346528) (xy 181.774733 -115.328663)
			(xy 181.761617 -115.314628) (xy 181.74427 -115.306374) (xy 181.734714 -115.305332) (xy 181.708563 -115.303157)
			(xy 181.657382 -115.29158) (xy 181.608672 -115.272063) (xy 181.563657 -115.245098) (xy 181.523467 -115.21136)
			(xy 181.48911 -115.171697) (xy 181.461451 -115.127105) (xy 181.441183 -115.078703) (xy 181.428814 -115.027708)
			(xy 181.424657 -114.975399) (xy 181.428815 -114.92309) (xy 181.441183 -114.872095) (xy 181.461452 -114.823694)
			(xy 181.489112 -114.779102) (xy 181.523468 -114.739439) (xy 181.563659 -114.705701) (xy 181.608674 -114.678736)
			(xy 181.657383 -114.65922) (xy 181.708564 -114.647643) (xy 181.734714 -114.64544) (xy 181.744286 -114.644418)
			(xy 181.761681 -114.636207) (xy 181.774822 -114.622161) (xy 181.781858 -114.604259) (xy 181.782212 -114.59464)
			(xy 181.782212 -114.556286) (xy 181.781788 -114.546687) (xy 181.774717 -114.528837) (xy 181.761601 -114.514816)
			(xy 181.744262 -114.506572) (xy 181.734714 -114.505486) (xy 181.708558 -114.50331) (xy 181.657369 -114.491732)
			(xy 181.608651 -114.472213) (xy 181.563629 -114.445244) (xy 181.523431 -114.411501) (xy 181.489069 -114.371832)
			(xy 181.461405 -114.327233) (xy 181.441132 -114.278824) (xy 181.428762 -114.22782) (xy 181.424603 -114.175503)
			(xy 181.428761 -114.123185) (xy 181.441131 -114.072181) (xy 181.461402 -114.023772) (xy 181.489066 -113.979172)
			(xy 181.523428 -113.939503) (xy 181.563624 -113.905759) (xy 181.608647 -113.878789) (xy 181.657364 -113.859269)
			(xy 181.708553 -113.84769) (xy 181.734714 -113.845594) (xy 181.744283 -113.844571) (xy 181.761669 -113.836358)
			(xy 181.774799 -113.822311) (xy 181.78182 -113.80441) (xy 181.782212 -113.794794) (xy 181.782212 -112.956086)
			(xy 181.781788 -112.946487) (xy 181.774717 -112.928637) (xy 181.761601 -112.914616) (xy 181.744262 -112.906372)
			(xy 181.734714 -112.905286) (xy 181.708558 -112.90311) (xy 181.657369 -112.891532) (xy 181.608651 -112.872013)
			(xy 181.563629 -112.845044) (xy 181.523431 -112.811301) (xy 181.489069 -112.771632) (xy 181.461405 -112.727033)
			(xy 181.441132 -112.678624) (xy 181.428762 -112.62762) (xy 181.424603 -112.575303) (xy 181.428761 -112.522985)
			(xy 181.441131 -112.471981) (xy 181.461402 -112.423572) (xy 181.489066 -112.378972) (xy 181.523428 -112.339303)
			(xy 181.563624 -112.305559) (xy 181.608647 -112.278589) (xy 181.657364 -112.259069) (xy 181.708553 -112.24749)
			(xy 181.734714 -112.245394) (xy 181.744283 -112.244371) (xy 181.761669 -112.236158) (xy 181.774799 -112.222111)
			(xy 181.78182 -112.20421) (xy 181.782212 -112.194594) (xy 181.782212 -112.15624) (xy 181.781797 -112.146635)
			(xy 181.774736 -112.128767) (xy 181.761619 -112.11473) (xy 181.744271 -112.106475) (xy 181.734714 -112.10544)
			(xy 181.708562 -112.103265) (xy 181.65738 -112.091687) (xy 181.608669 -112.072171) (xy 181.563653 -112.045205)
			(xy 181.523462 -112.011466) (xy 181.489104 -111.971802) (xy 181.461444 -111.927209) (xy 181.441175 -111.878806)
			(xy 181.428807 -111.82781) (xy 181.424649 -111.7755) (xy 181.428807 -111.723189) (xy 181.441175 -111.672193)
			(xy 181.461444 -111.62379) (xy 181.489105 -111.579197) (xy 181.523462 -111.539534) (xy 181.563654 -111.505795)
			(xy 181.60867 -111.478829) (xy 181.657381 -111.459312) (xy 181.708563 -111.447735) (xy 181.734714 -111.445548)
			(xy 181.744287 -111.444526) (xy 181.761683 -111.436316) (xy 181.774826 -111.42227) (xy 181.781865 -111.404367)
			(xy 181.782212 -111.394748) (xy 181.782212 -111.35614) (xy 181.781797 -111.346535) (xy 181.774736 -111.328667)
			(xy 181.761619 -111.31463) (xy 181.744271 -111.306375) (xy 181.734714 -111.30534) (xy 181.709868 -111.303293)
			(xy 181.661161 -111.292672) (xy 181.614599 -111.274863) (xy 181.571236 -111.250269) (xy 181.532054 -111.219447)
			(xy 181.497941 -111.183096) (xy 181.469667 -111.142037) (xy 181.447875 -111.097201) (xy 181.433056 -111.049603)
			(xy 181.425548 -111.00032) (xy 181.425088 -110.975394) (xy 181.425509 -110.951763) (xy 181.432232 -110.904981)
			(xy 181.445541 -110.859631) (xy 181.465165 -110.816636) (xy 181.490705 -110.776869) (xy 181.50586 -110.758732)
			(xy 181.515479 -110.746854) (xy 181.527787 -110.718892) (xy 181.531294 -110.688543) (xy 181.525687 -110.658511)
			(xy 181.511467 -110.631471) (xy 181.501034 -110.620302) (xy 181.36108 -110.480348) (xy 181.083712 -110.480348)
			(xy 181.074822 -110.48365) (xy 181.046132 -110.49401) (xy 180.98619 -110.505265) (xy 180.955696 -110.506002)
			(xy 180.925195 -110.505329) (xy 180.865239 -110.494084) (xy 180.83657 -110.48365) (xy 180.82768 -110.480348)
			(xy 180.283612 -110.480348) (xy 180.274722 -110.48365) (xy 180.246032 -110.49401) (xy 180.18609 -110.505265)
			(xy 180.155596 -110.506002) (xy 180.125095 -110.505329) (xy 180.065139 -110.494084) (xy 180.03647 -110.48365)
			(xy 180.02758 -110.480348) (xy 179.483766 -110.480348) (xy 179.474876 -110.48365) (xy 179.446186 -110.494006)
			(xy 179.386243 -110.505253) (xy 179.35575 -110.506002) (xy 179.32525 -110.505325) (xy 179.265296 -110.494072)
			(xy 179.236624 -110.48365) (xy 179.227734 -110.480348) (xy 177.883566 -110.480348) (xy 177.874676 -110.48365)
			(xy 177.845986 -110.494006) (xy 177.786043 -110.505253) (xy 177.75555 -110.506002) (xy 177.72505 -110.505325)
			(xy 177.665096 -110.494072) (xy 177.636424 -110.48365) (xy 177.627534 -110.480348) (xy 177.08372 -110.480348)
			(xy 177.07483 -110.48365) (xy 177.04614 -110.494011) (xy 176.986198 -110.505267) (xy 176.955704 -110.506002)
			(xy 176.925203 -110.50533) (xy 176.865246 -110.494086) (xy 176.836578 -110.48365) (xy 176.827688 -110.480348)
			(xy 176.28362 -110.480348) (xy 176.27473 -110.48365) (xy 176.24604 -110.494011) (xy 176.186098 -110.505267)
			(xy 176.155604 -110.506002) (xy 176.125103 -110.50533) (xy 176.065146 -110.494086) (xy 176.036478 -110.48365)
			(xy 176.027588 -110.480348) (xy 175.90008 -110.480348) (xy 175.612806 -110.767622) (xy 175.630028 -110.789837)
			(xy 175.657449 -110.838901) (xy 175.67618 -110.891894) (xy 175.685683 -110.947291) (xy 175.686212 -110.975394)
			(xy 175.685749 -111.000554) (xy 175.685622 -111.001381) (xy 175.825406 -111.001381) (xy 175.825406 -110.949407)
			(xy 175.833536 -110.898072) (xy 175.849597 -110.848642) (xy 175.873193 -110.802332) (xy 175.903743 -110.760284)
			(xy 175.940494 -110.723533) (xy 175.982542 -110.692983) (xy 176.028852 -110.669387) (xy 176.078282 -110.653326)
			(xy 176.129617 -110.645196) (xy 176.181591 -110.645196) (xy 176.232926 -110.653326) (xy 176.282356 -110.669387)
			(xy 176.328666 -110.692983) (xy 176.370714 -110.723533) (xy 176.407465 -110.760284) (xy 176.438015 -110.802332)
			(xy 176.461611 -110.848642) (xy 176.477672 -110.898072) (xy 176.485802 -110.949407) (xy 176.486312 -110.975394)
			(xy 176.485802 -111.001381) (xy 176.625506 -111.001381) (xy 176.625506 -110.949407) (xy 176.633636 -110.898072)
			(xy 176.649697 -110.848642) (xy 176.673293 -110.802332) (xy 176.703843 -110.760284) (xy 176.740594 -110.723533)
			(xy 176.782642 -110.692983) (xy 176.828952 -110.669387) (xy 176.878382 -110.653326) (xy 176.929717 -110.645196)
			(xy 176.981691 -110.645196) (xy 177.033026 -110.653326) (xy 177.082456 -110.669387) (xy 177.128766 -110.692983)
			(xy 177.170814 -110.723533) (xy 177.207565 -110.760284) (xy 177.238115 -110.802332) (xy 177.261711 -110.848642)
			(xy 177.277772 -110.898072) (xy 177.285902 -110.949407) (xy 177.286412 -110.975394) (xy 177.285902 -111.001381)
			(xy 177.425352 -111.001381) (xy 177.425352 -110.949407) (xy 177.433482 -110.898072) (xy 177.449543 -110.848642)
			(xy 177.473139 -110.802332) (xy 177.503689 -110.760284) (xy 177.54044 -110.723533) (xy 177.582488 -110.692983)
			(xy 177.628798 -110.669387) (xy 177.678228 -110.653326) (xy 177.729563 -110.645196) (xy 177.781537 -110.645196)
			(xy 177.832872 -110.653326) (xy 177.882302 -110.669387) (xy 177.928612 -110.692983) (xy 177.97066 -110.723533)
			(xy 178.007411 -110.760284) (xy 178.037961 -110.802332) (xy 178.061557 -110.848642) (xy 178.077618 -110.898072)
			(xy 178.085748 -110.949407) (xy 178.086258 -110.975394) (xy 178.085748 -111.001381) (xy 179.025552 -111.001381)
			(xy 179.025552 -110.949407) (xy 179.033682 -110.898072) (xy 179.049743 -110.848642) (xy 179.073339 -110.802332)
			(xy 179.103889 -110.760284) (xy 179.14064 -110.723533) (xy 179.182688 -110.692983) (xy 179.228998 -110.669387)
			(xy 179.278428 -110.653326) (xy 179.329763 -110.645196) (xy 179.381737 -110.645196) (xy 179.433072 -110.653326)
			(xy 179.482502 -110.669387) (xy 179.528812 -110.692983) (xy 179.57086 -110.723533) (xy 179.607611 -110.760284)
			(xy 179.638161 -110.802332) (xy 179.661757 -110.848642) (xy 179.677818 -110.898072) (xy 179.685948 -110.949407)
			(xy 179.686458 -110.975394) (xy 179.685948 -111.001381) (xy 179.825398 -111.001381) (xy 179.825398 -110.949407)
			(xy 179.833528 -110.898072) (xy 179.849589 -110.848642) (xy 179.873185 -110.802332) (xy 179.903735 -110.760284)
			(xy 179.940486 -110.723533) (xy 179.982534 -110.692983) (xy 180.028844 -110.669387) (xy 180.078274 -110.653326)
			(xy 180.129609 -110.645196) (xy 180.181583 -110.645196) (xy 180.232918 -110.653326) (xy 180.282348 -110.669387)
			(xy 180.328658 -110.692983) (xy 180.370706 -110.723533) (xy 180.407457 -110.760284) (xy 180.438007 -110.802332)
			(xy 180.461603 -110.848642) (xy 180.477664 -110.898072) (xy 180.485794 -110.949407) (xy 180.486304 -110.975394)
			(xy 180.485794 -111.001381) (xy 180.625498 -111.001381) (xy 180.625498 -110.949407) (xy 180.633628 -110.898072)
			(xy 180.649689 -110.848642) (xy 180.673285 -110.802332) (xy 180.703835 -110.760284) (xy 180.740586 -110.723533)
			(xy 180.782634 -110.692983) (xy 180.828944 -110.669387) (xy 180.878374 -110.653326) (xy 180.929709 -110.645196)
			(xy 180.981683 -110.645196) (xy 181.033018 -110.653326) (xy 181.082448 -110.669387) (xy 181.128758 -110.692983)
			(xy 181.170806 -110.723533) (xy 181.207557 -110.760284) (xy 181.238107 -110.802332) (xy 181.261703 -110.848642)
			(xy 181.277764 -110.898072) (xy 181.285894 -110.949407) (xy 181.286404 -110.975394) (xy 181.285894 -111.001381)
			(xy 181.277764 -111.052716) (xy 181.261703 -111.102146) (xy 181.238107 -111.148456) (xy 181.207557 -111.190504)
			(xy 181.170806 -111.227255) (xy 181.128758 -111.257805) (xy 181.082448 -111.281401) (xy 181.033018 -111.297462)
			(xy 180.981683 -111.305592) (xy 180.929709 -111.305592) (xy 180.878374 -111.297462) (xy 180.828944 -111.281401)
			(xy 180.782634 -111.257805) (xy 180.740586 -111.227255) (xy 180.703835 -111.190504) (xy 180.673285 -111.148456)
			(xy 180.649689 -111.102146) (xy 180.633628 -111.052716) (xy 180.625498 -111.001381) (xy 180.485794 -111.001381)
			(xy 180.477664 -111.052716) (xy 180.461603 -111.102146) (xy 180.438007 -111.148456) (xy 180.407457 -111.190504)
			(xy 180.370706 -111.227255) (xy 180.328658 -111.257805) (xy 180.282348 -111.281401) (xy 180.232918 -111.297462)
			(xy 180.181583 -111.305592) (xy 180.129609 -111.305592) (xy 180.078274 -111.297462) (xy 180.028844 -111.281401)
			(xy 179.982534 -111.257805) (xy 179.940486 -111.227255) (xy 179.903735 -111.190504) (xy 179.873185 -111.148456)
			(xy 179.849589 -111.102146) (xy 179.833528 -111.052716) (xy 179.825398 -111.001381) (xy 179.685948 -111.001381)
			(xy 179.677818 -111.052716) (xy 179.661757 -111.102146) (xy 179.638161 -111.148456) (xy 179.607611 -111.190504)
			(xy 179.57086 -111.227255) (xy 179.528812 -111.257805) (xy 179.482502 -111.281401) (xy 179.433072 -111.297462)
			(xy 179.381737 -111.305592) (xy 179.329763 -111.305592) (xy 179.278428 -111.297462) (xy 179.228998 -111.281401)
			(xy 179.182688 -111.257805) (xy 179.14064 -111.227255) (xy 179.103889 -111.190504) (xy 179.073339 -111.148456)
			(xy 179.049743 -111.102146) (xy 179.033682 -111.052716) (xy 179.025552 -111.001381) (xy 178.085748 -111.001381)
			(xy 178.077618 -111.052716) (xy 178.061557 -111.102146) (xy 178.037961 -111.148456) (xy 178.007411 -111.190504)
			(xy 177.97066 -111.227255) (xy 177.928612 -111.257805) (xy 177.882302 -111.281401) (xy 177.832872 -111.297462)
			(xy 177.781537 -111.305592) (xy 177.729563 -111.305592) (xy 177.678228 -111.297462) (xy 177.628798 -111.281401)
			(xy 177.582488 -111.257805) (xy 177.54044 -111.227255) (xy 177.503689 -111.190504) (xy 177.473139 -111.148456)
			(xy 177.449543 -111.102146) (xy 177.433482 -111.052716) (xy 177.425352 -111.001381) (xy 177.285902 -111.001381)
			(xy 177.277772 -111.052716) (xy 177.261711 -111.102146) (xy 177.238115 -111.148456) (xy 177.207565 -111.190504)
			(xy 177.170814 -111.227255) (xy 177.128766 -111.257805) (xy 177.082456 -111.281401) (xy 177.033026 -111.297462)
			(xy 176.981691 -111.305592) (xy 176.929717 -111.305592) (xy 176.878382 -111.297462) (xy 176.828952 -111.281401)
			(xy 176.782642 -111.257805) (xy 176.740594 -111.227255) (xy 176.703843 -111.190504) (xy 176.673293 -111.148456)
			(xy 176.649697 -111.102146) (xy 176.633636 -111.052716) (xy 176.625506 -111.001381) (xy 176.485802 -111.001381)
			(xy 176.477672 -111.052716) (xy 176.461611 -111.102146) (xy 176.438015 -111.148456) (xy 176.407465 -111.190504)
			(xy 176.370714 -111.227255) (xy 176.328666 -111.257805) (xy 176.282356 -111.281401) (xy 176.232926 -111.297462)
			(xy 176.181591 -111.305592) (xy 176.129617 -111.305592) (xy 176.078282 -111.297462) (xy 176.028852 -111.281401)
			(xy 175.982542 -111.257805) (xy 175.940494 -111.227255) (xy 175.903743 -111.190504) (xy 175.873193 -111.148456)
			(xy 175.849597 -111.102146) (xy 175.833536 -111.052716) (xy 175.825406 -111.001381) (xy 175.685622 -111.001381)
			(xy 175.678137 -111.050296) (xy 175.663073 -111.098309) (xy 175.640905 -111.143483) (xy 175.612145 -111.184775)
			(xy 175.577458 -111.221231) (xy 175.537646 -111.252006) (xy 175.493628 -111.276392) (xy 175.446423 -111.293823)
			(xy 175.397121 -111.303897) (xy 175.372014 -111.305594) (xy 175.362368 -111.30653) (xy 175.34479 -111.314653)
			(xy 175.331478 -111.328715) (xy 175.32433 -111.346711) (xy 175.324008 -111.356394) (xy 175.324008 -111.394494)
			(xy 175.324443 -111.40415) (xy 175.331605 -111.422087) (xy 175.344883 -111.436113) (xy 175.362401 -111.444247)
			(xy 175.372014 -111.445294) (xy 175.397113 -111.44702) (xy 175.446396 -111.457116) (xy 175.493581 -111.474561)
			(xy 175.537579 -111.498953) (xy 175.577373 -111.52973) (xy 175.612046 -111.56618) (xy 175.640796 -111.607462)
			(xy 175.66296 -111.652623) (xy 175.678027 -111.70062) (xy 175.685648 -111.750346) (xy 175.685648 -111.800653)
			(xy 175.685521 -111.801481) (xy 175.825406 -111.801481) (xy 175.825406 -111.749507) (xy 175.833536 -111.698172)
			(xy 175.849597 -111.648742) (xy 175.873193 -111.602432) (xy 175.903743 -111.560384) (xy 175.940494 -111.523633)
			(xy 175.982542 -111.493083) (xy 176.028852 -111.469487) (xy 176.078282 -111.453426) (xy 176.129617 -111.445296)
			(xy 176.181591 -111.445296) (xy 176.232926 -111.453426) (xy 176.282356 -111.469487) (xy 176.328666 -111.493083)
			(xy 176.370714 -111.523633) (xy 176.407465 -111.560384) (xy 176.438015 -111.602432) (xy 176.461611 -111.648742)
			(xy 176.477672 -111.698172) (xy 176.485802 -111.749507) (xy 176.486312 -111.775494) (xy 176.485802 -111.801481)
			(xy 177.425352 -111.801481) (xy 177.425352 -111.749507) (xy 177.433482 -111.698172) (xy 177.449543 -111.648742)
			(xy 177.473139 -111.602432) (xy 177.503689 -111.560384) (xy 177.54044 -111.523633) (xy 177.582488 -111.493083)
			(xy 177.628798 -111.469487) (xy 177.678228 -111.453426) (xy 177.729563 -111.445296) (xy 177.781537 -111.445296)
			(xy 177.832872 -111.453426) (xy 177.882302 -111.469487) (xy 177.928612 -111.493083) (xy 177.97066 -111.523633)
			(xy 178.007411 -111.560384) (xy 178.037961 -111.602432) (xy 178.061557 -111.648742) (xy 178.077618 -111.698172)
			(xy 178.085748 -111.749507) (xy 178.086258 -111.775494) (xy 178.085748 -111.801481) (xy 179.025552 -111.801481)
			(xy 179.025552 -111.749507) (xy 179.033682 -111.698172) (xy 179.049743 -111.648742) (xy 179.073339 -111.602432)
			(xy 179.103889 -111.560384) (xy 179.14064 -111.523633) (xy 179.182688 -111.493083) (xy 179.228998 -111.469487)
			(xy 179.278428 -111.453426) (xy 179.329763 -111.445296) (xy 179.381737 -111.445296) (xy 179.433072 -111.453426)
			(xy 179.482502 -111.469487) (xy 179.528812 -111.493083) (xy 179.57086 -111.523633) (xy 179.607611 -111.560384)
			(xy 179.638161 -111.602432) (xy 179.661757 -111.648742) (xy 179.677818 -111.698172) (xy 179.685948 -111.749507)
			(xy 179.686458 -111.775494) (xy 179.685948 -111.801481) (xy 180.625498 -111.801481) (xy 180.625498 -111.749507)
			(xy 180.633628 -111.698172) (xy 180.649689 -111.648742) (xy 180.673285 -111.602432) (xy 180.703835 -111.560384)
			(xy 180.740586 -111.523633) (xy 180.782634 -111.493083) (xy 180.828944 -111.469487) (xy 180.878374 -111.453426)
			(xy 180.929709 -111.445296) (xy 180.981683 -111.445296) (xy 181.033018 -111.453426) (xy 181.082448 -111.469487)
			(xy 181.128758 -111.493083) (xy 181.170806 -111.523633) (xy 181.207557 -111.560384) (xy 181.238107 -111.602432)
			(xy 181.261703 -111.648742) (xy 181.277764 -111.698172) (xy 181.285894 -111.749507) (xy 181.286404 -111.775494)
			(xy 181.285894 -111.801481) (xy 181.277764 -111.852816) (xy 181.261703 -111.902246) (xy 181.238107 -111.948556)
			(xy 181.207557 -111.990604) (xy 181.170806 -112.027355) (xy 181.128758 -112.057905) (xy 181.082448 -112.081501)
			(xy 181.033018 -112.097562) (xy 180.981683 -112.105692) (xy 180.929709 -112.105692) (xy 180.878374 -112.097562)
			(xy 180.828944 -112.081501) (xy 180.782634 -112.057905) (xy 180.740586 -112.027355) (xy 180.703835 -111.990604)
			(xy 180.673285 -111.948556) (xy 180.649689 -111.902246) (xy 180.633628 -111.852816) (xy 180.625498 -111.801481)
			(xy 179.685948 -111.801481) (xy 179.677818 -111.852816) (xy 179.661757 -111.902246) (xy 179.638161 -111.948556)
			(xy 179.607611 -111.990604) (xy 179.57086 -112.027355) (xy 179.528812 -112.057905) (xy 179.482502 -112.081501)
			(xy 179.433072 -112.097562) (xy 179.381737 -112.105692) (xy 179.329763 -112.105692) (xy 179.278428 -112.097562)
			(xy 179.228998 -112.081501) (xy 179.182688 -112.057905) (xy 179.14064 -112.027355) (xy 179.103889 -111.990604)
			(xy 179.073339 -111.948556) (xy 179.049743 -111.902246) (xy 179.033682 -111.852816) (xy 179.025552 -111.801481)
			(xy 178.085748 -111.801481) (xy 178.077618 -111.852816) (xy 178.061557 -111.902246) (xy 178.037961 -111.948556)
			(xy 178.007411 -111.990604) (xy 177.97066 -112.027355) (xy 177.928612 -112.057905) (xy 177.882302 -112.081501)
			(xy 177.832872 -112.097562) (xy 177.781537 -112.105692) (xy 177.729563 -112.105692) (xy 177.678228 -112.097562)
			(xy 177.628798 -112.081501) (xy 177.582488 -112.057905) (xy 177.54044 -112.027355) (xy 177.503689 -111.990604)
			(xy 177.473139 -111.948556) (xy 177.449543 -111.902246) (xy 177.433482 -111.852816) (xy 177.425352 -111.801481)
			(xy 176.485802 -111.801481) (xy 176.477672 -111.852816) (xy 176.461611 -111.902246) (xy 176.438015 -111.948556)
			(xy 176.407465 -111.990604) (xy 176.370714 -112.027355) (xy 176.328666 -112.057905) (xy 176.282356 -112.081501)
			(xy 176.232926 -112.097562) (xy 176.181591 -112.105692) (xy 176.129617 -112.105692) (xy 176.078282 -112.097562)
			(xy 176.028852 -112.081501) (xy 175.982542 -112.057905) (xy 175.940494 -112.027355) (xy 175.903743 -111.990604)
			(xy 175.873193 -111.948556) (xy 175.849597 -111.902246) (xy 175.833536 -111.852816) (xy 175.825406 -111.801481)
			(xy 175.685521 -111.801481) (xy 175.678027 -111.850379) (xy 175.66296 -111.898377) (xy 175.640796 -111.943538)
			(xy 175.612046 -111.98482) (xy 175.577373 -112.02127) (xy 175.537579 -112.052046) (xy 175.493582 -112.076439)
			(xy 175.446397 -112.093884) (xy 175.397113 -112.10398) (xy 175.372014 -112.105694) (xy 175.362368 -112.10663)
			(xy 175.34479 -112.114753) (xy 175.331478 -112.128815) (xy 175.32433 -112.146811) (xy 175.324008 -112.156494)
			(xy 175.324008 -112.19434) (xy 175.324434 -112.204003) (xy 175.331587 -112.221957) (xy 175.344865 -112.236)
			(xy 175.362392 -112.244145) (xy 175.372014 -112.24514) (xy 175.397109 -112.246866) (xy 175.446386 -112.25696)
			(xy 175.493564 -112.274404) (xy 175.537555 -112.298793) (xy 175.577344 -112.329565) (xy 175.612011 -112.36601)
			(xy 175.640757 -112.407287) (xy 175.662918 -112.452442) (xy 175.677983 -112.500433) (xy 175.685603 -112.550152)
			(xy 175.685602 -112.600452) (xy 175.685468 -112.601327) (xy 175.825406 -112.601327) (xy 175.825406 -112.549353)
			(xy 175.833536 -112.498018) (xy 175.849597 -112.448588) (xy 175.873193 -112.402278) (xy 175.903743 -112.36023)
			(xy 175.940494 -112.323479) (xy 175.982542 -112.292929) (xy 176.028852 -112.269333) (xy 176.078282 -112.253272)
			(xy 176.129617 -112.245142) (xy 176.181591 -112.245142) (xy 176.232926 -112.253272) (xy 176.282356 -112.269333)
			(xy 176.328666 -112.292929) (xy 176.370714 -112.323479) (xy 176.407465 -112.36023) (xy 176.438015 -112.402278)
			(xy 176.461611 -112.448588) (xy 176.477672 -112.498018) (xy 176.485802 -112.549353) (xy 176.486312 -112.57534)
			(xy 176.485802 -112.601327) (xy 180.625498 -112.601327) (xy 180.625498 -112.549353) (xy 180.633628 -112.498018)
			(xy 180.649689 -112.448588) (xy 180.673285 -112.402278) (xy 180.703835 -112.36023) (xy 180.740586 -112.323479)
			(xy 180.782634 -112.292929) (xy 180.828944 -112.269333) (xy 180.878374 -112.253272) (xy 180.929709 -112.245142)
			(xy 180.981683 -112.245142) (xy 181.033018 -112.253272) (xy 181.082448 -112.269333) (xy 181.128758 -112.292929)
			(xy 181.170806 -112.323479) (xy 181.207557 -112.36023) (xy 181.238107 -112.402278) (xy 181.261703 -112.448588)
			(xy 181.277764 -112.498018) (xy 181.285894 -112.549353) (xy 181.286404 -112.57534) (xy 181.285894 -112.601327)
			(xy 181.277764 -112.652662) (xy 181.261703 -112.702092) (xy 181.238107 -112.748402) (xy 181.207557 -112.79045)
			(xy 181.170806 -112.827201) (xy 181.128758 -112.857751) (xy 181.082448 -112.881347) (xy 181.033018 -112.897408)
			(xy 180.981683 -112.905538) (xy 180.929709 -112.905538) (xy 180.878374 -112.897408) (xy 180.828944 -112.881347)
			(xy 180.782634 -112.857751) (xy 180.740586 -112.827201) (xy 180.703835 -112.79045) (xy 180.673285 -112.748402)
			(xy 180.649689 -112.702092) (xy 180.633628 -112.652662) (xy 180.625498 -112.601327) (xy 176.485802 -112.601327)
			(xy 176.477672 -112.652662) (xy 176.461611 -112.702092) (xy 176.438015 -112.748402) (xy 176.407465 -112.79045)
			(xy 176.370714 -112.827201) (xy 176.328666 -112.857751) (xy 176.282356 -112.881347) (xy 176.232926 -112.897408)
			(xy 176.181591 -112.905538) (xy 176.129617 -112.905538) (xy 176.078282 -112.897408) (xy 176.028852 -112.881347)
			(xy 175.982542 -112.857751) (xy 175.940494 -112.827201) (xy 175.903743 -112.79045) (xy 175.873193 -112.748402)
			(xy 175.849597 -112.702092) (xy 175.833536 -112.652662) (xy 175.825406 -112.601327) (xy 175.685468 -112.601327)
			(xy 175.677982 -112.650171) (xy 175.662917 -112.698162) (xy 175.640755 -112.743317) (xy 175.612009 -112.784593)
			(xy 175.577341 -112.821037) (xy 175.537552 -112.851809) (xy 175.49356 -112.876198) (xy 175.446382 -112.893641)
			(xy 175.397105 -112.903735) (xy 175.372014 -112.90554) (xy 175.362372 -112.906477) (xy 175.344802 -112.914602)
			(xy 175.331501 -112.928665) (xy 175.324368 -112.94666) (xy 175.324008 -112.95634) (xy 175.324008 -113.79454)
			(xy 175.324434 -113.804203) (xy 175.331587 -113.822157) (xy 175.344865 -113.8362) (xy 175.362392 -113.844345)
			(xy 175.372014 -113.84534) (xy 175.397109 -113.847066) (xy 175.446386 -113.85716) (xy 175.493564 -113.874604)
			(xy 175.537555 -113.898993) (xy 175.577344 -113.929765) (xy 175.612011 -113.96621) (xy 175.640757 -114.007487)
			(xy 175.662918 -114.052642) (xy 175.677983 -114.100633) (xy 175.685603 -114.150352) (xy 175.685602 -114.200652)
			(xy 175.685468 -114.201527) (xy 175.825406 -114.201527) (xy 175.825406 -114.149553) (xy 175.833536 -114.098218)
			(xy 175.849597 -114.048788) (xy 175.873193 -114.002478) (xy 175.903743 -113.96043) (xy 175.940494 -113.923679)
			(xy 175.982542 -113.893129) (xy 176.028852 -113.869533) (xy 176.078282 -113.853472) (xy 176.129617 -113.845342)
			(xy 176.181591 -113.845342) (xy 176.232926 -113.853472) (xy 176.282356 -113.869533) (xy 176.328666 -113.893129)
			(xy 176.370714 -113.923679) (xy 176.407465 -113.96043) (xy 176.438015 -114.002478) (xy 176.461611 -114.048788)
			(xy 176.477672 -114.098218) (xy 176.485802 -114.149553) (xy 176.486312 -114.17554) (xy 176.485802 -114.201527)
			(xy 180.625498 -114.201527) (xy 180.625498 -114.149553) (xy 180.633628 -114.098218) (xy 180.649689 -114.048788)
			(xy 180.673285 -114.002478) (xy 180.703835 -113.96043) (xy 180.740586 -113.923679) (xy 180.782634 -113.893129)
			(xy 180.828944 -113.869533) (xy 180.878374 -113.853472) (xy 180.929709 -113.845342) (xy 180.981683 -113.845342)
			(xy 181.033018 -113.853472) (xy 181.082448 -113.869533) (xy 181.128758 -113.893129) (xy 181.170806 -113.923679)
			(xy 181.207557 -113.96043) (xy 181.238107 -114.002478) (xy 181.261703 -114.048788) (xy 181.277764 -114.098218)
			(xy 181.285894 -114.149553) (xy 181.286404 -114.17554) (xy 181.285894 -114.201527) (xy 181.277764 -114.252862)
			(xy 181.261703 -114.302292) (xy 181.238107 -114.348602) (xy 181.207557 -114.39065) (xy 181.170806 -114.427401)
			(xy 181.128758 -114.457951) (xy 181.082448 -114.481547) (xy 181.033018 -114.497608) (xy 180.981683 -114.505738)
			(xy 180.929709 -114.505738) (xy 180.878374 -114.497608) (xy 180.828944 -114.481547) (xy 180.782634 -114.457951)
			(xy 180.740586 -114.427401) (xy 180.703835 -114.39065) (xy 180.673285 -114.348602) (xy 180.649689 -114.302292)
			(xy 180.633628 -114.252862) (xy 180.625498 -114.201527) (xy 176.485802 -114.201527) (xy 176.477672 -114.252862)
			(xy 176.461611 -114.302292) (xy 176.438015 -114.348602) (xy 176.407465 -114.39065) (xy 176.370714 -114.427401)
			(xy 176.328666 -114.457951) (xy 176.282356 -114.481547) (xy 176.232926 -114.497608) (xy 176.181591 -114.505738)
			(xy 176.129617 -114.505738) (xy 176.078282 -114.497608) (xy 176.028852 -114.481547) (xy 175.982542 -114.457951)
			(xy 175.940494 -114.427401) (xy 175.903743 -114.39065) (xy 175.873193 -114.348602) (xy 175.849597 -114.302292)
			(xy 175.833536 -114.252862) (xy 175.825406 -114.201527) (xy 175.685468 -114.201527) (xy 175.677982 -114.250371)
			(xy 175.662917 -114.298362) (xy 175.640755 -114.343517) (xy 175.612009 -114.384793) (xy 175.577341 -114.421237)
			(xy 175.537552 -114.452009) (xy 175.49356 -114.476398) (xy 175.446382 -114.493841) (xy 175.397105 -114.503935)
			(xy 175.372014 -114.50574) (xy 175.362372 -114.506677) (xy 175.344802 -114.514802) (xy 175.331501 -114.528865)
			(xy 175.324368 -114.54686) (xy 175.324008 -114.55654) (xy 175.324008 -114.594386) (xy 175.324441 -114.604043)
			(xy 175.331603 -114.621983) (xy 175.344881 -114.636011) (xy 175.362399 -114.644147) (xy 175.372014 -114.645186)
			(xy 175.397113 -114.646912) (xy 175.446398 -114.657008) (xy 175.493584 -114.674454) (xy 175.537583 -114.698847)
			(xy 175.577378 -114.729624) (xy 175.612051 -114.766074) (xy 175.640803 -114.807357) (xy 175.662967 -114.852519)
			(xy 175.678035 -114.900518) (xy 175.685656 -114.950245) (xy 175.685656 -115.000553) (xy 175.68553 -115.001373)
			(xy 175.825406 -115.001373) (xy 175.825406 -114.949399) (xy 175.833536 -114.898064) (xy 175.849597 -114.848634)
			(xy 175.873193 -114.802324) (xy 175.903743 -114.760276) (xy 175.940494 -114.723525) (xy 175.982542 -114.692975)
			(xy 176.028852 -114.669379) (xy 176.078282 -114.653318) (xy 176.129617 -114.645188) (xy 176.181591 -114.645188)
			(xy 176.232926 -114.653318) (xy 176.282356 -114.669379) (xy 176.328666 -114.692975) (xy 176.370714 -114.723525)
			(xy 176.407465 -114.760276) (xy 176.438015 -114.802324) (xy 176.461611 -114.848634) (xy 176.477672 -114.898064)
			(xy 176.485802 -114.949399) (xy 176.486312 -114.975386) (xy 176.485802 -115.001373) (xy 177.425352 -115.001373)
			(xy 177.425352 -114.949399) (xy 177.433482 -114.898064) (xy 177.449543 -114.848634) (xy 177.473139 -114.802324)
			(xy 177.503689 -114.760276) (xy 177.54044 -114.723525) (xy 177.582488 -114.692975) (xy 177.628798 -114.669379)
			(xy 177.678228 -114.653318) (xy 177.729563 -114.645188) (xy 177.781537 -114.645188) (xy 177.832872 -114.653318)
			(xy 177.882302 -114.669379) (xy 177.928612 -114.692975) (xy 177.97066 -114.723525) (xy 178.007411 -114.760276)
			(xy 178.037961 -114.802324) (xy 178.061557 -114.848634) (xy 178.077618 -114.898064) (xy 178.085748 -114.949399)
			(xy 178.086258 -114.975386) (xy 178.085748 -115.001373) (xy 179.025552 -115.001373) (xy 179.025552 -114.949399)
			(xy 179.033682 -114.898064) (xy 179.049743 -114.848634) (xy 179.073339 -114.802324) (xy 179.103889 -114.760276)
			(xy 179.14064 -114.723525) (xy 179.182688 -114.692975) (xy 179.228998 -114.669379) (xy 179.278428 -114.653318)
			(xy 179.329763 -114.645188) (xy 179.381737 -114.645188) (xy 179.433072 -114.653318) (xy 179.482502 -114.669379)
			(xy 179.528812 -114.692975) (xy 179.57086 -114.723525) (xy 179.607611 -114.760276) (xy 179.638161 -114.802324)
			(xy 179.661757 -114.848634) (xy 179.677818 -114.898064) (xy 179.685948 -114.949399) (xy 179.686458 -114.975386)
			(xy 179.685948 -115.001373) (xy 180.625498 -115.001373) (xy 180.625498 -114.949399) (xy 180.633628 -114.898064)
			(xy 180.649689 -114.848634) (xy 180.673285 -114.802324) (xy 180.703835 -114.760276) (xy 180.740586 -114.723525)
			(xy 180.782634 -114.692975) (xy 180.828944 -114.669379) (xy 180.878374 -114.653318) (xy 180.929709 -114.645188)
			(xy 180.981683 -114.645188) (xy 181.033018 -114.653318) (xy 181.082448 -114.669379) (xy 181.128758 -114.692975)
			(xy 181.170806 -114.723525) (xy 181.207557 -114.760276) (xy 181.238107 -114.802324) (xy 181.261703 -114.848634)
			(xy 181.277764 -114.898064) (xy 181.285894 -114.949399) (xy 181.286404 -114.975386) (xy 181.285894 -115.001373)
			(xy 181.277764 -115.052708) (xy 181.261703 -115.102138) (xy 181.238107 -115.148448) (xy 181.207557 -115.190496)
			(xy 181.170806 -115.227247) (xy 181.128758 -115.257797) (xy 181.082448 -115.281393) (xy 181.033018 -115.297454)
			(xy 180.981683 -115.305584) (xy 180.929709 -115.305584) (xy 180.878374 -115.297454) (xy 180.828944 -115.281393)
			(xy 180.782634 -115.257797) (xy 180.740586 -115.227247) (xy 180.703835 -115.190496) (xy 180.673285 -115.148448)
			(xy 180.649689 -115.102138) (xy 180.633628 -115.052708) (xy 180.625498 -115.001373) (xy 179.685948 -115.001373)
			(xy 179.677818 -115.052708) (xy 179.661757 -115.102138) (xy 179.638161 -115.148448) (xy 179.607611 -115.190496)
			(xy 179.57086 -115.227247) (xy 179.528812 -115.257797) (xy 179.482502 -115.281393) (xy 179.433072 -115.297454)
			(xy 179.381737 -115.305584) (xy 179.329763 -115.305584) (xy 179.278428 -115.297454) (xy 179.228998 -115.281393)
			(xy 179.182688 -115.257797) (xy 179.14064 -115.227247) (xy 179.103889 -115.190496) (xy 179.073339 -115.148448)
			(xy 179.049743 -115.102138) (xy 179.033682 -115.052708) (xy 179.025552 -115.001373) (xy 178.085748 -115.001373)
			(xy 178.077618 -115.052708) (xy 178.061557 -115.102138) (xy 178.037961 -115.148448) (xy 178.007411 -115.190496)
			(xy 177.97066 -115.227247) (xy 177.928612 -115.257797) (xy 177.882302 -115.281393) (xy 177.832872 -115.297454)
			(xy 177.781537 -115.305584) (xy 177.729563 -115.305584) (xy 177.678228 -115.297454) (xy 177.628798 -115.281393)
			(xy 177.582488 -115.257797) (xy 177.54044 -115.227247) (xy 177.503689 -115.190496) (xy 177.473139 -115.148448)
			(xy 177.449543 -115.102138) (xy 177.433482 -115.052708) (xy 177.425352 -115.001373) (xy 176.485802 -115.001373)
			(xy 176.477672 -115.052708) (xy 176.461611 -115.102138) (xy 176.438015 -115.148448) (xy 176.407465 -115.190496)
			(xy 176.370714 -115.227247) (xy 176.328666 -115.257797) (xy 176.282356 -115.281393) (xy 176.232926 -115.297454)
			(xy 176.181591 -115.305584) (xy 176.129617 -115.305584) (xy 176.078282 -115.297454) (xy 176.028852 -115.281393)
			(xy 175.982542 -115.257797) (xy 175.940494 -115.227247) (xy 175.903743 -115.190496) (xy 175.873193 -115.148448)
			(xy 175.849597 -115.102138) (xy 175.833536 -115.052708) (xy 175.825406 -115.001373) (xy 175.68553 -115.001373)
			(xy 175.678035 -115.050281) (xy 175.662968 -115.098279) (xy 175.640803 -115.143442) (xy 175.612052 -115.184725)
			(xy 175.577379 -115.221175) (xy 175.537584 -115.251953) (xy 175.493585 -115.276346) (xy 175.446399 -115.293792)
			(xy 175.397115 -115.303888) (xy 175.372014 -115.305586) (xy 175.362375 -115.306524) (xy 175.344813 -115.31465)
			(xy 175.331524 -115.328716) (xy 175.324406 -115.346709) (xy 175.324008 -115.356386) (xy 175.324008 -115.394486)
			(xy 175.324441 -115.404143) (xy 175.331603 -115.422083) (xy 175.344881 -115.436111) (xy 175.362399 -115.444247)
			(xy 175.372014 -115.445286) (xy 175.397113 -115.447012) (xy 175.446398 -115.457108) (xy 175.493584 -115.474554)
			(xy 175.537583 -115.498947) (xy 175.577378 -115.529724) (xy 175.612051 -115.566174) (xy 175.640803 -115.607457)
			(xy 175.662967 -115.652619) (xy 175.678035 -115.700618) (xy 175.685656 -115.750345) (xy 175.685656 -115.800653)
			(xy 175.68553 -115.801473) (xy 175.825406 -115.801473) (xy 175.825406 -115.749499) (xy 175.833536 -115.698164)
			(xy 175.849597 -115.648734) (xy 175.873193 -115.602424) (xy 175.903743 -115.560376) (xy 175.940494 -115.523625)
			(xy 175.982542 -115.493075) (xy 176.028852 -115.469479) (xy 176.078282 -115.453418) (xy 176.129617 -115.445288)
			(xy 176.181591 -115.445288) (xy 176.232926 -115.453418) (xy 176.282356 -115.469479) (xy 176.328666 -115.493075)
			(xy 176.370714 -115.523625) (xy 176.407465 -115.560376) (xy 176.438015 -115.602424) (xy 176.461611 -115.648734)
			(xy 176.477672 -115.698164) (xy 176.485802 -115.749499) (xy 176.486312 -115.775486) (xy 176.485802 -115.801473)
			(xy 176.625506 -115.801473) (xy 176.625506 -115.749499) (xy 176.633636 -115.698164) (xy 176.649697 -115.648734)
			(xy 176.673293 -115.602424) (xy 176.703843 -115.560376) (xy 176.740594 -115.523625) (xy 176.782642 -115.493075)
			(xy 176.828952 -115.469479) (xy 176.878382 -115.453418) (xy 176.929717 -115.445288) (xy 176.981691 -115.445288)
			(xy 177.033026 -115.453418) (xy 177.082456 -115.469479) (xy 177.128766 -115.493075) (xy 177.170814 -115.523625)
			(xy 177.207565 -115.560376) (xy 177.238115 -115.602424) (xy 177.261711 -115.648734) (xy 177.277772 -115.698164)
			(xy 177.285902 -115.749499) (xy 177.286412 -115.775486) (xy 177.285902 -115.801473) (xy 177.425352 -115.801473)
			(xy 177.425352 -115.749499) (xy 177.433482 -115.698164) (xy 177.449543 -115.648734) (xy 177.473139 -115.602424)
			(xy 177.503689 -115.560376) (xy 177.54044 -115.523625) (xy 177.582488 -115.493075) (xy 177.628798 -115.469479)
			(xy 177.678228 -115.453418) (xy 177.729563 -115.445288) (xy 177.781537 -115.445288) (xy 177.832872 -115.453418)
			(xy 177.882302 -115.469479) (xy 177.928612 -115.493075) (xy 177.97066 -115.523625) (xy 178.007411 -115.560376)
			(xy 178.037961 -115.602424) (xy 178.061557 -115.648734) (xy 178.077618 -115.698164) (xy 178.085748 -115.749499)
			(xy 178.086258 -115.775486) (xy 178.085748 -115.801473) (xy 179.025552 -115.801473) (xy 179.025552 -115.749499)
			(xy 179.033682 -115.698164) (xy 179.049743 -115.648734) (xy 179.073339 -115.602424) (xy 179.103889 -115.560376)
			(xy 179.14064 -115.523625) (xy 179.182688 -115.493075) (xy 179.228998 -115.469479) (xy 179.278428 -115.453418)
			(xy 179.329763 -115.445288) (xy 179.381737 -115.445288) (xy 179.433072 -115.453418) (xy 179.482502 -115.469479)
			(xy 179.528812 -115.493075) (xy 179.57086 -115.523625) (xy 179.607611 -115.560376) (xy 179.638161 -115.602424)
			(xy 179.661757 -115.648734) (xy 179.677818 -115.698164) (xy 179.685948 -115.749499) (xy 179.686458 -115.775486)
			(xy 179.685948 -115.801473) (xy 179.825398 -115.801473) (xy 179.825398 -115.749499) (xy 179.833528 -115.698164)
			(xy 179.849589 -115.648734) (xy 179.873185 -115.602424) (xy 179.903735 -115.560376) (xy 179.940486 -115.523625)
			(xy 179.982534 -115.493075) (xy 180.028844 -115.469479) (xy 180.078274 -115.453418) (xy 180.129609 -115.445288)
			(xy 180.181583 -115.445288) (xy 180.232918 -115.453418) (xy 180.282348 -115.469479) (xy 180.328658 -115.493075)
			(xy 180.370706 -115.523625) (xy 180.407457 -115.560376) (xy 180.438007 -115.602424) (xy 180.461603 -115.648734)
			(xy 180.477664 -115.698164) (xy 180.485794 -115.749499) (xy 180.486304 -115.775486) (xy 180.485794 -115.801473)
			(xy 180.625498 -115.801473) (xy 180.625498 -115.749499) (xy 180.633628 -115.698164) (xy 180.649689 -115.648734)
			(xy 180.673285 -115.602424) (xy 180.703835 -115.560376) (xy 180.740586 -115.523625) (xy 180.782634 -115.493075)
			(xy 180.828944 -115.469479) (xy 180.878374 -115.453418) (xy 180.929709 -115.445288) (xy 180.981683 -115.445288)
			(xy 181.033018 -115.453418) (xy 181.082448 -115.469479) (xy 181.128758 -115.493075) (xy 181.170806 -115.523625)
			(xy 181.207557 -115.560376) (xy 181.238107 -115.602424) (xy 181.261703 -115.648734) (xy 181.277764 -115.698164)
			(xy 181.285894 -115.749499) (xy 181.286404 -115.775486) (xy 181.285894 -115.801473) (xy 181.277764 -115.852808)
			(xy 181.261703 -115.902238) (xy 181.238107 -115.948548) (xy 181.207557 -115.990596) (xy 181.170806 -116.027347)
			(xy 181.128758 -116.057897) (xy 181.082448 -116.081493) (xy 181.033018 -116.097554) (xy 180.981683 -116.105684)
			(xy 180.929709 -116.105684) (xy 180.878374 -116.097554) (xy 180.828944 -116.081493) (xy 180.782634 -116.057897)
			(xy 180.740586 -116.027347) (xy 180.703835 -115.990596) (xy 180.673285 -115.948548) (xy 180.649689 -115.902238)
			(xy 180.633628 -115.852808) (xy 180.625498 -115.801473) (xy 180.485794 -115.801473) (xy 180.477664 -115.852808)
			(xy 180.461603 -115.902238) (xy 180.438007 -115.948548) (xy 180.407457 -115.990596) (xy 180.370706 -116.027347)
			(xy 180.328658 -116.057897) (xy 180.282348 -116.081493) (xy 180.232918 -116.097554) (xy 180.181583 -116.105684)
			(xy 180.129609 -116.105684) (xy 180.078274 -116.097554) (xy 180.028844 -116.081493) (xy 179.982534 -116.057897)
			(xy 179.940486 -116.027347) (xy 179.903735 -115.990596) (xy 179.873185 -115.948548) (xy 179.849589 -115.902238)
			(xy 179.833528 -115.852808) (xy 179.825398 -115.801473) (xy 179.685948 -115.801473) (xy 179.677818 -115.852808)
			(xy 179.661757 -115.902238) (xy 179.638161 -115.948548) (xy 179.607611 -115.990596) (xy 179.57086 -116.027347)
			(xy 179.528812 -116.057897) (xy 179.482502 -116.081493) (xy 179.433072 -116.097554) (xy 179.381737 -116.105684)
			(xy 179.329763 -116.105684) (xy 179.278428 -116.097554) (xy 179.228998 -116.081493) (xy 179.182688 -116.057897)
			(xy 179.14064 -116.027347) (xy 179.103889 -115.990596) (xy 179.073339 -115.948548) (xy 179.049743 -115.902238)
			(xy 179.033682 -115.852808) (xy 179.025552 -115.801473) (xy 178.085748 -115.801473) (xy 178.077618 -115.852808)
			(xy 178.061557 -115.902238) (xy 178.037961 -115.948548) (xy 178.007411 -115.990596) (xy 177.97066 -116.027347)
			(xy 177.928612 -116.057897) (xy 177.882302 -116.081493) (xy 177.832872 -116.097554) (xy 177.781537 -116.105684)
			(xy 177.729563 -116.105684) (xy 177.678228 -116.097554) (xy 177.628798 -116.081493) (xy 177.582488 -116.057897)
			(xy 177.54044 -116.027347) (xy 177.503689 -115.990596) (xy 177.473139 -115.948548) (xy 177.449543 -115.902238)
			(xy 177.433482 -115.852808) (xy 177.425352 -115.801473) (xy 177.285902 -115.801473) (xy 177.277772 -115.852808)
			(xy 177.261711 -115.902238) (xy 177.238115 -115.948548) (xy 177.207565 -115.990596) (xy 177.170814 -116.027347)
			(xy 177.128766 -116.057897) (xy 177.082456 -116.081493) (xy 177.033026 -116.097554) (xy 176.981691 -116.105684)
			(xy 176.929717 -116.105684) (xy 176.878382 -116.097554) (xy 176.828952 -116.081493) (xy 176.782642 -116.057897)
			(xy 176.740594 -116.027347) (xy 176.703843 -115.990596) (xy 176.673293 -115.948548) (xy 176.649697 -115.902238)
			(xy 176.633636 -115.852808) (xy 176.625506 -115.801473) (xy 176.485802 -115.801473) (xy 176.477672 -115.852808)
			(xy 176.461611 -115.902238) (xy 176.438015 -115.948548) (xy 176.407465 -115.990596) (xy 176.370714 -116.027347)
			(xy 176.328666 -116.057897) (xy 176.282356 -116.081493) (xy 176.232926 -116.097554) (xy 176.181591 -116.105684)
			(xy 176.129617 -116.105684) (xy 176.078282 -116.097554) (xy 176.028852 -116.081493) (xy 175.982542 -116.057897)
			(xy 175.940494 -116.027347) (xy 175.903743 -115.990596) (xy 175.873193 -115.948548) (xy 175.849597 -115.902238)
			(xy 175.833536 -115.852808) (xy 175.825406 -115.801473) (xy 175.68553 -115.801473) (xy 175.678035 -115.850381)
			(xy 175.662968 -115.898379) (xy 175.640803 -115.943542) (xy 175.612052 -115.984825) (xy 175.577379 -116.021275)
			(xy 175.537584 -116.052053) (xy 175.493585 -116.076446) (xy 175.446399 -116.093892) (xy 175.397115 -116.103988)
			(xy 175.372014 -116.105686) (xy 175.362375 -116.106624) (xy 175.344813 -116.11475) (xy 175.331524 -116.128816)
			(xy 175.324406 -116.146809) (xy 175.324008 -116.156486) (xy 175.324008 -116.194586) (xy 175.324441 -116.204243)
			(xy 175.331603 -116.222183) (xy 175.344881 -116.236211) (xy 175.362399 -116.244347) (xy 175.372014 -116.245386)
			(xy 175.397113 -116.247112) (xy 175.446398 -116.257208) (xy 175.493584 -116.274654) (xy 175.537583 -116.299047)
			(xy 175.577378 -116.329824) (xy 175.612051 -116.366274) (xy 175.640803 -116.407557) (xy 175.662967 -116.452719)
			(xy 175.678035 -116.500718) (xy 175.685656 -116.550445) (xy 175.685656 -116.600753) (xy 175.68553 -116.601573)
			(xy 175.825406 -116.601573) (xy 175.825406 -116.549599) (xy 175.833536 -116.498264) (xy 175.849597 -116.448834)
			(xy 175.873193 -116.402524) (xy 175.903743 -116.360476) (xy 175.940494 -116.323725) (xy 175.982542 -116.293175)
			(xy 176.028852 -116.269579) (xy 176.078282 -116.253518) (xy 176.129617 -116.245388) (xy 176.181591 -116.245388)
			(xy 176.232926 -116.253518) (xy 176.282356 -116.269579) (xy 176.328666 -116.293175) (xy 176.370714 -116.323725)
			(xy 176.407465 -116.360476) (xy 176.438015 -116.402524) (xy 176.461611 -116.448834) (xy 176.477672 -116.498264)
			(xy 176.485802 -116.549599) (xy 176.486312 -116.575586) (xy 176.485802 -116.601573) (xy 176.625506 -116.601573)
			(xy 176.625506 -116.549599) (xy 176.633636 -116.498264) (xy 176.649697 -116.448834) (xy 176.673293 -116.402524)
			(xy 176.703843 -116.360476) (xy 176.740594 -116.323725) (xy 176.782642 -116.293175) (xy 176.828952 -116.269579)
			(xy 176.878382 -116.253518) (xy 176.929717 -116.245388) (xy 176.981691 -116.245388) (xy 177.033026 -116.253518)
			(xy 177.082456 -116.269579) (xy 177.128766 -116.293175) (xy 177.170814 -116.323725) (xy 177.207565 -116.360476)
			(xy 177.238115 -116.402524) (xy 177.261711 -116.448834) (xy 177.277772 -116.498264) (xy 177.285902 -116.549599)
			(xy 177.286412 -116.575586) (xy 177.285902 -116.601573) (xy 177.425352 -116.601573) (xy 177.425352 -116.549599)
			(xy 177.433482 -116.498264) (xy 177.449543 -116.448834) (xy 177.473139 -116.402524) (xy 177.503689 -116.360476)
			(xy 177.54044 -116.323725) (xy 177.582488 -116.293175) (xy 177.628798 -116.269579) (xy 177.678228 -116.253518)
			(xy 177.729563 -116.245388) (xy 177.781537 -116.245388) (xy 177.832872 -116.253518) (xy 177.882302 -116.269579)
			(xy 177.928612 -116.293175) (xy 177.97066 -116.323725) (xy 178.007411 -116.360476) (xy 178.037961 -116.402524)
			(xy 178.061557 -116.448834) (xy 178.077618 -116.498264) (xy 178.085748 -116.549599) (xy 178.086258 -116.575586)
			(xy 178.085748 -116.601573) (xy 179.025552 -116.601573) (xy 179.025552 -116.549599) (xy 179.033682 -116.498264)
			(xy 179.049743 -116.448834) (xy 179.073339 -116.402524) (xy 179.103889 -116.360476) (xy 179.14064 -116.323725)
			(xy 179.182688 -116.293175) (xy 179.228998 -116.269579) (xy 179.278428 -116.253518) (xy 179.329763 -116.245388)
			(xy 179.381737 -116.245388) (xy 179.433072 -116.253518) (xy 179.482502 -116.269579) (xy 179.528812 -116.293175)
			(xy 179.57086 -116.323725) (xy 179.607611 -116.360476) (xy 179.638161 -116.402524) (xy 179.661757 -116.448834)
			(xy 179.677818 -116.498264) (xy 179.685948 -116.549599) (xy 179.686458 -116.575586) (xy 179.685948 -116.601573)
			(xy 179.825398 -116.601573) (xy 179.825398 -116.549599) (xy 179.833528 -116.498264) (xy 179.849589 -116.448834)
			(xy 179.873185 -116.402524) (xy 179.903735 -116.360476) (xy 179.940486 -116.323725) (xy 179.982534 -116.293175)
			(xy 180.028844 -116.269579) (xy 180.078274 -116.253518) (xy 180.129609 -116.245388) (xy 180.181583 -116.245388)
			(xy 180.232918 -116.253518) (xy 180.282348 -116.269579) (xy 180.328658 -116.293175) (xy 180.370706 -116.323725)
			(xy 180.407457 -116.360476) (xy 180.438007 -116.402524) (xy 180.461603 -116.448834) (xy 180.477664 -116.498264)
			(xy 180.485794 -116.549599) (xy 180.486304 -116.575586) (xy 180.485794 -116.601573) (xy 180.625498 -116.601573)
			(xy 180.625498 -116.549599) (xy 180.633628 -116.498264) (xy 180.649689 -116.448834) (xy 180.673285 -116.402524)
			(xy 180.703835 -116.360476) (xy 180.740586 -116.323725) (xy 180.782634 -116.293175) (xy 180.828944 -116.269579)
			(xy 180.878374 -116.253518) (xy 180.929709 -116.245388) (xy 180.981683 -116.245388) (xy 181.033018 -116.253518)
			(xy 181.082448 -116.269579) (xy 181.128758 -116.293175) (xy 181.170806 -116.323725) (xy 181.207557 -116.360476)
			(xy 181.238107 -116.402524) (xy 181.261703 -116.448834) (xy 181.277764 -116.498264) (xy 181.285894 -116.549599)
			(xy 181.286404 -116.575586) (xy 181.285894 -116.601573) (xy 181.277764 -116.652908) (xy 181.261703 -116.702338)
			(xy 181.238107 -116.748648) (xy 181.207557 -116.790696) (xy 181.170806 -116.827447) (xy 181.128758 -116.857997)
			(xy 181.082448 -116.881593) (xy 181.033018 -116.897654) (xy 180.981683 -116.905784) (xy 180.929709 -116.905784)
			(xy 180.878374 -116.897654) (xy 180.828944 -116.881593) (xy 180.782634 -116.857997) (xy 180.740586 -116.827447)
			(xy 180.703835 -116.790696) (xy 180.673285 -116.748648) (xy 180.649689 -116.702338) (xy 180.633628 -116.652908)
			(xy 180.625498 -116.601573) (xy 180.485794 -116.601573) (xy 180.477664 -116.652908) (xy 180.461603 -116.702338)
			(xy 180.438007 -116.748648) (xy 180.407457 -116.790696) (xy 180.370706 -116.827447) (xy 180.328658 -116.857997)
			(xy 180.282348 -116.881593) (xy 180.232918 -116.897654) (xy 180.181583 -116.905784) (xy 180.129609 -116.905784)
			(xy 180.078274 -116.897654) (xy 180.028844 -116.881593) (xy 179.982534 -116.857997) (xy 179.940486 -116.827447)
			(xy 179.903735 -116.790696) (xy 179.873185 -116.748648) (xy 179.849589 -116.702338) (xy 179.833528 -116.652908)
			(xy 179.825398 -116.601573) (xy 179.685948 -116.601573) (xy 179.677818 -116.652908) (xy 179.661757 -116.702338)
			(xy 179.638161 -116.748648) (xy 179.607611 -116.790696) (xy 179.57086 -116.827447) (xy 179.528812 -116.857997)
			(xy 179.482502 -116.881593) (xy 179.433072 -116.897654) (xy 179.381737 -116.905784) (xy 179.329763 -116.905784)
			(xy 179.278428 -116.897654) (xy 179.228998 -116.881593) (xy 179.182688 -116.857997) (xy 179.14064 -116.827447)
			(xy 179.103889 -116.790696) (xy 179.073339 -116.748648) (xy 179.049743 -116.702338) (xy 179.033682 -116.652908)
			(xy 179.025552 -116.601573) (xy 178.085748 -116.601573) (xy 178.077618 -116.652908) (xy 178.061557 -116.702338)
			(xy 178.037961 -116.748648) (xy 178.007411 -116.790696) (xy 177.97066 -116.827447) (xy 177.928612 -116.857997)
			(xy 177.882302 -116.881593) (xy 177.832872 -116.897654) (xy 177.781537 -116.905784) (xy 177.729563 -116.905784)
			(xy 177.678228 -116.897654) (xy 177.628798 -116.881593) (xy 177.582488 -116.857997) (xy 177.54044 -116.827447)
			(xy 177.503689 -116.790696) (xy 177.473139 -116.748648) (xy 177.449543 -116.702338) (xy 177.433482 -116.652908)
			(xy 177.425352 -116.601573) (xy 177.285902 -116.601573) (xy 177.277772 -116.652908) (xy 177.261711 -116.702338)
			(xy 177.238115 -116.748648) (xy 177.207565 -116.790696) (xy 177.170814 -116.827447) (xy 177.128766 -116.857997)
			(xy 177.082456 -116.881593) (xy 177.033026 -116.897654) (xy 176.981691 -116.905784) (xy 176.929717 -116.905784)
			(xy 176.878382 -116.897654) (xy 176.828952 -116.881593) (xy 176.782642 -116.857997) (xy 176.740594 -116.827447)
			(xy 176.703843 -116.790696) (xy 176.673293 -116.748648) (xy 176.649697 -116.702338) (xy 176.633636 -116.652908)
			(xy 176.625506 -116.601573) (xy 176.485802 -116.601573) (xy 176.477672 -116.652908) (xy 176.461611 -116.702338)
			(xy 176.438015 -116.748648) (xy 176.407465 -116.790696) (xy 176.370714 -116.827447) (xy 176.328666 -116.857997)
			(xy 176.282356 -116.881593) (xy 176.232926 -116.897654) (xy 176.181591 -116.905784) (xy 176.129617 -116.905784)
			(xy 176.078282 -116.897654) (xy 176.028852 -116.881593) (xy 175.982542 -116.857997) (xy 175.940494 -116.827447)
			(xy 175.903743 -116.790696) (xy 175.873193 -116.748648) (xy 175.849597 -116.702338) (xy 175.833536 -116.652908)
			(xy 175.825406 -116.601573) (xy 175.68553 -116.601573) (xy 175.678035 -116.650481) (xy 175.662968 -116.698479)
			(xy 175.640803 -116.743642) (xy 175.612052 -116.784925) (xy 175.577379 -116.821375) (xy 175.537584 -116.852153)
			(xy 175.493585 -116.876546) (xy 175.446399 -116.893992) (xy 175.397115 -116.904088) (xy 175.372014 -116.905786)
			(xy 175.362375 -116.906724) (xy 175.344813 -116.91485) (xy 175.331524 -116.928916) (xy 175.324406 -116.946909)
			(xy 175.324008 -116.956586) (xy 175.324008 -116.994432) (xy 175.324432 -117.004096) (xy 175.331584 -117.022053)
			(xy 175.344862 -117.036098) (xy 175.36239 -117.044245) (xy 175.372014 -117.045232) (xy 175.39711 -117.046958)
			(xy 175.446387 -117.057053) (xy 175.493567 -117.074496) (xy 175.537559 -117.098886) (xy 175.577349 -117.129659)
			(xy 175.612017 -117.166105) (xy 175.640764 -117.207382) (xy 175.662926 -117.252538) (xy 175.67799 -117.300531)
			(xy 175.685611 -117.350251) (xy 175.68561 -117.400552) (xy 175.685477 -117.401419) (xy 175.825406 -117.401419)
			(xy 175.825406 -117.349445) (xy 175.833536 -117.29811) (xy 175.849597 -117.24868) (xy 175.873193 -117.20237)
			(xy 175.903743 -117.160322) (xy 175.940494 -117.123571) (xy 175.982542 -117.093021) (xy 176.028852 -117.069425)
			(xy 176.078282 -117.053364) (xy 176.129617 -117.045234) (xy 176.181591 -117.045234) (xy 176.232926 -117.053364)
			(xy 176.282356 -117.069425) (xy 176.328666 -117.093021) (xy 176.370714 -117.123571) (xy 176.407465 -117.160322)
			(xy 176.438015 -117.20237) (xy 176.461611 -117.24868) (xy 176.477672 -117.29811) (xy 176.485802 -117.349445)
			(xy 176.486312 -117.375432) (xy 176.485802 -117.401419) (xy 176.625506 -117.401419) (xy 176.625506 -117.349445)
			(xy 176.633636 -117.29811) (xy 176.649697 -117.24868) (xy 176.673293 -117.20237) (xy 176.703843 -117.160322)
			(xy 176.740594 -117.123571) (xy 176.782642 -117.093021) (xy 176.828952 -117.069425) (xy 176.878382 -117.053364)
			(xy 176.929717 -117.045234) (xy 176.981691 -117.045234) (xy 177.033026 -117.053364) (xy 177.082456 -117.069425)
			(xy 177.128766 -117.093021) (xy 177.170814 -117.123571) (xy 177.207565 -117.160322) (xy 177.238115 -117.20237)
			(xy 177.261711 -117.24868) (xy 177.277772 -117.29811) (xy 177.285902 -117.349445) (xy 177.286412 -117.375432)
			(xy 177.285902 -117.401419) (xy 177.425352 -117.401419) (xy 177.425352 -117.349445) (xy 177.433482 -117.29811)
			(xy 177.449543 -117.24868) (xy 177.473139 -117.20237) (xy 177.503689 -117.160322) (xy 177.54044 -117.123571)
			(xy 177.582488 -117.093021) (xy 177.628798 -117.069425) (xy 177.678228 -117.053364) (xy 177.729563 -117.045234)
			(xy 177.781537 -117.045234) (xy 177.832872 -117.053364) (xy 177.882302 -117.069425) (xy 177.928612 -117.093021)
			(xy 177.97066 -117.123571) (xy 178.007411 -117.160322) (xy 178.037961 -117.20237) (xy 178.061557 -117.24868)
			(xy 178.077618 -117.29811) (xy 178.085748 -117.349445) (xy 178.086258 -117.375432) (xy 178.085748 -117.401419)
			(xy 179.025552 -117.401419) (xy 179.025552 -117.349445) (xy 179.033682 -117.29811) (xy 179.049743 -117.24868)
			(xy 179.073339 -117.20237) (xy 179.103889 -117.160322) (xy 179.14064 -117.123571) (xy 179.182688 -117.093021)
			(xy 179.228998 -117.069425) (xy 179.278428 -117.053364) (xy 179.329763 -117.045234) (xy 179.381737 -117.045234)
			(xy 179.433072 -117.053364) (xy 179.482502 -117.069425) (xy 179.528812 -117.093021) (xy 179.57086 -117.123571)
			(xy 179.607611 -117.160322) (xy 179.638161 -117.20237) (xy 179.661757 -117.24868) (xy 179.677818 -117.29811)
			(xy 179.685948 -117.349445) (xy 179.686458 -117.375432) (xy 179.685948 -117.401419) (xy 179.825398 -117.401419)
			(xy 179.825398 -117.349445) (xy 179.833528 -117.29811) (xy 179.849589 -117.24868) (xy 179.873185 -117.20237)
			(xy 179.903735 -117.160322) (xy 179.940486 -117.123571) (xy 179.982534 -117.093021) (xy 180.028844 -117.069425)
			(xy 180.078274 -117.053364) (xy 180.129609 -117.045234) (xy 180.181583 -117.045234) (xy 180.232918 -117.053364)
			(xy 180.282348 -117.069425) (xy 180.328658 -117.093021) (xy 180.370706 -117.123571) (xy 180.407457 -117.160322)
			(xy 180.438007 -117.20237) (xy 180.461603 -117.24868) (xy 180.477664 -117.29811) (xy 180.485794 -117.349445)
			(xy 180.486304 -117.375432) (xy 180.485794 -117.401419) (xy 180.625498 -117.401419) (xy 180.625498 -117.349445)
			(xy 180.633628 -117.29811) (xy 180.649689 -117.24868) (xy 180.673285 -117.20237) (xy 180.703835 -117.160322)
			(xy 180.740586 -117.123571) (xy 180.782634 -117.093021) (xy 180.828944 -117.069425) (xy 180.878374 -117.053364)
			(xy 180.929709 -117.045234) (xy 180.981683 -117.045234) (xy 181.033018 -117.053364) (xy 181.082448 -117.069425)
			(xy 181.128758 -117.093021) (xy 181.170806 -117.123571) (xy 181.207557 -117.160322) (xy 181.238107 -117.20237)
			(xy 181.261703 -117.24868) (xy 181.277764 -117.29811) (xy 181.285894 -117.349445) (xy 181.286404 -117.375432)
			(xy 181.285894 -117.401419) (xy 181.277764 -117.452754) (xy 181.261703 -117.502184) (xy 181.238107 -117.548494)
			(xy 181.207557 -117.590542) (xy 181.170806 -117.627293) (xy 181.128758 -117.657843) (xy 181.082448 -117.681439)
			(xy 181.033018 -117.6975) (xy 180.981683 -117.70563) (xy 180.929709 -117.70563) (xy 180.878374 -117.6975)
			(xy 180.828944 -117.681439) (xy 180.782634 -117.657843) (xy 180.740586 -117.627293) (xy 180.703835 -117.590542)
			(xy 180.673285 -117.548494) (xy 180.649689 -117.502184) (xy 180.633628 -117.452754) (xy 180.625498 -117.401419)
			(xy 180.485794 -117.401419) (xy 180.477664 -117.452754) (xy 180.461603 -117.502184) (xy 180.438007 -117.548494)
			(xy 180.407457 -117.590542) (xy 180.370706 -117.627293) (xy 180.328658 -117.657843) (xy 180.282348 -117.681439)
			(xy 180.232918 -117.6975) (xy 180.181583 -117.70563) (xy 180.129609 -117.70563) (xy 180.078274 -117.6975)
			(xy 180.028844 -117.681439) (xy 179.982534 -117.657843) (xy 179.940486 -117.627293) (xy 179.903735 -117.590542)
			(xy 179.873185 -117.548494) (xy 179.849589 -117.502184) (xy 179.833528 -117.452754) (xy 179.825398 -117.401419)
			(xy 179.685948 -117.401419) (xy 179.677818 -117.452754) (xy 179.661757 -117.502184) (xy 179.638161 -117.548494)
			(xy 179.607611 -117.590542) (xy 179.57086 -117.627293) (xy 179.528812 -117.657843) (xy 179.482502 -117.681439)
			(xy 179.433072 -117.6975) (xy 179.381737 -117.70563) (xy 179.329763 -117.70563) (xy 179.278428 -117.6975)
			(xy 179.228998 -117.681439) (xy 179.182688 -117.657843) (xy 179.14064 -117.627293) (xy 179.103889 -117.590542)
			(xy 179.073339 -117.548494) (xy 179.049743 -117.502184) (xy 179.033682 -117.452754) (xy 179.025552 -117.401419)
			(xy 178.085748 -117.401419) (xy 178.077618 -117.452754) (xy 178.061557 -117.502184) (xy 178.037961 -117.548494)
			(xy 178.007411 -117.590542) (xy 177.97066 -117.627293) (xy 177.928612 -117.657843) (xy 177.882302 -117.681439)
			(xy 177.832872 -117.6975) (xy 177.781537 -117.70563) (xy 177.729563 -117.70563) (xy 177.678228 -117.6975)
			(xy 177.628798 -117.681439) (xy 177.582488 -117.657843) (xy 177.54044 -117.627293) (xy 177.503689 -117.590542)
			(xy 177.473139 -117.548494) (xy 177.449543 -117.502184) (xy 177.433482 -117.452754) (xy 177.425352 -117.401419)
			(xy 177.285902 -117.401419) (xy 177.277772 -117.452754) (xy 177.261711 -117.502184) (xy 177.238115 -117.548494)
			(xy 177.207565 -117.590542) (xy 177.170814 -117.627293) (xy 177.128766 -117.657843) (xy 177.082456 -117.681439)
			(xy 177.033026 -117.6975) (xy 176.981691 -117.70563) (xy 176.929717 -117.70563) (xy 176.878382 -117.6975)
			(xy 176.828952 -117.681439) (xy 176.782642 -117.657843) (xy 176.740594 -117.627293) (xy 176.703843 -117.590542)
			(xy 176.673293 -117.548494) (xy 176.649697 -117.502184) (xy 176.633636 -117.452754) (xy 176.625506 -117.401419)
			(xy 176.485802 -117.401419) (xy 176.477672 -117.452754) (xy 176.461611 -117.502184) (xy 176.438015 -117.548494)
			(xy 176.407465 -117.590542) (xy 176.370714 -117.627293) (xy 176.328666 -117.657843) (xy 176.282356 -117.681439)
			(xy 176.232926 -117.6975) (xy 176.181591 -117.70563) (xy 176.129617 -117.70563) (xy 176.078282 -117.6975)
			(xy 176.028852 -117.681439) (xy 175.982542 -117.657843) (xy 175.940494 -117.627293) (xy 175.903743 -117.590542)
			(xy 175.873193 -117.548494) (xy 175.849597 -117.502184) (xy 175.833536 -117.452754) (xy 175.825406 -117.401419)
			(xy 175.685477 -117.401419) (xy 175.67799 -117.450273) (xy 175.662924 -117.498265) (xy 175.640762 -117.54342)
			(xy 175.612015 -117.584697) (xy 175.577347 -117.621143) (xy 175.537557 -117.651916) (xy 175.493564 -117.676305)
			(xy 175.446384 -117.693748) (xy 175.397106 -117.703842) (xy 175.372014 -117.705632) (xy 175.362371 -117.706569)
			(xy 175.3448 -117.714693) (xy 175.331497 -117.728757) (xy 175.324361 -117.746752) (xy 175.324008 -117.756432)
			(xy 175.324008 -117.794532) (xy 175.324432 -117.804196) (xy 175.331584 -117.822153) (xy 175.344862 -117.836198)
			(xy 175.36239 -117.844345) (xy 175.372014 -117.845332) (xy 175.397112 -117.847065) (xy 175.446393 -117.85717)
			(xy 175.493575 -117.874621) (xy 175.537571 -117.899015) (xy 175.577366 -117.929789) (xy 175.612043 -117.966235)
			(xy 175.6408 -118.007511) (xy 175.662977 -118.052665) (xy 175.67806 -118.100657) (xy 175.685703 -118.150379)
			(xy 175.686212 -118.175532) (xy 175.6857 -118.201518) (xy 175.6857 -118.201519) (xy 175.825406 -118.201519)
			(xy 175.825406 -118.149545) (xy 175.833536 -118.09821) (xy 175.849597 -118.04878) (xy 175.873193 -118.00247)
			(xy 175.903743 -117.960422) (xy 175.940494 -117.923671) (xy 175.982542 -117.893121) (xy 176.028852 -117.869525)
			(xy 176.078282 -117.853464) (xy 176.129617 -117.845334) (xy 176.181591 -117.845334) (xy 176.232926 -117.853464)
			(xy 176.282356 -117.869525) (xy 176.328666 -117.893121) (xy 176.370714 -117.923671) (xy 176.407465 -117.960422)
			(xy 176.438015 -118.00247) (xy 176.461611 -118.04878) (xy 176.477672 -118.09821) (xy 176.485802 -118.149545)
			(xy 176.486312 -118.175532) (xy 176.485802 -118.201519) (xy 176.625506 -118.201519) (xy 176.625506 -118.149545)
			(xy 176.633636 -118.09821) (xy 176.649697 -118.04878) (xy 176.673293 -118.00247) (xy 176.703843 -117.960422)
			(xy 176.740594 -117.923671) (xy 176.782642 -117.893121) (xy 176.828952 -117.869525) (xy 176.878382 -117.853464)
			(xy 176.929717 -117.845334) (xy 176.981691 -117.845334) (xy 177.033026 -117.853464) (xy 177.082456 -117.869525)
			(xy 177.128766 -117.893121) (xy 177.170814 -117.923671) (xy 177.207565 -117.960422) (xy 177.238115 -118.00247)
			(xy 177.261711 -118.04878) (xy 177.277772 -118.09821) (xy 177.285902 -118.149545) (xy 177.286412 -118.175532)
			(xy 177.285902 -118.201519) (xy 177.425352 -118.201519) (xy 177.425352 -118.149545) (xy 177.433482 -118.09821)
			(xy 177.449543 -118.04878) (xy 177.473139 -118.00247) (xy 177.503689 -117.960422) (xy 177.54044 -117.923671)
			(xy 177.582488 -117.893121) (xy 177.628798 -117.869525) (xy 177.678228 -117.853464) (xy 177.729563 -117.845334)
			(xy 177.781537 -117.845334) (xy 177.832872 -117.853464) (xy 177.882302 -117.869525) (xy 177.928612 -117.893121)
			(xy 177.97066 -117.923671) (xy 178.007411 -117.960422) (xy 178.037961 -118.00247) (xy 178.061557 -118.04878)
			(xy 178.077618 -118.09821) (xy 178.085748 -118.149545) (xy 178.086258 -118.175532) (xy 178.085748 -118.201519)
			(xy 179.825398 -118.201519) (xy 179.825398 -118.149545) (xy 179.833528 -118.09821) (xy 179.849589 -118.04878)
			(xy 179.873185 -118.00247) (xy 179.903735 -117.960422) (xy 179.940486 -117.923671) (xy 179.982534 -117.893121)
			(xy 180.028844 -117.869525) (xy 180.078274 -117.853464) (xy 180.129609 -117.845334) (xy 180.181583 -117.845334)
			(xy 180.232918 -117.853464) (xy 180.282348 -117.869525) (xy 180.328658 -117.893121) (xy 180.370706 -117.923671)
			(xy 180.407457 -117.960422) (xy 180.438007 -118.00247) (xy 180.461603 -118.04878) (xy 180.477664 -118.09821)
			(xy 180.485794 -118.149545) (xy 180.486304 -118.175532) (xy 180.485794 -118.201519) (xy 180.625498 -118.201519)
			(xy 180.625498 -118.149545) (xy 180.633628 -118.09821) (xy 180.649689 -118.04878) (xy 180.673285 -118.00247)
			(xy 180.703835 -117.960422) (xy 180.740586 -117.923671) (xy 180.782634 -117.893121) (xy 180.828944 -117.869525)
			(xy 180.878374 -117.853464) (xy 180.929709 -117.845334) (xy 180.981683 -117.845334) (xy 181.033018 -117.853464)
			(xy 181.082448 -117.869525) (xy 181.128758 -117.893121) (xy 181.170806 -117.923671) (xy 181.207557 -117.960422)
			(xy 181.238107 -118.00247) (xy 181.261703 -118.04878) (xy 181.277764 -118.09821) (xy 181.285894 -118.149545)
			(xy 181.286404 -118.175532) (xy 181.285894 -118.201519) (xy 181.277764 -118.252854) (xy 181.261703 -118.302284)
			(xy 181.238107 -118.348594) (xy 181.207557 -118.390642) (xy 181.170806 -118.427393) (xy 181.128758 -118.457943)
			(xy 181.082448 -118.481539) (xy 181.033018 -118.4976) (xy 180.981683 -118.50573) (xy 180.929709 -118.50573)
			(xy 180.878374 -118.4976) (xy 180.828944 -118.481539) (xy 180.782634 -118.457943) (xy 180.740586 -118.427393)
			(xy 180.703835 -118.390642) (xy 180.673285 -118.348594) (xy 180.649689 -118.302284) (xy 180.633628 -118.252854)
			(xy 180.625498 -118.201519) (xy 180.485794 -118.201519) (xy 180.477664 -118.252854) (xy 180.461603 -118.302284)
			(xy 180.438007 -118.348594) (xy 180.407457 -118.390642) (xy 180.370706 -118.427393) (xy 180.328658 -118.457943)
			(xy 180.282348 -118.481539) (xy 180.232918 -118.4976) (xy 180.181583 -118.50573) (xy 180.129609 -118.50573)
			(xy 180.078274 -118.4976) (xy 180.028844 -118.481539) (xy 179.982534 -118.457943) (xy 179.940486 -118.427393)
			(xy 179.903735 -118.390642) (xy 179.873185 -118.348594) (xy 179.849589 -118.302284) (xy 179.833528 -118.252854)
			(xy 179.825398 -118.201519) (xy 178.085748 -118.201519) (xy 178.077618 -118.252854) (xy 178.061557 -118.302284)
			(xy 178.037961 -118.348594) (xy 178.007411 -118.390642) (xy 177.97066 -118.427393) (xy 177.928612 -118.457943)
			(xy 177.882302 -118.481539) (xy 177.832872 -118.4976) (xy 177.781537 -118.50573) (xy 177.729563 -118.50573)
			(xy 177.678228 -118.4976) (xy 177.628798 -118.481539) (xy 177.582488 -118.457943) (xy 177.54044 -118.427393)
			(xy 177.503689 -118.390642) (xy 177.473139 -118.348594) (xy 177.449543 -118.302284) (xy 177.433482 -118.252854)
			(xy 177.425352 -118.201519) (xy 177.285902 -118.201519) (xy 177.277772 -118.252854) (xy 177.261711 -118.302284)
			(xy 177.238115 -118.348594) (xy 177.207565 -118.390642) (xy 177.170814 -118.427393) (xy 177.128766 -118.457943)
			(xy 177.082456 -118.481539) (xy 177.033026 -118.4976) (xy 176.981691 -118.50573) (xy 176.929717 -118.50573)
			(xy 176.878382 -118.4976) (xy 176.828952 -118.481539) (xy 176.782642 -118.457943) (xy 176.740594 -118.427393)
			(xy 176.703843 -118.390642) (xy 176.673293 -118.348594) (xy 176.649697 -118.302284) (xy 176.633636 -118.252854)
			(xy 176.625506 -118.201519) (xy 176.485802 -118.201519) (xy 176.477672 -118.252854) (xy 176.461611 -118.302284)
			(xy 176.438015 -118.348594) (xy 176.407465 -118.390642) (xy 176.370714 -118.427393) (xy 176.328666 -118.457943)
			(xy 176.282356 -118.481539) (xy 176.232926 -118.4976) (xy 176.181591 -118.50573) (xy 176.129617 -118.50573)
			(xy 176.078282 -118.4976) (xy 176.028852 -118.481539) (xy 175.982542 -118.457943) (xy 175.940494 -118.427393)
			(xy 175.903743 -118.390642) (xy 175.873193 -118.348594) (xy 175.849597 -118.302284) (xy 175.833536 -118.252854)
			(xy 175.825406 -118.201519) (xy 175.6857 -118.201519) (xy 175.677566 -118.252848) (xy 175.661502 -118.302275)
			(xy 175.637904 -118.34858) (xy 175.607354 -118.390624) (xy 175.570603 -118.427372) (xy 175.528556 -118.457919)
			(xy 175.482249 -118.481513) (xy 175.432821 -118.497572) (xy 175.38149 -118.505702) (xy 175.355504 -118.50624)
			(xy 175.343458 -118.506124) (xy 175.319431 -118.504341) (xy 175.307498 -118.502684) (xy 175.301897 -118.520357)
			(xy 175.287641 -118.554582) (xy 175.27905 -118.57101) (xy 175.274233 -118.580909) (xy 175.272689 -118.602846)
			(xy 175.280463 -118.623418) (xy 175.296129 -118.638852) (xy 175.316814 -118.646317) (xy 175.327818 -118.64594)
			(xy 175.355504 -118.64467) (xy 175.381492 -118.64518) (xy 175.432827 -118.653311) (xy 175.482258 -118.669372)
			(xy 175.528569 -118.692968) (xy 175.570618 -118.723517) (xy 175.607371 -118.760268) (xy 175.637923 -118.802316)
			(xy 175.661521 -118.848625) (xy 175.677585 -118.898056) (xy 175.685719 -118.94939) (xy 175.686212 -118.975378)
			(xy 175.685749 -119.000552) (xy 175.685625 -119.001365) (xy 175.825406 -119.001365) (xy 175.825406 -118.949391)
			(xy 175.833536 -118.898056) (xy 175.849597 -118.848626) (xy 175.873193 -118.802316) (xy 175.903743 -118.760268)
			(xy 175.940494 -118.723517) (xy 175.982542 -118.692967) (xy 176.028852 -118.669371) (xy 176.078282 -118.65331)
			(xy 176.129617 -118.64518) (xy 176.181591 -118.64518) (xy 176.232926 -118.65331) (xy 176.282356 -118.669371)
			(xy 176.328666 -118.692967) (xy 176.370714 -118.723517) (xy 176.407465 -118.760268) (xy 176.438015 -118.802316)
			(xy 176.461611 -118.848626) (xy 176.477672 -118.898056) (xy 176.485802 -118.949391) (xy 176.486312 -118.975378)
			(xy 176.485802 -119.001365) (xy 176.625506 -119.001365) (xy 176.625506 -118.949391) (xy 176.633636 -118.898056)
			(xy 176.649697 -118.848626) (xy 176.673293 -118.802316) (xy 176.703843 -118.760268) (xy 176.740594 -118.723517)
			(xy 176.782642 -118.692967) (xy 176.828952 -118.669371) (xy 176.878382 -118.65331) (xy 176.929717 -118.64518)
			(xy 176.981691 -118.64518) (xy 177.033026 -118.65331) (xy 177.082456 -118.669371) (xy 177.128766 -118.692967)
			(xy 177.170814 -118.723517) (xy 177.207565 -118.760268) (xy 177.238115 -118.802316) (xy 177.261711 -118.848626)
			(xy 177.277772 -118.898056) (xy 177.285902 -118.949391) (xy 177.286412 -118.975378) (xy 177.285902 -119.001365)
			(xy 177.425352 -119.001365) (xy 177.425352 -118.949391) (xy 177.433482 -118.898056) (xy 177.449543 -118.848626)
			(xy 177.473139 -118.802316) (xy 177.503689 -118.760268) (xy 177.54044 -118.723517) (xy 177.582488 -118.692967)
			(xy 177.628798 -118.669371) (xy 177.678228 -118.65331) (xy 177.729563 -118.64518) (xy 177.781537 -118.64518)
			(xy 177.832872 -118.65331) (xy 177.882302 -118.669371) (xy 177.928612 -118.692967) (xy 177.97066 -118.723517)
			(xy 178.007411 -118.760268) (xy 178.037961 -118.802316) (xy 178.061557 -118.848626) (xy 178.077618 -118.898056)
			(xy 178.085748 -118.949391) (xy 178.086258 -118.975378) (xy 178.085748 -119.001365) (xy 179.025552 -119.001365)
			(xy 179.025552 -118.949391) (xy 179.033682 -118.898056) (xy 179.049743 -118.848626) (xy 179.073339 -118.802316)
			(xy 179.103889 -118.760268) (xy 179.14064 -118.723517) (xy 179.182688 -118.692967) (xy 179.228998 -118.669371)
			(xy 179.278428 -118.65331) (xy 179.329763 -118.64518) (xy 179.381737 -118.64518) (xy 179.433072 -118.65331)
			(xy 179.482502 -118.669371) (xy 179.528812 -118.692967) (xy 179.57086 -118.723517) (xy 179.607611 -118.760268)
			(xy 179.638161 -118.802316) (xy 179.661757 -118.848626) (xy 179.677818 -118.898056) (xy 179.685948 -118.949391)
			(xy 179.686458 -118.975378) (xy 179.685948 -119.001365) (xy 179.825398 -119.001365) (xy 179.825398 -118.949391)
			(xy 179.833528 -118.898056) (xy 179.849589 -118.848626) (xy 179.873185 -118.802316) (xy 179.903735 -118.760268)
			(xy 179.940486 -118.723517) (xy 179.982534 -118.692967) (xy 180.028844 -118.669371) (xy 180.078274 -118.65331)
			(xy 180.129609 -118.64518) (xy 180.181583 -118.64518) (xy 180.232918 -118.65331) (xy 180.282348 -118.669371)
			(xy 180.328658 -118.692967) (xy 180.370706 -118.723517) (xy 180.407457 -118.760268) (xy 180.438007 -118.802316)
			(xy 180.461603 -118.848626) (xy 180.477664 -118.898056) (xy 180.485794 -118.949391) (xy 180.486304 -118.975378)
			(xy 180.485794 -119.001365) (xy 180.625498 -119.001365) (xy 180.625498 -118.949391) (xy 180.633628 -118.898056)
			(xy 180.649689 -118.848626) (xy 180.673285 -118.802316) (xy 180.703835 -118.760268) (xy 180.740586 -118.723517)
			(xy 180.782634 -118.692967) (xy 180.828944 -118.669371) (xy 180.878374 -118.65331) (xy 180.929709 -118.64518)
			(xy 180.981683 -118.64518) (xy 181.033018 -118.65331) (xy 181.082448 -118.669371) (xy 181.128758 -118.692967)
			(xy 181.170806 -118.723517) (xy 181.207557 -118.760268) (xy 181.238107 -118.802316) (xy 181.261703 -118.848626)
			(xy 181.277764 -118.898056) (xy 181.285894 -118.949391) (xy 181.286404 -118.975378) (xy 181.285894 -119.001365)
			(xy 181.277764 -119.0527) (xy 181.261703 -119.10213) (xy 181.238107 -119.14844) (xy 181.207557 -119.190488)
			(xy 181.170806 -119.227239) (xy 181.128758 -119.257789) (xy 181.082448 -119.281385) (xy 181.033018 -119.297446)
			(xy 180.981683 -119.305576) (xy 180.929709 -119.305576) (xy 180.878374 -119.297446) (xy 180.828944 -119.281385)
			(xy 180.782634 -119.257789) (xy 180.740586 -119.227239) (xy 180.703835 -119.190488) (xy 180.673285 -119.14844)
			(xy 180.649689 -119.10213) (xy 180.633628 -119.0527) (xy 180.625498 -119.001365) (xy 180.485794 -119.001365)
			(xy 180.477664 -119.0527) (xy 180.461603 -119.10213) (xy 180.438007 -119.14844) (xy 180.407457 -119.190488)
			(xy 180.370706 -119.227239) (xy 180.328658 -119.257789) (xy 180.282348 -119.281385) (xy 180.232918 -119.297446)
			(xy 180.181583 -119.305576) (xy 180.129609 -119.305576) (xy 180.078274 -119.297446) (xy 180.028844 -119.281385)
			(xy 179.982534 -119.257789) (xy 179.940486 -119.227239) (xy 179.903735 -119.190488) (xy 179.873185 -119.14844)
			(xy 179.849589 -119.10213) (xy 179.833528 -119.0527) (xy 179.825398 -119.001365) (xy 179.685948 -119.001365)
			(xy 179.677818 -119.0527) (xy 179.661757 -119.10213) (xy 179.638161 -119.14844) (xy 179.607611 -119.190488)
			(xy 179.57086 -119.227239) (xy 179.528812 -119.257789) (xy 179.482502 -119.281385) (xy 179.433072 -119.297446)
			(xy 179.381737 -119.305576) (xy 179.329763 -119.305576) (xy 179.278428 -119.297446) (xy 179.228998 -119.281385)
			(xy 179.182688 -119.257789) (xy 179.14064 -119.227239) (xy 179.103889 -119.190488) (xy 179.073339 -119.14844)
			(xy 179.049743 -119.10213) (xy 179.033682 -119.0527) (xy 179.025552 -119.001365) (xy 178.085748 -119.001365)
			(xy 178.077618 -119.0527) (xy 178.061557 -119.10213) (xy 178.037961 -119.14844) (xy 178.007411 -119.190488)
			(xy 177.97066 -119.227239) (xy 177.928612 -119.257789) (xy 177.882302 -119.281385) (xy 177.832872 -119.297446)
			(xy 177.781537 -119.305576) (xy 177.729563 -119.305576) (xy 177.678228 -119.297446) (xy 177.628798 -119.281385)
			(xy 177.582488 -119.257789) (xy 177.54044 -119.227239) (xy 177.503689 -119.190488) (xy 177.473139 -119.14844)
			(xy 177.449543 -119.10213) (xy 177.433482 -119.0527) (xy 177.425352 -119.001365) (xy 177.285902 -119.001365)
			(xy 177.277772 -119.0527) (xy 177.261711 -119.10213) (xy 177.238115 -119.14844) (xy 177.207565 -119.190488)
			(xy 177.170814 -119.227239) (xy 177.128766 -119.257789) (xy 177.082456 -119.281385) (xy 177.033026 -119.297446)
			(xy 176.981691 -119.305576) (xy 176.929717 -119.305576) (xy 176.878382 -119.297446) (xy 176.828952 -119.281385)
			(xy 176.782642 -119.257789) (xy 176.740594 -119.227239) (xy 176.703843 -119.190488) (xy 176.673293 -119.14844)
			(xy 176.649697 -119.10213) (xy 176.633636 -119.0527) (xy 176.625506 -119.001365) (xy 176.485802 -119.001365)
			(xy 176.477672 -119.0527) (xy 176.461611 -119.10213) (xy 176.438015 -119.14844) (xy 176.407465 -119.190488)
			(xy 176.370714 -119.227239) (xy 176.328666 -119.257789) (xy 176.282356 -119.281385) (xy 176.232926 -119.297446)
			(xy 176.181591 -119.305576) (xy 176.129617 -119.305576) (xy 176.078282 -119.297446) (xy 176.028852 -119.281385)
			(xy 175.982542 -119.257789) (xy 175.940494 -119.227239) (xy 175.903743 -119.190488) (xy 175.873193 -119.14844)
			(xy 175.849597 -119.10213) (xy 175.833536 -119.0527) (xy 175.825406 -119.001365) (xy 175.685625 -119.001365)
			(xy 175.678131 -119.05032) (xy 175.663054 -119.098357) (xy 175.640865 -119.143551) (xy 175.612078 -119.184857)
			(xy 175.57736 -119.221319) (xy 175.537513 -119.252094) (xy 175.493459 -119.276469) (xy 175.446218 -119.293881)
			(xy 175.396883 -119.303927) (xy 175.37176 -119.305578) (xy 175.361806 -119.306558) (xy 175.343739 -119.315092)
			(xy 175.330293 -119.329872) (xy 175.323502 -119.348664) (xy 175.3235 -119.358664) (xy 175.324008 -119.37492)
			(xy 175.324008 -119.394478) (xy 175.32444 -119.404136) (xy 175.3316 -119.422078) (xy 175.344878 -119.436109)
			(xy 175.362398 -119.444247) (xy 175.372014 -119.445278) (xy 175.397114 -119.447004) (xy 175.4464 -119.4571)
			(xy 175.493587 -119.474546) (xy 175.537587 -119.49894) (xy 175.577383 -119.529717) (xy 175.612057 -119.566169)
			(xy 175.640809 -119.607453) (xy 175.662975 -119.652616) (xy 175.678042 -119.700616) (xy 175.685664 -119.750344)
			(xy 175.685664 -119.800654) (xy 175.68554 -119.801465) (xy 175.825406 -119.801465) (xy 175.825406 -119.749491)
			(xy 175.833536 -119.698156) (xy 175.849597 -119.648726) (xy 175.873193 -119.602416) (xy 175.903743 -119.560368)
			(xy 175.940494 -119.523617) (xy 175.982542 -119.493067) (xy 176.028852 -119.469471) (xy 176.078282 -119.45341)
			(xy 176.129617 -119.44528) (xy 176.181591 -119.44528) (xy 176.232926 -119.45341) (xy 176.282356 -119.469471)
			(xy 176.328666 -119.493067) (xy 176.370714 -119.523617) (xy 176.407465 -119.560368) (xy 176.438015 -119.602416)
			(xy 176.461611 -119.648726) (xy 176.477672 -119.698156) (xy 176.485802 -119.749491) (xy 176.486312 -119.775478)
			(xy 176.485802 -119.801465) (xy 176.625506 -119.801465) (xy 176.625506 -119.749491) (xy 176.633636 -119.698156)
			(xy 176.649697 -119.648726) (xy 176.673293 -119.602416) (xy 176.703843 -119.560368) (xy 176.740594 -119.523617)
			(xy 176.782642 -119.493067) (xy 176.828952 -119.469471) (xy 176.878382 -119.45341) (xy 176.929717 -119.44528)
			(xy 176.981691 -119.44528) (xy 177.033026 -119.45341) (xy 177.082456 -119.469471) (xy 177.128766 -119.493067)
			(xy 177.170814 -119.523617) (xy 177.207565 -119.560368) (xy 177.238115 -119.602416) (xy 177.261711 -119.648726)
			(xy 177.277772 -119.698156) (xy 177.285902 -119.749491) (xy 177.286412 -119.775478) (xy 177.285902 -119.801465)
			(xy 177.425352 -119.801465) (xy 177.425352 -119.749491) (xy 177.433482 -119.698156) (xy 177.449543 -119.648726)
			(xy 177.473139 -119.602416) (xy 177.503689 -119.560368) (xy 177.54044 -119.523617) (xy 177.582488 -119.493067)
			(xy 177.628798 -119.469471) (xy 177.678228 -119.45341) (xy 177.729563 -119.44528) (xy 177.781537 -119.44528)
			(xy 177.832872 -119.45341) (xy 177.882302 -119.469471) (xy 177.928612 -119.493067) (xy 177.97066 -119.523617)
			(xy 178.007411 -119.560368) (xy 178.037961 -119.602416) (xy 178.061557 -119.648726) (xy 178.077618 -119.698156)
			(xy 178.085748 -119.749491) (xy 178.086258 -119.775478) (xy 178.085748 -119.801465) (xy 179.025552 -119.801465)
			(xy 179.025552 -119.749491) (xy 179.033682 -119.698156) (xy 179.049743 -119.648726) (xy 179.073339 -119.602416)
			(xy 179.103889 -119.560368) (xy 179.14064 -119.523617) (xy 179.182688 -119.493067) (xy 179.228998 -119.469471)
			(xy 179.278428 -119.45341) (xy 179.329763 -119.44528) (xy 179.381737 -119.44528) (xy 179.433072 -119.45341)
			(xy 179.482502 -119.469471) (xy 179.528812 -119.493067) (xy 179.57086 -119.523617) (xy 179.607611 -119.560368)
			(xy 179.638161 -119.602416) (xy 179.661757 -119.648726) (xy 179.677818 -119.698156) (xy 179.685948 -119.749491)
			(xy 179.686458 -119.775478) (xy 179.685948 -119.801465) (xy 179.825398 -119.801465) (xy 179.825398 -119.749491)
			(xy 179.833528 -119.698156) (xy 179.849589 -119.648726) (xy 179.873185 -119.602416) (xy 179.903735 -119.560368)
			(xy 179.940486 -119.523617) (xy 179.982534 -119.493067) (xy 180.028844 -119.469471) (xy 180.078274 -119.45341)
			(xy 180.129609 -119.44528) (xy 180.181583 -119.44528) (xy 180.232918 -119.45341) (xy 180.282348 -119.469471)
			(xy 180.328658 -119.493067) (xy 180.370706 -119.523617) (xy 180.407457 -119.560368) (xy 180.438007 -119.602416)
			(xy 180.461603 -119.648726) (xy 180.477664 -119.698156) (xy 180.485794 -119.749491) (xy 180.486304 -119.775478)
			(xy 180.485794 -119.801465) (xy 180.625498 -119.801465) (xy 180.625498 -119.749491) (xy 180.633628 -119.698156)
			(xy 180.649689 -119.648726) (xy 180.673285 -119.602416) (xy 180.703835 -119.560368) (xy 180.740586 -119.523617)
			(xy 180.782634 -119.493067) (xy 180.828944 -119.469471) (xy 180.878374 -119.45341) (xy 180.929709 -119.44528)
			(xy 180.981683 -119.44528) (xy 181.033018 -119.45341) (xy 181.082448 -119.469471) (xy 181.128758 -119.493067)
			(xy 181.170806 -119.523617) (xy 181.207557 -119.560368) (xy 181.238107 -119.602416) (xy 181.261703 -119.648726)
			(xy 181.277764 -119.698156) (xy 181.285894 -119.749491) (xy 181.286404 -119.775478) (xy 181.285894 -119.801465)
			(xy 181.277764 -119.8528) (xy 181.261703 -119.90223) (xy 181.238107 -119.94854) (xy 181.207557 -119.990588)
			(xy 181.170806 -120.027339) (xy 181.128758 -120.057889) (xy 181.082448 -120.081485) (xy 181.033018 -120.097546)
			(xy 180.981683 -120.105676) (xy 180.929709 -120.105676) (xy 180.878374 -120.097546) (xy 180.828944 -120.081485)
			(xy 180.782634 -120.057889) (xy 180.740586 -120.027339) (xy 180.703835 -119.990588) (xy 180.673285 -119.94854)
			(xy 180.649689 -119.90223) (xy 180.633628 -119.8528) (xy 180.625498 -119.801465) (xy 180.485794 -119.801465)
			(xy 180.477664 -119.8528) (xy 180.461603 -119.90223) (xy 180.438007 -119.94854) (xy 180.407457 -119.990588)
			(xy 180.370706 -120.027339) (xy 180.328658 -120.057889) (xy 180.282348 -120.081485) (xy 180.232918 -120.097546)
			(xy 180.181583 -120.105676) (xy 180.129609 -120.105676) (xy 180.078274 -120.097546) (xy 180.028844 -120.081485)
			(xy 179.982534 -120.057889) (xy 179.940486 -120.027339) (xy 179.903735 -119.990588) (xy 179.873185 -119.94854)
			(xy 179.849589 -119.90223) (xy 179.833528 -119.8528) (xy 179.825398 -119.801465) (xy 179.685948 -119.801465)
			(xy 179.677818 -119.8528) (xy 179.661757 -119.90223) (xy 179.638161 -119.94854) (xy 179.607611 -119.990588)
			(xy 179.57086 -120.027339) (xy 179.528812 -120.057889) (xy 179.482502 -120.081485) (xy 179.433072 -120.097546)
			(xy 179.381737 -120.105676) (xy 179.329763 -120.105676) (xy 179.278428 -120.097546) (xy 179.228998 -120.081485)
			(xy 179.182688 -120.057889) (xy 179.14064 -120.027339) (xy 179.103889 -119.990588) (xy 179.073339 -119.94854)
			(xy 179.049743 -119.90223) (xy 179.033682 -119.8528) (xy 179.025552 -119.801465) (xy 178.085748 -119.801465)
			(xy 178.077618 -119.8528) (xy 178.061557 -119.90223) (xy 178.037961 -119.94854) (xy 178.007411 -119.990588)
			(xy 177.97066 -120.027339) (xy 177.928612 -120.057889) (xy 177.882302 -120.081485) (xy 177.832872 -120.097546)
			(xy 177.781537 -120.105676) (xy 177.729563 -120.105676) (xy 177.678228 -120.097546) (xy 177.628798 -120.081485)
			(xy 177.582488 -120.057889) (xy 177.54044 -120.027339) (xy 177.503689 -119.990588) (xy 177.473139 -119.94854)
			(xy 177.449543 -119.90223) (xy 177.433482 -119.8528) (xy 177.425352 -119.801465) (xy 177.285902 -119.801465)
			(xy 177.277772 -119.8528) (xy 177.261711 -119.90223) (xy 177.238115 -119.94854) (xy 177.207565 -119.990588)
			(xy 177.170814 -120.027339) (xy 177.128766 -120.057889) (xy 177.082456 -120.081485) (xy 177.033026 -120.097546)
			(xy 176.981691 -120.105676) (xy 176.929717 -120.105676) (xy 176.878382 -120.097546) (xy 176.828952 -120.081485)
			(xy 176.782642 -120.057889) (xy 176.740594 -120.027339) (xy 176.703843 -119.990588) (xy 176.673293 -119.94854)
			(xy 176.649697 -119.90223) (xy 176.633636 -119.8528) (xy 176.625506 -119.801465) (xy 176.485802 -119.801465)
			(xy 176.477672 -119.8528) (xy 176.461611 -119.90223) (xy 176.438015 -119.94854) (xy 176.407465 -119.990588)
			(xy 176.370714 -120.027339) (xy 176.328666 -120.057889) (xy 176.282356 -120.081485) (xy 176.232926 -120.097546)
			(xy 176.181591 -120.105676) (xy 176.129617 -120.105676) (xy 176.078282 -120.097546) (xy 176.028852 -120.081485)
			(xy 175.982542 -120.057889) (xy 175.940494 -120.027339) (xy 175.903743 -119.990588) (xy 175.873193 -119.94854)
			(xy 175.849597 -119.90223) (xy 175.833536 -119.8528) (xy 175.825406 -119.801465) (xy 175.68554 -119.801465)
			(xy 175.678043 -119.850382) (xy 175.662976 -119.898382) (xy 175.64081 -119.943545) (xy 175.612059 -119.984829)
			(xy 175.577385 -120.021281) (xy 175.537589 -120.052059) (xy 175.493589 -120.076453) (xy 175.446402 -120.093899)
			(xy 175.397116 -120.103996) (xy 175.372014 -120.105678) (xy 175.362374 -120.106616) (xy 175.344811 -120.114742)
			(xy 175.33152 -120.128807) (xy 175.324399 -120.146801) (xy 175.324008 -120.156478) (xy 175.324008 -120.194578)
			(xy 175.32444 -120.204236) (xy 175.3316 -120.222178) (xy 175.344878 -120.236209) (xy 175.362398 -120.244347)
			(xy 175.372014 -120.245378) (xy 175.397114 -120.247104) (xy 175.4464 -120.2572) (xy 175.493587 -120.274646)
			(xy 175.537587 -120.29904) (xy 175.577383 -120.329817) (xy 175.612057 -120.366269) (xy 175.640809 -120.407553)
			(xy 175.662975 -120.452716) (xy 175.678042 -120.500716) (xy 175.685664 -120.550444) (xy 175.685664 -120.600754)
			(xy 175.68554 -120.601565) (xy 175.825406 -120.601565) (xy 175.825406 -120.549591) (xy 175.833536 -120.498256)
			(xy 175.849597 -120.448826) (xy 175.873193 -120.402516) (xy 175.903743 -120.360468) (xy 175.940494 -120.323717)
			(xy 175.982542 -120.293167) (xy 176.028852 -120.269571) (xy 176.078282 -120.25351) (xy 176.129617 -120.24538)
			(xy 176.181591 -120.24538) (xy 176.232926 -120.25351) (xy 176.282356 -120.269571) (xy 176.328666 -120.293167)
			(xy 176.370714 -120.323717) (xy 176.407465 -120.360468) (xy 176.438015 -120.402516) (xy 176.461611 -120.448826)
			(xy 176.477672 -120.498256) (xy 176.485802 -120.549591) (xy 176.486312 -120.575578) (xy 176.485802 -120.601565)
			(xy 176.625506 -120.601565) (xy 176.625506 -120.549591) (xy 176.633636 -120.498256) (xy 176.649697 -120.448826)
			(xy 176.673293 -120.402516) (xy 176.703843 -120.360468) (xy 176.740594 -120.323717) (xy 176.782642 -120.293167)
			(xy 176.828952 -120.269571) (xy 176.878382 -120.25351) (xy 176.929717 -120.24538) (xy 176.981691 -120.24538)
			(xy 177.033026 -120.25351) (xy 177.082456 -120.269571) (xy 177.128766 -120.293167) (xy 177.170814 -120.323717)
			(xy 177.207565 -120.360468) (xy 177.238115 -120.402516) (xy 177.261711 -120.448826) (xy 177.277772 -120.498256)
			(xy 177.285902 -120.549591) (xy 177.286412 -120.575578) (xy 177.285902 -120.601565) (xy 177.425352 -120.601565)
			(xy 177.425352 -120.549591) (xy 177.433482 -120.498256) (xy 177.449543 -120.448826) (xy 177.473139 -120.402516)
			(xy 177.503689 -120.360468) (xy 177.54044 -120.323717) (xy 177.582488 -120.293167) (xy 177.628798 -120.269571)
			(xy 177.678228 -120.25351) (xy 177.729563 -120.24538) (xy 177.781537 -120.24538) (xy 177.832872 -120.25351)
			(xy 177.882302 -120.269571) (xy 177.928612 -120.293167) (xy 177.97066 -120.323717) (xy 178.007411 -120.360468)
			(xy 178.037961 -120.402516) (xy 178.061557 -120.448826) (xy 178.077618 -120.498256) (xy 178.085748 -120.549591)
			(xy 178.086258 -120.575578) (xy 178.085748 -120.601565) (xy 179.825398 -120.601565) (xy 179.825398 -120.549591)
			(xy 179.833528 -120.498256) (xy 179.849589 -120.448826) (xy 179.873185 -120.402516) (xy 179.903735 -120.360468)
			(xy 179.940486 -120.323717) (xy 179.982534 -120.293167) (xy 180.028844 -120.269571) (xy 180.078274 -120.25351)
			(xy 180.129609 -120.24538) (xy 180.181583 -120.24538) (xy 180.232918 -120.25351) (xy 180.282348 -120.269571)
			(xy 180.328658 -120.293167) (xy 180.370706 -120.323717) (xy 180.407457 -120.360468) (xy 180.438007 -120.402516)
			(xy 180.461603 -120.448826) (xy 180.477664 -120.498256) (xy 180.485794 -120.549591) (xy 180.486304 -120.575578)
			(xy 180.485794 -120.601565) (xy 180.625498 -120.601565) (xy 180.625498 -120.549591) (xy 180.633628 -120.498256)
			(xy 180.649689 -120.448826) (xy 180.673285 -120.402516) (xy 180.703835 -120.360468) (xy 180.740586 -120.323717)
			(xy 180.782634 -120.293167) (xy 180.828944 -120.269571) (xy 180.878374 -120.25351) (xy 180.929709 -120.24538)
			(xy 180.981683 -120.24538) (xy 181.033018 -120.25351) (xy 181.082448 -120.269571) (xy 181.128758 -120.293167)
			(xy 181.170806 -120.323717) (xy 181.207557 -120.360468) (xy 181.238107 -120.402516) (xy 181.261703 -120.448826)
			(xy 181.277764 -120.498256) (xy 181.285894 -120.549591) (xy 181.286404 -120.575578) (xy 181.285894 -120.601565)
			(xy 181.277764 -120.6529) (xy 181.261703 -120.70233) (xy 181.238107 -120.74864) (xy 181.207557 -120.790688)
			(xy 181.170806 -120.827439) (xy 181.128758 -120.857989) (xy 181.082448 -120.881585) (xy 181.033018 -120.897646)
			(xy 180.981683 -120.905776) (xy 180.929709 -120.905776) (xy 180.878374 -120.897646) (xy 180.828944 -120.881585)
			(xy 180.782634 -120.857989) (xy 180.740586 -120.827439) (xy 180.703835 -120.790688) (xy 180.673285 -120.74864)
			(xy 180.649689 -120.70233) (xy 180.633628 -120.6529) (xy 180.625498 -120.601565) (xy 180.485794 -120.601565)
			(xy 180.477664 -120.6529) (xy 180.461603 -120.70233) (xy 180.438007 -120.74864) (xy 180.407457 -120.790688)
			(xy 180.370706 -120.827439) (xy 180.328658 -120.857989) (xy 180.282348 -120.881585) (xy 180.232918 -120.897646)
			(xy 180.181583 -120.905776) (xy 180.129609 -120.905776) (xy 180.078274 -120.897646) (xy 180.028844 -120.881585)
			(xy 179.982534 -120.857989) (xy 179.940486 -120.827439) (xy 179.903735 -120.790688) (xy 179.873185 -120.74864)
			(xy 179.849589 -120.70233) (xy 179.833528 -120.6529) (xy 179.825398 -120.601565) (xy 178.085748 -120.601565)
			(xy 178.077618 -120.6529) (xy 178.061557 -120.70233) (xy 178.037961 -120.74864) (xy 178.007411 -120.790688)
			(xy 177.97066 -120.827439) (xy 177.928612 -120.857989) (xy 177.882302 -120.881585) (xy 177.832872 -120.897646)
			(xy 177.781537 -120.905776) (xy 177.729563 -120.905776) (xy 177.678228 -120.897646) (xy 177.628798 -120.881585)
			(xy 177.582488 -120.857989) (xy 177.54044 -120.827439) (xy 177.503689 -120.790688) (xy 177.473139 -120.74864)
			(xy 177.449543 -120.70233) (xy 177.433482 -120.6529) (xy 177.425352 -120.601565) (xy 177.285902 -120.601565)
			(xy 177.277772 -120.6529) (xy 177.261711 -120.70233) (xy 177.238115 -120.74864) (xy 177.207565 -120.790688)
			(xy 177.170814 -120.827439) (xy 177.128766 -120.857989) (xy 177.082456 -120.881585) (xy 177.033026 -120.897646)
			(xy 176.981691 -120.905776) (xy 176.929717 -120.905776) (xy 176.878382 -120.897646) (xy 176.828952 -120.881585)
			(xy 176.782642 -120.857989) (xy 176.740594 -120.827439) (xy 176.703843 -120.790688) (xy 176.673293 -120.74864)
			(xy 176.649697 -120.70233) (xy 176.633636 -120.6529) (xy 176.625506 -120.601565) (xy 176.485802 -120.601565)
			(xy 176.477672 -120.6529) (xy 176.461611 -120.70233) (xy 176.438015 -120.74864) (xy 176.407465 -120.790688)
			(xy 176.370714 -120.827439) (xy 176.328666 -120.857989) (xy 176.282356 -120.881585) (xy 176.232926 -120.897646)
			(xy 176.181591 -120.905776) (xy 176.129617 -120.905776) (xy 176.078282 -120.897646) (xy 176.028852 -120.881585)
			(xy 175.982542 -120.857989) (xy 175.940494 -120.827439) (xy 175.903743 -120.790688) (xy 175.873193 -120.74864)
			(xy 175.849597 -120.70233) (xy 175.833536 -120.6529) (xy 175.825406 -120.601565) (xy 175.68554 -120.601565)
			(xy 175.678043 -120.650482) (xy 175.662976 -120.698482) (xy 175.64081 -120.743645) (xy 175.612059 -120.784929)
			(xy 175.577385 -120.821381) (xy 175.537589 -120.852159) (xy 175.493589 -120.876553) (xy 175.446402 -120.893999)
			(xy 175.397116 -120.904096) (xy 175.372014 -120.905778) (xy 175.362374 -120.906716) (xy 175.344811 -120.914842)
			(xy 175.33152 -120.928907) (xy 175.324399 -120.946901) (xy 175.324008 -120.956578) (xy 175.324008 -120.994424)
			(xy 175.324431 -121.004089) (xy 175.331581 -121.022049) (xy 175.34486 -121.036096) (xy 175.362389 -121.044244)
			(xy 175.372014 -121.045224) (xy 175.39711 -121.04695) (xy 175.446389 -121.057045) (xy 175.49357 -121.074489)
			(xy 175.537563 -121.098879) (xy 175.577354 -121.129653) (xy 175.612023 -121.1661) (xy 175.640771 -121.207378)
			(xy 175.662933 -121.252535) (xy 175.677998 -121.300528) (xy 175.685619 -121.35025) (xy 175.685618 -121.400552)
			(xy 175.685486 -121.401411) (xy 175.825406 -121.401411) (xy 175.825406 -121.349437) (xy 175.833536 -121.298102)
			(xy 175.849597 -121.248672) (xy 175.873193 -121.202362) (xy 175.903743 -121.160314) (xy 175.940494 -121.123563)
			(xy 175.982542 -121.093013) (xy 176.028852 -121.069417) (xy 176.078282 -121.053356) (xy 176.129617 -121.045226)
			(xy 176.181591 -121.045226) (xy 176.232926 -121.053356) (xy 176.282356 -121.069417) (xy 176.328666 -121.093013)
			(xy 176.370714 -121.123563) (xy 176.407465 -121.160314) (xy 176.438015 -121.202362) (xy 176.461611 -121.248672)
			(xy 176.477672 -121.298102) (xy 176.485802 -121.349437) (xy 176.486312 -121.375424) (xy 176.485802 -121.401411)
			(xy 176.625506 -121.401411) (xy 176.625506 -121.349437) (xy 176.633636 -121.298102) (xy 176.649697 -121.248672)
			(xy 176.673293 -121.202362) (xy 176.703843 -121.160314) (xy 176.740594 -121.123563) (xy 176.782642 -121.093013)
			(xy 176.828952 -121.069417) (xy 176.878382 -121.053356) (xy 176.929717 -121.045226) (xy 176.981691 -121.045226)
			(xy 177.033026 -121.053356) (xy 177.082456 -121.069417) (xy 177.128766 -121.093013) (xy 177.170814 -121.123563)
			(xy 177.207565 -121.160314) (xy 177.238115 -121.202362) (xy 177.261711 -121.248672) (xy 177.277772 -121.298102)
			(xy 177.285902 -121.349437) (xy 177.286412 -121.375424) (xy 177.285902 -121.401411) (xy 179.025552 -121.401411)
			(xy 179.025552 -121.349437) (xy 179.033682 -121.298102) (xy 179.049743 -121.248672) (xy 179.073339 -121.202362)
			(xy 179.103889 -121.160314) (xy 179.14064 -121.123563) (xy 179.182688 -121.093013) (xy 179.228998 -121.069417)
			(xy 179.278428 -121.053356) (xy 179.329763 -121.045226) (xy 179.381737 -121.045226) (xy 179.433072 -121.053356)
			(xy 179.482502 -121.069417) (xy 179.528812 -121.093013) (xy 179.57086 -121.123563) (xy 179.607611 -121.160314)
			(xy 179.638161 -121.202362) (xy 179.661757 -121.248672) (xy 179.677818 -121.298102) (xy 179.685948 -121.349437)
			(xy 179.686458 -121.375424) (xy 179.685948 -121.401411) (xy 179.825398 -121.401411) (xy 179.825398 -121.349437)
			(xy 179.833528 -121.298102) (xy 179.849589 -121.248672) (xy 179.873185 -121.202362) (xy 179.903735 -121.160314)
			(xy 179.940486 -121.123563) (xy 179.982534 -121.093013) (xy 180.028844 -121.069417) (xy 180.078274 -121.053356)
			(xy 180.129609 -121.045226) (xy 180.181583 -121.045226) (xy 180.232918 -121.053356) (xy 180.282348 -121.069417)
			(xy 180.328658 -121.093013) (xy 180.370706 -121.123563) (xy 180.407457 -121.160314) (xy 180.438007 -121.202362)
			(xy 180.461603 -121.248672) (xy 180.477664 -121.298102) (xy 180.485794 -121.349437) (xy 180.486304 -121.375424)
			(xy 180.485794 -121.401411) (xy 180.477664 -121.452746) (xy 180.461603 -121.502176) (xy 180.438007 -121.548486)
			(xy 180.407457 -121.590534) (xy 180.370706 -121.627285) (xy 180.328658 -121.657835) (xy 180.282348 -121.681431)
			(xy 180.232918 -121.697492) (xy 180.181583 -121.705622) (xy 180.129609 -121.705622) (xy 180.078274 -121.697492)
			(xy 180.028844 -121.681431) (xy 179.982534 -121.657835) (xy 179.940486 -121.627285) (xy 179.903735 -121.590534)
			(xy 179.873185 -121.548486) (xy 179.849589 -121.502176) (xy 179.833528 -121.452746) (xy 179.825398 -121.401411)
			(xy 179.685948 -121.401411) (xy 179.677818 -121.452746) (xy 179.661757 -121.502176) (xy 179.638161 -121.548486)
			(xy 179.607611 -121.590534) (xy 179.57086 -121.627285) (xy 179.528812 -121.657835) (xy 179.482502 -121.681431)
			(xy 179.433072 -121.697492) (xy 179.381737 -121.705622) (xy 179.329763 -121.705622) (xy 179.278428 -121.697492)
			(xy 179.228998 -121.681431) (xy 179.182688 -121.657835) (xy 179.14064 -121.627285) (xy 179.103889 -121.590534)
			(xy 179.073339 -121.548486) (xy 179.049743 -121.502176) (xy 179.033682 -121.452746) (xy 179.025552 -121.401411)
			(xy 177.285902 -121.401411) (xy 177.277772 -121.452746) (xy 177.261711 -121.502176) (xy 177.238115 -121.548486)
			(xy 177.207565 -121.590534) (xy 177.170814 -121.627285) (xy 177.128766 -121.657835) (xy 177.082456 -121.681431)
			(xy 177.033026 -121.697492) (xy 176.981691 -121.705622) (xy 176.929717 -121.705622) (xy 176.878382 -121.697492)
			(xy 176.828952 -121.681431) (xy 176.782642 -121.657835) (xy 176.740594 -121.627285) (xy 176.703843 -121.590534)
			(xy 176.673293 -121.548486) (xy 176.649697 -121.502176) (xy 176.633636 -121.452746) (xy 176.625506 -121.401411)
			(xy 176.485802 -121.401411) (xy 176.477672 -121.452746) (xy 176.461611 -121.502176) (xy 176.438015 -121.548486)
			(xy 176.407465 -121.590534) (xy 176.370714 -121.627285) (xy 176.328666 -121.657835) (xy 176.282356 -121.681431)
			(xy 176.232926 -121.697492) (xy 176.181591 -121.705622) (xy 176.129617 -121.705622) (xy 176.078282 -121.697492)
			(xy 176.028852 -121.681431) (xy 175.982542 -121.657835) (xy 175.940494 -121.627285) (xy 175.903743 -121.590534)
			(xy 175.873193 -121.548486) (xy 175.849597 -121.502176) (xy 175.833536 -121.452746) (xy 175.825406 -121.401411)
			(xy 175.685486 -121.401411) (xy 175.677998 -121.450274) (xy 175.662932 -121.498267) (xy 175.64077 -121.543424)
			(xy 175.612022 -121.584702) (xy 175.577352 -121.621149) (xy 175.537561 -121.651922) (xy 175.493568 -121.676312)
			(xy 175.446387 -121.693756) (xy 175.397108 -121.70385) (xy 175.372014 -121.705624) (xy 175.36237 -121.706561)
			(xy 175.344798 -121.714685) (xy 175.331493 -121.728748) (xy 175.324355 -121.746743) (xy 175.324008 -121.756424)
			(xy 175.324008 -122.201511) (xy 179.025552 -122.201511) (xy 179.025552 -122.149537) (xy 179.033682 -122.098202)
			(xy 179.049743 -122.048772) (xy 179.073339 -122.002462) (xy 179.103889 -121.960414) (xy 179.14064 -121.923663)
			(xy 179.182688 -121.893113) (xy 179.228998 -121.869517) (xy 179.278428 -121.853456) (xy 179.329763 -121.845326)
			(xy 179.381737 -121.845326) (xy 179.433072 -121.853456) (xy 179.482502 -121.869517) (xy 179.528812 -121.893113)
			(xy 179.57086 -121.923663) (xy 179.607611 -121.960414) (xy 179.638161 -122.002462) (xy 179.661757 -122.048772)
			(xy 179.677818 -122.098202) (xy 179.685948 -122.149537) (xy 179.686458 -122.175524) (xy 179.685948 -122.201511)
			(xy 179.677818 -122.252846) (xy 179.661757 -122.302276) (xy 179.638161 -122.348586) (xy 179.607611 -122.390634)
			(xy 179.57086 -122.427385) (xy 179.528812 -122.457935) (xy 179.482502 -122.481531) (xy 179.433072 -122.497592)
			(xy 179.381737 -122.505722) (xy 179.329763 -122.505722) (xy 179.278428 -122.497592) (xy 179.228998 -122.481531)
			(xy 179.182688 -122.457935) (xy 179.14064 -122.427385) (xy 179.103889 -122.390634) (xy 179.073339 -122.348586)
			(xy 179.049743 -122.302276) (xy 179.033682 -122.252846) (xy 179.025552 -122.201511) (xy 175.324008 -122.201511)
			(xy 175.324008 -122.222514) (xy 175.324519 -122.238125) (xy 175.333855 -122.267915) (xy 175.35177 -122.293482)
			(xy 175.376583 -122.312428) (xy 175.405966 -122.322974) (xy 175.421544 -122.324114) (xy 175.448772 -122.325725)
			(xy 175.502298 -122.336192) (xy 175.553603 -122.354699) (xy 175.601484 -122.380814) (xy 175.644824 -122.413925)
			(xy 175.682607 -122.453259) (xy 175.713949 -122.497894) (xy 175.738119 -122.546787) (xy 175.754549 -122.598794)
			(xy 175.762856 -122.652698) (xy 175.763428 -122.679968) (xy 175.76317 -122.693917) (xy 176.04993 -122.693917)
			(xy 176.04993 -122.640619) (xy 176.057873 -122.587915) (xy 176.073583 -122.536985) (xy 176.096709 -122.488964)
			(xy 176.126733 -122.444927) (xy 176.162985 -122.405856) (xy 176.204656 -122.372625) (xy 176.250814 -122.345976)
			(xy 176.300428 -122.326504) (xy 176.35239 -122.314644) (xy 176.40554 -122.310661) (xy 176.45869 -122.314644)
			(xy 176.510652 -122.326504) (xy 176.560266 -122.345976) (xy 176.606424 -122.372625) (xy 176.648095 -122.405856)
			(xy 176.684347 -122.444927) (xy 176.714371 -122.488964) (xy 176.737497 -122.536985) (xy 176.753207 -122.587915)
			(xy 176.76115 -122.640619) (xy 176.761648 -122.667268) (xy 176.76115 -122.693917) (xy 176.753207 -122.746621)
			(xy 176.737497 -122.797551) (xy 176.714371 -122.845572) (xy 176.684347 -122.889609) (xy 176.648095 -122.92868)
			(xy 176.606424 -122.961911) (xy 176.560266 -122.98856) (xy 176.510652 -123.008032) (xy 176.45869 -123.019892)
			(xy 176.40554 -123.023876) (xy 176.35239 -123.019892) (xy 176.300428 -123.008032) (xy 176.250814 -122.98856)
			(xy 176.204656 -122.961911) (xy 176.162985 -122.92868) (xy 176.126733 -122.889609) (xy 176.096709 -122.845572)
			(xy 176.073583 -122.797551) (xy 176.057873 -122.746621) (xy 176.04993 -122.693917) (xy 175.76317 -122.693917)
			(xy 175.76291 -122.707956) (xy 175.754159 -122.763242) (xy 175.736866 -122.816479) (xy 175.711458 -122.866355)
			(xy 175.67856 -122.911643) (xy 175.638982 -122.951226) (xy 175.5937 -122.98413) (xy 175.543827 -123.009546)
			(xy 175.490593 -123.026847) (xy 175.435308 -123.035606) (xy 175.40732 -123.036076) (xy 175.384327 -123.035747)
			(xy 175.338719 -123.02988) (xy 175.316388 -123.024392) (xy 175.303444 -123.021424) (xy 175.276899 -123.02151)
			(xy 175.251275 -123.028443) (xy 175.228307 -123.041753) (xy 175.209552 -123.060539) (xy 175.196279 -123.083528)
			(xy 175.189388 -123.109164) (xy 175.18888 -123.122436) (xy 175.18888 -124.499878) (xy 175.189341 -124.513624)
			(xy 175.19669 -124.540117) (xy 175.210836 -124.563691) (xy 175.230754 -124.582642) (xy 175.255003 -124.595598)
			(xy 175.281828 -124.601621) (xy 175.309288 -124.600275) (xy 175.322484 -124.596398) (xy 175.351747 -124.587289)
			(xy 175.412238 -124.57747) (xy 175.44288 -124.57684) (xy 175.470133 -124.577302) (xy 175.524083 -124.585057)
			(xy 175.576381 -124.600412) (xy 175.62596 -124.623054) (xy 175.671812 -124.652522) (xy 175.713003 -124.688216)
			(xy 175.748695 -124.72941) (xy 175.77816 -124.775264) (xy 175.800798 -124.824846) (xy 175.816149 -124.877144)
			(xy 175.8239 -124.931095) (xy 175.824388 -124.958348) (xy 176.076862 -124.958348) (xy 176.080933 -124.902726)
			(xy 176.093059 -124.848289) (xy 176.112982 -124.796198) (xy 176.140278 -124.747563) (xy 176.174364 -124.70342)
			(xy 176.214513 -124.664711) (xy 176.259871 -124.63226) (xy 176.309471 -124.606759) (xy 176.362255 -124.588752)
			(xy 176.417098 -124.578622) (xy 176.472832 -124.576585) (xy 176.528269 -124.582685) (xy 176.582226 -124.596791)
			(xy 176.633555 -124.618603) (xy 176.681161 -124.647657) (xy 176.724029 -124.683332) (xy 176.761246 -124.724869)
			(xy 176.792019 -124.771382) (xy 176.815691 -124.821879) (xy 176.831759 -124.875286) (xy 176.839879 -124.930462)
			(xy 176.840388 -124.958348) (xy 176.839879 -124.986234) (xy 176.831759 -125.04141) (xy 176.815691 -125.094817)
			(xy 176.792019 -125.145314) (xy 176.761246 -125.191827) (xy 176.724029 -125.233364) (xy 176.681161 -125.269039)
			(xy 176.633555 -125.298093) (xy 176.582226 -125.319905) (xy 176.528269 -125.334011) (xy 176.472832 -125.340111)
			(xy 176.417098 -125.338074) (xy 176.362255 -125.327944) (xy 176.309471 -125.309937) (xy 176.259871 -125.284436)
			(xy 176.214513 -125.251985) (xy 176.174364 -125.213276) (xy 176.140278 -125.169133) (xy 176.112982 -125.120498)
			(xy 176.093059 -125.068407) (xy 176.080933 -125.01397) (xy 176.076862 -124.958348) (xy 175.824388 -124.958348)
			(xy 175.823855 -124.987296) (xy 175.815117 -125.044529) (xy 175.797833 -125.099784) (xy 175.772401 -125.151795)
			(xy 175.739403 -125.199367) (xy 175.699598 -125.241408) (xy 175.677068 -125.259592) (xy 175.666012 -125.268783)
			(xy 175.649106 -125.292021) (xy 175.639353 -125.319053) (xy 175.63753 -125.347732) (xy 175.643779 -125.375782)
			(xy 175.657606 -125.400974) (xy 175.667416 -125.411484) (xy 176.05248 -125.796548)
		)
		(stroke
			(width 0)
			(type solid)
		)
		(fill yes)
		(layer "In11.Cu")
		(net "VCC_PLD_CORE")
	)
	(gr_poly
		(pts
			(xy 310.2102 -438.277) (xy 310.2102 -427.2788) (xy 307.77942 -420.50462) (xy 306.6288 -419.354) (xy 306.6288 -419.3286)
			(xy 304.0126 -416.7124) (xy 304.0126 -405.638) (xy 303.0982 -404.7236) (xy 303.0982 -403.954742)
			(xy 303.097184 -403.949662) (xy 303.093154 -403.927946) (xy 303.090213 -403.883876) (xy 303.093161 -403.839807)
			(xy 303.097184 -403.81809) (xy 303.0982 -403.81301) (xy 303.0982 -400.929094) (xy 303.097184 -400.924014)
			(xy 303.093151 -400.902298) (xy 303.090203 -400.858227) (xy 303.093144 -400.814157) (xy 303.097184 -400.792442)
			(xy 303.0982 -400.787362) (xy 303.0982 -400.2278) (xy 303.4792 -399.8468) (xy 351.6122 -399.8468)
			(xy 352.094038 -400.328638) (xy 353.306632 -400.328638) (xy 353.310703 -400.273016) (xy 353.322829 -400.218579)
			(xy 353.342752 -400.166488) (xy 353.370048 -400.117853) (xy 353.404134 -400.07371) (xy 353.444283 -400.035001)
			(xy 353.489641 -400.00255) (xy 353.539241 -399.977049) (xy 353.592025 -399.959042) (xy 353.646868 -399.948912)
			(xy 353.702602 -399.946875) (xy 353.758039 -399.952975) (xy 353.811996 -399.967081) (xy 353.863325 -399.988893)
			(xy 353.910931 -400.017947) (xy 353.953799 -400.053622) (xy 353.991016 -400.095159) (xy 354.021789 -400.141672)
			(xy 354.045461 -400.192169) (xy 354.061529 -400.245576) (xy 354.069649 -400.300752) (xy 354.070158 -400.328638)
			(xy 355.862126 -400.328638) (xy 355.866197 -400.273016) (xy 355.878323 -400.218579) (xy 355.898246 -400.166488)
			(xy 355.925542 -400.117853) (xy 355.959628 -400.07371) (xy 355.999777 -400.035001) (xy 356.045135 -400.00255)
			(xy 356.094735 -399.977049) (xy 356.147519 -399.959042) (xy 356.202362 -399.948912) (xy 356.258096 -399.946875)
			(xy 356.313533 -399.952975) (xy 356.36749 -399.967081) (xy 356.418819 -399.988893) (xy 356.466425 -400.017947)
			(xy 356.481134 -400.030188) (xy 359.297222 -400.030188) (xy 359.301293 -399.974566) (xy 359.313419 -399.920129)
			(xy 359.333342 -399.868038) (xy 359.360638 -399.819403) (xy 359.394724 -399.77526) (xy 359.434873 -399.736551)
			(xy 359.480231 -399.7041) (xy 359.529831 -399.678599) (xy 359.582615 -399.660592) (xy 359.637458 -399.650462)
			(xy 359.693192 -399.648425) (xy 359.748629 -399.654525) (xy 359.802586 -399.668631) (xy 359.853915 -399.690443)
			(xy 359.901521 -399.719497) (xy 359.944389 -399.755172) (xy 359.981606 -399.796709) (xy 360.012379 -399.843222)
			(xy 360.036051 -399.893719) (xy 360.052119 -399.947126) (xy 360.060239 -400.002302) (xy 360.060748 -400.030188)
			(xy 360.060239 -400.058074) (xy 360.052119 -400.11325) (xy 360.043485 -400.141948) (xy 360.842812 -400.141948)
			(xy 360.846883 -400.086326) (xy 360.859009 -400.031889) (xy 360.878932 -399.979798) (xy 360.906228 -399.931163)
			(xy 360.940314 -399.88702) (xy 360.980463 -399.848311) (xy 361.025821 -399.81586) (xy 361.075421 -399.790359)
			(xy 361.128205 -399.772352) (xy 361.183048 -399.762222) (xy 361.238782 -399.760185) (xy 361.294219 -399.766285)
			(xy 361.348176 -399.780391) (xy 361.399505 -399.802203) (xy 361.447111 -399.831257) (xy 361.489979 -399.866932)
			(xy 361.527196 -399.908469) (xy 361.557969 -399.954982) (xy 361.581641 -400.005479) (xy 361.597709 -400.058886)
			(xy 361.605829 -400.114062) (xy 361.606338 -400.141948) (xy 361.605829 -400.169834) (xy 361.597709 -400.22501)
			(xy 361.581641 -400.278417) (xy 361.568219 -400.307048) (xy 364.651542 -400.307048) (xy 364.655613 -400.251426)
			(xy 364.667739 -400.196989) (xy 364.687662 -400.144898) (xy 364.714958 -400.096263) (xy 364.749044 -400.05212)
			(xy 364.789193 -400.013411) (xy 364.834551 -399.98096) (xy 364.884151 -399.955459) (xy 364.936935 -399.937452)
			(xy 364.991778 -399.927322) (xy 365.047512 -399.925285) (xy 365.102949 -399.931385) (xy 365.156906 -399.945491)
			(xy 365.208235 -399.967303) (xy 365.255841 -399.996357) (xy 365.298709 -400.032032) (xy 365.335926 -400.073569)
			(xy 365.366699 -400.120082) (xy 365.390371 -400.170579) (xy 365.406439 -400.223986) (xy 365.414559 -400.279162)
			(xy 365.415068 -400.307048) (xy 365.414559 -400.334934) (xy 365.406439 -400.39011) (xy 365.390371 -400.443517)
			(xy 365.366699 -400.494014) (xy 365.335926 -400.540527) (xy 365.298709 -400.582064) (xy 365.255841 -400.617739)
			(xy 365.208235 -400.646793) (xy 365.156906 -400.668605) (xy 365.102949 -400.682711) (xy 365.047512 -400.688811)
			(xy 364.991778 -400.686774) (xy 364.936935 -400.676644) (xy 364.884151 -400.658637) (xy 364.834551 -400.633136)
			(xy 364.789193 -400.600685) (xy 364.749044 -400.561976) (xy 364.714958 -400.517833) (xy 364.687662 -400.469198)
			(xy 364.667739 -400.417107) (xy 364.655613 -400.36267) (xy 364.651542 -400.307048) (xy 361.568219 -400.307048)
			(xy 361.557969 -400.328914) (xy 361.527196 -400.375427) (xy 361.489979 -400.416964) (xy 361.447111 -400.452639)
			(xy 361.399505 -400.481693) (xy 361.348176 -400.503505) (xy 361.294219 -400.517611) (xy 361.238782 -400.523711)
			(xy 361.183048 -400.521674) (xy 361.128205 -400.511544) (xy 361.075421 -400.493537) (xy 361.025821 -400.468036)
			(xy 360.980463 -400.435585) (xy 360.940314 -400.396876) (xy 360.906228 -400.352733) (xy 360.878932 -400.304098)
			(xy 360.859009 -400.252007) (xy 360.846883 -400.19757) (xy 360.842812 -400.141948) (xy 360.043485 -400.141948)
			(xy 360.036051 -400.166657) (xy 360.012379 -400.217154) (xy 359.981606 -400.263667) (xy 359.944389 -400.305204)
			(xy 359.901521 -400.340879) (xy 359.853915 -400.369933) (xy 359.802586 -400.391745) (xy 359.748629 -400.405851)
			(xy 359.693192 -400.411951) (xy 359.637458 -400.409914) (xy 359.582615 -400.399784) (xy 359.529831 -400.381777)
			(xy 359.480231 -400.356276) (xy 359.434873 -400.323825) (xy 359.394724 -400.285116) (xy 359.360638 -400.240973)
			(xy 359.333342 -400.192338) (xy 359.313419 -400.140247) (xy 359.301293 -400.08581) (xy 359.297222 -400.030188)
			(xy 356.481134 -400.030188) (xy 356.509293 -400.053622) (xy 356.54651 -400.095159) (xy 356.577283 -400.141672)
			(xy 356.600955 -400.192169) (xy 356.617023 -400.245576) (xy 356.625143 -400.300752) (xy 356.625652 -400.328638)
			(xy 356.625143 -400.356524) (xy 356.617023 -400.4117) (xy 356.600955 -400.465107) (xy 356.577283 -400.515604)
			(xy 356.54651 -400.562117) (xy 356.509293 -400.603654) (xy 356.466425 -400.639329) (xy 356.418819 -400.668383)
			(xy 356.36749 -400.690195) (xy 356.313533 -400.704301) (xy 356.258096 -400.710401) (xy 356.202362 -400.708364)
			(xy 356.147519 -400.698234) (xy 356.094735 -400.680227) (xy 356.045135 -400.654726) (xy 355.999777 -400.622275)
			(xy 355.959628 -400.583566) (xy 355.925542 -400.539423) (xy 355.898246 -400.490788) (xy 355.878323 -400.438697)
			(xy 355.866197 -400.38426) (xy 355.862126 -400.328638) (xy 354.070158 -400.328638) (xy 354.069649 -400.356524)
			(xy 354.061529 -400.4117) (xy 354.045461 -400.465107) (xy 354.021789 -400.515604) (xy 353.991016 -400.562117)
			(xy 353.953799 -400.603654) (xy 353.910931 -400.639329) (xy 353.863325 -400.668383) (xy 353.811996 -400.690195)
			(xy 353.758039 -400.704301) (xy 353.702602 -400.710401) (xy 353.646868 -400.708364) (xy 353.592025 -400.698234)
			(xy 353.539241 -400.680227) (xy 353.489641 -400.654726) (xy 353.444283 -400.622275) (xy 353.404134 -400.583566)
			(xy 353.370048 -400.539423) (xy 353.342752 -400.490788) (xy 353.322829 -400.438697) (xy 353.310703 -400.38426)
			(xy 353.306632 -400.328638) (xy 352.094038 -400.328638) (xy 353.7204 -401.955) (xy 354.354382 -401.955)
			(xy 354.358453 -401.899378) (xy 354.370579 -401.844941) (xy 354.390502 -401.79285) (xy 354.417798 -401.744215)
			(xy 354.451884 -401.700072) (xy 354.492033 -401.661363) (xy 354.537391 -401.628912) (xy 354.586991 -401.603411)
			(xy 354.639775 -401.585404) (xy 354.694618 -401.575274) (xy 354.750352 -401.573237) (xy 354.805789 -401.579337)
			(xy 354.859746 -401.593443) (xy 354.911075 -401.615255) (xy 354.958681 -401.644309) (xy 355.001549 -401.679984)
			(xy 355.038766 -401.721521) (xy 355.069539 -401.768034) (xy 355.093211 -401.818531) (xy 355.109279 -401.871938)
			(xy 355.117399 -401.927114) (xy 355.117908 -401.955) (xy 355.117399 -401.982886) (xy 355.109279 -402.038062)
			(xy 355.093211 -402.091469) (xy 355.069539 -402.141966) (xy 355.038766 -402.188479) (xy 355.033807 -402.194014)
			(xy 359.851196 -402.194014) (xy 359.855267 -402.138392) (xy 359.867393 -402.083955) (xy 359.887316 -402.031864)
			(xy 359.914612 -401.983229) (xy 359.948698 -401.939086) (xy 359.988847 -401.900377) (xy 360.034205 -401.867926)
			(xy 360.083805 -401.842425) (xy 360.136589 -401.824418) (xy 360.191432 -401.814288) (xy 360.247166 -401.812251)
			(xy 360.302603 -401.818351) (xy 360.35656 -401.832457) (xy 360.405844 -401.8534) (xy 360.978702 -401.8534)
			(xy 360.982773 -401.797778) (xy 360.994899 -401.743341) (xy 361.014822 -401.69125) (xy 361.042118 -401.642615)
			(xy 361.076204 -401.598472) (xy 361.116353 -401.559763) (xy 361.161711 -401.527312) (xy 361.211311 -401.501811)
			(xy 361.264095 -401.483804) (xy 361.318938 -401.473674) (xy 361.374672 -401.471637) (xy 361.430109 -401.477737)
			(xy 361.484066 -401.491843) (xy 361.535395 -401.513655) (xy 361.583001 -401.542709) (xy 361.625869 -401.578384)
			(xy 361.663086 -401.619921) (xy 361.693859 -401.666434) (xy 361.695536 -401.670012) (xy 362.432344 -401.670012)
			(xy 362.436415 -401.61439) (xy 362.448541 -401.559953) (xy 362.468464 -401.507862) (xy 362.49576 -401.459227)
			(xy 362.529846 -401.415084) (xy 362.569995 -401.376375) (xy 362.615353 -401.343924) (xy 362.664953 -401.318423)
			(xy 362.717737 -401.300416) (xy 362.77258 -401.290286) (xy 362.828314 -401.288249) (xy 362.883751 -401.294349)
			(xy 362.937708 -401.308455) (xy 362.989037 -401.330267) (xy 363.036643 -401.359321) (xy 363.079511 -401.394996)
			(xy 363.116728 -401.436533) (xy 363.147501 -401.483046) (xy 363.171173 -401.533543) (xy 363.187241 -401.58695)
			(xy 363.195361 -401.642126) (xy 363.19587 -401.670012) (xy 363.195361 -401.697898) (xy 363.187241 -401.753074)
			(xy 363.171173 -401.806481) (xy 363.147501 -401.856978) (xy 363.116728 -401.903491) (xy 363.079511 -401.945028)
			(xy 363.036643 -401.980703) (xy 362.989037 -402.009757) (xy 362.937708 -402.031569) (xy 362.883751 -402.045675)
			(xy 362.828314 -402.051775) (xy 362.77258 -402.049738) (xy 362.717737 -402.039608) (xy 362.664953 -402.021601)
			(xy 362.615353 -401.9961) (xy 362.569995 -401.963649) (xy 362.529846 -401.92494) (xy 362.49576 -401.880797)
			(xy 362.468464 -401.832162) (xy 362.448541 -401.780071) (xy 362.436415 -401.725634) (xy 362.432344 -401.670012)
			(xy 361.695536 -401.670012) (xy 361.717531 -401.716931) (xy 361.733599 -401.770338) (xy 361.741719 -401.825514)
			(xy 361.742228 -401.8534) (xy 361.741719 -401.881286) (xy 361.733599 -401.936462) (xy 361.717531 -401.989869)
			(xy 361.693859 -402.040366) (xy 361.663086 -402.086879) (xy 361.625869 -402.128416) (xy 361.583001 -402.164091)
			(xy 361.535395 -402.193145) (xy 361.484066 -402.214957) (xy 361.430109 -402.229063) (xy 361.374672 -402.235163)
			(xy 361.318938 -402.233126) (xy 361.264095 -402.222996) (xy 361.211311 -402.204989) (xy 361.161711 -402.179488)
			(xy 361.116353 -402.147037) (xy 361.076204 -402.108328) (xy 361.042118 -402.064185) (xy 361.014822 -402.01555)
			(xy 360.994899 -401.963459) (xy 360.982773 -401.909022) (xy 360.978702 -401.8534) (xy 360.405844 -401.8534)
			(xy 360.407889 -401.854269) (xy 360.455495 -401.883323) (xy 360.498363 -401.918998) (xy 360.53558 -401.960535)
			(xy 360.566353 -402.007048) (xy 360.590025 -402.057545) (xy 360.606093 -402.110952) (xy 360.614213 -402.166128)
			(xy 360.614722 -402.194014) (xy 360.614213 -402.2219) (xy 360.606093 -402.277076) (xy 360.590025 -402.330483)
			(xy 360.566353 -402.38098) (xy 360.53558 -402.427493) (xy 360.498363 -402.46903) (xy 360.455495 -402.504705)
			(xy 360.407889 -402.533759) (xy 360.35656 -402.555571) (xy 360.302603 -402.569677) (xy 360.247166 -402.575777)
			(xy 360.191432 -402.57374) (xy 360.136589 -402.56361) (xy 360.083805 -402.545603) (xy 360.034205 -402.520102)
			(xy 359.988847 -402.487651) (xy 359.948698 -402.448942) (xy 359.914612 -402.404799) (xy 359.887316 -402.356164)
			(xy 359.867393 -402.304073) (xy 359.855267 -402.249636) (xy 359.851196 -402.194014) (xy 355.033807 -402.194014)
			(xy 355.001549 -402.230016) (xy 354.958681 -402.265691) (xy 354.911075 -402.294745) (xy 354.859746 -402.316557)
			(xy 354.805789 -402.330663) (xy 354.750352 -402.336763) (xy 354.694618 -402.334726) (xy 354.639775 -402.324596)
			(xy 354.586991 -402.306589) (xy 354.537391 -402.281088) (xy 354.492033 -402.248637) (xy 354.451884 -402.209928)
			(xy 354.417798 -402.165785) (xy 354.390502 -402.11715) (xy 354.370579 -402.065059) (xy 354.358453 -402.010622)
			(xy 354.354382 -401.955) (xy 353.7204 -401.955) (xy 354.2284 -402.463) (xy 354.2284 -404.2156) (xy 357.046782 -404.2156)
			(xy 357.050853 -404.159978) (xy 357.062979 -404.105541) (xy 357.082902 -404.05345) (xy 357.110198 -404.004815)
			(xy 357.144284 -403.960672) (xy 357.184433 -403.921963) (xy 357.229791 -403.889512) (xy 357.279391 -403.864011)
			(xy 357.332175 -403.846004) (xy 357.387018 -403.835874) (xy 357.442752 -403.833837) (xy 357.498189 -403.839937)
			(xy 357.552146 -403.854043) (xy 357.603475 -403.875855) (xy 357.651081 -403.904909) (xy 357.693949 -403.940584)
			(xy 357.731166 -403.982121) (xy 357.761939 -404.028634) (xy 357.785611 -404.079131) (xy 357.801679 -404.132538)
			(xy 357.809799 -404.187714) (xy 357.810308 -404.2156) (xy 357.809799 -404.243486) (xy 357.801679 -404.298662)
			(xy 357.785611 -404.352069) (xy 357.761939 -404.402566) (xy 357.731166 -404.449079) (xy 357.693949 -404.490616)
			(xy 357.651081 -404.526291) (xy 357.603475 -404.555345) (xy 357.552146 -404.577157) (xy 357.498189 -404.591263)
			(xy 357.442752 -404.597363) (xy 357.387018 -404.595326) (xy 357.332175 -404.585196) (xy 357.279391 -404.567189)
			(xy 357.229791 -404.541688) (xy 357.184433 -404.509237) (xy 357.144284 -404.470528) (xy 357.110198 -404.426385)
			(xy 357.082902 -404.37775) (xy 357.062979 -404.325659) (xy 357.050853 -404.271222) (xy 357.046782 -404.2156)
			(xy 354.2284 -404.2156) (xy 354.2284 -404.876) (xy 354.354382 -404.876) (xy 354.358453 -404.820378)
			(xy 354.370579 -404.765941) (xy 354.390502 -404.71385) (xy 354.417798 -404.665215) (xy 354.451884 -404.621072)
			(xy 354.492033 -404.582363) (xy 354.537391 -404.549912) (xy 354.586991 -404.524411) (xy 354.639775 -404.506404)
			(xy 354.694618 -404.496274) (xy 354.750352 -404.494237) (xy 354.805789 -404.500337) (xy 354.859746 -404.514443)
			(xy 354.911075 -404.536255) (xy 354.958681 -404.565309) (xy 355.001549 -404.600984) (xy 355.038766 -404.642521)
			(xy 355.069539 -404.689034) (xy 355.093211 -404.739531) (xy 355.109279 -404.792938) (xy 355.117399 -404.848114)
			(xy 355.117908 -404.876) (xy 355.117399 -404.903886) (xy 355.109279 -404.959062) (xy 355.093211 -405.012469)
			(xy 355.069539 -405.062966) (xy 355.038766 -405.109479) (xy 355.001549 -405.151016) (xy 354.958681 -405.186691)
			(xy 354.911075 -405.215745) (xy 354.873764 -405.2316) (xy 367.054892 -405.2316) (xy 367.055378 -405.204349)
			(xy 367.063134 -405.150401) (xy 367.078489 -405.098106) (xy 367.101131 -405.048529) (xy 367.130597 -405.002679)
			(xy 367.166288 -404.961488) (xy 367.207479 -404.925797) (xy 367.253329 -404.896331) (xy 367.302906 -404.873689)
			(xy 367.355201 -404.858334) (xy 367.409149 -404.850578) (xy 367.463651 -404.850578) (xy 367.517599 -404.858334)
			(xy 367.569894 -404.873689) (xy 367.619471 -404.896331) (xy 367.665321 -404.925797) (xy 367.706512 -404.961488)
			(xy 367.742203 -405.002679) (xy 367.771669 -405.048529) (xy 367.794311 -405.098106) (xy 367.809666 -405.150401)
			(xy 367.817422 -405.204349) (xy 367.817908 -405.2316) (xy 367.817427 -405.259463) (xy 367.811742 -405.298148)
			(xy 368.832382 -405.298148) (xy 368.836453 -405.242526) (xy 368.848579 -405.188089) (xy 368.868502 -405.135998)
			(xy 368.895798 -405.087363) (xy 368.929884 -405.04322) (xy 368.970033 -405.004511) (xy 369.015391 -404.97206)
			(xy 369.064991 -404.946559) (xy 369.117775 -404.928552) (xy 369.172618 -404.918422) (xy 369.228352 -404.916385)
			(xy 369.283789 -404.922485) (xy 369.337746 -404.936591) (xy 369.389075 -404.958403) (xy 369.436681 -404.987457)
			(xy 369.479549 -405.023132) (xy 369.516766 -405.064669) (xy 369.547539 -405.111182) (xy 369.571211 -405.161679)
			(xy 369.587279 -405.215086) (xy 369.595399 -405.270262) (xy 369.595908 -405.298148) (xy 369.595399 -405.326034)
			(xy 369.587279 -405.38121) (xy 369.571211 -405.434617) (xy 369.547539 -405.485114) (xy 369.516766 -405.531627)
			(xy 369.479549 -405.573164) (xy 369.436681 -405.608839) (xy 369.389075 -405.637893) (xy 369.337746 -405.659705)
			(xy 369.283789 -405.673811) (xy 369.228352 -405.679911) (xy 369.172618 -405.677874) (xy 369.117775 -405.667744)
			(xy 369.064991 -405.649737) (xy 369.015391 -405.624236) (xy 368.970033 -405.591785) (xy 368.929884 -405.553076)
			(xy 368.895798 -405.508933) (xy 368.868502 -405.460298) (xy 368.848579 -405.408207) (xy 368.836453 -405.35377)
			(xy 368.832382 -405.298148) (xy 367.811742 -405.298148) (xy 367.809325 -405.314596) (xy 367.793293 -405.367965)
			(xy 367.769671 -405.418436) (xy 367.738962 -405.464937) (xy 367.701818 -405.506478) (xy 367.680748 -405.524716)
			(xy 367.669232 -405.535019) (xy 367.65246 -405.560952) (xy 367.644208 -405.590714) (xy 367.645232 -405.621581)
			(xy 367.655439 -405.65073) (xy 367.673893 -405.675494) (xy 367.686082 -405.68499) (xy 367.706621 -405.700426)
			(xy 367.743754 -405.735937) (xy 367.775785 -405.776111) (xy 367.802135 -405.82022) (xy 367.822326 -405.867466)
			(xy 367.835993 -405.916995) (xy 367.842889 -405.96791) (xy 367.843308 -405.9936) (xy 367.842822 -406.020851)
			(xy 367.835066 -406.074799) (xy 367.819711 -406.127094) (xy 367.797069 -406.176671) (xy 367.767603 -406.222521)
			(xy 367.731912 -406.263712) (xy 367.690721 -406.299403) (xy 367.644871 -406.328869) (xy 367.595294 -406.351511)
			(xy 367.542999 -406.366866) (xy 367.489051 -406.374622) (xy 367.434549 -406.374622) (xy 367.380601 -406.366866)
			(xy 367.328306 -406.351511) (xy 367.278729 -406.328869) (xy 367.232879 -406.299403) (xy 367.191688 -406.263712)
			(xy 367.155997 -406.222521) (xy 367.126531 -406.176671) (xy 367.103889 -406.127094) (xy 367.088534 -406.074799)
			(xy 367.080778 -406.020851) (xy 367.080292 -405.9936) (xy 367.080773 -405.965737) (xy 367.088875 -405.910604)
			(xy 367.104907 -405.857235) (xy 367.128529 -405.806764) (xy 367.159238 -405.760263) (xy 367.196382 -405.718722)
			(xy 367.217452 -405.700484) (xy 367.228968 -405.690181) (xy 367.24574 -405.664248) (xy 367.253992 -405.634486)
			(xy 367.252968 -405.603619) (xy 367.242761 -405.57447) (xy 367.224307 -405.549706) (xy 367.212118 -405.54021)
			(xy 367.191579 -405.524774) (xy 367.154446 -405.489263) (xy 367.122415 -405.449089) (xy 367.096065 -405.40498)
			(xy 367.075874 -405.357734) (xy 367.062207 -405.308205) (xy 367.055311 -405.25729) (xy 367.054892 -405.2316)
			(xy 354.873764 -405.2316) (xy 354.859746 -405.237557) (xy 354.805789 -405.251663) (xy 354.750352 -405.257763)
			(xy 354.694618 -405.255726) (xy 354.639775 -405.245596) (xy 354.586991 -405.227589) (xy 354.537391 -405.202088)
			(xy 354.492033 -405.169637) (xy 354.451884 -405.130928) (xy 354.417798 -405.086785) (xy 354.390502 -405.03815)
			(xy 354.370579 -404.986059) (xy 354.358453 -404.931622) (xy 354.354382 -404.876) (xy 354.2284 -404.876)
			(xy 354.2284 -405.8412) (xy 354.887782 -405.8412) (xy 354.891853 -405.785578) (xy 354.903979 -405.731141)
			(xy 354.923902 -405.67905) (xy 354.951198 -405.630415) (xy 354.985284 -405.586272) (xy 355.025433 -405.547563)
			(xy 355.070791 -405.515112) (xy 355.120391 -405.489611) (xy 355.173175 -405.471604) (xy 355.228018 -405.461474)
			(xy 355.283752 -405.459437) (xy 355.339189 -405.465537) (xy 355.393146 -405.479643) (xy 355.444475 -405.501455)
			(xy 355.492081 -405.530509) (xy 355.534949 -405.566184) (xy 355.572166 -405.607721) (xy 355.602939 -405.654234)
			(xy 355.626611 -405.704731) (xy 355.642679 -405.758138) (xy 355.650799 -405.813314) (xy 355.651308 -405.8412)
			(xy 355.650799 -405.869086) (xy 355.642679 -405.924262) (xy 355.626611 -405.977669) (xy 355.619143 -405.9936)
			(xy 364.946182 -405.9936) (xy 364.950253 -405.937978) (xy 364.962379 -405.883541) (xy 364.982302 -405.83145)
			(xy 365.009598 -405.782815) (xy 365.043684 -405.738672) (xy 365.083833 -405.699963) (xy 365.129191 -405.667512)
			(xy 365.178791 -405.642011) (xy 365.231575 -405.624004) (xy 365.286418 -405.613874) (xy 365.342152 -405.611837)
			(xy 365.397589 -405.617937) (xy 365.451546 -405.632043) (xy 365.502875 -405.653855) (xy 365.550481 -405.682909)
			(xy 365.593349 -405.718584) (xy 365.630566 -405.760121) (xy 365.661339 -405.806634) (xy 365.685011 -405.857131)
			(xy 365.701079 -405.910538) (xy 365.709199 -405.965714) (xy 365.709708 -405.9936) (xy 365.709199 -406.021486)
			(xy 365.701079 -406.076662) (xy 365.685011 -406.130069) (xy 365.661339 -406.180566) (xy 365.630566 -406.227079)
			(xy 365.593349 -406.268616) (xy 365.550481 -406.304291) (xy 365.502875 -406.333345) (xy 365.451546 -406.355157)
			(xy 365.397589 -406.369263) (xy 365.342152 -406.375363) (xy 365.286418 -406.373326) (xy 365.231575 -406.363196)
			(xy 365.178791 -406.345189) (xy 365.129191 -406.319688) (xy 365.083833 -406.287237) (xy 365.043684 -406.248528)
			(xy 365.009598 -406.204385) (xy 364.982302 -406.15575) (xy 364.962379 -406.103659) (xy 364.950253 -406.049222)
			(xy 364.946182 -405.9936) (xy 355.619143 -405.9936) (xy 355.602939 -406.028166) (xy 355.572166 -406.074679)
			(xy 355.534949 -406.116216) (xy 355.492081 -406.151891) (xy 355.444475 -406.180945) (xy 355.393146 -406.202757)
			(xy 355.339189 -406.216863) (xy 355.283752 -406.222963) (xy 355.228018 -406.220926) (xy 355.173175 -406.210796)
			(xy 355.120391 -406.192789) (xy 355.070791 -406.167288) (xy 355.025433 -406.134837) (xy 354.985284 -406.096128)
			(xy 354.951198 -406.051985) (xy 354.923902 -406.00335) (xy 354.903979 -405.951259) (xy 354.891853 -405.896822)
			(xy 354.887782 -405.8412) (xy 354.2284 -405.8412) (xy 354.2284 -407.233628) (xy 358.029762 -407.233628)
			(xy 358.033833 -407.178006) (xy 358.045959 -407.123569) (xy 358.065882 -407.071478) (xy 358.093178 -407.022843)
			(xy 358.127264 -406.9787) (xy 358.167413 -406.939991) (xy 358.212771 -406.90754) (xy 358.262371 -406.882039)
			(xy 358.315155 -406.864032) (xy 358.369998 -406.853902) (xy 358.425732 -406.851865) (xy 358.481169 -406.857965)
			(xy 358.535126 -406.872071) (xy 358.586455 -406.893883) (xy 358.634061 -406.922937) (xy 358.676929 -406.958612)
			(xy 358.714146 -407.000149) (xy 358.744919 -407.046662) (xy 358.768591 -407.097159) (xy 358.784659 -407.150566)
			(xy 358.792779 -407.205742) (xy 358.793195 -407.228548) (xy 361.994702 -407.228548) (xy 361.998773 -407.172926)
			(xy 362.010899 -407.118489) (xy 362.030822 -407.066398) (xy 362.058118 -407.017763) (xy 362.092204 -406.97362)
			(xy 362.132353 -406.934911) (xy 362.177711 -406.90246) (xy 362.227311 -406.876959) (xy 362.280095 -406.858952)
			(xy 362.334938 -406.848822) (xy 362.390672 -406.846785) (xy 362.446109 -406.852885) (xy 362.500066 -406.866991)
			(xy 362.551395 -406.888803) (xy 362.599001 -406.917857) (xy 362.641869 -406.953532) (xy 362.679086 -406.995069)
			(xy 362.709859 -407.041582) (xy 362.733531 -407.092079) (xy 362.749599 -407.145486) (xy 362.757719 -407.200662)
			(xy 362.758228 -407.228548) (xy 362.757719 -407.256434) (xy 362.749599 -407.31161) (xy 362.733531 -407.365017)
			(xy 362.709859 -407.415514) (xy 362.679086 -407.462027) (xy 362.641869 -407.503564) (xy 362.599001 -407.539239)
			(xy 362.551395 -407.568293) (xy 362.500066 -407.590105) (xy 362.446109 -407.604211) (xy 362.390672 -407.610311)
			(xy 362.334938 -407.608274) (xy 362.280095 -407.598144) (xy 362.227311 -407.580137) (xy 362.177711 -407.554636)
			(xy 362.132353 -407.522185) (xy 362.092204 -407.483476) (xy 362.058118 -407.439333) (xy 362.030822 -407.390698)
			(xy 362.010899 -407.338607) (xy 361.998773 -407.28417) (xy 361.994702 -407.228548) (xy 358.793195 -407.228548)
			(xy 358.793288 -407.233628) (xy 358.792779 -407.261514) (xy 358.784659 -407.31669) (xy 358.768591 -407.370097)
			(xy 358.744919 -407.420594) (xy 358.714146 -407.467107) (xy 358.676929 -407.508644) (xy 358.634061 -407.544319)
			(xy 358.586455 -407.573373) (xy 358.535126 -407.595185) (xy 358.481169 -407.609291) (xy 358.425732 -407.615391)
			(xy 358.369998 -407.613354) (xy 358.315155 -407.603224) (xy 358.262371 -407.585217) (xy 358.212771 -407.559716)
			(xy 358.167413 -407.527265) (xy 358.127264 -407.488556) (xy 358.093178 -407.444413) (xy 358.065882 -407.395778)
			(xy 358.045959 -407.343687) (xy 358.033833 -407.28925) (xy 358.029762 -407.233628) (xy 354.2284 -407.233628)
			(xy 354.2284 -407.666952) (xy 354.228895 -407.681728) (xy 354.237347 -407.710045) (xy 354.253557 -407.734755)
			(xy 354.276166 -407.753785) (xy 354.303279 -407.765541) (xy 354.332624 -407.769037) (xy 354.347272 -407.767028)
			(xy 354.363464 -407.764406) (xy 354.396148 -407.761608) (xy 354.41255 -407.76144) (xy 354.439802 -407.7619)
			(xy 354.493751 -407.76965) (xy 354.546049 -407.785) (xy 354.595629 -407.807637) (xy 354.641482 -407.8371)
			(xy 354.682676 -407.872789) (xy 354.71837 -407.913978) (xy 354.747839 -407.959827) (xy 354.770483 -408.009405)
			(xy 354.785839 -408.0617) (xy 354.793597 -408.115648) (xy 354.793597 -408.170152) (xy 354.785839 -408.2241)
			(xy 354.770483 -408.276395) (xy 354.747839 -408.325973) (xy 354.71837 -408.371822) (xy 354.682676 -408.413011)
			(xy 354.641482 -408.4487) (xy 354.595629 -408.478163) (xy 354.546049 -408.5008) (xy 354.493751 -408.51615)
			(xy 354.439802 -408.5239) (xy 354.41255 -408.524456) (xy 354.396148 -408.524295) (xy 354.363464 -408.521493)
			(xy 354.347272 -408.518868) (xy 354.332628 -408.516849) (xy 354.303291 -408.520368) (xy 354.276187 -408.532133)
			(xy 354.261772 -408.544268) (xy 362.901482 -408.544268) (xy 362.905553 -408.488646) (xy 362.917679 -408.434209)
			(xy 362.937602 -408.382118) (xy 362.964898 -408.333483) (xy 362.998984 -408.28934) (xy 363.039133 -408.250631)
			(xy 363.084491 -408.21818) (xy 363.134091 -408.192679) (xy 363.186875 -408.174672) (xy 363.241718 -408.164542)
			(xy 363.297452 -408.162505) (xy 363.352889 -408.168605) (xy 363.406846 -408.182711) (xy 363.458175 -408.204523)
			(xy 363.505781 -408.233577) (xy 363.548649 -408.269252) (xy 363.585866 -408.310789) (xy 363.616639 -408.357302)
			(xy 363.640311 -408.407799) (xy 363.656379 -408.461206) (xy 363.664499 -408.516382) (xy 363.665008 -408.544268)
			(xy 363.664499 -408.572154) (xy 363.656379 -408.62733) (xy 363.640311 -408.680737) (xy 363.616639 -408.731234)
			(xy 363.585866 -408.777747) (xy 363.548649 -408.819284) (xy 363.505781 -408.854959) (xy 363.458175 -408.884013)
			(xy 363.406846 -408.905825) (xy 363.352889 -408.919931) (xy 363.297452 -408.926031) (xy 363.241718 -408.923994)
			(xy 363.186875 -408.913864) (xy 363.134091 -408.895857) (xy 363.084491 -408.870356) (xy 363.039133 -408.837905)
			(xy 362.998984 -408.799196) (xy 362.964898 -408.755053) (xy 362.937602 -408.706418) (xy 362.917679 -408.654327)
			(xy 362.905553 -408.59989) (xy 362.901482 -408.544268) (xy 354.261772 -408.544268) (xy 354.253582 -408.551162)
			(xy 354.237367 -408.575863) (xy 354.228897 -408.60417) (xy 354.2284 -408.618944) (xy 354.2284 -409.194)
			(xy 364.946182 -409.194) (xy 364.950253 -409.138378) (xy 364.962379 -409.083941) (xy 364.982302 -409.03185)
			(xy 365.009598 -408.983215) (xy 365.043684 -408.939072) (xy 365.083833 -408.900363) (xy 365.129191 -408.867912)
			(xy 365.178791 -408.842411) (xy 365.231575 -408.824404) (xy 365.286418 -408.814274) (xy 365.342152 -408.812237)
			(xy 365.397589 -408.818337) (xy 365.451546 -408.832443) (xy 365.502875 -408.854255) (xy 365.550481 -408.883309)
			(xy 365.593349 -408.918984) (xy 365.630566 -408.960521) (xy 365.661339 -409.007034) (xy 365.685011 -409.057531)
			(xy 365.698482 -409.102306) (xy 367.101626 -409.102306) (xy 367.105697 -409.046684) (xy 367.117823 -408.992247)
			(xy 367.137746 -408.940156) (xy 367.165042 -408.891521) (xy 367.199128 -408.847378) (xy 367.239277 -408.808669)
			(xy 367.284635 -408.776218) (xy 367.334235 -408.750717) (xy 367.387019 -408.73271) (xy 367.441862 -408.72258)
			(xy 367.497596 -408.720543) (xy 367.553033 -408.726643) (xy 367.60699 -408.740749) (xy 367.658319 -408.762561)
			(xy 367.705925 -408.791615) (xy 367.748793 -408.82729) (xy 367.78601 -408.868827) (xy 367.816783 -408.91534)
			(xy 367.840455 -408.965837) (xy 367.856523 -409.019244) (xy 367.864643 -409.07442) (xy 367.865152 -409.102306)
			(xy 367.864643 -409.130192) (xy 367.856523 -409.185368) (xy 367.840455 -409.238775) (xy 367.816783 -409.289272)
			(xy 367.78601 -409.335785) (xy 367.748793 -409.377322) (xy 367.705925 -409.412997) (xy 367.658319 -409.442051)
			(xy 367.60699 -409.463863) (xy 367.553033 -409.477969) (xy 367.497596 -409.484069) (xy 367.441862 -409.482032)
			(xy 367.387019 -409.471902) (xy 367.334235 -409.453895) (xy 367.284635 -409.428394) (xy 367.239277 -409.395943)
			(xy 367.199128 -409.357234) (xy 367.165042 -409.313091) (xy 367.137746 -409.264456) (xy 367.117823 -409.212365)
			(xy 367.105697 -409.157928) (xy 367.101626 -409.102306) (xy 365.698482 -409.102306) (xy 365.701079 -409.110938)
			(xy 365.709199 -409.166114) (xy 365.709708 -409.194) (xy 365.709199 -409.221886) (xy 365.701079 -409.277062)
			(xy 365.685011 -409.330469) (xy 365.661339 -409.380966) (xy 365.630566 -409.427479) (xy 365.593349 -409.469016)
			(xy 365.550481 -409.504691) (xy 365.502875 -409.533745) (xy 365.451546 -409.555557) (xy 365.397589 -409.569663)
			(xy 365.342152 -409.575763) (xy 365.286418 -409.573726) (xy 365.231575 -409.563596) (xy 365.178791 -409.545589)
			(xy 365.129191 -409.520088) (xy 365.083833 -409.487637) (xy 365.043684 -409.448928) (xy 365.009598 -409.404785)
			(xy 364.982302 -409.35615) (xy 364.962379 -409.304059) (xy 364.950253 -409.249622) (xy 364.946182 -409.194)
			(xy 354.2284 -409.194) (xy 354.2284 -411.458918) (xy 355.548182 -411.458918) (xy 355.552253 -411.403296)
			(xy 355.564379 -411.348859) (xy 355.584302 -411.296768) (xy 355.611598 -411.248133) (xy 355.645684 -411.20399)
			(xy 355.685833 -411.165281) (xy 355.731191 -411.13283) (xy 355.780791 -411.107329) (xy 355.833575 -411.089322)
			(xy 355.888418 -411.079192) (xy 355.944152 -411.077155) (xy 355.999589 -411.083255) (xy 356.053546 -411.097361)
			(xy 356.104875 -411.119173) (xy 356.152481 -411.148227) (xy 356.195349 -411.183902) (xy 356.232566 -411.225439)
			(xy 356.263339 -411.271952) (xy 356.287011 -411.322449) (xy 356.303079 -411.375856) (xy 356.311199 -411.431032)
			(xy 356.311708 -411.458918) (xy 356.311199 -411.486804) (xy 356.303079 -411.54198) (xy 356.298801 -411.5562)
			(xy 365.835182 -411.5562) (xy 365.839253 -411.500578) (xy 365.851379 -411.446141) (xy 365.871302 -411.39405)
			(xy 365.898598 -411.345415) (xy 365.932684 -411.301272) (xy 365.972833 -411.262563) (xy 366.018191 -411.230112)
			(xy 366.067791 -411.204611) (xy 366.120575 -411.186604) (xy 366.175418 -411.176474) (xy 366.231152 -411.174437)
			(xy 366.286589 -411.180537) (xy 366.340546 -411.194643) (xy 366.391875 -411.216455) (xy 366.439481 -411.245509)
			(xy 366.482349 -411.281184) (xy 366.519566 -411.322721) (xy 366.550339 -411.369234) (xy 366.574011 -411.419731)
			(xy 366.590079 -411.473138) (xy 366.598199 -411.528314) (xy 366.598708 -411.5562) (xy 366.598199 -411.584086)
			(xy 366.590079 -411.639262) (xy 366.574011 -411.692669) (xy 366.550339 -411.743166) (xy 366.519566 -411.789679)
			(xy 366.482349 -411.831216) (xy 366.439481 -411.866891) (xy 366.391875 -411.895945) (xy 366.340546 -411.917757)
			(xy 366.286589 -411.931863) (xy 366.231152 -411.937963) (xy 366.175418 -411.935926) (xy 366.120575 -411.925796)
			(xy 366.067791 -411.907789) (xy 366.018191 -411.882288) (xy 365.972833 -411.849837) (xy 365.932684 -411.811128)
			(xy 365.898598 -411.766985) (xy 365.871302 -411.71835) (xy 365.851379 -411.666259) (xy 365.839253 -411.611822)
			(xy 365.835182 -411.5562) (xy 356.298801 -411.5562) (xy 356.287011 -411.595387) (xy 356.263339 -411.645884)
			(xy 356.232566 -411.692397) (xy 356.195349 -411.733934) (xy 356.152481 -411.769609) (xy 356.104875 -411.798663)
			(xy 356.053546 -411.820475) (xy 355.999589 -411.834581) (xy 355.944152 -411.840681) (xy 355.888418 -411.838644)
			(xy 355.833575 -411.828514) (xy 355.780791 -411.810507) (xy 355.731191 -411.785006) (xy 355.685833 -411.752555)
			(xy 355.645684 -411.713846) (xy 355.611598 -411.669703) (xy 355.584302 -411.621068) (xy 355.564379 -411.568977)
			(xy 355.552253 -411.51454) (xy 355.548182 -411.458918) (xy 354.2284 -411.458918) (xy 354.2284 -412.341314)
			(xy 362.647482 -412.341314) (xy 362.651553 -412.285692) (xy 362.663679 -412.231255) (xy 362.683602 -412.179164)
			(xy 362.710898 -412.130529) (xy 362.744984 -412.086386) (xy 362.785133 -412.047677) (xy 362.830491 -412.015226)
			(xy 362.880091 -411.989725) (xy 362.932875 -411.971718) (xy 362.987718 -411.961588) (xy 363.043452 -411.959551)
			(xy 363.098889 -411.965651) (xy 363.152846 -411.979757) (xy 363.204175 -412.001569) (xy 363.251781 -412.030623)
			(xy 363.294649 -412.066298) (xy 363.331866 -412.107835) (xy 363.362639 -412.154348) (xy 363.386311 -412.204845)
			(xy 363.402379 -412.258252) (xy 363.410499 -412.313428) (xy 363.411008 -412.341314) (xy 363.410499 -412.3692)
			(xy 363.402379 -412.424376) (xy 363.386311 -412.477783) (xy 363.362639 -412.52828) (xy 363.331866 -412.574793)
			(xy 363.294649 -412.61633) (xy 363.251781 -412.652005) (xy 363.204175 -412.681059) (xy 363.152846 -412.702871)
			(xy 363.098889 -412.716977) (xy 363.043452 -412.723077) (xy 362.987718 -412.72104) (xy 362.932875 -412.71091)
			(xy 362.880091 -412.692903) (xy 362.830491 -412.667402) (xy 362.785133 -412.634951) (xy 362.744984 -412.596242)
			(xy 362.710898 -412.552099) (xy 362.683602 -412.503464) (xy 362.663679 -412.451373) (xy 362.651553 -412.396936)
			(xy 362.647482 -412.341314) (xy 354.2284 -412.341314) (xy 354.2284 -413.095948) (xy 355.217982 -413.095948)
			(xy 355.222053 -413.040326) (xy 355.234179 -412.985889) (xy 355.254102 -412.933798) (xy 355.281398 -412.885163)
			(xy 355.315484 -412.84102) (xy 355.355633 -412.802311) (xy 355.400991 -412.76986) (xy 355.450591 -412.744359)
			(xy 355.503375 -412.726352) (xy 355.558218 -412.716222) (xy 355.613952 -412.714185) (xy 355.669389 -412.720285)
			(xy 355.723346 -412.734391) (xy 355.774675 -412.756203) (xy 355.822281 -412.785257) (xy 355.865149 -412.820932)
			(xy 355.902366 -412.862469) (xy 355.933139 -412.908982) (xy 355.956811 -412.959479) (xy 355.972879 -413.012886)
			(xy 355.980999 -413.068062) (xy 355.981508 -413.095948) (xy 355.980999 -413.123834) (xy 355.972879 -413.17901)
			(xy 355.956811 -413.232417) (xy 355.933139 -413.282914) (xy 355.902366 -413.329427) (xy 355.865149 -413.370964)
			(xy 355.822281 -413.406639) (xy 355.774675 -413.435693) (xy 355.723346 -413.457505) (xy 355.669389 -413.471611)
			(xy 355.613952 -413.477711) (xy 355.558218 -413.475674) (xy 355.503375 -413.465544) (xy 355.450591 -413.447537)
			(xy 355.400991 -413.422036) (xy 355.355633 -413.389585) (xy 355.315484 -413.350876) (xy 355.281398 -413.306733)
			(xy 355.254102 -413.258098) (xy 355.234179 -413.206007) (xy 355.222053 -413.15157) (xy 355.217982 -413.095948)
			(xy 354.2284 -413.095948) (xy 354.2284 -413.50946) (xy 368.319302 -413.50946) (xy 368.323373 -413.453838)
			(xy 368.335499 -413.399401) (xy 368.355422 -413.34731) (xy 368.382718 -413.298675) (xy 368.416804 -413.254532)
			(xy 368.456953 -413.215823) (xy 368.502311 -413.183372) (xy 368.551911 -413.157871) (xy 368.604695 -413.139864)
			(xy 368.659538 -413.129734) (xy 368.715272 -413.127697) (xy 368.770709 -413.133797) (xy 368.824666 -413.147903)
			(xy 368.875995 -413.169715) (xy 368.923601 -413.198769) (xy 368.966469 -413.234444) (xy 369.003686 -413.275981)
			(xy 369.034459 -413.322494) (xy 369.058131 -413.372991) (xy 369.074199 -413.426398) (xy 369.082319 -413.481574)
			(xy 369.082828 -413.50946) (xy 369.082319 -413.537346) (xy 369.074199 -413.592522) (xy 369.058131 -413.645929)
			(xy 369.034459 -413.696426) (xy 369.003686 -413.742939) (xy 368.966469 -413.784476) (xy 368.923601 -413.820151)
			(xy 368.875995 -413.849205) (xy 368.824666 -413.871017) (xy 368.770709 -413.885123) (xy 368.715272 -413.891223)
			(xy 368.659538 -413.889186) (xy 368.604695 -413.879056) (xy 368.551911 -413.861049) (xy 368.502311 -413.835548)
			(xy 368.456953 -413.803097) (xy 368.416804 -413.764388) (xy 368.382718 -413.720245) (xy 368.355422 -413.67161)
			(xy 368.335499 -413.619519) (xy 368.323373 -413.565082) (xy 368.319302 -413.50946) (xy 354.2284 -413.50946)
			(xy 354.2284 -414.111948) (xy 355.217982 -414.111948) (xy 355.222053 -414.056326) (xy 355.234179 -414.001889)
			(xy 355.254102 -413.949798) (xy 355.281398 -413.901163) (xy 355.315484 -413.85702) (xy 355.355633 -413.818311)
			(xy 355.400991 -413.78586) (xy 355.450591 -413.760359) (xy 355.503375 -413.742352) (xy 355.558218 -413.732222)
			(xy 355.613952 -413.730185) (xy 355.669389 -413.736285) (xy 355.723346 -413.750391) (xy 355.774675 -413.772203)
			(xy 355.822281 -413.801257) (xy 355.865149 -413.836932) (xy 355.902366 -413.878469) (xy 355.933139 -413.924982)
			(xy 355.956811 -413.975479) (xy 355.972879 -414.028886) (xy 355.980999 -414.084062) (xy 355.981508 -414.111948)
			(xy 355.980999 -414.139834) (xy 355.972879 -414.19501) (xy 355.956811 -414.248417) (xy 355.944818 -414.274)
			(xy 360.112562 -414.274) (xy 360.116633 -414.218378) (xy 360.128759 -414.163941) (xy 360.148682 -414.11185)
			(xy 360.175978 -414.063215) (xy 360.210064 -414.019072) (xy 360.250213 -413.980363) (xy 360.295571 -413.947912)
			(xy 360.345171 -413.922411) (xy 360.397955 -413.904404) (xy 360.452798 -413.894274) (xy 360.508532 -413.892237)
			(xy 360.563969 -413.898337) (xy 360.617926 -413.912443) (xy 360.669255 -413.934255) (xy 360.716861 -413.963309)
			(xy 360.759729 -413.998984) (xy 360.796946 -414.040521) (xy 360.827719 -414.087034) (xy 360.851391 -414.137531)
			(xy 360.867459 -414.190938) (xy 360.875579 -414.246114) (xy 360.876088 -414.274) (xy 360.875579 -414.301886)
			(xy 360.867459 -414.357062) (xy 360.851391 -414.410469) (xy 360.827719 -414.460966) (xy 360.796946 -414.507479)
			(xy 360.759729 -414.549016) (xy 360.716861 -414.584691) (xy 360.669255 -414.613745) (xy 360.617926 -414.635557)
			(xy 360.563969 -414.649663) (xy 360.508532 -414.655763) (xy 360.452798 -414.653726) (xy 360.397955 -414.643596)
			(xy 360.345171 -414.625589) (xy 360.295571 -414.600088) (xy 360.250213 -414.567637) (xy 360.210064 -414.528928)
			(xy 360.175978 -414.484785) (xy 360.148682 -414.43615) (xy 360.128759 -414.384059) (xy 360.116633 -414.329622)
			(xy 360.112562 -414.274) (xy 355.944818 -414.274) (xy 355.933139 -414.298914) (xy 355.902366 -414.345427)
			(xy 355.865149 -414.386964) (xy 355.822281 -414.422639) (xy 355.774675 -414.451693) (xy 355.723346 -414.473505)
			(xy 355.669389 -414.487611) (xy 355.613952 -414.493711) (xy 355.558218 -414.491674) (xy 355.503375 -414.481544)
			(xy 355.450591 -414.463537) (xy 355.400991 -414.438036) (xy 355.355633 -414.405585) (xy 355.315484 -414.366876)
			(xy 355.281398 -414.322733) (xy 355.254102 -414.274098) (xy 355.234179 -414.222007) (xy 355.222053 -414.16757)
			(xy 355.217982 -414.111948) (xy 354.2284 -414.111948) (xy 354.2284 -414.978088) (xy 361.763562 -414.978088)
			(xy 361.767633 -414.922466) (xy 361.779759 -414.868029) (xy 361.799682 -414.815938) (xy 361.826978 -414.767303)
			(xy 361.861064 -414.72316) (xy 361.901213 -414.684451) (xy 361.946571 -414.652) (xy 361.996171 -414.626499)
			(xy 362.048955 -414.608492) (xy 362.103798 -414.598362) (xy 362.159532 -414.596325) (xy 362.214969 -414.602425)
			(xy 362.268926 -414.616531) (xy 362.320255 -414.638343) (xy 362.367861 -414.667397) (xy 362.410729 -414.703072)
			(xy 362.447946 -414.744609) (xy 362.455879 -414.7566) (xy 365.835182 -414.7566) (xy 365.839253 -414.700978)
			(xy 365.851379 -414.646541) (xy 365.871302 -414.59445) (xy 365.898598 -414.545815) (xy 365.932684 -414.501672)
			(xy 365.972833 -414.462963) (xy 366.018191 -414.430512) (xy 366.067791 -414.405011) (xy 366.120575 -414.387004)
			(xy 366.175418 -414.376874) (xy 366.231152 -414.374837) (xy 366.286589 -414.380937) (xy 366.340546 -414.395043)
			(xy 366.391875 -414.416855) (xy 366.439481 -414.445909) (xy 366.482349 -414.481584) (xy 366.519566 -414.523121)
			(xy 366.550339 -414.569634) (xy 366.574011 -414.620131) (xy 366.590079 -414.673538) (xy 366.598199 -414.728714)
			(xy 366.598708 -414.7566) (xy 366.598199 -414.784486) (xy 366.590079 -414.839662) (xy 366.574011 -414.893069)
			(xy 366.550339 -414.943566) (xy 366.519566 -414.990079) (xy 366.482349 -415.031616) (xy 366.439481 -415.067291)
			(xy 366.391875 -415.096345) (xy 366.340546 -415.118157) (xy 366.286589 -415.132263) (xy 366.231152 -415.138363)
			(xy 366.175418 -415.136326) (xy 366.120575 -415.126196) (xy 366.067791 -415.108189) (xy 366.018191 -415.082688)
			(xy 365.972833 -415.050237) (xy 365.932684 -415.011528) (xy 365.898598 -414.967385) (xy 365.871302 -414.91875)
			(xy 365.851379 -414.866659) (xy 365.839253 -414.812222) (xy 365.835182 -414.7566) (xy 362.455879 -414.7566)
			(xy 362.478719 -414.791122) (xy 362.502391 -414.841619) (xy 362.518459 -414.895026) (xy 362.526579 -414.950202)
			(xy 362.527088 -414.978088) (xy 362.526579 -415.005974) (xy 362.518459 -415.06115) (xy 362.502391 -415.114557)
			(xy 362.478719 -415.165054) (xy 362.447946 -415.211567) (xy 362.410729 -415.253104) (xy 362.367861 -415.288779)
			(xy 362.320255 -415.317833) (xy 362.268926 -415.339645) (xy 362.214969 -415.353751) (xy 362.159532 -415.359851)
			(xy 362.103798 -415.357814) (xy 362.048955 -415.347684) (xy 361.996171 -415.329677) (xy 361.946571 -415.304176)
			(xy 361.901213 -415.271725) (xy 361.861064 -415.233016) (xy 361.826978 -415.188873) (xy 361.799682 -415.140238)
			(xy 361.779759 -415.088147) (xy 361.767633 -415.03371) (xy 361.763562 -414.978088) (xy 354.2284 -414.978088)
			(xy 354.2284 -416.270948) (xy 357.884982 -416.270948) (xy 357.889053 -416.215326) (xy 357.901179 -416.160889)
			(xy 357.921102 -416.108798) (xy 357.948398 -416.060163) (xy 357.982484 -416.01602) (xy 358.022633 -415.977311)
			(xy 358.067991 -415.94486) (xy 358.117591 -415.919359) (xy 358.170375 -415.901352) (xy 358.225218 -415.891222)
			(xy 358.280952 -415.889185) (xy 358.336389 -415.895285) (xy 358.390346 -415.909391) (xy 358.441675 -415.931203)
			(xy 358.489281 -415.960257) (xy 358.532149 -415.995932) (xy 358.569366 -416.037469) (xy 358.600139 -416.083982)
			(xy 358.623811 -416.134479) (xy 358.639879 -416.187886) (xy 358.647999 -416.243062) (xy 358.648508 -416.270948)
			(xy 358.647999 -416.298834) (xy 358.639879 -416.35401) (xy 358.623811 -416.407417) (xy 358.600139 -416.457914)
			(xy 358.569366 -416.504427) (xy 358.532149 -416.545964) (xy 358.489281 -416.581639) (xy 358.441675 -416.610693)
			(xy 358.390346 -416.632505) (xy 358.336389 -416.646611) (xy 358.280952 -416.652711) (xy 358.225218 -416.650674)
			(xy 358.170375 -416.640544) (xy 358.117591 -416.622537) (xy 358.067991 -416.597036) (xy 358.022633 -416.564585)
			(xy 357.982484 -416.525876) (xy 357.948398 -416.481733) (xy 357.921102 -416.433098) (xy 357.901179 -416.381007)
			(xy 357.889053 -416.32657) (xy 357.884982 -416.270948) (xy 354.2284 -416.270948) (xy 354.2284 -417.120651)
			(xy 354.431578 -417.120651) (xy 354.431578 -417.066149) (xy 354.439334 -417.012201) (xy 354.454689 -416.959906)
			(xy 354.477331 -416.910329) (xy 354.506797 -416.864479) (xy 354.542488 -416.823288) (xy 354.583679 -416.787597)
			(xy 354.629529 -416.758131) (xy 354.679106 -416.735489) (xy 354.731401 -416.720134) (xy 354.785349 -416.712378)
			(xy 354.8126 -416.711892) (xy 354.841007 -416.712388) (xy 354.89719 -416.720834) (xy 354.951502 -416.737508)
			(xy 355.002745 -416.762044) (xy 355.049789 -416.7939) (xy 355.091594 -416.832373) (xy 355.127239 -416.876614)
			(xy 355.142038 -416.900868) (xy 355.149371 -416.912726) (xy 355.169412 -416.932103) (xy 355.193946 -416.945338)
			(xy 355.221145 -416.951444) (xy 355.248982 -416.949966) (xy 355.275381 -416.941014) (xy 355.298376 -416.925255)
			(xy 355.307646 -416.914838) (xy 355.32586 -416.89387) (xy 355.367341 -416.856936) (xy 355.413738 -416.826407)
			(xy 355.464071 -416.802927) (xy 355.517276 -416.786992) (xy 355.57223 -416.77894) (xy 355.6 -416.77844)
			(xy 355.627255 -416.77883) (xy 355.681209 -416.786587) (xy 355.733511 -416.801944) (xy 355.783094 -416.824588)
			(xy 355.783218 -416.824668) (xy 358.578402 -416.824668) (xy 358.582473 -416.769046) (xy 358.594599 -416.714609)
			(xy 358.614522 -416.662518) (xy 358.641818 -416.613883) (xy 358.675904 -416.56974) (xy 358.716053 -416.531031)
			(xy 358.761411 -416.49858) (xy 358.811011 -416.473079) (xy 358.863795 -416.455072) (xy 358.918638 -416.444942)
			(xy 358.974372 -416.442905) (xy 359.029809 -416.449005) (xy 359.083766 -416.463111) (xy 359.135095 -416.484923)
			(xy 359.182701 -416.513977) (xy 359.225569 -416.549652) (xy 359.262786 -416.591189) (xy 359.293559 -416.637702)
			(xy 359.317231 -416.688199) (xy 359.333299 -416.741606) (xy 359.341419 -416.796782) (xy 359.341928 -416.824668)
			(xy 359.341419 -416.852554) (xy 359.333299 -416.90773) (xy 359.317231 -416.961137) (xy 359.293559 -417.011634)
			(xy 359.262786 -417.058147) (xy 359.225569 -417.099684) (xy 359.182701 -417.135359) (xy 359.135095 -417.164413)
			(xy 359.083766 -417.186225) (xy 359.029809 -417.200331) (xy 358.974372 -417.206431) (xy 358.918638 -417.204394)
			(xy 358.863795 -417.194264) (xy 358.811011 -417.176257) (xy 358.761411 -417.150756) (xy 358.716053 -417.118305)
			(xy 358.675904 -417.079596) (xy 358.641818 -417.035453) (xy 358.614522 -416.986818) (xy 358.594599 -416.934727)
			(xy 358.582473 -416.88029) (xy 358.578402 -416.824668) (xy 355.783218 -416.824668) (xy 355.82895 -416.854058)
			(xy 355.870146 -416.889754) (xy 355.905842 -416.93095) (xy 355.935312 -416.976806) (xy 355.957956 -417.026389)
			(xy 355.973313 -417.078691) (xy 355.98107 -417.132645) (xy 355.98107 -417.187155) (xy 355.973313 -417.241109)
			(xy 355.957956 -417.293411) (xy 355.935312 -417.342994) (xy 355.905842 -417.38885) (xy 355.870146 -417.430046)
			(xy 355.82895 -417.465742) (xy 355.783094 -417.495212) (xy 355.733511 -417.517856) (xy 355.681209 -417.533213)
			(xy 355.627255 -417.54097) (xy 355.6 -417.541456) (xy 355.571594 -417.540936) (xy 355.515413 -417.532492)
			(xy 355.461103 -417.51582) (xy 355.409861 -417.491287) (xy 355.362817 -417.459435) (xy 355.321011 -417.420967)
			(xy 355.285363 -417.376731) (xy 355.270562 -417.35248) (xy 355.263226 -417.340622) (xy 355.24319 -417.321237)
			(xy 355.218656 -417.307996) (xy 355.191455 -417.301888) (xy 355.163616 -417.303367) (xy 355.137215 -417.312323)
			(xy 355.114222 -417.328089) (xy 355.104954 -417.33851) (xy 355.086728 -417.359467) (xy 355.045251 -417.396404)
			(xy 354.998857 -417.426936) (xy 354.948526 -417.450418) (xy 354.895322 -417.466354) (xy 354.84037 -417.474407)
			(xy 354.8126 -417.474908) (xy 354.785349 -417.474422) (xy 354.731401 -417.466666) (xy 354.679106 -417.451311)
			(xy 354.629529 -417.428669) (xy 354.583679 -417.399203) (xy 354.542488 -417.363512) (xy 354.506797 -417.322321)
			(xy 354.477331 -417.276471) (xy 354.454689 -417.226894) (xy 354.439334 -417.174599) (xy 354.431578 -417.120651)
			(xy 354.2284 -417.120651) (xy 354.2284 -417.7284) (xy 355.1936 -418.6936) (xy 364.0582 -418.6936)
			(xy 364.429548 -419.064948) (xy 366.031524 -419.064948) (xy 366.035595 -419.009326) (xy 366.047721 -418.954889)
			(xy 366.067644 -418.902798) (xy 366.09494 -418.854163) (xy 366.129026 -418.81002) (xy 366.169175 -418.771311)
			(xy 366.214533 -418.73886) (xy 366.264133 -418.713359) (xy 366.316917 -418.695352) (xy 366.37176 -418.685222)
			(xy 366.427494 -418.683185) (xy 366.482931 -418.689285) (xy 366.536888 -418.703391) (xy 366.588217 -418.725203)
			(xy 366.635823 -418.754257) (xy 366.678691 -418.789932) (xy 366.715908 -418.831469) (xy 366.746681 -418.877982)
			(xy 366.770353 -418.928479) (xy 366.786421 -418.981886) (xy 366.794541 -419.037062) (xy 366.79505 -419.064948)
			(xy 366.794541 -419.092834) (xy 366.786421 -419.14801) (xy 366.770353 -419.201417) (xy 366.746681 -419.251914)
			(xy 366.715908 -419.298427) (xy 366.678691 -419.339964) (xy 366.635823 -419.375639) (xy 366.588217 -419.404693)
			(xy 366.536888 -419.426505) (xy 366.482931 -419.440611) (xy 366.427494 -419.446711) (xy 366.37176 -419.444674)
			(xy 366.316917 -419.434544) (xy 366.264133 -419.416537) (xy 366.214533 -419.391036) (xy 366.169175 -419.358585)
			(xy 366.129026 -419.319876) (xy 366.09494 -419.275733) (xy 366.067644 -419.227098) (xy 366.047721 -419.175007)
			(xy 366.035595 -419.12057) (xy 366.031524 -419.064948) (xy 364.429548 -419.064948) (xy 366.430306 -421.065706)
			(xy 366.448848 -421.06723) (xy 366.475519 -421.069912) (xy 366.527788 -421.081804) (xy 366.577878 -421.100894)
			(xy 366.62225 -421.125396) (xy 374.666762 -421.125396) (xy 374.670833 -421.069774) (xy 374.682959 -421.015337)
			(xy 374.702882 -420.963246) (xy 374.730178 -420.914611) (xy 374.764264 -420.870468) (xy 374.804413 -420.831759)
			(xy 374.849771 -420.799308) (xy 374.899371 -420.773807) (xy 374.952155 -420.7558) (xy 375.006998 -420.74567)
			(xy 375.062732 -420.743633) (xy 375.118169 -420.749733) (xy 375.172126 -420.763839) (xy 375.223455 -420.785651)
			(xy 375.271061 -420.814705) (xy 375.313929 -420.85038) (xy 375.351146 -420.891917) (xy 375.381919 -420.93843)
			(xy 375.405591 -420.988927) (xy 375.421659 -421.042334) (xy 375.429779 -421.09751) (xy 375.430288 -421.125396)
			(xy 375.429779 -421.153282) (xy 375.421659 -421.208458) (xy 375.405591 -421.261865) (xy 375.381919 -421.312362)
			(xy 375.351146 -421.358875) (xy 375.313929 -421.400412) (xy 375.271061 -421.436087) (xy 375.223455 -421.465141)
			(xy 375.172126 -421.486953) (xy 375.118169 -421.501059) (xy 375.062732 -421.507159) (xy 375.006998 -421.505122)
			(xy 374.952155 -421.494992) (xy 374.899371 -421.476985) (xy 374.849771 -421.451484) (xy 374.804413 -421.419033)
			(xy 374.764264 -421.380324) (xy 374.730178 -421.336181) (xy 374.702882 -421.287546) (xy 374.682959 -421.235455)
			(xy 374.670833 -421.181018) (xy 374.666762 -421.125396) (xy 366.62225 -421.125396) (xy 366.624803 -421.126806)
			(xy 366.66764 -421.15903) (xy 366.705546 -421.196932) (xy 366.737774 -421.239766) (xy 366.763691 -421.286689)
			(xy 366.782785 -421.336777) (xy 366.794682 -421.389044) (xy 366.797336 -421.415718) (xy 366.79886 -421.43426)
			(xy 368.1476 -422.783) (xy 375.3104 -422.783) (xy 376.2756 -421.8178) (xy 376.2756 -420.842948) (xy 374.39473 -417.67633)
			(xy 370.3066 -413.5882) (xy 370.3066 -403.243034) (xy 370.306047 -403.227881) (xy 370.297159 -403.198909)
			(xy 370.280156 -403.173823) (xy 370.256537 -403.154835) (xy 370.228384 -403.143618) (xy 370.198178 -403.141162)
			(xy 370.168583 -403.147683) (xy 370.142206 -403.162605) (xy 370.13134 -403.173184) (xy 370.11325 -403.191613)
			(xy 370.072966 -403.223924) (xy 370.028693 -403.250507) (xy 369.981239 -403.270877) (xy 369.931472 -403.284662)
			(xy 369.880301 -403.291609) (xy 369.85448 -403.292056) (xy 369.827226 -403.291569) (xy 369.773274 -403.283809)
			(xy 369.720975 -403.26845) (xy 369.671394 -403.245805) (xy 369.62554 -403.216334) (xy 369.584347 -403.180638)
			(xy 369.548654 -403.139444) (xy 369.519185 -403.093588) (xy 369.496543 -403.044006) (xy 369.481187 -402.991707)
			(xy 369.47343 -402.937754) (xy 369.47343 -402.883246) (xy 369.481187 -402.829293) (xy 369.496543 -402.776994)
			(xy 369.519185 -402.727412) (xy 369.548654 -402.681556) (xy 369.584347 -402.640362) (xy 369.62554 -402.604666)
			(xy 369.671394 -402.575195) (xy 369.720975 -402.55255) (xy 369.773274 -402.537191) (xy 369.827226 -402.529431)
			(xy 369.85448 -402.52904) (xy 369.880299 -402.529472) (xy 369.931466 -402.536439) (xy 369.981227 -402.550237)
			(xy 370.028675 -402.570614) (xy 370.072946 -402.597197) (xy 370.113231 -402.629502) (xy 370.13134 -402.647912)
			(xy 370.14217 -402.658515) (xy 370.168552 -402.673403) (xy 370.19814 -402.679898) (xy 370.228332 -402.677428)
			(xy 370.256471 -402.66621) (xy 370.280082 -402.647232) (xy 370.297087 -402.622163) (xy 370.30599 -402.593208)
			(xy 370.3066 -402.578062) (xy 370.3066 -398.8054) (xy 368.2746 -396.7734) (xy 352.636836 -396.7734)
			(xy 352.622902 -396.773869) (xy 352.596089 -396.781474) (xy 352.57233 -396.796044) (xy 352.553396 -396.816496)
			(xy 352.540696 -396.841305) (xy 352.535176 -396.868623) (xy 352.537248 -396.896417) (xy 352.546757 -396.922615)
			(xy 352.55454 -396.934182) (xy 352.571426 -396.958675) (xy 352.598205 -397.011794) (xy 352.61642 -397.068425)
			(xy 352.625627 -397.127196) (xy 352.626168 -397.15694) (xy 352.625679 -397.184188) (xy 352.617918 -397.23813)
			(xy 352.602559 -397.290417) (xy 352.579915 -397.339987) (xy 352.550447 -397.385829) (xy 352.514755 -397.427011)
			(xy 352.473565 -397.462695) (xy 352.427716 -397.492153) (xy 352.378142 -397.514787) (xy 352.362432 -397.519398)
			(xy 352.945952 -397.519398) (xy 352.950023 -397.463776) (xy 352.962149 -397.409339) (xy 352.982072 -397.357248)
			(xy 353.009368 -397.308613) (xy 353.043454 -397.26447) (xy 353.083603 -397.225761) (xy 353.128961 -397.19331)
			(xy 353.178561 -397.167809) (xy 353.231345 -397.149802) (xy 353.286188 -397.139672) (xy 353.341922 -397.137635)
			(xy 353.397359 -397.143735) (xy 353.451316 -397.157841) (xy 353.502645 -397.179653) (xy 353.550251 -397.208707)
			(xy 353.593119 -397.244382) (xy 353.630336 -397.285919) (xy 353.661109 -397.332432) (xy 353.684781 -397.382929)
			(xy 353.700849 -397.436336) (xy 353.708969 -397.491512) (xy 353.709478 -397.519398) (xy 355.399592 -397.519398)
			(xy 355.403663 -397.463776) (xy 355.415789 -397.409339) (xy 355.435712 -397.357248) (xy 355.463008 -397.308613)
			(xy 355.497094 -397.26447) (xy 355.537243 -397.225761) (xy 355.582601 -397.19331) (xy 355.632201 -397.167809)
			(xy 355.684985 -397.149802) (xy 355.739828 -397.139672) (xy 355.795562 -397.137635) (xy 355.850999 -397.143735)
			(xy 355.904956 -397.157841) (xy 355.956285 -397.179653) (xy 356.003891 -397.208707) (xy 356.046759 -397.244382)
			(xy 356.083976 -397.285919) (xy 356.114749 -397.332432) (xy 356.138421 -397.382929) (xy 356.154489 -397.436336)
			(xy 356.160171 -397.474948) (xy 359.485182 -397.474948) (xy 359.489253 -397.419326) (xy 359.501379 -397.364889)
			(xy 359.521302 -397.312798) (xy 359.548598 -397.264163) (xy 359.582684 -397.22002) (xy 359.622833 -397.181311)
			(xy 359.668191 -397.14886) (xy 359.717791 -397.123359) (xy 359.770575 -397.105352) (xy 359.825418 -397.095222)
			(xy 359.881152 -397.093185) (xy 359.936589 -397.099285) (xy 359.990546 -397.113391) (xy 360.041875 -397.135203)
			(xy 360.089481 -397.164257) (xy 360.132349 -397.199932) (xy 360.169566 -397.241469) (xy 360.200339 -397.287982)
			(xy 360.224011 -397.338479) (xy 360.240079 -397.391886) (xy 360.248199 -397.447062) (xy 360.248708 -397.474948)
			(xy 360.248199 -397.502834) (xy 360.240079 -397.55801) (xy 360.224011 -397.611417) (xy 360.200339 -397.661914)
			(xy 360.169566 -397.708427) (xy 360.132349 -397.749964) (xy 360.089481 -397.785639) (xy 360.041875 -397.814693)
			(xy 359.990546 -397.836505) (xy 359.936589 -397.850611) (xy 359.881152 -397.856711) (xy 359.825418 -397.854674)
			(xy 359.770575 -397.844544) (xy 359.717791 -397.826537) (xy 359.668191 -397.801036) (xy 359.622833 -397.768585)
			(xy 359.582684 -397.729876) (xy 359.548598 -397.685733) (xy 359.521302 -397.637098) (xy 359.501379 -397.585007)
			(xy 359.489253 -397.53057) (xy 359.485182 -397.474948) (xy 356.160171 -397.474948) (xy 356.162609 -397.491512)
			(xy 356.163118 -397.519398) (xy 356.162609 -397.547284) (xy 356.154489 -397.60246) (xy 356.138421 -397.655867)
			(xy 356.114749 -397.706364) (xy 356.083976 -397.752877) (xy 356.046759 -397.794414) (xy 356.003891 -397.830089)
			(xy 355.956285 -397.859143) (xy 355.904956 -397.880955) (xy 355.850999 -397.895061) (xy 355.795562 -397.901161)
			(xy 355.739828 -397.899124) (xy 355.684985 -397.888994) (xy 355.632201 -397.870987) (xy 355.582601 -397.845486)
			(xy 355.537243 -397.813035) (xy 355.497094 -397.774326) (xy 355.463008 -397.730183) (xy 355.435712 -397.681548)
			(xy 355.415789 -397.629457) (xy 355.403663 -397.57502) (xy 355.399592 -397.519398) (xy 353.709478 -397.519398)
			(xy 353.708969 -397.547284) (xy 353.700849 -397.60246) (xy 353.684781 -397.655867) (xy 353.661109 -397.706364)
			(xy 353.630336 -397.752877) (xy 353.593119 -397.794414) (xy 353.550251 -397.830089) (xy 353.502645 -397.859143)
			(xy 353.451316 -397.880955) (xy 353.397359 -397.895061) (xy 353.341922 -397.901161) (xy 353.286188 -397.899124)
			(xy 353.231345 -397.888994) (xy 353.178561 -397.870987) (xy 353.128961 -397.845486) (xy 353.083603 -397.813035)
			(xy 353.043454 -397.774326) (xy 353.009368 -397.730183) (xy 352.982072 -397.681548) (xy 352.962149 -397.629457)
			(xy 352.950023 -397.57502) (xy 352.945952 -397.519398) (xy 352.362432 -397.519398) (xy 352.325851 -397.530135)
			(xy 352.271908 -397.537885) (xy 352.24466 -397.538448) (xy 352.234246 -397.538194) (xy 352.220102 -397.538259)
			(xy 352.192708 -397.54525) (xy 352.168282 -397.559488) (xy 352.148699 -397.579881) (xy 352.135461 -397.604863)
			(xy 352.129585 -397.632518) (xy 352.130106 -397.646652) (xy 352.130868 -397.67256) (xy 352.130382 -397.699811)
			(xy 352.122626 -397.753759) (xy 352.107271 -397.806054) (xy 352.084629 -397.855631) (xy 352.055163 -397.901481)
			(xy 352.019472 -397.942672) (xy 351.978281 -397.978363) (xy 351.932431 -398.007829) (xy 351.882854 -398.030471)
			(xy 351.830559 -398.045826) (xy 351.776611 -398.053582) (xy 351.722109 -398.053582) (xy 351.668161 -398.045826)
			(xy 351.615866 -398.030471) (xy 351.566289 -398.007829) (xy 351.520439 -397.978363) (xy 351.479248 -397.942672)
			(xy 351.443557 -397.901481) (xy 351.414091 -397.855631) (xy 351.391449 -397.806054) (xy 351.376094 -397.753759)
			(xy 351.368338 -397.699811) (xy 351.367852 -397.67256) (xy 351.368005 -397.657831) (xy 351.370297 -397.628462)
			(xy 351.372424 -397.613886) (xy 351.374061 -397.600067) (xy 351.370697 -397.572455) (xy 351.360012 -397.546774)
			(xy 351.342795 -397.524926) (xy 351.320325 -397.508532) (xy 351.294265 -397.498805) (xy 351.266548 -397.496468)
			(xy 351.25279 -397.49857) (xy 351.234869 -397.501807) (xy 351.198611 -397.505243) (xy 351.1804 -397.505428)
			(xy 351.153148 -397.504942) (xy 351.099199 -397.497186) (xy 351.046904 -397.481831) (xy 350.997325 -397.45919)
			(xy 350.951473 -397.429724) (xy 350.910281 -397.394033) (xy 350.874588 -397.352843) (xy 350.84512 -397.306993)
			(xy 350.822476 -397.257415) (xy 350.807118 -397.20512) (xy 350.799359 -397.151172) (xy 350.798892 -397.12392)
			(xy 350.79932 -397.09809) (xy 350.806296 -397.046902) (xy 350.820123 -396.997126) (xy 350.840547 -396.949675)
			(xy 350.853502 -396.927324) (xy 350.860069 -396.915595) (xy 350.867417 -396.889747) (xy 350.867765 -396.862877)
			(xy 350.86109 -396.836847) (xy 350.847854 -396.813461) (xy 350.828974 -396.794338) (xy 350.805759 -396.780805)
			(xy 350.779816 -396.773798) (xy 350.76638 -396.7734) (xy 304.7492 -396.7734) (xy 304.456846 -397.065754)
			(xy 304.46091 -397.091408) (xy 304.463081 -397.106234) (xy 304.465367 -397.136114) (xy 304.465482 -397.151098)
			(xy 304.465019 -397.17835) (xy 304.457262 -397.2323) (xy 304.441906 -397.284597) (xy 304.419263 -397.334175)
			(xy 304.389795 -397.380027) (xy 304.354101 -397.421218) (xy 304.312908 -397.456909) (xy 304.267054 -397.486375)
			(xy 304.217474 -397.509014) (xy 304.165177 -397.524367) (xy 304.111226 -397.53212) (xy 304.083974 -397.532606)
			(xy 304.063495 -397.532364) (xy 304.022766 -397.52804) (xy 304.002694 -397.52397) (xy 303.99736 -397.5227)
			(xy 300.1645 -397.5227) (xy 299.9486 -397.7386) (xy 299.9486 -398.80032) (xy 300.428152 -398.80032)
			(xy 300.428638 -398.773069) (xy 300.436394 -398.719121) (xy 300.451749 -398.666826) (xy 300.474391 -398.617249)
			(xy 300.503857 -398.571399) (xy 300.539548 -398.530208) (xy 300.580739 -398.494517) (xy 300.626589 -398.465051)
			(xy 300.676166 -398.442409) (xy 300.728461 -398.427054) (xy 300.782409 -398.419298) (xy 300.836911 -398.419298)
			(xy 300.890859 -398.427054) (xy 300.943154 -398.442409) (xy 300.992731 -398.465051) (xy 301.038581 -398.494517)
			(xy 301.079772 -398.530208) (xy 301.115463 -398.571399) (xy 301.144929 -398.617249) (xy 301.167571 -398.666826)
			(xy 301.182926 -398.719121) (xy 301.190682 -398.773069) (xy 301.190973 -398.789398) (xy 353.098352 -398.789398)
			(xy 353.102423 -398.733776) (xy 353.114549 -398.679339) (xy 353.134472 -398.627248) (xy 353.161768 -398.578613)
			(xy 353.195854 -398.53447) (xy 353.236003 -398.495761) (xy 353.281361 -398.46331) (xy 353.330961 -398.437809)
			(xy 353.383745 -398.419802) (xy 353.438588 -398.409672) (xy 353.494322 -398.407635) (xy 353.549759 -398.413735)
			(xy 353.603716 -398.427841) (xy 353.655045 -398.449653) (xy 353.702651 -398.478707) (xy 353.745519 -398.514382)
			(xy 353.782736 -398.555919) (xy 353.813509 -398.602432) (xy 353.837181 -398.652929) (xy 353.853249 -398.706336)
			(xy 353.861369 -398.761512) (xy 353.861878 -398.789398) (xy 355.394512 -398.789398) (xy 355.398583 -398.733776)
			(xy 355.410709 -398.679339) (xy 355.430632 -398.627248) (xy 355.457928 -398.578613) (xy 355.492014 -398.53447)
			(xy 355.532163 -398.495761) (xy 355.577521 -398.46331) (xy 355.627121 -398.437809) (xy 355.679905 -398.419802)
			(xy 355.734748 -398.409672) (xy 355.790482 -398.407635) (xy 355.845919 -398.413735) (xy 355.899876 -398.427841)
			(xy 355.951205 -398.449653) (xy 355.998811 -398.478707) (xy 356.041679 -398.514382) (xy 356.078896 -398.555919)
			(xy 356.109669 -398.602432) (xy 356.133341 -398.652929) (xy 356.149409 -398.706336) (xy 356.151353 -398.719548)
			(xy 363.782862 -398.719548) (xy 363.786933 -398.663926) (xy 363.799059 -398.609489) (xy 363.818982 -398.557398)
			(xy 363.846278 -398.508763) (xy 363.880364 -398.46462) (xy 363.920513 -398.425911) (xy 363.965871 -398.39346)
			(xy 364.015471 -398.367959) (xy 364.068255 -398.349952) (xy 364.123098 -398.339822) (xy 364.178832 -398.337785)
			(xy 364.234269 -398.343885) (xy 364.288226 -398.357991) (xy 364.339555 -398.379803) (xy 364.387161 -398.408857)
			(xy 364.430029 -398.444532) (xy 364.467246 -398.486069) (xy 364.498019 -398.532582) (xy 364.521691 -398.583079)
			(xy 364.537759 -398.636486) (xy 364.545879 -398.691662) (xy 364.546388 -398.719548) (xy 364.545879 -398.747434)
			(xy 364.537759 -398.80261) (xy 364.521691 -398.856017) (xy 364.498019 -398.906514) (xy 364.467246 -398.953027)
			(xy 364.430029 -398.994564) (xy 364.387161 -399.030239) (xy 364.339555 -399.059293) (xy 364.288226 -399.081105)
			(xy 364.234269 -399.095211) (xy 364.178832 -399.101311) (xy 364.123098 -399.099274) (xy 364.068255 -399.089144)
			(xy 364.015471 -399.071137) (xy 363.965871 -399.045636) (xy 363.920513 -399.013185) (xy 363.880364 -398.974476)
			(xy 363.846278 -398.930333) (xy 363.818982 -398.881698) (xy 363.799059 -398.829607) (xy 363.786933 -398.77517)
			(xy 363.782862 -398.719548) (xy 356.151353 -398.719548) (xy 356.157529 -398.761512) (xy 356.158038 -398.789398)
			(xy 356.157529 -398.817284) (xy 356.149409 -398.87246) (xy 356.133341 -398.925867) (xy 356.109669 -398.976364)
			(xy 356.078896 -399.022877) (xy 356.041679 -399.064414) (xy 355.998811 -399.100089) (xy 355.951205 -399.129143)
			(xy 355.899876 -399.150955) (xy 355.845919 -399.165061) (xy 355.790482 -399.171161) (xy 355.734748 -399.169124)
			(xy 355.679905 -399.158994) (xy 355.627121 -399.140987) (xy 355.577521 -399.115486) (xy 355.532163 -399.083035)
			(xy 355.492014 -399.044326) (xy 355.457928 -399.000183) (xy 355.430632 -398.951548) (xy 355.410709 -398.899457)
			(xy 355.398583 -398.84502) (xy 355.394512 -398.789398) (xy 353.861878 -398.789398) (xy 353.861369 -398.817284)
			(xy 353.853249 -398.87246) (xy 353.837181 -398.925867) (xy 353.813509 -398.976364) (xy 353.782736 -399.022877)
			(xy 353.745519 -399.064414) (xy 353.702651 -399.100089) (xy 353.655045 -399.129143) (xy 353.603716 -399.150955)
			(xy 353.549759 -399.165061) (xy 353.494322 -399.171161) (xy 353.438588 -399.169124) (xy 353.383745 -399.158994)
			(xy 353.330961 -399.140987) (xy 353.281361 -399.115486) (xy 353.236003 -399.083035) (xy 353.195854 -399.044326)
			(xy 353.161768 -399.000183) (xy 353.134472 -398.951548) (xy 353.114549 -398.899457) (xy 353.102423 -398.84502)
			(xy 353.098352 -398.789398) (xy 301.190973 -398.789398) (xy 301.191168 -398.80032) (xy 301.190737 -398.826961)
			(xy 301.183308 -398.879723) (xy 301.168611 -398.930939) (xy 301.146932 -398.979612) (xy 301.118692 -399.024796)
			(xy 301.084442 -399.065612) (xy 301.044846 -399.101266) (xy 301.02302 -399.11655) (xy 301.011299 -399.124942)
			(xy 300.992832 -399.147067) (xy 300.981281 -399.173469) (xy 300.977564 -399.202047) (xy 300.981978 -399.230526)
			(xy 300.994171 -399.256639) (xy 301.013172 -399.278306) (xy 301.025052 -399.286476) (xy 301.047839 -399.301586)
			(xy 301.089266 -399.337268) (xy 301.125173 -399.378501) (xy 301.154822 -399.424439) (xy 301.177606 -399.47414)
			(xy 301.193058 -399.526587) (xy 301.200861 -399.580702) (xy 301.201328 -399.60804) (xy 301.200842 -399.635291)
			(xy 301.193086 -399.689239) (xy 301.177731 -399.741534) (xy 301.155089 -399.791111) (xy 301.125623 -399.836961)
			(xy 301.089932 -399.878152) (xy 301.048741 -399.913843) (xy 301.002891 -399.943309) (xy 300.953314 -399.965951)
			(xy 300.901019 -399.981306) (xy 300.847071 -399.989062) (xy 300.792569 -399.989062) (xy 300.738621 -399.981306)
			(xy 300.686326 -399.965951) (xy 300.636749 -399.943309) (xy 300.590899 -399.913843) (xy 300.549708 -399.878152)
			(xy 300.514017 -399.836961) (xy 300.484551 -399.791111) (xy 300.461909 -399.741534) (xy 300.446554 -399.689239)
			(xy 300.438798 -399.635291) (xy 300.438312 -399.60804) (xy 300.438798 -399.581401) (xy 300.446218 -399.528641)
			(xy 300.460906 -399.477427) (xy 300.482577 -399.428755) (xy 300.510807 -399.38357) (xy 300.54505 -399.342753)
			(xy 300.584638 -399.307096) (xy 300.60646 -399.29181) (xy 300.618124 -399.283345) (xy 300.636592 -399.261237)
			(xy 300.648149 -399.234851) (xy 300.651874 -399.206286) (xy 300.647471 -399.177818) (xy 300.63529 -399.151714)
			(xy 300.616302 -399.130052) (xy 300.604428 -399.121884) (xy 300.581618 -399.106807) (xy 300.540192 -399.071119)
			(xy 300.504288 -399.02988) (xy 300.474642 -398.983937) (xy 300.451862 -398.93423) (xy 300.436414 -398.881779)
			(xy 300.428616 -398.827659) (xy 300.428152 -398.80032) (xy 299.9486 -398.80032) (xy 299.9486 -402.59)
			(xy 301.2821 -403.9235) (xy 301.7266 -405.525478) (xy 301.7266 -409.575) (xy 300.559978 -410.741622)
			(xy 300.549942 -410.752332) (xy 300.535926 -410.778105) (xy 300.529799 -410.806796) (xy 300.532065 -410.836046)
			(xy 300.542537 -410.863451) (xy 300.560355 -410.886758) (xy 300.571916 -410.8958) (xy 300.592426 -410.911233)
			(xy 300.629511 -410.946719) (xy 300.661497 -410.986862) (xy 300.687805 -411.030935) (xy 300.707959 -411.078141)
			(xy 300.721593 -411.127625) (xy 300.728462 -411.178492) (xy 300.728888 -411.204156) (xy 300.728428 -411.23141)
			(xy 300.720676 -411.285365) (xy 300.705323 -411.337667) (xy 300.682683 -411.387251) (xy 300.653216 -411.433109)
			(xy 300.617522 -411.474305) (xy 300.576328 -411.510001) (xy 300.530472 -411.539471) (xy 300.48089 -411.562115)
			(xy 300.428588 -411.577471) (xy 300.374634 -411.585226) (xy 300.34738 -411.585664) (xy 300.33341 -411.58541)
			(xy 300.319759 -411.585337) (xy 300.293194 -411.591577) (xy 300.269232 -411.604634) (xy 300.249588 -411.623575)
			(xy 300.235666 -411.647045) (xy 300.228463 -411.673365) (xy 300.228 -411.68701) (xy 300.228 -412.66364)
			(xy 300.615602 -412.66364) (xy 300.619673 -412.608018) (xy 300.631799 -412.553581) (xy 300.651722 -412.50149)
			(xy 300.679018 -412.452855) (xy 300.713104 -412.408712) (xy 300.753253 -412.370003) (xy 300.798611 -412.337552)
			(xy 300.848211 -412.312051) (xy 300.900995 -412.294044) (xy 300.955838 -412.283914) (xy 301.011572 -412.281877)
			(xy 301.067009 -412.287977) (xy 301.120966 -412.302083) (xy 301.172295 -412.323895) (xy 301.219901 -412.352949)
			(xy 301.262769 -412.388624) (xy 301.299986 -412.430161) (xy 301.330759 -412.476674) (xy 301.354431 -412.527171)
			(xy 301.370499 -412.580578) (xy 301.378619 -412.635754) (xy 301.379128 -412.66364) (xy 301.378619 -412.691526)
			(xy 301.370499 -412.746702) (xy 301.354431 -412.800109) (xy 301.330759 -412.850606) (xy 301.299986 -412.897119)
			(xy 301.262769 -412.938656) (xy 301.219901 -412.974331) (xy 301.172295 -413.003385) (xy 301.120966 -413.025197)
			(xy 301.067009 -413.039303) (xy 301.011572 -413.045403) (xy 300.955838 -413.043366) (xy 300.900995 -413.033236)
			(xy 300.848211 -413.015229) (xy 300.798611 -412.989728) (xy 300.753253 -412.957277) (xy 300.713104 -412.918568)
			(xy 300.679018 -412.874425) (xy 300.651722 -412.82579) (xy 300.631799 -412.773699) (xy 300.619673 -412.719262)
			(xy 300.615602 -412.66364) (xy 300.228 -412.66364) (xy 300.228 -414.78454) (xy 300.615602 -414.78454)
			(xy 300.619673 -414.728918) (xy 300.631799 -414.674481) (xy 300.651722 -414.62239) (xy 300.679018 -414.573755)
			(xy 300.713104 -414.529612) (xy 300.753253 -414.490903) (xy 300.798611 -414.458452) (xy 300.848211 -414.432951)
			(xy 300.900995 -414.414944) (xy 300.955838 -414.404814) (xy 301.011572 -414.402777) (xy 301.067009 -414.408877)
			(xy 301.120966 -414.422983) (xy 301.172295 -414.444795) (xy 301.219901 -414.473849) (xy 301.262769 -414.509524)
			(xy 301.299986 -414.551061) (xy 301.330759 -414.597574) (xy 301.354431 -414.648071) (xy 301.370499 -414.701478)
			(xy 301.378619 -414.756654) (xy 301.379128 -414.78454) (xy 301.378619 -414.812426) (xy 301.370499 -414.867602)
			(xy 301.354431 -414.921009) (xy 301.330759 -414.971506) (xy 301.299986 -415.018019) (xy 301.262769 -415.059556)
			(xy 301.219901 -415.095231) (xy 301.172295 -415.124285) (xy 301.120966 -415.146097) (xy 301.067009 -415.160203)
			(xy 301.011572 -415.166303) (xy 300.955838 -415.164266) (xy 300.900995 -415.154136) (xy 300.848211 -415.136129)
			(xy 300.798611 -415.110628) (xy 300.753253 -415.078177) (xy 300.713104 -415.039468) (xy 300.679018 -414.995325)
			(xy 300.651722 -414.94669) (xy 300.631799 -414.894599) (xy 300.619673 -414.840162) (xy 300.615602 -414.78454)
			(xy 300.228 -414.78454) (xy 300.228 -416.56) (xy 300.861982 -416.56) (xy 300.866053 -416.504378)
			(xy 300.878179 -416.449941) (xy 300.898102 -416.39785) (xy 300.925398 -416.349215) (xy 300.959484 -416.305072)
			(xy 300.999633 -416.266363) (xy 301.044991 -416.233912) (xy 301.094591 -416.208411) (xy 301.147375 -416.190404)
			(xy 301.202218 -416.180274) (xy 301.257952 -416.178237) (xy 301.313389 -416.184337) (xy 301.367346 -416.198443)
			(xy 301.418675 -416.220255) (xy 301.466281 -416.249309) (xy 301.509149 -416.284984) (xy 301.546366 -416.326521)
			(xy 301.577139 -416.373034) (xy 301.600811 -416.423531) (xy 301.616879 -416.476938) (xy 301.624999 -416.532114)
			(xy 301.625508 -416.56) (xy 301.624999 -416.587886) (xy 301.616879 -416.643062) (xy 301.600811 -416.696469)
			(xy 301.577139 -416.746966) (xy 301.546366 -416.793479) (xy 301.509149 -416.835016) (xy 301.466281 -416.870691)
			(xy 301.418675 -416.899745) (xy 301.367346 -416.921557) (xy 301.313389 -416.935663) (xy 301.257952 -416.941763)
			(xy 301.202218 -416.939726) (xy 301.147375 -416.929596) (xy 301.094591 -416.911589) (xy 301.044991 -416.886088)
			(xy 300.999633 -416.853637) (xy 300.959484 -416.814928) (xy 300.925398 -416.770785) (xy 300.898102 -416.72215)
			(xy 300.878179 -416.670059) (xy 300.866053 -416.615622) (xy 300.861982 -416.56) (xy 300.228 -416.56)
			(xy 300.228 -417.29914) (xy 302.105312 -417.29914) (xy 302.109383 -417.243518) (xy 302.121509 -417.189081)
			(xy 302.141432 -417.13699) (xy 302.168728 -417.088355) (xy 302.202814 -417.044212) (xy 302.242963 -417.005503)
			(xy 302.288321 -416.973052) (xy 302.337921 -416.947551) (xy 302.390705 -416.929544) (xy 302.445548 -416.919414)
			(xy 302.501282 -416.917377) (xy 302.556719 -416.923477) (xy 302.610676 -416.937583) (xy 302.662005 -416.959395)
			(xy 302.709611 -416.988449) (xy 302.752479 -417.024124) (xy 302.789696 -417.065661) (xy 302.820469 -417.112174)
			(xy 302.844141 -417.162671) (xy 302.860209 -417.216078) (xy 302.868329 -417.271254) (xy 302.868838 -417.29914)
			(xy 302.868329 -417.327026) (xy 302.860209 -417.382202) (xy 302.844141 -417.435609) (xy 302.820469 -417.486106)
			(xy 302.789696 -417.532619) (xy 302.752479 -417.574156) (xy 302.709611 -417.609831) (xy 302.662005 -417.638885)
			(xy 302.610676 -417.660697) (xy 302.556719 -417.674803) (xy 302.501282 -417.680903) (xy 302.445548 -417.678866)
			(xy 302.390705 -417.668736) (xy 302.337921 -417.650729) (xy 302.288321 -417.625228) (xy 302.242963 -417.592777)
			(xy 302.202814 -417.554068) (xy 302.168728 -417.509925) (xy 302.141432 -417.46129) (xy 302.121509 -417.409199)
			(xy 302.109383 -417.354762) (xy 302.105312 -417.29914) (xy 300.228 -417.29914) (xy 300.228 -417.606988)
			(xy 300.270672 -417.613846) (xy 300.298587 -417.618853) (xy 300.352633 -417.636034) (xy 300.403541 -417.661026)
			(xy 300.450187 -417.69328) (xy 300.491545 -417.732084) (xy 300.526702 -417.776583) (xy 300.554883 -417.825797)
			(xy 300.575468 -417.878641) (xy 300.588004 -417.933949) (xy 300.592213 -417.990504) (xy 300.592211 -417.990528)
			(xy 301.072802 -417.990528) (xy 301.076873 -417.934906) (xy 301.088999 -417.880469) (xy 301.108922 -417.828378)
			(xy 301.136218 -417.779743) (xy 301.170304 -417.7356) (xy 301.210453 -417.696891) (xy 301.255811 -417.66444)
			(xy 301.305411 -417.638939) (xy 301.358195 -417.620932) (xy 301.413038 -417.610802) (xy 301.468772 -417.608765)
			(xy 301.524209 -417.614865) (xy 301.578166 -417.628971) (xy 301.629495 -417.650783) (xy 301.677101 -417.679837)
			(xy 301.719969 -417.715512) (xy 301.757186 -417.757049) (xy 301.787959 -417.803562) (xy 301.811631 -417.854059)
			(xy 301.827699 -417.907466) (xy 301.835819 -417.962642) (xy 301.836328 -417.990528) (xy 301.835819 -418.018414)
			(xy 301.828335 -418.069268) (xy 302.512982 -418.069268) (xy 302.517053 -418.013646) (xy 302.529179 -417.959209)
			(xy 302.549102 -417.907118) (xy 302.576398 -417.858483) (xy 302.610484 -417.81434) (xy 302.650633 -417.775631)
			(xy 302.695991 -417.74318) (xy 302.745591 -417.717679) (xy 302.798375 -417.699672) (xy 302.853218 -417.689542)
			(xy 302.908952 -417.687505) (xy 302.964389 -417.693605) (xy 303.018346 -417.707711) (xy 303.069675 -417.729523)
			(xy 303.117281 -417.758577) (xy 303.160149 -417.794252) (xy 303.197366 -417.835789) (xy 303.228139 -417.882302)
			(xy 303.251811 -417.932799) (xy 303.267879 -417.986206) (xy 303.275999 -418.041382) (xy 303.276508 -418.069268)
			(xy 303.757582 -418.069268) (xy 303.761653 -418.013646) (xy 303.773779 -417.959209) (xy 303.793702 -417.907118)
			(xy 303.820998 -417.858483) (xy 303.855084 -417.81434) (xy 303.895233 -417.775631) (xy 303.940591 -417.74318)
			(xy 303.990191 -417.717679) (xy 304.042975 -417.699672) (xy 304.097818 -417.689542) (xy 304.153552 -417.687505)
			(xy 304.208989 -417.693605) (xy 304.262946 -417.707711) (xy 304.314275 -417.729523) (xy 304.361881 -417.758577)
			(xy 304.404749 -417.794252) (xy 304.441966 -417.835789) (xy 304.472739 -417.882302) (xy 304.496411 -417.932799)
			(xy 304.512479 -417.986206) (xy 304.520599 -418.041382) (xy 304.521108 -418.069268) (xy 304.520599 -418.097154)
			(xy 304.512479 -418.15233) (xy 304.496411 -418.205737) (xy 304.472739 -418.256234) (xy 304.441966 -418.302747)
			(xy 304.404749 -418.344284) (xy 304.361881 -418.379959) (xy 304.314275 -418.409013) (xy 304.262946 -418.430825)
			(xy 304.208989 -418.444931) (xy 304.153552 -418.451031) (xy 304.097818 -418.448994) (xy 304.042975 -418.438864)
			(xy 303.990191 -418.420857) (xy 303.940591 -418.395356) (xy 303.895233 -418.362905) (xy 303.855084 -418.324196)
			(xy 303.820998 -418.280053) (xy 303.793702 -418.231418) (xy 303.773779 -418.179327) (xy 303.761653 -418.12489)
			(xy 303.757582 -418.069268) (xy 303.276508 -418.069268) (xy 303.275999 -418.097154) (xy 303.267879 -418.15233)
			(xy 303.251811 -418.205737) (xy 303.228139 -418.256234) (xy 303.197366 -418.302747) (xy 303.160149 -418.344284)
			(xy 303.117281 -418.379959) (xy 303.069675 -418.409013) (xy 303.018346 -418.430825) (xy 302.964389 -418.444931)
			(xy 302.908952 -418.451031) (xy 302.853218 -418.448994) (xy 302.798375 -418.438864) (xy 302.745591 -418.420857)
			(xy 302.695991 -418.395356) (xy 302.650633 -418.362905) (xy 302.610484 -418.324196) (xy 302.576398 -418.280053)
			(xy 302.549102 -418.231418) (xy 302.529179 -418.179327) (xy 302.517053 -418.12489) (xy 302.512982 -418.069268)
			(xy 301.828335 -418.069268) (xy 301.827699 -418.07359) (xy 301.811631 -418.126997) (xy 301.787959 -418.177494)
			(xy 301.757186 -418.224007) (xy 301.719969 -418.265544) (xy 301.677101 -418.301219) (xy 301.629495 -418.330273)
			(xy 301.578166 -418.352085) (xy 301.524209 -418.366191) (xy 301.468772 -418.372291) (xy 301.413038 -418.370254)
			(xy 301.358195 -418.360124) (xy 301.305411 -418.342117) (xy 301.255811 -418.316616) (xy 301.210453 -418.284165)
			(xy 301.170304 -418.245456) (xy 301.136218 -418.201313) (xy 301.108922 -418.152678) (xy 301.088999 -418.100587)
			(xy 301.076873 -418.04615) (xy 301.072802 -417.990528) (xy 300.592211 -417.990528) (xy 300.588002 -418.047059)
			(xy 300.575466 -418.102368) (xy 300.554879 -418.155211) (xy 300.526697 -418.204424) (xy 300.491539 -418.248922)
			(xy 300.45018 -418.287726) (xy 300.403533 -418.319978) (xy 300.352625 -418.34497) (xy 300.298578 -418.362149)
			(xy 300.270672 -418.36721) (xy 300.228 -418.374068) (xy 300.228 -418.6936) (xy 299.794422 -419.127178)
			(xy 299.801026 -419.15461) (xy 299.80495 -419.17245) (xy 299.809149 -419.208736) (xy 299.809408 -419.227)
			(xy 299.809408 -419.73627) (xy 300.451264 -419.73627) (xy 300.455335 -419.680648) (xy 300.467461 -419.626211)
			(xy 300.487384 -419.57412) (xy 300.51468 -419.525485) (xy 300.548766 -419.481342) (xy 300.588915 -419.442633)
			(xy 300.634273 -419.410182) (xy 300.683873 -419.384681) (xy 300.736657 -419.366674) (xy 300.7915 -419.356544)
			(xy 300.847234 -419.354507) (xy 300.902671 -419.360607) (xy 300.956628 -419.374713) (xy 301.007957 -419.396525)
			(xy 301.055563 -419.425579) (xy 301.098431 -419.461254) (xy 301.135648 -419.502791) (xy 301.166421 -419.549304)
			(xy 301.190093 -419.599801) (xy 301.206161 -419.653208) (xy 301.214281 -419.708384) (xy 301.21479 -419.73627)
			(xy 301.214281 -419.764156) (xy 301.206161 -419.819332) (xy 301.200202 -419.83914) (xy 305.896262 -419.83914)
			(xy 305.900333 -419.783518) (xy 305.912459 -419.729081) (xy 305.932382 -419.67699) (xy 305.959678 -419.628355)
			(xy 305.993764 -419.584212) (xy 306.033913 -419.545503) (xy 306.079271 -419.513052) (xy 306.128871 -419.487551)
			(xy 306.181655 -419.469544) (xy 306.236498 -419.459414) (xy 306.292232 -419.457377) (xy 306.347669 -419.463477)
			(xy 306.401626 -419.477583) (xy 306.452955 -419.499395) (xy 306.500561 -419.528449) (xy 306.543429 -419.564124)
			(xy 306.580646 -419.605661) (xy 306.611419 -419.652174) (xy 306.635091 -419.702671) (xy 306.651159 -419.756078)
			(xy 306.659279 -419.811254) (xy 306.659788 -419.83914) (xy 306.659279 -419.867026) (xy 306.651159 -419.922202)
			(xy 306.635091 -419.975609) (xy 306.611419 -420.026106) (xy 306.580646 -420.072619) (xy 306.543429 -420.114156)
			(xy 306.500561 -420.149831) (xy 306.452955 -420.178885) (xy 306.401626 -420.200697) (xy 306.347669 -420.214803)
			(xy 306.292232 -420.220903) (xy 306.236498 -420.218866) (xy 306.181655 -420.208736) (xy 306.128871 -420.190729)
			(xy 306.079271 -420.165228) (xy 306.033913 -420.132777) (xy 305.993764 -420.094068) (xy 305.959678 -420.049925)
			(xy 305.932382 -420.00129) (xy 305.912459 -419.949199) (xy 305.900333 -419.894762) (xy 305.896262 -419.83914)
			(xy 301.200202 -419.83914) (xy 301.190093 -419.872739) (xy 301.166421 -419.923236) (xy 301.135648 -419.969749)
			(xy 301.098431 -420.011286) (xy 301.055563 -420.046961) (xy 301.007957 -420.076015) (xy 300.956628 -420.097827)
			(xy 300.902671 -420.111933) (xy 300.847234 -420.118033) (xy 300.7915 -420.115996) (xy 300.736657 -420.105866)
			(xy 300.683873 -420.087859) (xy 300.634273 -420.062358) (xy 300.588915 -420.029907) (xy 300.548766 -419.991198)
			(xy 300.51468 -419.947055) (xy 300.487384 -419.89842) (xy 300.467461 -419.846329) (xy 300.455335 -419.791892)
			(xy 300.451264 -419.73627) (xy 299.809408 -419.73627) (xy 299.809408 -420.87292) (xy 299.808947 -420.89791)
			(xy 299.80113 -420.947274) (xy 299.785675 -420.994803) (xy 299.762964 -421.039324) (xy 299.733559 -421.079738)
			(xy 299.71619 -421.09771) (xy 299.6946 -421.1193) (xy 299.6946 -421.23741) (xy 307.07406 -421.23741)
			(xy 307.078131 -421.181788) (xy 307.090257 -421.127351) (xy 307.11018 -421.07526) (xy 307.137476 -421.026625)
			(xy 307.171562 -420.982482) (xy 307.211711 -420.943773) (xy 307.257069 -420.911322) (xy 307.306669 -420.885821)
			(xy 307.359453 -420.867814) (xy 307.414296 -420.857684) (xy 307.47003 -420.855647) (xy 307.525467 -420.861747)
			(xy 307.579424 -420.875853) (xy 307.630753 -420.897665) (xy 307.678359 -420.926719) (xy 307.721227 -420.962394)
			(xy 307.758444 -421.003931) (xy 307.789217 -421.050444) (xy 307.812889 -421.100941) (xy 307.828957 -421.154348)
			(xy 307.837077 -421.209524) (xy 307.837586 -421.23741) (xy 307.837077 -421.265296) (xy 307.828957 -421.320472)
			(xy 307.812889 -421.373879) (xy 307.789217 -421.424376) (xy 307.758444 -421.470889) (xy 307.721227 -421.512426)
			(xy 307.678359 -421.548101) (xy 307.630753 -421.577155) (xy 307.579424 -421.598967) (xy 307.525467 -421.613073)
			(xy 307.47003 -421.619173) (xy 307.414296 -421.617136) (xy 307.359453 -421.607006) (xy 307.306669 -421.588999)
			(xy 307.257069 -421.563498) (xy 307.211711 -421.531047) (xy 307.171562 -421.492338) (xy 307.137476 -421.448195)
			(xy 307.11018 -421.39956) (xy 307.090257 -421.347469) (xy 307.078131 -421.293032) (xy 307.07406 -421.23741)
			(xy 299.6946 -421.23741) (xy 299.6946 -423.954448) (xy 300.255684 -423.954448) (xy 300.259755 -423.898826)
			(xy 300.271881 -423.844389) (xy 300.291804 -423.792298) (xy 300.3191 -423.743663) (xy 300.353186 -423.69952)
			(xy 300.393335 -423.660811) (xy 300.438693 -423.62836) (xy 300.488293 -423.602859) (xy 300.541077 -423.584852)
			(xy 300.59592 -423.574722) (xy 300.651654 -423.572685) (xy 300.707091 -423.578785) (xy 300.761048 -423.592891)
			(xy 300.812377 -423.614703) (xy 300.859983 -423.643757) (xy 300.902851 -423.679432) (xy 300.940068 -423.720969)
			(xy 300.970841 -423.767482) (xy 300.994513 -423.817979) (xy 301.010581 -423.871386) (xy 301.018701 -423.926562)
			(xy 301.01921 -423.954448) (xy 301.018701 -423.982334) (xy 301.011217 -424.033188) (xy 302.940464 -424.033188)
			(xy 302.944535 -423.977566) (xy 302.956661 -423.923129) (xy 302.976584 -423.871038) (xy 303.00388 -423.822403)
			(xy 303.037966 -423.77826) (xy 303.078115 -423.739551) (xy 303.123473 -423.7071) (xy 303.173073 -423.681599)
			(xy 303.225857 -423.663592) (xy 303.2807 -423.653462) (xy 303.336434 -423.651425) (xy 303.391871 -423.657525)
			(xy 303.445828 -423.671631) (xy 303.497157 -423.693443) (xy 303.544763 -423.722497) (xy 303.587631 -423.758172)
			(xy 303.624848 -423.799709) (xy 303.655621 -423.846222) (xy 303.679293 -423.896719) (xy 303.695361 -423.950126)
			(xy 303.703481 -424.005302) (xy 303.70399 -424.033188) (xy 303.703481 -424.061074) (xy 303.695361 -424.11625)
			(xy 303.679293 -424.169657) (xy 303.655621 -424.220154) (xy 303.624848 -424.266667) (xy 303.587631 -424.308204)
			(xy 303.544763 -424.343879) (xy 303.497157 -424.372933) (xy 303.445828 -424.394745) (xy 303.391871 -424.408851)
			(xy 303.336434 -424.414951) (xy 303.2807 -424.412914) (xy 303.225857 -424.402784) (xy 303.173073 -424.384777)
			(xy 303.123473 -424.359276) (xy 303.078115 -424.326825) (xy 303.037966 -424.288116) (xy 303.00388 -424.243973)
			(xy 302.976584 -424.195338) (xy 302.956661 -424.143247) (xy 302.944535 -424.08881) (xy 302.940464 -424.033188)
			(xy 301.011217 -424.033188) (xy 301.010581 -424.03751) (xy 300.994513 -424.090917) (xy 300.970841 -424.141414)
			(xy 300.940068 -424.187927) (xy 300.902851 -424.229464) (xy 300.859983 -424.265139) (xy 300.812377 -424.294193)
			(xy 300.761048 -424.316005) (xy 300.707091 -424.330111) (xy 300.651654 -424.336211) (xy 300.59592 -424.334174)
			(xy 300.541077 -424.324044) (xy 300.488293 -424.306037) (xy 300.438693 -424.280536) (xy 300.393335 -424.248085)
			(xy 300.353186 -424.209376) (xy 300.3191 -424.165233) (xy 300.291804 -424.116598) (xy 300.271881 -424.064507)
			(xy 300.259755 -424.01007) (xy 300.255684 -423.954448) (xy 299.6946 -423.954448) (xy 299.6946 -425.831)
			(xy 307.968902 -425.831) (xy 307.972973 -425.775378) (xy 307.985099 -425.720941) (xy 308.005022 -425.66885)
			(xy 308.032318 -425.620215) (xy 308.066404 -425.576072) (xy 308.106553 -425.537363) (xy 308.151911 -425.504912)
			(xy 308.201511 -425.479411) (xy 308.254295 -425.461404) (xy 308.309138 -425.451274) (xy 308.364872 -425.449237)
			(xy 308.420309 -425.455337) (xy 308.474266 -425.469443) (xy 308.525595 -425.491255) (xy 308.573201 -425.520309)
			(xy 308.616069 -425.555984) (xy 308.653286 -425.597521) (xy 308.684059 -425.644034) (xy 308.707731 -425.694531)
			(xy 308.723799 -425.747938) (xy 308.731919 -425.803114) (xy 308.732428 -425.831) (xy 308.731919 -425.858886)
			(xy 308.723799 -425.914062) (xy 308.707731 -425.967469) (xy 308.684059 -426.017966) (xy 308.653286 -426.064479)
			(xy 308.616069 -426.106016) (xy 308.573201 -426.141691) (xy 308.525595 -426.170745) (xy 308.474266 -426.192557)
			(xy 308.420309 -426.206663) (xy 308.364872 -426.212763) (xy 308.309138 -426.210726) (xy 308.254295 -426.200596)
			(xy 308.201511 -426.182589) (xy 308.151911 -426.157088) (xy 308.106553 -426.124637) (xy 308.066404 -426.085928)
			(xy 308.032318 -426.041785) (xy 308.005022 -425.99315) (xy 307.985099 -425.941059) (xy 307.972973 -425.886622)
			(xy 307.968902 -425.831) (xy 299.6946 -425.831) (xy 299.6946 -427.168818) (xy 304.699922 -427.168818)
			(xy 304.703993 -427.113196) (xy 304.716119 -427.058759) (xy 304.736042 -427.006668) (xy 304.763338 -426.958033)
			(xy 304.797424 -426.91389) (xy 304.837573 -426.875181) (xy 304.882931 -426.84273) (xy 304.932531 -426.817229)
			(xy 304.985315 -426.799222) (xy 305.040158 -426.789092) (xy 305.095892 -426.787055) (xy 305.151329 -426.793155)
			(xy 305.205286 -426.807261) (xy 305.256615 -426.829073) (xy 305.304221 -426.858127) (xy 305.347089 -426.893802)
			(xy 305.384306 -426.935339) (xy 305.415079 -426.981852) (xy 305.438751 -427.032349) (xy 305.454819 -427.085756)
			(xy 305.462939 -427.140932) (xy 305.463448 -427.168818) (xy 305.462939 -427.196704) (xy 305.454819 -427.25188)
			(xy 305.438751 -427.305287) (xy 305.415079 -427.355784) (xy 305.384306 -427.402297) (xy 305.347089 -427.443834)
			(xy 305.304221 -427.479509) (xy 305.256615 -427.508563) (xy 305.205286 -427.530375) (xy 305.151329 -427.544481)
			(xy 305.095892 -427.550581) (xy 305.040158 -427.548544) (xy 304.985315 -427.538414) (xy 304.932531 -427.520407)
			(xy 304.882931 -427.494906) (xy 304.837573 -427.462455) (xy 304.797424 -427.423746) (xy 304.763338 -427.379603)
			(xy 304.736042 -427.330968) (xy 304.716119 -427.278877) (xy 304.703993 -427.22444) (xy 304.699922 -427.168818)
			(xy 299.6946 -427.168818) (xy 299.6946 -427.8122) (xy 300.04512 -428.16272) (xy 306.241702 -428.16272)
			(xy 306.245773 -428.107098) (xy 306.257899 -428.052661) (xy 306.277822 -428.00057) (xy 306.305118 -427.951935)
			(xy 306.339204 -427.907792) (xy 306.379353 -427.869083) (xy 306.424711 -427.836632) (xy 306.474311 -427.811131)
			(xy 306.527095 -427.793124) (xy 306.581938 -427.782994) (xy 306.637672 -427.780957) (xy 306.693109 -427.787057)
			(xy 306.747066 -427.801163) (xy 306.798395 -427.822975) (xy 306.846001 -427.852029) (xy 306.865288 -427.86808)
			(xy 308.789322 -427.86808) (xy 308.793393 -427.812458) (xy 308.805519 -427.758021) (xy 308.825442 -427.70593)
			(xy 308.852738 -427.657295) (xy 308.886824 -427.613152) (xy 308.926973 -427.574443) (xy 308.972331 -427.541992)
			(xy 309.021931 -427.516491) (xy 309.074715 -427.498484) (xy 309.129558 -427.488354) (xy 309.185292 -427.486317)
			(xy 309.240729 -427.492417) (xy 309.294686 -427.506523) (xy 309.346015 -427.528335) (xy 309.393621 -427.557389)
			(xy 309.436489 -427.593064) (xy 309.473706 -427.634601) (xy 309.504479 -427.681114) (xy 309.528151 -427.731611)
			(xy 309.544219 -427.785018) (xy 309.552339 -427.840194) (xy 309.552848 -427.86808) (xy 309.552339 -427.895966)
			(xy 309.544219 -427.951142) (xy 309.528151 -428.004549) (xy 309.504479 -428.055046) (xy 309.473706 -428.101559)
			(xy 309.436489 -428.143096) (xy 309.393621 -428.178771) (xy 309.346015 -428.207825) (xy 309.294686 -428.229637)
			(xy 309.240729 -428.243743) (xy 309.185292 -428.249843) (xy 309.129558 -428.247806) (xy 309.074715 -428.237676)
			(xy 309.021931 -428.219669) (xy 308.972331 -428.194168) (xy 308.926973 -428.161717) (xy 308.886824 -428.123008)
			(xy 308.852738 -428.078865) (xy 308.825442 -428.03023) (xy 308.805519 -427.978139) (xy 308.793393 -427.923702)
			(xy 308.789322 -427.86808) (xy 306.865288 -427.86808) (xy 306.888869 -427.887704) (xy 306.926086 -427.929241)
			(xy 306.956859 -427.975754) (xy 306.980531 -428.026251) (xy 306.996599 -428.079658) (xy 307.004719 -428.134834)
			(xy 307.005228 -428.16272) (xy 307.004719 -428.190606) (xy 306.996599 -428.245782) (xy 306.980531 -428.299189)
			(xy 306.956859 -428.349686) (xy 306.926086 -428.396199) (xy 306.888869 -428.437736) (xy 306.846001 -428.473411)
			(xy 306.798395 -428.502465) (xy 306.747066 -428.524277) (xy 306.693109 -428.538383) (xy 306.637672 -428.544483)
			(xy 306.581938 -428.542446) (xy 306.527095 -428.532316) (xy 306.474311 -428.514309) (xy 306.424711 -428.488808)
			(xy 306.379353 -428.456357) (xy 306.339204 -428.417648) (xy 306.305118 -428.373505) (xy 306.277822 -428.32487)
			(xy 306.257899 -428.272779) (xy 306.245773 -428.218342) (xy 306.241702 -428.16272) (xy 300.04512 -428.16272)
			(xy 300.73346 -428.85106) (xy 302.064672 -428.85106) (xy 302.068743 -428.795438) (xy 302.080869 -428.741001)
			(xy 302.100792 -428.68891) (xy 302.128088 -428.640275) (xy 302.162174 -428.596132) (xy 302.202323 -428.557423)
			(xy 302.247681 -428.524972) (xy 302.297281 -428.499471) (xy 302.350065 -428.481464) (xy 302.404908 -428.471334)
			(xy 302.460642 -428.469297) (xy 302.516079 -428.475397) (xy 302.570036 -428.489503) (xy 302.621365 -428.511315)
			(xy 302.668971 -428.540369) (xy 302.711839 -428.576044) (xy 302.749056 -428.617581) (xy 302.779829 -428.664094)
			(xy 302.803501 -428.714591) (xy 302.819569 -428.767998) (xy 302.827689 -428.823174) (xy 302.828198 -428.85106)
			(xy 302.827989 -428.86249) (xy 304.800252 -428.86249) (xy 304.804323 -428.806868) (xy 304.816449 -428.752431)
			(xy 304.836372 -428.70034) (xy 304.863668 -428.651705) (xy 304.897754 -428.607562) (xy 304.937903 -428.568853)
			(xy 304.983261 -428.536402) (xy 305.032861 -428.510901) (xy 305.085645 -428.492894) (xy 305.140488 -428.482764)
			(xy 305.196222 -428.480727) (xy 305.251659 -428.486827) (xy 305.305616 -428.500933) (xy 305.356945 -428.522745)
			(xy 305.404551 -428.551799) (xy 305.447419 -428.587474) (xy 305.484636 -428.629011) (xy 305.515409 -428.675524)
			(xy 305.539081 -428.726021) (xy 305.555149 -428.779428) (xy 305.563269 -428.834604) (xy 305.563778 -428.86249)
			(xy 305.563269 -428.890376) (xy 305.557467 -428.9298) (xy 307.543452 -428.9298) (xy 307.547523 -428.874178)
			(xy 307.559649 -428.819741) (xy 307.579572 -428.76765) (xy 307.606868 -428.719015) (xy 307.640954 -428.674872)
			(xy 307.681103 -428.636163) (xy 307.726461 -428.603712) (xy 307.776061 -428.578211) (xy 307.828845 -428.560204)
			(xy 307.883688 -428.550074) (xy 307.939422 -428.548037) (xy 307.994859 -428.554137) (xy 308.048816 -428.568243)
			(xy 308.100145 -428.590055) (xy 308.147751 -428.619109) (xy 308.190619 -428.654784) (xy 308.227836 -428.696321)
			(xy 308.258609 -428.742834) (xy 308.282281 -428.793331) (xy 308.298349 -428.846738) (xy 308.306469 -428.901914)
			(xy 308.306978 -428.9298) (xy 308.306469 -428.957686) (xy 308.298349 -429.012862) (xy 308.282281 -429.066269)
			(xy 308.258609 -429.116766) (xy 308.227836 -429.163279) (xy 308.190619 -429.204816) (xy 308.147751 -429.240491)
			(xy 308.100145 -429.269545) (xy 308.048816 -429.291357) (xy 307.994859 -429.305463) (xy 307.939422 -429.311563)
			(xy 307.883688 -429.309526) (xy 307.828845 -429.299396) (xy 307.776061 -429.281389) (xy 307.726461 -429.255888)
			(xy 307.681103 -429.223437) (xy 307.640954 -429.184728) (xy 307.606868 -429.140585) (xy 307.579572 -429.09195)
			(xy 307.559649 -429.039859) (xy 307.547523 -428.985422) (xy 307.543452 -428.9298) (xy 305.557467 -428.9298)
			(xy 305.555149 -428.945552) (xy 305.539081 -428.998959) (xy 305.515409 -429.049456) (xy 305.484636 -429.095969)
			(xy 305.447419 -429.137506) (xy 305.404551 -429.173181) (xy 305.356945 -429.202235) (xy 305.305616 -429.224047)
			(xy 305.251659 -429.238153) (xy 305.196222 -429.244253) (xy 305.140488 -429.242216) (xy 305.085645 -429.232086)
			(xy 305.032861 -429.214079) (xy 304.983261 -429.188578) (xy 304.937903 -429.156127) (xy 304.897754 -429.117418)
			(xy 304.863668 -429.073275) (xy 304.836372 -429.02464) (xy 304.816449 -428.972549) (xy 304.804323 -428.918112)
			(xy 304.800252 -428.86249) (xy 302.827989 -428.86249) (xy 302.827689 -428.878946) (xy 302.819569 -428.934122)
			(xy 302.803501 -428.987529) (xy 302.779829 -429.038026) (xy 302.749056 -429.084539) (xy 302.711839 -429.126076)
			(xy 302.668971 -429.161751) (xy 302.621365 -429.190805) (xy 302.570036 -429.212617) (xy 302.516079 -429.226723)
			(xy 302.460642 -429.232823) (xy 302.404908 -429.230786) (xy 302.350065 -429.220656) (xy 302.297281 -429.202649)
			(xy 302.247681 -429.177148) (xy 302.202323 -429.144697) (xy 302.162174 -429.105988) (xy 302.128088 -429.061845)
			(xy 302.100792 -429.01321) (xy 302.080869 -428.961119) (xy 302.068743 -428.906682) (xy 302.064672 -428.85106)
			(xy 300.73346 -428.85106) (xy 301.503588 -429.621188) (xy 302.472342 -429.621188) (xy 302.476413 -429.565566)
			(xy 302.488539 -429.511129) (xy 302.508462 -429.459038) (xy 302.535758 -429.410403) (xy 302.569844 -429.36626)
			(xy 302.609993 -429.327551) (xy 302.655351 -429.2951) (xy 302.704951 -429.269599) (xy 302.757735 -429.251592)
			(xy 302.812578 -429.241462) (xy 302.868312 -429.239425) (xy 302.923749 -429.245525) (xy 302.977706 -429.259631)
			(xy 303.029035 -429.281443) (xy 303.076641 -429.310497) (xy 303.119509 -429.346172) (xy 303.156726 -429.387709)
			(xy 303.187499 -429.434222) (xy 303.211171 -429.484719) (xy 303.227239 -429.538126) (xy 303.235359 -429.593302)
			(xy 303.235868 -429.621188) (xy 303.716942 -429.621188) (xy 303.721013 -429.565566) (xy 303.733139 -429.511129)
			(xy 303.753062 -429.459038) (xy 303.780358 -429.410403) (xy 303.814444 -429.36626) (xy 303.854593 -429.327551)
			(xy 303.899951 -429.2951) (xy 303.949551 -429.269599) (xy 304.002335 -429.251592) (xy 304.057178 -429.241462)
			(xy 304.112912 -429.239425) (xy 304.168349 -429.245525) (xy 304.222306 -429.259631) (xy 304.273635 -429.281443)
			(xy 304.321241 -429.310497) (xy 304.364109 -429.346172) (xy 304.401326 -429.387709) (xy 304.432099 -429.434222)
			(xy 304.455771 -429.484719) (xy 304.471839 -429.538126) (xy 304.479959 -429.593302) (xy 304.480468 -429.621188)
			(xy 304.480259 -429.632618) (xy 305.207922 -429.632618) (xy 305.211993 -429.576996) (xy 305.224119 -429.522559)
			(xy 305.244042 -429.470468) (xy 305.271338 -429.421833) (xy 305.305424 -429.37769) (xy 305.345573 -429.338981)
			(xy 305.390931 -429.30653) (xy 305.440531 -429.281029) (xy 305.493315 -429.263022) (xy 305.548158 -429.252892)
			(xy 305.603892 -429.250855) (xy 305.659329 -429.256955) (xy 305.713286 -429.271061) (xy 305.764615 -429.292873)
			(xy 305.812221 -429.321927) (xy 305.855089 -429.357602) (xy 305.892306 -429.399139) (xy 305.923079 -429.445652)
			(xy 305.946751 -429.496149) (xy 305.962819 -429.549556) (xy 305.970939 -429.604732) (xy 305.971448 -429.632618)
			(xy 306.452522 -429.632618) (xy 306.456593 -429.576996) (xy 306.468719 -429.522559) (xy 306.488642 -429.470468)
			(xy 306.515938 -429.421833) (xy 306.550024 -429.37769) (xy 306.590173 -429.338981) (xy 306.635531 -429.30653)
			(xy 306.685131 -429.281029) (xy 306.737915 -429.263022) (xy 306.792758 -429.252892) (xy 306.848492 -429.250855)
			(xy 306.903929 -429.256955) (xy 306.957886 -429.271061) (xy 307.009215 -429.292873) (xy 307.056821 -429.321927)
			(xy 307.099689 -429.357602) (xy 307.136906 -429.399139) (xy 307.167679 -429.445652) (xy 307.191351 -429.496149)
			(xy 307.207419 -429.549556) (xy 307.215539 -429.604732) (xy 307.216048 -429.632618) (xy 307.215539 -429.660504)
			(xy 307.209737 -429.699928) (xy 307.951122 -429.699928) (xy 307.955193 -429.644306) (xy 307.967319 -429.589869)
			(xy 307.987242 -429.537778) (xy 308.014538 -429.489143) (xy 308.048624 -429.445) (xy 308.088773 -429.406291)
			(xy 308.134131 -429.37384) (xy 308.183731 -429.348339) (xy 308.236515 -429.330332) (xy 308.291358 -429.320202)
			(xy 308.347092 -429.318165) (xy 308.402529 -429.324265) (xy 308.456486 -429.338371) (xy 308.507815 -429.360183)
			(xy 308.555421 -429.389237) (xy 308.598289 -429.424912) (xy 308.635506 -429.466449) (xy 308.666279 -429.512962)
			(xy 308.689951 -429.563459) (xy 308.706019 -429.616866) (xy 308.714139 -429.672042) (xy 308.714648 -429.699928)
			(xy 309.195722 -429.699928) (xy 309.199793 -429.644306) (xy 309.211919 -429.589869) (xy 309.231842 -429.537778)
			(xy 309.259138 -429.489143) (xy 309.293224 -429.445) (xy 309.333373 -429.406291) (xy 309.378731 -429.37384)
			(xy 309.428331 -429.348339) (xy 309.481115 -429.330332) (xy 309.535958 -429.320202) (xy 309.591692 -429.318165)
			(xy 309.647129 -429.324265) (xy 309.701086 -429.338371) (xy 309.752415 -429.360183) (xy 309.800021 -429.389237)
			(xy 309.842889 -429.424912) (xy 309.880106 -429.466449) (xy 309.910879 -429.512962) (xy 309.934551 -429.563459)
			(xy 309.950619 -429.616866) (xy 309.958739 -429.672042) (xy 309.959248 -429.699928) (xy 309.958739 -429.727814)
			(xy 309.950619 -429.78299) (xy 309.934551 -429.836397) (xy 309.910879 -429.886894) (xy 309.880106 -429.933407)
			(xy 309.842889 -429.974944) (xy 309.800021 -430.010619) (xy 309.752415 -430.039673) (xy 309.701086 -430.061485)
			(xy 309.647129 -430.075591) (xy 309.591692 -430.081691) (xy 309.535958 -430.079654) (xy 309.481115 -430.069524)
			(xy 309.428331 -430.051517) (xy 309.378731 -430.026016) (xy 309.333373 -429.993565) (xy 309.293224 -429.954856)
			(xy 309.259138 -429.910713) (xy 309.231842 -429.862078) (xy 309.211919 -429.809987) (xy 309.199793 -429.75555)
			(xy 309.195722 -429.699928) (xy 308.714648 -429.699928) (xy 308.714139 -429.727814) (xy 308.706019 -429.78299)
			(xy 308.689951 -429.836397) (xy 308.666279 -429.886894) (xy 308.635506 -429.933407) (xy 308.598289 -429.974944)
			(xy 308.555421 -430.010619) (xy 308.507815 -430.039673) (xy 308.456486 -430.061485) (xy 308.402529 -430.075591)
			(xy 308.347092 -430.081691) (xy 308.291358 -430.079654) (xy 308.236515 -430.069524) (xy 308.183731 -430.051517)
			(xy 308.134131 -430.026016) (xy 308.088773 -429.993565) (xy 308.048624 -429.954856) (xy 308.014538 -429.910713)
			(xy 307.987242 -429.862078) (xy 307.967319 -429.809987) (xy 307.955193 -429.75555) (xy 307.951122 -429.699928)
			(xy 307.209737 -429.699928) (xy 307.207419 -429.71568) (xy 307.191351 -429.769087) (xy 307.167679 -429.819584)
			(xy 307.136906 -429.866097) (xy 307.099689 -429.907634) (xy 307.056821 -429.943309) (xy 307.009215 -429.972363)
			(xy 306.957886 -429.994175) (xy 306.903929 -430.008281) (xy 306.848492 -430.014381) (xy 306.792758 -430.012344)
			(xy 306.737915 -430.002214) (xy 306.685131 -429.984207) (xy 306.635531 -429.958706) (xy 306.590173 -429.926255)
			(xy 306.550024 -429.887546) (xy 306.515938 -429.843403) (xy 306.488642 -429.794768) (xy 306.468719 -429.742677)
			(xy 306.456593 -429.68824) (xy 306.452522 -429.632618) (xy 305.971448 -429.632618) (xy 305.970939 -429.660504)
			(xy 305.962819 -429.71568) (xy 305.946751 -429.769087) (xy 305.923079 -429.819584) (xy 305.892306 -429.866097)
			(xy 305.855089 -429.907634) (xy 305.812221 -429.943309) (xy 305.764615 -429.972363) (xy 305.713286 -429.994175)
			(xy 305.659329 -430.008281) (xy 305.603892 -430.014381) (xy 305.548158 -430.012344) (xy 305.493315 -430.002214)
			(xy 305.440531 -429.984207) (xy 305.390931 -429.958706) (xy 305.345573 -429.926255) (xy 305.305424 -429.887546)
			(xy 305.271338 -429.843403) (xy 305.244042 -429.794768) (xy 305.224119 -429.742677) (xy 305.211993 -429.68824)
			(xy 305.207922 -429.632618) (xy 304.480259 -429.632618) (xy 304.479959 -429.649074) (xy 304.471839 -429.70425)
			(xy 304.455771 -429.757657) (xy 304.432099 -429.808154) (xy 304.401326 -429.854667) (xy 304.364109 -429.896204)
			(xy 304.321241 -429.931879) (xy 304.273635 -429.960933) (xy 304.222306 -429.982745) (xy 304.168349 -429.996851)
			(xy 304.112912 -430.002951) (xy 304.057178 -430.000914) (xy 304.002335 -429.990784) (xy 303.949551 -429.972777)
			(xy 303.899951 -429.947276) (xy 303.854593 -429.914825) (xy 303.814444 -429.876116) (xy 303.780358 -429.831973)
			(xy 303.753062 -429.783338) (xy 303.733139 -429.731247) (xy 303.721013 -429.67681) (xy 303.716942 -429.621188)
			(xy 303.235868 -429.621188) (xy 303.235359 -429.649074) (xy 303.227239 -429.70425) (xy 303.211171 -429.757657)
			(xy 303.187499 -429.808154) (xy 303.156726 -429.854667) (xy 303.119509 -429.896204) (xy 303.076641 -429.931879)
			(xy 303.029035 -429.960933) (xy 302.977706 -429.982745) (xy 302.923749 -429.996851) (xy 302.868312 -430.002951)
			(xy 302.812578 -430.000914) (xy 302.757735 -429.990784) (xy 302.704951 -429.972777) (xy 302.655351 -429.947276)
			(xy 302.609993 -429.914825) (xy 302.569844 -429.876116) (xy 302.535758 -429.831973) (xy 302.508462 -429.783338)
			(xy 302.488539 -429.731247) (xy 302.476413 -429.67681) (xy 302.472342 -429.621188) (xy 301.503588 -429.621188)
			(xy 302.2854 -430.403) (xy 302.2854 -431.36693) (xy 303.095404 -431.36693) (xy 303.099475 -431.311308)
			(xy 303.111601 -431.256871) (xy 303.131524 -431.20478) (xy 303.15882 -431.156145) (xy 303.192906 -431.112002)
			(xy 303.233055 -431.073293) (xy 303.278413 -431.040842) (xy 303.328013 -431.015341) (xy 303.380797 -430.997334)
			(xy 303.43564 -430.987204) (xy 303.491374 -430.985167) (xy 303.546811 -430.991267) (xy 303.600768 -431.005373)
			(xy 303.652097 -431.027185) (xy 303.699703 -431.056239) (xy 303.742571 -431.091914) (xy 303.779788 -431.133451)
			(xy 303.810561 -431.179964) (xy 303.834233 -431.230461) (xy 303.850301 -431.283868) (xy 303.858421 -431.339044)
			(xy 303.85893 -431.36693) (xy 303.858721 -431.37836) (xy 305.830984 -431.37836) (xy 305.835055 -431.322738)
			(xy 305.847181 -431.268301) (xy 305.867104 -431.21621) (xy 305.8944 -431.167575) (xy 305.928486 -431.123432)
			(xy 305.968635 -431.084723) (xy 306.013993 -431.052272) (xy 306.063593 -431.026771) (xy 306.116377 -431.008764)
			(xy 306.17122 -430.998634) (xy 306.226954 -430.996597) (xy 306.282391 -431.002697) (xy 306.336348 -431.016803)
			(xy 306.387677 -431.038615) (xy 306.435283 -431.067669) (xy 306.478151 -431.103344) (xy 306.515368 -431.144881)
			(xy 306.546141 -431.191394) (xy 306.569813 -431.241891) (xy 306.585881 -431.295298) (xy 306.594001 -431.350474)
			(xy 306.59451 -431.37836) (xy 306.594001 -431.406246) (xy 306.588199 -431.44567) (xy 308.574184 -431.44567)
			(xy 308.578255 -431.390048) (xy 308.590381 -431.335611) (xy 308.610304 -431.28352) (xy 308.6376 -431.234885)
			(xy 308.671686 -431.190742) (xy 308.711835 -431.152033) (xy 308.757193 -431.119582) (xy 308.806793 -431.094081)
			(xy 308.859577 -431.076074) (xy 308.91442 -431.065944) (xy 308.970154 -431.063907) (xy 309.025591 -431.070007)
			(xy 309.079548 -431.084113) (xy 309.130877 -431.105925) (xy 309.178483 -431.134979) (xy 309.221351 -431.170654)
			(xy 309.258568 -431.212191) (xy 309.289341 -431.258704) (xy 309.313013 -431.309201) (xy 309.329081 -431.362608)
			(xy 309.337201 -431.417784) (xy 309.33771 -431.44567) (xy 309.337201 -431.473556) (xy 309.329081 -431.528732)
			(xy 309.313013 -431.582139) (xy 309.289341 -431.632636) (xy 309.258568 -431.679149) (xy 309.221351 -431.720686)
			(xy 309.178483 -431.756361) (xy 309.130877 -431.785415) (xy 309.079548 -431.807227) (xy 309.025591 -431.821333)
			(xy 308.970154 -431.827433) (xy 308.91442 -431.825396) (xy 308.859577 -431.815266) (xy 308.806793 -431.797259)
			(xy 308.757193 -431.771758) (xy 308.711835 -431.739307) (xy 308.671686 -431.700598) (xy 308.6376 -431.656455)
			(xy 308.610304 -431.60782) (xy 308.590381 -431.555729) (xy 308.578255 -431.501292) (xy 308.574184 -431.44567)
			(xy 306.588199 -431.44567) (xy 306.585881 -431.461422) (xy 306.569813 -431.514829) (xy 306.546141 -431.565326)
			(xy 306.515368 -431.611839) (xy 306.478151 -431.653376) (xy 306.435283 -431.689051) (xy 306.387677 -431.718105)
			(xy 306.336348 -431.739917) (xy 306.282391 -431.754023) (xy 306.226954 -431.760123) (xy 306.17122 -431.758086)
			(xy 306.116377 -431.747956) (xy 306.063593 -431.729949) (xy 306.013993 -431.704448) (xy 305.968635 -431.671997)
			(xy 305.928486 -431.633288) (xy 305.8944 -431.589145) (xy 305.867104 -431.54051) (xy 305.847181 -431.488419)
			(xy 305.835055 -431.433982) (xy 305.830984 -431.37836) (xy 303.858721 -431.37836) (xy 303.858421 -431.394816)
			(xy 303.850301 -431.449992) (xy 303.834233 -431.503399) (xy 303.810561 -431.553896) (xy 303.779788 -431.600409)
			(xy 303.742571 -431.641946) (xy 303.699703 -431.677621) (xy 303.652097 -431.706675) (xy 303.600768 -431.728487)
			(xy 303.546811 -431.742593) (xy 303.491374 -431.748693) (xy 303.43564 -431.746656) (xy 303.380797 -431.736526)
			(xy 303.328013 -431.718519) (xy 303.278413 -431.693018) (xy 303.233055 -431.660567) (xy 303.192906 -431.621858)
			(xy 303.15882 -431.577715) (xy 303.131524 -431.52908) (xy 303.111601 -431.476989) (xy 303.099475 -431.422552)
			(xy 303.095404 -431.36693) (xy 302.2854 -431.36693) (xy 302.2854 -435.585108) (xy 302.899824 -435.585108)
			(xy 302.903895 -435.529486) (xy 302.916021 -435.475049) (xy 302.935944 -435.422958) (xy 302.96324 -435.374323)
			(xy 302.997326 -435.33018) (xy 303.037475 -435.291471) (xy 303.082833 -435.25902) (xy 303.132433 -435.233519)
			(xy 303.185217 -435.215512) (xy 303.24006 -435.205382) (xy 303.295794 -435.203345) (xy 303.351231 -435.209445)
			(xy 303.405188 -435.223551) (xy 303.456517 -435.245363) (xy 303.504123 -435.274417) (xy 303.546991 -435.310092)
			(xy 303.584208 -435.351629) (xy 303.614981 -435.398142) (xy 303.638653 -435.448639) (xy 303.654721 -435.502046)
			(xy 303.662841 -435.557222) (xy 303.66335 -435.585108) (xy 303.663141 -435.596538) (xy 305.635404 -435.596538)
			(xy 305.639475 -435.540916) (xy 305.651601 -435.486479) (xy 305.671524 -435.434388) (xy 305.69882 -435.385753)
			(xy 305.732906 -435.34161) (xy 305.773055 -435.302901) (xy 305.818413 -435.27045) (xy 305.868013 -435.244949)
			(xy 305.920797 -435.226942) (xy 305.97564 -435.216812) (xy 306.031374 -435.214775) (xy 306.086811 -435.220875)
			(xy 306.140768 -435.234981) (xy 306.192097 -435.256793) (xy 306.239703 -435.285847) (xy 306.282571 -435.321522)
			(xy 306.319788 -435.363059) (xy 306.350561 -435.409572) (xy 306.374233 -435.460069) (xy 306.390301 -435.513476)
			(xy 306.398421 -435.568652) (xy 306.39893 -435.596538) (xy 306.398421 -435.624424) (xy 306.392619 -435.663848)
			(xy 308.378604 -435.663848) (xy 308.382675 -435.608226) (xy 308.394801 -435.553789) (xy 308.414724 -435.501698)
			(xy 308.44202 -435.453063) (xy 308.476106 -435.40892) (xy 308.516255 -435.370211) (xy 308.561613 -435.33776)
			(xy 308.611213 -435.312259) (xy 308.663997 -435.294252) (xy 308.71884 -435.284122) (xy 308.774574 -435.282085)
			(xy 308.830011 -435.288185) (xy 308.883968 -435.302291) (xy 308.935297 -435.324103) (xy 308.982903 -435.353157)
			(xy 309.025771 -435.388832) (xy 309.062988 -435.430369) (xy 309.093761 -435.476882) (xy 309.117433 -435.527379)
			(xy 309.133501 -435.580786) (xy 309.141621 -435.635962) (xy 309.14213 -435.663848) (xy 309.141621 -435.691734)
			(xy 309.133501 -435.74691) (xy 309.117433 -435.800317) (xy 309.093761 -435.850814) (xy 309.062988 -435.897327)
			(xy 309.025771 -435.938864) (xy 308.982903 -435.974539) (xy 308.935297 -436.003593) (xy 308.883968 -436.025405)
			(xy 308.830011 -436.039511) (xy 308.774574 -436.045611) (xy 308.71884 -436.043574) (xy 308.663997 -436.033444)
			(xy 308.611213 -436.015437) (xy 308.561613 -435.989936) (xy 308.516255 -435.957485) (xy 308.476106 -435.918776)
			(xy 308.44202 -435.874633) (xy 308.414724 -435.825998) (xy 308.394801 -435.773907) (xy 308.382675 -435.71947)
			(xy 308.378604 -435.663848) (xy 306.392619 -435.663848) (xy 306.390301 -435.6796) (xy 306.374233 -435.733007)
			(xy 306.350561 -435.783504) (xy 306.319788 -435.830017) (xy 306.282571 -435.871554) (xy 306.239703 -435.907229)
			(xy 306.192097 -435.936283) (xy 306.140768 -435.958095) (xy 306.086811 -435.972201) (xy 306.031374 -435.978301)
			(xy 305.97564 -435.976264) (xy 305.920797 -435.966134) (xy 305.868013 -435.948127) (xy 305.818413 -435.922626)
			(xy 305.773055 -435.890175) (xy 305.732906 -435.851466) (xy 305.69882 -435.807323) (xy 305.671524 -435.758688)
			(xy 305.651601 -435.706597) (xy 305.639475 -435.65216) (xy 305.635404 -435.596538) (xy 303.663141 -435.596538)
			(xy 303.662841 -435.612994) (xy 303.654721 -435.66817) (xy 303.638653 -435.721577) (xy 303.614981 -435.772074)
			(xy 303.584208 -435.818587) (xy 303.546991 -435.860124) (xy 303.504123 -435.895799) (xy 303.456517 -435.924853)
			(xy 303.405188 -435.946665) (xy 303.351231 -435.960771) (xy 303.295794 -435.966871) (xy 303.24006 -435.964834)
			(xy 303.185217 -435.954704) (xy 303.132433 -435.936697) (xy 303.082833 -435.911196) (xy 303.037475 -435.878745)
			(xy 302.997326 -435.840036) (xy 302.96324 -435.795893) (xy 302.935944 -435.747258) (xy 302.916021 -435.695167)
			(xy 302.903895 -435.64073) (xy 302.899824 -435.585108) (xy 302.2854 -435.585108) (xy 302.2854 -438.277)
			(xy 303.1236 -439.1152) (xy 309.372 -439.1152)
		)
		(stroke
			(width 0)
			(type solid)
		)
		(fill yes)
		(layer "In11.Cu")
		(net "P3V3_AUX")
	)
	(gr_poly
		(pts
			(xy 368.50828 -222.150178) (xy 368.525984 -222.149816) (xy 368.560854 -222.14367) (xy 368.594126 -222.131561)
			(xy 368.609626 -222.123) (xy 368.61115 -222.122238) (xy 368.621056 -222.11665) (xy 368.656087 -222.097839)
			(xy 368.729381 -222.067001) (xy 368.80557 -222.044237) (xy 368.883768 -222.029812) (xy 368.963064 -222.023894)
			(xy 369.002818 -222.024702) (xy 369.012216 -222.024956) (xy 369.025585 -222.025157) (xy 369.051681 -222.019376)
			(xy 369.075374 -222.007005) (xy 369.095032 -221.988895) (xy 369.109301 -221.966294) (xy 369.117197 -221.940759)
			(xy 369.118134 -221.92742) (xy 369.120055 -221.90318) (xy 369.130115 -221.855608) (xy 369.147034 -221.810023)
			(xy 369.170449 -221.767408) (xy 369.199853 -221.728682) (xy 369.234613 -221.694681) (xy 369.273978 -221.666138)
			(xy 369.317099 -221.64367) (xy 369.363047 -221.62776) (xy 369.386866 -221.622874) (xy 369.40998 -221.618556)
			(xy 369.613942 -221.264988) (xy 369.606322 -221.24289) (xy 369.597758 -221.216789) (xy 369.58844 -221.162656)
			(xy 369.58778 -221.135194) (xy 369.58778 -221.132146) (xy 369.58842 -221.10627) (xy 369.596761 -221.055188)
			(xy 369.612965 -221.006032) (xy 369.636636 -220.960004) (xy 369.667193 -220.918229) (xy 369.70389 -220.88173)
			(xy 369.74583 -220.851399) (xy 369.791986 -220.827978) (xy 369.841229 -220.81204) (xy 369.892355 -220.803975)
			(xy 369.918234 -220.80347) (xy 369.944199 -220.803982) (xy 369.995488 -220.812111) (xy 370.044875 -220.828162)
			(xy 370.091142 -220.851742) (xy 370.133151 -220.88227) (xy 370.169868 -220.918993) (xy 370.200388 -220.961007)
			(xy 370.22396 -221.007279) (xy 370.240003 -221.056668) (xy 370.248123 -221.107959) (xy 370.248688 -221.133924)
			(xy 370.248215 -221.159396) (xy 370.240392 -221.209734) (xy 370.224935 -221.258276) (xy 370.20221 -221.303869)
			(xy 370.172755 -221.345434) (xy 370.13727 -221.381985) (xy 370.096595 -221.412657) (xy 370.051693 -221.436721)
			(xy 370.003631 -221.453607) (xy 369.978686 -221.45879) (xy 369.955572 -221.463108) (xy 369.752118 -221.815914)
			(xy 369.759738 -221.838012) (xy 369.766903 -221.859485) (xy 369.775946 -221.903841) (xy 369.777772 -221.926404)
			(xy 369.778026 -221.929198) (xy 369.779424 -221.944568) (xy 369.790249 -221.973455) (xy 369.809188 -221.997806)
			(xy 369.834522 -222.015408) (xy 369.863949 -222.024664) (xy 369.879372 -222.02521) (xy 369.879626 -222.02521)
			(xy 369.919829 -222.023636) (xy 370.000161 -222.028193) (xy 370.079517 -222.041477) (xy 370.156954 -222.063329)
			(xy 370.231548 -222.09349) (xy 370.26723 -222.112078) (xy 370.267738 -222.112332) (xy 370.272818 -222.115126)
			(xy 370.287042 -222.123508) (xy 370.308832 -222.135161) (xy 370.356359 -222.148636) (xy 370.381022 -222.150178)
			(xy 370.38788 -222.150178) (xy 370.405584 -222.149816) (xy 370.440454 -222.14367) (xy 370.473726 -222.131561)
			(xy 370.489226 -222.123) (xy 370.49075 -222.122238) (xy 370.500656 -222.11665) (xy 370.535687 -222.097839)
			(xy 370.608981 -222.067001) (xy 370.68517 -222.044237) (xy 370.763368 -222.029812) (xy 370.842664 -222.023894)
			(xy 370.882418 -222.024702) (xy 370.891816 -222.024956) (xy 370.905185 -222.025157) (xy 370.931281 -222.019376)
			(xy 370.954974 -222.007005) (xy 370.974632 -221.988895) (xy 370.988901 -221.966294) (xy 370.996797 -221.940759)
			(xy 370.997734 -221.92742) (xy 370.999655 -221.90318) (xy 371.009715 -221.855608) (xy 371.026634 -221.810023)
			(xy 371.050049 -221.767408) (xy 371.079453 -221.728682) (xy 371.114213 -221.694681) (xy 371.153578 -221.666138)
			(xy 371.196699 -221.64367) (xy 371.242647 -221.62776) (xy 371.266466 -221.622874) (xy 371.28958 -221.618556)
			(xy 371.493542 -221.264988) (xy 371.485922 -221.24289) (xy 371.477358 -221.216789) (xy 371.46804 -221.162656)
			(xy 371.46738 -221.135194) (xy 371.46738 -221.132146) (xy 371.46802 -221.10627) (xy 371.476361 -221.055188)
			(xy 371.492565 -221.006032) (xy 371.516236 -220.960004) (xy 371.546793 -220.918229) (xy 371.58349 -220.88173)
			(xy 371.62543 -220.851399) (xy 371.671586 -220.827978) (xy 371.720829 -220.81204) (xy 371.771955 -220.803975)
			(xy 371.797834 -220.80347) (xy 371.823799 -220.803982) (xy 371.875088 -220.812111) (xy 371.924475 -220.828162)
			(xy 371.970742 -220.851742) (xy 372.012751 -220.88227) (xy 372.049468 -220.918993) (xy 372.079988 -220.961007)
			(xy 372.10356 -221.007279) (xy 372.119603 -221.056668) (xy 372.127723 -221.107959) (xy 372.128288 -221.133924)
			(xy 372.127815 -221.159396) (xy 372.119992 -221.209734) (xy 372.104535 -221.258276) (xy 372.08181 -221.303869)
			(xy 372.052355 -221.345434) (xy 372.01687 -221.381985) (xy 371.976195 -221.412657) (xy 371.931293 -221.436721)
			(xy 371.883231 -221.453607) (xy 371.858286 -221.45879) (xy 371.835172 -221.463108) (xy 371.631718 -221.815914)
			(xy 371.639338 -221.838012) (xy 371.646503 -221.859485) (xy 371.655546 -221.903841) (xy 371.657372 -221.926404)
			(xy 371.657626 -221.929198) (xy 371.659024 -221.944568) (xy 371.669849 -221.973455) (xy 371.688788 -221.997806)
			(xy 371.714122 -222.015408) (xy 371.743549 -222.024664) (xy 371.758972 -222.02521) (xy 371.759226 -222.02521)
			(xy 371.799429 -222.023636) (xy 371.879761 -222.028193) (xy 371.959117 -222.041477) (xy 372.036554 -222.063329)
			(xy 372.111148 -222.09349) (xy 372.14683 -222.112078) (xy 372.147338 -222.112332) (xy 372.152418 -222.115126)
			(xy 372.166642 -222.123508) (xy 372.188432 -222.135161) (xy 372.235959 -222.148636) (xy 372.260622 -222.150178)
			(xy 372.26748 -222.150178) (xy 372.285184 -222.149816) (xy 372.320054 -222.14367) (xy 372.353326 -222.131561)
			(xy 372.368826 -222.123) (xy 372.37035 -222.122238) (xy 372.380256 -222.11665) (xy 372.415287 -222.097839)
			(xy 372.488581 -222.067001) (xy 372.56477 -222.044237) (xy 372.642968 -222.029812) (xy 372.722264 -222.023894)
			(xy 372.762018 -222.024702) (xy 372.771416 -222.024956) (xy 372.784785 -222.025157) (xy 372.810881 -222.019376)
			(xy 372.834574 -222.007005) (xy 372.854232 -221.988895) (xy 372.868501 -221.966294) (xy 372.876397 -221.940759)
			(xy 372.877334 -221.92742) (xy 372.879255 -221.90318) (xy 372.889315 -221.855608) (xy 372.906234 -221.810023)
			(xy 372.929649 -221.767408) (xy 372.959053 -221.728682) (xy 372.993813 -221.694681) (xy 373.033178 -221.666138)
			(xy 373.076299 -221.64367) (xy 373.122247 -221.62776) (xy 373.146066 -221.622874) (xy 373.16918 -221.618556)
			(xy 373.373142 -221.264988) (xy 373.365522 -221.24289) (xy 373.356958 -221.216789) (xy 373.34764 -221.162656)
			(xy 373.34698 -221.135194) (xy 373.34698 -221.132146) (xy 373.34762 -221.10627) (xy 373.355961 -221.055188)
			(xy 373.372165 -221.006032) (xy 373.395836 -220.960004) (xy 373.426393 -220.918229) (xy 373.46309 -220.88173)
			(xy 373.50503 -220.851399) (xy 373.551186 -220.827978) (xy 373.600429 -220.81204) (xy 373.651555 -220.803975)
			(xy 373.677434 -220.80347) (xy 373.703399 -220.803982) (xy 373.754688 -220.812111) (xy 373.804075 -220.828162)
			(xy 373.850342 -220.851742) (xy 373.892351 -220.88227) (xy 373.929068 -220.918993) (xy 373.959588 -220.961007)
			(xy 373.98316 -221.007279) (xy 373.999203 -221.056668) (xy 374.007323 -221.107959) (xy 374.007888 -221.133924)
			(xy 374.007415 -221.159396) (xy 373.999592 -221.209734) (xy 373.984135 -221.258276) (xy 373.96141 -221.303869)
			(xy 373.931955 -221.345434) (xy 373.89647 -221.381985) (xy 373.855795 -221.412657) (xy 373.810893 -221.436721)
			(xy 373.762831 -221.453607) (xy 373.737886 -221.45879) (xy 373.714772 -221.463108) (xy 373.511318 -221.815914)
			(xy 373.518938 -221.838012) (xy 373.526103 -221.859485) (xy 373.535146 -221.903841) (xy 373.536972 -221.926404)
			(xy 373.537226 -221.929198) (xy 373.538624 -221.944568) (xy 373.549449 -221.973455) (xy 373.568388 -221.997806)
			(xy 373.593722 -222.015408) (xy 373.623149 -222.024664) (xy 373.638572 -222.02521) (xy 373.638826 -222.02521)
			(xy 373.679029 -222.023636) (xy 373.759361 -222.028193) (xy 373.838717 -222.041477) (xy 373.916154 -222.063329)
			(xy 373.990748 -222.09349) (xy 374.02643 -222.112078) (xy 374.026938 -222.112332) (xy 374.032018 -222.115126)
			(xy 374.046242 -222.123508) (xy 374.068032 -222.135161) (xy 374.115559 -222.148636) (xy 374.140222 -222.150178)
			(xy 374.14708 -222.150178) (xy 374.164577 -222.149818) (xy 374.199056 -222.143845) (xy 374.23201 -222.132073)
			(xy 374.24741 -222.123762) (xy 374.252236 -222.120968) (xy 374.287808 -222.10132) (xy 374.362415 -222.069099)
			(xy 374.440114 -222.045281) (xy 374.519961 -222.030156) (xy 374.600988 -222.023908) (xy 374.641618 -222.024702)
			(xy 374.651016 -222.024956) (xy 374.666444 -222.025115) (xy 374.696265 -222.017253) (xy 374.722382 -222.000853)
			(xy 374.742418 -221.977407) (xy 374.754546 -221.949053) (xy 374.75668 -221.93377) (xy 374.757188 -221.924118)
			(xy 374.759188 -221.901608) (xy 374.768562 -221.857399) (xy 374.783872 -221.814879) (xy 374.80483 -221.774842)
			(xy 374.81764 -221.756224) (xy 374.81764 -221.554548) (xy 374.81713 -221.539271) (xy 374.808101 -221.510083)
			(xy 374.790839 -221.484875) (xy 374.76689 -221.465904) (xy 374.738399 -221.454871) (xy 374.707919 -221.452764)
			(xy 374.692926 -221.455742) (xy 374.674271 -221.459824) (xy 374.636329 -221.464155) (xy 374.617234 -221.464378)
			(xy 374.591262 -221.463898) (xy 374.539958 -221.455777) (xy 374.490555 -221.439731) (xy 374.444271 -221.416153)
			(xy 374.402245 -221.385625) (xy 374.365512 -221.348899) (xy 374.334977 -221.306879) (xy 374.311392 -221.260599)
			(xy 374.295336 -221.211199) (xy 374.287207 -221.159896) (xy 374.28678 -221.133924) (xy 374.287391 -221.105943)
			(xy 374.296839 -221.050784) (xy 374.305576 -221.024196) (xy 374.313196 -221.002098) (xy 374.109488 -220.649038)
			(xy 374.086374 -220.64472) (xy 374.061428 -220.639586) (xy 374.013389 -220.62267) (xy 373.968515 -220.598584)
			(xy 373.927868 -220.567898) (xy 373.892411 -220.531338) (xy 373.862983 -220.489771) (xy 373.840282 -220.44418)
			(xy 373.824845 -220.395647) (xy 373.817037 -220.345319) (xy 373.816626 -220.319854) (xy 373.817135 -220.293887)
			(xy 373.82526 -220.242592) (xy 373.841308 -220.193199) (xy 373.864886 -220.146925) (xy 373.895412 -220.104909)
			(xy 373.932135 -220.068186) (xy 373.974151 -220.03766) (xy 374.020425 -220.014082) (xy 374.069818 -219.998034)
			(xy 374.121113 -219.989909) (xy 374.173047 -219.989909) (xy 374.224342 -219.998034) (xy 374.273735 -220.014082)
			(xy 374.320009 -220.03766) (xy 374.362025 -220.068186) (xy 374.398748 -220.104909) (xy 374.429274 -220.146925)
			(xy 374.452852 -220.193199) (xy 374.4689 -220.242592) (xy 374.477025 -220.293887) (xy 374.477534 -220.319854)
			(xy 374.477534 -220.320616) (xy 374.476923 -220.348332) (xy 374.467599 -220.402975) (xy 374.458992 -220.429328)
			(xy 374.451372 -220.451426) (xy 374.655334 -220.80474) (xy 374.678448 -220.809058) (xy 374.692926 -220.812106)
			(xy 374.707912 -220.815072) (xy 374.738371 -220.812916) (xy 374.766837 -220.801866) (xy 374.790773 -220.782905)
			(xy 374.808046 -220.757724) (xy 374.817117 -220.728567) (xy 374.81764 -220.7133) (xy 374.81764 -220.511116)
			(xy 374.803264 -220.490039) (xy 374.780486 -220.44439) (xy 374.764994 -220.395782) (xy 374.757158 -220.345371)
			(xy 374.757164 -220.294354) (xy 374.765012 -220.243945) (xy 374.780514 -220.19534) (xy 374.803303 -220.149696)
			(xy 374.81764 -220.128592) (xy 374.81764 -219.926662) (xy 374.817132 -219.911384) (xy 374.808106 -219.882192)
			(xy 374.790844 -219.85698) (xy 374.766893 -219.838006) (xy 374.7384 -219.826971) (xy 374.707917 -219.824865)
			(xy 374.692926 -219.827856) (xy 374.674271 -219.831938) (xy 374.636329 -219.836269) (xy 374.617234 -219.836492)
			(xy 374.59126 -219.836012) (xy 374.539951 -219.82789) (xy 374.490544 -219.811841) (xy 374.444256 -219.788261)
			(xy 374.402228 -219.757729) (xy 374.365493 -219.720998) (xy 374.334957 -219.678973) (xy 374.311372 -219.632687)
			(xy 374.295318 -219.583282) (xy 374.287191 -219.531974) (xy 374.287191 -219.480026) (xy 374.295318 -219.428718)
			(xy 374.311372 -219.379313) (xy 374.334957 -219.333027) (xy 374.365493 -219.291002) (xy 374.402228 -219.254271)
			(xy 374.444256 -219.223739) (xy 374.490544 -219.200159) (xy 374.539951 -219.18411) (xy 374.59126 -219.175988)
			(xy 374.617234 -219.175584) (xy 374.636328 -219.175829) (xy 374.674268 -219.180159) (xy 374.692926 -219.18422)
			(xy 374.707912 -219.187186) (xy 374.738373 -219.18503) (xy 374.766841 -219.17398) (xy 374.790778 -219.15502)
			(xy 374.808054 -219.129839) (xy 374.817128 -219.100681) (xy 374.81764 -219.085414) (xy 374.81764 -218.883738)
			(xy 374.803207 -218.862646) (xy 374.780329 -218.816946) (xy 374.764765 -218.768267) (xy 374.756888 -218.717771)
			(xy 374.756886 -218.666665) (xy 374.764757 -218.616168) (xy 374.780315 -218.567487) (xy 374.803188 -218.521785)
			(xy 374.81764 -218.500706) (xy 374.81764 -218.29903) (xy 374.817141 -218.283745) (xy 374.808126 -218.254535)
			(xy 374.790867 -218.229304) (xy 374.76691 -218.210316) (xy 374.738405 -218.199272) (xy 374.707909 -218.197165)
			(xy 374.692926 -218.200224) (xy 374.674271 -218.204306) (xy 374.636329 -218.208638) (xy 374.617234 -218.20886)
			(xy 374.591263 -218.20838) (xy 374.539959 -218.200259) (xy 374.490558 -218.184212) (xy 374.444275 -218.160634)
			(xy 374.402251 -218.130106) (xy 374.36552 -218.09338) (xy 374.334987 -218.051359) (xy 374.311403 -218.005079)
			(xy 374.29535 -217.95568) (xy 374.287223 -217.904377) (xy 374.28678 -217.878406) (xy 374.287393 -217.850426)
			(xy 374.296843 -217.795268) (xy 374.305576 -217.768678) (xy 374.313196 -217.74658) (xy 374.109488 -217.39352)
			(xy 374.086374 -217.389202) (xy 374.061428 -217.384067) (xy 374.013391 -217.367152) (xy 373.968519 -217.343065)
			(xy 373.927873 -217.312378) (xy 373.892418 -217.275818) (xy 373.862992 -217.234251) (xy 373.840293 -217.188661)
			(xy 373.824858 -217.140127) (xy 373.817054 -217.0898) (xy 373.816626 -217.064336) (xy 373.817135 -217.038369)
			(xy 373.82526 -216.987074) (xy 373.841308 -216.937681) (xy 373.864886 -216.891407) (xy 373.895412 -216.849391)
			(xy 373.932135 -216.812668) (xy 373.974151 -216.782142) (xy 374.020425 -216.758564) (xy 374.069818 -216.742516)
			(xy 374.121113 -216.734391) (xy 374.173047 -216.734391) (xy 374.224342 -216.742516) (xy 374.273735 -216.758564)
			(xy 374.320009 -216.782142) (xy 374.362025 -216.812668) (xy 374.398748 -216.849391) (xy 374.429274 -216.891407)
			(xy 374.452852 -216.937681) (xy 374.4689 -216.987074) (xy 374.477025 -217.038369) (xy 374.477534 -217.064336)
			(xy 374.477534 -217.065098) (xy 374.476924 -217.092814) (xy 374.467603 -217.147459) (xy 374.458992 -217.17381)
			(xy 374.451372 -217.195908) (xy 374.655334 -217.549222) (xy 374.678448 -217.55354) (xy 374.692926 -217.556588)
			(xy 374.707911 -217.559555) (xy 374.738369 -217.557399) (xy 374.766833 -217.546348) (xy 374.790766 -217.527387)
			(xy 374.808036 -217.502205) (xy 374.817102 -217.473048) (xy 374.81764 -217.457782) (xy 374.81764 -217.255598)
			(xy 374.803258 -217.234521) (xy 374.780467 -217.18887) (xy 374.764963 -217.140258) (xy 374.757116 -217.089841)
			(xy 374.757112 -217.038817) (xy 374.76495 -216.988399) (xy 374.780445 -216.939785) (xy 374.803228 -216.894129)
			(xy 374.81764 -216.873074) (xy 374.81764 -216.671144) (xy 374.817129 -216.655868) (xy 374.8081 -216.626681)
			(xy 374.790838 -216.601473) (xy 374.766889 -216.582503) (xy 374.738399 -216.571471) (xy 374.70792 -216.569364)
			(xy 374.692926 -216.572338) (xy 374.674271 -216.57642) (xy 374.636329 -216.580751) (xy 374.617234 -216.580974)
			(xy 374.591261 -216.580494) (xy 374.539955 -216.572372) (xy 374.490551 -216.556325) (xy 374.444266 -216.532745)
			(xy 374.402239 -216.502215) (xy 374.365507 -216.465486) (xy 374.334973 -216.423463) (xy 374.311389 -216.37718)
			(xy 374.295336 -216.327778) (xy 374.287209 -216.276473) (xy 374.287209 -216.224527) (xy 374.295336 -216.173222)
			(xy 374.311389 -216.12382) (xy 374.334973 -216.077537) (xy 374.365507 -216.035514) (xy 374.402239 -215.998785)
			(xy 374.444266 -215.968255) (xy 374.490551 -215.944675) (xy 374.539955 -215.928628) (xy 374.591261 -215.920506)
			(xy 374.617234 -215.920066) (xy 374.636327 -215.920311) (xy 374.674267 -215.924642) (xy 374.692926 -215.928702)
			(xy 374.707911 -215.931669) (xy 374.738371 -215.929513) (xy 374.766836 -215.918462) (xy 374.790772 -215.899501)
			(xy 374.808044 -215.87432) (xy 374.817113 -215.845163) (xy 374.81764 -215.829896) (xy 374.81764 -215.204548)
			(xy 380.2634 -209.758788) (xy 380.2634 -204.892148) (xy 381.5207 -203.634848) (xy 381.516382 -203.60894)
			(xy 381.513899 -203.593246) (xy 381.511227 -203.561582) (xy 381.511048 -203.545694) (xy 381.511494 -203.519315)
			(xy 381.518757 -203.467059) (xy 381.533146 -203.4163) (xy 381.554386 -203.368006) (xy 381.582071 -203.323096)
			(xy 381.615676 -203.282424) (xy 381.65456 -203.246767) (xy 381.697983 -203.216801) (xy 381.72136 -203.204572)
			(xy 381.733718 -203.197871) (xy 381.754447 -203.178896) (xy 381.769207 -203.154983) (xy 381.776879 -203.127948)
			(xy 381.776878 -203.099846) (xy 381.769205 -203.072812) (xy 381.754443 -203.0489) (xy 381.733714 -203.029926)
			(xy 381.72136 -203.023216) (xy 381.697993 -203.01097) (xy 381.654573 -202.98101) (xy 381.615692 -202.945355)
			(xy 381.582091 -202.904685) (xy 381.554412 -202.859776) (xy 381.533181 -202.811482) (xy 381.518804 -202.760725)
			(xy 381.511553 -202.708471) (xy 381.511048 -202.682094) (xy 381.511534 -202.654842) (xy 381.519291 -202.600892)
			(xy 381.534646 -202.548596) (xy 381.557287 -202.499017) (xy 381.586753 -202.453164) (xy 381.622444 -202.411971)
			(xy 381.663633 -202.376276) (xy 381.709483 -202.346805) (xy 381.75906 -202.32416) (xy 381.811355 -202.308799)
			(xy 381.865304 -202.301037) (xy 381.892556 -202.300586) (xy 381.920804 -202.301101) (xy 381.976681 -202.309438)
			(xy 382.030719 -202.325923) (xy 382.081736 -202.350194) (xy 382.128616 -202.381722) (xy 382.170336 -202.419817)
			(xy 382.205984 -202.463647) (xy 382.23478 -202.512253) (xy 382.256096 -202.564574) (xy 382.269464 -202.619465)
			(xy 382.27254 -202.64755) (xy 382.274373 -202.661832) (xy 382.28494 -202.688604) (xy 382.302557 -202.711365)
			(xy 382.325825 -202.728306) (xy 382.352896 -202.738081) (xy 382.381619 -202.739915) (xy 382.409713 -202.733662)
			(xy 382.434947 -202.719818) (xy 382.445514 -202.710034) (xy 399.8976 -185.257948) (xy 399.8976 -184.622948)
			(xy 402.385784 -184.622948) (xy 402.424138 -184.58434) (xy 402.445474 -184.563004) (xy 402.46357 -184.545749)
			(xy 402.505117 -184.517943) (xy 402.551288 -184.49877) (xy 402.60031 -184.488966) (xy 402.625306 -184.488328)
			(xy 408.524964 -184.488328) (xy 408.539462 -184.487833) (xy 408.567294 -184.479708) (xy 408.591714 -184.464077)
			(xy 408.610746 -184.442204) (xy 408.622851 -184.415857) (xy 408.627049 -184.387169) (xy 408.623002 -184.358459)
			(xy 408.61742 -184.345072) (xy 408.606824 -184.320364) (xy 408.591894 -184.268718) (xy 408.584361 -184.215488)
			(xy 408.583892 -184.188608) (xy 408.584355 -184.161355) (xy 408.592111 -184.107403) (xy 408.607466 -184.055104)
			(xy 408.630108 -184.005523) (xy 408.659576 -183.959669) (xy 408.69527 -183.918475) (xy 408.736463 -183.882781)
			(xy 408.782316 -183.853312) (xy 408.831897 -183.830669) (xy 408.884195 -183.815313) (xy 408.938147 -183.807555)
			(xy 408.9654 -183.8071) (xy 408.993444 -183.807603) (xy 409.048924 -183.81583) (xy 409.102603 -183.832091)
			(xy 409.153322 -183.856036) (xy 409.199988 -183.88715) (xy 409.241596 -183.924761) (xy 409.277249 -183.968058)
			(xy 409.306178 -184.01611) (xy 409.317444 -184.041796) (xy 409.323912 -184.054087) (xy 409.342282 -184.074901)
			(xy 409.365577 -184.090002) (xy 409.392077 -184.098276) (xy 409.419826 -184.099112) (xy 409.446775 -184.092448)
			(xy 409.470937 -184.078777) (xy 409.48102 -184.069228) (xy 409.53182 -184.018428) (xy 409.53182 -182.739284)
			(xy 409.507863 -182.72728) (xy 409.463277 -182.697559) (xy 409.42329 -182.66189) (xy 409.388688 -182.620976)
			(xy 409.360152 -182.575622) (xy 409.338244 -182.526721) (xy 409.323395 -182.475235) (xy 409.315898 -182.422178)
			(xy 409.3159 -182.368594) (xy 409.323401 -182.315538) (xy 409.338253 -182.264053) (xy 409.360165 -182.215153)
			(xy 409.388704 -182.169802) (xy 409.423309 -182.12889) (xy 409.463299 -182.093224) (xy 409.507887 -182.063506)
			(xy 409.53182 -182.051452) (xy 409.53182 -176.711864) (xy 409.507864 -176.699857) (xy 409.46328 -176.67013)
			(xy 409.423294 -176.634457) (xy 409.388692 -176.593541) (xy 409.360155 -176.548186) (xy 409.338244 -176.499285)
			(xy 409.32339 -176.447799) (xy 409.315886 -176.394741) (xy 409.315412 -176.367948) (xy 409.315936 -176.339137)
			(xy 409.324599 -176.282171) (xy 409.341735 -176.227157) (xy 409.366954 -176.175348) (xy 409.399682 -176.127923)
			(xy 409.419044 -176.106582) (xy 409.428916 -176.095061) (xy 409.442032 -176.067721) (xy 409.446543 -176.037735)
			(xy 409.442053 -176.007747) (xy 409.428956 -175.980398) (xy 409.419044 -175.968914) (xy 409.399689 -175.947567)
			(xy 409.36697 -175.900138) (xy 409.341752 -175.84833) (xy 409.324606 -175.79332) (xy 409.315924 -175.736358)
			(xy 409.315412 -175.707548) (xy 409.315863 -175.680752) (xy 409.323357 -175.627686) (xy 409.338204 -175.576192)
			(xy 409.360112 -175.527282) (xy 409.38865 -175.48192) (xy 409.423255 -175.440998) (xy 409.463247 -175.405322)
			(xy 409.507839 -175.375595) (xy 409.53182 -175.363632) (xy 409.53182 -174.103284) (xy 409.507863 -174.09128)
			(xy 409.463277 -174.061559) (xy 409.42329 -174.02589) (xy 409.388688 -173.984976) (xy 409.360152 -173.939622)
			(xy 409.338244 -173.890721) (xy 409.323395 -173.839235) (xy 409.315898 -173.786178) (xy 409.3159 -173.732594)
			(xy 409.323401 -173.679538) (xy 409.338253 -173.628053) (xy 409.360165 -173.579153) (xy 409.388704 -173.533802)
			(xy 409.423309 -173.49289) (xy 409.463299 -173.457224) (xy 409.507887 -173.427506) (xy 409.53182 -173.415452)
			(xy 409.53182 -168.075864) (xy 409.507864 -168.063857) (xy 409.46328 -168.03413) (xy 409.423294 -167.998457)
			(xy 409.388692 -167.957541) (xy 409.360155 -167.912186) (xy 409.338244 -167.863285) (xy 409.32339 -167.811799)
			(xy 409.315886 -167.758741) (xy 409.315412 -167.731948) (xy 409.315848 -167.705679) (xy 409.323055 -167.653638)
			(xy 409.337338 -167.603079) (xy 409.358428 -167.55496) (xy 409.385924 -167.510192) (xy 409.40228 -167.489632)
			(xy 409.407917 -167.482096) (xy 409.413822 -167.464245) (xy 409.412913 -167.445465) (xy 409.405309 -167.428269)
			(xy 409.398978 -167.421306) (xy 408.71394 -166.736268) (xy 396.409926 -166.736268) (xy 396.395631 -166.761154)
			(xy 396.360724 -166.806707) (xy 396.319377 -166.846507) (xy 396.272526 -166.879652) (xy 396.247112 -166.892986)
			(xy 396.23475 -166.899689) (xy 396.214016 -166.918669) (xy 396.19925 -166.942588) (xy 396.191573 -166.969629)
			(xy 396.191569 -166.997739) (xy 396.199237 -167.024782) (xy 396.213996 -167.048706) (xy 396.234724 -167.067692)
			(xy 396.247112 -167.074342) (xy 396.270482 -167.086586) (xy 396.313909 -167.116544) (xy 396.352797 -167.152197)
			(xy 396.386404 -167.192865) (xy 396.41409 -167.237775) (xy 396.435328 -167.286069) (xy 396.449712 -167.336829)
			(xy 396.456969 -167.389085) (xy 396.457424 -167.415464) (xy 396.456938 -167.442715) (xy 396.449182 -167.496663)
			(xy 396.433827 -167.548958) (xy 396.411185 -167.598535) (xy 396.381719 -167.644385) (xy 396.346028 -167.685576)
			(xy 396.304837 -167.721267) (xy 396.258987 -167.750733) (xy 396.20941 -167.773375) (xy 396.157115 -167.78873)
			(xy 396.103167 -167.796486) (xy 396.048665 -167.796486) (xy 395.994717 -167.78873) (xy 395.942422 -167.773375)
			(xy 395.892845 -167.750733) (xy 395.846995 -167.721267) (xy 395.805804 -167.685576) (xy 395.770113 -167.644385)
			(xy 395.740647 -167.598535) (xy 395.718005 -167.548958) (xy 395.70265 -167.496663) (xy 395.694894 -167.442715)
			(xy 395.694408 -167.415464) (xy 395.694856 -167.389087) (xy 395.702124 -167.336835) (xy 395.716517 -167.286082)
			(xy 395.73776 -167.237793) (xy 395.76545 -167.192889) (xy 395.799058 -167.152225) (xy 395.837945 -167.116576)
			(xy 395.881369 -167.08662) (xy 395.90472 -167.074342) (xy 395.917078 -167.067644) (xy 395.937807 -167.048674)
			(xy 395.952567 -167.024765) (xy 395.960236 -166.997733) (xy 395.960231 -166.969635) (xy 395.952553 -166.942606)
			(xy 395.937786 -166.918701) (xy 395.917052 -166.899737) (xy 395.90472 -166.892986) (xy 395.879325 -166.879625)
			(xy 395.832502 -166.846453) (xy 395.791162 -166.806658) (xy 395.75623 -166.761133) (xy 395.741906 -166.736268)
			(xy 385.52628 -166.736268) (xy 384.6068 -167.655748) (xy 384.6068 -168.478708) (xy 397.049242 -168.478708)
			(xy 397.053313 -168.423086) (xy 397.065439 -168.368649) (xy 397.085362 -168.316558) (xy 397.112658 -168.267923)
			(xy 397.146744 -168.22378) (xy 397.186893 -168.185071) (xy 397.232251 -168.15262) (xy 397.281851 -168.127119)
			(xy 397.334635 -168.109112) (xy 397.389478 -168.098982) (xy 397.445212 -168.096945) (xy 397.500649 -168.103045)
			(xy 397.554606 -168.117151) (xy 397.605935 -168.138963) (xy 397.653541 -168.168017) (xy 397.696409 -168.203692)
			(xy 397.733626 -168.245229) (xy 397.764399 -168.291742) (xy 397.788071 -168.342239) (xy 397.804139 -168.395646)
			(xy 397.812259 -168.450822) (xy 397.812768 -168.478708) (xy 397.812259 -168.506594) (xy 397.804139 -168.56177)
			(xy 397.788071 -168.615177) (xy 397.764399 -168.665674) (xy 397.733626 -168.712187) (xy 397.696409 -168.753724)
			(xy 397.653541 -168.789399) (xy 397.605935 -168.818453) (xy 397.554606 -168.840265) (xy 397.500649 -168.854371)
			(xy 397.445212 -168.860471) (xy 397.389478 -168.858434) (xy 397.334635 -168.848304) (xy 397.281851 -168.830297)
			(xy 397.232251 -168.804796) (xy 397.186893 -168.772345) (xy 397.146744 -168.733636) (xy 397.112658 -168.689493)
			(xy 397.085362 -168.640858) (xy 397.065439 -168.588767) (xy 397.053313 -168.53433) (xy 397.049242 -168.478708)
			(xy 384.6068 -168.478708) (xy 384.6068 -168.983152) (xy 399.642589 -168.983152) (xy 399.646611 -168.897432)
			(xy 399.658642 -168.812464) (xy 399.678578 -168.728997) (xy 399.706241 -168.647763) (xy 399.74139 -168.569477)
			(xy 399.783716 -168.494826) (xy 399.832845 -168.424467) (xy 399.888348 -168.359017) (xy 399.949735 -168.299053)
			(xy 400.016468 -168.2451) (xy 400.08796 -168.197633) (xy 400.163582 -168.157069) (xy 400.242671 -168.123765)
			(xy 400.324531 -168.098013) (xy 400.408442 -168.08004) (xy 400.493668 -168.070004) (xy 400.57946 -168.067992)
			(xy 400.665062 -168.074023) (xy 400.749724 -168.088043) (xy 400.832701 -168.109929) (xy 400.913264 -168.13949)
			(xy 400.990704 -168.176464) (xy 401.064343 -168.220528) (xy 401.133531 -168.271294) (xy 401.197662 -168.328315)
			(xy 401.256171 -168.391091) (xy 401.308544 -168.459071) (xy 401.354322 -168.531656) (xy 401.393102 -168.608208)
			(xy 401.424543 -168.688056) (xy 401.448369 -168.770497) (xy 401.46437 -168.854807) (xy 401.472405 -168.940245)
			(xy 401.472908 -168.983152) (xy 401.472405 -169.026059) (xy 401.46437 -169.111497) (xy 401.448369 -169.195807)
			(xy 401.424543 -169.278248) (xy 401.393102 -169.358096) (xy 401.354322 -169.434648) (xy 401.308544 -169.507233)
			(xy 401.256171 -169.575213) (xy 401.197662 -169.637989) (xy 401.133531 -169.69501) (xy 401.064343 -169.745776)
			(xy 400.990704 -169.78984) (xy 400.913264 -169.826814) (xy 400.832701 -169.856375) (xy 400.749724 -169.878261)
			(xy 400.665062 -169.892281) (xy 400.57946 -169.898312) (xy 400.493668 -169.8963) (xy 400.408442 -169.886264)
			(xy 400.324531 -169.868291) (xy 400.242671 -169.842539) (xy 400.163582 -169.809235) (xy 400.08796 -169.768671)
			(xy 400.016468 -169.721204) (xy 399.949735 -169.667251) (xy 399.888348 -169.607287) (xy 399.832845 -169.541837)
			(xy 399.783716 -169.471478) (xy 399.74139 -169.396827) (xy 399.706241 -169.318541) (xy 399.678578 -169.237307)
			(xy 399.658642 -169.15384) (xy 399.646611 -169.068872) (xy 399.642589 -168.983152) (xy 384.6068 -168.983152)
			(xy 384.6068 -171.025496) (xy 399.668996 -171.025496) (xy 399.668996 -170.9408) (xy 399.677047 -170.856486)
			(xy 399.693076 -170.77332) (xy 399.716937 -170.692053) (xy 399.748416 -170.613423) (xy 399.787227 -170.538142)
			(xy 399.833017 -170.46689) (xy 399.885373 -170.400314) (xy 399.943821 -170.339016) (xy 400.007831 -170.283551)
			(xy 400.076823 -170.234422) (xy 400.150173 -170.192073) (xy 400.227216 -170.156889) (xy 400.307255 -170.129187)
			(xy 400.389564 -170.109219) (xy 400.473399 -170.097166) (xy 400.558 -170.093136) (xy 400.642601 -170.097166)
			(xy 400.726436 -170.109219) (xy 400.808745 -170.129187) (xy 400.888784 -170.156889) (xy 400.965827 -170.192073)
			(xy 401.039177 -170.234422) (xy 401.108169 -170.283551) (xy 401.172179 -170.339016) (xy 401.230627 -170.400314)
			(xy 401.282983 -170.46689) (xy 401.328773 -170.538142) (xy 401.367584 -170.613423) (xy 401.399063 -170.692053)
			(xy 401.422924 -170.77332) (xy 401.438953 -170.856486) (xy 401.447004 -170.9408) (xy 401.447508 -170.983148)
			(xy 401.447004 -171.025496) (xy 401.438953 -171.10981) (xy 401.422924 -171.192976) (xy 401.399063 -171.274243)
			(xy 401.367584 -171.352873) (xy 401.328773 -171.428154) (xy 401.282983 -171.499406) (xy 401.230627 -171.565982)
			(xy 401.172179 -171.62728) (xy 401.108169 -171.682745) (xy 401.039177 -171.731874) (xy 400.965827 -171.774223)
			(xy 400.888784 -171.809407) (xy 400.808745 -171.837109) (xy 400.726436 -171.857077) (xy 400.642601 -171.86913)
			(xy 400.558 -171.873161) (xy 400.473399 -171.86913) (xy 400.389564 -171.857077) (xy 400.307255 -171.837109)
			(xy 400.227216 -171.809407) (xy 400.150173 -171.774223) (xy 400.076823 -171.731874) (xy 400.007831 -171.682745)
			(xy 399.943821 -171.62728) (xy 399.885373 -171.565982) (xy 399.833017 -171.499406) (xy 399.787227 -171.428154)
			(xy 399.748416 -171.352873) (xy 399.716937 -171.274243) (xy 399.693076 -171.192976) (xy 399.677047 -171.10981)
			(xy 399.668996 -171.025496) (xy 384.6068 -171.025496) (xy 384.6068 -171.96943) (xy 393.4239 -171.96943)
			(xy 393.427971 -171.913808) (xy 393.440097 -171.859371) (xy 393.46002 -171.80728) (xy 393.487316 -171.758645)
			(xy 393.521402 -171.714502) (xy 393.561551 -171.675793) (xy 393.606909 -171.643342) (xy 393.656509 -171.617841)
			(xy 393.709293 -171.599834) (xy 393.764136 -171.589704) (xy 393.81987 -171.587667) (xy 393.875307 -171.593767)
			(xy 393.929264 -171.607873) (xy 393.980593 -171.629685) (xy 394.028199 -171.658739) (xy 394.071067 -171.694414)
			(xy 394.108284 -171.735951) (xy 394.139057 -171.782464) (xy 394.162729 -171.832961) (xy 394.178797 -171.886368)
			(xy 394.186917 -171.941544) (xy 394.187426 -171.96943) (xy 394.186917 -171.997316) (xy 394.178797 -172.052492)
			(xy 394.162729 -172.105899) (xy 394.139057 -172.156396) (xy 394.108284 -172.202909) (xy 394.071067 -172.244446)
			(xy 394.028199 -172.280121) (xy 393.980593 -172.309175) (xy 393.929264 -172.330987) (xy 393.875307 -172.345093)
			(xy 393.81987 -172.351193) (xy 393.764136 -172.349156) (xy 393.709293 -172.339026) (xy 393.656509 -172.321019)
			(xy 393.606909 -172.295518) (xy 393.561551 -172.263067) (xy 393.521402 -172.224358) (xy 393.487316 -172.180215)
			(xy 393.46002 -172.13158) (xy 393.440097 -172.079489) (xy 393.427971 -172.025052) (xy 393.4239 -171.96943)
			(xy 384.6068 -171.96943) (xy 384.6068 -173.11751) (xy 393.44168 -173.11751) (xy 393.445751 -173.061888)
			(xy 393.457877 -173.007451) (xy 393.4778 -172.95536) (xy 393.505096 -172.906725) (xy 393.539182 -172.862582)
			(xy 393.579331 -172.823873) (xy 393.624689 -172.791422) (xy 393.674289 -172.765921) (xy 393.727073 -172.747914)
			(xy 393.781916 -172.737784) (xy 393.83765 -172.735747) (xy 393.893087 -172.741847) (xy 393.947044 -172.755953)
			(xy 393.998373 -172.777765) (xy 394.045979 -172.806819) (xy 394.088847 -172.842494) (xy 394.126064 -172.884031)
			(xy 394.156837 -172.930544) (xy 394.180509 -172.981041) (xy 394.196577 -173.034448) (xy 394.204697 -173.089624)
			(xy 394.205206 -173.11751) (xy 394.204697 -173.145396) (xy 394.196577 -173.200572) (xy 394.180509 -173.253979)
			(xy 394.156837 -173.304476) (xy 394.126064 -173.350989) (xy 394.088847 -173.392526) (xy 394.045979 -173.428201)
			(xy 393.998373 -173.457255) (xy 393.947044 -173.479067) (xy 393.893087 -173.493173) (xy 393.83765 -173.499273)
			(xy 393.781916 -173.497236) (xy 393.727073 -173.487106) (xy 393.674289 -173.469099) (xy 393.624689 -173.443598)
			(xy 393.579331 -173.411147) (xy 393.539182 -173.372438) (xy 393.505096 -173.328295) (xy 393.4778 -173.27966)
			(xy 393.457877 -173.227569) (xy 393.445751 -173.173132) (xy 393.44168 -173.11751) (xy 384.6068 -173.11751)
			(xy 384.6068 -175.206152) (xy 399.642589 -175.206152) (xy 399.646611 -175.120432) (xy 399.658642 -175.035464)
			(xy 399.678578 -174.951997) (xy 399.706241 -174.870763) (xy 399.74139 -174.792477) (xy 399.783716 -174.717826)
			(xy 399.832845 -174.647467) (xy 399.888348 -174.582017) (xy 399.949735 -174.522053) (xy 400.016468 -174.4681)
			(xy 400.08796 -174.420633) (xy 400.163582 -174.380069) (xy 400.242671 -174.346765) (xy 400.324531 -174.321013)
			(xy 400.408442 -174.30304) (xy 400.493668 -174.293004) (xy 400.57946 -174.290992) (xy 400.665062 -174.297023)
			(xy 400.749724 -174.311043) (xy 400.832701 -174.332929) (xy 400.913264 -174.36249) (xy 400.990704 -174.399464)
			(xy 401.064343 -174.443528) (xy 401.133531 -174.494294) (xy 401.197662 -174.551315) (xy 401.256171 -174.614091)
			(xy 401.308544 -174.682071) (xy 401.354322 -174.754656) (xy 401.393102 -174.831208) (xy 401.424543 -174.911056)
			(xy 401.448369 -174.993497) (xy 401.46437 -175.077807) (xy 401.472405 -175.163245) (xy 401.472908 -175.206152)
			(xy 401.472405 -175.249059) (xy 401.46437 -175.334497) (xy 401.448369 -175.418807) (xy 401.424543 -175.501248)
			(xy 401.393102 -175.581096) (xy 401.354322 -175.657648) (xy 401.308544 -175.730233) (xy 401.256171 -175.798213)
			(xy 401.197662 -175.860989) (xy 401.133531 -175.91801) (xy 401.064343 -175.968776) (xy 400.990704 -176.01284)
			(xy 400.913264 -176.049814) (xy 400.832701 -176.079375) (xy 400.749724 -176.101261) (xy 400.665062 -176.115281)
			(xy 400.57946 -176.121312) (xy 400.493668 -176.1193) (xy 400.408442 -176.109264) (xy 400.324531 -176.091291)
			(xy 400.242671 -176.065539) (xy 400.163582 -176.032235) (xy 400.08796 -175.991671) (xy 400.016468 -175.944204)
			(xy 399.949735 -175.890251) (xy 399.888348 -175.830287) (xy 399.832845 -175.764837) (xy 399.783716 -175.694478)
			(xy 399.74139 -175.619827) (xy 399.706241 -175.541541) (xy 399.678578 -175.460307) (xy 399.658642 -175.37684)
			(xy 399.646611 -175.291872) (xy 399.642589 -175.206152) (xy 384.6068 -175.206152) (xy 384.6068 -176.14519)
			(xy 393.33297 -176.14519) (xy 393.333456 -176.117939) (xy 393.341212 -176.063991) (xy 393.356567 -176.011696)
			(xy 393.379209 -175.962119) (xy 393.408675 -175.916269) (xy 393.444366 -175.875078) (xy 393.485557 -175.839387)
			(xy 393.531407 -175.809921) (xy 393.580984 -175.787279) (xy 393.633279 -175.771924) (xy 393.687227 -175.764168)
			(xy 393.741729 -175.764168) (xy 393.795677 -175.771924) (xy 393.847972 -175.787279) (xy 393.897549 -175.809921)
			(xy 393.943399 -175.839387) (xy 393.98459 -175.875078) (xy 394.020281 -175.916269) (xy 394.049747 -175.962119)
			(xy 394.072389 -176.011696) (xy 394.087744 -176.063991) (xy 394.0955 -176.117939) (xy 394.095986 -176.14519)
			(xy 394.095519 -176.1726) (xy 394.087673 -176.226857) (xy 394.072143 -176.279431) (xy 394.049246 -176.329241)
			(xy 394.019456 -176.375261) (xy 393.983385 -176.416543) (xy 393.96289 -176.43475) (xy 393.952758 -176.444076)
			(xy 393.937417 -176.46693) (xy 393.928736 -176.49305) (xy 393.927348 -176.520541) (xy 393.933352 -176.547403)
			(xy 393.946312 -176.571686) (xy 393.965287 -176.591625) (xy 393.97686 -176.599088) (xy 394.000774 -176.613961)
			(xy 394.044353 -176.649629) (xy 394.082217 -176.691313) (xy 394.113543 -176.738111) (xy 394.137651 -176.789003)
			(xy 394.154018 -176.842887) (xy 394.162288 -176.898591) (xy 394.162788 -176.926748) (xy 394.162302 -176.953999)
			(xy 394.154546 -177.007947) (xy 394.139191 -177.060242) (xy 394.116549 -177.109819) (xy 394.087083 -177.155669)
			(xy 394.051392 -177.19686) (xy 394.010201 -177.232551) (xy 393.98539 -177.248496) (xy 399.668996 -177.248496)
			(xy 399.668996 -177.1638) (xy 399.677047 -177.079486) (xy 399.693076 -176.99632) (xy 399.716937 -176.915053)
			(xy 399.748416 -176.836423) (xy 399.787227 -176.761142) (xy 399.833017 -176.68989) (xy 399.885373 -176.623314)
			(xy 399.943821 -176.562016) (xy 400.007831 -176.506551) (xy 400.076823 -176.457422) (xy 400.150173 -176.415073)
			(xy 400.227216 -176.379889) (xy 400.307255 -176.352187) (xy 400.389564 -176.332219) (xy 400.473399 -176.320166)
			(xy 400.558 -176.316136) (xy 400.642601 -176.320166) (xy 400.726436 -176.332219) (xy 400.808745 -176.352187)
			(xy 400.888784 -176.379889) (xy 400.965827 -176.415073) (xy 401.039177 -176.457422) (xy 401.108169 -176.506551)
			(xy 401.172179 -176.562016) (xy 401.230627 -176.623314) (xy 401.282983 -176.68989) (xy 401.328773 -176.761142)
			(xy 401.367584 -176.836423) (xy 401.399063 -176.915053) (xy 401.422924 -176.99632) (xy 401.438953 -177.079486)
			(xy 401.447004 -177.1638) (xy 401.447508 -177.206148) (xy 401.447004 -177.248496) (xy 401.438953 -177.33281)
			(xy 401.422924 -177.415976) (xy 401.399063 -177.497243) (xy 401.367584 -177.575873) (xy 401.328773 -177.651154)
			(xy 401.282983 -177.722406) (xy 401.230627 -177.788982) (xy 401.172179 -177.85028) (xy 401.108169 -177.905745)
			(xy 401.039177 -177.954874) (xy 400.965827 -177.997223) (xy 400.888784 -178.032407) (xy 400.808745 -178.060109)
			(xy 400.726436 -178.080077) (xy 400.642601 -178.09213) (xy 400.558 -178.096161) (xy 400.473399 -178.09213)
			(xy 400.389564 -178.080077) (xy 400.307255 -178.060109) (xy 400.227216 -178.032407) (xy 400.150173 -177.997223)
			(xy 400.076823 -177.954874) (xy 400.007831 -177.905745) (xy 399.943821 -177.85028) (xy 399.885373 -177.788982)
			(xy 399.833017 -177.722406) (xy 399.787227 -177.651154) (xy 399.748416 -177.575873) (xy 399.716937 -177.497243)
			(xy 399.693076 -177.415976) (xy 399.677047 -177.33281) (xy 399.668996 -177.248496) (xy 393.98539 -177.248496)
			(xy 393.964351 -177.262017) (xy 393.914774 -177.284659) (xy 393.862479 -177.300014) (xy 393.808531 -177.30777)
			(xy 393.754029 -177.30777) (xy 393.700081 -177.300014) (xy 393.647786 -177.284659) (xy 393.598209 -177.262017)
			(xy 393.552359 -177.232551) (xy 393.511168 -177.19686) (xy 393.475477 -177.155669) (xy 393.446011 -177.109819)
			(xy 393.423369 -177.060242) (xy 393.408014 -177.007947) (xy 393.400258 -176.953999) (xy 393.399772 -176.926748)
			(xy 393.400245 -176.899338) (xy 393.408087 -176.845081) (xy 393.423615 -176.792506) (xy 393.44651 -176.742695)
			(xy 393.4763 -176.696675) (xy 393.512372 -176.655394) (xy 393.532868 -176.637188) (xy 393.542967 -176.627826)
			(xy 393.558316 -176.604983) (xy 393.567004 -176.57887) (xy 393.568399 -176.551384) (xy 393.5624 -176.524525)
			(xy 393.549443 -176.500245) (xy 393.530469 -176.48031) (xy 393.518898 -176.47285) (xy 393.494992 -176.457966)
			(xy 393.451415 -176.422298) (xy 393.413552 -176.380615) (xy 393.382226 -176.33382) (xy 393.358116 -176.282929)
			(xy 393.341747 -176.229048) (xy 393.333473 -176.173346) (xy 393.33297 -176.14519) (xy 384.6068 -176.14519)
			(xy 384.6068 -179.373653) (xy 392.93263 -179.373653) (xy 392.93263 -179.319147) (xy 392.940386 -179.265195)
			(xy 392.955742 -179.212897) (xy 392.978383 -179.163316) (xy 393.00785 -179.117461) (xy 393.043542 -179.076266)
			(xy 393.084734 -179.04057) (xy 393.130586 -179.0111) (xy 393.180165 -178.988454) (xy 393.232462 -178.973094)
			(xy 393.286413 -178.965332) (xy 393.313666 -178.964844) (xy 393.340974 -178.9653) (xy 393.395033 -178.973077)
			(xy 393.421362 -178.980338) (xy 393.436348 -178.98414) (xy 393.467243 -178.983622) (xy 393.496574 -178.9739)
			(xy 393.521661 -178.955861) (xy 393.540216 -178.931153) (xy 393.550545 -178.902031) (xy 393.551664 -178.886612)
			(xy 393.553084 -178.860019) (xy 393.562379 -178.807582) (xy 393.578876 -178.756948) (xy 393.602256 -178.709101)
			(xy 393.632064 -178.66497) (xy 393.667719 -178.625415) (xy 393.708531 -178.591203) (xy 393.753703 -178.563)
			(xy 393.80236 -178.541354) (xy 393.853554 -178.526687) (xy 393.906291 -178.519282) (xy 393.932918 -178.51882)
			(xy 393.96017 -178.519251) (xy 394.01412 -178.52701) (xy 394.066417 -178.542368) (xy 394.115995 -178.565012)
			(xy 394.161847 -178.594481) (xy 394.203038 -178.630175) (xy 394.23873 -178.671368) (xy 394.268197 -178.717221)
			(xy 394.290838 -178.7668) (xy 394.306194 -178.819097) (xy 394.31395 -178.873048) (xy 394.31395 -178.927552)
			(xy 394.306194 -178.981503) (xy 394.290838 -179.0338) (xy 394.268197 -179.083379) (xy 394.23873 -179.129232)
			(xy 394.203038 -179.170425) (xy 394.161847 -179.206119) (xy 394.115995 -179.235588) (xy 394.066417 -179.258232)
			(xy 394.01412 -179.27359) (xy 393.96017 -179.281349) (xy 393.932918 -179.281836) (xy 393.90561 -179.281384)
			(xy 393.851551 -179.273605) (xy 393.825222 -179.266342) (xy 393.810237 -179.262541) (xy 393.779343 -179.263063)
			(xy 393.750015 -179.272787) (xy 393.724929 -179.290825) (xy 393.706373 -179.315531) (xy 393.696042 -179.34465)
			(xy 393.69492 -179.360068) (xy 393.693497 -179.386661) (xy 393.684205 -179.439099) (xy 393.667709 -179.489734)
			(xy 393.64433 -179.537582) (xy 393.614523 -179.581713) (xy 393.578868 -179.62127) (xy 393.538056 -179.655482)
			(xy 393.492883 -179.683684) (xy 393.444226 -179.705329) (xy 393.393031 -179.719996) (xy 393.340293 -179.727399)
			(xy 393.313666 -179.72786) (xy 393.286413 -179.727468) (xy 393.232462 -179.719706) (xy 393.180165 -179.704346)
			(xy 393.130586 -179.6817) (xy 393.084734 -179.65223) (xy 393.043542 -179.616534) (xy 393.00785 -179.575339)
			(xy 392.978383 -179.529484) (xy 392.955742 -179.479903) (xy 392.940386 -179.427605) (xy 392.93263 -179.373653)
			(xy 384.6068 -179.373653) (xy 384.6068 -179.872386) (xy 397.069054 -179.872386) (xy 397.073125 -179.816764)
			(xy 397.085251 -179.762327) (xy 397.105174 -179.710236) (xy 397.13247 -179.661601) (xy 397.166556 -179.617458)
			(xy 397.206705 -179.578749) (xy 397.252063 -179.546298) (xy 397.301663 -179.520797) (xy 397.354447 -179.50279)
			(xy 397.40929 -179.49266) (xy 397.465024 -179.490623) (xy 397.520461 -179.496723) (xy 397.574418 -179.510829)
			(xy 397.625747 -179.532641) (xy 397.673353 -179.561695) (xy 397.716221 -179.59737) (xy 397.753438 -179.638907)
			(xy 397.784211 -179.68542) (xy 397.807883 -179.735917) (xy 397.823951 -179.789324) (xy 397.832071 -179.8445)
			(xy 397.83258 -179.872386) (xy 397.832071 -179.900272) (xy 397.823951 -179.955448) (xy 397.807883 -180.008855)
			(xy 397.784211 -180.059352) (xy 397.753438 -180.105865) (xy 397.716221 -180.147402) (xy 397.673353 -180.183077)
			(xy 397.625747 -180.212131) (xy 397.574418 -180.233943) (xy 397.520461 -180.248049) (xy 397.465024 -180.254149)
			(xy 397.40929 -180.252112) (xy 397.354447 -180.241982) (xy 397.301663 -180.223975) (xy 397.252063 -180.198474)
			(xy 397.206705 -180.166023) (xy 397.166556 -180.127314) (xy 397.13247 -180.083171) (xy 397.105174 -180.034536)
			(xy 397.085251 -179.982445) (xy 397.073125 -179.928008) (xy 397.069054 -179.872386) (xy 384.6068 -179.872386)
			(xy 384.6068 -180.31079) (xy 393.417042 -180.31079) (xy 393.421113 -180.255168) (xy 393.433239 -180.200731)
			(xy 393.453162 -180.14864) (xy 393.480458 -180.100005) (xy 393.514544 -180.055862) (xy 393.554693 -180.017153)
			(xy 393.600051 -179.984702) (xy 393.649651 -179.959201) (xy 393.702435 -179.941194) (xy 393.757278 -179.931064)
			(xy 393.813012 -179.929027) (xy 393.868449 -179.935127) (xy 393.922406 -179.949233) (xy 393.973735 -179.971045)
			(xy 394.021341 -180.000099) (xy 394.064209 -180.035774) (xy 394.101426 -180.077311) (xy 394.132199 -180.123824)
			(xy 394.155871 -180.174321) (xy 394.171939 -180.227728) (xy 394.180059 -180.282904) (xy 394.180568 -180.31079)
			(xy 394.180059 -180.338676) (xy 394.171939 -180.393852) (xy 394.155871 -180.447259) (xy 394.132199 -180.497756)
			(xy 394.101426 -180.544269) (xy 394.064209 -180.585806) (xy 394.021341 -180.621481) (xy 393.973735 -180.650535)
			(xy 393.922406 -180.672347) (xy 393.868449 -180.686453) (xy 393.813012 -180.692553) (xy 393.757278 -180.690516)
			(xy 393.702435 -180.680386) (xy 393.649651 -180.662379) (xy 393.600051 -180.636878) (xy 393.554693 -180.604427)
			(xy 393.514544 -180.565718) (xy 393.480458 -180.521575) (xy 393.453162 -180.47294) (xy 393.433239 -180.420849)
			(xy 393.421113 -180.366412) (xy 393.417042 -180.31079) (xy 384.6068 -180.31079) (xy 384.6068 -181.429152)
			(xy 399.642589 -181.429152) (xy 399.646611 -181.343432) (xy 399.658642 -181.258464) (xy 399.678578 -181.174997)
			(xy 399.706241 -181.093763) (xy 399.74139 -181.015477) (xy 399.783716 -180.940826) (xy 399.832845 -180.870467)
			(xy 399.888348 -180.805017) (xy 399.949735 -180.745053) (xy 400.016468 -180.6911) (xy 400.08796 -180.643633)
			(xy 400.163582 -180.603069) (xy 400.242671 -180.569765) (xy 400.324531 -180.544013) (xy 400.408442 -180.52604)
			(xy 400.493668 -180.516004) (xy 400.57946 -180.513992) (xy 400.665062 -180.520023) (xy 400.749724 -180.534043)
			(xy 400.832701 -180.555929) (xy 400.913264 -180.58549) (xy 400.990704 -180.622464) (xy 401.064343 -180.666528)
			(xy 401.133531 -180.717294) (xy 401.197662 -180.774315) (xy 401.256171 -180.837091) (xy 401.308544 -180.905071)
			(xy 401.354322 -180.977656) (xy 401.393102 -181.054208) (xy 401.424543 -181.134056) (xy 401.448369 -181.216497)
			(xy 401.46437 -181.300807) (xy 401.472405 -181.386245) (xy 401.472908 -181.429152) (xy 401.472405 -181.472059)
			(xy 401.46437 -181.557497) (xy 401.448369 -181.641807) (xy 401.424543 -181.724248) (xy 401.393102 -181.804096)
			(xy 401.354322 -181.880648) (xy 401.308544 -181.953233) (xy 401.256171 -182.021213) (xy 401.197662 -182.083989)
			(xy 401.133531 -182.14101) (xy 401.064343 -182.191776) (xy 400.990704 -182.23584) (xy 400.913264 -182.272814)
			(xy 400.832701 -182.302375) (xy 400.749724 -182.324261) (xy 400.665062 -182.338281) (xy 400.57946 -182.344312)
			(xy 400.493668 -182.3423) (xy 400.408442 -182.332264) (xy 400.324531 -182.314291) (xy 400.242671 -182.288539)
			(xy 400.163582 -182.255235) (xy 400.08796 -182.214671) (xy 400.016468 -182.167204) (xy 399.949735 -182.113251)
			(xy 399.888348 -182.053287) (xy 399.832845 -181.987837) (xy 399.783716 -181.917478) (xy 399.74139 -181.842827)
			(xy 399.706241 -181.764541) (xy 399.678578 -181.683307) (xy 399.658642 -181.59984) (xy 399.646611 -181.514872)
			(xy 399.642589 -181.429152) (xy 384.6068 -181.429152) (xy 384.6068 -183.471496) (xy 399.668996 -183.471496)
			(xy 399.668996 -183.3868) (xy 399.677047 -183.302486) (xy 399.693076 -183.21932) (xy 399.716937 -183.138053)
			(xy 399.748416 -183.059423) (xy 399.787227 -182.984142) (xy 399.833017 -182.91289) (xy 399.885373 -182.846314)
			(xy 399.943821 -182.785016) (xy 400.007831 -182.729551) (xy 400.076823 -182.680422) (xy 400.150173 -182.638073)
			(xy 400.227216 -182.602889) (xy 400.307255 -182.575187) (xy 400.389564 -182.555219) (xy 400.473399 -182.543166)
			(xy 400.558 -182.539136) (xy 400.642601 -182.543166) (xy 400.726436 -182.555219) (xy 400.808745 -182.575187)
			(xy 400.888784 -182.602889) (xy 400.965827 -182.638073) (xy 401.039177 -182.680422) (xy 401.108169 -182.729551)
			(xy 401.172179 -182.785016) (xy 401.230627 -182.846314) (xy 401.282983 -182.91289) (xy 401.328773 -182.984142)
			(xy 401.367584 -183.059423) (xy 401.399063 -183.138053) (xy 401.422924 -183.21932) (xy 401.438953 -183.302486)
			(xy 401.447004 -183.3868) (xy 401.447508 -183.429148) (xy 401.447004 -183.471496) (xy 401.438953 -183.55581)
			(xy 401.422924 -183.638976) (xy 401.399063 -183.720243) (xy 401.367584 -183.798873) (xy 401.328773 -183.874154)
			(xy 401.282983 -183.945406) (xy 401.230627 -184.011982) (xy 401.172179 -184.07328) (xy 401.108169 -184.128745)
			(xy 401.039177 -184.177874) (xy 400.965827 -184.220223) (xy 400.888784 -184.255407) (xy 400.808745 -184.283109)
			(xy 400.726436 -184.303077) (xy 400.642601 -184.31513) (xy 400.558 -184.319161) (xy 400.473399 -184.31513)
			(xy 400.389564 -184.303077) (xy 400.307255 -184.283109) (xy 400.227216 -184.255407) (xy 400.150173 -184.220223)
			(xy 400.076823 -184.177874) (xy 400.007831 -184.128745) (xy 399.943821 -184.07328) (xy 399.885373 -184.011982)
			(xy 399.833017 -183.945406) (xy 399.787227 -183.874154) (xy 399.748416 -183.798873) (xy 399.716937 -183.720243)
			(xy 399.693076 -183.638976) (xy 399.677047 -183.55581) (xy 399.668996 -183.471496) (xy 384.6068 -183.471496)
			(xy 384.6068 -185.257948) (xy 398.580862 -185.257948) (xy 398.584933 -185.202326) (xy 398.597059 -185.147889)
			(xy 398.616982 -185.095798) (xy 398.644278 -185.047163) (xy 398.678364 -185.00302) (xy 398.718513 -184.964311)
			(xy 398.763871 -184.93186) (xy 398.813471 -184.906359) (xy 398.866255 -184.888352) (xy 398.921098 -184.878222)
			(xy 398.976832 -184.876185) (xy 399.032269 -184.882285) (xy 399.086226 -184.896391) (xy 399.137555 -184.918203)
			(xy 399.185161 -184.947257) (xy 399.228029 -184.982932) (xy 399.265246 -185.024469) (xy 399.296019 -185.070982)
			(xy 399.319691 -185.121479) (xy 399.335759 -185.174886) (xy 399.343879 -185.230062) (xy 399.344388 -185.257948)
			(xy 399.343879 -185.285834) (xy 399.335759 -185.34101) (xy 399.319691 -185.394417) (xy 399.296019 -185.444914)
			(xy 399.265246 -185.491427) (xy 399.228029 -185.532964) (xy 399.185161 -185.568639) (xy 399.137555 -185.597693)
			(xy 399.086226 -185.619505) (xy 399.032269 -185.633611) (xy 398.976832 -185.639711) (xy 398.921098 -185.637674)
			(xy 398.866255 -185.627544) (xy 398.813471 -185.609537) (xy 398.763871 -185.584036) (xy 398.718513 -185.551585)
			(xy 398.678364 -185.512876) (xy 398.644278 -185.468733) (xy 398.616982 -185.420098) (xy 398.597059 -185.368007)
			(xy 398.584933 -185.31357) (xy 398.580862 -185.257948) (xy 384.6068 -185.257948) (xy 384.6068 -186.871864)
			(xy 396.587726 -186.871864) (xy 396.588153 -186.845484) (xy 396.595411 -186.793225) (xy 396.609798 -186.742464)
			(xy 396.631039 -186.694168) (xy 396.658729 -186.649258) (xy 396.692341 -186.60859) (xy 396.731234 -186.572939)
			(xy 396.774666 -186.542984) (xy 396.798038 -186.530742) (xy 396.810431 -186.524096) (xy 396.831169 -186.505113)
			(xy 396.845935 -186.481188) (xy 396.853608 -186.454141) (xy 396.853603 -186.426027) (xy 396.845922 -186.398982)
			(xy 396.831148 -186.375062) (xy 396.810404 -186.356086) (xy 396.798038 -186.349386) (xy 396.77468 -186.337123)
			(xy 396.731259 -186.307161) (xy 396.692376 -186.271507) (xy 396.65877 -186.230841) (xy 396.631083 -186.185935)
			(xy 396.60984 -186.137646) (xy 396.595446 -186.086893) (xy 396.588175 -186.034641) (xy 396.587726 -186.008264)
			(xy 396.588212 -185.981013) (xy 396.595968 -185.927065) (xy 396.611323 -185.87477) (xy 396.633965 -185.825193)
			(xy 396.663431 -185.779343) (xy 396.699122 -185.738152) (xy 396.740313 -185.702461) (xy 396.786163 -185.672995)
			(xy 396.83574 -185.650353) (xy 396.888035 -185.634998) (xy 396.941983 -185.627242) (xy 396.996485 -185.627242)
			(xy 397.050433 -185.634998) (xy 397.102728 -185.650353) (xy 397.152305 -185.672995) (xy 397.198155 -185.702461)
			(xy 397.239346 -185.738152) (xy 397.275037 -185.779343) (xy 397.304503 -185.825193) (xy 397.327145 -185.87477)
			(xy 397.3425 -185.927065) (xy 397.350256 -185.981013) (xy 397.350742 -186.008264) (xy 397.3503 -186.034643)
			(xy 397.34304 -186.0869) (xy 397.328653 -186.137659) (xy 397.307413 -186.185953) (xy 397.279725 -186.230862)
			(xy 397.246116 -186.271531) (xy 397.207228 -186.307184) (xy 397.1638 -186.337142) (xy 397.14043 -186.349386)
			(xy 397.128103 -186.356141) (xy 397.107379 -186.375108) (xy 397.092619 -186.399012) (xy 397.084946 -186.426037)
			(xy 397.084941 -186.454131) (xy 397.092606 -186.481158) (xy 397.107358 -186.505067) (xy 397.128077 -186.52404)
			(xy 397.14043 -186.530742) (xy 397.163792 -186.542998) (xy 397.207215 -186.572959) (xy 397.246099 -186.608613)
			(xy 397.279705 -186.649281) (xy 397.307393 -186.694187) (xy 397.328635 -186.742478) (xy 397.343027 -186.793233)
			(xy 397.350294 -186.845486) (xy 397.350742 -186.871864) (xy 397.350256 -186.899115) (xy 397.3425 -186.953063)
			(xy 397.327145 -187.005358) (xy 397.304503 -187.054935) (xy 397.275037 -187.100785) (xy 397.239346 -187.141976)
			(xy 397.198155 -187.177667) (xy 397.152305 -187.207133) (xy 397.102728 -187.229775) (xy 397.050433 -187.24513)
			(xy 396.996485 -187.252886) (xy 396.941983 -187.252886) (xy 396.888035 -187.24513) (xy 396.83574 -187.229775)
			(xy 396.786163 -187.207133) (xy 396.740313 -187.177667) (xy 396.699122 -187.141976) (xy 396.663431 -187.100785)
			(xy 396.633965 -187.054935) (xy 396.611323 -187.005358) (xy 396.595968 -186.953063) (xy 396.588212 -186.899115)
			(xy 396.587726 -186.871864) (xy 384.6068 -186.871864) (xy 384.6068 -188.458348) (xy 382.8415 -190.223648)
			(xy 386.842252 -190.223648) (xy 386.846323 -190.168026) (xy 386.858449 -190.113589) (xy 386.878372 -190.061498)
			(xy 386.905668 -190.012863) (xy 386.939754 -189.96872) (xy 386.979903 -189.930011) (xy 387.025261 -189.89756)
			(xy 387.074861 -189.872059) (xy 387.127645 -189.854052) (xy 387.182488 -189.843922) (xy 387.238222 -189.841885)
			(xy 387.293659 -189.847985) (xy 387.347616 -189.862091) (xy 387.398945 -189.883903) (xy 387.446551 -189.912957)
			(xy 387.489419 -189.948632) (xy 387.526636 -189.990169) (xy 387.557409 -190.036682) (xy 387.581081 -190.087179)
			(xy 387.597149 -190.140586) (xy 387.605269 -190.195762) (xy 387.605778 -190.223648) (xy 387.605269 -190.251534)
			(xy 387.597149 -190.30671) (xy 387.581081 -190.360117) (xy 387.557409 -190.410614) (xy 387.526636 -190.457127)
			(xy 387.489419 -190.498664) (xy 387.446551 -190.534339) (xy 387.398945 -190.563393) (xy 387.347616 -190.585205)
			(xy 387.293659 -190.599311) (xy 387.238222 -190.605411) (xy 387.182488 -190.603374) (xy 387.127645 -190.593244)
			(xy 387.074861 -190.575237) (xy 387.025261 -190.549736) (xy 386.979903 -190.517285) (xy 386.939754 -190.478576)
			(xy 386.905668 -190.434433) (xy 386.878372 -190.385798) (xy 386.858449 -190.333707) (xy 386.846323 -190.27927)
			(xy 386.842252 -190.223648) (xy 382.8415 -190.223648) (xy 381.7112 -191.353948) (xy 377.063 -191.353948)
			(xy 368.7318 -199.685148) (xy 367.7666 -212.562948) (xy 367.61293 -213.40191) (xy 367.657634 -213.414356)
			(xy 367.683334 -213.422081) (xy 367.732002 -213.444684) (xy 367.776378 -213.474854) (xy 367.815296 -213.511798)
			(xy 367.847733 -213.554545) (xy 367.872837 -213.601972) (xy 367.889947 -213.652832) (xy 367.898615 -213.705788)
			(xy 367.899188 -213.732618) (xy 367.898729 -213.757287) (xy 367.898534 -213.758585) (xy 369.118389 -213.758585)
			(xy 369.118389 -213.706651) (xy 369.126514 -213.655356) (xy 369.142562 -213.605963) (xy 369.16614 -213.559689)
			(xy 369.196666 -213.517673) (xy 369.233389 -213.48095) (xy 369.275405 -213.450424) (xy 369.321679 -213.426846)
			(xy 369.371072 -213.410798) (xy 369.422367 -213.402673) (xy 369.474301 -213.402673) (xy 369.525596 -213.410798)
			(xy 369.574989 -213.426846) (xy 369.621263 -213.450424) (xy 369.663279 -213.48095) (xy 369.700002 -213.517673)
			(xy 369.730528 -213.559689) (xy 369.754106 -213.605963) (xy 369.770154 -213.655356) (xy 369.778279 -213.706651)
			(xy 369.778788 -213.732618) (xy 369.778279 -213.758585) (xy 370.997989 -213.758585) (xy 370.997989 -213.706651)
			(xy 371.006114 -213.655356) (xy 371.022162 -213.605963) (xy 371.04574 -213.559689) (xy 371.076266 -213.517673)
			(xy 371.112989 -213.48095) (xy 371.155005 -213.450424) (xy 371.201279 -213.426846) (xy 371.250672 -213.410798)
			(xy 371.301967 -213.402673) (xy 371.353901 -213.402673) (xy 371.405196 -213.410798) (xy 371.454589 -213.426846)
			(xy 371.500863 -213.450424) (xy 371.542879 -213.48095) (xy 371.579602 -213.517673) (xy 371.610128 -213.559689)
			(xy 371.633706 -213.605963) (xy 371.649754 -213.655356) (xy 371.657879 -213.706651) (xy 371.658388 -213.732618)
			(xy 371.657879 -213.758585) (xy 372.877589 -213.758585) (xy 372.877589 -213.706651) (xy 372.885714 -213.655356)
			(xy 372.901762 -213.605963) (xy 372.92534 -213.559689) (xy 372.955866 -213.517673) (xy 372.992589 -213.48095)
			(xy 373.034605 -213.450424) (xy 373.080879 -213.426846) (xy 373.130272 -213.410798) (xy 373.181567 -213.402673)
			(xy 373.233501 -213.402673) (xy 373.284796 -213.410798) (xy 373.334189 -213.426846) (xy 373.380463 -213.450424)
			(xy 373.422479 -213.48095) (xy 373.459202 -213.517673) (xy 373.489728 -213.559689) (xy 373.513306 -213.605963)
			(xy 373.529354 -213.655356) (xy 373.537479 -213.706651) (xy 373.537988 -213.732618) (xy 373.537479 -213.758585)
			(xy 374.757189 -213.758585) (xy 374.757189 -213.706651) (xy 374.765314 -213.655356) (xy 374.781362 -213.605963)
			(xy 374.80494 -213.559689) (xy 374.835466 -213.517673) (xy 374.872189 -213.48095) (xy 374.914205 -213.450424)
			(xy 374.960479 -213.426846) (xy 375.009872 -213.410798) (xy 375.061167 -213.402673) (xy 375.113101 -213.402673)
			(xy 375.164396 -213.410798) (xy 375.213789 -213.426846) (xy 375.260063 -213.450424) (xy 375.302079 -213.48095)
			(xy 375.338802 -213.517673) (xy 375.369328 -213.559689) (xy 375.392906 -213.605963) (xy 375.408954 -213.655356)
			(xy 375.417079 -213.706651) (xy 375.417588 -213.732618) (xy 375.417079 -213.758585) (xy 375.408954 -213.80988)
			(xy 375.392906 -213.859273) (xy 375.369328 -213.905547) (xy 375.338802 -213.947563) (xy 375.302079 -213.984286)
			(xy 375.260063 -214.014812) (xy 375.213789 -214.03839) (xy 375.164396 -214.054438) (xy 375.113101 -214.062563)
			(xy 375.061167 -214.062563) (xy 375.009872 -214.054438) (xy 374.960479 -214.03839) (xy 374.914205 -214.014812)
			(xy 374.872189 -213.984286) (xy 374.835466 -213.947563) (xy 374.80494 -213.905547) (xy 374.781362 -213.859273)
			(xy 374.765314 -213.80988) (xy 374.757189 -213.758585) (xy 373.537479 -213.758585) (xy 373.529354 -213.80988)
			(xy 373.513306 -213.859273) (xy 373.489728 -213.905547) (xy 373.459202 -213.947563) (xy 373.422479 -213.984286)
			(xy 373.380463 -214.014812) (xy 373.334189 -214.03839) (xy 373.284796 -214.054438) (xy 373.233501 -214.062563)
			(xy 373.181567 -214.062563) (xy 373.130272 -214.054438) (xy 373.080879 -214.03839) (xy 373.034605 -214.014812)
			(xy 372.992589 -213.984286) (xy 372.955866 -213.947563) (xy 372.92534 -213.905547) (xy 372.901762 -213.859273)
			(xy 372.885714 -213.80988) (xy 372.877589 -213.758585) (xy 371.657879 -213.758585) (xy 371.649754 -213.80988)
			(xy 371.633706 -213.859273) (xy 371.610128 -213.905547) (xy 371.579602 -213.947563) (xy 371.542879 -213.984286)
			(xy 371.500863 -214.014812) (xy 371.454589 -214.03839) (xy 371.405196 -214.054438) (xy 371.353901 -214.062563)
			(xy 371.301967 -214.062563) (xy 371.250672 -214.054438) (xy 371.201279 -214.03839) (xy 371.155005 -214.014812)
			(xy 371.112989 -213.984286) (xy 371.076266 -213.947563) (xy 371.04574 -213.905547) (xy 371.022162 -213.859273)
			(xy 371.006114 -213.80988) (xy 370.997989 -213.758585) (xy 369.778279 -213.758585) (xy 369.770154 -213.80988)
			(xy 369.754106 -213.859273) (xy 369.730528 -213.905547) (xy 369.700002 -213.947563) (xy 369.663279 -213.984286)
			(xy 369.621263 -214.014812) (xy 369.574989 -214.03839) (xy 369.525596 -214.054438) (xy 369.474301 -214.062563)
			(xy 369.422367 -214.062563) (xy 369.371072 -214.054438) (xy 369.321679 -214.03839) (xy 369.275405 -214.014812)
			(xy 369.233389 -213.984286) (xy 369.196666 -213.947563) (xy 369.16614 -213.905547) (xy 369.142562 -213.859273)
			(xy 369.126514 -213.80988) (xy 369.118389 -213.758585) (xy 367.898534 -213.758585) (xy 367.891392 -213.806076)
			(xy 367.876883 -213.853232) (xy 367.855525 -213.897707) (xy 367.827793 -213.938512) (xy 367.794302 -213.974742)
			(xy 367.755798 -214.00559) (xy 367.713135 -214.030371) (xy 367.667263 -214.048534) (xy 367.6192 -214.059676)
			(xy 367.594642 -214.062056) (xy 367.579968 -214.064244) (xy 367.55271 -214.075925) (xy 367.529949 -214.094935)
			(xy 367.513599 -214.119676) (xy 367.505033 -214.148067) (xy 367.504472 -214.162894) (xy 367.504472 -214.21471)
			(xy 367.504089 -214.252034) (xy 367.4984 -214.326466) (xy 367.487123 -214.400258) (xy 367.479072 -214.436706)
			(xy 367.470616 -214.471833) (xy 367.449256 -214.540862) (xy 367.4364 -214.574628) (xy 367.432844 -214.583518)
			(xy 367.432844 -214.750904) (xy 367.43239 -214.793811) (xy 367.424757 -214.879283) (xy 367.417604 -214.921592)
			(xy 367.407932 -214.971721) (xy 367.379298 -215.069723) (xy 367.360454 -215.117172) (xy 367.213134 -215.473788)
			(xy 367.21288 -215.483186) (xy 367.21288 -215.48344) (xy 367.210575 -215.541019) (xy 367.198357 -215.655614)
			(xy 367.177511 -215.768958) (xy 367.16335 -215.824816) (xy 367.163096 -215.826086) (xy 367.160136 -215.840016)
			(xy 367.161188 -215.868462) (xy 367.170053 -215.895512) (xy 367.186041 -215.919064) (xy 367.20791 -215.937286)
			(xy 367.220754 -215.943434) (xy 367.243487 -215.952957) (xy 367.286079 -215.977756) (xy 367.324516 -216.008605)
			(xy 367.357947 -216.044819) (xy 367.385629 -216.085596) (xy 367.40695 -216.130031) (xy 367.421436 -216.17714)
			(xy 367.428766 -216.225877) (xy 367.429288 -216.25052) (xy 367.428832 -216.275155) (xy 367.428632 -216.276487)
			(xy 367.708689 -216.276487) (xy 367.708689 -216.224553) (xy 367.716814 -216.173258) (xy 367.732862 -216.123865)
			(xy 367.75644 -216.077591) (xy 367.786966 -216.035575) (xy 367.823689 -215.998852) (xy 367.865705 -215.968326)
			(xy 367.911979 -215.944748) (xy 367.961372 -215.9287) (xy 368.012667 -215.920575) (xy 368.064601 -215.920575)
			(xy 368.115896 -215.9287) (xy 368.165289 -215.944748) (xy 368.211563 -215.968326) (xy 368.253579 -215.998852)
			(xy 368.290302 -216.035575) (xy 368.320828 -216.077591) (xy 368.344406 -216.123865) (xy 368.360454 -216.173258)
			(xy 368.368579 -216.224553) (xy 368.369088 -216.25052) (xy 368.368579 -216.276487) (xy 368.648489 -216.276487)
			(xy 368.648489 -216.224553) (xy 368.656614 -216.173258) (xy 368.672662 -216.123865) (xy 368.69624 -216.077591)
			(xy 368.726766 -216.035575) (xy 368.763489 -215.998852) (xy 368.805505 -215.968326) (xy 368.851779 -215.944748)
			(xy 368.901172 -215.9287) (xy 368.952467 -215.920575) (xy 369.004401 -215.920575) (xy 369.055696 -215.9287)
			(xy 369.105089 -215.944748) (xy 369.151363 -215.968326) (xy 369.193379 -215.998852) (xy 369.230102 -216.035575)
			(xy 369.260628 -216.077591) (xy 369.284206 -216.123865) (xy 369.300254 -216.173258) (xy 369.308379 -216.224553)
			(xy 369.308888 -216.25052) (xy 369.308379 -216.276487) (xy 369.588289 -216.276487) (xy 369.588289 -216.224553)
			(xy 369.596414 -216.173258) (xy 369.612462 -216.123865) (xy 369.63604 -216.077591) (xy 369.666566 -216.035575)
			(xy 369.703289 -215.998852) (xy 369.745305 -215.968326) (xy 369.791579 -215.944748) (xy 369.840972 -215.9287)
			(xy 369.892267 -215.920575) (xy 369.944201 -215.920575) (xy 369.995496 -215.9287) (xy 370.044889 -215.944748)
			(xy 370.091163 -215.968326) (xy 370.133179 -215.998852) (xy 370.169902 -216.035575) (xy 370.200428 -216.077591)
			(xy 370.224006 -216.123865) (xy 370.240054 -216.173258) (xy 370.248179 -216.224553) (xy 370.248688 -216.25052)
			(xy 370.248179 -216.276487) (xy 370.528089 -216.276487) (xy 370.528089 -216.224553) (xy 370.536214 -216.173258)
			(xy 370.552262 -216.123865) (xy 370.57584 -216.077591) (xy 370.606366 -216.035575) (xy 370.643089 -215.998852)
			(xy 370.685105 -215.968326) (xy 370.731379 -215.944748) (xy 370.780772 -215.9287) (xy 370.832067 -215.920575)
			(xy 370.884001 -215.920575) (xy 370.935296 -215.9287) (xy 370.984689 -215.944748) (xy 371.030963 -215.968326)
			(xy 371.072979 -215.998852) (xy 371.109702 -216.035575) (xy 371.140228 -216.077591) (xy 371.163806 -216.123865)
			(xy 371.179854 -216.173258) (xy 371.187979 -216.224553) (xy 371.188488 -216.25052) (xy 371.187979 -216.276487)
			(xy 371.467889 -216.276487) (xy 371.467889 -216.224553) (xy 371.476014 -216.173258) (xy 371.492062 -216.123865)
			(xy 371.51564 -216.077591) (xy 371.546166 -216.035575) (xy 371.582889 -215.998852) (xy 371.624905 -215.968326)
			(xy 371.671179 -215.944748) (xy 371.720572 -215.9287) (xy 371.771867 -215.920575) (xy 371.823801 -215.920575)
			(xy 371.875096 -215.9287) (xy 371.924489 -215.944748) (xy 371.970763 -215.968326) (xy 372.012779 -215.998852)
			(xy 372.049502 -216.035575) (xy 372.080028 -216.077591) (xy 372.103606 -216.123865) (xy 372.119654 -216.173258)
			(xy 372.127779 -216.224553) (xy 372.128288 -216.25052) (xy 372.127779 -216.276487) (xy 372.407689 -216.276487)
			(xy 372.407689 -216.224553) (xy 372.415814 -216.173258) (xy 372.431862 -216.123865) (xy 372.45544 -216.077591)
			(xy 372.485966 -216.035575) (xy 372.522689 -215.998852) (xy 372.564705 -215.968326) (xy 372.610979 -215.944748)
			(xy 372.660372 -215.9287) (xy 372.711667 -215.920575) (xy 372.763601 -215.920575) (xy 372.814896 -215.9287)
			(xy 372.864289 -215.944748) (xy 372.910563 -215.968326) (xy 372.952579 -215.998852) (xy 372.989302 -216.035575)
			(xy 373.019828 -216.077591) (xy 373.043406 -216.123865) (xy 373.059454 -216.173258) (xy 373.067579 -216.224553)
			(xy 373.068088 -216.25052) (xy 373.067579 -216.276487) (xy 373.347489 -216.276487) (xy 373.347489 -216.224553)
			(xy 373.355614 -216.173258) (xy 373.371662 -216.123865) (xy 373.39524 -216.077591) (xy 373.425766 -216.035575)
			(xy 373.462489 -215.998852) (xy 373.504505 -215.968326) (xy 373.550779 -215.944748) (xy 373.600172 -215.9287)
			(xy 373.651467 -215.920575) (xy 373.703401 -215.920575) (xy 373.754696 -215.9287) (xy 373.804089 -215.944748)
			(xy 373.850363 -215.968326) (xy 373.892379 -215.998852) (xy 373.929102 -216.035575) (xy 373.959628 -216.077591)
			(xy 373.983206 -216.123865) (xy 373.999254 -216.173258) (xy 374.007379 -216.224553) (xy 374.007888 -216.25052)
			(xy 374.007379 -216.276487) (xy 373.999254 -216.327782) (xy 373.983206 -216.377175) (xy 373.959628 -216.423449)
			(xy 373.929102 -216.465465) (xy 373.892379 -216.502188) (xy 373.850363 -216.532714) (xy 373.804089 -216.556292)
			(xy 373.754696 -216.57234) (xy 373.703401 -216.580465) (xy 373.651467 -216.580465) (xy 373.600172 -216.57234)
			(xy 373.550779 -216.556292) (xy 373.504505 -216.532714) (xy 373.462489 -216.502188) (xy 373.425766 -216.465465)
			(xy 373.39524 -216.423449) (xy 373.371662 -216.377175) (xy 373.355614 -216.327782) (xy 373.347489 -216.276487)
			(xy 373.067579 -216.276487) (xy 373.059454 -216.327782) (xy 373.043406 -216.377175) (xy 373.019828 -216.423449)
			(xy 372.989302 -216.465465) (xy 372.952579 -216.502188) (xy 372.910563 -216.532714) (xy 372.864289 -216.556292)
			(xy 372.814896 -216.57234) (xy 372.763601 -216.580465) (xy 372.711667 -216.580465) (xy 372.660372 -216.57234)
			(xy 372.610979 -216.556292) (xy 372.564705 -216.532714) (xy 372.522689 -216.502188) (xy 372.485966 -216.465465)
			(xy 372.45544 -216.423449) (xy 372.431862 -216.377175) (xy 372.415814 -216.327782) (xy 372.407689 -216.276487)
			(xy 372.127779 -216.276487) (xy 372.119654 -216.327782) (xy 372.103606 -216.377175) (xy 372.080028 -216.423449)
			(xy 372.049502 -216.465465) (xy 372.012779 -216.502188) (xy 371.970763 -216.532714) (xy 371.924489 -216.556292)
			(xy 371.875096 -216.57234) (xy 371.823801 -216.580465) (xy 371.771867 -216.580465) (xy 371.720572 -216.57234)
			(xy 371.671179 -216.556292) (xy 371.624905 -216.532714) (xy 371.582889 -216.502188) (xy 371.546166 -216.465465)
			(xy 371.51564 -216.423449) (xy 371.492062 -216.377175) (xy 371.476014 -216.327782) (xy 371.467889 -216.276487)
			(xy 371.187979 -216.276487) (xy 371.179854 -216.327782) (xy 371.163806 -216.377175) (xy 371.140228 -216.423449)
			(xy 371.109702 -216.465465) (xy 371.072979 -216.502188) (xy 371.030963 -216.532714) (xy 370.984689 -216.556292)
			(xy 370.935296 -216.57234) (xy 370.884001 -216.580465) (xy 370.832067 -216.580465) (xy 370.780772 -216.57234)
			(xy 370.731379 -216.556292) (xy 370.685105 -216.532714) (xy 370.643089 -216.502188) (xy 370.606366 -216.465465)
			(xy 370.57584 -216.423449) (xy 370.552262 -216.377175) (xy 370.536214 -216.327782) (xy 370.528089 -216.276487)
			(xy 370.248179 -216.276487) (xy 370.240054 -216.327782) (xy 370.224006 -216.377175) (xy 370.200428 -216.423449)
			(xy 370.169902 -216.465465) (xy 370.133179 -216.502188) (xy 370.091163 -216.532714) (xy 370.044889 -216.556292)
			(xy 369.995496 -216.57234) (xy 369.944201 -216.580465) (xy 369.892267 -216.580465) (xy 369.840972 -216.57234)
			(xy 369.791579 -216.556292) (xy 369.745305 -216.532714) (xy 369.703289 -216.502188) (xy 369.666566 -216.465465)
			(xy 369.63604 -216.423449) (xy 369.612462 -216.377175) (xy 369.596414 -216.327782) (xy 369.588289 -216.276487)
			(xy 369.308379 -216.276487) (xy 369.300254 -216.327782) (xy 369.284206 -216.377175) (xy 369.260628 -216.423449)
			(xy 369.230102 -216.465465) (xy 369.193379 -216.502188) (xy 369.151363 -216.532714) (xy 369.105089 -216.556292)
			(xy 369.055696 -216.57234) (xy 369.004401 -216.580465) (xy 368.952467 -216.580465) (xy 368.901172 -216.57234)
			(xy 368.851779 -216.556292) (xy 368.805505 -216.532714) (xy 368.763489 -216.502188) (xy 368.726766 -216.465465)
			(xy 368.69624 -216.423449) (xy 368.672662 -216.377175) (xy 368.656614 -216.327782) (xy 368.648489 -216.276487)
			(xy 368.368579 -216.276487) (xy 368.360454 -216.327782) (xy 368.344406 -216.377175) (xy 368.320828 -216.423449)
			(xy 368.290302 -216.465465) (xy 368.253579 -216.502188) (xy 368.211563 -216.532714) (xy 368.165289 -216.556292)
			(xy 368.115896 -216.57234) (xy 368.064601 -216.580465) (xy 368.012667 -216.580465) (xy 367.961372 -216.57234)
			(xy 367.911979 -216.556292) (xy 367.865705 -216.532714) (xy 367.823689 -216.502188) (xy 367.786966 -216.465465)
			(xy 367.75644 -216.423449) (xy 367.732862 -216.377175) (xy 367.716814 -216.327782) (xy 367.708689 -216.276487)
			(xy 367.428632 -216.276487) (xy 367.421517 -216.323879) (xy 367.407051 -216.370977) (xy 367.385755 -216.415407)
			(xy 367.358101 -216.456184) (xy 367.324702 -216.492406) (xy 367.286296 -216.523269) (xy 367.243735 -216.54809)
			(xy 367.221008 -216.557606) (xy 367.208329 -216.563613) (xy 367.18663 -216.581383) (xy 367.170579 -216.604383)
			(xy 367.161388 -216.63088) (xy 367.159747 -216.658878) (xy 367.162334 -216.672668) (xy 367.174272 -216.72042)
			(xy 367.180114 -216.746328) (xy 367.18875 -216.754202) (xy 367.232184 -216.79535) (xy 367.242662 -216.805023)
			(xy 367.26769 -216.818665) (xy 367.295512 -216.824862) (xy 367.323964 -216.823133) (xy 367.350831 -216.813612)
			(xy 367.36274 -216.805764) (xy 367.384859 -216.788896) (xy 367.433566 -216.762037) (xy 367.486081 -216.743706)
			(xy 367.540923 -216.734421) (xy 367.568734 -216.733882) (xy 367.594701 -216.734367) (xy 367.645993 -216.742497)
			(xy 367.695383 -216.75855) (xy 367.741653 -216.782132) (xy 367.783665 -216.812662) (xy 367.820383 -216.849388)
			(xy 367.850904 -216.891406) (xy 367.874477 -216.937682) (xy 367.89052 -216.987075) (xy 367.898638 -217.038369)
			(xy 367.899188 -217.064336) (xy 368.177826 -217.064336) (xy 368.178335 -217.038369) (xy 368.18646 -216.987074)
			(xy 368.202508 -216.937681) (xy 368.226086 -216.891407) (xy 368.256612 -216.849391) (xy 368.293335 -216.812668)
			(xy 368.335351 -216.782142) (xy 368.381625 -216.758564) (xy 368.431018 -216.742516) (xy 368.482313 -216.734391)
			(xy 368.534247 -216.734391) (xy 368.585542 -216.742516) (xy 368.634935 -216.758564) (xy 368.681209 -216.782142)
			(xy 368.723225 -216.812668) (xy 368.759948 -216.849391) (xy 368.790474 -216.891407) (xy 368.814052 -216.937681)
			(xy 368.8301 -216.987074) (xy 368.838225 -217.038369) (xy 368.838734 -217.064336) (xy 368.838234 -217.090303)
			(xy 369.118389 -217.090303) (xy 369.118389 -217.038369) (xy 369.126514 -216.987074) (xy 369.142562 -216.937681)
			(xy 369.16614 -216.891407) (xy 369.196666 -216.849391) (xy 369.233389 -216.812668) (xy 369.275405 -216.782142)
			(xy 369.321679 -216.758564) (xy 369.371072 -216.742516) (xy 369.422367 -216.734391) (xy 369.474301 -216.734391)
			(xy 369.525596 -216.742516) (xy 369.574989 -216.758564) (xy 369.621263 -216.782142) (xy 369.663279 -216.812668)
			(xy 369.700002 -216.849391) (xy 369.730528 -216.891407) (xy 369.754106 -216.937681) (xy 369.770154 -216.987074)
			(xy 369.778279 -217.038369) (xy 369.778788 -217.064336) (xy 370.057426 -217.064336) (xy 370.057935 -217.038369)
			(xy 370.06606 -216.987074) (xy 370.082108 -216.937681) (xy 370.105686 -216.891407) (xy 370.136212 -216.849391)
			(xy 370.172935 -216.812668) (xy 370.214951 -216.782142) (xy 370.261225 -216.758564) (xy 370.310618 -216.742516)
			(xy 370.361913 -216.734391) (xy 370.413847 -216.734391) (xy 370.465142 -216.742516) (xy 370.514535 -216.758564)
			(xy 370.560809 -216.782142) (xy 370.602825 -216.812668) (xy 370.639548 -216.849391) (xy 370.670074 -216.891407)
			(xy 370.693652 -216.937681) (xy 370.7097 -216.987074) (xy 370.717825 -217.038369) (xy 370.718334 -217.064336)
			(xy 370.717834 -217.090303) (xy 370.997989 -217.090303) (xy 370.997989 -217.038369) (xy 371.006114 -216.987074)
			(xy 371.022162 -216.937681) (xy 371.04574 -216.891407) (xy 371.076266 -216.849391) (xy 371.112989 -216.812668)
			(xy 371.155005 -216.782142) (xy 371.201279 -216.758564) (xy 371.250672 -216.742516) (xy 371.301967 -216.734391)
			(xy 371.353901 -216.734391) (xy 371.405196 -216.742516) (xy 371.454589 -216.758564) (xy 371.500863 -216.782142)
			(xy 371.542879 -216.812668) (xy 371.579602 -216.849391) (xy 371.610128 -216.891407) (xy 371.633706 -216.937681)
			(xy 371.649754 -216.987074) (xy 371.657879 -217.038369) (xy 371.658388 -217.064336) (xy 371.937026 -217.064336)
			(xy 371.937535 -217.038369) (xy 371.94566 -216.987074) (xy 371.961708 -216.937681) (xy 371.985286 -216.891407)
			(xy 372.015812 -216.849391) (xy 372.052535 -216.812668) (xy 372.094551 -216.782142) (xy 372.140825 -216.758564)
			(xy 372.190218 -216.742516) (xy 372.241513 -216.734391) (xy 372.293447 -216.734391) (xy 372.344742 -216.742516)
			(xy 372.394135 -216.758564) (xy 372.440409 -216.782142) (xy 372.482425 -216.812668) (xy 372.519148 -216.849391)
			(xy 372.549674 -216.891407) (xy 372.573252 -216.937681) (xy 372.5893 -216.987074) (xy 372.597425 -217.038369)
			(xy 372.597934 -217.064336) (xy 372.597434 -217.090303) (xy 372.877589 -217.090303) (xy 372.877589 -217.038369)
			(xy 372.885714 -216.987074) (xy 372.901762 -216.937681) (xy 372.92534 -216.891407) (xy 372.955866 -216.849391)
			(xy 372.992589 -216.812668) (xy 373.034605 -216.782142) (xy 373.080879 -216.758564) (xy 373.130272 -216.742516)
			(xy 373.181567 -216.734391) (xy 373.233501 -216.734391) (xy 373.284796 -216.742516) (xy 373.334189 -216.758564)
			(xy 373.380463 -216.782142) (xy 373.422479 -216.812668) (xy 373.459202 -216.849391) (xy 373.489728 -216.891407)
			(xy 373.513306 -216.937681) (xy 373.529354 -216.987074) (xy 373.537479 -217.038369) (xy 373.537988 -217.064336)
			(xy 373.537479 -217.090303) (xy 373.529354 -217.141598) (xy 373.513306 -217.190991) (xy 373.489728 -217.237265)
			(xy 373.459202 -217.279281) (xy 373.422479 -217.316004) (xy 373.380463 -217.34653) (xy 373.334189 -217.370108)
			(xy 373.284796 -217.386156) (xy 373.233501 -217.394281) (xy 373.181567 -217.394281) (xy 373.130272 -217.386156)
			(xy 373.080879 -217.370108) (xy 373.034605 -217.34653) (xy 372.992589 -217.316004) (xy 372.955866 -217.279281)
			(xy 372.92534 -217.237265) (xy 372.901762 -217.190991) (xy 372.885714 -217.141598) (xy 372.877589 -217.090303)
			(xy 372.597434 -217.090303) (xy 372.597397 -217.092246) (xy 372.588071 -217.147278) (xy 372.579392 -217.17381)
			(xy 372.571518 -217.195654) (xy 372.775734 -217.549222) (xy 372.798594 -217.55354) (xy 372.823503 -217.558766)
			(xy 372.871485 -217.575722) (xy 372.916302 -217.599831) (xy 372.956895 -217.630524) (xy 372.992305 -217.667074)
			(xy 373.021696 -217.70862) (xy 373.044372 -217.754178) (xy 373.0598 -217.802674) (xy 373.067613 -217.852961)
			(xy 373.068088 -217.878406) (xy 373.067579 -217.904373) (xy 373.059454 -217.955668) (xy 373.043406 -218.005061)
			(xy 373.019828 -218.051335) (xy 372.989302 -218.093351) (xy 372.952579 -218.130074) (xy 372.910563 -218.1606)
			(xy 372.864289 -218.184178) (xy 372.814896 -218.200226) (xy 372.763601 -218.208351) (xy 372.711667 -218.208351)
			(xy 372.660372 -218.200226) (xy 372.610979 -218.184178) (xy 372.564705 -218.1606) (xy 372.522689 -218.130074)
			(xy 372.485966 -218.093351) (xy 372.45544 -218.051335) (xy 372.431862 -218.005061) (xy 372.415814 -217.955668)
			(xy 372.407689 -217.904373) (xy 372.40718 -217.878406) (xy 372.407735 -217.85042) (xy 372.417184 -217.795252)
			(xy 372.425976 -217.768678) (xy 372.433596 -217.74658) (xy 372.229888 -217.39352) (xy 372.206774 -217.389202)
			(xy 372.181829 -217.384082) (xy 372.133805 -217.367147) (xy 372.088946 -217.343047) (xy 372.048313 -217.312353)
			(xy 372.012868 -217.275792) (xy 371.983449 -217.234227) (xy 371.960751 -217.188643) (xy 371.945313 -217.140117)
			(xy 371.937498 -217.089797) (xy 371.937026 -217.064336) (xy 371.658388 -217.064336) (xy 371.657879 -217.090303)
			(xy 371.649754 -217.141598) (xy 371.633706 -217.190991) (xy 371.610128 -217.237265) (xy 371.579602 -217.279281)
			(xy 371.542879 -217.316004) (xy 371.500863 -217.34653) (xy 371.454589 -217.370108) (xy 371.405196 -217.386156)
			(xy 371.353901 -217.394281) (xy 371.301967 -217.394281) (xy 371.250672 -217.386156) (xy 371.201279 -217.370108)
			(xy 371.155005 -217.34653) (xy 371.112989 -217.316004) (xy 371.076266 -217.279281) (xy 371.04574 -217.237265)
			(xy 371.022162 -217.190991) (xy 371.006114 -217.141598) (xy 370.997989 -217.090303) (xy 370.717834 -217.090303)
			(xy 370.717797 -217.092246) (xy 370.708471 -217.147278) (xy 370.699792 -217.17381) (xy 370.691918 -217.195654)
			(xy 370.896134 -217.549222) (xy 370.918994 -217.55354) (xy 370.943903 -217.558766) (xy 370.991885 -217.575722)
			(xy 371.036702 -217.599831) (xy 371.077295 -217.630524) (xy 371.112705 -217.667074) (xy 371.142096 -217.70862)
			(xy 371.164772 -217.754178) (xy 371.1802 -217.802674) (xy 371.188013 -217.852961) (xy 371.188488 -217.878406)
			(xy 371.187979 -217.904373) (xy 371.179854 -217.955668) (xy 371.163806 -218.005061) (xy 371.140228 -218.051335)
			(xy 371.109702 -218.093351) (xy 371.072979 -218.130074) (xy 371.030963 -218.1606) (xy 370.984689 -218.184178)
			(xy 370.935296 -218.200226) (xy 370.884001 -218.208351) (xy 370.832067 -218.208351) (xy 370.780772 -218.200226)
			(xy 370.731379 -218.184178) (xy 370.685105 -218.1606) (xy 370.643089 -218.130074) (xy 370.606366 -218.093351)
			(xy 370.57584 -218.051335) (xy 370.552262 -218.005061) (xy 370.536214 -217.955668) (xy 370.528089 -217.904373)
			(xy 370.52758 -217.878406) (xy 370.528135 -217.85042) (xy 370.537584 -217.795252) (xy 370.546376 -217.768678)
			(xy 370.553996 -217.74658) (xy 370.350288 -217.39352) (xy 370.327174 -217.389202) (xy 370.302229 -217.384082)
			(xy 370.254205 -217.367147) (xy 370.209346 -217.343047) (xy 370.168713 -217.312353) (xy 370.133268 -217.275792)
			(xy 370.103849 -217.234227) (xy 370.081151 -217.188643) (xy 370.065713 -217.140117) (xy 370.057898 -217.089797)
			(xy 370.057426 -217.064336) (xy 369.778788 -217.064336) (xy 369.778279 -217.090303) (xy 369.770154 -217.141598)
			(xy 369.754106 -217.190991) (xy 369.730528 -217.237265) (xy 369.700002 -217.279281) (xy 369.663279 -217.316004)
			(xy 369.621263 -217.34653) (xy 369.574989 -217.370108) (xy 369.525596 -217.386156) (xy 369.474301 -217.394281)
			(xy 369.422367 -217.394281) (xy 369.371072 -217.386156) (xy 369.321679 -217.370108) (xy 369.275405 -217.34653)
			(xy 369.233389 -217.316004) (xy 369.196666 -217.279281) (xy 369.16614 -217.237265) (xy 369.142562 -217.190991)
			(xy 369.126514 -217.141598) (xy 369.118389 -217.090303) (xy 368.838234 -217.090303) (xy 368.838197 -217.092246)
			(xy 368.828871 -217.147278) (xy 368.820192 -217.17381) (xy 368.812318 -217.195654) (xy 369.016534 -217.549222)
			(xy 369.039394 -217.55354) (xy 369.064303 -217.558766) (xy 369.112285 -217.575722) (xy 369.157102 -217.599831)
			(xy 369.197695 -217.630524) (xy 369.233105 -217.667074) (xy 369.262496 -217.70862) (xy 369.285172 -217.754178)
			(xy 369.3006 -217.802674) (xy 369.308413 -217.852961) (xy 369.308888 -217.878406) (xy 369.308379 -217.904373)
			(xy 369.300254 -217.955668) (xy 369.284206 -218.005061) (xy 369.260628 -218.051335) (xy 369.230102 -218.093351)
			(xy 369.193379 -218.130074) (xy 369.151363 -218.1606) (xy 369.105089 -218.184178) (xy 369.055696 -218.200226)
			(xy 369.004401 -218.208351) (xy 368.952467 -218.208351) (xy 368.901172 -218.200226) (xy 368.851779 -218.184178)
			(xy 368.805505 -218.1606) (xy 368.763489 -218.130074) (xy 368.726766 -218.093351) (xy 368.69624 -218.051335)
			(xy 368.672662 -218.005061) (xy 368.656614 -217.955668) (xy 368.648489 -217.904373) (xy 368.64798 -217.878406)
			(xy 368.648535 -217.85042) (xy 368.657984 -217.795252) (xy 368.666776 -217.768678) (xy 368.674396 -217.74658)
			(xy 368.470688 -217.39352) (xy 368.447574 -217.389202) (xy 368.422629 -217.384082) (xy 368.374605 -217.367147)
			(xy 368.329746 -217.343047) (xy 368.289113 -217.312353) (xy 368.253668 -217.275792) (xy 368.224249 -217.234227)
			(xy 368.201551 -217.188643) (xy 368.186113 -217.140117) (xy 368.178298 -217.089797) (xy 368.177826 -217.064336)
			(xy 367.899188 -217.064336) (xy 367.898744 -217.0888) (xy 367.891527 -217.137192) (xy 367.877257 -217.183991)
			(xy 367.856245 -217.228177) (xy 367.828949 -217.268783) (xy 367.795968 -217.304922) (xy 367.758019 -217.335806)
			(xy 367.715933 -217.360759) (xy 367.693448 -217.370406) (xy 367.68006 -217.376405) (xy 367.657184 -217.394752)
			(xy 367.640449 -217.418834) (xy 367.631229 -217.446672) (xy 367.630282 -217.475981) (xy 367.633504 -217.490294)
			(xy 367.638528 -217.509808) (xy 367.647672 -217.549056) (xy 367.651792 -217.56878) (xy 367.653316 -217.576146)
			(xy 367.656983 -217.590598) (xy 367.671438 -217.616659) (xy 367.6928 -217.63744) (xy 367.719249 -217.651172)
			(xy 367.748535 -217.656688) (xy 367.778168 -217.653518) (xy 367.805625 -217.641932) (xy 367.8174 -217.632788)
			(xy 367.835712 -217.616894) (xy 367.876114 -217.590084) (xy 367.919997 -217.569459) (xy 367.96642 -217.55546)
			(xy 368.01439 -217.548387) (xy 368.038634 -217.547952) (xy 368.064599 -217.548464) (xy 368.11589 -217.556592)
			(xy 368.165278 -217.572644) (xy 368.211546 -217.596224) (xy 368.253557 -217.626751) (xy 368.290275 -217.663473)
			(xy 368.320797 -217.705488) (xy 368.344371 -217.75176) (xy 368.360417 -217.801149) (xy 368.368539 -217.852441)
			(xy 368.369088 -217.878406) (xy 368.368617 -217.903878) (xy 368.360796 -217.954219) (xy 368.34534 -218.002763)
			(xy 368.322616 -218.048359) (xy 368.293162 -218.089926) (xy 368.257677 -218.126479) (xy 368.217001 -218.157153)
			(xy 368.172099 -218.181218) (xy 368.124035 -218.198106) (xy 368.099086 -218.203272) (xy 368.075972 -218.20759)
			(xy 367.872518 -218.560396) (xy 367.878868 -218.578938) (xy 367.888192 -218.606329) (xy 367.898292 -218.663295)
			(xy 367.898934 -218.692222) (xy 369.117626 -218.692222) (xy 369.118059 -218.66677) (xy 369.125847 -218.616464)
			(xy 369.14126 -218.567949) (xy 369.163931 -218.522372) (xy 369.193324 -218.480811) (xy 369.228744 -218.44425)
			(xy 369.269352 -218.413554) (xy 369.314188 -218.38945) (xy 369.36219 -218.372507) (xy 369.38712 -218.367356)
			(xy 369.40998 -218.363038) (xy 369.613942 -218.00947) (xy 369.606322 -217.987626) (xy 369.597684 -217.96115)
			(xy 369.588359 -217.906249) (xy 369.58778 -217.878406) (xy 369.588289 -217.852439) (xy 369.596414 -217.801144)
			(xy 369.612462 -217.751751) (xy 369.63604 -217.705477) (xy 369.666566 -217.663461) (xy 369.703289 -217.626738)
			(xy 369.745305 -217.596212) (xy 369.791579 -217.572634) (xy 369.840972 -217.556586) (xy 369.892267 -217.548461)
			(xy 369.944201 -217.548461) (xy 369.995496 -217.556586) (xy 370.044889 -217.572634) (xy 370.091163 -217.596212)
			(xy 370.133179 -217.626738) (xy 370.169902 -217.663461) (xy 370.200428 -217.705477) (xy 370.224006 -217.751751)
			(xy 370.240054 -217.801144) (xy 370.248179 -217.852439) (xy 370.248688 -217.878406) (xy 370.248184 -217.903878)
			(xy 370.240364 -217.954219) (xy 370.224912 -218.002763) (xy 370.202193 -218.04836) (xy 370.172745 -218.089931)
			(xy 370.137266 -218.12649) (xy 370.096597 -218.15717) (xy 370.051701 -218.181246) (xy 370.003642 -218.198147)
			(xy 369.978686 -218.203272) (xy 369.955572 -218.20759) (xy 369.752118 -218.560396) (xy 369.759738 -218.582494)
			(xy 369.768472 -218.609083) (xy 369.777922 -218.664242) (xy 369.778534 -218.692222) (xy 370.997226 -218.692222)
			(xy 370.997659 -218.66677) (xy 371.005447 -218.616464) (xy 371.02086 -218.567949) (xy 371.043531 -218.522372)
			(xy 371.072924 -218.480811) (xy 371.108344 -218.44425) (xy 371.148952 -218.413554) (xy 371.193788 -218.38945)
			(xy 371.24179 -218.372507) (xy 371.26672 -218.367356) (xy 371.28958 -218.363038) (xy 371.493542 -218.00947)
			(xy 371.485922 -217.987626) (xy 371.477284 -217.96115) (xy 371.467959 -217.906249) (xy 371.46738 -217.878406)
			(xy 371.467889 -217.852439) (xy 371.476014 -217.801144) (xy 371.492062 -217.751751) (xy 371.51564 -217.705477)
			(xy 371.546166 -217.663461) (xy 371.582889 -217.626738) (xy 371.624905 -217.596212) (xy 371.671179 -217.572634)
			(xy 371.720572 -217.556586) (xy 371.771867 -217.548461) (xy 371.823801 -217.548461) (xy 371.875096 -217.556586)
			(xy 371.924489 -217.572634) (xy 371.970763 -217.596212) (xy 372.012779 -217.626738) (xy 372.049502 -217.663461)
			(xy 372.080028 -217.705477) (xy 372.103606 -217.751751) (xy 372.119654 -217.801144) (xy 372.127779 -217.852439)
			(xy 372.128288 -217.878406) (xy 372.127784 -217.903878) (xy 372.119964 -217.954219) (xy 372.104512 -218.002763)
			(xy 372.081793 -218.04836) (xy 372.052345 -218.089931) (xy 372.016866 -218.12649) (xy 371.976197 -218.15717)
			(xy 371.931301 -218.181246) (xy 371.883242 -218.198147) (xy 371.858286 -218.203272) (xy 371.835172 -218.20759)
			(xy 371.631718 -218.560396) (xy 371.639338 -218.582494) (xy 371.648072 -218.609083) (xy 371.657522 -218.664242)
			(xy 371.658134 -218.692222) (xy 372.876826 -218.692222) (xy 372.877259 -218.66677) (xy 372.885047 -218.616464)
			(xy 372.90046 -218.567949) (xy 372.923131 -218.522372) (xy 372.952524 -218.480811) (xy 372.987944 -218.44425)
			(xy 373.028552 -218.413554) (xy 373.073388 -218.38945) (xy 373.12139 -218.372507) (xy 373.14632 -218.367356)
			(xy 373.16918 -218.363038) (xy 373.373142 -218.00947) (xy 373.365522 -217.987626) (xy 373.356884 -217.96115)
			(xy 373.347559 -217.906249) (xy 373.34698 -217.878406) (xy 373.347489 -217.852439) (xy 373.355614 -217.801144)
			(xy 373.371662 -217.751751) (xy 373.39524 -217.705477) (xy 373.425766 -217.663461) (xy 373.462489 -217.626738)
			(xy 373.504505 -217.596212) (xy 373.550779 -217.572634) (xy 373.600172 -217.556586) (xy 373.651467 -217.548461)
			(xy 373.703401 -217.548461) (xy 373.754696 -217.556586) (xy 373.804089 -217.572634) (xy 373.850363 -217.596212)
			(xy 373.892379 -217.626738) (xy 373.929102 -217.663461) (xy 373.959628 -217.705477) (xy 373.983206 -217.751751)
			(xy 373.999254 -217.801144) (xy 374.007379 -217.852439) (xy 374.007888 -217.878406) (xy 374.007384 -217.903878)
			(xy 373.999564 -217.954219) (xy 373.984112 -218.002763) (xy 373.961393 -218.04836) (xy 373.931945 -218.089931)
			(xy 373.896466 -218.12649) (xy 373.855797 -218.15717) (xy 373.810901 -218.181246) (xy 373.762842 -218.198147)
			(xy 373.737886 -218.203272) (xy 373.714772 -218.20759) (xy 373.511318 -218.560396) (xy 373.518938 -218.582494)
			(xy 373.527672 -218.609083) (xy 373.537122 -218.664242) (xy 373.537734 -218.692222) (xy 373.537225 -218.718189)
			(xy 373.5291 -218.769484) (xy 373.513052 -218.818877) (xy 373.489474 -218.865151) (xy 373.458948 -218.907167)
			(xy 373.422225 -218.94389) (xy 373.380209 -218.974416) (xy 373.333935 -218.997994) (xy 373.284542 -219.014042)
			(xy 373.233247 -219.022167) (xy 373.181313 -219.022167) (xy 373.130018 -219.014042) (xy 373.080625 -218.997994)
			(xy 373.034351 -218.974416) (xy 372.992335 -218.94389) (xy 372.955612 -218.907167) (xy 372.925086 -218.865151)
			(xy 372.901508 -218.818877) (xy 372.88546 -218.769484) (xy 372.877335 -218.718189) (xy 372.876826 -218.692222)
			(xy 371.658134 -218.692222) (xy 371.657625 -218.718189) (xy 371.6495 -218.769484) (xy 371.633452 -218.818877)
			(xy 371.609874 -218.865151) (xy 371.579348 -218.907167) (xy 371.542625 -218.94389) (xy 371.500609 -218.974416)
			(xy 371.454335 -218.997994) (xy 371.404942 -219.014042) (xy 371.353647 -219.022167) (xy 371.301713 -219.022167)
			(xy 371.250418 -219.014042) (xy 371.201025 -218.997994) (xy 371.154751 -218.974416) (xy 371.112735 -218.94389)
			(xy 371.076012 -218.907167) (xy 371.045486 -218.865151) (xy 371.021908 -218.818877) (xy 371.00586 -218.769484)
			(xy 370.997735 -218.718189) (xy 370.997226 -218.692222) (xy 369.778534 -218.692222) (xy 369.778025 -218.718189)
			(xy 369.7699 -218.769484) (xy 369.753852 -218.818877) (xy 369.730274 -218.865151) (xy 369.699748 -218.907167)
			(xy 369.663025 -218.94389) (xy 369.621009 -218.974416) (xy 369.574735 -218.997994) (xy 369.525342 -219.014042)
			(xy 369.474047 -219.022167) (xy 369.422113 -219.022167) (xy 369.370818 -219.014042) (xy 369.321425 -218.997994)
			(xy 369.275151 -218.974416) (xy 369.233135 -218.94389) (xy 369.196412 -218.907167) (xy 369.165886 -218.865151)
			(xy 369.142308 -218.818877) (xy 369.12626 -218.769484) (xy 369.118135 -218.718189) (xy 369.117626 -218.692222)
			(xy 367.898934 -218.692222) (xy 367.898491 -218.716687) (xy 367.891276 -218.765082) (xy 367.877009 -218.811885)
			(xy 367.855999 -218.856075) (xy 367.828706 -218.896685) (xy 367.795726 -218.93283) (xy 367.75778 -218.96372)
			(xy 367.715695 -218.98868) (xy 367.693194 -218.998292) (xy 367.679811 -219.004295) (xy 367.656944 -219.022647)
			(xy 367.640215 -219.046727) (xy 367.630997 -219.07456) (xy 367.630046 -219.103865) (xy 367.63325 -219.11818)
			(xy 367.634774 -219.123768) (xy 367.64976 -219.187776) (xy 367.679732 -219.215462) (xy 367.702084 -219.237052)
			(xy 367.712562 -219.246725) (xy 367.73759 -219.260366) (xy 367.765412 -219.266563) (xy 367.793864 -219.264834)
			(xy 367.820731 -219.255314) (xy 367.83264 -219.247466) (xy 367.854759 -219.230598) (xy 367.903466 -219.203738)
			(xy 367.955981 -219.185408) (xy 368.010823 -219.176123) (xy 368.038634 -219.175584) (xy 368.0646 -219.176069)
			(xy 368.115893 -219.184199) (xy 368.165283 -219.200252) (xy 368.211553 -219.223834) (xy 368.253564 -219.254364)
			(xy 368.290283 -219.29109) (xy 368.320803 -219.333109) (xy 368.344375 -219.379384) (xy 368.360418 -219.428777)
			(xy 368.368536 -219.480071) (xy 368.369088 -219.506038) (xy 368.368636 -219.530686) (xy 368.368438 -219.532005)
			(xy 368.648489 -219.532005) (xy 368.648489 -219.480071) (xy 368.656614 -219.428776) (xy 368.672662 -219.379383)
			(xy 368.69624 -219.333109) (xy 368.726766 -219.291093) (xy 368.763489 -219.25437) (xy 368.805505 -219.223844)
			(xy 368.851779 -219.200266) (xy 368.901172 -219.184218) (xy 368.952467 -219.176093) (xy 369.004401 -219.176093)
			(xy 369.055696 -219.184218) (xy 369.105089 -219.200266) (xy 369.151363 -219.223844) (xy 369.193379 -219.25437)
			(xy 369.230102 -219.291093) (xy 369.260628 -219.333109) (xy 369.284206 -219.379383) (xy 369.300254 -219.428776)
			(xy 369.308379 -219.480071) (xy 369.308888 -219.506038) (xy 369.308379 -219.532005) (xy 369.588289 -219.532005)
			(xy 369.588289 -219.480071) (xy 369.596414 -219.428776) (xy 369.612462 -219.379383) (xy 369.63604 -219.333109)
			(xy 369.666566 -219.291093) (xy 369.703289 -219.25437) (xy 369.745305 -219.223844) (xy 369.791579 -219.200266)
			(xy 369.840972 -219.184218) (xy 369.892267 -219.176093) (xy 369.944201 -219.176093) (xy 369.995496 -219.184218)
			(xy 370.044889 -219.200266) (xy 370.091163 -219.223844) (xy 370.133179 -219.25437) (xy 370.169902 -219.291093)
			(xy 370.200428 -219.333109) (xy 370.224006 -219.379383) (xy 370.240054 -219.428776) (xy 370.248179 -219.480071)
			(xy 370.248688 -219.506038) (xy 370.248179 -219.532005) (xy 370.528089 -219.532005) (xy 370.528089 -219.480071)
			(xy 370.536214 -219.428776) (xy 370.552262 -219.379383) (xy 370.57584 -219.333109) (xy 370.606366 -219.291093)
			(xy 370.643089 -219.25437) (xy 370.685105 -219.223844) (xy 370.731379 -219.200266) (xy 370.780772 -219.184218)
			(xy 370.832067 -219.176093) (xy 370.884001 -219.176093) (xy 370.935296 -219.184218) (xy 370.984689 -219.200266)
			(xy 371.030963 -219.223844) (xy 371.072979 -219.25437) (xy 371.109702 -219.291093) (xy 371.140228 -219.333109)
			(xy 371.163806 -219.379383) (xy 371.179854 -219.428776) (xy 371.187979 -219.480071) (xy 371.188488 -219.506038)
			(xy 371.187979 -219.532005) (xy 371.467889 -219.532005) (xy 371.467889 -219.480071) (xy 371.476014 -219.428776)
			(xy 371.492062 -219.379383) (xy 371.51564 -219.333109) (xy 371.546166 -219.291093) (xy 371.582889 -219.25437)
			(xy 371.624905 -219.223844) (xy 371.671179 -219.200266) (xy 371.720572 -219.184218) (xy 371.771867 -219.176093)
			(xy 371.823801 -219.176093) (xy 371.875096 -219.184218) (xy 371.924489 -219.200266) (xy 371.970763 -219.223844)
			(xy 372.012779 -219.25437) (xy 372.049502 -219.291093) (xy 372.080028 -219.333109) (xy 372.103606 -219.379383)
			(xy 372.119654 -219.428776) (xy 372.127779 -219.480071) (xy 372.128288 -219.506038) (xy 372.127779 -219.532005)
			(xy 372.407689 -219.532005) (xy 372.407689 -219.480071) (xy 372.415814 -219.428776) (xy 372.431862 -219.379383)
			(xy 372.45544 -219.333109) (xy 372.485966 -219.291093) (xy 372.522689 -219.25437) (xy 372.564705 -219.223844)
			(xy 372.610979 -219.200266) (xy 372.660372 -219.184218) (xy 372.711667 -219.176093) (xy 372.763601 -219.176093)
			(xy 372.814896 -219.184218) (xy 372.864289 -219.200266) (xy 372.910563 -219.223844) (xy 372.952579 -219.25437)
			(xy 372.989302 -219.291093) (xy 373.019828 -219.333109) (xy 373.043406 -219.379383) (xy 373.059454 -219.428776)
			(xy 373.067579 -219.480071) (xy 373.068088 -219.506038) (xy 373.067579 -219.532005) (xy 373.347489 -219.532005)
			(xy 373.347489 -219.480071) (xy 373.355614 -219.428776) (xy 373.371662 -219.379383) (xy 373.39524 -219.333109)
			(xy 373.425766 -219.291093) (xy 373.462489 -219.25437) (xy 373.504505 -219.223844) (xy 373.550779 -219.200266)
			(xy 373.600172 -219.184218) (xy 373.651467 -219.176093) (xy 373.703401 -219.176093) (xy 373.754696 -219.184218)
			(xy 373.804089 -219.200266) (xy 373.850363 -219.223844) (xy 373.892379 -219.25437) (xy 373.929102 -219.291093)
			(xy 373.959628 -219.333109) (xy 373.983206 -219.379383) (xy 373.999254 -219.428776) (xy 374.007379 -219.480071)
			(xy 374.007888 -219.506038) (xy 374.007379 -219.532005) (xy 373.999254 -219.5833) (xy 373.983206 -219.632693)
			(xy 373.959628 -219.678967) (xy 373.929102 -219.720983) (xy 373.892379 -219.757706) (xy 373.850363 -219.788232)
			(xy 373.804089 -219.81181) (xy 373.754696 -219.827858) (xy 373.703401 -219.835983) (xy 373.651467 -219.835983)
			(xy 373.600172 -219.827858) (xy 373.550779 -219.81181) (xy 373.504505 -219.788232) (xy 373.462489 -219.757706)
			(xy 373.425766 -219.720983) (xy 373.39524 -219.678967) (xy 373.371662 -219.632693) (xy 373.355614 -219.5833)
			(xy 373.347489 -219.532005) (xy 373.067579 -219.532005) (xy 373.059454 -219.5833) (xy 373.043406 -219.632693)
			(xy 373.019828 -219.678967) (xy 372.989302 -219.720983) (xy 372.952579 -219.757706) (xy 372.910563 -219.788232)
			(xy 372.864289 -219.81181) (xy 372.814896 -219.827858) (xy 372.763601 -219.835983) (xy 372.711667 -219.835983)
			(xy 372.660372 -219.827858) (xy 372.610979 -219.81181) (xy 372.564705 -219.788232) (xy 372.522689 -219.757706)
			(xy 372.485966 -219.720983) (xy 372.45544 -219.678967) (xy 372.431862 -219.632693) (xy 372.415814 -219.5833)
			(xy 372.407689 -219.532005) (xy 372.127779 -219.532005) (xy 372.119654 -219.5833) (xy 372.103606 -219.632693)
			(xy 372.080028 -219.678967) (xy 372.049502 -219.720983) (xy 372.012779 -219.757706) (xy 371.970763 -219.788232)
			(xy 371.924489 -219.81181) (xy 371.875096 -219.827858) (xy 371.823801 -219.835983) (xy 371.771867 -219.835983)
			(xy 371.720572 -219.827858) (xy 371.671179 -219.81181) (xy 371.624905 -219.788232) (xy 371.582889 -219.757706)
			(xy 371.546166 -219.720983) (xy 371.51564 -219.678967) (xy 371.492062 -219.632693) (xy 371.476014 -219.5833)
			(xy 371.467889 -219.532005) (xy 371.187979 -219.532005) (xy 371.179854 -219.5833) (xy 371.163806 -219.632693)
			(xy 371.140228 -219.678967) (xy 371.109702 -219.720983) (xy 371.072979 -219.757706) (xy 371.030963 -219.788232)
			(xy 370.984689 -219.81181) (xy 370.935296 -219.827858) (xy 370.884001 -219.835983) (xy 370.832067 -219.835983)
			(xy 370.780772 -219.827858) (xy 370.731379 -219.81181) (xy 370.685105 -219.788232) (xy 370.643089 -219.757706)
			(xy 370.606366 -219.720983) (xy 370.57584 -219.678967) (xy 370.552262 -219.632693) (xy 370.536214 -219.5833)
			(xy 370.528089 -219.532005) (xy 370.248179 -219.532005) (xy 370.240054 -219.5833) (xy 370.224006 -219.632693)
			(xy 370.200428 -219.678967) (xy 370.169902 -219.720983) (xy 370.133179 -219.757706) (xy 370.091163 -219.788232)
			(xy 370.044889 -219.81181) (xy 369.995496 -219.827858) (xy 369.944201 -219.835983) (xy 369.892267 -219.835983)
			(xy 369.840972 -219.827858) (xy 369.791579 -219.81181) (xy 369.745305 -219.788232) (xy 369.703289 -219.757706)
			(xy 369.666566 -219.720983) (xy 369.63604 -219.678967) (xy 369.612462 -219.632693) (xy 369.596414 -219.5833)
			(xy 369.588289 -219.532005) (xy 369.308379 -219.532005) (xy 369.300254 -219.5833) (xy 369.284206 -219.632693)
			(xy 369.260628 -219.678967) (xy 369.230102 -219.720983) (xy 369.193379 -219.757706) (xy 369.151363 -219.788232)
			(xy 369.105089 -219.81181) (xy 369.055696 -219.827858) (xy 369.004401 -219.835983) (xy 368.952467 -219.835983)
			(xy 368.901172 -219.827858) (xy 368.851779 -219.81181) (xy 368.805505 -219.788232) (xy 368.763489 -219.757706)
			(xy 368.726766 -219.720983) (xy 368.69624 -219.678967) (xy 368.672662 -219.632693) (xy 368.656614 -219.5833)
			(xy 368.648489 -219.532005) (xy 368.368438 -219.532005) (xy 368.361318 -219.579436) (xy 368.346836 -219.626557)
			(xy 368.325512 -219.671001) (xy 368.297819 -219.711783) (xy 368.264371 -219.747996) (xy 368.225913 -219.778836)
			(xy 368.183299 -219.803617) (xy 368.160554 -219.813124) (xy 368.14766 -219.819344) (xy 368.125704 -219.837698)
			(xy 368.109686 -219.861411) (xy 368.100856 -219.888631) (xy 368.099905 -219.917232) (xy 368.102896 -219.931234)
			(xy 368.108623 -219.95332) (xy 368.118911 -219.997778) (xy 368.12347 -220.020134) (xy 368.127447 -220.034339)
			(xy 368.142321 -220.0598) (xy 368.163839 -220.07996) (xy 368.190213 -220.093147) (xy 368.219252 -220.098263)
			(xy 368.248544 -220.094885) (xy 368.275657 -220.083293) (xy 368.2873 -220.074236) (xy 368.305582 -220.058341)
			(xy 368.345929 -220.031527) (xy 368.389759 -220.010895) (xy 368.436134 -219.996889) (xy 368.484058 -219.989808)
			(xy 368.50828 -219.9894) (xy 368.53425 -219.989908) (xy 368.58555 -219.998029) (xy 368.634948 -220.014076)
			(xy 368.681228 -220.037651) (xy 368.72325 -220.068177) (xy 368.75998 -220.104899) (xy 368.790514 -220.146916)
			(xy 368.814099 -220.193191) (xy 368.830155 -220.242586) (xy 368.838287 -220.293885) (xy 368.838734 -220.319854)
			(xy 368.838734 -220.320616) (xy 368.838178 -220.345821) (xy 369.118389 -220.345821) (xy 369.118389 -220.293887)
			(xy 369.126514 -220.242592) (xy 369.142562 -220.193199) (xy 369.16614 -220.146925) (xy 369.196666 -220.104909)
			(xy 369.233389 -220.068186) (xy 369.275405 -220.03766) (xy 369.321679 -220.014082) (xy 369.371072 -219.998034)
			(xy 369.422367 -219.989909) (xy 369.474301 -219.989909) (xy 369.525596 -219.998034) (xy 369.574989 -220.014082)
			(xy 369.621263 -220.03766) (xy 369.663279 -220.068186) (xy 369.700002 -220.104909) (xy 369.730528 -220.146925)
			(xy 369.754106 -220.193199) (xy 369.770154 -220.242592) (xy 369.778279 -220.293887) (xy 369.778788 -220.319854)
			(xy 370.057426 -220.319854) (xy 370.057935 -220.293887) (xy 370.06606 -220.242592) (xy 370.082108 -220.193199)
			(xy 370.105686 -220.146925) (xy 370.136212 -220.104909) (xy 370.172935 -220.068186) (xy 370.214951 -220.03766)
			(xy 370.261225 -220.014082) (xy 370.310618 -219.998034) (xy 370.361913 -219.989909) (xy 370.413847 -219.989909)
			(xy 370.465142 -219.998034) (xy 370.514535 -220.014082) (xy 370.560809 -220.03766) (xy 370.602825 -220.068186)
			(xy 370.639548 -220.104909) (xy 370.670074 -220.146925) (xy 370.693652 -220.193199) (xy 370.7097 -220.242592)
			(xy 370.717825 -220.293887) (xy 370.718334 -220.319854) (xy 370.717838 -220.345821) (xy 370.997989 -220.345821)
			(xy 370.997989 -220.293887) (xy 371.006114 -220.242592) (xy 371.022162 -220.193199) (xy 371.04574 -220.146925)
			(xy 371.076266 -220.104909) (xy 371.112989 -220.068186) (xy 371.155005 -220.03766) (xy 371.201279 -220.014082)
			(xy 371.250672 -219.998034) (xy 371.301967 -219.989909) (xy 371.353901 -219.989909) (xy 371.405196 -219.998034)
			(xy 371.454589 -220.014082) (xy 371.500863 -220.03766) (xy 371.542879 -220.068186) (xy 371.579602 -220.104909)
			(xy 371.610128 -220.146925) (xy 371.633706 -220.193199) (xy 371.649754 -220.242592) (xy 371.657879 -220.293887)
			(xy 371.658388 -220.319854) (xy 371.937026 -220.319854) (xy 371.937535 -220.293887) (xy 371.94566 -220.242592)
			(xy 371.961708 -220.193199) (xy 371.985286 -220.146925) (xy 372.015812 -220.104909) (xy 372.052535 -220.068186)
			(xy 372.094551 -220.03766) (xy 372.140825 -220.014082) (xy 372.190218 -219.998034) (xy 372.241513 -219.989909)
			(xy 372.293447 -219.989909) (xy 372.344742 -219.998034) (xy 372.394135 -220.014082) (xy 372.440409 -220.03766)
			(xy 372.482425 -220.068186) (xy 372.519148 -220.104909) (xy 372.549674 -220.146925) (xy 372.573252 -220.193199)
			(xy 372.5893 -220.242592) (xy 372.597425 -220.293887) (xy 372.597934 -220.319854) (xy 372.597438 -220.345821)
			(xy 372.877589 -220.345821) (xy 372.877589 -220.293887) (xy 372.885714 -220.242592) (xy 372.901762 -220.193199)
			(xy 372.92534 -220.146925) (xy 372.955866 -220.104909) (xy 372.992589 -220.068186) (xy 373.034605 -220.03766)
			(xy 373.080879 -220.014082) (xy 373.130272 -219.998034) (xy 373.181567 -219.989909) (xy 373.233501 -219.989909)
			(xy 373.284796 -219.998034) (xy 373.334189 -220.014082) (xy 373.380463 -220.03766) (xy 373.422479 -220.068186)
			(xy 373.459202 -220.104909) (xy 373.489728 -220.146925) (xy 373.513306 -220.193199) (xy 373.529354 -220.242592)
			(xy 373.537479 -220.293887) (xy 373.537988 -220.319854) (xy 373.537479 -220.345821) (xy 373.529354 -220.397116)
			(xy 373.513306 -220.446509) (xy 373.489728 -220.492783) (xy 373.459202 -220.534799) (xy 373.422479 -220.571522)
			(xy 373.380463 -220.602048) (xy 373.334189 -220.625626) (xy 373.284796 -220.641674) (xy 373.233501 -220.649799)
			(xy 373.181567 -220.649799) (xy 373.130272 -220.641674) (xy 373.080879 -220.625626) (xy 373.034605 -220.602048)
			(xy 372.992589 -220.571522) (xy 372.955866 -220.534799) (xy 372.92534 -220.492783) (xy 372.901762 -220.446509)
			(xy 372.885714 -220.397116) (xy 372.877589 -220.345821) (xy 372.597438 -220.345821) (xy 372.597401 -220.347764)
			(xy 372.588072 -220.402797) (xy 372.579392 -220.429328) (xy 372.571518 -220.451172) (xy 372.775734 -220.80474)
			(xy 372.798594 -220.809058) (xy 372.823507 -220.814267) (xy 372.87149 -220.831224) (xy 372.916308 -220.855335)
			(xy 372.956902 -220.886029) (xy 372.992312 -220.922582) (xy 373.021702 -220.96413) (xy 373.044378 -221.009691)
			(xy 373.059803 -221.058189) (xy 373.067614 -221.108478) (xy 373.068088 -221.133924) (xy 373.067579 -221.159891)
			(xy 373.059454 -221.211186) (xy 373.043406 -221.260579) (xy 373.019828 -221.306853) (xy 372.989302 -221.348869)
			(xy 372.952579 -221.385592) (xy 372.910563 -221.416118) (xy 372.864289 -221.439696) (xy 372.814896 -221.455744)
			(xy 372.763601 -221.463869) (xy 372.711667 -221.463869) (xy 372.660372 -221.455744) (xy 372.610979 -221.439696)
			(xy 372.564705 -221.416118) (xy 372.522689 -221.385592) (xy 372.485966 -221.348869) (xy 372.45544 -221.306853)
			(xy 372.431862 -221.260579) (xy 372.415814 -221.211186) (xy 372.407689 -221.159891) (xy 372.40718 -221.133924)
			(xy 372.40774 -221.105938) (xy 372.417185 -221.050771) (xy 372.425976 -221.024196) (xy 372.433596 -221.002098)
			(xy 372.229888 -220.649038) (xy 372.206774 -220.64472) (xy 372.181833 -220.639583) (xy 372.13381 -220.622649)
			(xy 372.088952 -220.598551) (xy 372.04832 -220.567859) (xy 372.012875 -220.5313) (xy 371.983455 -220.489738)
			(xy 371.960756 -220.444156) (xy 371.945316 -220.395632) (xy 371.9375 -220.345314) (xy 371.937026 -220.319854)
			(xy 371.658388 -220.319854) (xy 371.657879 -220.345821) (xy 371.649754 -220.397116) (xy 371.633706 -220.446509)
			(xy 371.610128 -220.492783) (xy 371.579602 -220.534799) (xy 371.542879 -220.571522) (xy 371.500863 -220.602048)
			(xy 371.454589 -220.625626) (xy 371.405196 -220.641674) (xy 371.353901 -220.649799) (xy 371.301967 -220.649799)
			(xy 371.250672 -220.641674) (xy 371.201279 -220.625626) (xy 371.155005 -220.602048) (xy 371.112989 -220.571522)
			(xy 371.076266 -220.534799) (xy 371.04574 -220.492783) (xy 371.022162 -220.446509) (xy 371.006114 -220.397116)
			(xy 370.997989 -220.345821) (xy 370.717838 -220.345821) (xy 370.717801 -220.347764) (xy 370.708472 -220.402797)
			(xy 370.699792 -220.429328) (xy 370.691918 -220.451172) (xy 370.896134 -220.80474) (xy 370.918994 -220.809058)
			(xy 370.943907 -220.814267) (xy 370.99189 -220.831224) (xy 371.036708 -220.855335) (xy 371.077302 -220.886029)
			(xy 371.112712 -220.922582) (xy 371.142102 -220.96413) (xy 371.164778 -221.009691) (xy 371.180203 -221.058189)
			(xy 371.188014 -221.108478) (xy 371.188488 -221.133924) (xy 371.187979 -221.159891) (xy 371.179854 -221.211186)
			(xy 371.163806 -221.260579) (xy 371.140228 -221.306853) (xy 371.109702 -221.348869) (xy 371.072979 -221.385592)
			(xy 371.030963 -221.416118) (xy 370.984689 -221.439696) (xy 370.935296 -221.455744) (xy 370.884001 -221.463869)
			(xy 370.832067 -221.463869) (xy 370.780772 -221.455744) (xy 370.731379 -221.439696) (xy 370.685105 -221.416118)
			(xy 370.643089 -221.385592) (xy 370.606366 -221.348869) (xy 370.57584 -221.306853) (xy 370.552262 -221.260579)
			(xy 370.536214 -221.211186) (xy 370.528089 -221.159891) (xy 370.52758 -221.133924) (xy 370.52814 -221.105938)
			(xy 370.537585 -221.050771) (xy 370.546376 -221.024196) (xy 370.553996 -221.002098) (xy 370.350288 -220.649038)
			(xy 370.327174 -220.64472) (xy 370.302233 -220.639583) (xy 370.25421 -220.622649) (xy 370.209352 -220.598551)
			(xy 370.16872 -220.567859) (xy 370.133275 -220.5313) (xy 370.103855 -220.489738) (xy 370.081156 -220.444156)
			(xy 370.065716 -220.395632) (xy 370.0579 -220.345314) (xy 370.057426 -220.319854) (xy 369.778788 -220.319854)
			(xy 369.778279 -220.345821) (xy 369.770154 -220.397116) (xy 369.754106 -220.446509) (xy 369.730528 -220.492783)
			(xy 369.700002 -220.534799) (xy 369.663279 -220.571522) (xy 369.621263 -220.602048) (xy 369.574989 -220.625626)
			(xy 369.525596 -220.641674) (xy 369.474301 -220.649799) (xy 369.422367 -220.649799) (xy 369.371072 -220.641674)
			(xy 369.321679 -220.625626) (xy 369.275405 -220.602048) (xy 369.233389 -220.571522) (xy 369.196666 -220.534799)
			(xy 369.16614 -220.492783) (xy 369.142562 -220.446509) (xy 369.126514 -220.397116) (xy 369.118389 -220.345821)
			(xy 368.838178 -220.345821) (xy 368.838123 -220.348332) (xy 368.828799 -220.402975) (xy 368.820192 -220.429328)
			(xy 368.812572 -220.451426) (xy 369.016534 -220.80474) (xy 369.039394 -220.809058) (xy 369.064323 -220.81421)
			(xy 369.112324 -220.831154) (xy 369.157157 -220.855259) (xy 369.197764 -220.885956) (xy 369.233182 -220.922517)
			(xy 369.262573 -220.964077) (xy 369.285243 -221.009654) (xy 369.300654 -221.058168) (xy 369.308442 -221.108472)
			(xy 369.308888 -221.133924) (xy 369.308379 -221.159891) (xy 369.300254 -221.211186) (xy 369.284206 -221.260579)
			(xy 369.260628 -221.306853) (xy 369.230102 -221.348869) (xy 369.193379 -221.385592) (xy 369.151363 -221.416118)
			(xy 369.105089 -221.439696) (xy 369.055696 -221.455744) (xy 369.004401 -221.463869) (xy 368.952467 -221.463869)
			(xy 368.901172 -221.455744) (xy 368.851779 -221.439696) (xy 368.805505 -221.416118) (xy 368.763489 -221.385592)
			(xy 368.726766 -221.348869) (xy 368.69624 -221.306853) (xy 368.672662 -221.260579) (xy 368.656614 -221.211186)
			(xy 368.648489 -221.159891) (xy 368.64798 -221.133924) (xy 368.648591 -221.105943) (xy 368.658039 -221.050784)
			(xy 368.666776 -221.024196) (xy 368.674396 -221.002098) (xy 368.470688 -220.649038) (xy 368.447574 -220.64472)
			(xy 368.425469 -220.640224) (xy 368.382664 -220.625988) (xy 368.3422 -220.606049) (xy 368.304832 -220.58078)
			(xy 368.287808 -220.56598) (xy 368.276069 -220.556818) (xy 368.24871 -220.545093) (xy 368.219132 -220.541757)
			(xy 368.189848 -220.547094) (xy 368.163349 -220.560649) (xy 368.141885 -220.581271) (xy 368.12728 -220.607208)
			(xy 368.12347 -220.621606) (xy 368.117882 -220.647768) (xy 368.103404 -220.707966) (xy 368.100129 -220.722261)
			(xy 368.101002 -220.751563) (xy 368.110163 -220.779409) (xy 368.126856 -220.803507) (xy 368.149706 -220.821871)
			(xy 368.163094 -220.827854) (xy 368.185586 -220.837492) (xy 368.227687 -220.862431) (xy 368.265648 -220.893308)
			(xy 368.298639 -220.929446) (xy 368.325938 -220.970056) (xy 368.346948 -221.014249) (xy 368.361209 -221.061057)
			(xy 368.368409 -221.109457) (xy 368.368834 -221.133924) (xy 368.368323 -221.159889) (xy 368.360195 -221.21118)
			(xy 368.344144 -221.260568) (xy 368.320565 -221.306838) (xy 368.290038 -221.348848) (xy 368.253315 -221.385567)
			(xy 368.2113 -221.416088) (xy 368.165028 -221.439661) (xy 368.115638 -221.455706) (xy 368.064345 -221.463826)
			(xy 368.03838 -221.464378) (xy 368.028832 -221.464286) (xy 368.00977 -221.463144) (xy 368.00028 -221.462092)
			(xy 367.983872 -221.505565) (xy 367.943797 -221.589407) (xy 367.92027 -221.629478) (xy 367.900689 -221.661137)
			(xy 367.857332 -221.721657) (xy 367.833656 -221.750382) (xy 367.847784 -221.77007) (xy 367.870741 -221.812745)
			(xy 367.887235 -221.85831) (xy 367.896912 -221.905792) (xy 367.89868 -221.92996) (xy 367.900243 -221.945548)
			(xy 367.911585 -221.974733) (xy 367.931218 -221.999124) (xy 367.957306 -222.016438) (xy 367.987408 -222.025057)
			(xy 368.003074 -222.02521) (xy 368.010186 -222.024956) (xy 368.050025 -222.023971) (xy 368.129527 -222.029535)
			(xy 368.207966 -222.043634) (xy 368.284428 -222.066105) (xy 368.358024 -222.096685) (xy 368.393218 -222.11538)
			(xy 368.395504 -222.11665) (xy 368.397536 -222.117666) (xy 368.407442 -222.123508) (xy 368.429232 -222.135161)
			(xy 368.476759 -222.148636) (xy 368.501422 -222.150178)
		)
		(stroke
			(width 0)
			(type solid)
		)
		(fill yes)
		(layer "In11.Cu")
		(net "PVCCINFAON_CPU0")
	)
	(gr_poly
		(pts
			(xy 334.19161 -49.00168) (xy 335.278984 -49.00168) (xy 336.508344 -47.772574) (xy 336.508344 -47.608998)
			(xy 336.462878 -47.604172) (xy 336.436929 -47.60103) (xy 336.38628 -47.588114) (xy 336.338067 -47.567926)
			(xy 336.293327 -47.5409) (xy 336.253023 -47.507618) (xy 336.218022 -47.468798) (xy 336.189079 -47.425273)
			(xy 336.166816 -47.377982) (xy 336.151713 -47.327942) (xy 336.144094 -47.276231) (xy 336.1436 -47.250096)
			(xy 336.144106 -47.223036) (xy 336.1523 -47.169539) (xy 336.1685 -47.1179) (xy 336.192332 -47.069309)
			(xy 336.223245 -47.024887) (xy 336.260528 -46.985657) (xy 336.303321 -46.952524) (xy 336.326734 -46.938946)
			(xy 336.33839 -46.932008) (xy 336.357822 -46.913096) (xy 336.371594 -46.889738) (xy 336.378734 -46.86358)
			(xy 336.37874 -46.836464) (xy 336.371611 -46.810303) (xy 336.35785 -46.786939) (xy 336.338426 -46.768019)
			(xy 336.326734 -46.761146) (xy 336.303322 -46.747568) (xy 336.26053 -46.714435) (xy 336.223248 -46.675205)
			(xy 336.192335 -46.630783) (xy 336.168505 -46.582192) (xy 336.152306 -46.530554) (xy 336.144112 -46.477058)
			(xy 336.144112 -46.422938) (xy 336.152307 -46.369442) (xy 336.168506 -46.317804) (xy 336.192337 -46.269214)
			(xy 336.22325 -46.224792) (xy 336.260533 -46.185562) (xy 336.303325 -46.15243) (xy 336.326734 -46.138846)
			(xy 336.33839 -46.131908) (xy 336.357822 -46.112996) (xy 336.371594 -46.089638) (xy 336.378734 -46.06348)
			(xy 336.37874 -46.036364) (xy 336.371611 -46.010203) (xy 336.35785 -45.986839) (xy 336.338426 -45.967919)
			(xy 336.326734 -45.961046) (xy 336.303316 -45.947472) (xy 336.260513 -45.914345) (xy 336.22322 -45.875118)
			(xy 336.192299 -45.830695) (xy 336.168461 -45.782102) (xy 336.152257 -45.730459) (xy 336.144061 -45.676959)
			(xy 336.1436 -45.649896) (xy 336.144067 -45.623765) (xy 336.151721 -45.572065) (xy 336.16685 -45.522039)
			(xy 336.189128 -45.474762) (xy 336.218077 -45.431249) (xy 336.253076 -45.392435) (xy 336.293371 -45.359153)
			(xy 336.338099 -45.332119) (xy 336.386298 -45.311912) (xy 336.436933 -45.298968) (xy 336.462878 -45.29582)
			(xy 336.508344 -45.290994) (xy 336.508344 -45.15866) (xy 336.471768 -45.147992) (xy 336.447437 -45.140439)
			(xy 336.401065 -45.119344) (xy 336.358173 -45.091855) (xy 336.319637 -45.058534) (xy 336.286243 -45.02006)
			(xy 336.258674 -44.977219) (xy 336.237493 -44.930886) (xy 336.223131 -44.882007) (xy 336.215883 -44.831581)
			(xy 336.215482 -44.806108) (xy 336.215981 -44.779099) (xy 336.224136 -44.725701) (xy 336.240259 -44.674146)
			(xy 336.263982 -44.625616) (xy 336.29476 -44.581225) (xy 336.331887 -44.541989) (xy 336.374513 -44.508809)
			(xy 336.397854 -44.495212) (xy 336.41073 -44.487409) (xy 336.431587 -44.465717) (xy 336.4452 -44.43888)
			(xy 336.450383 -44.409238) (xy 336.446683 -44.379374) (xy 336.441034 -44.365418) (xy 336.431388 -44.342603)
			(xy 336.417799 -44.294971) (xy 336.410963 -44.245913) (xy 336.410554 -44.221146) (xy 336.411054 -44.194097)
			(xy 336.419231 -44.14062) (xy 336.435404 -44.088996) (xy 336.459201 -44.040412) (xy 336.490074 -43.995988)
			(xy 336.508344 -43.976036) (xy 336.508344 -38.022276) (xy 338.175092 -36.355528) (xy 340.725252 -36.355528)
			(xy 340.738877 -36.355058) (xy 340.765139 -36.347785) (xy 340.788543 -36.333824) (xy 340.80742 -36.31417)
			(xy 340.820427 -36.290223) (xy 340.826636 -36.263688) (xy 340.825605 -36.236456) (xy 340.817408 -36.210467)
			(xy 340.810342 -36.19881) (xy 340.795837 -36.175519) (xy 340.772932 -36.12566) (xy 340.757406 -36.073034)
			(xy 340.749576 -36.018727) (xy 340.749128 -35.991292) (xy 340.749614 -35.964041) (xy 340.75737 -35.910093)
			(xy 340.772725 -35.857798) (xy 340.795367 -35.808221) (xy 340.824833 -35.762371) (xy 340.860524 -35.72118)
			(xy 340.901715 -35.685489) (xy 340.947565 -35.656023) (xy 340.997142 -35.633381) (xy 341.049437 -35.618026)
			(xy 341.103385 -35.61027) (xy 341.157887 -35.61027) (xy 341.211835 -35.618026) (xy 341.26413 -35.633381)
			(xy 341.313707 -35.656023) (xy 341.359557 -35.685489) (xy 341.400748 -35.72118) (xy 341.436439 -35.762371)
			(xy 341.465905 -35.808221) (xy 341.488547 -35.857798) (xy 341.503902 -35.910093) (xy 341.511658 -35.964041)
			(xy 341.512144 -35.991292) (xy 341.511683 -36.018725) (xy 341.503851 -36.073029) (xy 341.48832 -36.125651)
			(xy 341.465411 -36.175505) (xy 341.45093 -36.19881) (xy 341.443911 -36.21049) (xy 341.43572 -36.236468)
			(xy 341.434691 -36.263687) (xy 341.440897 -36.29021) (xy 341.453896 -36.314147) (xy 341.472762 -36.333794)
			(xy 341.496153 -36.347753) (xy 341.522402 -36.355029) (xy 341.53602 -36.355528) (xy 347.063568 -36.355528)
			(xy 347.751908 -35.667188) (xy 347.751908 -27.492452) (xy 347.736922 -27.477466) (xy 347.736922 -22.672294)
			(xy 346.883228 -21.8186) (xy 342.780366 -21.8186) (xy 342.757982 -21.8353) (xy 342.709298 -21.862666)
			(xy 342.657146 -21.882642) (xy 342.602638 -21.894801) (xy 342.54694 -21.898883) (xy 342.491242 -21.894801)
			(xy 342.436734 -21.882642) (xy 342.384582 -21.862666) (xy 342.335898 -21.8353) (xy 342.313514 -21.8186)
			(xy 341.347044 -21.8186) (xy 336.689446 -17.161002) (xy 336.315304 -17.161002) (xy 336.301859 -17.161403)
			(xy 336.275899 -17.168411) (xy 336.252678 -17.181968) (xy 336.233812 -17.201127) (xy 336.220616 -17.224556)
			(xy 336.214009 -17.25062) (xy 336.214452 -17.277506) (xy 336.217768 -17.290542) (xy 336.224645 -17.316286)
			(xy 336.232036 -17.369056) (xy 336.2325 -17.395698) (xy 336.232014 -17.422949) (xy 336.224258 -17.476897)
			(xy 336.208903 -17.529192) (xy 336.186261 -17.578769) (xy 336.156795 -17.624619) (xy 336.121104 -17.66581)
			(xy 336.079913 -17.701501) (xy 336.034063 -17.730967) (xy 335.984486 -17.753609) (xy 335.932191 -17.768964)
			(xy 335.878243 -17.77672) (xy 335.823741 -17.77672) (xy 335.769793 -17.768964) (xy 335.717498 -17.753609)
			(xy 335.667921 -17.730967) (xy 335.622071 -17.701501) (xy 335.58088 -17.66581) (xy 335.545189 -17.624619)
			(xy 335.515723 -17.578769) (xy 335.493081 -17.529192) (xy 335.477726 -17.476897) (xy 335.46997 -17.422949)
			(xy 335.469484 -17.395698) (xy 335.469911 -17.369053) (xy 335.477311 -17.31628) (xy 335.484216 -17.290542)
			(xy 335.487516 -17.277511) (xy 335.487908 -17.250641) (xy 335.481276 -17.2246) (xy 335.468081 -17.201191)
			(xy 335.449235 -17.182034) (xy 335.426045 -17.168458) (xy 335.400115 -17.161401) (xy 335.38668 -17.161002)
			(xy 335.179416 -17.161002) (xy 335.16529 -17.161458) (xy 335.138116 -17.169187) (xy 335.114095 -17.184059)
			(xy 335.095063 -17.204938) (xy 335.082473 -17.23023) (xy 335.077287 -17.258001) (xy 335.079901 -17.286132)
			(xy 335.084674 -17.299432) (xy 335.092887 -17.321532) (xy 335.104423 -17.367247) (xy 335.110242 -17.414034)
			(xy 335.110582 -17.437608) (xy 335.110118 -17.46486) (xy 335.10236 -17.518808) (xy 335.087003 -17.571104)
			(xy 335.06436 -17.620681) (xy 335.034891 -17.666532) (xy 334.999197 -17.707721) (xy 334.958004 -17.743412)
			(xy 334.912151 -17.772876) (xy 334.862572 -17.795515) (xy 334.810275 -17.810867) (xy 334.756326 -17.818621)
			(xy 334.729074 -17.819116) (xy 334.70323 -17.818684) (xy 334.652015 -17.8117) (xy 334.602213 -17.797864)
			(xy 334.554736 -17.777429) (xy 334.510454 -17.750769) (xy 334.470177 -17.718373) (xy 334.434645 -17.680834)
			(xy 334.419194 -17.660112) (xy 334.410787 -17.649172) (xy 334.389302 -17.631879) (xy 334.363971 -17.62097)
			(xy 334.336644 -17.617243) (xy 334.309317 -17.62097) (xy 334.283986 -17.631879) (xy 334.262501 -17.649172)
			(xy 334.254094 -17.660112) (xy 334.238668 -17.68085) (xy 334.203123 -17.718373) (xy 334.162838 -17.750755)
			(xy 334.11855 -17.777401) (xy 334.071071 -17.797826) (xy 334.021269 -17.811654) (xy 333.970057 -17.818633)
			(xy 333.944214 -17.819116) (xy 333.915325 -17.818585) (xy 333.858208 -17.809877) (xy 333.803056 -17.792659)
			(xy 333.75113 -17.767323) (xy 333.703616 -17.734449) (xy 333.661601 -17.694789) (xy 333.626045 -17.649248)
			(xy 333.611474 -17.624298) (xy 333.6045 -17.612788) (xy 333.585611 -17.593631) (xy 333.562376 -17.58007)
			(xy 333.536406 -17.573046) (xy 333.509504 -17.573046) (xy 333.483534 -17.58007) (xy 333.460299 -17.593631)
			(xy 333.44141 -17.612788) (xy 333.434436 -17.624298) (xy 333.419838 -17.649232) (xy 333.384294 -17.694781)
			(xy 333.342288 -17.734448) (xy 333.294778 -17.767326) (xy 333.242854 -17.792661) (xy 333.187702 -17.809876)
			(xy 333.130584 -17.818574) (xy 333.101696 -17.819116) (xy 333.074445 -17.81863) (xy 333.020497 -17.810873)
			(xy 332.968202 -17.795518) (xy 332.918625 -17.772876) (xy 332.872775 -17.74341) (xy 332.831584 -17.707719)
			(xy 332.795892 -17.666529) (xy 332.766426 -17.620678) (xy 332.743784 -17.571101) (xy 332.728428 -17.518807)
			(xy 332.72067 -17.464859) (xy 332.720188 -17.437608) (xy 332.720539 -17.414034) (xy 332.726349 -17.367246)
			(xy 332.737882 -17.321531) (xy 332.746096 -17.299432) (xy 332.750788 -17.286103) (xy 332.753425 -17.257981)
			(xy 332.748258 -17.230212) (xy 332.735682 -17.204921) (xy 332.71666 -17.184041) (xy 332.692646 -17.16917)
			(xy 332.665477 -17.161446) (xy 332.651354 -17.161002) (xy 323.182234 -17.161002) (xy 322.391278 -17.951958)
			(xy 309.599076 -17.951958) (xy 308.379114 -19.17192) (xy 335.511392 -19.17192) (xy 335.515463 -19.116298)
			(xy 335.527589 -19.061861) (xy 335.547512 -19.00977) (xy 335.574808 -18.961135) (xy 335.608894 -18.916992)
			(xy 335.649043 -18.878283) (xy 335.694401 -18.845832) (xy 335.744001 -18.820331) (xy 335.796785 -18.802324)
			(xy 335.851628 -18.792194) (xy 335.907362 -18.790157) (xy 335.962799 -18.796257) (xy 336.016756 -18.810363)
			(xy 336.068085 -18.832175) (xy 336.115691 -18.861229) (xy 336.158559 -18.896904) (xy 336.195776 -18.938441)
			(xy 336.226549 -18.984954) (xy 336.250221 -19.035451) (xy 336.266289 -19.088858) (xy 336.274409 -19.144034)
			(xy 336.274918 -19.17192) (xy 336.274409 -19.199806) (xy 336.266289 -19.254982) (xy 336.250221 -19.308389)
			(xy 336.226549 -19.358886) (xy 336.195776 -19.405399) (xy 336.158559 -19.446936) (xy 336.115691 -19.482611)
			(xy 336.068085 -19.511665) (xy 336.016756 -19.533477) (xy 335.962799 -19.547583) (xy 335.907362 -19.553683)
			(xy 335.851628 -19.551646) (xy 335.796785 -19.541516) (xy 335.744001 -19.523509) (xy 335.694401 -19.498008)
			(xy 335.649043 -19.465557) (xy 335.608894 -19.426848) (xy 335.574808 -19.382705) (xy 335.547512 -19.33407)
			(xy 335.527589 -19.281979) (xy 335.515463 -19.227542) (xy 335.511392 -19.17192) (xy 308.379114 -19.17192)
			(xy 307.596286 -19.954748) (xy 331.626462 -19.954748) (xy 331.630533 -19.899126) (xy 331.642659 -19.844689)
			(xy 331.662582 -19.792598) (xy 331.689878 -19.743963) (xy 331.723964 -19.69982) (xy 331.764113 -19.661111)
			(xy 331.809471 -19.62866) (xy 331.859071 -19.603159) (xy 331.911855 -19.585152) (xy 331.966698 -19.575022)
			(xy 332.022432 -19.572985) (xy 332.077869 -19.579085) (xy 332.131826 -19.593191) (xy 332.183155 -19.615003)
			(xy 332.230761 -19.644057) (xy 332.273629 -19.679732) (xy 332.310846 -19.721269) (xy 332.341619 -19.767782)
			(xy 332.365291 -19.818279) (xy 332.381359 -19.871686) (xy 332.389479 -19.926862) (xy 332.389895 -19.949668)
			(xy 332.57566 -19.949668) (xy 332.579731 -19.894046) (xy 332.591857 -19.839609) (xy 332.61178 -19.787518)
			(xy 332.639076 -19.738883) (xy 332.673162 -19.69474) (xy 332.713311 -19.656031) (xy 332.758669 -19.62358)
			(xy 332.808269 -19.598079) (xy 332.861053 -19.580072) (xy 332.915896 -19.569942) (xy 332.97163 -19.567905)
			(xy 333.027067 -19.574005) (xy 333.081024 -19.588111) (xy 333.132353 -19.609923) (xy 333.179959 -19.638977)
			(xy 333.222827 -19.674652) (xy 333.260044 -19.716189) (xy 333.290817 -19.762702) (xy 333.314489 -19.813199)
			(xy 333.330557 -19.866606) (xy 333.338677 -19.921782) (xy 333.339186 -19.949668) (xy 333.338677 -19.977554)
			(xy 333.330557 -20.03273) (xy 333.314489 -20.086137) (xy 333.290817 -20.136634) (xy 333.260044 -20.183147)
			(xy 333.222827 -20.224684) (xy 333.179959 -20.260359) (xy 333.132353 -20.289413) (xy 333.081024 -20.311225)
			(xy 333.027067 -20.325331) (xy 332.97163 -20.331431) (xy 332.915896 -20.329394) (xy 332.861053 -20.319264)
			(xy 332.808269 -20.301257) (xy 332.758669 -20.275756) (xy 332.713311 -20.243305) (xy 332.673162 -20.204596)
			(xy 332.639076 -20.160453) (xy 332.61178 -20.111818) (xy 332.591857 -20.059727) (xy 332.579731 -20.00529)
			(xy 332.57566 -19.949668) (xy 332.389895 -19.949668) (xy 332.389988 -19.954748) (xy 332.389479 -19.982634)
			(xy 332.381359 -20.03781) (xy 332.365291 -20.091217) (xy 332.341619 -20.141714) (xy 332.310846 -20.188227)
			(xy 332.273629 -20.229764) (xy 332.230761 -20.265439) (xy 332.183155 -20.294493) (xy 332.131826 -20.316305)
			(xy 332.077869 -20.330411) (xy 332.022432 -20.336511) (xy 331.966698 -20.334474) (xy 331.911855 -20.324344)
			(xy 331.859071 -20.306337) (xy 331.809471 -20.280836) (xy 331.764113 -20.248385) (xy 331.723964 -20.209676)
			(xy 331.689878 -20.165533) (xy 331.662582 -20.116898) (xy 331.642659 -20.064807) (xy 331.630533 -20.01037)
			(xy 331.626462 -19.954748) (xy 307.596286 -19.954748) (xy 306.918106 -20.632928) (xy 324.306182 -20.632928)
			(xy 324.310253 -20.577306) (xy 324.322379 -20.522869) (xy 324.342302 -20.470778) (xy 324.369598 -20.422143)
			(xy 324.403684 -20.378) (xy 324.443833 -20.339291) (xy 324.489191 -20.30684) (xy 324.538791 -20.281339)
			(xy 324.591575 -20.263332) (xy 324.646418 -20.253202) (xy 324.702152 -20.251165) (xy 324.757589 -20.257265)
			(xy 324.811546 -20.271371) (xy 324.862875 -20.293183) (xy 324.910481 -20.322237) (xy 324.953349 -20.357912)
			(xy 324.990566 -20.399449) (xy 325.021339 -20.445962) (xy 325.045011 -20.496459) (xy 325.061079 -20.549866)
			(xy 325.069199 -20.605042) (xy 325.069708 -20.632928) (xy 325.069199 -20.660814) (xy 325.061079 -20.71599)
			(xy 325.045011 -20.769397) (xy 325.021339 -20.819894) (xy 324.990566 -20.866407) (xy 324.953349 -20.907944)
			(xy 324.910481 -20.943619) (xy 324.862875 -20.972673) (xy 324.811546 -20.994485) (xy 324.757589 -21.008591)
			(xy 324.702152 -21.014691) (xy 324.646418 -21.012654) (xy 324.591575 -21.002524) (xy 324.538791 -20.984517)
			(xy 324.489191 -20.959016) (xy 324.443833 -20.926565) (xy 324.403684 -20.887856) (xy 324.369598 -20.843713)
			(xy 324.342302 -20.795078) (xy 324.322379 -20.742987) (xy 324.310253 -20.68855) (xy 324.306182 -20.632928)
			(xy 306.918106 -20.632928) (xy 306.426583 -21.124451) (xy 320.536295 -21.124451) (xy 320.536295 -21.069949)
			(xy 320.544052 -21.016003) (xy 320.559407 -20.963709) (xy 320.582048 -20.914133) (xy 320.611515 -20.868284)
			(xy 320.647206 -20.827095) (xy 320.688397 -20.791405) (xy 320.734247 -20.761941) (xy 320.783824 -20.739301)
			(xy 320.836118 -20.723948) (xy 320.890065 -20.716194) (xy 320.917316 -20.715732) (xy 320.946688 -20.716242)
			(xy 321.004737 -20.725249) (xy 321.060719 -20.743048) (xy 321.113311 -20.769218) (xy 321.16127 -20.80314)
			(xy 321.203463 -20.844013) (xy 321.221608 -20.867116) (xy 321.231423 -20.87911) (xy 321.256681 -20.89704)
			(xy 321.286148 -20.906591) (xy 321.317122 -20.906886) (xy 321.346765 -20.8979) (xy 321.372361 -20.880455)
			(xy 321.38239 -20.86864) (xy 321.400605 -20.846431) (xy 321.442512 -20.807158) (xy 321.489837 -20.774615)
			(xy 321.541508 -20.749539) (xy 321.596356 -20.732497) (xy 321.653139 -20.723876) (xy 321.681856 -20.723352)
			(xy 321.709108 -20.723892) (xy 321.763058 -20.731643) (xy 321.815356 -20.746994) (xy 321.864936 -20.769632)
			(xy 321.91079 -20.799095) (xy 321.951984 -20.834785) (xy 321.987678 -20.875975) (xy 322.017147 -20.921825)
			(xy 322.039791 -20.971403) (xy 322.055147 -21.023699) (xy 322.062905 -21.077648) (xy 322.062905 -21.132152)
			(xy 322.055147 -21.186101) (xy 322.039791 -21.238397) (xy 322.017147 -21.287975) (xy 321.987678 -21.333825)
			(xy 321.969945 -21.354288) (xy 328.149712 -21.354288) (xy 328.150188 -21.327208) (xy 328.157844 -21.273593)
			(xy 328.172999 -21.221597) (xy 328.195351 -21.172265) (xy 328.22445 -21.126587) (xy 328.259713 -21.085479)
			(xy 328.27976 -21.067268) (xy 328.290207 -21.0575) (xy 328.305635 -21.033432) (xy 328.313787 -21.006029)
			(xy 328.314024 -20.977441) (xy 328.306325 -20.949908) (xy 328.291297 -20.925588) (xy 328.28103 -20.91563)
			(xy 328.261702 -20.897438) (xy 328.22771 -20.856675) (xy 328.199694 -20.811595) (xy 328.178194 -20.763068)
			(xy 328.163624 -20.71203) (xy 328.156267 -20.659466) (xy 328.155808 -20.632928) (xy 328.156294 -20.605677)
			(xy 328.16405 -20.551729) (xy 328.179405 -20.499434) (xy 328.202047 -20.449857) (xy 328.231513 -20.404007)
			(xy 328.267204 -20.362816) (xy 328.308395 -20.327125) (xy 328.354245 -20.297659) (xy 328.403822 -20.275017)
			(xy 328.456117 -20.259662) (xy 328.510065 -20.251906) (xy 328.564567 -20.251906) (xy 328.618515 -20.259662)
			(xy 328.67081 -20.275017) (xy 328.720387 -20.297659) (xy 328.766237 -20.327125) (xy 328.807428 -20.362816)
			(xy 328.843119 -20.404007) (xy 328.872585 -20.449857) (xy 328.895227 -20.499434) (xy 328.910582 -20.551729)
			(xy 328.918338 -20.605677) (xy 328.918824 -20.632928) (xy 328.918381 -20.660009) (xy 328.910721 -20.713627)
			(xy 328.895561 -20.765624) (xy 328.873203 -20.814957) (xy 328.844097 -20.860634) (xy 328.808827 -20.901739)
			(xy 328.788776 -20.919948) (xy 328.778311 -20.929699) (xy 328.762877 -20.953771) (xy 328.754724 -20.981178)
			(xy 328.754491 -21.009772) (xy 328.762195 -21.037309) (xy 328.777234 -21.061629) (xy 328.787506 -21.071586)
			(xy 328.806848 -21.089763) (xy 328.807152 -21.090128) (xy 332.678022 -21.090128) (xy 332.682093 -21.034506)
			(xy 332.694219 -20.980069) (xy 332.714142 -20.927978) (xy 332.741438 -20.879343) (xy 332.775524 -20.8352)
			(xy 332.815673 -20.796491) (xy 332.861031 -20.76404) (xy 332.910631 -20.738539) (xy 332.963415 -20.720532)
			(xy 333.018258 -20.710402) (xy 333.073992 -20.708365) (xy 333.129429 -20.714465) (xy 333.183386 -20.728571)
			(xy 333.234715 -20.750383) (xy 333.282321 -20.779437) (xy 333.325189 -20.815112) (xy 333.362406 -20.856649)
			(xy 333.393179 -20.903162) (xy 333.416851 -20.953659) (xy 333.432919 -21.007066) (xy 333.441039 -21.062242)
			(xy 333.441548 -21.090128) (xy 333.441039 -21.118014) (xy 333.432919 -21.17319) (xy 333.416851 -21.226597)
			(xy 333.393179 -21.277094) (xy 333.362406 -21.323607) (xy 333.325189 -21.365144) (xy 333.282321 -21.400819)
			(xy 333.234715 -21.429873) (xy 333.205772 -21.442172) (xy 336.918564 -21.442172) (xy 336.92254 -21.387846)
			(xy 336.934383 -21.334677) (xy 336.953842 -21.2838) (xy 336.980502 -21.236298) (xy 337.013793 -21.193184)
			(xy 337.053007 -21.155377) (xy 337.097309 -21.123682) (xy 337.145752 -21.098776) (xy 337.197306 -21.081188)
			(xy 337.250872 -21.071294) (xy 337.305307 -21.069304) (xy 337.359452 -21.075262) (xy 337.412152 -21.08904)
			(xy 337.462285 -21.110344) (xy 337.508781 -21.13872) (xy 337.550651 -21.173564) (xy 337.587 -21.214133)
			(xy 337.617056 -21.259562) (xy 337.640177 -21.308883) (xy 337.65587 -21.361045) (xy 337.663801 -21.414936)
			(xy 337.664298 -21.442172) (xy 337.663801 -21.469408) (xy 337.65587 -21.523299) (xy 337.640177 -21.575461)
			(xy 337.617056 -21.624782) (xy 337.587 -21.670211) (xy 337.550651 -21.71078) (xy 337.508781 -21.745624)
			(xy 337.462285 -21.774) (xy 337.412152 -21.795304) (xy 337.359452 -21.809082) (xy 337.305307 -21.81504)
			(xy 337.250872 -21.81305) (xy 337.197306 -21.803156) (xy 337.145752 -21.785568) (xy 337.097309 -21.760662)
			(xy 337.053007 -21.728967) (xy 337.013793 -21.69116) (xy 336.980502 -21.648046) (xy 336.953842 -21.600544)
			(xy 336.934383 -21.549667) (xy 336.92254 -21.496498) (xy 336.918564 -21.442172) (xy 333.205772 -21.442172)
			(xy 333.183386 -21.451685) (xy 333.129429 -21.465791) (xy 333.073992 -21.471891) (xy 333.018258 -21.469854)
			(xy 332.963415 -21.459724) (xy 332.910631 -21.441717) (xy 332.861031 -21.416216) (xy 332.815673 -21.383765)
			(xy 332.775524 -21.345056) (xy 332.741438 -21.300913) (xy 332.714142 -21.252278) (xy 332.694219 -21.200187)
			(xy 332.682093 -21.14575) (xy 332.678022 -21.090128) (xy 328.807152 -21.090128) (xy 328.840838 -21.13053)
			(xy 328.868851 -21.175614) (xy 328.890349 -21.224143) (xy 328.904915 -21.275183) (xy 328.912271 -21.327749)
			(xy 328.912728 -21.354288) (xy 328.912242 -21.381539) (xy 328.904486 -21.435487) (xy 328.889131 -21.487782)
			(xy 328.866489 -21.537359) (xy 328.837023 -21.583209) (xy 328.801332 -21.6244) (xy 328.760141 -21.660091)
			(xy 328.714291 -21.689557) (xy 328.664714 -21.712199) (xy 328.612419 -21.727554) (xy 328.558471 -21.73531)
			(xy 328.503969 -21.73531) (xy 328.450021 -21.727554) (xy 328.397726 -21.712199) (xy 328.348149 -21.689557)
			(xy 328.302299 -21.660091) (xy 328.261108 -21.6244) (xy 328.225417 -21.583209) (xy 328.195951 -21.537359)
			(xy 328.173309 -21.487782) (xy 328.157954 -21.435487) (xy 328.150198 -21.381539) (xy 328.149712 -21.354288)
			(xy 321.969945 -21.354288) (xy 321.951984 -21.375015) (xy 321.91079 -21.410705) (xy 321.864936 -21.440168)
			(xy 321.815356 -21.462806) (xy 321.763058 -21.478157) (xy 321.709108 -21.485908) (xy 321.681856 -21.486368)
			(xy 321.652486 -21.485805) (xy 321.59444 -21.476809) (xy 321.538459 -21.459021) (xy 321.485866 -21.432861)
			(xy 321.437906 -21.398947) (xy 321.395711 -21.358083) (xy 321.377564 -21.334984) (xy 321.36778 -21.322963)
			(xy 321.342513 -21.305032) (xy 321.313039 -21.295485) (xy 321.282058 -21.295194) (xy 321.25241 -21.304188)
			(xy 321.226811 -21.321641) (xy 321.216782 -21.33346) (xy 321.198583 -21.355682) (xy 321.156672 -21.394955)
			(xy 321.109344 -21.427496) (xy 321.05767 -21.45257) (xy 321.00282 -21.469608) (xy 320.946034 -21.478226)
			(xy 320.917316 -21.478748) (xy 320.890065 -21.478206) (xy 320.836118 -21.470452) (xy 320.783824 -21.455099)
			(xy 320.734247 -21.432459) (xy 320.688397 -21.402995) (xy 320.647206 -21.367305) (xy 320.611515 -21.326116)
			(xy 320.582048 -21.280267) (xy 320.559407 -21.230691) (xy 320.544052 -21.178397) (xy 320.536295 -21.124451)
			(xy 306.426583 -21.124451) (xy 304.830734 -22.7203) (xy 312.101482 -22.7203) (xy 312.105553 -22.664678)
			(xy 312.117679 -22.610241) (xy 312.137602 -22.55815) (xy 312.164898 -22.509515) (xy 312.198984 -22.465372)
			(xy 312.239133 -22.426663) (xy 312.284491 -22.394212) (xy 312.334091 -22.368711) (xy 312.386875 -22.350704)
			(xy 312.441718 -22.340574) (xy 312.497452 -22.338537) (xy 312.552889 -22.344637) (xy 312.606846 -22.358743)
			(xy 312.658175 -22.380555) (xy 312.705781 -22.409609) (xy 312.748649 -22.445284) (xy 312.785866 -22.486821)
			(xy 312.816639 -22.533334) (xy 312.825341 -22.551898) (xy 320.698874 -22.551898) (xy 320.702945 -22.496276)
			(xy 320.715071 -22.441839) (xy 320.734994 -22.389748) (xy 320.76229 -22.341113) (xy 320.796376 -22.29697)
			(xy 320.836525 -22.258261) (xy 320.881883 -22.22581) (xy 320.931483 -22.200309) (xy 320.984267 -22.182302)
			(xy 321.03911 -22.172172) (xy 321.094844 -22.170135) (xy 321.150281 -22.176235) (xy 321.204238 -22.190341)
			(xy 321.255567 -22.212153) (xy 321.303173 -22.241207) (xy 321.346041 -22.276882) (xy 321.383258 -22.318419)
			(xy 321.399089 -22.342348) (xy 323.676262 -22.342348) (xy 323.680333 -22.286726) (xy 323.692459 -22.232289)
			(xy 323.712382 -22.180198) (xy 323.739678 -22.131563) (xy 323.773764 -22.08742) (xy 323.813913 -22.048711)
			(xy 323.859271 -22.01626) (xy 323.908871 -21.990759) (xy 323.961655 -21.972752) (xy 324.016498 -21.962622)
			(xy 324.072232 -21.960585) (xy 324.127669 -21.966685) (xy 324.181626 -21.980791) (xy 324.232955 -22.002603)
			(xy 324.280561 -22.031657) (xy 324.323429 -22.067332) (xy 324.360646 -22.108869) (xy 324.391419 -22.155382)
			(xy 324.415091 -22.205879) (xy 324.431159 -22.259286) (xy 324.433477 -22.275038) (xy 324.583552 -22.275038)
			(xy 324.584038 -22.247787) (xy 324.591794 -22.193839) (xy 324.607149 -22.141544) (xy 324.629791 -22.091967)
			(xy 324.659257 -22.046117) (xy 324.694948 -22.004926) (xy 324.736139 -21.969235) (xy 324.781989 -21.939769)
			(xy 324.831566 -21.917127) (xy 324.883861 -21.901772) (xy 324.937809 -21.894016) (xy 324.992311 -21.894016)
			(xy 325.046259 -21.901772) (xy 325.098554 -21.917127) (xy 325.148131 -21.939769) (xy 325.193981 -21.969235)
			(xy 325.235172 -22.004926) (xy 325.270863 -22.046117) (xy 325.300329 -22.091967) (xy 325.322971 -22.141544)
			(xy 325.338326 -22.193839) (xy 325.346082 -22.247787) (xy 325.346568 -22.275038) (xy 325.346098 -22.301418)
			(xy 325.338835 -22.353675) (xy 325.32444 -22.404433) (xy 325.303186 -22.452722) (xy 325.27548 -22.497622)
			(xy 325.241851 -22.538274) (xy 325.20294 -22.573904) (xy 325.181468 -22.589236) (xy 325.170038 -22.597669)
			(xy 325.15199 -22.619589) (xy 325.140666 -22.645627) (xy 325.136937 -22.673775) (xy 325.141092 -22.701863)
			(xy 325.15281 -22.727726) (xy 325.171187 -22.749371) (xy 325.182738 -22.757638) (xy 325.204842 -22.77282)
			(xy 325.244893 -22.808481) (xy 325.279553 -22.849401) (xy 325.308138 -22.894774) (xy 325.330083 -22.943704)
			(xy 325.344957 -22.995227) (xy 325.352465 -23.048325) (xy 325.352918 -23.075138) (xy 325.352432 -23.102389)
			(xy 325.344676 -23.156337) (xy 325.329321 -23.208632) (xy 325.306679 -23.258209) (xy 325.277213 -23.304059)
			(xy 325.241522 -23.34525) (xy 325.200331 -23.380941) (xy 325.154481 -23.410407) (xy 325.104904 -23.433049)
			(xy 325.052609 -23.448404) (xy 324.998661 -23.45616) (xy 324.944159 -23.45616) (xy 324.890211 -23.448404)
			(xy 324.837916 -23.433049) (xy 324.788339 -23.410407) (xy 324.742489 -23.380941) (xy 324.701298 -23.34525)
			(xy 324.665607 -23.304059) (xy 324.636141 -23.258209) (xy 324.613499 -23.208632) (xy 324.598144 -23.156337)
			(xy 324.590388 -23.102389) (xy 324.589902 -23.075138) (xy 324.590367 -23.048758) (xy 324.597632 -22.996501)
			(xy 324.612029 -22.945744) (xy 324.633284 -22.897455) (xy 324.66099 -22.852555) (xy 324.69462 -22.811902)
			(xy 324.73353 -22.776272) (xy 324.755002 -22.76094) (xy 324.766459 -22.752539) (xy 324.784512 -22.730613)
			(xy 324.795839 -22.704568) (xy 324.799566 -22.676411) (xy 324.795405 -22.648316) (xy 324.783678 -22.622448)
			(xy 324.765289 -22.600804) (xy 324.753732 -22.592538) (xy 324.731679 -22.577285) (xy 324.691623 -22.541638)
			(xy 324.656958 -22.500731) (xy 324.628366 -22.455371) (xy 324.606412 -22.406451) (xy 324.591529 -22.354938)
			(xy 324.58401 -22.301848) (xy 324.583552 -22.275038) (xy 324.433477 -22.275038) (xy 324.439279 -22.314462)
			(xy 324.439788 -22.342348) (xy 324.439279 -22.370234) (xy 324.431159 -22.42541) (xy 324.415091 -22.478817)
			(xy 324.391419 -22.529314) (xy 324.360646 -22.575827) (xy 324.323429 -22.617364) (xy 324.280561 -22.653039)
			(xy 324.232955 -22.682093) (xy 324.181626 -22.703905) (xy 324.127669 -22.718011) (xy 324.072232 -22.724111)
			(xy 324.016498 -22.722074) (xy 323.961655 -22.711944) (xy 323.908871 -22.693937) (xy 323.859271 -22.668436)
			(xy 323.813913 -22.635985) (xy 323.773764 -22.597276) (xy 323.739678 -22.553133) (xy 323.712382 -22.504498)
			(xy 323.692459 -22.452407) (xy 323.680333 -22.39797) (xy 323.676262 -22.342348) (xy 321.399089 -22.342348)
			(xy 321.414031 -22.364932) (xy 321.437703 -22.415429) (xy 321.453771 -22.468836) (xy 321.461891 -22.524012)
			(xy 321.4624 -22.551898) (xy 321.461891 -22.579784) (xy 321.453771 -22.63496) (xy 321.437703 -22.688367)
			(xy 321.414031 -22.738864) (xy 321.383258 -22.785377) (xy 321.346041 -22.826914) (xy 321.303173 -22.862589)
			(xy 321.255567 -22.891643) (xy 321.204238 -22.913455) (xy 321.150281 -22.927561) (xy 321.094844 -22.933661)
			(xy 321.03911 -22.931624) (xy 320.984267 -22.921494) (xy 320.931483 -22.903487) (xy 320.881883 -22.877986)
			(xy 320.836525 -22.845535) (xy 320.796376 -22.806826) (xy 320.76229 -22.762683) (xy 320.734994 -22.714048)
			(xy 320.715071 -22.661957) (xy 320.702945 -22.60752) (xy 320.698874 -22.551898) (xy 312.825341 -22.551898)
			(xy 312.840311 -22.583831) (xy 312.856379 -22.637238) (xy 312.864499 -22.692414) (xy 312.865008 -22.7203)
			(xy 312.864499 -22.748186) (xy 312.856379 -22.803362) (xy 312.840311 -22.856769) (xy 312.816639 -22.907266)
			(xy 312.785866 -22.953779) (xy 312.748649 -22.995316) (xy 312.705781 -23.030991) (xy 312.658175 -23.060045)
			(xy 312.606846 -23.081857) (xy 312.552889 -23.095963) (xy 312.497452 -23.102063) (xy 312.441718 -23.100026)
			(xy 312.386875 -23.089896) (xy 312.334091 -23.071889) (xy 312.284491 -23.046388) (xy 312.239133 -23.013937)
			(xy 312.198984 -22.975228) (xy 312.164898 -22.931085) (xy 312.137602 -22.88245) (xy 312.117679 -22.830359)
			(xy 312.105553 -22.775922) (xy 312.101482 -22.7203) (xy 304.830734 -22.7203) (xy 304.790856 -22.760178)
			(xy 304.790856 -23.241) (xy 310.793382 -23.241) (xy 310.797453 -23.185378) (xy 310.809579 -23.130941)
			(xy 310.829502 -23.07885) (xy 310.856798 -23.030215) (xy 310.890884 -22.986072) (xy 310.931033 -22.947363)
			(xy 310.976391 -22.914912) (xy 311.025991 -22.889411) (xy 311.078775 -22.871404) (xy 311.133618 -22.861274)
			(xy 311.189352 -22.859237) (xy 311.244789 -22.865337) (xy 311.298746 -22.879443) (xy 311.350075 -22.901255)
			(xy 311.397681 -22.930309) (xy 311.440549 -22.965984) (xy 311.477766 -23.007521) (xy 311.508539 -23.054034)
			(xy 311.532211 -23.104531) (xy 311.548279 -23.157938) (xy 311.556399 -23.213114) (xy 311.556908 -23.241)
			(xy 311.556399 -23.268886) (xy 311.548279 -23.324062) (xy 311.533379 -23.373588) (xy 317.758062 -23.373588)
			(xy 317.762133 -23.317966) (xy 317.774259 -23.263529) (xy 317.794182 -23.211438) (xy 317.821478 -23.162803)
			(xy 317.855564 -23.11866) (xy 317.895713 -23.079951) (xy 317.941071 -23.0475) (xy 317.990671 -23.021999)
			(xy 318.043455 -23.003992) (xy 318.098298 -22.993862) (xy 318.154032 -22.991825) (xy 318.209469 -22.997925)
			(xy 318.263426 -23.012031) (xy 318.314755 -23.033843) (xy 318.362361 -23.062897) (xy 318.405229 -23.098572)
			(xy 318.442446 -23.140109) (xy 318.473219 -23.186622) (xy 318.496891 -23.237119) (xy 318.512959 -23.290526)
			(xy 318.521079 -23.345702) (xy 318.521588 -23.373588) (xy 318.521079 -23.401474) (xy 318.512959 -23.45665)
			(xy 318.496891 -23.510057) (xy 318.473219 -23.560554) (xy 318.442446 -23.607067) (xy 318.405229 -23.648604)
			(xy 318.362361 -23.684279) (xy 318.314755 -23.713333) (xy 318.263426 -23.735145) (xy 318.209469 -23.749251)
			(xy 318.154032 -23.755351) (xy 318.098298 -23.753314) (xy 318.043455 -23.743184) (xy 317.990671 -23.725177)
			(xy 317.941071 -23.699676) (xy 317.895713 -23.667225) (xy 317.855564 -23.628516) (xy 317.821478 -23.584373)
			(xy 317.794182 -23.535738) (xy 317.774259 -23.483647) (xy 317.762133 -23.42921) (xy 317.758062 -23.373588)
			(xy 311.533379 -23.373588) (xy 311.532211 -23.377469) (xy 311.508539 -23.427966) (xy 311.477766 -23.474479)
			(xy 311.440549 -23.516016) (xy 311.397681 -23.551691) (xy 311.350075 -23.580745) (xy 311.298746 -23.602557)
			(xy 311.244789 -23.616663) (xy 311.189352 -23.622763) (xy 311.133618 -23.620726) (xy 311.078775 -23.610596)
			(xy 311.025991 -23.592589) (xy 310.976391 -23.567088) (xy 310.931033 -23.534637) (xy 310.890884 -23.495928)
			(xy 310.856798 -23.451785) (xy 310.829502 -23.40315) (xy 310.809579 -23.351059) (xy 310.797453 -23.296622)
			(xy 310.793382 -23.241) (xy 304.790856 -23.241) (xy 304.790856 -23.711662) (xy 304.7913 -23.725382)
			(xy 304.798603 -23.751832) (xy 304.812692 -23.775379) (xy 304.832547 -23.79432) (xy 304.856732 -23.807283)
			(xy 304.883496 -23.813332) (xy 304.910905 -23.812029) (xy 304.936976 -23.803468) (xy 304.959821 -23.788269)
			(xy 304.969164 -23.77821) (xy 304.987373 -23.757977) (xy 305.028539 -23.722366) (xy 305.074349 -23.692969)
			(xy 305.123873 -23.670382) (xy 305.176105 -23.655064) (xy 305.229984 -23.647326) (xy 305.2572 -23.646892)
			(xy 305.284451 -23.647378) (xy 305.338399 -23.655134) (xy 305.390694 -23.670489) (xy 305.440271 -23.693131)
			(xy 305.486121 -23.722597) (xy 305.527312 -23.758288) (xy 305.563003 -23.799479) (xy 305.592469 -23.845329)
			(xy 305.615111 -23.894906) (xy 305.630466 -23.947201) (xy 305.638222 -24.001149) (xy 305.638222 -24.055651)
			(xy 305.630466 -24.109599) (xy 305.615111 -24.161894) (xy 305.592469 -24.211471) (xy 305.563003 -24.257321)
			(xy 305.527312 -24.298512) (xy 305.486121 -24.334203) (xy 305.440271 -24.363669) (xy 305.390694 -24.386311)
			(xy 305.338399 -24.401666) (xy 305.284451 -24.409422) (xy 305.2572 -24.409908) (xy 305.229986 -24.409425)
			(xy 305.17611 -24.401692) (xy 305.12388 -24.386382) (xy 305.074354 -24.363806) (xy 305.028539 -24.334423)
			(xy 304.987364 -24.298828) (xy 304.969164 -24.27859) (xy 304.959832 -24.268519) (xy 304.936974 -24.25333)
			(xy 304.910895 -24.244776) (xy 304.883481 -24.243478) (xy 304.856711 -24.249527) (xy 304.832519 -24.262488)
			(xy 304.812653 -24.281424) (xy 304.798548 -24.304966) (xy 304.791222 -24.331416) (xy 304.790856 -24.345138)
			(xy 304.790856 -27.6606) (xy 305.637182 -27.6606) (xy 305.641253 -27.604978) (xy 305.653379 -27.550541)
			(xy 305.673302 -27.49845) (xy 305.700598 -27.449815) (xy 305.734684 -27.405672) (xy 305.774833 -27.366963)
			(xy 305.820191 -27.334512) (xy 305.869791 -27.309011) (xy 305.922575 -27.291004) (xy 305.977418 -27.280874)
			(xy 306.033152 -27.278837) (xy 306.088589 -27.284937) (xy 306.142546 -27.299043) (xy 306.193875 -27.320855)
			(xy 306.241481 -27.349909) (xy 306.284349 -27.385584) (xy 306.321566 -27.427121) (xy 306.352339 -27.473634)
			(xy 306.376011 -27.524131) (xy 306.392079 -27.577538) (xy 306.400199 -27.632714) (xy 306.400708 -27.6606)
			(xy 306.400199 -27.688486) (xy 306.392079 -27.743662) (xy 306.376011 -27.797069) (xy 306.352339 -27.847566)
			(xy 306.321566 -27.894079) (xy 306.284349 -27.935616) (xy 306.241481 -27.971291) (xy 306.193875 -28.000345)
			(xy 306.142546 -28.022157) (xy 306.088589 -28.036263) (xy 306.033152 -28.042363) (xy 305.977418 -28.040326)
			(xy 305.922575 -28.030196) (xy 305.869791 -28.012189) (xy 305.820191 -27.986688) (xy 305.774833 -27.954237)
			(xy 305.734684 -27.915528) (xy 305.700598 -27.871385) (xy 305.673302 -27.82275) (xy 305.653379 -27.770659)
			(xy 305.641253 -27.716222) (xy 305.637182 -27.6606) (xy 304.790856 -27.6606) (xy 304.790856 -28.050236)
			(xy 305.041046 -28.300172) (xy 307.460396 -28.300172) (xy 311.833514 -23.927308) (xy 314.61456 -23.927308)
			(xy 314.629641 -23.904454) (xy 314.665314 -23.862914) (xy 314.706562 -23.826904) (xy 314.752537 -23.797164)
			(xy 314.802294 -23.774308) (xy 314.854808 -23.758803) (xy 314.909 -23.750971) (xy 314.963756 -23.750971)
			(xy 315.017948 -23.758803) (xy 315.070462 -23.774308) (xy 315.120219 -23.797164) (xy 315.166194 -23.826904)
			(xy 315.207442 -23.862914) (xy 315.243115 -23.904454) (xy 315.258196 -23.927308) (xy 320.815462 -23.927308)
			(xy 320.829288 -23.926838) (xy 320.855923 -23.919408) (xy 320.879591 -23.905108) (xy 320.898558 -23.884986)
			(xy 320.911436 -23.860516) (xy 320.917281 -23.833488) (xy 320.915666 -23.805883) (xy 320.906708 -23.779722)
			(xy 320.899282 -23.76805) (xy 320.883406 -23.744079) (xy 320.858271 -23.692373) (xy 320.84118 -23.637479)
			(xy 320.832522 -23.580642) (xy 320.831972 -23.551896) (xy 320.832458 -23.524645) (xy 320.840214 -23.470697)
			(xy 320.855569 -23.418402) (xy 320.878211 -23.368825) (xy 320.907677 -23.322975) (xy 320.943368 -23.281784)
			(xy 320.984559 -23.246093) (xy 321.030409 -23.216627) (xy 321.079986 -23.193985) (xy 321.132281 -23.17863)
			(xy 321.186229 -23.170874) (xy 321.240731 -23.170874) (xy 321.294679 -23.17863) (xy 321.346974 -23.193985)
			(xy 321.396551 -23.216627) (xy 321.442401 -23.246093) (xy 321.483592 -23.281784) (xy 321.519283 -23.322975)
			(xy 321.548749 -23.368825) (xy 321.571391 -23.418402) (xy 321.586746 -23.470697) (xy 321.594502 -23.524645)
			(xy 321.594988 -23.551896) (xy 321.594445 -23.580641) (xy 321.585776 -23.637476) (xy 321.57778 -23.663148)
			(xy 328.009502 -23.663148) (xy 328.013573 -23.607526) (xy 328.025699 -23.553089) (xy 328.045622 -23.500998)
			(xy 328.072918 -23.452363) (xy 328.107004 -23.40822) (xy 328.147153 -23.369511) (xy 328.192511 -23.33706)
			(xy 328.242111 -23.311559) (xy 328.294895 -23.293552) (xy 328.349738 -23.283422) (xy 328.405472 -23.281385)
			(xy 328.460909 -23.287485) (xy 328.514866 -23.301591) (xy 328.566195 -23.323403) (xy 328.613801 -23.352457)
			(xy 328.656669 -23.388132) (xy 328.693886 -23.429669) (xy 328.724659 -23.476182) (xy 328.748331 -23.526679)
			(xy 328.764399 -23.580086) (xy 328.772519 -23.635262) (xy 328.772564 -23.637748) (xy 329.473052 -23.637748)
			(xy 329.473538 -23.610497) (xy 329.481294 -23.556549) (xy 329.496649 -23.504254) (xy 329.519291 -23.454677)
			(xy 329.548757 -23.408827) (xy 329.584448 -23.367636) (xy 329.625639 -23.331945) (xy 329.671489 -23.302479)
			(xy 329.721066 -23.279837) (xy 329.773361 -23.264482) (xy 329.827309 -23.256726) (xy 329.881811 -23.256726)
			(xy 329.935759 -23.264482) (xy 329.988054 -23.279837) (xy 330.037631 -23.302479) (xy 330.083481 -23.331945)
			(xy 330.124672 -23.367636) (xy 330.160363 -23.408827) (xy 330.189829 -23.454677) (xy 330.212471 -23.504254)
			(xy 330.227826 -23.556549) (xy 330.235582 -23.610497) (xy 330.236068 -23.637748) (xy 330.235875 -23.65486)
			(xy 330.232824 -23.688947) (xy 330.229972 -23.70582) (xy 330.227878 -23.72025) (xy 330.231026 -23.749224)
			(xy 330.242219 -23.776134) (xy 330.260546 -23.798795) (xy 330.284521 -23.815367) (xy 330.312197 -23.824505)
			(xy 330.326746 -23.825454) (xy 330.353454 -23.82668) (xy 330.406151 -23.835706) (xy 330.457071 -23.852005)
			(xy 330.498583 -23.872054) (xy 333.389936 -23.872054) (xy 333.389936 -23.817546) (xy 333.397693 -23.763594)
			(xy 333.413049 -23.711295) (xy 333.435692 -23.661713) (xy 333.46516 -23.615858) (xy 333.500854 -23.574664)
			(xy 333.542047 -23.538968) (xy 333.587901 -23.509498) (xy 333.637481 -23.486854) (xy 333.68978 -23.471496)
			(xy 333.743732 -23.463737) (xy 333.770986 -23.46325) (xy 333.795658 -23.46365) (xy 333.844584 -23.470056)
			(xy 333.892278 -23.48271) (xy 333.915258 -23.491698) (xy 333.92952 -23.497071) (xy 333.959863 -23.499823)
			(xy 333.989664 -23.49349) (xy 334.016266 -23.478638) (xy 334.037296 -23.456592) (xy 334.044544 -23.443184)
			(xy 334.056788 -23.419829) (xy 334.086703 -23.376405) (xy 334.122317 -23.337517) (xy 334.162949 -23.303907)
			(xy 334.207825 -23.276216) (xy 334.256088 -23.254972) (xy 334.306818 -23.240581) (xy 334.359046 -23.233317)
			(xy 334.385412 -23.232872) (xy 334.412661 -23.233399) (xy 334.466605 -23.241157) (xy 334.518895 -23.256512)
			(xy 334.568468 -23.279152) (xy 334.614315 -23.308618) (xy 334.655501 -23.344307) (xy 334.69119 -23.385495)
			(xy 334.720653 -23.431342) (xy 334.743292 -23.480916) (xy 334.758646 -23.533207) (xy 334.766402 -23.587151)
			(xy 334.766402 -23.641649) (xy 334.758646 -23.695593) (xy 334.743292 -23.747884) (xy 334.720653 -23.797458)
			(xy 334.69119 -23.843305) (xy 334.655501 -23.884493) (xy 334.614315 -23.920182) (xy 334.599275 -23.929848)
			(xy 335.636106 -23.929848) (xy 335.640177 -23.874226) (xy 335.652303 -23.819789) (xy 335.672226 -23.767698)
			(xy 335.699522 -23.719063) (xy 335.733608 -23.67492) (xy 335.773757 -23.636211) (xy 335.819115 -23.60376)
			(xy 335.868715 -23.578259) (xy 335.921499 -23.560252) (xy 335.976342 -23.550122) (xy 336.032076 -23.548085)
			(xy 336.087513 -23.554185) (xy 336.14147 -23.568291) (xy 336.192799 -23.590103) (xy 336.240405 -23.619157)
			(xy 336.283273 -23.654832) (xy 336.32049 -23.696369) (xy 336.351263 -23.742882) (xy 336.374935 -23.793379)
			(xy 336.391003 -23.846786) (xy 336.399123 -23.901962) (xy 336.399632 -23.929848) (xy 336.399123 -23.957734)
			(xy 336.391003 -24.01291) (xy 336.374935 -24.066317) (xy 336.351263 -24.116814) (xy 336.32049 -24.163327)
			(xy 336.283273 -24.204864) (xy 336.240405 -24.240539) (xy 336.192799 -24.269593) (xy 336.14147 -24.291405)
			(xy 336.087513 -24.305511) (xy 336.032076 -24.311611) (xy 335.976342 -24.309574) (xy 335.921499 -24.299444)
			(xy 335.868715 -24.281437) (xy 335.819115 -24.255936) (xy 335.773757 -24.223485) (xy 335.733608 -24.184776)
			(xy 335.699522 -24.140633) (xy 335.672226 -24.091998) (xy 335.652303 -24.039907) (xy 335.640177 -23.98547)
			(xy 335.636106 -23.929848) (xy 334.599275 -23.929848) (xy 334.568468 -23.949648) (xy 334.518895 -23.972288)
			(xy 334.466605 -23.987643) (xy 334.412661 -23.995401) (xy 334.385412 -23.995888) (xy 334.36074 -23.995493)
			(xy 334.311813 -23.989086) (xy 334.26412 -23.976429) (xy 334.24114 -23.96744) (xy 334.22687 -23.962096)
			(xy 334.196534 -23.959348) (xy 334.166739 -23.965677) (xy 334.14014 -23.98052) (xy 334.119107 -24.002552)
			(xy 334.111854 -24.015954) (xy 334.099585 -24.039296) (xy 334.069675 -24.082722) (xy 334.034067 -24.121613)
			(xy 333.993439 -24.155226) (xy 333.948566 -24.182919) (xy 333.900306 -24.204164) (xy 333.849578 -24.218556)
			(xy 333.797351 -24.225821) (xy 333.770986 -24.226266) (xy 333.743732 -24.225863) (xy 333.68978 -24.218104)
			(xy 333.637481 -24.202746) (xy 333.587901 -24.180102) (xy 333.542047 -24.150632) (xy 333.500854 -24.114936)
			(xy 333.46516 -24.073742) (xy 333.435692 -24.027887) (xy 333.413049 -23.978305) (xy 333.397693 -23.926006)
			(xy 333.389936 -23.872054) (xy 330.498583 -23.872054) (xy 330.505215 -23.875257) (xy 330.549638 -23.905006)
			(xy 330.589471 -23.940669) (xy 330.623932 -23.981546) (xy 330.652345 -24.026836) (xy 330.674153 -24.07565)
			(xy 330.688928 -24.127033) (xy 330.696382 -24.179976) (xy 330.696824 -24.206708) (xy 330.696338 -24.233959)
			(xy 330.688582 -24.287907) (xy 330.673227 -24.340202) (xy 330.650585 -24.389779) (xy 330.621119 -24.435629)
			(xy 330.585428 -24.47682) (xy 330.544237 -24.512511) (xy 330.498387 -24.541977) (xy 330.44881 -24.564619)
			(xy 330.396515 -24.579974) (xy 330.342567 -24.58773) (xy 330.288065 -24.58773) (xy 330.234117 -24.579974)
			(xy 330.181822 -24.564619) (xy 330.132245 -24.541977) (xy 330.086395 -24.512511) (xy 330.045204 -24.47682)
			(xy 330.009513 -24.435629) (xy 329.980047 -24.389779) (xy 329.957405 -24.340202) (xy 329.94205 -24.287907)
			(xy 329.934294 -24.233959) (xy 329.933808 -24.206708) (xy 329.933996 -24.189596) (xy 329.937051 -24.155509)
			(xy 329.939904 -24.138636) (xy 329.941963 -24.124201) (xy 329.938828 -24.095228) (xy 329.927645 -24.068317)
			(xy 329.909323 -24.045655) (xy 329.885352 -24.029083) (xy 329.857678 -24.019949) (xy 329.84313 -24.019002)
			(xy 329.816425 -24.017742) (xy 329.763732 -24.008714) (xy 329.712816 -23.992415) (xy 329.664676 -23.969165)
			(xy 329.620255 -23.939419) (xy 329.580423 -23.90376) (xy 329.545963 -23.862888) (xy 329.517549 -23.817603)
			(xy 329.495738 -23.768794) (xy 329.480958 -23.717416) (xy 329.473498 -23.664479) (xy 329.473052 -23.637748)
			(xy 328.772564 -23.637748) (xy 328.773028 -23.663148) (xy 328.772519 -23.691034) (xy 328.764399 -23.74621)
			(xy 328.748331 -23.799617) (xy 328.724659 -23.850114) (xy 328.693886 -23.896627) (xy 328.656669 -23.938164)
			(xy 328.613801 -23.973839) (xy 328.566195 -24.002893) (xy 328.514866 -24.024705) (xy 328.460909 -24.038811)
			(xy 328.405472 -24.044911) (xy 328.349738 -24.042874) (xy 328.294895 -24.032744) (xy 328.242111 -24.014737)
			(xy 328.192511 -23.989236) (xy 328.147153 -23.956785) (xy 328.107004 -23.918076) (xy 328.072918 -23.873933)
			(xy 328.045622 -23.825298) (xy 328.025699 -23.773207) (xy 328.013573 -23.71877) (xy 328.009502 -23.663148)
			(xy 321.57778 -23.663148) (xy 321.568679 -23.692367) (xy 321.543541 -23.744071) (xy 321.527678 -23.76805)
			(xy 321.520207 -23.779707) (xy 321.511198 -23.805875) (xy 321.509553 -23.833501) (xy 321.51539 -23.860553)
			(xy 321.528283 -23.885042) (xy 321.547281 -23.905166) (xy 321.570988 -23.919446) (xy 321.597659 -23.92683)
			(xy 321.611498 -23.927308) (xy 323.65569 -23.927308) (xy 324.176136 -24.447754) (xy 324.186552 -24.457508)
			(xy 324.211505 -24.471328) (xy 324.239307 -24.477704) (xy 324.267788 -24.476139) (xy 324.294724 -24.466754)
			(xy 324.318012 -24.450281) (xy 324.335832 -24.428009) (xy 324.346793 -24.401675) (xy 324.348856 -24.387556)
			(xy 324.352553 -24.360025) (xy 324.366886 -24.30636) (xy 324.388851 -24.25534) (xy 324.417982 -24.208045)
			(xy 324.453665 -24.165476) (xy 324.495144 -24.128531) (xy 324.541543 -24.097993) (xy 324.59188 -24.074506)
			(xy 324.645091 -24.058568) (xy 324.700051 -24.050516) (xy 324.727824 -24.04999) (xy 324.754393 -24.05045)
			(xy 324.807017 -24.057822) (xy 324.858111 -24.07242) (xy 324.906687 -24.093962) (xy 324.951806 -24.122032)
			(xy 324.992597 -24.156088) (xy 325.01078 -24.175466) (xy 325.020249 -24.185315) (xy 325.04326 -24.200025)
			(xy 325.06935 -24.208102) (xy 325.096647 -24.208967) (xy 325.123196 -24.202558) (xy 325.147092 -24.189335)
			(xy 325.166623 -24.170244) (xy 325.180389 -24.146656) (xy 325.184262 -24.133556) (xy 325.191918 -24.106861)
			(xy 325.213891 -24.055859) (xy 325.243026 -24.008581) (xy 325.278708 -23.966028) (xy 325.320183 -23.929098)
			(xy 325.366575 -23.898572) (xy 325.416902 -23.875095) (xy 325.470102 -23.859164) (xy 325.525049 -23.851114)
			(xy 325.552816 -23.8506) (xy 325.580066 -23.851087) (xy 325.634011 -23.858845) (xy 325.686303 -23.874201)
			(xy 325.735877 -23.896843) (xy 325.781724 -23.926309) (xy 325.822912 -23.962) (xy 325.858601 -24.003189)
			(xy 325.888065 -24.049037) (xy 325.910704 -24.098612) (xy 325.926058 -24.150905) (xy 325.933814 -24.20485)
			(xy 325.933814 -24.25935) (xy 325.926058 -24.313295) (xy 325.910704 -24.365588) (xy 325.888065 -24.415163)
			(xy 325.858601 -24.461011) (xy 325.822912 -24.5022) (xy 325.781724 -24.537891) (xy 325.735877 -24.567357)
			(xy 325.686303 -24.589999) (xy 325.634011 -24.605355) (xy 325.580066 -24.613113) (xy 325.552816 -24.613616)
			(xy 325.526246 -24.613159) (xy 325.473618 -24.605792) (xy 325.422521 -24.591198) (xy 325.373941 -24.569659)
			(xy 325.328817 -24.541592) (xy 325.288022 -24.507539) (xy 325.26986 -24.48814) (xy 325.260393 -24.4783)
			(xy 325.237389 -24.463605) (xy 325.211311 -24.455541) (xy 325.184029 -24.454685) (xy 325.157496 -24.461098)
			(xy 325.133617 -24.47432) (xy 325.114101 -24.493405) (xy 325.100348 -24.516983) (xy 325.096378 -24.53005)
			(xy 325.08851 -24.557432) (xy 325.065773 -24.60967) (xy 325.035522 -24.657946) (xy 324.998428 -24.701186)
			(xy 324.955317 -24.738431) (xy 324.907147 -24.76885) (xy 324.854989 -24.791768) (xy 324.800003 -24.806676)
			(xy 324.771766 -24.810466) (xy 324.757667 -24.812585) (xy 324.731371 -24.823568) (xy 324.709134 -24.84139)
			(xy 324.692685 -24.864661) (xy 324.683307 -24.891572) (xy 324.681729 -24.920026) (xy 324.688073 -24.947808)
			(xy 324.701847 -24.972757) (xy 324.711568 -24.983186) (xy 324.752208 -25.023826) (xy 328.014328 -25.023826)
			(xy 328.018399 -24.968204) (xy 328.030525 -24.913767) (xy 328.050448 -24.861676) (xy 328.077744 -24.813041)
			(xy 328.11183 -24.768898) (xy 328.151979 -24.730189) (xy 328.197337 -24.697738) (xy 328.246937 -24.672237)
			(xy 328.299721 -24.65423) (xy 328.354564 -24.6441) (xy 328.410298 -24.642063) (xy 328.465735 -24.648163)
			(xy 328.519692 -24.662269) (xy 328.571021 -24.684081) (xy 328.618627 -24.713135) (xy 328.661495 -24.74881)
			(xy 328.698712 -24.790347) (xy 328.729485 -24.83686) (xy 328.732353 -24.842978) (xy 332.588106 -24.842978)
			(xy 332.592177 -24.787356) (xy 332.604303 -24.732919) (xy 332.624226 -24.680828) (xy 332.651522 -24.632193)
			(xy 332.685608 -24.58805) (xy 332.725757 -24.549341) (xy 332.771115 -24.51689) (xy 332.820715 -24.491389)
			(xy 332.873499 -24.473382) (xy 332.928342 -24.463252) (xy 332.984076 -24.461215) (xy 333.039513 -24.467315)
			(xy 333.09347 -24.481421) (xy 333.144799 -24.503233) (xy 333.192405 -24.532287) (xy 333.235273 -24.567962)
			(xy 333.27249 -24.609499) (xy 333.303263 -24.656012) (xy 333.326935 -24.706509) (xy 333.343003 -24.759916)
			(xy 333.351123 -24.815092) (xy 333.351396 -24.830024) (xy 333.477106 -24.830024) (xy 333.481177 -24.774402)
			(xy 333.493303 -24.719965) (xy 333.513226 -24.667874) (xy 333.540522 -24.619239) (xy 333.574608 -24.575096)
			(xy 333.614757 -24.536387) (xy 333.660115 -24.503936) (xy 333.709715 -24.478435) (xy 333.762499 -24.460428)
			(xy 333.817342 -24.450298) (xy 333.873076 -24.448261) (xy 333.928513 -24.454361) (xy 333.98247 -24.468467)
			(xy 334.033799 -24.490279) (xy 334.081405 -24.519333) (xy 334.124273 -24.555008) (xy 334.16149 -24.596545)
			(xy 334.192263 -24.643058) (xy 334.215935 -24.693555) (xy 334.232003 -24.746962) (xy 334.240123 -24.802138)
			(xy 334.240632 -24.830024) (xy 334.240123 -24.85791) (xy 334.232003 -24.913086) (xy 334.21802 -24.959564)
			(xy 334.889854 -24.959564) (xy 334.893925 -24.903942) (xy 334.906051 -24.849505) (xy 334.925974 -24.797414)
			(xy 334.95327 -24.748779) (xy 334.987356 -24.704636) (xy 335.027505 -24.665927) (xy 335.072863 -24.633476)
			(xy 335.122463 -24.607975) (xy 335.175247 -24.589968) (xy 335.23009 -24.579838) (xy 335.285824 -24.577801)
			(xy 335.341261 -24.583901) (xy 335.395218 -24.598007) (xy 335.446547 -24.619819) (xy 335.494153 -24.648873)
			(xy 335.537021 -24.684548) (xy 335.574238 -24.726085) (xy 335.605011 -24.772598) (xy 335.628683 -24.823095)
			(xy 335.644751 -24.876502) (xy 335.652871 -24.931678) (xy 335.65338 -24.959564) (xy 335.652871 -24.98745)
			(xy 335.644751 -25.042626) (xy 335.628683 -25.096033) (xy 335.605011 -25.14653) (xy 335.574238 -25.193043)
			(xy 335.537021 -25.23458) (xy 335.504589 -25.26157) (xy 337.410296 -25.26157) (xy 337.414367 -25.205948)
			(xy 337.426493 -25.151511) (xy 337.446416 -25.09942) (xy 337.473712 -25.050785) (xy 337.507798 -25.006642)
			(xy 337.547947 -24.967933) (xy 337.593305 -24.935482) (xy 337.642905 -24.909981) (xy 337.695689 -24.891974)
			(xy 337.750532 -24.881844) (xy 337.806266 -24.879807) (xy 337.861703 -24.885907) (xy 337.91566 -24.900013)
			(xy 337.966989 -24.921825) (xy 338.014595 -24.950879) (xy 338.057463 -24.986554) (xy 338.09468 -25.028091)
			(xy 338.125453 -25.074604) (xy 338.149125 -25.125101) (xy 338.165193 -25.178508) (xy 338.173313 -25.233684)
			(xy 338.173822 -25.26157) (xy 338.173313 -25.289456) (xy 338.165193 -25.344632) (xy 338.149125 -25.398039)
			(xy 338.125453 -25.448536) (xy 338.09468 -25.495049) (xy 338.057463 -25.536586) (xy 338.014595 -25.572261)
			(xy 337.966989 -25.601315) (xy 337.91566 -25.623127) (xy 337.861703 -25.637233) (xy 337.806266 -25.643333)
			(xy 337.750532 -25.641296) (xy 337.695689 -25.631166) (xy 337.642905 -25.613159) (xy 337.593305 -25.587658)
			(xy 337.547947 -25.555207) (xy 337.507798 -25.516498) (xy 337.473712 -25.472355) (xy 337.446416 -25.42372)
			(xy 337.426493 -25.371629) (xy 337.414367 -25.317192) (xy 337.410296 -25.26157) (xy 335.504589 -25.26157)
			(xy 335.494153 -25.270255) (xy 335.446547 -25.299309) (xy 335.395218 -25.321121) (xy 335.341261 -25.335227)
			(xy 335.285824 -25.341327) (xy 335.23009 -25.33929) (xy 335.175247 -25.32916) (xy 335.122463 -25.311153)
			(xy 335.072863 -25.285652) (xy 335.027505 -25.253201) (xy 334.987356 -25.214492) (xy 334.95327 -25.170349)
			(xy 334.925974 -25.121714) (xy 334.906051 -25.069623) (xy 334.893925 -25.015186) (xy 334.889854 -24.959564)
			(xy 334.21802 -24.959564) (xy 334.215935 -24.966493) (xy 334.192263 -25.01699) (xy 334.16149 -25.063503)
			(xy 334.124273 -25.10504) (xy 334.081405 -25.140715) (xy 334.033799 -25.169769) (xy 333.98247 -25.191581)
			(xy 333.928513 -25.205687) (xy 333.873076 -25.211787) (xy 333.817342 -25.20975) (xy 333.762499 -25.19962)
			(xy 333.709715 -25.181613) (xy 333.660115 -25.156112) (xy 333.614757 -25.123661) (xy 333.574608 -25.084952)
			(xy 333.540522 -25.040809) (xy 333.513226 -24.992174) (xy 333.493303 -24.940083) (xy 333.481177 -24.885646)
			(xy 333.477106 -24.830024) (xy 333.351396 -24.830024) (xy 333.351632 -24.842978) (xy 333.351123 -24.870864)
			(xy 333.343003 -24.92604) (xy 333.326935 -24.979447) (xy 333.303263 -25.029944) (xy 333.27249 -25.076457)
			(xy 333.235273 -25.117994) (xy 333.192405 -25.153669) (xy 333.144799 -25.182723) (xy 333.09347 -25.204535)
			(xy 333.039513 -25.218641) (xy 332.984076 -25.224741) (xy 332.928342 -25.222704) (xy 332.873499 -25.212574)
			(xy 332.820715 -25.194567) (xy 332.771115 -25.169066) (xy 332.725757 -25.136615) (xy 332.685608 -25.097906)
			(xy 332.651522 -25.053763) (xy 332.624226 -25.005128) (xy 332.604303 -24.953037) (xy 332.592177 -24.8986)
			(xy 332.588106 -24.842978) (xy 328.732353 -24.842978) (xy 328.753157 -24.887357) (xy 328.769225 -24.940764)
			(xy 328.777345 -24.99594) (xy 328.777854 -25.023826) (xy 328.777345 -25.051712) (xy 328.769225 -25.106888)
			(xy 328.753157 -25.160295) (xy 328.729485 -25.210792) (xy 328.698712 -25.257305) (xy 328.661495 -25.298842)
			(xy 328.618627 -25.334517) (xy 328.571021 -25.363571) (xy 328.519692 -25.385383) (xy 328.465735 -25.399489)
			(xy 328.410298 -25.405589) (xy 328.354564 -25.403552) (xy 328.299721 -25.393422) (xy 328.246937 -25.375415)
			(xy 328.197337 -25.349914) (xy 328.151979 -25.317463) (xy 328.11183 -25.278754) (xy 328.077744 -25.234611)
			(xy 328.050448 -25.185976) (xy 328.030525 -25.133885) (xy 328.018399 -25.079448) (xy 328.014328 -25.023826)
			(xy 324.752208 -25.023826) (xy 326.63003 -26.901648) (xy 328.384408 -26.901648) (xy 328.384815 -26.875997)
			(xy 328.391702 -26.825158) (xy 328.405346 -26.775703) (xy 328.4255 -26.728524) (xy 328.451799 -26.684475)
			(xy 328.483768 -26.644351) (xy 328.50201 -26.626312) (xy 328.511586 -26.616514) (xy 328.525618 -26.592997)
			(xy 328.532897 -26.566597) (xy 328.532898 -26.539211) (xy 328.525622 -26.51281) (xy 328.511591 -26.489293)
			(xy 328.50201 -26.4795) (xy 328.483799 -26.461435) (xy 328.451855 -26.421301) (xy 328.42557 -26.377252)
			(xy 328.405418 -26.330082) (xy 328.391762 -26.280638) (xy 328.384848 -26.229811) (xy 328.384408 -26.204164)
			(xy 328.384894 -26.176913) (xy 328.39265 -26.122965) (xy 328.408005 -26.07067) (xy 328.430647 -26.021093)
			(xy 328.460113 -25.975243) (xy 328.495804 -25.934052) (xy 328.536995 -25.898361) (xy 328.582845 -25.868895)
			(xy 328.632422 -25.846253) (xy 328.684717 -25.830898) (xy 328.738665 -25.823142) (xy 328.793167 -25.823142)
			(xy 328.847115 -25.830898) (xy 328.89941 -25.846253) (xy 328.948987 -25.868895) (xy 328.994837 -25.898361)
			(xy 329.022752 -25.922549) (xy 341.919578 -25.922549) (xy 341.919578 -25.868051) (xy 341.927333 -25.814106)
			(xy 341.942686 -25.761815) (xy 341.965324 -25.71224) (xy 341.994787 -25.666392) (xy 342.030474 -25.625203)
			(xy 342.07166 -25.589511) (xy 342.117505 -25.560044) (xy 342.167077 -25.5374) (xy 342.219367 -25.522042)
			(xy 342.273311 -25.514281) (xy 342.30056 -25.513792) (xy 342.329931 -25.514308) (xy 342.387981 -25.523308)
			(xy 342.443964 -25.541101) (xy 342.496557 -25.567267) (xy 342.544517 -25.601187) (xy 342.56599 -25.621234)
			(xy 342.577062 -25.631232) (xy 342.603538 -25.644945) (xy 342.632849 -25.650414) (xy 342.662489 -25.647173)
			(xy 342.689925 -25.635497) (xy 342.712811 -25.616386) (xy 342.721438 -25.604216) (xy 342.736668 -25.582034)
			(xy 342.772336 -25.541748) (xy 342.813312 -25.506876) (xy 342.858782 -25.47811) (xy 342.907845 -25.456019)
			(xy 342.959525 -25.441044) (xy 343.012797 -25.433482) (xy 343.0397 -25.43302) (xy 343.066953 -25.43345)
			(xy 343.120905 -25.441207) (xy 343.173204 -25.456563) (xy 343.222784 -25.479206) (xy 343.268638 -25.508674)
			(xy 343.309831 -25.544369) (xy 343.345526 -25.585562) (xy 343.374994 -25.631416) (xy 343.397637 -25.680996)
			(xy 343.412993 -25.733295) (xy 343.42075 -25.787247) (xy 343.42075 -25.788366) (xy 346.613478 -25.788366)
			(xy 346.617549 -25.732744) (xy 346.629675 -25.678307) (xy 346.649598 -25.626216) (xy 346.676894 -25.577581)
			(xy 346.71098 -25.533438) (xy 346.751129 -25.494729) (xy 346.796487 -25.462278) (xy 346.846087 -25.436777)
			(xy 346.898871 -25.41877) (xy 346.953714 -25.40864) (xy 347.009448 -25.406603) (xy 347.064885 -25.412703)
			(xy 347.118842 -25.426809) (xy 347.170171 -25.448621) (xy 347.217777 -25.477675) (xy 347.260645 -25.51335)
			(xy 347.297862 -25.554887) (xy 347.328635 -25.6014) (xy 347.352307 -25.651897) (xy 347.368375 -25.705304)
			(xy 347.376495 -25.76048) (xy 347.377004 -25.788366) (xy 347.376495 -25.816252) (xy 347.368375 -25.871428)
			(xy 347.352307 -25.924835) (xy 347.328635 -25.975332) (xy 347.297862 -26.021845) (xy 347.260645 -26.063382)
			(xy 347.217777 -26.099057) (xy 347.170171 -26.128111) (xy 347.118842 -26.149923) (xy 347.064885 -26.164029)
			(xy 347.009448 -26.170129) (xy 346.953714 -26.168092) (xy 346.898871 -26.157962) (xy 346.846087 -26.139955)
			(xy 346.796487 -26.114454) (xy 346.751129 -26.082003) (xy 346.71098 -26.043294) (xy 346.676894 -25.999151)
			(xy 346.649598 -25.950516) (xy 346.629675 -25.898425) (xy 346.617549 -25.843988) (xy 346.613478 -25.788366)
			(xy 343.42075 -25.788366) (xy 343.42075 -25.841753) (xy 343.412993 -25.895705) (xy 343.397637 -25.948004)
			(xy 343.374994 -25.997584) (xy 343.345526 -26.043438) (xy 343.309831 -26.084631) (xy 343.268638 -26.120326)
			(xy 343.222784 -26.149794) (xy 343.173204 -26.172437) (xy 343.120905 -26.187793) (xy 343.066953 -26.19555)
			(xy 343.0397 -26.196036) (xy 343.010329 -26.195503) (xy 342.95228 -26.18651) (xy 342.896296 -26.168722)
			(xy 342.843702 -26.14256) (xy 342.795742 -26.108641) (xy 342.77427 -26.088594) (xy 342.763224 -26.078568)
			(xy 342.736738 -26.06487) (xy 342.707423 -26.059412) (xy 342.677782 -26.062659) (xy 342.650345 -26.074336)
			(xy 342.627454 -26.093444) (xy 342.618822 -26.105612) (xy 342.603627 -26.127819) (xy 342.567952 -26.168103)
			(xy 342.52697 -26.202972) (xy 342.481493 -26.231735) (xy 342.432425 -26.253821) (xy 342.380741 -26.268792)
			(xy 342.327465 -26.276349) (xy 342.30056 -26.276808) (xy 342.273311 -26.276319) (xy 342.219367 -26.268558)
			(xy 342.167077 -26.2532) (xy 342.117505 -26.230556) (xy 342.07166 -26.201089) (xy 342.030474 -26.165397)
			(xy 341.994787 -26.124208) (xy 341.965324 -26.07836) (xy 341.942686 -26.028785) (xy 341.927333 -25.976494)
			(xy 341.919578 -25.922549) (xy 329.022752 -25.922549) (xy 329.036028 -25.934052) (xy 329.071719 -25.975243)
			(xy 329.101185 -26.021093) (xy 329.123827 -26.07067) (xy 329.139182 -26.122965) (xy 329.146938 -26.176913)
			(xy 329.147424 -26.204164) (xy 329.147015 -26.229815) (xy 329.140127 -26.280653) (xy 329.126483 -26.330108)
			(xy 329.106329 -26.377286) (xy 329.080031 -26.421336) (xy 329.048063 -26.461461) (xy 329.029822 -26.4795)
			(xy 329.02024 -26.48929) (xy 329.006217 -26.512811) (xy 328.998945 -26.539212) (xy 328.998947 -26.566596)
			(xy 329.006221 -26.592996) (xy 329.020245 -26.616517) (xy 329.029822 -26.626312) (xy 329.048045 -26.644366)
			(xy 329.079987 -26.684503) (xy 329.106269 -26.728554) (xy 329.126418 -26.775727) (xy 329.140072 -26.825172)
			(xy 329.146985 -26.876) (xy 329.147424 -26.901648) (xy 329.146938 -26.928899) (xy 329.139182 -26.982847)
			(xy 329.123827 -27.035142) (xy 329.101185 -27.084719) (xy 329.071719 -27.130569) (xy 329.036028 -27.17176)
			(xy 328.994837 -27.207451) (xy 328.948987 -27.236917) (xy 328.89941 -27.259559) (xy 328.847115 -27.274914)
			(xy 328.793167 -27.28267) (xy 328.738665 -27.28267) (xy 328.684717 -27.274914) (xy 328.632422 -27.259559)
			(xy 328.582845 -27.236917) (xy 328.536995 -27.207451) (xy 328.495804 -27.17176) (xy 328.460113 -27.130569)
			(xy 328.430647 -27.084719) (xy 328.408005 -27.035142) (xy 328.39265 -26.982847) (xy 328.384894 -26.928899)
			(xy 328.384408 -26.901648) (xy 326.63003 -26.901648) (xy 327.804018 -28.075636) (xy 330.56195 -28.075636)
			(xy 331.775308 -26.862278) (xy 331.925676 -26.862278) (xy 331.939978 -26.861785) (xy 331.967456 -26.853837)
			(xy 331.991656 -26.838585) (xy 332.01068 -26.817225) (xy 332.023041 -26.791429) (xy 332.027768 -26.763217)
			(xy 332.024491 -26.734801) (xy 332.013468 -26.708406) (xy 332.004924 -26.696924) (xy 331.98895 -26.67648)
			(xy 331.962095 -26.63209) (xy 331.941509 -26.584467) (xy 331.927573 -26.534492) (xy 331.920543 -26.483089)
			(xy 331.920088 -26.457148) (xy 331.920574 -26.429897) (xy 331.92833 -26.375949) (xy 331.943685 -26.323654)
			(xy 331.966327 -26.274077) (xy 331.995793 -26.228227) (xy 332.031484 -26.187036) (xy 332.072675 -26.151345)
			(xy 332.118525 -26.121879) (xy 332.168102 -26.099237) (xy 332.220397 -26.083882) (xy 332.274345 -26.076126)
			(xy 332.328847 -26.076126) (xy 332.382795 -26.083882) (xy 332.43509 -26.099237) (xy 332.484667 -26.121879)
			(xy 332.530517 -26.151345) (xy 332.571708 -26.187036) (xy 332.607399 -26.228227) (xy 332.636865 -26.274077)
			(xy 332.659507 -26.323654) (xy 332.674862 -26.375949) (xy 332.682618 -26.429897) (xy 332.683104 -26.457148)
			(xy 332.682666 -26.483344) (xy 332.675487 -26.53524) (xy 332.66127 -26.585666) (xy 332.640283 -26.63367)
			(xy 332.612922 -26.678349) (xy 332.579702 -26.718861) (xy 332.541247 -26.754443) (xy 332.520036 -26.769822)
			(xy 332.498446 -26.785062) (xy 332.498446 -26.862278) (xy 332.566264 -26.862278) (xy 332.842362 -27.138376)
			(xy 332.842362 -27.534108) (xy 332.504288 -27.872182) (xy 335.636106 -27.872182) (xy 335.640177 -27.81656)
			(xy 335.652303 -27.762123) (xy 335.672226 -27.710032) (xy 335.699522 -27.661397) (xy 335.733608 -27.617254)
			(xy 335.773757 -27.578545) (xy 335.819115 -27.546094) (xy 335.868715 -27.520593) (xy 335.921499 -27.502586)
			(xy 335.976342 -27.492456) (xy 336.032076 -27.490419) (xy 336.087513 -27.496519) (xy 336.14147 -27.510625)
			(xy 336.192799 -27.532437) (xy 336.240405 -27.561491) (xy 336.283273 -27.597166) (xy 336.32049 -27.638703)
			(xy 336.351263 -27.685216) (xy 336.374935 -27.735713) (xy 336.391003 -27.78912) (xy 336.399123 -27.844296)
			(xy 336.399632 -27.872182) (xy 336.399123 -27.900068) (xy 336.391003 -27.955244) (xy 336.374935 -28.008651)
			(xy 336.351263 -28.059148) (xy 336.32049 -28.105661) (xy 336.283273 -28.147198) (xy 336.240405 -28.182873)
			(xy 336.192799 -28.211927) (xy 336.14147 -28.233739) (xy 336.087513 -28.247845) (xy 336.032076 -28.253945)
			(xy 335.976342 -28.251908) (xy 335.921499 -28.241778) (xy 335.868715 -28.223771) (xy 335.819115 -28.19827)
			(xy 335.773757 -28.165819) (xy 335.733608 -28.12711) (xy 335.699522 -28.082967) (xy 335.672226 -28.034332)
			(xy 335.652303 -27.982241) (xy 335.640177 -27.927804) (xy 335.636106 -27.872182) (xy 332.504288 -27.872182)
			(xy 330.959206 -29.417264) (xy 330.995274 -29.453586) (xy 331.016559 -29.475263) (xy 331.052669 -29.524115)
			(xy 331.080579 -29.578073) (xy 331.099586 -29.635772) (xy 331.109209 -29.695754) (xy 331.109828 -29.726128)
			(xy 331.10934 -29.753378) (xy 331.101581 -29.807324) (xy 331.086223 -29.859617) (xy 331.063581 -29.909192)
			(xy 331.034114 -29.95504) (xy 330.998423 -29.996229) (xy 330.957234 -30.031919) (xy 330.911385 -30.061385)
			(xy 330.861809 -30.084026) (xy 330.852335 -30.086808) (xy 331.657958 -30.086808) (xy 331.662029 -30.031186)
			(xy 331.674155 -29.976749) (xy 331.694078 -29.924658) (xy 331.721374 -29.876023) (xy 331.75546 -29.83188)
			(xy 331.795609 -29.793171) (xy 331.840967 -29.76072) (xy 331.890567 -29.735219) (xy 331.943351 -29.717212)
			(xy 331.998194 -29.707082) (xy 332.053928 -29.705045) (xy 332.109365 -29.711145) (xy 332.163322 -29.725251)
			(xy 332.214651 -29.747063) (xy 332.262257 -29.776117) (xy 332.305125 -29.811792) (xy 332.342342 -29.853329)
			(xy 332.373115 -29.899842) (xy 332.396787 -29.950339) (xy 332.412855 -30.003746) (xy 332.420975 -30.058922)
			(xy 332.421484 -30.086808) (xy 332.420975 -30.114694) (xy 332.412855 -30.16987) (xy 332.396787 -30.223277)
			(xy 332.373115 -30.273774) (xy 332.342342 -30.320287) (xy 332.305125 -30.361824) (xy 332.262257 -30.397499)
			(xy 332.214651 -30.426553) (xy 332.163322 -30.448365) (xy 332.109365 -30.462471) (xy 332.053928 -30.468571)
			(xy 331.998194 -30.466534) (xy 331.943351 -30.456404) (xy 331.890567 -30.438397) (xy 331.840967 -30.412896)
			(xy 331.795609 -30.380445) (xy 331.75546 -30.341736) (xy 331.721374 -30.297593) (xy 331.694078 -30.248958)
			(xy 331.674155 -30.196867) (xy 331.662029 -30.14243) (xy 331.657958 -30.086808) (xy 330.852335 -30.086808)
			(xy 330.809516 -30.099382) (xy 330.75557 -30.107141) (xy 330.72832 -30.107636) (xy 330.697944 -30.107049)
			(xy 330.637959 -30.097422) (xy 330.580259 -30.078409) (xy 330.526302 -30.05049) (xy 330.477453 -30.014372)
			(xy 330.455778 -29.993082) (xy 330.419456 -29.957014) (xy 329.95489 -30.42158) (xy 329.95489 -31.656782)
			(xy 330.570838 -31.656782) (xy 330.574909 -31.60116) (xy 330.587035 -31.546723) (xy 330.606958 -31.494632)
			(xy 330.634254 -31.445997) (xy 330.66834 -31.401854) (xy 330.708489 -31.363145) (xy 330.753847 -31.330694)
			(xy 330.803447 -31.305193) (xy 330.856231 -31.287186) (xy 330.911074 -31.277056) (xy 330.966808 -31.275019)
			(xy 331.022245 -31.281119) (xy 331.076202 -31.295225) (xy 331.127531 -31.317037) (xy 331.175137 -31.346091)
			(xy 331.218005 -31.381766) (xy 331.255222 -31.423303) (xy 331.285995 -31.469816) (xy 331.309667 -31.520313)
			(xy 331.325735 -31.57372) (xy 331.333855 -31.628896) (xy 331.334364 -31.656782) (xy 331.333855 -31.684668)
			(xy 331.325735 -31.739844) (xy 331.309667 -31.793251) (xy 331.285995 -31.843748) (xy 331.255222 -31.890261)
			(xy 331.218005 -31.931798) (xy 331.175137 -31.967473) (xy 331.127531 -31.996527) (xy 331.076202 -32.018339)
			(xy 331.022245 -32.032445) (xy 330.966808 -32.038545) (xy 330.911074 -32.036508) (xy 330.856231 -32.026378)
			(xy 330.803447 -32.008371) (xy 330.753847 -31.98287) (xy 330.708489 -31.950419) (xy 330.66834 -31.91171)
			(xy 330.634254 -31.867567) (xy 330.606958 -31.818932) (xy 330.587035 -31.766841) (xy 330.574909 -31.712404)
			(xy 330.570838 -31.656782) (xy 329.95489 -31.656782) (xy 329.95489 -32.04845) (xy 339.795102 -32.04845)
			(xy 339.799173 -31.992828) (xy 339.811299 -31.938391) (xy 339.831222 -31.8863) (xy 339.858518 -31.837665)
			(xy 339.892604 -31.793522) (xy 339.932753 -31.754813) (xy 339.978111 -31.722362) (xy 340.027711 -31.696861)
			(xy 340.080495 -31.678854) (xy 340.135338 -31.668724) (xy 340.191072 -31.666687) (xy 340.246509 -31.672787)
			(xy 340.300466 -31.686893) (xy 340.351795 -31.708705) (xy 340.399401 -31.737759) (xy 340.442269 -31.773434)
			(xy 340.479486 -31.814971) (xy 340.510259 -31.861484) (xy 340.533931 -31.911981) (xy 340.549999 -31.965388)
			(xy 340.558119 -32.020564) (xy 340.558628 -32.04845) (xy 340.558119 -32.076336) (xy 340.549999 -32.131512)
			(xy 340.533931 -32.184919) (xy 340.510259 -32.235416) (xy 340.479486 -32.281929) (xy 340.442269 -32.323466)
			(xy 340.399401 -32.359141) (xy 340.351795 -32.388195) (xy 340.300466 -32.410007) (xy 340.246509 -32.424113)
			(xy 340.191072 -32.430213) (xy 340.135338 -32.428176) (xy 340.080495 -32.418046) (xy 340.027711 -32.400039)
			(xy 339.978111 -32.374538) (xy 339.932753 -32.342087) (xy 339.892604 -32.303378) (xy 339.858518 -32.259235)
			(xy 339.831222 -32.2106) (xy 339.811299 -32.158509) (xy 339.799173 -32.104072) (xy 339.795102 -32.04845)
			(xy 329.95489 -32.04845) (xy 329.95489 -32.606742) (xy 337.507324 -32.606742) (xy 337.511395 -32.55112)
			(xy 337.523521 -32.496683) (xy 337.543444 -32.444592) (xy 337.57074 -32.395957) (xy 337.604826 -32.351814)
			(xy 337.644975 -32.313105) (xy 337.690333 -32.280654) (xy 337.739933 -32.255153) (xy 337.792717 -32.237146)
			(xy 337.84756 -32.227016) (xy 337.903294 -32.224979) (xy 337.958731 -32.231079) (xy 338.012688 -32.245185)
			(xy 338.064017 -32.266997) (xy 338.111623 -32.296051) (xy 338.154491 -32.331726) (xy 338.191708 -32.373263)
			(xy 338.222481 -32.419776) (xy 338.246153 -32.470273) (xy 338.262221 -32.52368) (xy 338.270341 -32.578856)
			(xy 338.27085 -32.606742) (xy 338.270341 -32.634628) (xy 338.262221 -32.689804) (xy 338.246153 -32.743211)
			(xy 338.222481 -32.793708) (xy 338.191708 -32.840221) (xy 338.154491 -32.881758) (xy 338.111623 -32.917433)
			(xy 338.064017 -32.946487) (xy 338.012688 -32.968299) (xy 337.958731 -32.982405) (xy 337.903294 -32.988505)
			(xy 337.84756 -32.986468) (xy 337.792717 -32.976338) (xy 337.739933 -32.958331) (xy 337.690333 -32.93283)
			(xy 337.644975 -32.900379) (xy 337.604826 -32.86167) (xy 337.57074 -32.817527) (xy 337.543444 -32.768892)
			(xy 337.523521 -32.716801) (xy 337.511395 -32.662364) (xy 337.507324 -32.606742) (xy 329.95489 -32.606742)
			(xy 329.95489 -32.784288) (xy 330.357226 -33.186624) (xy 333.667606 -33.186624) (xy 333.671677 -33.131002)
			(xy 333.683803 -33.076565) (xy 333.703726 -33.024474) (xy 333.731022 -32.975839) (xy 333.765108 -32.931696)
			(xy 333.805257 -32.892987) (xy 333.850615 -32.860536) (xy 333.900215 -32.835035) (xy 333.952999 -32.817028)
			(xy 334.007842 -32.806898) (xy 334.063576 -32.804861) (xy 334.119013 -32.810961) (xy 334.17297 -32.825067)
			(xy 334.224299 -32.846879) (xy 334.271905 -32.875933) (xy 334.314773 -32.911608) (xy 334.35199 -32.953145)
			(xy 334.382763 -32.999658) (xy 334.406435 -33.050155) (xy 334.422503 -33.103562) (xy 334.430623 -33.158738)
			(xy 334.431132 -33.186624) (xy 334.430623 -33.21451) (xy 334.422503 -33.269686) (xy 334.406435 -33.323093)
			(xy 334.382763 -33.37359) (xy 334.353033 -33.418526) (xy 344.098624 -33.418526) (xy 344.102695 -33.362904)
			(xy 344.114821 -33.308467) (xy 344.134744 -33.256376) (xy 344.16204 -33.207741) (xy 344.196126 -33.163598)
			(xy 344.236275 -33.124889) (xy 344.281633 -33.092438) (xy 344.331233 -33.066937) (xy 344.384017 -33.04893)
			(xy 344.43886 -33.0388) (xy 344.494594 -33.036763) (xy 344.550031 -33.042863) (xy 344.603988 -33.056969)
			(xy 344.655317 -33.078781) (xy 344.702923 -33.107835) (xy 344.745791 -33.14351) (xy 344.783008 -33.185047)
			(xy 344.813781 -33.23156) (xy 344.837453 -33.282057) (xy 344.853521 -33.335464) (xy 344.861641 -33.39064)
			(xy 344.86215 -33.418526) (xy 344.861641 -33.446412) (xy 344.853521 -33.501588) (xy 344.837453 -33.554995)
			(xy 344.813781 -33.605492) (xy 344.783008 -33.652005) (xy 344.745791 -33.693542) (xy 344.702923 -33.729217)
			(xy 344.655317 -33.758271) (xy 344.603988 -33.780083) (xy 344.550031 -33.794189) (xy 344.494594 -33.800289)
			(xy 344.43886 -33.798252) (xy 344.384017 -33.788122) (xy 344.331233 -33.770115) (xy 344.281633 -33.744614)
			(xy 344.236275 -33.712163) (xy 344.196126 -33.673454) (xy 344.16204 -33.629311) (xy 344.134744 -33.580676)
			(xy 344.114821 -33.528585) (xy 344.102695 -33.474148) (xy 344.098624 -33.418526) (xy 334.353033 -33.418526)
			(xy 334.35199 -33.420103) (xy 334.314773 -33.46164) (xy 334.271905 -33.497315) (xy 334.224299 -33.526369)
			(xy 334.17297 -33.548181) (xy 334.119013 -33.562287) (xy 334.063576 -33.568387) (xy 334.007842 -33.56635)
			(xy 333.952999 -33.55622) (xy 333.900215 -33.538213) (xy 333.850615 -33.512712) (xy 333.805257 -33.480261)
			(xy 333.765108 -33.441552) (xy 333.731022 -33.397409) (xy 333.703726 -33.348774) (xy 333.683803 -33.296683)
			(xy 333.671677 -33.242246) (xy 333.667606 -33.186624) (xy 330.357226 -33.186624) (xy 331.552296 -34.381694)
			(xy 333.607662 -34.381694) (xy 333.611733 -34.326072) (xy 333.623859 -34.271635) (xy 333.643782 -34.219544)
			(xy 333.671078 -34.170909) (xy 333.705164 -34.126766) (xy 333.745313 -34.088057) (xy 333.790671 -34.055606)
			(xy 333.840271 -34.030105) (xy 333.893055 -34.012098) (xy 333.947898 -34.001968) (xy 334.003632 -33.999931)
			(xy 334.059069 -34.006031) (xy 334.106665 -34.018474) (xy 338.07222 -34.018474) (xy 338.076291 -33.962852)
			(xy 338.088417 -33.908415) (xy 338.10834 -33.856324) (xy 338.135636 -33.807689) (xy 338.169722 -33.763546)
			(xy 338.209871 -33.724837) (xy 338.255229 -33.692386) (xy 338.304829 -33.666885) (xy 338.357613 -33.648878)
			(xy 338.412456 -33.638748) (xy 338.46819 -33.636711) (xy 338.523627 -33.642811) (xy 338.577584 -33.656917)
			(xy 338.628913 -33.678729) (xy 338.676519 -33.707783) (xy 338.719387 -33.743458) (xy 338.756604 -33.784995)
			(xy 338.787377 -33.831508) (xy 338.811049 -33.882005) (xy 338.827117 -33.935412) (xy 338.835237 -33.990588)
			(xy 338.835746 -34.018474) (xy 338.835237 -34.04636) (xy 338.827117 -34.101536) (xy 338.811049 -34.154943)
			(xy 338.787377 -34.20544) (xy 338.756604 -34.251953) (xy 338.719387 -34.29349) (xy 338.676519 -34.329165)
			(xy 338.628913 -34.358219) (xy 338.577584 -34.380031) (xy 338.523627 -34.394137) (xy 338.46819 -34.400237)
			(xy 338.412456 -34.3982) (xy 338.357613 -34.38807) (xy 338.304829 -34.370063) (xy 338.255229 -34.344562)
			(xy 338.209871 -34.312111) (xy 338.169722 -34.273402) (xy 338.135636 -34.229259) (xy 338.10834 -34.180624)
			(xy 338.088417 -34.128533) (xy 338.076291 -34.074096) (xy 338.07222 -34.018474) (xy 334.106665 -34.018474)
			(xy 334.113026 -34.020137) (xy 334.164355 -34.041949) (xy 334.211961 -34.071003) (xy 334.254829 -34.106678)
			(xy 334.292046 -34.148215) (xy 334.322819 -34.194728) (xy 334.346491 -34.245225) (xy 334.362559 -34.298632)
			(xy 334.370679 -34.353808) (xy 334.371188 -34.381694) (xy 334.370679 -34.40958) (xy 334.362559 -34.464756)
			(xy 334.346491 -34.518163) (xy 334.322819 -34.56866) (xy 334.311911 -34.585148) (xy 342.167462 -34.585148)
			(xy 342.171533 -34.529526) (xy 342.183659 -34.475089) (xy 342.203582 -34.422998) (xy 342.230878 -34.374363)
			(xy 342.264964 -34.33022) (xy 342.305113 -34.291511) (xy 342.350471 -34.25906) (xy 342.400071 -34.233559)
			(xy 342.452855 -34.215552) (xy 342.507698 -34.205422) (xy 342.563432 -34.203385) (xy 342.618869 -34.209485)
			(xy 342.672826 -34.223591) (xy 342.724155 -34.245403) (xy 342.771761 -34.274457) (xy 342.814629 -34.310132)
			(xy 342.851846 -34.351669) (xy 342.882619 -34.398182) (xy 342.906291 -34.448679) (xy 342.922359 -34.502086)
			(xy 342.930479 -34.557262) (xy 342.930988 -34.585148) (xy 342.930479 -34.613034) (xy 342.922359 -34.66821)
			(xy 342.906291 -34.721617) (xy 342.882619 -34.772114) (xy 342.851846 -34.818627) (xy 342.814629 -34.860164)
			(xy 342.771761 -34.895839) (xy 342.724155 -34.924893) (xy 342.672826 -34.946705) (xy 342.618869 -34.960811)
			(xy 342.563432 -34.966911) (xy 342.507698 -34.964874) (xy 342.452855 -34.954744) (xy 342.400071 -34.936737)
			(xy 342.350471 -34.911236) (xy 342.305113 -34.878785) (xy 342.264964 -34.840076) (xy 342.230878 -34.795933)
			(xy 342.203582 -34.747298) (xy 342.183659 -34.695207) (xy 342.171533 -34.64077) (xy 342.167462 -34.585148)
			(xy 334.311911 -34.585148) (xy 334.292046 -34.615173) (xy 334.254829 -34.65671) (xy 334.211961 -34.692385)
			(xy 334.164355 -34.721439) (xy 334.113026 -34.743251) (xy 334.059069 -34.757357) (xy 334.003632 -34.763457)
			(xy 333.947898 -34.76142) (xy 333.893055 -34.75129) (xy 333.840271 -34.733283) (xy 333.790671 -34.707782)
			(xy 333.745313 -34.675331) (xy 333.705164 -34.636622) (xy 333.671078 -34.592479) (xy 333.643782 -34.543844)
			(xy 333.623859 -34.491753) (xy 333.611733 -34.437316) (xy 333.607662 -34.381694) (xy 331.552296 -34.381694)
			(xy 333.049118 -35.878516) (xy 333.049118 -37.141658) (xy 335.912216 -37.141658) (xy 335.916192 -37.087332)
			(xy 335.928035 -37.034163) (xy 335.947494 -36.983286) (xy 335.974154 -36.935784) (xy 336.007445 -36.89267)
			(xy 336.046659 -36.854863) (xy 336.090961 -36.823168) (xy 336.139404 -36.798262) (xy 336.190958 -36.780674)
			(xy 336.244524 -36.77078) (xy 336.298959 -36.76879) (xy 336.353104 -36.774748) (xy 336.405804 -36.788526)
			(xy 336.455937 -36.80983) (xy 336.502433 -36.838206) (xy 336.544303 -36.87305) (xy 336.580652 -36.913619)
			(xy 336.610708 -36.959048) (xy 336.633829 -37.008369) (xy 336.649522 -37.060531) (xy 336.657453 -37.114422)
			(xy 336.65795 -37.141658) (xy 336.657453 -37.168894) (xy 336.649522 -37.222785) (xy 336.633829 -37.274947)
			(xy 336.610708 -37.324268) (xy 336.580652 -37.369697) (xy 336.544303 -37.410266) (xy 336.502433 -37.44511)
			(xy 336.455937 -37.473486) (xy 336.405804 -37.49479) (xy 336.353104 -37.508568) (xy 336.298959 -37.514526)
			(xy 336.244524 -37.512536) (xy 336.190958 -37.502642) (xy 336.139404 -37.485054) (xy 336.090961 -37.460148)
			(xy 336.046659 -37.428453) (xy 336.007445 -37.390646) (xy 335.974154 -37.347532) (xy 335.947494 -37.30003)
			(xy 335.928035 -37.249153) (xy 335.916192 -37.195984) (xy 335.912216 -37.141658) (xy 333.049118 -37.141658)
			(xy 333.049118 -39.434198) (xy 335.042556 -39.434198) (xy 335.04803 -39.380312) (xy 335.061601 -39.327876)
			(xy 335.082956 -39.2781) (xy 335.111602 -39.232132) (xy 335.146879 -39.191031) (xy 335.187972 -39.155746)
			(xy 335.233934 -39.12709) (xy 335.283706 -39.105725) (xy 335.336139 -39.092143) (xy 335.390024 -39.086657)
			(xy 335.444119 -39.089395) (xy 335.497175 -39.100291) (xy 335.547969 -39.119097) (xy 335.59533 -39.145377)
			(xy 335.638165 -39.178525) (xy 335.675487 -39.217778) (xy 335.706435 -39.26223) (xy 335.730294 -39.310855)
			(xy 335.746516 -39.362532) (xy 335.754725 -39.41607) (xy 335.755234 -39.443152) (xy 335.754943 -39.463659)
			(xy 335.750235 -39.504401) (xy 335.745836 -39.524432) (xy 335.742981 -39.538986) (xy 335.744906 -39.56857)
			(xy 335.75523 -39.596361) (xy 335.773086 -39.620028) (xy 335.796977 -39.637584) (xy 335.824896 -39.647556)
			(xy 335.854502 -39.649107) (xy 335.869026 -39.646098) (xy 335.889847 -39.641343) (xy 335.932253 -39.636253)
			(xy 335.953608 -39.635938) (xy 335.980687 -39.636406) (xy 336.034219 -39.644608) (xy 336.085893 -39.660821)
			(xy 336.134515 -39.684672) (xy 336.178966 -39.715611) (xy 336.218219 -39.752923) (xy 336.251369 -39.79575)
			(xy 336.277652 -39.843102) (xy 336.296462 -39.893888) (xy 336.307365 -39.946936) (xy 336.31011 -40.001024)
			(xy 336.304632 -40.054904) (xy 336.29106 -40.107333) (xy 336.269704 -40.157102) (xy 336.241059 -40.203064)
			(xy 336.205785 -40.244158) (xy 336.164694 -40.279437) (xy 336.118736 -40.308087) (xy 336.068969 -40.329447)
			(xy 336.016541 -40.343026) (xy 335.962662 -40.348509) (xy 335.908574 -40.34577) (xy 335.855524 -40.334873)
			(xy 335.804736 -40.316068) (xy 335.757381 -40.28979) (xy 335.714552 -40.256644) (xy 335.677235 -40.217395)
			(xy 335.646292 -40.172948) (xy 335.622436 -40.124328) (xy 335.606217 -40.072656) (xy 335.598009 -40.019125)
			(xy 335.5975 -39.992046) (xy 335.597792 -39.971539) (xy 335.6025 -39.930797) (xy 335.606898 -39.910766)
			(xy 335.609836 -39.896223) (xy 335.60791 -39.866623) (xy 335.597578 -39.838817) (xy 335.579708 -39.815142)
			(xy 335.555799 -39.797584) (xy 335.527861 -39.787618) (xy 335.498238 -39.78608) (xy 335.483708 -39.7891)
			(xy 335.462886 -39.793849) (xy 335.420481 -39.798943) (xy 335.399126 -39.79926) (xy 335.372044 -39.79883)
			(xy 335.318505 -39.790632) (xy 335.266824 -39.774422) (xy 335.218193 -39.750572) (xy 335.173735 -39.719634)
			(xy 335.134475 -39.68232) (xy 335.101317 -39.639492) (xy 335.075028 -39.592136) (xy 335.056212 -39.541346)
			(xy 335.045304 -39.488292) (xy 335.042556 -39.434198) (xy 333.049118 -39.434198) (xy 333.049118 -39.936674)
			(xy 333.049626 -39.94023) (xy 333.051412 -39.953109) (xy 333.053316 -39.979044) (xy 333.053436 -39.992046)
			(xy 333.053308 -40.005048) (xy 333.052306 -40.018695) (xy 333.969604 -40.018695) (xy 333.969604 -39.965397)
			(xy 333.977547 -39.912693) (xy 333.993257 -39.861763) (xy 334.016383 -39.813742) (xy 334.046407 -39.769705)
			(xy 334.082659 -39.730634) (xy 334.12433 -39.697403) (xy 334.170488 -39.670754) (xy 334.220102 -39.651282)
			(xy 334.272064 -39.639422) (xy 334.325214 -39.635439) (xy 334.378364 -39.639422) (xy 334.430326 -39.651282)
			(xy 334.47994 -39.670754) (xy 334.526098 -39.697403) (xy 334.567769 -39.730634) (xy 334.604021 -39.769705)
			(xy 334.634045 -39.813742) (xy 334.657171 -39.861763) (xy 334.672881 -39.912693) (xy 334.680824 -39.965397)
			(xy 334.681322 -39.992046) (xy 334.680824 -40.018695) (xy 334.672881 -40.071399) (xy 334.657171 -40.122329)
			(xy 334.634045 -40.17035) (xy 334.604021 -40.214387) (xy 334.567769 -40.253458) (xy 334.526098 -40.286689)
			(xy 334.47994 -40.313338) (xy 334.430326 -40.33281) (xy 334.378364 -40.34467) (xy 334.325214 -40.348654)
			(xy 334.272064 -40.34467) (xy 334.220102 -40.33281) (xy 334.170488 -40.313338) (xy 334.12433 -40.286689)
			(xy 334.082659 -40.253458) (xy 334.046407 -40.214387) (xy 334.016383 -40.17035) (xy 333.993257 -40.122329)
			(xy 333.977547 -40.071399) (xy 333.969604 -40.018695) (xy 333.052306 -40.018695) (xy 333.051403 -40.030982)
			(xy 333.049626 -40.043862) (xy 333.049118 -40.047418) (xy 333.049118 -40.488595) (xy 333.155788 -40.488595)
			(xy 333.155788 -40.435297) (xy 333.163731 -40.382593) (xy 333.179441 -40.331663) (xy 333.202567 -40.283642)
			(xy 333.232591 -40.239605) (xy 333.268843 -40.200534) (xy 333.310514 -40.167303) (xy 333.356672 -40.140654)
			(xy 333.406286 -40.121182) (xy 333.458248 -40.109322) (xy 333.511398 -40.105339) (xy 333.564548 -40.109322)
			(xy 333.61651 -40.121182) (xy 333.666124 -40.140654) (xy 333.712282 -40.167303) (xy 333.753953 -40.200534)
			(xy 333.790205 -40.239605) (xy 333.820229 -40.283642) (xy 333.843355 -40.331663) (xy 333.859065 -40.382593)
			(xy 333.867008 -40.435297) (xy 333.867506 -40.461946) (xy 333.867008 -40.488595) (xy 334.782658 -40.488595)
			(xy 334.782658 -40.435297) (xy 334.790601 -40.382593) (xy 334.806311 -40.331663) (xy 334.829437 -40.283642)
			(xy 334.859461 -40.239605) (xy 334.895713 -40.200534) (xy 334.937384 -40.167303) (xy 334.983542 -40.140654)
			(xy 335.033156 -40.121182) (xy 335.085118 -40.109322) (xy 335.138268 -40.105339) (xy 335.191418 -40.109322)
			(xy 335.24338 -40.121182) (xy 335.292994 -40.140654) (xy 335.339152 -40.167303) (xy 335.380823 -40.200534)
			(xy 335.417075 -40.239605) (xy 335.447099 -40.283642) (xy 335.470225 -40.331663) (xy 335.485935 -40.382593)
			(xy 335.493878 -40.435297) (xy 335.494376 -40.461946) (xy 335.493878 -40.488595) (xy 335.485935 -40.541299)
			(xy 335.470225 -40.592229) (xy 335.447099 -40.64025) (xy 335.417075 -40.684287) (xy 335.380823 -40.723358)
			(xy 335.339152 -40.756589) (xy 335.292994 -40.783238) (xy 335.24338 -40.80271) (xy 335.191418 -40.81457)
			(xy 335.138268 -40.818554) (xy 335.085118 -40.81457) (xy 335.033156 -40.80271) (xy 334.983542 -40.783238)
			(xy 334.937384 -40.756589) (xy 334.895713 -40.723358) (xy 334.859461 -40.684287) (xy 334.829437 -40.64025)
			(xy 334.806311 -40.592229) (xy 334.790601 -40.541299) (xy 334.782658 -40.488595) (xy 333.867008 -40.488595)
			(xy 333.859065 -40.541299) (xy 333.843355 -40.592229) (xy 333.820229 -40.64025) (xy 333.790205 -40.684287)
			(xy 333.753953 -40.723358) (xy 333.712282 -40.756589) (xy 333.666124 -40.783238) (xy 333.61651 -40.80271)
			(xy 333.564548 -40.81457) (xy 333.511398 -40.818554) (xy 333.458248 -40.81457) (xy 333.406286 -40.80271)
			(xy 333.356672 -40.783238) (xy 333.310514 -40.756589) (xy 333.268843 -40.723358) (xy 333.232591 -40.684287)
			(xy 333.202567 -40.64025) (xy 333.179441 -40.592229) (xy 333.163731 -40.541299) (xy 333.155788 -40.488595)
			(xy 333.049118 -40.488595) (xy 333.049118 -40.876474) (xy 333.049626 -40.88003) (xy 333.051412 -40.892909)
			(xy 333.053316 -40.918844) (xy 333.053436 -40.931846) (xy 333.053308 -40.944848) (xy 333.052306 -40.958495)
			(xy 333.969858 -40.958495) (xy 333.969858 -40.905197) (xy 333.977801 -40.852493) (xy 333.993511 -40.801563)
			(xy 334.016637 -40.753542) (xy 334.046661 -40.709505) (xy 334.082913 -40.670434) (xy 334.124584 -40.637203)
			(xy 334.170742 -40.610554) (xy 334.220356 -40.591082) (xy 334.272318 -40.579222) (xy 334.325468 -40.575239)
			(xy 334.378618 -40.579222) (xy 334.43058 -40.591082) (xy 334.480194 -40.610554) (xy 334.526352 -40.637203)
			(xy 334.568023 -40.670434) (xy 334.604275 -40.709505) (xy 334.634299 -40.753542) (xy 334.657425 -40.801563)
			(xy 334.673135 -40.852493) (xy 334.681078 -40.905197) (xy 334.681576 -40.931846) (xy 334.681078 -40.958495)
			(xy 335.597998 -40.958495) (xy 335.597998 -40.905197) (xy 335.605941 -40.852493) (xy 335.621651 -40.801563)
			(xy 335.644777 -40.753542) (xy 335.674801 -40.709505) (xy 335.711053 -40.670434) (xy 335.752724 -40.637203)
			(xy 335.798882 -40.610554) (xy 335.848496 -40.591082) (xy 335.900458 -40.579222) (xy 335.953608 -40.575239)
			(xy 336.006758 -40.579222) (xy 336.05872 -40.591082) (xy 336.108334 -40.610554) (xy 336.154492 -40.637203)
			(xy 336.196163 -40.670434) (xy 336.232415 -40.709505) (xy 336.262439 -40.753542) (xy 336.285565 -40.801563)
			(xy 336.301275 -40.852493) (xy 336.309218 -40.905197) (xy 336.309716 -40.931846) (xy 336.309218 -40.958495)
			(xy 336.301275 -41.011199) (xy 336.285565 -41.062129) (xy 336.262439 -41.11015) (xy 336.232415 -41.154187)
			(xy 336.196163 -41.193258) (xy 336.154492 -41.226489) (xy 336.108334 -41.253138) (xy 336.05872 -41.27261)
			(xy 336.006758 -41.28447) (xy 335.953608 -41.288454) (xy 335.900458 -41.28447) (xy 335.848496 -41.27261)
			(xy 335.798882 -41.253138) (xy 335.752724 -41.226489) (xy 335.711053 -41.193258) (xy 335.674801 -41.154187)
			(xy 335.644777 -41.11015) (xy 335.621651 -41.062129) (xy 335.605941 -41.011199) (xy 335.597998 -40.958495)
			(xy 334.681078 -40.958495) (xy 334.673135 -41.011199) (xy 334.657425 -41.062129) (xy 334.634299 -41.11015)
			(xy 334.604275 -41.154187) (xy 334.568023 -41.193258) (xy 334.526352 -41.226489) (xy 334.480194 -41.253138)
			(xy 334.43058 -41.27261) (xy 334.378618 -41.28447) (xy 334.325468 -41.288454) (xy 334.272318 -41.28447)
			(xy 334.220356 -41.27261) (xy 334.170742 -41.253138) (xy 334.124584 -41.226489) (xy 334.082913 -41.193258)
			(xy 334.046661 -41.154187) (xy 334.016637 -41.11015) (xy 333.993511 -41.062129) (xy 333.977801 -41.011199)
			(xy 333.969858 -40.958495) (xy 333.052306 -40.958495) (xy 333.051403 -40.970782) (xy 333.049626 -40.983662)
			(xy 333.049118 -40.987218) (xy 333.049118 -41.428395) (xy 333.155788 -41.428395) (xy 333.155788 -41.375097)
			(xy 333.163731 -41.322393) (xy 333.179441 -41.271463) (xy 333.202567 -41.223442) (xy 333.232591 -41.179405)
			(xy 333.268843 -41.140334) (xy 333.310514 -41.107103) (xy 333.356672 -41.080454) (xy 333.406286 -41.060982)
			(xy 333.458248 -41.049122) (xy 333.511398 -41.045139) (xy 333.564548 -41.049122) (xy 333.61651 -41.060982)
			(xy 333.666124 -41.080454) (xy 333.712282 -41.107103) (xy 333.753953 -41.140334) (xy 333.790205 -41.179405)
			(xy 333.820229 -41.223442) (xy 333.843355 -41.271463) (xy 333.859065 -41.322393) (xy 333.867008 -41.375097)
			(xy 333.867506 -41.401746) (xy 333.867008 -41.428395) (xy 334.785198 -41.428395) (xy 334.785198 -41.375097)
			(xy 334.793141 -41.322393) (xy 334.808851 -41.271463) (xy 334.831977 -41.223442) (xy 334.862001 -41.179405)
			(xy 334.898253 -41.140334) (xy 334.939924 -41.107103) (xy 334.986082 -41.080454) (xy 335.035696 -41.060982)
			(xy 335.087658 -41.049122) (xy 335.140808 -41.045139) (xy 335.193958 -41.049122) (xy 335.24592 -41.060982)
			(xy 335.295534 -41.080454) (xy 335.341692 -41.107103) (xy 335.383363 -41.140334) (xy 335.419615 -41.179405)
			(xy 335.449639 -41.223442) (xy 335.472765 -41.271463) (xy 335.488475 -41.322393) (xy 335.496418 -41.375097)
			(xy 335.496916 -41.401746) (xy 335.496418 -41.428395) (xy 335.488475 -41.481099) (xy 335.472765 -41.532029)
			(xy 335.449639 -41.58005) (xy 335.419615 -41.624087) (xy 335.383363 -41.663158) (xy 335.341692 -41.696389)
			(xy 335.295534 -41.723038) (xy 335.24592 -41.74251) (xy 335.193958 -41.75437) (xy 335.140808 -41.758354)
			(xy 335.087658 -41.75437) (xy 335.035696 -41.74251) (xy 334.986082 -41.723038) (xy 334.939924 -41.696389)
			(xy 334.898253 -41.663158) (xy 334.862001 -41.624087) (xy 334.831977 -41.58005) (xy 334.808851 -41.532029)
			(xy 334.793141 -41.481099) (xy 334.785198 -41.428395) (xy 333.867008 -41.428395) (xy 333.859065 -41.481099)
			(xy 333.843355 -41.532029) (xy 333.820229 -41.58005) (xy 333.790205 -41.624087) (xy 333.753953 -41.663158)
			(xy 333.712282 -41.696389) (xy 333.666124 -41.723038) (xy 333.61651 -41.74251) (xy 333.564548 -41.75437)
			(xy 333.511398 -41.758354) (xy 333.458248 -41.75437) (xy 333.406286 -41.74251) (xy 333.356672 -41.723038)
			(xy 333.310514 -41.696389) (xy 333.268843 -41.663158) (xy 333.232591 -41.624087) (xy 333.202567 -41.58005)
			(xy 333.179441 -41.532029) (xy 333.163731 -41.481099) (xy 333.155788 -41.428395) (xy 333.049118 -41.428395)
			(xy 333.049118 -41.816274) (xy 333.049626 -41.81983) (xy 333.051412 -41.832709) (xy 333.053316 -41.858644)
			(xy 333.053436 -41.871646) (xy 333.053308 -41.884648) (xy 333.052306 -41.898295) (xy 333.969858 -41.898295)
			(xy 333.969858 -41.844997) (xy 333.977801 -41.792293) (xy 333.993511 -41.741363) (xy 334.016637 -41.693342)
			(xy 334.046661 -41.649305) (xy 334.082913 -41.610234) (xy 334.124584 -41.577003) (xy 334.170742 -41.550354)
			(xy 334.220356 -41.530882) (xy 334.272318 -41.519022) (xy 334.325468 -41.515039) (xy 334.378618 -41.519022)
			(xy 334.43058 -41.530882) (xy 334.480194 -41.550354) (xy 334.526352 -41.577003) (xy 334.568023 -41.610234)
			(xy 334.604275 -41.649305) (xy 334.634299 -41.693342) (xy 334.657425 -41.741363) (xy 334.673135 -41.792293)
			(xy 334.681078 -41.844997) (xy 334.681576 -41.871646) (xy 334.681078 -41.898295) (xy 335.597998 -41.898295)
			(xy 335.597998 -41.844997) (xy 335.605941 -41.792293) (xy 335.621651 -41.741363) (xy 335.644777 -41.693342)
			(xy 335.674801 -41.649305) (xy 335.711053 -41.610234) (xy 335.752724 -41.577003) (xy 335.798882 -41.550354)
			(xy 335.848496 -41.530882) (xy 335.900458 -41.519022) (xy 335.953608 -41.515039) (xy 336.006758 -41.519022)
			(xy 336.05872 -41.530882) (xy 336.108334 -41.550354) (xy 336.154492 -41.577003) (xy 336.196163 -41.610234)
			(xy 336.232415 -41.649305) (xy 336.262439 -41.693342) (xy 336.285565 -41.741363) (xy 336.301275 -41.792293)
			(xy 336.309218 -41.844997) (xy 336.309716 -41.871646) (xy 336.309218 -41.898295) (xy 336.301275 -41.950999)
			(xy 336.285565 -42.001929) (xy 336.262439 -42.04995) (xy 336.232415 -42.093987) (xy 336.196163 -42.133058)
			(xy 336.154492 -42.166289) (xy 336.108334 -42.192938) (xy 336.05872 -42.21241) (xy 336.006758 -42.22427)
			(xy 335.953608 -42.228254) (xy 335.900458 -42.22427) (xy 335.848496 -42.21241) (xy 335.798882 -42.192938)
			(xy 335.752724 -42.166289) (xy 335.711053 -42.133058) (xy 335.674801 -42.093987) (xy 335.644777 -42.04995)
			(xy 335.621651 -42.001929) (xy 335.605941 -41.950999) (xy 335.597998 -41.898295) (xy 334.681078 -41.898295)
			(xy 334.673135 -41.950999) (xy 334.657425 -42.001929) (xy 334.634299 -42.04995) (xy 334.604275 -42.093987)
			(xy 334.568023 -42.133058) (xy 334.526352 -42.166289) (xy 334.480194 -42.192938) (xy 334.43058 -42.21241)
			(xy 334.378618 -42.22427) (xy 334.325468 -42.228254) (xy 334.272318 -42.22427) (xy 334.220356 -42.21241)
			(xy 334.170742 -42.192938) (xy 334.124584 -42.166289) (xy 334.082913 -42.133058) (xy 334.046661 -42.093987)
			(xy 334.016637 -42.04995) (xy 333.993511 -42.001929) (xy 333.977801 -41.950999) (xy 333.969858 -41.898295)
			(xy 333.052306 -41.898295) (xy 333.051403 -41.910582) (xy 333.049626 -41.923462) (xy 333.049118 -41.927018)
			(xy 333.049118 -42.368195) (xy 333.154772 -42.368195) (xy 333.154772 -42.314897) (xy 333.162715 -42.262193)
			(xy 333.178425 -42.211263) (xy 333.201551 -42.163242) (xy 333.231575 -42.119205) (xy 333.267827 -42.080134)
			(xy 333.309498 -42.046903) (xy 333.355656 -42.020254) (xy 333.40527 -42.000782) (xy 333.457232 -41.988922)
			(xy 333.510382 -41.984939) (xy 333.563532 -41.988922) (xy 333.615494 -42.000782) (xy 333.665108 -42.020254)
			(xy 333.711266 -42.046903) (xy 333.752937 -42.080134) (xy 333.789189 -42.119205) (xy 333.819213 -42.163242)
			(xy 333.842339 -42.211263) (xy 333.858049 -42.262193) (xy 333.865992 -42.314897) (xy 333.86649 -42.341546)
			(xy 333.865992 -42.368195) (xy 334.785198 -42.368195) (xy 334.785198 -42.314897) (xy 334.793141 -42.262193)
			(xy 334.808851 -42.211263) (xy 334.831977 -42.163242) (xy 334.862001 -42.119205) (xy 334.898253 -42.080134)
			(xy 334.939924 -42.046903) (xy 334.986082 -42.020254) (xy 335.035696 -42.000782) (xy 335.087658 -41.988922)
			(xy 335.140808 -41.984939) (xy 335.193958 -41.988922) (xy 335.24592 -42.000782) (xy 335.295534 -42.020254)
			(xy 335.341692 -42.046903) (xy 335.383363 -42.080134) (xy 335.419615 -42.119205) (xy 335.449639 -42.163242)
			(xy 335.472765 -42.211263) (xy 335.488475 -42.262193) (xy 335.496418 -42.314897) (xy 335.496916 -42.341546)
			(xy 335.496418 -42.368195) (xy 335.488475 -42.420899) (xy 335.472765 -42.471829) (xy 335.449639 -42.51985)
			(xy 335.419615 -42.563887) (xy 335.383363 -42.602958) (xy 335.341692 -42.636189) (xy 335.295534 -42.662838)
			(xy 335.24592 -42.68231) (xy 335.193958 -42.69417) (xy 335.140808 -42.698154) (xy 335.087658 -42.69417)
			(xy 335.035696 -42.68231) (xy 334.986082 -42.662838) (xy 334.939924 -42.636189) (xy 334.898253 -42.602958)
			(xy 334.862001 -42.563887) (xy 334.831977 -42.51985) (xy 334.808851 -42.471829) (xy 334.793141 -42.420899)
			(xy 334.785198 -42.368195) (xy 333.865992 -42.368195) (xy 333.858049 -42.420899) (xy 333.842339 -42.471829)
			(xy 333.819213 -42.51985) (xy 333.789189 -42.563887) (xy 333.752937 -42.602958) (xy 333.711266 -42.636189)
			(xy 333.665108 -42.662838) (xy 333.615494 -42.68231) (xy 333.563532 -42.69417) (xy 333.510382 -42.698154)
			(xy 333.457232 -42.69417) (xy 333.40527 -42.68231) (xy 333.355656 -42.662838) (xy 333.309498 -42.636189)
			(xy 333.267827 -42.602958) (xy 333.231575 -42.563887) (xy 333.201551 -42.51985) (xy 333.178425 -42.471829)
			(xy 333.162715 -42.420899) (xy 333.154772 -42.368195) (xy 333.049118 -42.368195) (xy 333.049118 -42.756074)
			(xy 333.049626 -42.75963) (xy 333.051412 -42.772509) (xy 333.053316 -42.798444) (xy 333.053436 -42.811446)
			(xy 333.053308 -42.824448) (xy 333.052306 -42.838095) (xy 333.969858 -42.838095) (xy 333.969858 -42.784797)
			(xy 333.977801 -42.732093) (xy 333.993511 -42.681163) (xy 334.016637 -42.633142) (xy 334.046661 -42.589105)
			(xy 334.082913 -42.550034) (xy 334.124584 -42.516803) (xy 334.170742 -42.490154) (xy 334.220356 -42.470682)
			(xy 334.272318 -42.458822) (xy 334.325468 -42.454839) (xy 334.378618 -42.458822) (xy 334.43058 -42.470682)
			(xy 334.480194 -42.490154) (xy 334.526352 -42.516803) (xy 334.568023 -42.550034) (xy 334.604275 -42.589105)
			(xy 334.634299 -42.633142) (xy 334.657425 -42.681163) (xy 334.673135 -42.732093) (xy 334.681078 -42.784797)
			(xy 334.681576 -42.811446) (xy 334.681078 -42.838095) (xy 334.673135 -42.890799) (xy 334.657425 -42.941729)
			(xy 334.634299 -42.98975) (xy 334.604275 -43.033787) (xy 334.568023 -43.072858) (xy 334.526352 -43.106089)
			(xy 334.480194 -43.132738) (xy 334.43058 -43.15221) (xy 334.378618 -43.16407) (xy 334.325468 -43.168054)
			(xy 334.272318 -43.16407) (xy 334.220356 -43.15221) (xy 334.170742 -43.132738) (xy 334.124584 -43.106089)
			(xy 334.082913 -43.072858) (xy 334.046661 -43.033787) (xy 334.016637 -42.98975) (xy 333.993511 -42.941729)
			(xy 333.977801 -42.890799) (xy 333.969858 -42.838095) (xy 333.052306 -42.838095) (xy 333.051403 -42.850382)
			(xy 333.049626 -42.863262) (xy 333.049118 -42.866818) (xy 333.049118 -43.307995) (xy 333.155788 -43.307995)
			(xy 333.155788 -43.254697) (xy 333.163731 -43.201993) (xy 333.179441 -43.151063) (xy 333.202567 -43.103042)
			(xy 333.232591 -43.059005) (xy 333.268843 -43.019934) (xy 333.310514 -42.986703) (xy 333.356672 -42.960054)
			(xy 333.406286 -42.940582) (xy 333.458248 -42.928722) (xy 333.511398 -42.924739) (xy 333.564548 -42.928722)
			(xy 333.61651 -42.940582) (xy 333.666124 -42.960054) (xy 333.712282 -42.986703) (xy 333.753953 -43.019934)
			(xy 333.790205 -43.059005) (xy 333.820229 -43.103042) (xy 333.843355 -43.151063) (xy 333.859065 -43.201993)
			(xy 333.867008 -43.254697) (xy 333.867506 -43.281346) (xy 333.867008 -43.307995) (xy 334.782658 -43.307995)
			(xy 334.782658 -43.254697) (xy 334.790601 -43.201993) (xy 334.806311 -43.151063) (xy 334.829437 -43.103042)
			(xy 334.859461 -43.059005) (xy 334.895713 -43.019934) (xy 334.937384 -42.986703) (xy 334.983542 -42.960054)
			(xy 335.033156 -42.940582) (xy 335.085118 -42.928722) (xy 335.138268 -42.924739) (xy 335.191418 -42.928722)
			(xy 335.24338 -42.940582) (xy 335.292994 -42.960054) (xy 335.339152 -42.986703) (xy 335.380823 -43.019934)
			(xy 335.417075 -43.059005) (xy 335.447099 -43.103042) (xy 335.470225 -43.151063) (xy 335.485935 -43.201993)
			(xy 335.493878 -43.254697) (xy 335.494376 -43.281346) (xy 335.493878 -43.307995) (xy 335.485935 -43.360699)
			(xy 335.470225 -43.411629) (xy 335.447099 -43.45965) (xy 335.417075 -43.503687) (xy 335.380823 -43.542758)
			(xy 335.339152 -43.575989) (xy 335.292994 -43.602638) (xy 335.24338 -43.62211) (xy 335.191418 -43.63397)
			(xy 335.138268 -43.637954) (xy 335.085118 -43.63397) (xy 335.033156 -43.62211) (xy 334.983542 -43.602638)
			(xy 334.937384 -43.575989) (xy 334.895713 -43.542758) (xy 334.859461 -43.503687) (xy 334.829437 -43.45965)
			(xy 334.806311 -43.411629) (xy 334.790601 -43.360699) (xy 334.782658 -43.307995) (xy 333.867008 -43.307995)
			(xy 333.859065 -43.360699) (xy 333.843355 -43.411629) (xy 333.820229 -43.45965) (xy 333.790205 -43.503687)
			(xy 333.753953 -43.542758) (xy 333.712282 -43.575989) (xy 333.666124 -43.602638) (xy 333.61651 -43.62211)
			(xy 333.564548 -43.63397) (xy 333.511398 -43.637954) (xy 333.458248 -43.63397) (xy 333.406286 -43.62211)
			(xy 333.356672 -43.602638) (xy 333.310514 -43.575989) (xy 333.268843 -43.542758) (xy 333.232591 -43.503687)
			(xy 333.202567 -43.45965) (xy 333.179441 -43.411629) (xy 333.163731 -43.360699) (xy 333.155788 -43.307995)
			(xy 333.049118 -43.307995) (xy 333.049118 -43.695874) (xy 333.049626 -43.69943) (xy 333.051412 -43.712309)
			(xy 333.053316 -43.738244) (xy 333.053436 -43.751246) (xy 333.053308 -43.764248) (xy 333.052306 -43.777895)
			(xy 333.968588 -43.777895) (xy 333.968588 -43.724597) (xy 333.976531 -43.671893) (xy 333.992241 -43.620963)
			(xy 334.015367 -43.572942) (xy 334.045391 -43.528905) (xy 334.081643 -43.489834) (xy 334.123314 -43.456603)
			(xy 334.169472 -43.429954) (xy 334.219086 -43.410482) (xy 334.271048 -43.398622) (xy 334.324198 -43.394639)
			(xy 334.377348 -43.398622) (xy 334.42931 -43.410482) (xy 334.478924 -43.429954) (xy 334.525082 -43.456603)
			(xy 334.566753 -43.489834) (xy 334.603005 -43.528905) (xy 334.633029 -43.572942) (xy 334.656155 -43.620963)
			(xy 334.671865 -43.671893) (xy 334.679808 -43.724597) (xy 334.680306 -43.751246) (xy 334.679808 -43.777895)
			(xy 334.671865 -43.830599) (xy 334.656155 -43.881529) (xy 334.633029 -43.92955) (xy 334.603005 -43.973587)
			(xy 334.566753 -44.012658) (xy 334.525082 -44.045889) (xy 334.478924 -44.072538) (xy 334.42931 -44.09201)
			(xy 334.377348 -44.10387) (xy 334.324198 -44.107854) (xy 334.271048 -44.10387) (xy 334.219086 -44.09201)
			(xy 334.169472 -44.072538) (xy 334.123314 -44.045889) (xy 334.081643 -44.012658) (xy 334.045391 -43.973587)
			(xy 334.015367 -43.92955) (xy 333.992241 -43.881529) (xy 333.976531 -43.830599) (xy 333.968588 -43.777895)
			(xy 333.052306 -43.777895) (xy 333.051403 -43.790182) (xy 333.049626 -43.803062) (xy 333.049118 -43.806618)
			(xy 333.049118 -44.247795) (xy 333.154772 -44.247795) (xy 333.154772 -44.194497) (xy 333.162715 -44.141793)
			(xy 333.178425 -44.090863) (xy 333.201551 -44.042842) (xy 333.231575 -43.998805) (xy 333.267827 -43.959734)
			(xy 333.309498 -43.926503) (xy 333.355656 -43.899854) (xy 333.40527 -43.880382) (xy 333.457232 -43.868522)
			(xy 333.510382 -43.864539) (xy 333.563532 -43.868522) (xy 333.615494 -43.880382) (xy 333.665108 -43.899854)
			(xy 333.711266 -43.926503) (xy 333.752937 -43.959734) (xy 333.789189 -43.998805) (xy 333.819213 -44.042842)
			(xy 333.842339 -44.090863) (xy 333.858049 -44.141793) (xy 333.865992 -44.194497) (xy 333.86649 -44.221146)
			(xy 333.865992 -44.247795) (xy 333.858049 -44.300499) (xy 333.842339 -44.351429) (xy 333.819213 -44.39945)
			(xy 333.789189 -44.443487) (xy 333.752937 -44.482558) (xy 333.711266 -44.515789) (xy 333.665108 -44.542438)
			(xy 333.615494 -44.56191) (xy 333.563532 -44.57377) (xy 333.510382 -44.577754) (xy 333.457232 -44.57377)
			(xy 333.40527 -44.56191) (xy 333.355656 -44.542438) (xy 333.309498 -44.515789) (xy 333.267827 -44.482558)
			(xy 333.231575 -44.443487) (xy 333.201551 -44.39945) (xy 333.178425 -44.351429) (xy 333.162715 -44.300499)
			(xy 333.154772 -44.247795) (xy 333.049118 -44.247795) (xy 333.049118 -44.673266) (xy 333.049626 -44.691046)
			(xy 333.049118 -44.708826) (xy 333.049118 -44.876445) (xy 334.543898 -44.876445) (xy 334.543898 -44.823147)
			(xy 334.551841 -44.770443) (xy 334.567551 -44.719513) (xy 334.590677 -44.671492) (xy 334.620701 -44.627455)
			(xy 334.656953 -44.588384) (xy 334.698624 -44.555153) (xy 334.744782 -44.528504) (xy 334.794396 -44.509032)
			(xy 334.846358 -44.497172) (xy 334.899508 -44.493189) (xy 334.952658 -44.497172) (xy 335.00462 -44.509032)
			(xy 335.054234 -44.528504) (xy 335.100392 -44.555153) (xy 335.142063 -44.588384) (xy 335.178315 -44.627455)
			(xy 335.208339 -44.671492) (xy 335.231465 -44.719513) (xy 335.247175 -44.770443) (xy 335.255118 -44.823147)
			(xy 335.255616 -44.849796) (xy 335.255118 -44.876445) (xy 335.247175 -44.929149) (xy 335.231465 -44.980079)
			(xy 335.208339 -45.0281) (xy 335.178315 -45.072137) (xy 335.142063 -45.111208) (xy 335.100392 -45.144439)
			(xy 335.054234 -45.171088) (xy 335.00462 -45.19056) (xy 334.952658 -45.20242) (xy 334.899508 -45.206404)
			(xy 334.846358 -45.20242) (xy 334.794396 -45.19056) (xy 334.744782 -45.171088) (xy 334.698624 -45.144439)
			(xy 334.656953 -45.111208) (xy 334.620701 -45.072137) (xy 334.590677 -45.0281) (xy 334.567551 -44.980079)
			(xy 334.551841 -44.929149) (xy 334.543898 -44.876445) (xy 333.049118 -44.876445) (xy 333.049118 -45.613066)
			(xy 333.049626 -45.630846) (xy 333.049118 -45.648626) (xy 333.049118 -47.067195) (xy 333.153248 -47.067195)
			(xy 333.153248 -47.013897) (xy 333.161191 -46.961193) (xy 333.176901 -46.910263) (xy 333.200027 -46.862242)
			(xy 333.230051 -46.818205) (xy 333.266303 -46.779134) (xy 333.307974 -46.745903) (xy 333.354132 -46.719254)
			(xy 333.403746 -46.699782) (xy 333.455708 -46.687922) (xy 333.508858 -46.683939) (xy 333.562008 -46.687922)
			(xy 333.61397 -46.699782) (xy 333.663584 -46.719254) (xy 333.709742 -46.745903) (xy 333.751413 -46.779134)
			(xy 333.787665 -46.818205) (xy 333.817689 -46.862242) (xy 333.840815 -46.910263) (xy 333.856525 -46.961193)
			(xy 333.864468 -47.013897) (xy 333.864966 -47.040546) (xy 333.864468 -47.067195) (xy 333.856525 -47.119899)
			(xy 333.840815 -47.170829) (xy 333.817689 -47.21885) (xy 333.787665 -47.262887) (xy 333.751413 -47.301958)
			(xy 333.709742 -47.335189) (xy 333.663584 -47.361838) (xy 333.61397 -47.38131) (xy 333.562008 -47.39317)
			(xy 333.508858 -47.397154) (xy 333.455708 -47.39317) (xy 333.403746 -47.38131) (xy 333.354132 -47.361838)
			(xy 333.307974 -47.335189) (xy 333.266303 -47.301958) (xy 333.230051 -47.262887) (xy 333.200027 -47.21885)
			(xy 333.176901 -47.170829) (xy 333.161191 -47.119899) (xy 333.153248 -47.067195) (xy 333.049118 -47.067195)
			(xy 333.049118 -47.492666) (xy 333.049626 -47.510446) (xy 333.049118 -47.528226) (xy 333.049118 -48.006995)
			(xy 333.15274 -48.006995) (xy 333.15274 -47.953697) (xy 333.160683 -47.900993) (xy 333.176393 -47.850063)
			(xy 333.199519 -47.802042) (xy 333.229543 -47.758005) (xy 333.265795 -47.718934) (xy 333.307466 -47.685703)
			(xy 333.353624 -47.659054) (xy 333.403238 -47.639582) (xy 333.4552 -47.627722) (xy 333.50835 -47.623739)
			(xy 333.5615 -47.627722) (xy 333.613462 -47.639582) (xy 333.663076 -47.659054) (xy 333.709234 -47.685703)
			(xy 333.750905 -47.718934) (xy 333.787157 -47.758005) (xy 333.817181 -47.802042) (xy 333.840307 -47.850063)
			(xy 333.856017 -47.900993) (xy 333.86396 -47.953697) (xy 333.864458 -47.980346) (xy 333.86396 -48.006995)
			(xy 333.857449 -48.050196) (xy 334.5434 -48.050196) (xy 334.543934 -48.023136) (xy 334.552117 -47.969639)
			(xy 334.568308 -47.917998) (xy 334.592133 -47.869405) (xy 334.623044 -47.824981) (xy 334.660326 -47.785751)
			(xy 334.70312 -47.752621) (xy 334.726534 -47.739046) (xy 334.738141 -47.732043) (xy 334.757558 -47.713146)
			(xy 334.771319 -47.689807) (xy 334.778454 -47.663669) (xy 334.77846 -47.636575) (xy 334.771337 -47.610434)
			(xy 334.757586 -47.587089) (xy 334.738177 -47.568184) (xy 334.726534 -47.561246) (xy 334.703118 -47.547674)
			(xy 334.660325 -47.514541) (xy 334.623042 -47.47531) (xy 334.592129 -47.430887) (xy 334.568298 -47.382295)
			(xy 334.552099 -47.330655) (xy 334.543905 -47.277158) (xy 334.543905 -47.223038) (xy 334.5521 -47.169541)
			(xy 334.568299 -47.117901) (xy 334.592131 -47.06931) (xy 334.623045 -47.024887) (xy 334.660328 -46.985657)
			(xy 334.703121 -46.952524) (xy 334.726534 -46.938946) (xy 334.738141 -46.931943) (xy 334.757558 -46.913046)
			(xy 334.771319 -46.889707) (xy 334.778454 -46.863569) (xy 334.77846 -46.836475) (xy 334.771337 -46.810334)
			(xy 334.757586 -46.786989) (xy 334.738177 -46.768084) (xy 334.726534 -46.761146) (xy 334.703118 -46.747574)
			(xy 334.660325 -46.71444) (xy 334.623042 -46.675209) (xy 334.592129 -46.630786) (xy 334.568298 -46.582194)
			(xy 334.552099 -46.530554) (xy 334.543905 -46.477057) (xy 334.5434 -46.449996) (xy 334.543898 -46.423347)
			(xy 334.551841 -46.370643) (xy 334.567551 -46.319713) (xy 334.590677 -46.271692) (xy 334.620701 -46.227655)
			(xy 334.656953 -46.188584) (xy 334.698624 -46.155353) (xy 334.744782 -46.128704) (xy 334.794396 -46.109232)
			(xy 334.846358 -46.097372) (xy 334.899508 -46.093389) (xy 334.952658 -46.097372) (xy 335.00462 -46.109232)
			(xy 335.054234 -46.128704) (xy 335.100392 -46.155353) (xy 335.142063 -46.188584) (xy 335.178315 -46.227655)
			(xy 335.208339 -46.271692) (xy 335.231465 -46.319713) (xy 335.247175 -46.370643) (xy 335.255118 -46.423347)
			(xy 335.255616 -46.449996) (xy 335.255147 -46.477058) (xy 335.246951 -46.530558) (xy 335.230748 -46.5822)
			(xy 335.206912 -46.630793) (xy 335.175991 -46.675216) (xy 335.1387 -46.714444) (xy 335.095899 -46.747572)
			(xy 335.072482 -46.761146) (xy 335.060798 -46.768025) (xy 335.04139 -46.78695) (xy 335.02764 -46.810312)
			(xy 335.020518 -46.836468) (xy 335.020524 -46.863576) (xy 335.027658 -46.889729) (xy 335.041417 -46.913085)
			(xy 335.060834 -46.932002) (xy 335.072482 -46.938946) (xy 335.095896 -46.952526) (xy 335.138697 -46.985654)
			(xy 335.175988 -47.024881) (xy 335.206909 -47.069303) (xy 335.230746 -47.117895) (xy 335.24695 -47.169536)
			(xy 335.255147 -47.223036) (xy 335.255147 -47.27716) (xy 335.246951 -47.33066) (xy 335.230748 -47.382302)
			(xy 335.206911 -47.430894) (xy 335.175991 -47.475316) (xy 335.1387 -47.514544) (xy 335.095899 -47.547672)
			(xy 335.072482 -47.561246) (xy 335.060798 -47.568125) (xy 335.04139 -47.58705) (xy 335.02764 -47.610412)
			(xy 335.020518 -47.636568) (xy 335.020524 -47.663676) (xy 335.027658 -47.689829) (xy 335.041417 -47.713185)
			(xy 335.060834 -47.732102) (xy 335.072482 -47.739046) (xy 335.095898 -47.752618) (xy 335.138691 -47.785752)
			(xy 335.175973 -47.824984) (xy 335.206886 -47.869407) (xy 335.230717 -47.917999) (xy 335.246916 -47.969639)
			(xy 335.255111 -48.023136) (xy 335.255616 -48.050196) (xy 335.255118 -48.076845) (xy 335.247175 -48.129549)
			(xy 335.231465 -48.180479) (xy 335.208339 -48.2285) (xy 335.178315 -48.272537) (xy 335.142063 -48.311608)
			(xy 335.100392 -48.344839) (xy 335.054234 -48.371488) (xy 335.00462 -48.39096) (xy 334.952658 -48.40282)
			(xy 334.899508 -48.406804) (xy 334.846358 -48.40282) (xy 334.794396 -48.39096) (xy 334.744782 -48.371488)
			(xy 334.698624 -48.344839) (xy 334.656953 -48.311608) (xy 334.620701 -48.272537) (xy 334.590677 -48.2285)
			(xy 334.567551 -48.180479) (xy 334.551841 -48.129549) (xy 334.543898 -48.076845) (xy 334.5434 -48.050196)
			(xy 333.857449 -48.050196) (xy 333.856017 -48.059699) (xy 333.840307 -48.110629) (xy 333.817181 -48.15865)
			(xy 333.787157 -48.202687) (xy 333.750905 -48.241758) (xy 333.709234 -48.274989) (xy 333.663076 -48.301638)
			(xy 333.613462 -48.32111) (xy 333.5615 -48.33297) (xy 333.50835 -48.336954) (xy 333.4552 -48.33297)
			(xy 333.403238 -48.32111) (xy 333.353624 -48.301638) (xy 333.307466 -48.274989) (xy 333.265795 -48.241758)
			(xy 333.229543 -48.202687) (xy 333.199519 -48.15865) (xy 333.176393 -48.110629) (xy 333.160683 -48.059699)
			(xy 333.15274 -48.006995) (xy 333.049118 -48.006995) (xy 333.049118 -48.432466) (xy 333.049626 -48.450246)
			(xy 333.049118 -48.468026) (xy 333.049118 -48.770794) (xy 333.488792 -49.210468) (xy 333.983076 -49.210468)
		)
		(stroke
			(width 0)
			(type solid)
		)
		(fill yes)
		(layer "In11.Cu")
		(net "P3V3_AUX")
	)
	(gr_poly
		(pts
			(xy 426.54982 -179.954428) (xy 426.54982 -177.632868) (xy 428.79518 -175.387508) (xy 429.806354 -175.387508)
			(xy 429.806354 -172.482256) (xy 429.873156 -172.4152) (xy 429.873156 -147.505928) (xy 423.650918 -141.28369)
			(xy 423.615866 -141.308836) (xy 423.591379 -141.325747) (xy 423.538267 -141.352582) (xy 423.481638 -141.370862)
			(xy 423.422861 -141.380146) (xy 423.393108 -141.380718) (xy 423.365913 -141.380236) (xy 423.312074 -141.372511)
			(xy 423.259879 -141.357216) (xy 423.210386 -141.334661) (xy 423.164599 -141.305304) (xy 423.123446 -141.269741)
			(xy 423.087763 -141.228692) (xy 423.058273 -141.182991) (xy 423.035574 -141.133564) (xy 423.020127 -141.081413)
			(xy 423.015664 -141.054582) (xy 423.009314 -141.011148) (xy 422.913302 -141.011148) (xy 422.906952 -141.054582)
			(xy 422.902527 -141.081419) (xy 422.88707 -141.133566) (xy 422.864362 -141.182989) (xy 422.834865 -141.228686)
			(xy 422.799177 -141.269729) (xy 422.75802 -141.305288) (xy 422.712231 -141.334641) (xy 422.662737 -141.357193)
			(xy 422.610541 -141.372487) (xy 422.556703 -141.380212) (xy 422.502313 -141.380212) (xy 422.448475 -141.372487)
			(xy 422.396279 -141.357193) (xy 422.346785 -141.334641) (xy 422.300996 -141.305288) (xy 422.259839 -141.269729)
			(xy 422.224151 -141.228686) (xy 422.194654 -141.182989) (xy 422.171946 -141.133566) (xy 422.156489 -141.081419)
			(xy 422.152064 -141.054582) (xy 422.145714 -141.011148) (xy 419.7604 -141.011148) (xy 418.43579 -139.686538)
			(xy 418.424862 -139.676408) (xy 418.398579 -139.662392) (xy 418.369374 -139.656542) (xy 418.339722 -139.659354)
			(xy 418.312136 -139.670588) (xy 418.288956 -139.689292) (xy 418.280088 -139.70127) (xy 418.264761 -139.722984)
			(xy 418.229055 -139.762351) (xy 418.188227 -139.796379) (xy 418.14307 -139.824407) (xy 418.094458 -139.845893)
			(xy 418.043334 -139.86042) (xy 417.990687 -139.867705) (xy 417.964112 -139.868148) (xy 417.942776 -139.868148)
			(xy 416.560508 -141.25067) (xy 416.560508 -142.458948) (xy 416.868862 -142.458948) (xy 416.872933 -142.403326)
			(xy 416.885059 -142.348889) (xy 416.904982 -142.296798) (xy 416.932278 -142.248163) (xy 416.966364 -142.20402)
			(xy 417.006513 -142.165311) (xy 417.051871 -142.13286) (xy 417.101471 -142.107359) (xy 417.154255 -142.089352)
			(xy 417.209098 -142.079222) (xy 417.264832 -142.077185) (xy 417.320269 -142.083285) (xy 417.374226 -142.097391)
			(xy 417.425555 -142.119203) (xy 417.473161 -142.148257) (xy 417.516029 -142.183932) (xy 417.553246 -142.225469)
			(xy 417.584019 -142.271982) (xy 417.607691 -142.322479) (xy 417.623759 -142.375886) (xy 417.631879 -142.431062)
			(xy 417.632388 -142.458948) (xy 417.631879 -142.486834) (xy 417.623759 -142.54201) (xy 417.607691 -142.595417)
			(xy 417.584019 -142.645914) (xy 417.553246 -142.692427) (xy 417.516029 -142.733964) (xy 417.473161 -142.769639)
			(xy 417.425555 -142.798693) (xy 417.374226 -142.820505) (xy 417.320269 -142.834611) (xy 417.264832 -142.840711)
			(xy 417.209098 -142.838674) (xy 417.154255 -142.828544) (xy 417.101471 -142.810537) (xy 417.051871 -142.785036)
			(xy 417.006513 -142.752585) (xy 416.966364 -142.713876) (xy 416.932278 -142.669733) (xy 416.904982 -142.621098)
			(xy 416.885059 -142.569007) (xy 416.872933 -142.51457) (xy 416.868862 -142.458948) (xy 416.560508 -142.458948)
			(xy 416.560508 -143.648938) (xy 418.008816 -145.0975) (xy 425.853606 -145.0975) (xy 425.87859 -145.098111)
			(xy 425.927599 -145.107852) (xy 425.973769 -145.126959) (xy 426.015329 -145.154699) (xy 426.033438 -145.171922)
			(xy 427.026832 -146.165316) (xy 427.044087 -146.183412) (xy 427.071894 -146.224958) (xy 427.091064 -146.271129)
			(xy 427.100862 -146.320152) (xy 427.101508 -146.345148) (xy 427.101508 -154.617166) (xy 427.100869 -154.642161)
			(xy 427.091066 -154.691182) (xy 427.071887 -154.737348) (xy 427.044071 -154.778886) (xy 427.026832 -154.796998)
			(xy 426.036232 -155.787598) (xy 426.036232 -157.016196) (xy 426.587415 -157.016196) (xy 426.591451 -156.932749)
			(xy 426.603523 -156.850081) (xy 426.623516 -156.768964) (xy 426.651245 -156.690155) (xy 426.686451 -156.61439)
			(xy 426.728805 -156.542377) (xy 426.777911 -156.474788) (xy 426.833312 -156.412254) (xy 426.894489 -156.355359)
			(xy 426.960872 -156.304633) (xy 427.03184 -156.260552) (xy 427.106732 -156.223526) (xy 427.184848 -156.1939)
			(xy 427.265458 -156.171952) (xy 427.34781 -156.157887) (xy 427.431136 -156.151835) (xy 427.514656 -156.153854)
			(xy 427.597592 -156.163924) (xy 427.679168 -156.181952) (xy 427.758624 -156.207769) (xy 427.835217 -156.241134)
			(xy 427.908233 -156.281735) (xy 427.976989 -156.329194) (xy 428.040843 -156.383067) (xy 428.0992 -156.442852)
			(xy 428.151515 -156.507989) (xy 428.197298 -156.577872) (xy 428.236123 -156.651847) (xy 428.267628 -156.729224)
			(xy 428.291517 -156.809281) (xy 428.307568 -156.891269) (xy 428.315631 -156.974424) (xy 428.316136 -157.016196)
			(xy 428.315631 -157.057968) (xy 428.307568 -157.141123) (xy 428.291517 -157.223111) (xy 428.267628 -157.303168)
			(xy 428.236123 -157.380545) (xy 428.197298 -157.45452) (xy 428.151515 -157.524403) (xy 428.0992 -157.58954)
			(xy 428.040843 -157.649325) (xy 427.976989 -157.703198) (xy 427.908233 -157.750657) (xy 427.835217 -157.791258)
			(xy 427.758624 -157.824623) (xy 427.679168 -157.85044) (xy 427.597592 -157.868468) (xy 427.514656 -157.878538)
			(xy 427.431136 -157.880557) (xy 427.34781 -157.874505) (xy 427.265458 -157.86044) (xy 427.184848 -157.838492)
			(xy 427.106732 -157.808866) (xy 427.03184 -157.77184) (xy 426.960872 -157.727759) (xy 426.894489 -157.677033)
			(xy 426.833312 -157.620138) (xy 426.777911 -157.557604) (xy 426.728805 -157.490015) (xy 426.686451 -157.418002)
			(xy 426.651245 -157.342237) (xy 426.623516 -157.263428) (xy 426.603523 -157.182311) (xy 426.591451 -157.099643)
			(xy 426.587415 -157.016196) (xy 426.036232 -157.016196) (xy 426.036232 -159.558666) (xy 426.563024 -159.558666)
			(xy 426.563024 -159.47397) (xy 426.571075 -159.389656) (xy 426.587104 -159.30649) (xy 426.610965 -159.225223)
			(xy 426.642444 -159.146593) (xy 426.681255 -159.071312) (xy 426.727045 -159.00006) (xy 426.779401 -158.933484)
			(xy 426.837849 -158.872186) (xy 426.901859 -158.816721) (xy 426.970851 -158.767592) (xy 427.044201 -158.725243)
			(xy 427.121244 -158.690059) (xy 427.201283 -158.662357) (xy 427.283592 -158.642389) (xy 427.367427 -158.630336)
			(xy 427.452028 -158.626306) (xy 427.536629 -158.630336) (xy 427.620464 -158.642389) (xy 427.702773 -158.662357)
			(xy 427.782812 -158.690059) (xy 427.859855 -158.725243) (xy 427.933205 -158.767592) (xy 428.002197 -158.816721)
			(xy 428.066207 -158.872186) (xy 428.124655 -158.933484) (xy 428.177011 -159.00006) (xy 428.222801 -159.071312)
			(xy 428.261612 -159.146593) (xy 428.293091 -159.225223) (xy 428.316952 -159.30649) (xy 428.332981 -159.389656)
			(xy 428.341032 -159.47397) (xy 428.341536 -159.516318) (xy 428.341032 -159.558666) (xy 428.332981 -159.64298)
			(xy 428.316952 -159.726146) (xy 428.293091 -159.807413) (xy 428.261612 -159.886043) (xy 428.222801 -159.961324)
			(xy 428.177011 -160.032576) (xy 428.124655 -160.099152) (xy 428.066207 -160.16045) (xy 428.002197 -160.215915)
			(xy 427.933205 -160.265044) (xy 427.859855 -160.307393) (xy 427.782812 -160.342577) (xy 427.702773 -160.370279)
			(xy 427.620464 -160.390247) (xy 427.536629 -160.4023) (xy 427.452028 -160.406331) (xy 427.367427 -160.4023)
			(xy 427.283592 -160.390247) (xy 427.201283 -160.370279) (xy 427.121244 -160.342577) (xy 427.044201 -160.307393)
			(xy 426.970851 -160.265044) (xy 426.901859 -160.215915) (xy 426.837849 -160.16045) (xy 426.779401 -160.099152)
			(xy 426.727045 -160.032576) (xy 426.681255 -159.961324) (xy 426.642444 -159.886043) (xy 426.610965 -159.807413)
			(xy 426.587104 -159.726146) (xy 426.571075 -159.64298) (xy 426.563024 -159.558666) (xy 426.036232 -159.558666)
			(xy 426.036232 -160.46831) (xy 426.03562 -160.493293) (xy 426.025876 -160.5423) (xy 426.006765 -160.588466)
			(xy 425.97902 -160.630021) (xy 425.96181 -160.648142) (xy 424.876468 -161.733738) (xy 424.876468 -163.170616)
			(xy 425.480988 -163.170616) (xy 425.48147 -163.143364) (xy 425.489225 -163.089414) (xy 425.504579 -163.037116)
			(xy 425.527219 -162.987537) (xy 425.556685 -162.941684) (xy 425.592377 -162.900491) (xy 425.633568 -162.864797)
			(xy 425.679419 -162.835329) (xy 425.728998 -162.812686) (xy 425.781294 -162.797329) (xy 425.835244 -162.789572)
			(xy 425.862496 -162.789108) (xy 425.890642 -162.789598) (xy 425.946324 -162.797875) (xy 426.000186 -162.814237)
			(xy 426.051064 -162.838327) (xy 426.097854 -162.869626) (xy 426.119036 -162.888168) (xy 426.130841 -162.8982)
			(xy 426.15893 -162.911235) (xy 426.189633 -162.915257) (xy 426.220131 -162.909897) (xy 426.247624 -162.895647)
			(xy 426.25899 -162.88512) (xy 426.280551 -162.864437) (xy 426.328964 -162.829427) (xy 426.382244 -162.802395)
			(xy 426.439087 -162.784001) (xy 426.498103 -162.774696) (xy 426.527976 -162.774122) (xy 426.556122 -162.77462)
			(xy 426.611803 -162.782895) (xy 426.665666 -162.799254) (xy 426.716544 -162.823343) (xy 426.763334 -162.85464)
			(xy 426.784516 -162.873182) (xy 426.796337 -162.883193) (xy 426.82442 -162.896228) (xy 426.855118 -162.900253)
			(xy 426.885612 -162.894899) (xy 426.913103 -162.880657) (xy 426.92447 -162.870134) (xy 426.946042 -162.849463)
			(xy 426.994452 -162.814451) (xy 427.047729 -162.787416) (xy 427.10457 -162.76902) (xy 427.163584 -162.759712)
			(xy 427.193456 -162.759136) (xy 427.22071 -162.759596) (xy 427.274663 -162.767348) (xy 427.326964 -162.782701)
			(xy 427.376547 -162.805342) (xy 427.422402 -162.834809) (xy 427.463596 -162.870504) (xy 427.499291 -162.911698)
			(xy 427.528758 -162.957553) (xy 427.551399 -163.007136) (xy 427.566752 -163.059437) (xy 427.574504 -163.11339)
			(xy 427.574964 -163.140644) (xy 427.57445 -163.169383) (xy 427.565822 -163.22621) (xy 427.548769 -163.2811)
			(xy 427.523676 -163.332812) (xy 427.49111 -163.380175) (xy 427.47184 -163.401502) (xy 427.461724 -163.413001)
			(xy 427.448385 -163.44056) (xy 427.443809 -163.470832) (xy 427.448405 -163.501102) (xy 427.461761 -163.528652)
			(xy 427.47184 -163.540186) (xy 427.491156 -163.561474) (xy 427.523723 -163.608842) (xy 427.548814 -163.66056)
			(xy 427.565863 -163.715457) (xy 427.574482 -163.77229) (xy 427.574477 -163.829774) (xy 427.565849 -163.886606)
			(xy 427.548791 -163.9415) (xy 427.52369 -163.993213) (xy 427.491116 -164.040576) (xy 427.47184 -164.061902)
			(xy 427.461724 -164.073401) (xy 427.448385 -164.10096) (xy 427.443809 -164.131232) (xy 427.448405 -164.161502)
			(xy 427.461761 -164.189052) (xy 427.47184 -164.200586) (xy 427.491156 -164.221874) (xy 427.523723 -164.269242)
			(xy 427.548814 -164.32096) (xy 427.565863 -164.375857) (xy 427.574482 -164.43269) (xy 427.574477 -164.490174)
			(xy 427.565849 -164.547006) (xy 427.548791 -164.6019) (xy 427.52369 -164.653613) (xy 427.491116 -164.700976)
			(xy 427.47184 -164.722302) (xy 427.461724 -164.733801) (xy 427.448385 -164.76136) (xy 427.443809 -164.791632)
			(xy 427.448405 -164.821902) (xy 427.461761 -164.849452) (xy 427.47184 -164.860986) (xy 427.491156 -164.882274)
			(xy 427.523723 -164.929642) (xy 427.548814 -164.98136) (xy 427.565863 -165.036257) (xy 427.574482 -165.09309)
			(xy 427.574477 -165.150574) (xy 427.565849 -165.207406) (xy 427.548791 -165.2623) (xy 427.52369 -165.314013)
			(xy 427.491116 -165.361376) (xy 427.47184 -165.382702) (xy 427.461724 -165.394201) (xy 427.448385 -165.42176)
			(xy 427.443809 -165.452032) (xy 427.448405 -165.482302) (xy 427.461761 -165.509852) (xy 427.47184 -165.521386)
			(xy 427.491156 -165.542674) (xy 427.523723 -165.590042) (xy 427.548814 -165.64176) (xy 427.565863 -165.696657)
			(xy 427.574482 -165.75349) (xy 427.574477 -165.810974) (xy 427.565849 -165.867806) (xy 427.548791 -165.9227)
			(xy 427.52369 -165.974413) (xy 427.491116 -166.021776) (xy 427.47184 -166.043102) (xy 427.461724 -166.054601)
			(xy 427.448385 -166.08216) (xy 427.443809 -166.112432) (xy 427.448405 -166.142702) (xy 427.461761 -166.170252)
			(xy 427.47184 -166.181786) (xy 427.491128 -166.203098) (xy 427.523693 -166.250464) (xy 427.548782 -166.302179)
			(xy 427.565829 -166.357073) (xy 427.574446 -166.413904) (xy 427.574964 -166.442644) (xy 427.574563 -166.469898)
			(xy 427.566799 -166.523851) (xy 427.551436 -166.57615) (xy 427.528787 -166.625731) (xy 427.499312 -166.671583)
			(xy 427.463612 -166.712774) (xy 427.422412 -166.748465) (xy 427.376553 -166.777929) (xy 427.326968 -166.800567)
			(xy 427.274665 -166.815918) (xy 427.22071 -166.823669) (xy 427.193456 -166.824152) (xy 427.16531 -166.823641)
			(xy 427.10963 -166.815371) (xy 427.055766 -166.799015) (xy 427.004888 -166.774928) (xy 426.958098 -166.743633)
			(xy 426.936916 -166.725092) (xy 426.925069 -166.715116) (xy 426.896995 -166.702081) (xy 426.866306 -166.698051)
			(xy 426.835818 -166.703395) (xy 426.80833 -166.717624) (xy 426.796962 -166.72814) (xy 426.775372 -166.748791)
			(xy 426.726968 -166.783807) (xy 426.673695 -166.810846) (xy 426.616858 -166.829247) (xy 426.557847 -166.838559)
			(xy 426.527976 -166.839138) (xy 426.499237 -166.838619) (xy 426.44241 -166.829993) (xy 426.38752 -166.812942)
			(xy 426.335808 -166.78785) (xy 426.288445 -166.755284) (xy 426.267118 -166.736014) (xy 426.255584 -166.725942)
			(xy 426.228038 -166.7126) (xy 426.197776 -166.708015) (xy 426.167514 -166.7126) (xy 426.139968 -166.725942)
			(xy 426.128434 -166.736014) (xy 426.10711 -166.755288) (xy 426.059748 -166.787856) (xy 426.008036 -166.812948)
			(xy 425.953144 -166.829998) (xy 425.896315 -166.838619) (xy 425.867576 -166.839138) (xy 425.840326 -166.838645)
			(xy 425.78638 -166.830886) (xy 425.734087 -166.815529) (xy 425.684512 -166.792887) (xy 425.638663 -166.763421)
			(xy 425.597474 -166.727731) (xy 425.561782 -166.686542) (xy 425.532316 -166.640694) (xy 425.509673 -166.591119)
			(xy 425.494316 -166.538826) (xy 425.486556 -166.48488) (xy 425.486068 -166.45763) (xy 425.486619 -166.428892)
			(xy 425.495236 -166.372066) (xy 425.51228 -166.317176) (xy 425.537366 -166.265464) (xy 425.569924 -166.2181)
			(xy 425.589192 -166.196772) (xy 425.599232 -166.185214) (xy 425.612575 -166.157676) (xy 425.617164 -166.127422)
			(xy 425.612588 -166.097166) (xy 425.599257 -166.069623) (xy 425.589192 -166.058088) (xy 425.569952 -166.036735)
			(xy 425.537389 -165.989376) (xy 425.512298 -165.937668) (xy 425.495247 -165.882782) (xy 425.486622 -165.825959)
			(xy 425.486619 -165.768485) (xy 425.495237 -165.711661) (xy 425.512282 -165.656773) (xy 425.537367 -165.605062)
			(xy 425.569925 -165.557699) (xy 425.589192 -165.536372) (xy 425.599232 -165.524814) (xy 425.612575 -165.497276)
			(xy 425.617164 -165.467022) (xy 425.612588 -165.436766) (xy 425.599257 -165.409223) (xy 425.589192 -165.397688)
			(xy 425.569952 -165.376335) (xy 425.537389 -165.328976) (xy 425.512298 -165.277268) (xy 425.495247 -165.222382)
			(xy 425.486622 -165.165559) (xy 425.486619 -165.108085) (xy 425.495237 -165.051261) (xy 425.512282 -164.996373)
			(xy 425.537367 -164.944662) (xy 425.569925 -164.897299) (xy 425.589192 -164.875972) (xy 425.599232 -164.864414)
			(xy 425.612575 -164.836876) (xy 425.617164 -164.806622) (xy 425.612588 -164.776366) (xy 425.599257 -164.748823)
			(xy 425.589192 -164.737288) (xy 425.569952 -164.715935) (xy 425.537389 -164.668576) (xy 425.512298 -164.616868)
			(xy 425.495247 -164.561982) (xy 425.486622 -164.505159) (xy 425.486619 -164.447685) (xy 425.495237 -164.390861)
			(xy 425.512282 -164.335973) (xy 425.537367 -164.284262) (xy 425.569925 -164.236899) (xy 425.589192 -164.215572)
			(xy 425.599232 -164.204014) (xy 425.612575 -164.176476) (xy 425.617164 -164.146222) (xy 425.612588 -164.115966)
			(xy 425.599257 -164.088423) (xy 425.589192 -164.076888) (xy 425.569945 -164.05554) (xy 425.537373 -164.008185)
			(xy 425.512276 -163.956479) (xy 425.49522 -163.901592) (xy 425.486592 -163.844768) (xy 425.486068 -163.81603)
			(xy 425.486539 -163.788401) (xy 425.494478 -163.733716) (xy 425.510222 -163.680748) (xy 425.533443 -163.630605)
			(xy 425.563654 -163.584337) (xy 425.581572 -163.5633) (xy 425.590996 -163.551771) (xy 425.603448 -163.524742)
			(xy 425.607576 -163.495271) (xy 425.603028 -163.465862) (xy 425.590191 -163.439014) (xy 425.580556 -163.427664)
			(xy 425.561911 -163.406478) (xy 425.530459 -163.35962) (xy 425.506249 -163.308641) (xy 425.489809 -163.254654)
			(xy 425.481497 -163.198834) (xy 425.480988 -163.170616) (xy 424.876468 -163.170616) (xy 424.876468 -169.953686)
			(xy 426.587415 -169.953686) (xy 426.591451 -169.870239) (xy 426.603523 -169.787571) (xy 426.623516 -169.706454)
			(xy 426.651245 -169.627645) (xy 426.686451 -169.55188) (xy 426.728805 -169.479867) (xy 426.777911 -169.412278)
			(xy 426.833312 -169.349744) (xy 426.894489 -169.292849) (xy 426.960872 -169.242123) (xy 427.03184 -169.198042)
			(xy 427.106732 -169.161016) (xy 427.184848 -169.13139) (xy 427.265458 -169.109442) (xy 427.34781 -169.095377)
			(xy 427.431136 -169.089325) (xy 427.514656 -169.091344) (xy 427.597592 -169.101414) (xy 427.679168 -169.119442)
			(xy 427.758624 -169.145259) (xy 427.835217 -169.178624) (xy 427.908233 -169.219225) (xy 427.976989 -169.266684)
			(xy 428.040843 -169.320557) (xy 428.0992 -169.380342) (xy 428.151515 -169.445479) (xy 428.197298 -169.515362)
			(xy 428.236123 -169.589337) (xy 428.267628 -169.666714) (xy 428.291517 -169.746771) (xy 428.307568 -169.828759)
			(xy 428.315631 -169.911914) (xy 428.316136 -169.953686) (xy 428.315631 -169.995458) (xy 428.307568 -170.078613)
			(xy 428.291517 -170.160601) (xy 428.267628 -170.240658) (xy 428.236123 -170.318035) (xy 428.197298 -170.39201)
			(xy 428.151515 -170.461893) (xy 428.0992 -170.52703) (xy 428.040843 -170.586815) (xy 427.976989 -170.640688)
			(xy 427.908233 -170.688147) (xy 427.835217 -170.728748) (xy 427.758624 -170.762113) (xy 427.679168 -170.78793)
			(xy 427.597592 -170.805958) (xy 427.514656 -170.816028) (xy 427.431136 -170.818047) (xy 427.34781 -170.811995)
			(xy 427.265458 -170.79793) (xy 427.184848 -170.775982) (xy 427.106732 -170.746356) (xy 427.03184 -170.70933)
			(xy 426.960872 -170.665249) (xy 426.894489 -170.614523) (xy 426.833312 -170.557628) (xy 426.777911 -170.495094)
			(xy 426.728805 -170.427505) (xy 426.686451 -170.355492) (xy 426.651245 -170.279727) (xy 426.623516 -170.200918)
			(xy 426.603523 -170.119801) (xy 426.591451 -170.037133) (xy 426.587415 -169.953686) (xy 424.876468 -169.953686)
			(xy 424.876468 -171.401994) (xy 424.875836 -171.426993) (xy 424.866046 -171.476023) (xy 424.84688 -171.522201)
			(xy 424.819075 -171.563754) (xy 424.801792 -171.581826) (xy 424.599354 -171.784518) (xy 424.837352 -172.022516)
			(xy 424.854606 -172.040612) (xy 424.88241 -172.082159) (xy 424.901579 -172.12833) (xy 424.911376 -172.177353)
			(xy 424.912028 -172.202348) (xy 424.912028 -172.496156) (xy 426.563024 -172.496156) (xy 426.563024 -172.41146)
			(xy 426.571075 -172.327146) (xy 426.587104 -172.24398) (xy 426.610965 -172.162713) (xy 426.642444 -172.084083)
			(xy 426.681255 -172.008802) (xy 426.727045 -171.93755) (xy 426.779401 -171.870974) (xy 426.837849 -171.809676)
			(xy 426.901859 -171.754211) (xy 426.970851 -171.705082) (xy 427.044201 -171.662733) (xy 427.121244 -171.627549)
			(xy 427.201283 -171.599847) (xy 427.283592 -171.579879) (xy 427.367427 -171.567826) (xy 427.452028 -171.563796)
			(xy 427.536629 -171.567826) (xy 427.620464 -171.579879) (xy 427.702773 -171.599847) (xy 427.782812 -171.627549)
			(xy 427.859855 -171.662733) (xy 427.933205 -171.705082) (xy 428.002197 -171.754211) (xy 428.066207 -171.809676)
			(xy 428.124655 -171.870974) (xy 428.177011 -171.93755) (xy 428.222801 -172.008802) (xy 428.261612 -172.084083)
			(xy 428.293091 -172.162713) (xy 428.316952 -172.24398) (xy 428.332981 -172.327146) (xy 428.341032 -172.41146)
			(xy 428.341536 -172.453808) (xy 428.341032 -172.496156) (xy 428.332981 -172.58047) (xy 428.316952 -172.663636)
			(xy 428.293091 -172.744903) (xy 428.261612 -172.823533) (xy 428.222801 -172.898814) (xy 428.177011 -172.970066)
			(xy 428.124655 -173.036642) (xy 428.066207 -173.09794) (xy 428.002197 -173.153405) (xy 427.933205 -173.202534)
			(xy 427.859855 -173.244883) (xy 427.782812 -173.280067) (xy 427.702773 -173.307769) (xy 427.620464 -173.327737)
			(xy 427.536629 -173.33979) (xy 427.452028 -173.343821) (xy 427.367427 -173.33979) (xy 427.283592 -173.327737)
			(xy 427.201283 -173.307769) (xy 427.121244 -173.280067) (xy 427.044201 -173.244883) (xy 426.970851 -173.202534)
			(xy 426.901859 -173.153405) (xy 426.837849 -173.09794) (xy 426.779401 -173.036642) (xy 426.727045 -172.970066)
			(xy 426.681255 -172.898814) (xy 426.642444 -172.823533) (xy 426.610965 -172.744903) (xy 426.587104 -172.663636)
			(xy 426.571075 -172.58047) (xy 426.563024 -172.496156) (xy 424.912028 -172.496156) (xy 424.912028 -179.276248)
			(xy 424.911391 -179.301244) (xy 424.901591 -179.350267) (xy 424.882416 -179.396437) (xy 424.854603 -179.437979)
			(xy 424.837352 -179.45608) (xy 423.676572 -180.61686) (xy 423.658475 -180.634112) (xy 423.616928 -180.661914)
			(xy 423.570757 -180.68108) (xy 423.521735 -180.690875) (xy 423.49674 -180.691536) (xy 420.210234 -180.691536)
			(xy 420.18869 -180.711855) (xy 420.140489 -180.746256) (xy 420.087551 -180.772796) (xy 420.031149 -180.790837)
			(xy 419.972635 -180.799946) (xy 419.943026 -180.800502) (xy 419.915772 -180.80004) (xy 419.861819 -180.792286)
			(xy 419.809518 -180.776933) (xy 419.759935 -180.754291) (xy 419.714079 -180.724824) (xy 419.672884 -180.68913)
			(xy 419.637188 -180.647937) (xy 419.607718 -180.602083) (xy 419.585074 -180.552501) (xy 419.569718 -180.500201)
			(xy 419.561961 -180.446248) (xy 419.561518 -180.418994) (xy 419.561929 -180.393761) (xy 419.56858 -180.343735)
			(xy 419.581752 -180.295019) (xy 419.601216 -180.248457) (xy 419.613588 -180.226462) (xy 419.620612 -180.213491)
			(xy 419.62763 -180.184855) (xy 419.626182 -180.155406) (xy 419.616386 -180.127597) (xy 419.599059 -180.103742)
			(xy 419.575643 -180.085826) (xy 419.562026 -180.080158) (xy 419.53525 -180.069464) (xy 419.48501 -180.041177)
			(xy 419.439602 -180.005647) (xy 419.400063 -179.963684) (xy 419.367294 -179.916246) (xy 419.342042 -179.864414)
			(xy 419.324884 -179.80937) (xy 419.31621 -179.75237) (xy 419.315646 -179.723542) (xy 419.316129 -179.696288)
			(xy 419.32388 -179.642333) (xy 419.339231 -179.59003) (xy 419.361869 -179.540445) (xy 419.391334 -179.494586)
			(xy 419.427025 -179.453387) (xy 419.468215 -179.417687) (xy 419.514068 -179.388212) (xy 419.563648 -179.365562)
			(xy 419.615947 -179.350199) (xy 419.6699 -179.342435) (xy 419.697154 -179.342034) (xy 419.727054 -179.342622)
			(xy 419.786123 -179.351943) (xy 419.814756 -179.360576) (xy 419.828667 -179.364534) (xy 419.857565 -179.365357)
			(xy 419.885539 -179.358064) (xy 419.910357 -179.343237) (xy 419.930036 -179.32206) (xy 419.943006 -179.296223)
			(xy 419.946074 -179.28209) (xy 419.951235 -179.256017) (xy 419.967821 -179.205522) (xy 419.991255 -179.157817)
			(xy 420.021083 -179.113827) (xy 420.056727 -179.074402) (xy 420.097499 -179.040305) (xy 420.142607 -179.012197)
			(xy 420.191181 -178.990621) (xy 420.242278 -178.975996) (xy 420.294911 -178.968604) (xy 420.321486 -178.968146)
			(xy 420.348743 -178.968608) (xy 420.402702 -178.976364) (xy 420.455008 -178.991721) (xy 420.504596 -179.014365)
			(xy 420.550456 -179.043837) (xy 420.591655 -179.079535) (xy 420.627355 -179.120733) (xy 420.656828 -179.166592)
			(xy 420.679474 -179.216179) (xy 420.694833 -179.268484) (xy 420.702591 -179.322443) (xy 420.702591 -179.376957)
			(xy 420.694833 -179.430916) (xy 420.679474 -179.483221) (xy 420.656828 -179.532808) (xy 420.627355 -179.578667)
			(xy 420.591655 -179.619865) (xy 420.550456 -179.655563) (xy 420.504596 -179.685035) (xy 420.455008 -179.707679)
			(xy 420.402702 -179.723036) (xy 420.348743 -179.730792) (xy 420.321486 -179.731162) (xy 420.291586 -179.730578)
			(xy 420.232514 -179.721262) (xy 420.203884 -179.71262) (xy 420.189977 -179.708671) (xy 420.161091 -179.707862)
			(xy 420.133132 -179.715163) (xy 420.10833 -179.729992) (xy 420.088664 -179.751165) (xy 420.075704 -179.776992)
			(xy 420.072566 -179.791106) (xy 420.065976 -179.823944) (xy 420.04286 -179.886798) (xy 420.026592 -179.916074)
			(xy 420.019575 -179.929044) (xy 420.012568 -179.957675) (xy 420.014024 -179.987115) (xy 420.023821 -180.014915)
			(xy 420.041146 -180.038762) (xy 420.064556 -180.056673) (xy 420.078154 -180.062378) (xy 420.102108 -180.071887)
			(xy 420.147425 -180.09643) (xy 420.189031 -180.126844) (xy 420.226168 -180.162577) (xy 420.242492 -180.18252)
			(xy 423.39133 -180.18252) (xy 424.403012 -179.170838) (xy 424.403012 -172.307758) (xy 424.132756 -172.037248)
			(xy 420.227252 -172.037248) (xy 420.209097 -172.056892) (xy 420.168234 -172.091409) (xy 420.122948 -172.119876)
			(xy 420.074129 -172.141735) (xy 420.022733 -172.156556) (xy 419.969771 -172.164049) (xy 419.943026 -172.164502)
			(xy 419.915772 -172.16404) (xy 419.861819 -172.156286) (xy 419.809518 -172.140933) (xy 419.759935 -172.118291)
			(xy 419.714079 -172.088824) (xy 419.672884 -172.05313) (xy 419.637188 -172.011937) (xy 419.607718 -171.966083)
			(xy 419.585074 -171.916501) (xy 419.569718 -171.864201) (xy 419.561961 -171.810248) (xy 419.561518 -171.782994)
			(xy 419.561929 -171.757761) (xy 419.56858 -171.707735) (xy 419.581752 -171.659019) (xy 419.601216 -171.612457)
			(xy 419.613588 -171.590462) (xy 419.620612 -171.577491) (xy 419.62763 -171.548855) (xy 419.626182 -171.519406)
			(xy 419.616386 -171.491597) (xy 419.599059 -171.467742) (xy 419.575643 -171.449826) (xy 419.562026 -171.444158)
			(xy 419.53525 -171.433464) (xy 419.48501 -171.405177) (xy 419.439602 -171.369647) (xy 419.400063 -171.327684)
			(xy 419.367294 -171.280246) (xy 419.342042 -171.228414) (xy 419.324884 -171.17337) (xy 419.31621 -171.11637)
			(xy 419.315646 -171.087542) (xy 419.316129 -171.060288) (xy 419.32388 -171.006333) (xy 419.339231 -170.95403)
			(xy 419.361869 -170.904445) (xy 419.391334 -170.858586) (xy 419.427025 -170.817387) (xy 419.468215 -170.781687)
			(xy 419.514068 -170.752212) (xy 419.563648 -170.729562) (xy 419.615947 -170.714199) (xy 419.6699 -170.706435)
			(xy 419.697154 -170.706034) (xy 419.727054 -170.706622) (xy 419.786123 -170.715943) (xy 419.814756 -170.724576)
			(xy 419.828667 -170.728534) (xy 419.857565 -170.729357) (xy 419.885539 -170.722064) (xy 419.910357 -170.707237)
			(xy 419.930036 -170.68606) (xy 419.943006 -170.660223) (xy 419.946074 -170.64609) (xy 419.951235 -170.620017)
			(xy 419.967821 -170.569522) (xy 419.991255 -170.521817) (xy 420.021083 -170.477827) (xy 420.056727 -170.438402)
			(xy 420.097499 -170.404305) (xy 420.142607 -170.376197) (xy 420.191181 -170.354621) (xy 420.242278 -170.339996)
			(xy 420.294911 -170.332604) (xy 420.321486 -170.332146) (xy 420.348743 -170.332608) (xy 420.402702 -170.340364)
			(xy 420.455008 -170.355721) (xy 420.504596 -170.378365) (xy 420.550456 -170.407837) (xy 420.591655 -170.443535)
			(xy 420.627355 -170.484733) (xy 420.656828 -170.530592) (xy 420.679474 -170.580179) (xy 420.694833 -170.632484)
			(xy 420.702591 -170.686443) (xy 420.702591 -170.740957) (xy 420.694833 -170.794916) (xy 420.679474 -170.847221)
			(xy 420.656828 -170.896808) (xy 420.627355 -170.942667) (xy 420.591655 -170.983865) (xy 420.550456 -171.019563)
			(xy 420.504596 -171.049035) (xy 420.455008 -171.071679) (xy 420.402702 -171.087036) (xy 420.348743 -171.094792)
			(xy 420.321486 -171.095162) (xy 420.291586 -171.094578) (xy 420.232514 -171.085262) (xy 420.203884 -171.07662)
			(xy 420.189977 -171.072671) (xy 420.161091 -171.071862) (xy 420.133132 -171.079163) (xy 420.10833 -171.093992)
			(xy 420.088664 -171.115165) (xy 420.075704 -171.140992) (xy 420.072566 -171.155106) (xy 420.065976 -171.187944)
			(xy 420.04286 -171.250798) (xy 420.026592 -171.280074) (xy 420.019575 -171.293044) (xy 420.012568 -171.321675)
			(xy 420.014024 -171.351115) (xy 420.023821 -171.378915) (xy 420.041146 -171.402762) (xy 420.064556 -171.420673)
			(xy 420.078154 -171.426378) (xy 420.106418 -171.437722) (xy 420.159215 -171.468075) (xy 420.206515 -171.506435)
			(xy 420.227252 -171.52874) (xy 424.13555 -171.52874) (xy 424.367452 -171.296584) (xy 424.367452 -161.628328)
			(xy 424.368091 -161.603333) (xy 424.377895 -161.554311) (xy 424.397072 -161.508144) (xy 424.424885 -161.466604)
			(xy 424.442128 -161.448496) (xy 425.527724 -160.3629) (xy 425.527724 -155.682188) (xy 425.528336 -155.657205)
			(xy 425.538079 -155.608197) (xy 425.557188 -155.562029) (xy 425.58493 -155.520471) (xy 425.602146 -155.502356)
			(xy 426.592492 -154.511756) (xy 426.592492 -146.450558) (xy 425.748196 -145.606008) (xy 417.903406 -145.606008)
			(xy 417.878422 -145.605398) (xy 417.829411 -145.595659) (xy 417.783239 -145.576554) (xy 417.741677 -145.548816)
			(xy 417.723574 -145.531586) (xy 416.126168 -143.93418) (xy 416.108913 -143.916084) (xy 416.081107 -143.874538)
			(xy 416.061938 -143.828367) (xy 416.05214 -143.779344) (xy 416.051492 -143.754348) (xy 416.051492 -141.14526)
			(xy 416.052088 -141.12026) (xy 416.061889 -141.071228) (xy 416.081067 -141.025051) (xy 416.108886 -140.983503)
			(xy 416.126168 -140.965428) (xy 417.583112 -139.508484) (xy 417.583112 -139.487148) (xy 417.583508 -139.460868)
			(xy 417.59064 -139.408796) (xy 417.604858 -139.358198) (xy 417.625893 -139.310033) (xy 417.653346 -139.265214)
			(xy 417.686696 -139.224592) (xy 417.72531 -139.188937) (xy 417.768457 -139.158925) (xy 417.815317 -139.135126)
			(xy 417.865004 -139.117989) (xy 417.890706 -139.112498) (xy 417.9316 -139.10437) (xy 417.9316 -132.116322)
			(xy 417.931058 -132.101339) (xy 417.922341 -132.072667) (xy 417.905681 -132.047757) (xy 417.882511 -132.028752)
			(xy 417.854823 -132.017287) (xy 417.825 -132.014348) (xy 417.795607 -132.020188) (xy 417.769173 -132.034305)
			(xy 417.758118 -132.04444) (xy 415.798508 -134.004304) (xy 415.798508 -144.004538) (xy 417.68141 -145.88744)
			(xy 425.5262 -145.88744) (xy 425.551198 -145.888072) (xy 425.600228 -145.897863) (xy 425.646405 -145.917031)
			(xy 425.687956 -145.944837) (xy 425.706032 -145.962116) (xy 426.264832 -146.520916) (xy 426.282087 -146.539012)
			(xy 426.309894 -146.580558) (xy 426.329064 -146.626729) (xy 426.338862 -146.675752) (xy 426.339508 -146.700748)
			(xy 426.339508 -154.086306) (xy 426.338915 -154.111307) (xy 426.32912 -154.160343) (xy 426.309946 -154.206524)
			(xy 426.28213 -154.248078) (xy 426.264832 -154.266138) (xy 425.251372 -155.279598) (xy 425.251372 -159.58439)
			(xy 425.250762 -159.609374) (xy 425.241023 -159.658384) (xy 425.221916 -159.704555) (xy 425.194176 -159.746115)
			(xy 425.17695 -159.764222) (xy 421.614346 -163.326826) (xy 421.596236 -163.344046) (xy 421.554674 -163.371782)
			(xy 421.508505 -163.390887) (xy 421.459497 -163.400627) (xy 421.434514 -163.401248) (xy 420.227252 -163.401248)
			(xy 420.209097 -163.420892) (xy 420.168234 -163.455409) (xy 420.122948 -163.483876) (xy 420.074129 -163.505735)
			(xy 420.022733 -163.520556) (xy 419.969771 -163.528049) (xy 419.943026 -163.528502) (xy 419.915772 -163.52804)
			(xy 419.861819 -163.520286) (xy 419.809518 -163.504933) (xy 419.759935 -163.482291) (xy 419.714079 -163.452824)
			(xy 419.672884 -163.41713) (xy 419.637188 -163.375937) (xy 419.607718 -163.330083) (xy 419.585074 -163.280501)
			(xy 419.569718 -163.228201) (xy 419.561961 -163.174248) (xy 419.561518 -163.146994) (xy 419.561929 -163.121761)
			(xy 419.56858 -163.071735) (xy 419.581752 -163.023019) (xy 419.601216 -162.976457) (xy 419.613588 -162.954462)
			(xy 419.620612 -162.941491) (xy 419.62763 -162.912855) (xy 419.626182 -162.883406) (xy 419.616386 -162.855597)
			(xy 419.599059 -162.831742) (xy 419.575643 -162.813826) (xy 419.562026 -162.808158) (xy 419.53525 -162.797464)
			(xy 419.48501 -162.769177) (xy 419.439602 -162.733647) (xy 419.400063 -162.691684) (xy 419.367294 -162.644246)
			(xy 419.342042 -162.592414) (xy 419.324884 -162.53737) (xy 419.31621 -162.48037) (xy 419.315646 -162.451542)
			(xy 419.316129 -162.424288) (xy 419.32388 -162.370333) (xy 419.339231 -162.31803) (xy 419.361869 -162.268445)
			(xy 419.391334 -162.222586) (xy 419.427025 -162.181387) (xy 419.468215 -162.145687) (xy 419.514068 -162.116212)
			(xy 419.563648 -162.093562) (xy 419.615947 -162.078199) (xy 419.6699 -162.070435) (xy 419.697154 -162.070034)
			(xy 419.727054 -162.070622) (xy 419.786123 -162.079943) (xy 419.814756 -162.088576) (xy 419.828667 -162.092534)
			(xy 419.857565 -162.093357) (xy 419.885539 -162.086064) (xy 419.910357 -162.071237) (xy 419.930036 -162.05006)
			(xy 419.943006 -162.024223) (xy 419.946074 -162.01009) (xy 419.951235 -161.984017) (xy 419.967821 -161.933522)
			(xy 419.991255 -161.885817) (xy 420.021083 -161.841827) (xy 420.056727 -161.802402) (xy 420.097499 -161.768305)
			(xy 420.142607 -161.740197) (xy 420.191181 -161.718621) (xy 420.242278 -161.703996) (xy 420.294911 -161.696604)
			(xy 420.321486 -161.696146) (xy 420.348743 -161.696608) (xy 420.402702 -161.704364) (xy 420.455008 -161.719721)
			(xy 420.504596 -161.742365) (xy 420.550456 -161.771837) (xy 420.591655 -161.807535) (xy 420.627355 -161.848733)
			(xy 420.656828 -161.894592) (xy 420.679474 -161.944179) (xy 420.694833 -161.996484) (xy 420.702591 -162.050443)
			(xy 420.702591 -162.104957) (xy 420.694833 -162.158916) (xy 420.679474 -162.211221) (xy 420.656828 -162.260808)
			(xy 420.627355 -162.306667) (xy 420.591655 -162.347865) (xy 420.550456 -162.383563) (xy 420.504596 -162.413035)
			(xy 420.455008 -162.435679) (xy 420.402702 -162.451036) (xy 420.348743 -162.458792) (xy 420.321486 -162.459162)
			(xy 420.291586 -162.458578) (xy 420.232514 -162.449262) (xy 420.203884 -162.44062) (xy 420.189977 -162.436671)
			(xy 420.161091 -162.435862) (xy 420.133132 -162.443163) (xy 420.10833 -162.457992) (xy 420.088664 -162.479165)
			(xy 420.075704 -162.504992) (xy 420.072566 -162.519106) (xy 420.065976 -162.551944) (xy 420.04286 -162.614798)
			(xy 420.026592 -162.644074) (xy 420.019575 -162.657044) (xy 420.012568 -162.685675) (xy 420.014024 -162.715115)
			(xy 420.023821 -162.742915) (xy 420.041146 -162.766762) (xy 420.064556 -162.784673) (xy 420.078154 -162.790378)
			(xy 420.106418 -162.801722) (xy 420.159215 -162.832075) (xy 420.206515 -162.870435) (xy 420.227252 -162.89274)
			(xy 421.329104 -162.89274) (xy 424.742864 -159.47898) (xy 424.742864 -155.174188) (xy 424.743476 -155.149205)
			(xy 424.75322 -155.100199) (xy 424.772331 -155.054032) (xy 424.800077 -155.012477) (xy 424.817286 -154.994356)
			(xy 425.830492 -153.980896) (xy 425.830492 -146.806158) (xy 425.42079 -146.396456) (xy 417.576 -146.396456)
			(xy 417.551002 -146.395824) (xy 417.501973 -146.386032) (xy 417.455795 -146.366865) (xy 417.414244 -146.339058)
			(xy 417.396168 -146.32178) (xy 415.364168 -144.28978) (xy 415.346913 -144.271684) (xy 415.319107 -144.230138)
			(xy 415.299938 -144.183967) (xy 415.29014 -144.134944) (xy 415.289492 -144.109948) (xy 415.289492 -133.898894)
			(xy 415.290085 -133.873893) (xy 415.29988 -133.824857) (xy 415.319054 -133.778676) (xy 415.34687 -133.737122)
			(xy 415.364168 -133.719062) (xy 417.9316 -131.15163) (xy 417.9316 -123.66117) (xy 417.4236 -123.15317)
			(xy 411.39491 -123.15317) (xy 410.41574 -124.13234) (xy 410.41574 -147.992846) (xy 410.459936 -147.998688)
			(xy 410.486624 -148.002724) (xy 410.538448 -148.017802) (xy 410.587404 -148.040528) (xy 410.632369 -148.070382)
			(xy 410.672314 -148.106679) (xy 410.706324 -148.14859) (xy 410.733619 -148.195153) (xy 410.753574 -148.245302)
			(xy 410.765733 -148.297888) (xy 410.769816 -148.351706) (xy 410.765731 -148.405525) (xy 410.75357 -148.45811)
			(xy 410.733613 -148.508259) (xy 410.706316 -148.554821) (xy 410.672305 -148.59673) (xy 410.632359 -148.633026)
			(xy 410.587393 -148.662878) (xy 410.538437 -148.685603) (xy 410.486611 -148.700678) (xy 410.459936 -148.704808)
			(xy 410.41574 -148.71065) (xy 410.41574 -150.423949) (xy 420.30348 -150.423949) (xy 420.30348 -150.369451)
			(xy 420.311235 -150.315508) (xy 420.326587 -150.263217) (xy 420.349225 -150.213643) (xy 420.378687 -150.167796)
			(xy 420.414373 -150.126607) (xy 420.455557 -150.090915) (xy 420.501401 -150.061448) (xy 420.550972 -150.038804)
			(xy 420.603261 -150.023445) (xy 420.657203 -150.015683) (xy 420.684452 -150.015194) (xy 420.711821 -150.01569)
			(xy 420.765999 -150.023501) (xy 420.818502 -150.038983) (xy 420.868249 -150.061818) (xy 420.914217 -150.091536)
			(xy 420.93515 -150.109174) (xy 420.946478 -150.11841) (xy 420.973035 -150.130586) (xy 421.001952 -150.134759)
			(xy 421.030869 -150.130586) (xy 421.057426 -150.11841) (xy 421.068754 -150.109174) (xy 421.089687 -150.091533)
			(xy 421.135655 -150.061809) (xy 421.185401 -150.038963) (xy 421.237903 -150.023467) (xy 421.292081 -150.015638)
			(xy 421.346823 -150.015638) (xy 421.401001 -150.023467) (xy 421.453503 -150.038963) (xy 421.503249 -150.061809)
			(xy 421.549217 -150.091533) (xy 421.57015 -150.109174) (xy 421.581478 -150.11841) (xy 421.608035 -150.130586)
			(xy 421.636952 -150.134759) (xy 421.665869 -150.130586) (xy 421.692426 -150.11841) (xy 421.703754 -150.109174)
			(xy 421.724689 -150.091539) (xy 421.770662 -150.061827) (xy 421.820408 -150.038991) (xy 421.872908 -150.023499)
			(xy 421.927083 -150.015669) (xy 421.954452 -150.015194) (xy 421.981707 -150.01565) (xy 422.035664 -150.023402)
			(xy 422.087968 -150.038753) (xy 422.137554 -150.061393) (xy 422.183413 -150.09086) (xy 422.224612 -150.126554)
			(xy 422.260311 -150.167748) (xy 422.289784 -150.213604) (xy 422.31243 -150.263187) (xy 422.327788 -150.315489)
			(xy 422.335547 -150.369445) (xy 422.335547 -150.423955) (xy 422.327788 -150.477911) (xy 422.31243 -150.530213)
			(xy 422.289784 -150.579796) (xy 422.260311 -150.625652) (xy 422.224612 -150.666846) (xy 422.183413 -150.70254)
			(xy 422.137554 -150.732007) (xy 422.087968 -150.754647) (xy 422.035664 -150.769998) (xy 421.981707 -150.77775)
			(xy 421.954452 -150.77821) (xy 421.927083 -150.777711) (xy 421.872905 -150.769901) (xy 421.820403 -150.754419)
			(xy 421.770655 -150.731585) (xy 421.724687 -150.701868) (xy 421.703754 -150.68423) (xy 421.692426 -150.674994)
			(xy 421.665869 -150.662818) (xy 421.636952 -150.658645) (xy 421.608035 -150.662818) (xy 421.581478 -150.674994)
			(xy 421.57015 -150.68423) (xy 421.549217 -150.701871) (xy 421.503249 -150.731595) (xy 421.453503 -150.754441)
			(xy 421.401001 -150.769937) (xy 421.346823 -150.777766) (xy 421.292081 -150.777766) (xy 421.237903 -150.769937)
			(xy 421.185401 -150.754441) (xy 421.135655 -150.731595) (xy 421.089687 -150.701871) (xy 421.068754 -150.68423)
			(xy 421.057426 -150.674994) (xy 421.030869 -150.662818) (xy 421.001952 -150.658645) (xy 420.973035 -150.662818)
			(xy 420.946478 -150.674994) (xy 420.93515 -150.68423) (xy 420.914214 -150.701864) (xy 420.868242 -150.731575)
			(xy 420.818495 -150.754412) (xy 420.765996 -150.769904) (xy 420.711821 -150.777735) (xy 420.684452 -150.77821)
			(xy 420.657203 -150.777717) (xy 420.603261 -150.769955) (xy 420.550972 -150.754596) (xy 420.501401 -150.731952)
			(xy 420.455557 -150.702485) (xy 420.414373 -150.666793) (xy 420.378687 -150.625604) (xy 420.349225 -150.579757)
			(xy 420.326587 -150.530183) (xy 420.311235 -150.477892) (xy 420.30348 -150.423949) (xy 410.41574 -150.423949)
			(xy 410.41574 -151.116284) (xy 418.675564 -151.116284) (xy 418.679635 -151.060662) (xy 418.691761 -151.006225)
			(xy 418.711684 -150.954134) (xy 418.73898 -150.905499) (xy 418.773066 -150.861356) (xy 418.813215 -150.822647)
			(xy 418.858573 -150.790196) (xy 418.908173 -150.764695) (xy 418.960957 -150.746688) (xy 419.0158 -150.736558)
			(xy 419.071534 -150.734521) (xy 419.126971 -150.740621) (xy 419.180928 -150.754727) (xy 419.232257 -150.776539)
			(xy 419.279863 -150.805593) (xy 419.322731 -150.841268) (xy 419.359948 -150.882805) (xy 419.390721 -150.929318)
			(xy 419.414393 -150.979815) (xy 419.430461 -151.033222) (xy 419.438581 -151.088398) (xy 419.43909 -151.116284)
			(xy 419.439044 -151.118824) (xy 419.681658 -151.118824) (xy 419.685729 -151.063202) (xy 419.697855 -151.008765)
			(xy 419.717778 -150.956674) (xy 419.745074 -150.908039) (xy 419.77916 -150.863896) (xy 419.819309 -150.825187)
			(xy 419.864667 -150.792736) (xy 419.914267 -150.767235) (xy 419.967051 -150.749228) (xy 420.021894 -150.739098)
			(xy 420.077628 -150.737061) (xy 420.133065 -150.743161) (xy 420.187022 -150.757267) (xy 420.238351 -150.779079)
			(xy 420.285957 -150.808133) (xy 420.328825 -150.843808) (xy 420.366042 -150.885345) (xy 420.396815 -150.931858)
			(xy 420.420487 -150.982355) (xy 420.431436 -151.018748) (xy 423.976292 -151.018748) (xy 423.976778 -150.991497)
			(xy 423.984534 -150.937549) (xy 423.999889 -150.885254) (xy 424.022531 -150.835677) (xy 424.051997 -150.789827)
			(xy 424.087688 -150.748636) (xy 424.128879 -150.712945) (xy 424.174729 -150.683479) (xy 424.224306 -150.660837)
			(xy 424.276601 -150.645482) (xy 424.330549 -150.637726) (xy 424.385051 -150.637726) (xy 424.438999 -150.645482)
			(xy 424.491294 -150.660837) (xy 424.540871 -150.683479) (xy 424.586721 -150.712945) (xy 424.627912 -150.748636)
			(xy 424.663603 -150.789827) (xy 424.693069 -150.835677) (xy 424.715711 -150.885254) (xy 424.731066 -150.937549)
			(xy 424.738822 -150.991497) (xy 424.739308 -151.018748) (xy 424.739308 -151.019002) (xy 424.739877 -151.034449)
			(xy 424.749157 -151.063917) (xy 424.766809 -151.089273) (xy 424.791224 -151.108204) (xy 424.820177 -151.118986)
			(xy 424.835574 -151.120348) (xy 424.864452 -151.122457) (xy 424.921128 -151.134291) (xy 424.975366 -151.154551)
			(xy 425.025922 -151.182773) (xy 425.071634 -151.218307) (xy 425.111453 -151.26034) (xy 425.144465 -151.307905)
			(xy 425.169913 -151.359911) (xy 425.187213 -151.415165) (xy 425.195968 -151.472399) (xy 425.196508 -151.501348)
			(xy 425.196022 -151.528599) (xy 425.188266 -151.582547) (xy 425.172911 -151.634842) (xy 425.150269 -151.684419)
			(xy 425.120803 -151.730269) (xy 425.085112 -151.77146) (xy 425.043921 -151.807151) (xy 424.998071 -151.836617)
			(xy 424.948494 -151.859259) (xy 424.896199 -151.874614) (xy 424.842251 -151.88237) (xy 424.787749 -151.88237)
			(xy 424.733801 -151.874614) (xy 424.681506 -151.859259) (xy 424.631929 -151.836617) (xy 424.586079 -151.807151)
			(xy 424.544888 -151.77146) (xy 424.509197 -151.730269) (xy 424.479731 -151.684419) (xy 424.457089 -151.634842)
			(xy 424.441734 -151.582547) (xy 424.433978 -151.528599) (xy 424.433492 -151.501348) (xy 424.433492 -151.501094)
			(xy 424.432927 -151.485647) (xy 424.423646 -151.456178) (xy 424.405993 -151.430823) (xy 424.381577 -151.411891)
			(xy 424.352623 -151.40111) (xy 424.337226 -151.399748) (xy 424.308348 -151.397643) (xy 424.251671 -151.385809)
			(xy 424.197432 -151.365548) (xy 424.146877 -151.337326) (xy 424.101165 -151.301791) (xy 424.061346 -151.259758)
			(xy 424.028333 -151.212193) (xy 424.002885 -151.160186) (xy 423.985586 -151.104931) (xy 423.976832 -151.047698)
			(xy 423.976292 -151.018748) (xy 420.431436 -151.018748) (xy 420.436555 -151.035762) (xy 420.444675 -151.090938)
			(xy 420.445184 -151.118824) (xy 420.444675 -151.14671) (xy 420.436555 -151.201886) (xy 420.420487 -151.255293)
			(xy 420.396815 -151.30579) (xy 420.366042 -151.352303) (xy 420.328825 -151.39384) (xy 420.285957 -151.429515)
			(xy 420.238351 -151.458569) (xy 420.187022 -151.480381) (xy 420.133065 -151.494487) (xy 420.077628 -151.500587)
			(xy 420.021894 -151.49855) (xy 419.967051 -151.48842) (xy 419.914267 -151.470413) (xy 419.864667 -151.444912)
			(xy 419.819309 -151.412461) (xy 419.77916 -151.373752) (xy 419.745074 -151.329609) (xy 419.717778 -151.280974)
			(xy 419.697855 -151.228883) (xy 419.685729 -151.174446) (xy 419.681658 -151.118824) (xy 419.439044 -151.118824)
			(xy 419.438581 -151.14417) (xy 419.430461 -151.199346) (xy 419.414393 -151.252753) (xy 419.390721 -151.30325)
			(xy 419.359948 -151.349763) (xy 419.322731 -151.3913) (xy 419.279863 -151.426975) (xy 419.232257 -151.456029)
			(xy 419.180928 -151.477841) (xy 419.126971 -151.491947) (xy 419.071534 -151.498047) (xy 419.0158 -151.49601)
			(xy 418.960957 -151.48588) (xy 418.908173 -151.467873) (xy 418.858573 -151.442372) (xy 418.813215 -151.409921)
			(xy 418.773066 -151.371212) (xy 418.73898 -151.327069) (xy 418.711684 -151.278434) (xy 418.691761 -151.226343)
			(xy 418.679635 -151.171906) (xy 418.675564 -151.116284) (xy 410.41574 -151.116284) (xy 410.41574 -152.03297)
			(xy 418.678358 -152.03297) (xy 418.682429 -151.977348) (xy 418.694555 -151.922911) (xy 418.714478 -151.87082)
			(xy 418.741774 -151.822185) (xy 418.77586 -151.778042) (xy 418.816009 -151.739333) (xy 418.861367 -151.706882)
			(xy 418.910967 -151.681381) (xy 418.963751 -151.663374) (xy 419.018594 -151.653244) (xy 419.074328 -151.651207)
			(xy 419.129765 -151.657307) (xy 419.183722 -151.671413) (xy 419.235051 -151.693225) (xy 419.282657 -151.722279)
			(xy 419.325525 -151.757954) (xy 419.362742 -151.799491) (xy 419.393515 -151.846004) (xy 419.417187 -151.896501)
			(xy 419.433255 -151.949908) (xy 419.441375 -152.005084) (xy 419.441884 -152.03297) (xy 419.441787 -152.038304)
			(xy 419.676578 -152.038304) (xy 419.680649 -151.982682) (xy 419.692775 -151.928245) (xy 419.712698 -151.876154)
			(xy 419.739994 -151.827519) (xy 419.77408 -151.783376) (xy 419.814229 -151.744667) (xy 419.859587 -151.712216)
			(xy 419.909187 -151.686715) (xy 419.961971 -151.668708) (xy 420.016814 -151.658578) (xy 420.072548 -151.656541)
			(xy 420.127985 -151.662641) (xy 420.181942 -151.676747) (xy 420.233271 -151.698559) (xy 420.280877 -151.727613)
			(xy 420.323745 -151.763288) (xy 420.360962 -151.804825) (xy 420.391735 -151.851338) (xy 420.415407 -151.901835)
			(xy 420.431475 -151.955242) (xy 420.439595 -152.010418) (xy 420.440104 -152.038304) (xy 420.439595 -152.06619)
			(xy 420.431475 -152.121366) (xy 420.415407 -152.174773) (xy 420.391735 -152.22527) (xy 420.360962 -152.271783)
			(xy 420.323745 -152.31332) (xy 420.280877 -152.348995) (xy 420.233271 -152.378049) (xy 420.181942 -152.399861)
			(xy 420.127985 -152.413967) (xy 420.072548 -152.420067) (xy 420.016814 -152.41803) (xy 419.961971 -152.4079)
			(xy 419.909187 -152.389893) (xy 419.859587 -152.364392) (xy 419.814229 -152.331941) (xy 419.77408 -152.293232)
			(xy 419.739994 -152.249089) (xy 419.712698 -152.200454) (xy 419.692775 -152.148363) (xy 419.680649 -152.093926)
			(xy 419.676578 -152.038304) (xy 419.441787 -152.038304) (xy 419.441375 -152.060856) (xy 419.433255 -152.116032)
			(xy 419.417187 -152.169439) (xy 419.393515 -152.219936) (xy 419.362742 -152.266449) (xy 419.325525 -152.307986)
			(xy 419.282657 -152.343661) (xy 419.235051 -152.372715) (xy 419.183722 -152.394527) (xy 419.129765 -152.408633)
			(xy 419.074328 -152.414733) (xy 419.018594 -152.412696) (xy 418.963751 -152.402566) (xy 418.910967 -152.384559)
			(xy 418.861367 -152.359058) (xy 418.816009 -152.326607) (xy 418.77586 -152.287898) (xy 418.741774 -152.243755)
			(xy 418.714478 -152.19512) (xy 418.694555 -152.143029) (xy 418.682429 -152.088592) (xy 418.678358 -152.03297)
			(xy 410.41574 -152.03297) (xy 410.41574 -152.977342) (xy 421.425622 -152.977342) (xy 421.429693 -152.92172)
			(xy 421.441819 -152.867283) (xy 421.461742 -152.815192) (xy 421.489038 -152.766557) (xy 421.523124 -152.722414)
			(xy 421.563273 -152.683705) (xy 421.608631 -152.651254) (xy 421.658231 -152.625753) (xy 421.711015 -152.607746)
			(xy 421.765858 -152.597616) (xy 421.821592 -152.595579) (xy 421.877029 -152.601679) (xy 421.930986 -152.615785)
			(xy 421.982315 -152.637597) (xy 422.029921 -152.666651) (xy 422.072789 -152.702326) (xy 422.110006 -152.743863)
			(xy 422.140779 -152.790376) (xy 422.164451 -152.840873) (xy 422.180519 -152.89428) (xy 422.188639 -152.949456)
			(xy 422.188768 -152.956514) (xy 422.32402 -152.956514) (xy 422.328091 -152.900892) (xy 422.340217 -152.846455)
			(xy 422.36014 -152.794364) (xy 422.387436 -152.745729) (xy 422.421522 -152.701586) (xy 422.461671 -152.662877)
			(xy 422.507029 -152.630426) (xy 422.556629 -152.604925) (xy 422.609413 -152.586918) (xy 422.664256 -152.576788)
			(xy 422.71999 -152.574751) (xy 422.775427 -152.580851) (xy 422.829384 -152.594957) (xy 422.880713 -152.616769)
			(xy 422.928319 -152.645823) (xy 422.971187 -152.681498) (xy 423.008404 -152.723035) (xy 423.039177 -152.769548)
			(xy 423.062849 -152.820045) (xy 423.078917 -152.873452) (xy 423.087037 -152.928628) (xy 423.087546 -152.956514)
			(xy 423.087037 -152.9844) (xy 423.078917 -153.039576) (xy 423.062849 -153.092983) (xy 423.039177 -153.14348)
			(xy 423.008404 -153.189993) (xy 422.971187 -153.23153) (xy 422.928319 -153.267205) (xy 422.880713 -153.296259)
			(xy 422.829384 -153.318071) (xy 422.775427 -153.332177) (xy 422.71999 -153.338277) (xy 422.664256 -153.33624)
			(xy 422.609413 -153.32611) (xy 422.556629 -153.308103) (xy 422.507029 -153.282602) (xy 422.461671 -153.250151)
			(xy 422.421522 -153.211442) (xy 422.387436 -153.167299) (xy 422.36014 -153.118664) (xy 422.340217 -153.066573)
			(xy 422.328091 -153.012136) (xy 422.32402 -152.956514) (xy 422.188768 -152.956514) (xy 422.189148 -152.977342)
			(xy 422.188639 -153.005228) (xy 422.180519 -153.060404) (xy 422.164451 -153.113811) (xy 422.140779 -153.164308)
			(xy 422.110006 -153.210821) (xy 422.072789 -153.252358) (xy 422.029921 -153.288033) (xy 421.982315 -153.317087)
			(xy 421.930986 -153.338899) (xy 421.877029 -153.353005) (xy 421.821592 -153.359105) (xy 421.765858 -153.357068)
			(xy 421.711015 -153.346938) (xy 421.658231 -153.328931) (xy 421.608631 -153.30343) (xy 421.563273 -153.270979)
			(xy 421.523124 -153.23227) (xy 421.489038 -153.188127) (xy 421.461742 -153.139492) (xy 421.441819 -153.087401)
			(xy 421.429693 -153.032964) (xy 421.425622 -152.977342) (xy 410.41574 -152.977342) (xy 410.41574 -153.54046)
			(xy 423.60037 -153.54046) (xy 423.604441 -153.484838) (xy 423.616567 -153.430401) (xy 423.63649 -153.37831)
			(xy 423.663786 -153.329675) (xy 423.697872 -153.285532) (xy 423.738021 -153.246823) (xy 423.783379 -153.214372)
			(xy 423.832979 -153.188871) (xy 423.885763 -153.170864) (xy 423.940606 -153.160734) (xy 423.99634 -153.158697)
			(xy 424.051777 -153.164797) (xy 424.105734 -153.178903) (xy 424.157063 -153.200715) (xy 424.204669 -153.229769)
			(xy 424.247537 -153.265444) (xy 424.284754 -153.306981) (xy 424.315527 -153.353494) (xy 424.339199 -153.403991)
			(xy 424.355267 -153.457398) (xy 424.363387 -153.512574) (xy 424.363896 -153.54046) (xy 424.363387 -153.568346)
			(xy 424.355267 -153.623522) (xy 424.339199 -153.676929) (xy 424.315527 -153.727426) (xy 424.284754 -153.773939)
			(xy 424.247537 -153.815476) (xy 424.204669 -153.851151) (xy 424.157063 -153.880205) (xy 424.105734 -153.902017)
			(xy 424.051777 -153.916123) (xy 423.99634 -153.922223) (xy 423.940606 -153.920186) (xy 423.885763 -153.910056)
			(xy 423.832979 -153.892049) (xy 423.783379 -153.866548) (xy 423.738021 -153.834097) (xy 423.697872 -153.795388)
			(xy 423.663786 -153.751245) (xy 423.63649 -153.70261) (xy 423.616567 -153.650519) (xy 423.604441 -153.596082)
			(xy 423.60037 -153.54046) (xy 410.41574 -153.54046) (xy 410.41574 -155.499308) (xy 417.524182 -155.499308)
			(xy 417.528253 -155.443686) (xy 417.540379 -155.389249) (xy 417.560302 -155.337158) (xy 417.587598 -155.288523)
			(xy 417.621684 -155.24438) (xy 417.661833 -155.205671) (xy 417.707191 -155.17322) (xy 417.756791 -155.147719)
			(xy 417.809575 -155.129712) (xy 417.864418 -155.119582) (xy 417.920152 -155.117545) (xy 417.975589 -155.123645)
			(xy 418.029546 -155.137751) (xy 418.080875 -155.159563) (xy 418.128481 -155.188617) (xy 418.162419 -155.21686)
			(xy 420.484552 -155.21686) (xy 420.488623 -155.161238) (xy 420.500749 -155.106801) (xy 420.520672 -155.05471)
			(xy 420.547968 -155.006075) (xy 420.582054 -154.961932) (xy 420.622203 -154.923223) (xy 420.667561 -154.890772)
			(xy 420.717161 -154.865271) (xy 420.769945 -154.847264) (xy 420.824788 -154.837134) (xy 420.880522 -154.835097)
			(xy 420.935959 -154.841197) (xy 420.989916 -154.855303) (xy 421.041245 -154.877115) (xy 421.088851 -154.906169)
			(xy 421.112505 -154.925854) (xy 421.450453 -154.925854) (xy 421.450453 -154.871346) (xy 421.458211 -154.817394)
			(xy 421.473568 -154.765094) (xy 421.496212 -154.715513) (xy 421.525681 -154.669659) (xy 421.561377 -154.628465)
			(xy 421.602572 -154.592772) (xy 421.648427 -154.563304) (xy 421.698009 -154.540662) (xy 421.750309 -154.525307)
			(xy 421.804262 -154.517552) (xy 421.831516 -154.51709) (xy 421.861892 -154.517675) (xy 421.921876 -154.527306)
			(xy 421.979575 -154.54632) (xy 422.033532 -154.574239) (xy 422.082383 -154.610355) (xy 422.104058 -154.631644)
			(xy 422.113809 -154.640955) (xy 422.137082 -154.65455) (xy 422.163099 -154.661592) (xy 422.190051 -154.661592)
			(xy 422.216068 -154.65455) (xy 422.239341 -154.640955) (xy 422.249092 -154.631644) (xy 422.270748 -154.610335)
			(xy 422.319604 -154.574222) (xy 422.373566 -154.546308) (xy 422.43127 -154.527299) (xy 422.491257 -154.517676)
			(xy 422.521634 -154.51709) (xy 422.548884 -154.517582) (xy 422.602827 -154.525342) (xy 422.655118 -154.5407)
			(xy 422.70469 -154.563343) (xy 422.750536 -154.592811) (xy 422.791722 -154.628502) (xy 422.82741 -154.669691)
			(xy 422.856873 -154.71554) (xy 422.879511 -154.765114) (xy 422.894865 -154.817406) (xy 422.90262 -154.87135)
			(xy 422.90262 -154.92585) (xy 422.894865 -154.979794) (xy 422.879511 -155.032086) (xy 422.856873 -155.08166)
			(xy 422.82741 -155.127509) (xy 422.791722 -155.168698) (xy 422.750536 -155.204389) (xy 422.70469 -155.233857)
			(xy 422.655118 -155.2565) (xy 422.602827 -155.271858) (xy 422.548884 -155.279618) (xy 422.521634 -155.280106)
			(xy 422.491257 -155.279554) (xy 422.431272 -155.269915) (xy 422.373572 -155.250893) (xy 422.319615 -155.222967)
			(xy 422.270766 -155.186844) (xy 422.249092 -155.165552) (xy 422.239364 -155.156194) (xy 422.216103 -155.142518)
			(xy 422.190067 -155.135431) (xy 422.163083 -155.135431) (xy 422.137047 -155.142518) (xy 422.113786 -155.156194)
			(xy 422.104058 -155.165552) (xy 422.082379 -155.186837) (xy 422.033529 -155.222953) (xy 421.979573 -155.250871)
			(xy 421.921874 -155.269886) (xy 421.861891 -155.279516) (xy 421.831516 -155.280106) (xy 421.804262 -155.279648)
			(xy 421.750309 -155.271893) (xy 421.698009 -155.256538) (xy 421.648427 -155.233896) (xy 421.602572 -155.204428)
			(xy 421.561377 -155.168735) (xy 421.525681 -155.127541) (xy 421.496212 -155.081687) (xy 421.473568 -155.032106)
			(xy 421.458211 -154.979806) (xy 421.450453 -154.925854) (xy 421.112505 -154.925854) (xy 421.131719 -154.941844)
			(xy 421.168936 -154.983381) (xy 421.199709 -155.029894) (xy 421.223381 -155.080391) (xy 421.239449 -155.133798)
			(xy 421.247569 -155.188974) (xy 421.248078 -155.21686) (xy 421.247569 -155.244746) (xy 421.239449 -155.299922)
			(xy 421.223381 -155.353329) (xy 421.199709 -155.403826) (xy 421.168936 -155.450339) (xy 421.131719 -155.491876)
			(xy 421.088851 -155.527551) (xy 421.041245 -155.556605) (xy 420.989916 -155.578417) (xy 420.935959 -155.592523)
			(xy 420.880522 -155.598623) (xy 420.824788 -155.596586) (xy 420.769945 -155.586456) (xy 420.717161 -155.568449)
			(xy 420.667561 -155.542948) (xy 420.622203 -155.510497) (xy 420.582054 -155.471788) (xy 420.547968 -155.427645)
			(xy 420.520672 -155.37901) (xy 420.500749 -155.326919) (xy 420.488623 -155.272482) (xy 420.484552 -155.21686)
			(xy 418.162419 -155.21686) (xy 418.171349 -155.224292) (xy 418.208566 -155.265829) (xy 418.239339 -155.312342)
			(xy 418.263011 -155.362839) (xy 418.279079 -155.416246) (xy 418.287199 -155.471422) (xy 418.287708 -155.499308)
			(xy 418.287199 -155.527194) (xy 418.279079 -155.58237) (xy 418.263011 -155.635777) (xy 418.239339 -155.686274)
			(xy 418.208566 -155.732787) (xy 418.171349 -155.774324) (xy 418.128481 -155.809999) (xy 418.080875 -155.839053)
			(xy 418.029546 -155.860865) (xy 417.975589 -155.874971) (xy 417.920152 -155.881071) (xy 417.864418 -155.879034)
			(xy 417.809575 -155.868904) (xy 417.756791 -155.850897) (xy 417.707191 -155.825396) (xy 417.661833 -155.792945)
			(xy 417.621684 -155.754236) (xy 417.587598 -155.710093) (xy 417.560302 -155.661458) (xy 417.540379 -155.609367)
			(xy 417.528253 -155.55493) (xy 417.524182 -155.499308) (xy 410.41574 -155.499308) (xy 410.41574 -164.770054)
			(xy 410.452824 -164.780214) (xy 410.478928 -164.788017) (xy 410.528576 -164.810447) (xy 410.574231 -164.840175)
			(xy 410.614826 -164.876509) (xy 410.649416 -164.9186) (xy 410.677194 -164.965466) (xy 410.697511 -165.016016)
			(xy 410.709895 -165.06907) (xy 410.714056 -165.123391) (xy 410.709898 -165.177713) (xy 410.697517 -165.230767)
			(xy 410.677201 -165.281318) (xy 410.649426 -165.328186) (xy 410.614838 -165.370279) (xy 410.574244 -165.406614)
			(xy 410.528591 -165.436345) (xy 410.478944 -165.458777) (xy 410.452824 -165.466522) (xy 410.41574 -165.476682)
			(xy 410.41574 -166.718234) (xy 410.452824 -166.728394) (xy 410.477484 -166.735725) (xy 410.524547 -166.756504)
			(xy 410.56813 -166.78384) (xy 410.607324 -166.817164) (xy 410.641314 -166.855782) (xy 410.669391 -166.89889)
			(xy 410.690972 -166.945591) (xy 410.705606 -166.994912) (xy 410.71299 -167.045825) (xy 410.713428 -167.071548)
			(xy 410.712877 -167.10025) (xy 410.703657 -167.15691) (xy 410.685463 -167.211355) (xy 410.658768 -167.262175)
			(xy 410.624263 -167.308052) (xy 410.603954 -167.328342) (xy 410.594382 -167.338136) (xy 410.580367 -167.361651)
			(xy 410.573103 -167.388045) (xy 410.573112 -167.415421) (xy 410.580393 -167.44181) (xy 410.594423 -167.465316)
			(xy 410.603954 -167.475154) (xy 410.624291 -167.49542) (xy 410.658805 -167.541298) (xy 410.685505 -167.592123)
			(xy 410.703696 -167.646575) (xy 410.712907 -167.703242) (xy 410.713428 -167.731948) (xy 410.712973 -167.757668)
			(xy 410.705569 -167.808573) (xy 410.690922 -167.857885) (xy 410.669337 -167.904577) (xy 410.641262 -167.947681)
			(xy 410.60728 -167.9863) (xy 410.568099 -168.019631) (xy 410.524532 -168.046981) (xy 410.477484 -168.067782)
			(xy 410.452824 -168.075102) (xy 410.41574 -168.085262) (xy 410.41574 -173.406054) (xy 410.452824 -173.416214)
			(xy 410.478928 -173.424017) (xy 410.528576 -173.446447) (xy 410.574231 -173.476175) (xy 410.614826 -173.512509)
			(xy 410.649416 -173.5546) (xy 410.677194 -173.601466) (xy 410.697511 -173.652016) (xy 410.709895 -173.70507)
			(xy 410.714056 -173.759391) (xy 410.709898 -173.813713) (xy 410.697517 -173.866767) (xy 410.677201 -173.917318)
			(xy 410.649426 -173.964186) (xy 410.614838 -174.006279) (xy 410.574244 -174.042614) (xy 410.528591 -174.072345)
			(xy 410.478944 -174.094777) (xy 410.452824 -174.102522) (xy 410.41574 -174.112682) (xy 410.41574 -175.354234)
			(xy 410.452824 -175.364394) (xy 410.477484 -175.371725) (xy 410.524547 -175.392504) (xy 410.56813 -175.41984)
			(xy 410.607324 -175.453164) (xy 410.641314 -175.491782) (xy 410.669391 -175.53489) (xy 410.690972 -175.581591)
			(xy 410.705606 -175.630912) (xy 410.71299 -175.681825) (xy 410.713428 -175.707548) (xy 410.712877 -175.73625)
			(xy 410.703657 -175.79291) (xy 410.685463 -175.847355) (xy 410.658768 -175.898175) (xy 410.624263 -175.944052)
			(xy 410.603954 -175.964342) (xy 410.594382 -175.974136) (xy 410.580367 -175.997651) (xy 410.573103 -176.024045)
			(xy 410.573112 -176.051421) (xy 410.580393 -176.07781) (xy 410.594423 -176.101316) (xy 410.603954 -176.111154)
			(xy 410.624291 -176.13142) (xy 410.658805 -176.177298) (xy 410.685505 -176.228123) (xy 410.703696 -176.282575)
			(xy 410.712907 -176.339242) (xy 410.713428 -176.367948) (xy 410.712973 -176.393668) (xy 410.705569 -176.444573)
			(xy 410.690922 -176.493885) (xy 410.669337 -176.540577) (xy 410.641262 -176.583681) (xy 410.60728 -176.6223)
			(xy 410.568099 -176.655631) (xy 410.524532 -176.682981) (xy 410.477484 -176.703782) (xy 410.452824 -176.711102)
			(xy 410.41574 -176.721262) (xy 410.41574 -182.042054) (xy 410.452824 -182.052214) (xy 410.478928 -182.060017)
			(xy 410.528576 -182.082447) (xy 410.574231 -182.112175) (xy 410.614826 -182.148509) (xy 410.649416 -182.1906)
			(xy 410.677194 -182.237466) (xy 410.697511 -182.288016) (xy 410.709895 -182.34107) (xy 410.714056 -182.395391)
			(xy 410.709898 -182.449713) (xy 410.697517 -182.502767) (xy 410.677201 -182.553318) (xy 410.649426 -182.600186)
			(xy 410.614838 -182.642279) (xy 410.574244 -182.678614) (xy 410.528591 -182.708345) (xy 410.478944 -182.730777)
			(xy 410.452824 -182.738522) (xy 410.41574 -182.748682) (xy 410.41574 -183.032654) (xy 416.45332 -183.032654)
			(xy 416.45332 -182.364126) (xy 416.453938 -182.33415) (xy 416.463323 -182.274936) (xy 416.481852 -182.217919)
			(xy 416.509069 -182.1645) (xy 416.544303 -182.115993) (xy 416.56508 -182.094378) (xy 416.818572 -181.840886)
			(xy 416.818572 -179.622196) (xy 416.56508 -179.368704) (xy 416.544256 -179.347127) (xy 416.509006 -179.298619)
			(xy 416.481781 -179.245192) (xy 416.463251 -179.188164) (xy 416.453874 -179.128938) (xy 416.45332 -179.098956)
			(xy 416.45332 -174.051214) (xy 416.45393 -174.021238) (xy 416.463318 -173.962024) (xy 416.481848 -173.905006)
			(xy 416.509066 -173.851587) (xy 416.544302 -173.803081) (xy 416.56508 -173.781466) (xy 416.955732 -173.390814)
			(xy 416.955732 -171.052236) (xy 416.56508 -170.661584) (xy 416.544247 -170.640016) (xy 416.508998 -170.591505)
			(xy 416.481774 -170.538077) (xy 416.463247 -170.481046) (xy 416.453873 -170.421818) (xy 416.45332 -170.391836)
			(xy 416.45332 -165.760654) (xy 416.453708 -165.736844) (xy 416.459712 -165.689604) (xy 416.47157 -165.643483)
			(xy 416.47999 -165.621208) (xy 416.483292 -165.612064) (xy 416.483292 -164.955728) (xy 416.48389 -164.925751)
			(xy 416.493278 -164.866536) (xy 416.51181 -164.809517) (xy 416.539031 -164.756098) (xy 416.574271 -164.707594)
			(xy 416.595052 -164.68598) (xy 416.958272 -164.32276) (xy 416.958272 -162.30727) (xy 416.828732 -162.17773)
			(xy 416.80793 -162.156133) (xy 416.772675 -162.107631) (xy 416.745444 -162.05421) (xy 416.72691 -161.997185)
			(xy 416.717529 -161.937963) (xy 416.716972 -161.907982) (xy 416.716972 -158.158688) (xy 416.717551 -158.12871)
			(xy 416.726944 -158.069494) (xy 416.745481 -158.012476) (xy 416.772706 -157.959057) (xy 416.80795 -157.910553)
			(xy 416.828732 -157.88894) (xy 418.781992 -155.93568) (xy 418.803571 -155.914858) (xy 418.852078 -155.879608)
			(xy 418.905504 -155.852382) (xy 418.962533 -155.833852) (xy 419.021758 -155.824475) (xy 419.05174 -155.82392)
			(xy 421.643302 -155.82392) (xy 421.904922 -155.5623) (xy 421.926491 -155.541467) (xy 421.975001 -155.506217)
			(xy 422.028429 -155.478993) (xy 422.08546 -155.460466) (xy 422.144688 -155.451092) (xy 422.17467 -155.45054)
			(xy 423.88663 -155.45054) (xy 423.916608 -155.451117) (xy 423.975823 -155.460512) (xy 424.032842 -155.47905)
			(xy 424.08626 -155.506275) (xy 424.134764 -155.541518) (xy 424.156378 -155.5623) (xy 424.296586 -155.702508)
			(xy 424.317328 -155.724144) (xy 424.352516 -155.772659) (xy 424.379687 -155.826079) (xy 424.398172 -155.88309)
			(xy 424.407518 -155.942289) (xy 424.408092 -155.972256) (xy 424.407582 -155.999495) (xy 424.399837 -156.053421)
			(xy 424.3845 -156.105696) (xy 424.361881 -156.155257) (xy 424.332442 -156.201096) (xy 424.29678 -156.24228)
			(xy 424.255622 -156.277972) (xy 424.209805 -156.307446) (xy 424.16026 -156.330101) (xy 424.107997 -156.345477)
			(xy 424.054077 -156.353261) (xy 424.026838 -156.353764) (xy 423.996862 -156.353143) (xy 423.937648 -156.343759)
			(xy 423.880631 -156.325231) (xy 423.827212 -156.298015) (xy 423.778705 -156.262781) (xy 423.75709 -156.242004)
			(xy 423.728642 -156.213556) (xy 422.332658 -156.213556) (xy 422.071038 -156.475176) (xy 422.049439 -156.495976)
			(xy 422.000938 -156.531231) (xy 421.947517 -156.558462) (xy 421.890493 -156.576997) (xy 421.83127 -156.586379)
			(xy 421.80129 -156.586936) (xy 419.209728 -156.586936) (xy 418.836602 -156.960062) (xy 422.378122 -156.960062)
			(xy 422.382193 -156.90444) (xy 422.394319 -156.850003) (xy 422.414242 -156.797912) (xy 422.441538 -156.749277)
			(xy 422.475624 -156.705134) (xy 422.515773 -156.666425) (xy 422.561131 -156.633974) (xy 422.610731 -156.608473)
			(xy 422.663515 -156.590466) (xy 422.718358 -156.580336) (xy 422.774092 -156.578299) (xy 422.829529 -156.584399)
			(xy 422.883486 -156.598505) (xy 422.934815 -156.620317) (xy 422.982421 -156.649371) (xy 423.025289 -156.685046)
			(xy 423.062506 -156.726583) (xy 423.093279 -156.773096) (xy 423.116951 -156.823593) (xy 423.133019 -156.877)
			(xy 423.133431 -156.879798) (xy 423.523662 -156.879798) (xy 423.527733 -156.824176) (xy 423.539859 -156.769739)
			(xy 423.559782 -156.717648) (xy 423.587078 -156.669013) (xy 423.621164 -156.62487) (xy 423.661313 -156.586161)
			(xy 423.706671 -156.55371) (xy 423.756271 -156.528209) (xy 423.809055 -156.510202) (xy 423.863898 -156.500072)
			(xy 423.919632 -156.498035) (xy 423.975069 -156.504135) (xy 424.029026 -156.518241) (xy 424.080355 -156.540053)
			(xy 424.127961 -156.569107) (xy 424.170829 -156.604782) (xy 424.208046 -156.646319) (xy 424.238819 -156.692832)
			(xy 424.262491 -156.743329) (xy 424.278559 -156.796736) (xy 424.286679 -156.851912) (xy 424.287188 -156.879798)
			(xy 424.286679 -156.907684) (xy 424.278559 -156.96286) (xy 424.262491 -157.016267) (xy 424.238819 -157.066764)
			(xy 424.208046 -157.113277) (xy 424.170829 -157.154814) (xy 424.127961 -157.190489) (xy 424.080355 -157.219543)
			(xy 424.029026 -157.241355) (xy 423.975069 -157.255461) (xy 423.919632 -157.261561) (xy 423.863898 -157.259524)
			(xy 423.809055 -157.249394) (xy 423.756271 -157.231387) (xy 423.706671 -157.205886) (xy 423.661313 -157.173435)
			(xy 423.621164 -157.134726) (xy 423.587078 -157.090583) (xy 423.559782 -157.041948) (xy 423.539859 -156.989857)
			(xy 423.527733 -156.93542) (xy 423.523662 -156.879798) (xy 423.133431 -156.879798) (xy 423.141139 -156.932176)
			(xy 423.141648 -156.960062) (xy 423.141139 -156.987948) (xy 423.133019 -157.043124) (xy 423.116951 -157.096531)
			(xy 423.093279 -157.147028) (xy 423.062506 -157.193541) (xy 423.025289 -157.235078) (xy 422.982421 -157.270753)
			(xy 422.934815 -157.299807) (xy 422.883486 -157.321619) (xy 422.829529 -157.335725) (xy 422.774092 -157.341825)
			(xy 422.718358 -157.339788) (xy 422.663515 -157.329658) (xy 422.610731 -157.311651) (xy 422.561131 -157.28615)
			(xy 422.515773 -157.253699) (xy 422.475624 -157.21499) (xy 422.441538 -157.170847) (xy 422.414242 -157.122212)
			(xy 422.394319 -157.070121) (xy 422.382193 -157.015684) (xy 422.378122 -156.960062) (xy 418.836602 -156.960062)
			(xy 418.148516 -157.648148) (xy 419.535862 -157.648148) (xy 419.539933 -157.592526) (xy 419.552059 -157.538089)
			(xy 419.571982 -157.485998) (xy 419.599278 -157.437363) (xy 419.633364 -157.39322) (xy 419.673513 -157.354511)
			(xy 419.718871 -157.32206) (xy 419.768471 -157.296559) (xy 419.821255 -157.278552) (xy 419.876098 -157.268422)
			(xy 419.931832 -157.266385) (xy 419.987269 -157.272485) (xy 420.041226 -157.286591) (xy 420.092555 -157.308403)
			(xy 420.140161 -157.337457) (xy 420.183029 -157.373132) (xy 420.220246 -157.414669) (xy 420.251019 -157.461182)
			(xy 420.274691 -157.511679) (xy 420.290759 -157.565086) (xy 420.298879 -157.620262) (xy 420.299388 -157.648148)
			(xy 420.298879 -157.676034) (xy 420.290759 -157.73121) (xy 420.274691 -157.784617) (xy 420.251019 -157.835114)
			(xy 420.220246 -157.881627) (xy 420.183029 -157.923164) (xy 420.140161 -157.958839) (xy 420.092555 -157.987893)
			(xy 420.041226 -158.009705) (xy 419.987269 -158.023811) (xy 419.931832 -158.029911) (xy 419.876098 -158.027874)
			(xy 419.821255 -158.017744) (xy 419.768471 -157.999737) (xy 419.718871 -157.974236) (xy 419.673513 -157.941785)
			(xy 419.633364 -157.903076) (xy 419.599278 -157.858933) (xy 419.571982 -157.810298) (xy 419.552059 -157.758207)
			(xy 419.539933 -157.70377) (xy 419.535862 -157.648148) (xy 418.148516 -157.648148) (xy 417.479988 -158.316676)
			(xy 417.479988 -159.962342) (xy 417.480485 -159.976525) (xy 417.4883 -160.003792) (xy 417.503314 -160.027858)
			(xy 417.52437 -160.046865) (xy 417.549842 -160.059346) (xy 417.577764 -160.064338) (xy 417.605983 -160.061457)
			(xy 417.63232 -160.050923) (xy 417.643818 -160.042606) (xy 417.652388 -160.035997) (xy 417.67018 -160.023672)
			(xy 417.679378 -160.017968) (xy 417.691605 -160.010048) (xy 417.711279 -159.988577) (xy 417.724084 -159.962423)
			(xy 417.728979 -159.933716) (xy 417.725563 -159.904796) (xy 417.720272 -159.891222) (xy 417.710796 -159.868007)
			(xy 417.69744 -159.819677) (xy 417.690706 -159.769989) (xy 417.6903 -159.744918) (xy 417.690766 -159.718075)
			(xy 417.698468 -159.664945) (xy 417.713716 -159.61347) (xy 417.736193 -159.564717) (xy 417.765435 -159.519694)
			(xy 417.800836 -159.479334) (xy 417.841662 -159.444472) (xy 417.887069 -159.415831) (xy 417.936117 -159.394002)
			(xy 417.961826 -159.38627) (xy 417.976329 -159.38162) (xy 418.0019 -159.365103) (xy 418.021469 -159.341785)
			(xy 418.033299 -159.313737) (xy 418.03634 -159.283448) (xy 418.030322 -159.253608) (xy 418.023548 -159.239966)
			(xy 418.00892 -159.211818) (xy 417.988191 -159.151868) (xy 417.977691 -159.08931) (xy 417.977066 -159.057594)
			(xy 417.977291 -159.039575) (xy 417.980722 -159.0037) (xy 417.983924 -158.985966) (xy 417.986322 -158.970764)
			(xy 417.982784 -158.940201) (xy 417.97031 -158.912077) (xy 417.95003 -158.888941) (xy 417.923782 -158.872889)
			(xy 417.908994 -158.868618) (xy 417.881967 -158.861164) (xy 417.830242 -158.839542) (xy 417.782237 -158.810585)
			(xy 417.738984 -158.774917) (xy 417.701416 -158.733305) (xy 417.670339 -158.686645) (xy 417.646423 -158.63594)
			(xy 417.630183 -158.582282) (xy 417.621967 -158.526825) (xy 417.621466 -158.498794) (xy 417.621972 -158.471544)
			(xy 417.629729 -158.417598) (xy 417.645083 -158.365305) (xy 417.667723 -158.31573) (xy 417.697188 -158.269881)
			(xy 417.732877 -158.228691) (xy 417.774065 -158.193) (xy 417.819912 -158.163533) (xy 417.869487 -158.14089)
			(xy 417.921779 -158.125533) (xy 417.975724 -158.117774) (xy 418.002974 -158.117286) (xy 418.030548 -158.117774)
			(xy 418.085119 -158.125723) (xy 418.137979 -158.141444) (xy 418.188024 -158.16461) (xy 418.234215 -158.194738)
			(xy 418.275587 -158.231201) (xy 418.293804 -158.251906) (xy 418.303702 -158.262804) (xy 418.328352 -158.278879)
			(xy 418.35656 -158.287263) (xy 418.385988 -158.287263) (xy 418.414196 -158.278879) (xy 418.438846 -158.262804)
			(xy 418.448744 -158.251906) (xy 418.466959 -158.2312) (xy 418.50833 -158.194735) (xy 418.55452 -158.164608)
			(xy 418.604567 -158.141445) (xy 418.657428 -158.125729) (xy 418.712 -158.117789) (xy 418.767148 -158.117789)
			(xy 418.82172 -158.125729) (xy 418.874581 -158.141445) (xy 418.924628 -158.164608) (xy 418.970818 -158.194735)
			(xy 419.012189 -158.2312) (xy 419.030404 -158.251906) (xy 419.040302 -158.262804) (xy 419.064952 -158.278879)
			(xy 419.09316 -158.287263) (xy 419.122588 -158.287263) (xy 419.150796 -158.278879) (xy 419.175446 -158.262804)
			(xy 419.185344 -158.251906) (xy 419.203582 -158.23122) (xy 419.244945 -158.194747) (xy 419.291129 -158.164612)
			(xy 419.341172 -158.141442) (xy 419.39403 -158.12572) (xy 419.448601 -158.117775) (xy 419.476174 -158.117286)
			(xy 419.503426 -158.117779) (xy 419.557375 -158.125533) (xy 419.609672 -158.140885) (xy 419.659252 -158.163524)
			(xy 419.705105 -158.192989) (xy 419.746298 -158.22868) (xy 419.781992 -158.269869) (xy 419.81146 -158.31572)
			(xy 419.834104 -158.365298) (xy 419.84946 -158.417593) (xy 419.857218 -158.471542) (xy 419.857682 -158.498794)
			(xy 419.857167 -158.52665) (xy 419.849043 -158.581766) (xy 419.832998 -158.635117) (xy 419.80937 -158.685571)
			(xy 419.778663 -158.732056) (xy 419.741526 -158.773585) (xy 419.69875 -158.809278) (xy 419.651241 -158.838376)
			(xy 419.600008 -158.860262) (xy 419.573202 -158.867856) (xy 419.559077 -158.872105) (xy 419.53393 -158.887501)
			(xy 419.514215 -158.909425) (xy 419.501566 -158.93606) (xy 419.497034 -158.965195) (xy 419.498526 -158.97987)
			(xy 419.5002 -158.992886) (xy 419.501977 -159.019071) (xy 419.502082 -159.032194) (xy 419.501988 -159.046343)
			(xy 419.499954 -159.074566) (xy 419.498018 -159.088582) (xy 419.496394 -159.101927) (xy 419.4995 -159.128623)
			(xy 419.509476 -159.153579) (xy 419.525629 -159.17506) (xy 419.546835 -159.191572) (xy 419.57162 -159.201966)
			(xy 419.584886 -159.204152) (xy 419.612039 -159.208237) (xy 419.664868 -159.223214) (xy 419.715004 -159.245609)
			(xy 419.761412 -159.274958) (xy 419.803135 -159.310656) (xy 419.839311 -159.351965) (xy 419.869192 -159.398033)
			(xy 419.892162 -159.447908) (xy 419.907746 -159.500561) (xy 419.915622 -159.554903) (xy 419.916102 -159.582358)
			(xy 419.915606 -159.60961) (xy 419.907854 -159.66356) (xy 419.892503 -159.715858) (xy 419.869865 -159.765438)
			(xy 419.840401 -159.811292) (xy 419.804711 -159.852485) (xy 419.763521 -159.888179) (xy 419.71767 -159.917648)
			(xy 419.668092 -159.940291) (xy 419.615795 -159.955647) (xy 419.561846 -159.963403) (xy 419.534594 -159.963866)
			(xy 419.507019 -159.963416) (xy 419.452445 -159.955462) (xy 419.399584 -159.939735) (xy 419.349538 -159.916562)
			(xy 419.303349 -159.886426) (xy 419.261979 -159.849955) (xy 419.243764 -159.829246) (xy 419.233866 -159.818348)
			(xy 419.209216 -159.802273) (xy 419.181008 -159.793889) (xy 419.15158 -159.793889) (xy 419.123372 -159.802273)
			(xy 419.098722 -159.818348) (xy 419.088824 -159.829246) (xy 419.070614 -159.849958) (xy 419.029244 -159.886426)
			(xy 418.983053 -159.916557) (xy 418.933005 -159.939722) (xy 418.880143 -159.955439) (xy 418.825569 -159.96338)
			(xy 418.797994 -159.963866) (xy 418.771493 -159.963405) (xy 418.719002 -159.956063) (xy 418.668034 -159.941521)
			(xy 418.619572 -159.920059) (xy 418.574549 -159.892091) (xy 418.5539 -159.875474) (xy 418.541717 -159.866082)
			(xy 418.51333 -159.854285) (xy 418.482719 -159.851451) (xy 418.452648 -159.857838) (xy 418.425831 -159.872868)
			(xy 418.404689 -159.895186) (xy 418.397436 -159.908748) (xy 418.385321 -159.93243) (xy 418.355402 -159.976413)
			(xy 418.319535 -160.015696) (xy 418.278448 -160.049482) (xy 418.255958 -160.063688) (xy 418.243751 -160.071635)
			(xy 418.224085 -160.093102) (xy 418.211281 -160.119249) (xy 418.206381 -160.147947) (xy 418.209783 -160.176861)
			(xy 418.215064 -160.190434) (xy 418.22456 -160.213641) (xy 418.237908 -160.261976) (xy 418.244633 -160.311666)
			(xy 418.245036 -160.336738) (xy 418.244615 -160.361807) (xy 418.237865 -160.411491) (xy 418.224531 -160.459825)
			(xy 418.215064 -160.483042) (xy 418.209854 -160.496631) (xy 418.206485 -160.525525) (xy 418.211389 -160.554198)
			(xy 418.224168 -160.58033) (xy 418.243789 -160.601805) (xy 418.255958 -160.609788) (xy 418.27905 -160.624416)
			(xy 418.321167 -160.659255) (xy 418.357742 -160.699872) (xy 418.387993 -160.745397) (xy 418.411268 -160.794852)
			(xy 418.427069 -160.847177) (xy 418.435057 -160.901249) (xy 418.43506 -160.955908) (xy 418.427078 -161.00998)
			(xy 418.411283 -161.062307) (xy 418.388014 -161.111765) (xy 418.357769 -161.157294) (xy 418.321198 -161.197915)
			(xy 418.279085 -161.232759) (xy 418.255958 -161.247328) (xy 418.243724 -161.255237) (xy 418.224058 -161.276714)
			(xy 418.211257 -161.302871) (xy 418.206364 -161.331578) (xy 418.209777 -161.360499) (xy 418.215064 -161.374074)
			(xy 418.224541 -161.397289) (xy 418.237896 -161.445619) (xy 418.244629 -161.495307) (xy 418.245036 -161.520378)
			(xy 418.244545 -161.546994) (xy 418.236973 -161.599686) (xy 418.221978 -161.650763) (xy 418.199867 -161.699187)
			(xy 418.17109 -161.743971) (xy 418.136232 -161.784203) (xy 418.096003 -161.819066) (xy 418.051222 -161.847848)
			(xy 418.002801 -161.869964) (xy 417.951725 -161.884964) (xy 417.899034 -161.892543) (xy 417.872418 -161.892996)
			(xy 417.85717 -161.892815) (xy 417.826779 -161.890268) (xy 417.811712 -161.887916) (xy 417.796754 -161.886023)
			(xy 417.766891 -161.890068) (xy 417.739503 -161.902639) (xy 417.716966 -161.922646) (xy 417.701238 -161.948351)
			(xy 417.693684 -161.977525) (xy 417.694958 -162.007633) (xy 417.699444 -162.022028) (xy 417.709653 -162.052845)
			(xy 417.720636 -162.116824) (xy 417.721288 -162.149282) (xy 417.721288 -164.19025) (xy 419.374572 -164.19025)
			(xy 419.374572 -164.13575) (xy 419.382328 -164.081803) (xy 419.397682 -164.02951) (xy 419.420321 -163.979933)
			(xy 419.449786 -163.934084) (xy 419.485475 -163.892893) (xy 419.526663 -163.857201) (xy 419.572511 -163.827734)
			(xy 419.622085 -163.805091) (xy 419.674378 -163.789733) (xy 419.728324 -163.781974) (xy 419.755574 -163.781486)
			(xy 419.785261 -163.782065) (xy 419.843919 -163.79126) (xy 419.900444 -163.809431) (xy 419.953471 -163.836139)
			(xy 420.001721 -163.870741) (xy 420.044027 -163.912399) (xy 420.062152 -163.935918) (xy 420.070578 -163.946525)
			(xy 420.091891 -163.963232) (xy 420.116845 -163.973751) (xy 420.143686 -163.977341) (xy 420.170527 -163.973751)
			(xy 420.195481 -163.963232) (xy 420.216794 -163.946525) (xy 420.22522 -163.935918) (xy 420.243349 -163.912402)
			(xy 420.285654 -163.870741) (xy 420.333902 -163.836136) (xy 420.386928 -163.809424) (xy 420.443453 -163.79125)
			(xy 420.502111 -163.782051) (xy 420.531798 -163.781486) (xy 420.559051 -163.781961) (xy 420.613001 -163.789718)
			(xy 420.665298 -163.805073) (xy 420.714878 -163.827715) (xy 420.76073 -163.857183) (xy 420.801923 -163.892876)
			(xy 420.837616 -163.934068) (xy 420.867084 -163.979921) (xy 420.889726 -164.0295) (xy 420.905082 -164.081797)
			(xy 420.912839 -164.135747) (xy 420.912839 -164.190253) (xy 420.905082 -164.244203) (xy 420.889726 -164.2965)
			(xy 420.867084 -164.346079) (xy 420.837616 -164.391932) (xy 420.801923 -164.433124) (xy 420.76073 -164.468817)
			(xy 420.714878 -164.498285) (xy 420.665298 -164.520927) (xy 420.613001 -164.536282) (xy 420.559051 -164.544039)
			(xy 420.531798 -164.544502) (xy 420.50211 -164.543948) (xy 420.443451 -164.534749) (xy 420.386925 -164.516573)
			(xy 420.333898 -164.48986) (xy 420.285649 -164.455254) (xy 420.243344 -164.413591) (xy 420.22522 -164.39007)
			(xy 420.216794 -164.379463) (xy 420.195481 -164.362756) (xy 420.170527 -164.352237) (xy 420.143686 -164.348647)
			(xy 420.116845 -164.352237) (xy 420.091891 -164.362756) (xy 420.070578 -164.379463) (xy 420.062152 -164.39007)
			(xy 420.044036 -164.413597) (xy 420.001729 -164.455258) (xy 419.953478 -164.489861) (xy 419.900449 -164.516572)
			(xy 419.843922 -164.534744) (xy 419.785262 -164.543939) (xy 419.755574 -164.544502) (xy 419.728324 -164.544026)
			(xy 419.674378 -164.536267) (xy 419.622085 -164.520909) (xy 419.572511 -164.498266) (xy 419.526663 -164.468799)
			(xy 419.485475 -164.433107) (xy 419.449786 -164.391916) (xy 419.420321 -164.346067) (xy 419.397682 -164.29649)
			(xy 419.382328 -164.244197) (xy 419.374572 -164.19025) (xy 417.721288 -164.19025) (xy 417.721288 -164.480748)
			(xy 417.720652 -164.510723) (xy 417.71127 -164.569936) (xy 417.692745 -164.626953) (xy 417.665533 -164.680372)
			(xy 417.630303 -164.72888) (xy 417.609528 -164.750496) (xy 417.418071 -164.941953) (xy 418.557175 -164.941953)
			(xy 418.564931 -164.888006) (xy 418.580286 -164.835711) (xy 418.602926 -164.786133) (xy 418.632392 -164.740282)
			(xy 418.668083 -164.699091) (xy 418.709272 -164.663399) (xy 418.755122 -164.633932) (xy 418.804699 -164.61129)
			(xy 418.856994 -164.595934) (xy 418.910941 -164.588176) (xy 418.965444 -164.588175) (xy 419.019392 -164.595931)
			(xy 419.071687 -164.611285) (xy 419.121265 -164.633925) (xy 419.167116 -164.66339) (xy 419.208307 -164.699081)
			(xy 419.243999 -164.74027) (xy 419.273467 -164.78612) (xy 419.296109 -164.835697) (xy 419.311466 -164.887991)
			(xy 419.319224 -164.941939) (xy 419.31971 -164.96919) (xy 419.319282 -164.994581) (xy 419.312524 -165.044913)
			(xy 419.306248 -165.06952) (xy 419.302808 -165.084167) (xy 419.303729 -165.114225) (xy 419.31336 -165.142715)
			(xy 419.330866 -165.167167) (xy 419.354731 -165.185465) (xy 419.38289 -165.196023) (xy 419.412902 -165.197929)
			(xy 419.42766 -165.194996) (xy 419.449255 -165.190239) (xy 419.49318 -165.18514) (xy 419.51529 -165.184836)
			(xy 419.542541 -165.185267) (xy 419.59649 -165.193022) (xy 419.648785 -165.208376) (xy 419.698364 -165.231015)
			(xy 419.744216 -165.26048) (xy 419.785408 -165.29617) (xy 419.821101 -165.337359) (xy 419.85057 -165.383209)
			(xy 419.873213 -165.432785) (xy 419.888571 -165.48508) (xy 419.896331 -165.539027) (xy 419.896334 -165.59353)
			(xy 419.88858 -165.647479) (xy 419.873228 -165.699775) (xy 419.85059 -165.749354) (xy 419.821127 -165.795207)
			(xy 419.785438 -165.8364) (xy 419.74425 -165.872094) (xy 419.698401 -165.901564) (xy 419.648825 -165.924209)
			(xy 419.596532 -165.939569) (xy 419.542584 -165.94733) (xy 419.488081 -165.947335) (xy 419.434132 -165.939583)
			(xy 419.381836 -165.924232) (xy 419.332256 -165.901596) (xy 419.286403 -165.872134) (xy 419.245208 -165.836446)
			(xy 419.209512 -165.795259) (xy 419.180041 -165.749411) (xy 419.157395 -165.699836) (xy 419.142034 -165.647543)
			(xy 419.134271 -165.593595) (xy 419.133782 -165.566344) (xy 419.134216 -165.540953) (xy 419.14097 -165.490622)
			(xy 419.147244 -165.466014) (xy 419.150657 -165.451361) (xy 419.149744 -165.421304) (xy 419.14012 -165.392815)
			(xy 419.122618 -165.368362) (xy 419.098755 -165.350064) (xy 419.070599 -165.339507) (xy 419.040588 -165.337604)
			(xy 419.025832 -165.340538) (xy 419.004238 -165.345297) (xy 418.960312 -165.350394) (xy 418.938202 -165.350698)
			(xy 418.910951 -165.350224) (xy 418.857003 -165.342468) (xy 418.804708 -165.327113) (xy 418.755131 -165.304473)
			(xy 418.70928 -165.275007) (xy 418.668089 -165.239315) (xy 418.632397 -165.198125) (xy 418.602931 -165.152275)
			(xy 418.580289 -165.102698) (xy 418.564933 -165.050404) (xy 418.557176 -164.996456) (xy 418.557175 -164.941953)
			(xy 417.418071 -164.941953) (xy 417.246308 -165.113716) (xy 417.246308 -165.293294) (xy 417.246741 -165.306565)
			(xy 417.253586 -165.332209) (xy 417.266813 -165.35522) (xy 417.285529 -165.37404) (xy 417.308466 -165.387396)
			(xy 417.334072 -165.394384) (xy 417.360613 -165.39453) (xy 417.373562 -165.391592) (xy 417.397199 -165.385761)
			(xy 417.445485 -165.379524) (xy 417.469828 -165.379146) (xy 417.497075 -165.379726) (xy 417.551013 -165.387485)
			(xy 417.603298 -165.402841) (xy 417.652865 -165.425481) (xy 417.698707 -165.454944) (xy 417.739889 -165.490631)
			(xy 417.775573 -165.531816) (xy 417.805033 -165.577659) (xy 417.827669 -165.627228) (xy 417.843021 -165.679515)
			(xy 417.850776 -165.733453) (xy 417.850776 -165.787947) (xy 417.843021 -165.841885) (xy 417.827669 -165.894172)
			(xy 417.805033 -165.943741) (xy 417.775573 -165.989584) (xy 417.739889 -166.030769) (xy 417.698707 -166.066456)
			(xy 417.652865 -166.095919) (xy 417.603298 -166.118559) (xy 417.551013 -166.133915) (xy 417.497075 -166.141674)
			(xy 417.469828 -166.142162) (xy 417.439259 -166.141593) (xy 417.378896 -166.131892) (xy 417.349686 -166.122858)
			(xy 417.336504 -166.119068) (xy 417.309124 -166.117736) (xy 417.282378 -166.123741) (xy 417.258195 -166.136648)
			(xy 417.238321 -166.155528) (xy 417.224189 -166.179016) (xy 417.21682 -166.205419) (xy 417.216336 -166.219124)
			(xy 417.216336 -170.156378) (xy 417.4998 -170.156378) (xy 417.500317 -170.129048) (xy 417.50828 -170.074971)
			(xy 417.524061 -170.022638) (xy 417.547322 -169.973175) (xy 417.577563 -169.927642) (xy 417.614133 -169.887018)
			(xy 417.656249 -169.852176) (xy 417.679378 -169.837608) (xy 417.691578 -169.82965) (xy 417.711251 -169.808189)
			(xy 417.724061 -169.782045) (xy 417.728962 -169.753347) (xy 417.725556 -169.724434) (xy 417.720272 -169.710862)
			(xy 417.710777 -169.687654) (xy 417.697428 -169.63932) (xy 417.690702 -169.58963) (xy 417.6903 -169.564558)
			(xy 417.690724 -169.539489) (xy 417.697474 -169.489806) (xy 417.710806 -169.441471) (xy 417.720272 -169.418254)
			(xy 417.725563 -169.404687) (xy 417.728937 -169.375773) (xy 417.724027 -169.347079) (xy 417.711231 -169.32093)
			(xy 417.691587 -169.299447) (xy 417.679378 -169.291508) (xy 417.656281 -169.276887) (xy 417.61416 -169.24205)
			(xy 417.57758 -169.201433) (xy 417.547327 -169.155907) (xy 417.52405 -169.106451) (xy 417.508247 -169.054124)
			(xy 417.500259 -169.00005) (xy 417.500256 -168.945389) (xy 417.508238 -168.891314) (xy 417.524036 -168.838986)
			(xy 417.547308 -168.789527) (xy 417.577556 -168.743998) (xy 417.614131 -168.703377) (xy 417.656249 -168.668536)
			(xy 417.679378 -168.653968) (xy 417.691605 -168.646048) (xy 417.711279 -168.624577) (xy 417.724084 -168.598423)
			(xy 417.728979 -168.569716) (xy 417.725563 -168.540796) (xy 417.720272 -168.527222) (xy 417.710796 -168.504007)
			(xy 417.69744 -168.455677) (xy 417.690706 -168.405989) (xy 417.6903 -168.380918) (xy 417.690766 -168.354075)
			(xy 417.698468 -168.300945) (xy 417.713716 -168.24947) (xy 417.736193 -168.200717) (xy 417.765435 -168.155694)
			(xy 417.800836 -168.115334) (xy 417.841662 -168.080472) (xy 417.887069 -168.051831) (xy 417.936117 -168.030002)
			(xy 417.961826 -168.02227) (xy 417.976329 -168.01762) (xy 418.0019 -168.001103) (xy 418.021469 -167.977785)
			(xy 418.033299 -167.949737) (xy 418.03634 -167.919448) (xy 418.030322 -167.889608) (xy 418.023548 -167.875966)
			(xy 418.00892 -167.847818) (xy 417.988191 -167.787868) (xy 417.977691 -167.72531) (xy 417.977066 -167.693594)
			(xy 417.977291 -167.675575) (xy 417.980722 -167.6397) (xy 417.983924 -167.621966) (xy 417.986322 -167.606764)
			(xy 417.982784 -167.576201) (xy 417.97031 -167.548077) (xy 417.95003 -167.524941) (xy 417.923782 -167.508889)
			(xy 417.908994 -167.504618) (xy 417.881967 -167.497164) (xy 417.830242 -167.475542) (xy 417.782237 -167.446585)
			(xy 417.738984 -167.410917) (xy 417.701416 -167.369305) (xy 417.670339 -167.322645) (xy 417.646423 -167.27194)
			(xy 417.630183 -167.218282) (xy 417.621967 -167.162825) (xy 417.621466 -167.134794) (xy 417.621972 -167.107544)
			(xy 417.629729 -167.053598) (xy 417.645083 -167.001305) (xy 417.667723 -166.95173) (xy 417.697188 -166.905881)
			(xy 417.732877 -166.864691) (xy 417.774065 -166.829) (xy 417.819912 -166.799533) (xy 417.869487 -166.77689)
			(xy 417.921779 -166.761533) (xy 417.975724 -166.753774) (xy 418.002974 -166.753286) (xy 418.030548 -166.753774)
			(xy 418.085119 -166.761723) (xy 418.137979 -166.777444) (xy 418.188024 -166.80061) (xy 418.234215 -166.830738)
			(xy 418.275587 -166.867201) (xy 418.293804 -166.887906) (xy 418.303702 -166.898804) (xy 418.328352 -166.914879)
			(xy 418.35656 -166.923263) (xy 418.385988 -166.923263) (xy 418.414196 -166.914879) (xy 418.438846 -166.898804)
			(xy 418.448744 -166.887906) (xy 418.466959 -166.8672) (xy 418.50833 -166.830735) (xy 418.55452 -166.800608)
			(xy 418.604567 -166.777445) (xy 418.657428 -166.761729) (xy 418.712 -166.753789) (xy 418.767148 -166.753789)
			(xy 418.82172 -166.761729) (xy 418.874581 -166.777445) (xy 418.924628 -166.800608) (xy 418.970818 -166.830735)
			(xy 419.012189 -166.8672) (xy 419.030404 -166.887906) (xy 419.040302 -166.898804) (xy 419.064952 -166.914879)
			(xy 419.09316 -166.923263) (xy 419.122588 -166.923263) (xy 419.150796 -166.914879) (xy 419.175446 -166.898804)
			(xy 419.185344 -166.887906) (xy 419.203582 -166.86722) (xy 419.244945 -166.830747) (xy 419.291129 -166.800612)
			(xy 419.341172 -166.777442) (xy 419.39403 -166.76172) (xy 419.448601 -166.753775) (xy 419.476174 -166.753286)
			(xy 419.503426 -166.753779) (xy 419.557375 -166.761533) (xy 419.609672 -166.776885) (xy 419.659252 -166.799524)
			(xy 419.705105 -166.828989) (xy 419.746298 -166.86468) (xy 419.781992 -166.905869) (xy 419.81146 -166.95172)
			(xy 419.834104 -167.001298) (xy 419.84946 -167.053593) (xy 419.857218 -167.107542) (xy 419.857682 -167.134794)
			(xy 419.857167 -167.16265) (xy 419.849043 -167.217766) (xy 419.832998 -167.271117) (xy 419.80937 -167.321571)
			(xy 419.778663 -167.368056) (xy 419.741526 -167.409585) (xy 419.69875 -167.445278) (xy 419.651241 -167.474376)
			(xy 419.600008 -167.496262) (xy 419.573202 -167.503856) (xy 419.559077 -167.508105) (xy 419.53393 -167.523501)
			(xy 419.514215 -167.545425) (xy 419.501566 -167.57206) (xy 419.497034 -167.601195) (xy 419.498526 -167.61587)
			(xy 419.5002 -167.628886) (xy 419.501977 -167.655071) (xy 419.502082 -167.668194) (xy 419.501988 -167.682343)
			(xy 419.499954 -167.710566) (xy 419.498018 -167.724582) (xy 419.496394 -167.737927) (xy 419.4995 -167.764623)
			(xy 419.509476 -167.789579) (xy 419.525629 -167.81106) (xy 419.546835 -167.827572) (xy 419.57162 -167.837966)
			(xy 419.584886 -167.840152) (xy 419.612039 -167.844237) (xy 419.664868 -167.859214) (xy 419.715004 -167.881609)
			(xy 419.761412 -167.910958) (xy 419.803135 -167.946656) (xy 419.839311 -167.987965) (xy 419.869192 -168.034033)
			(xy 419.892162 -168.083908) (xy 419.907746 -168.136561) (xy 419.915622 -168.190903) (xy 419.916102 -168.218358)
			(xy 419.915606 -168.24561) (xy 419.907854 -168.29956) (xy 419.892503 -168.351858) (xy 419.869865 -168.401438)
			(xy 419.840401 -168.447292) (xy 419.804711 -168.488485) (xy 419.763521 -168.524179) (xy 419.71767 -168.553648)
			(xy 419.668092 -168.576291) (xy 419.615795 -168.591647) (xy 419.561846 -168.599403) (xy 419.534594 -168.599866)
			(xy 419.507019 -168.599416) (xy 419.452445 -168.591462) (xy 419.399584 -168.575735) (xy 419.349538 -168.552562)
			(xy 419.303349 -168.522426) (xy 419.261979 -168.485955) (xy 419.243764 -168.465246) (xy 419.233866 -168.454348)
			(xy 419.209216 -168.438273) (xy 419.181008 -168.429889) (xy 419.15158 -168.429889) (xy 419.123372 -168.438273)
			(xy 419.098722 -168.454348) (xy 419.088824 -168.465246) (xy 419.070614 -168.485958) (xy 419.029244 -168.522426)
			(xy 418.983053 -168.552557) (xy 418.933005 -168.575722) (xy 418.880143 -168.591439) (xy 418.825569 -168.59938)
			(xy 418.797994 -168.599866) (xy 418.771493 -168.599405) (xy 418.719002 -168.592063) (xy 418.668034 -168.577521)
			(xy 418.619572 -168.556059) (xy 418.574549 -168.528091) (xy 418.5539 -168.511474) (xy 418.541717 -168.502082)
			(xy 418.51333 -168.490285) (xy 418.482719 -168.487451) (xy 418.452648 -168.493838) (xy 418.425831 -168.508868)
			(xy 418.404689 -168.531186) (xy 418.397436 -168.544748) (xy 418.385321 -168.56843) (xy 418.355402 -168.612413)
			(xy 418.319535 -168.651696) (xy 418.278448 -168.685482) (xy 418.255958 -168.699688) (xy 418.243751 -168.707635)
			(xy 418.224085 -168.729102) (xy 418.211281 -168.755249) (xy 418.206381 -168.783947) (xy 418.209783 -168.812861)
			(xy 418.215064 -168.826434) (xy 418.22456 -168.849641) (xy 418.237908 -168.897976) (xy 418.244633 -168.947666)
			(xy 418.245036 -168.972738) (xy 418.244615 -168.997807) (xy 418.237865 -169.047491) (xy 418.224531 -169.095825)
			(xy 418.215064 -169.119042) (xy 418.209854 -169.132631) (xy 418.206485 -169.161525) (xy 418.211389 -169.190198)
			(xy 418.224168 -169.21633) (xy 418.243789 -169.237805) (xy 418.255958 -169.245788) (xy 418.27905 -169.260416)
			(xy 418.321167 -169.295255) (xy 418.357742 -169.335872) (xy 418.387993 -169.381397) (xy 418.411268 -169.430852)
			(xy 418.427069 -169.483177) (xy 418.435057 -169.537249) (xy 418.43506 -169.591908) (xy 418.427078 -169.64598)
			(xy 418.411283 -169.698307) (xy 418.388014 -169.747765) (xy 418.357769 -169.793294) (xy 418.321198 -169.833915)
			(xy 418.279085 -169.868759) (xy 418.255958 -169.883328) (xy 418.243724 -169.891237) (xy 418.224058 -169.912714)
			(xy 418.211257 -169.938871) (xy 418.206364 -169.967578) (xy 418.209777 -169.996499) (xy 418.215064 -170.010074)
			(xy 418.224541 -170.033289) (xy 418.237896 -170.081619) (xy 418.244629 -170.131307) (xy 418.245036 -170.156378)
			(xy 418.244515 -170.184263) (xy 418.236203 -170.23941) (xy 418.219765 -170.292702) (xy 418.195567 -170.342948)
			(xy 418.164151 -170.389027) (xy 418.126218 -170.429909) (xy 418.082616 -170.464681) (xy 418.034318 -170.492566)
			(xy 417.982403 -170.512941) (xy 417.928032 -170.525351) (xy 417.872418 -170.529519) (xy 417.816804 -170.525351)
			(xy 417.762433 -170.512941) (xy 417.710518 -170.492566) (xy 417.66222 -170.464681) (xy 417.618618 -170.429909)
			(xy 417.580685 -170.389027) (xy 417.549269 -170.342948) (xy 417.525071 -170.292702) (xy 417.508633 -170.23941)
			(xy 417.500321 -170.184263) (xy 417.4998 -170.156378) (xy 417.216336 -170.156378) (xy 417.216336 -170.233848)
			(xy 417.606988 -170.6245) (xy 417.627808 -170.646081) (xy 417.66306 -170.694587) (xy 417.690287 -170.748013)
			(xy 417.708817 -170.805041) (xy 417.718194 -170.864266) (xy 417.718748 -170.894248) (xy 417.718748 -172.82625)
			(xy 419.374572 -172.82625) (xy 419.374572 -172.77175) (xy 419.382328 -172.717803) (xy 419.397682 -172.66551)
			(xy 419.420321 -172.615933) (xy 419.449786 -172.570084) (xy 419.485475 -172.528893) (xy 419.526663 -172.493201)
			(xy 419.572511 -172.463734) (xy 419.622085 -172.441091) (xy 419.674378 -172.425733) (xy 419.728324 -172.417974)
			(xy 419.755574 -172.417486) (xy 419.78151 -172.417935) (xy 419.832905 -172.42496) (xy 419.882874 -172.438884)
			(xy 419.930495 -172.459451) (xy 419.97489 -172.48628) (xy 420.015241 -172.518878) (xy 420.050803 -172.556642)
			(xy 420.066216 -172.577506) (xy 420.075441 -172.589618) (xy 420.099609 -172.608114) (xy 420.128159 -172.618654)
			(xy 420.158548 -172.620298) (xy 420.188068 -172.6129) (xy 420.201344 -172.605446) (xy 420.223766 -172.592408)
			(xy 420.271398 -172.571875) (xy 420.321372 -172.557986) (xy 420.372767 -172.550998) (xy 420.398702 -172.550582)
			(xy 420.425952 -172.551088) (xy 420.479898 -172.558845) (xy 420.532192 -172.5742) (xy 420.581767 -172.59684)
			(xy 420.627616 -172.626306) (xy 420.668805 -172.661997) (xy 420.704495 -172.703186) (xy 420.733961 -172.749035)
			(xy 420.756601 -172.79861) (xy 420.771956 -172.850904) (xy 420.779712 -172.90485) (xy 420.779712 -172.95935)
			(xy 420.771956 -173.013296) (xy 420.756601 -173.06559) (xy 420.733961 -173.115165) (xy 420.704495 -173.161014)
			(xy 420.668805 -173.202203) (xy 420.627616 -173.237894) (xy 420.581767 -173.26736) (xy 420.532192 -173.29)
			(xy 420.479898 -173.305355) (xy 420.425952 -173.313112) (xy 420.398702 -173.313598) (xy 420.372765 -173.313174)
			(xy 420.321369 -173.306145) (xy 420.271399 -173.292217) (xy 420.223778 -173.271647) (xy 420.179382 -173.244813)
			(xy 420.139033 -173.212212) (xy 420.103472 -173.174444) (xy 420.08806 -173.153578) (xy 420.07886 -173.141445)
			(xy 420.054684 -173.122952) (xy 420.026127 -173.112417) (xy 419.995733 -173.110778) (xy 419.966209 -173.118181)
			(xy 419.952932 -173.125638) (xy 419.930497 -173.138654) (xy 419.88287 -173.15919) (xy 419.8329 -173.173085)
			(xy 419.781507 -173.180081) (xy 419.755574 -173.180502) (xy 419.728324 -173.180026) (xy 419.674378 -173.172267)
			(xy 419.622085 -173.156909) (xy 419.572511 -173.134266) (xy 419.526663 -173.104799) (xy 419.485475 -173.069107)
			(xy 419.449786 -173.027916) (xy 419.420321 -172.982067) (xy 419.397682 -172.93249) (xy 419.382328 -172.880197)
			(xy 419.374572 -172.82625) (xy 417.718748 -172.82625) (xy 417.718748 -173.548802) (xy 417.718173 -173.577953)
			(xy 418.557175 -173.577953) (xy 418.564931 -173.524006) (xy 418.580286 -173.471711) (xy 418.602926 -173.422133)
			(xy 418.632392 -173.376282) (xy 418.668083 -173.335091) (xy 418.709272 -173.299399) (xy 418.755122 -173.269932)
			(xy 418.804699 -173.24729) (xy 418.856994 -173.231934) (xy 418.910941 -173.224176) (xy 418.965444 -173.224175)
			(xy 419.019392 -173.231931) (xy 419.071687 -173.247285) (xy 419.121265 -173.269925) (xy 419.167116 -173.29939)
			(xy 419.208307 -173.335081) (xy 419.243999 -173.37627) (xy 419.273467 -173.42212) (xy 419.296109 -173.471697)
			(xy 419.311466 -173.523991) (xy 419.319224 -173.577939) (xy 419.31971 -173.60519) (xy 419.319282 -173.630581)
			(xy 419.312524 -173.680913) (xy 419.306248 -173.70552) (xy 419.302808 -173.720167) (xy 419.303729 -173.750225)
			(xy 419.31336 -173.778715) (xy 419.330866 -173.803167) (xy 419.354731 -173.821465) (xy 419.38289 -173.832023)
			(xy 419.412902 -173.833929) (xy 419.42766 -173.830996) (xy 419.449255 -173.826239) (xy 419.49318 -173.82114)
			(xy 419.51529 -173.820836) (xy 419.542541 -173.821267) (xy 419.59649 -173.829022) (xy 419.648785 -173.844376)
			(xy 419.698364 -173.867015) (xy 419.744216 -173.89648) (xy 419.785408 -173.93217) (xy 419.821101 -173.973359)
			(xy 419.85057 -174.019209) (xy 419.873213 -174.068785) (xy 419.888571 -174.12108) (xy 419.896331 -174.175027)
			(xy 419.896334 -174.22953) (xy 419.88858 -174.283479) (xy 419.873228 -174.335775) (xy 419.85059 -174.385354)
			(xy 419.821127 -174.431207) (xy 419.785438 -174.4724) (xy 419.74425 -174.508094) (xy 419.698401 -174.537564)
			(xy 419.648825 -174.560209) (xy 419.596532 -174.575569) (xy 419.542584 -174.58333) (xy 419.488081 -174.583335)
			(xy 419.434132 -174.575583) (xy 419.381836 -174.560232) (xy 419.332256 -174.537596) (xy 419.286403 -174.508134)
			(xy 419.245208 -174.472446) (xy 419.209512 -174.431259) (xy 419.180041 -174.385411) (xy 419.157395 -174.335836)
			(xy 419.142034 -174.283543) (xy 419.134271 -174.229595) (xy 419.133782 -174.202344) (xy 419.134216 -174.176953)
			(xy 419.14097 -174.126622) (xy 419.147244 -174.102014) (xy 419.150657 -174.087361) (xy 419.149744 -174.057304)
			(xy 419.14012 -174.028815) (xy 419.122618 -174.004362) (xy 419.098755 -173.986064) (xy 419.070599 -173.975507)
			(xy 419.040588 -173.973604) (xy 419.025832 -173.976538) (xy 419.004238 -173.981297) (xy 418.960312 -173.986394)
			(xy 418.938202 -173.986698) (xy 418.910951 -173.986224) (xy 418.857003 -173.978468) (xy 418.804708 -173.963113)
			(xy 418.755131 -173.940473) (xy 418.70928 -173.911007) (xy 418.668089 -173.875315) (xy 418.632397 -173.834125)
			(xy 418.602931 -173.788275) (xy 418.580289 -173.738698) (xy 418.564933 -173.686404) (xy 418.557176 -173.632456)
			(xy 418.557175 -173.577953) (xy 417.718173 -173.577953) (xy 417.718157 -173.578779) (xy 417.708766 -173.637994)
			(xy 417.690232 -173.695013) (xy 417.663009 -173.748431) (xy 417.627768 -173.796936) (xy 417.606988 -173.81855)
			(xy 417.556696 -173.868588) (xy 417.546638 -173.879312) (xy 417.532655 -173.905163) (xy 417.526616 -173.933927)
			(xy 417.529023 -173.963219) (xy 417.539676 -173.990611) (xy 417.557692 -174.013833) (xy 417.581577 -174.030959)
			(xy 417.595304 -174.036228) (xy 417.61991 -174.045261) (xy 417.666579 -174.069124) (xy 417.709543 -174.099148)
			(xy 417.747993 -174.134771) (xy 417.781208 -174.17532) (xy 417.80856 -174.220033) (xy 417.829535 -174.268068)
			(xy 417.84374 -174.318523) (xy 417.850906 -174.370446) (xy 417.851336 -174.396654) (xy 417.850802 -174.423904)
			(xy 417.843052 -174.477851) (xy 417.827703 -174.530146) (xy 417.805068 -174.579724) (xy 417.775608 -174.625576)
			(xy 417.739921 -174.666769) (xy 417.698736 -174.702463) (xy 417.652889 -174.731933) (xy 417.603316 -174.754577)
			(xy 417.551024 -174.769936) (xy 417.497078 -174.777697) (xy 417.469828 -174.778162) (xy 417.439259 -174.777593)
			(xy 417.378896 -174.767892) (xy 417.349686 -174.758858) (xy 417.336504 -174.755068) (xy 417.309124 -174.753736)
			(xy 417.282378 -174.759741) (xy 417.258195 -174.772648) (xy 417.238321 -174.791528) (xy 417.224189 -174.815016)
			(xy 417.21682 -174.841419) (xy 417.216336 -174.855124) (xy 417.216336 -178.792378) (xy 417.4998 -178.792378)
			(xy 417.500317 -178.765048) (xy 417.50828 -178.710971) (xy 417.524061 -178.658638) (xy 417.547322 -178.609175)
			(xy 417.577563 -178.563642) (xy 417.614133 -178.523018) (xy 417.656249 -178.488176) (xy 417.679378 -178.473608)
			(xy 417.691578 -178.46565) (xy 417.711251 -178.444189) (xy 417.724061 -178.418045) (xy 417.728962 -178.389347)
			(xy 417.725556 -178.360434) (xy 417.720272 -178.346862) (xy 417.710777 -178.323654) (xy 417.697428 -178.27532)
			(xy 417.690702 -178.22563) (xy 417.6903 -178.200558) (xy 417.690724 -178.175489) (xy 417.697474 -178.125806)
			(xy 417.710806 -178.077471) (xy 417.720272 -178.054254) (xy 417.725563 -178.040687) (xy 417.728937 -178.011773)
			(xy 417.724027 -177.983079) (xy 417.711231 -177.95693) (xy 417.691587 -177.935447) (xy 417.679378 -177.927508)
			(xy 417.656281 -177.912887) (xy 417.61416 -177.87805) (xy 417.57758 -177.837433) (xy 417.547327 -177.791907)
			(xy 417.52405 -177.742451) (xy 417.508247 -177.690124) (xy 417.500259 -177.63605) (xy 417.500256 -177.581389)
			(xy 417.508238 -177.527314) (xy 417.524036 -177.474986) (xy 417.547308 -177.425527) (xy 417.577556 -177.379998)
			(xy 417.614131 -177.339377) (xy 417.656249 -177.304536) (xy 417.679378 -177.289968) (xy 417.691605 -177.282048)
			(xy 417.711279 -177.260577) (xy 417.724084 -177.234423) (xy 417.728979 -177.205716) (xy 417.725563 -177.176796)
			(xy 417.720272 -177.163222) (xy 417.710796 -177.140007) (xy 417.69744 -177.091677) (xy 417.690706 -177.041989)
			(xy 417.6903 -177.016918) (xy 417.690766 -176.990075) (xy 417.698468 -176.936945) (xy 417.713716 -176.88547)
			(xy 417.736193 -176.836717) (xy 417.765435 -176.791694) (xy 417.800836 -176.751334) (xy 417.841662 -176.716472)
			(xy 417.887069 -176.687831) (xy 417.936117 -176.666002) (xy 417.961826 -176.65827) (xy 417.976329 -176.65362)
			(xy 418.0019 -176.637103) (xy 418.021469 -176.613785) (xy 418.033299 -176.585737) (xy 418.03634 -176.555448)
			(xy 418.030322 -176.525608) (xy 418.023548 -176.511966) (xy 418.00892 -176.483818) (xy 417.988191 -176.423868)
			(xy 417.977691 -176.36131) (xy 417.977066 -176.329594) (xy 417.977291 -176.311575) (xy 417.980722 -176.2757)
			(xy 417.983924 -176.257966) (xy 417.986322 -176.242764) (xy 417.982784 -176.212201) (xy 417.97031 -176.184077)
			(xy 417.95003 -176.160941) (xy 417.923782 -176.144889) (xy 417.908994 -176.140618) (xy 417.881967 -176.133164)
			(xy 417.830242 -176.111542) (xy 417.782237 -176.082585) (xy 417.738984 -176.046917) (xy 417.701416 -176.005305)
			(xy 417.670339 -175.958645) (xy 417.646423 -175.90794) (xy 417.630183 -175.854282) (xy 417.621967 -175.798825)
			(xy 417.621466 -175.770794) (xy 417.621972 -175.743544) (xy 417.629729 -175.689598) (xy 417.645083 -175.637305)
			(xy 417.667723 -175.58773) (xy 417.697188 -175.541881) (xy 417.732877 -175.500691) (xy 417.774065 -175.465)
			(xy 417.819912 -175.435533) (xy 417.869487 -175.41289) (xy 417.921779 -175.397533) (xy 417.975724 -175.389774)
			(xy 418.002974 -175.389286) (xy 418.030548 -175.389774) (xy 418.085119 -175.397723) (xy 418.137979 -175.413444)
			(xy 418.188024 -175.43661) (xy 418.234215 -175.466738) (xy 418.275587 -175.503201) (xy 418.293804 -175.523906)
			(xy 418.303702 -175.534804) (xy 418.328352 -175.550879) (xy 418.35656 -175.559263) (xy 418.385988 -175.559263)
			(xy 418.414196 -175.550879) (xy 418.438846 -175.534804) (xy 418.448744 -175.523906) (xy 418.466959 -175.5032)
			(xy 418.50833 -175.466735) (xy 418.55452 -175.436608) (xy 418.604567 -175.413445) (xy 418.657428 -175.397729)
			(xy 418.712 -175.389789) (xy 418.767148 -175.389789) (xy 418.82172 -175.397729) (xy 418.874581 -175.413445)
			(xy 418.924628 -175.436608) (xy 418.970818 -175.466735) (xy 419.012189 -175.5032) (xy 419.030404 -175.523906)
			(xy 419.040302 -175.534804) (xy 419.064952 -175.550879) (xy 419.09316 -175.559263) (xy 419.122588 -175.559263)
			(xy 419.150796 -175.550879) (xy 419.175446 -175.534804) (xy 419.185344 -175.523906) (xy 419.203582 -175.50322)
			(xy 419.244945 -175.466747) (xy 419.291129 -175.436612) (xy 419.341172 -175.413442) (xy 419.39403 -175.39772)
			(xy 419.448601 -175.389775) (xy 419.476174 -175.389286) (xy 419.503426 -175.389779) (xy 419.557375 -175.397533)
			(xy 419.609672 -175.412885) (xy 419.659252 -175.435524) (xy 419.705105 -175.464989) (xy 419.746298 -175.50068)
			(xy 419.781992 -175.541869) (xy 419.81146 -175.58772) (xy 419.834104 -175.637298) (xy 419.84946 -175.689593)
			(xy 419.857218 -175.743542) (xy 419.857682 -175.770794) (xy 419.857167 -175.79865) (xy 419.849043 -175.853766)
			(xy 419.832998 -175.907117) (xy 419.80937 -175.957571) (xy 419.778663 -176.004056) (xy 419.741526 -176.045585)
			(xy 419.69875 -176.081278) (xy 419.651241 -176.110376) (xy 419.600008 -176.132262) (xy 419.573202 -176.139856)
			(xy 419.559077 -176.144105) (xy 419.53393 -176.159501) (xy 419.514215 -176.181425) (xy 419.501566 -176.20806)
			(xy 419.497034 -176.237195) (xy 419.498526 -176.25187) (xy 419.5002 -176.264886) (xy 419.501977 -176.291071)
			(xy 419.502082 -176.304194) (xy 419.501988 -176.318343) (xy 419.499954 -176.346566) (xy 419.498018 -176.360582)
			(xy 419.496394 -176.373927) (xy 419.4995 -176.400623) (xy 419.509476 -176.425579) (xy 419.525629 -176.44706)
			(xy 419.546835 -176.463572) (xy 419.57162 -176.473966) (xy 419.584886 -176.476152) (xy 419.612039 -176.480237)
			(xy 419.664868 -176.495214) (xy 419.715004 -176.517609) (xy 419.761412 -176.546958) (xy 419.803135 -176.582656)
			(xy 419.839311 -176.623965) (xy 419.869192 -176.670033) (xy 419.892162 -176.719908) (xy 419.907746 -176.772561)
			(xy 419.915622 -176.826903) (xy 419.916102 -176.854358) (xy 419.915606 -176.88161) (xy 419.907854 -176.93556)
			(xy 419.892503 -176.987858) (xy 419.869865 -177.037438) (xy 419.840401 -177.083292) (xy 419.804711 -177.124485)
			(xy 419.763521 -177.160179) (xy 419.71767 -177.189648) (xy 419.668092 -177.212291) (xy 419.615795 -177.227647)
			(xy 419.561846 -177.235403) (xy 419.534594 -177.235866) (xy 419.507019 -177.235416) (xy 419.452445 -177.227462)
			(xy 419.399584 -177.211735) (xy 419.349538 -177.188562) (xy 419.303349 -177.158426) (xy 419.261979 -177.121955)
			(xy 419.243764 -177.101246) (xy 419.233866 -177.090348) (xy 419.209216 -177.074273) (xy 419.181008 -177.065889)
			(xy 419.15158 -177.065889) (xy 419.123372 -177.074273) (xy 419.098722 -177.090348) (xy 419.088824 -177.101246)
			(xy 419.070614 -177.121958) (xy 419.029244 -177.158426) (xy 418.983053 -177.188557) (xy 418.933005 -177.211722)
			(xy 418.880143 -177.227439) (xy 418.825569 -177.23538) (xy 418.797994 -177.235866) (xy 418.771493 -177.235405)
			(xy 418.719002 -177.228063) (xy 418.668034 -177.213521) (xy 418.619572 -177.192059) (xy 418.574549 -177.164091)
			(xy 418.5539 -177.147474) (xy 418.541717 -177.138082) (xy 418.51333 -177.126285) (xy 418.482719 -177.123451)
			(xy 418.452648 -177.129838) (xy 418.425831 -177.144868) (xy 418.404689 -177.167186) (xy 418.397436 -177.180748)
			(xy 418.385321 -177.20443) (xy 418.355402 -177.248413) (xy 418.319535 -177.287696) (xy 418.278448 -177.321482)
			(xy 418.255958 -177.335688) (xy 418.243751 -177.343635) (xy 418.224085 -177.365102) (xy 418.211281 -177.391249)
			(xy 418.206381 -177.419947) (xy 418.209783 -177.448861) (xy 418.215064 -177.462434) (xy 418.22456 -177.485641)
			(xy 418.237908 -177.533976) (xy 418.244633 -177.583666) (xy 418.245036 -177.608738) (xy 418.244615 -177.633807)
			(xy 418.237865 -177.683491) (xy 418.224531 -177.731825) (xy 418.215064 -177.755042) (xy 418.209854 -177.768631)
			(xy 418.206485 -177.797525) (xy 418.211389 -177.826198) (xy 418.224168 -177.85233) (xy 418.243789 -177.873805)
			(xy 418.255958 -177.881788) (xy 418.27905 -177.896416) (xy 418.321167 -177.931255) (xy 418.357742 -177.971872)
			(xy 418.387993 -178.017397) (xy 418.411268 -178.066852) (xy 418.427069 -178.119177) (xy 418.435057 -178.173249)
			(xy 418.43506 -178.227908) (xy 418.427078 -178.28198) (xy 418.411283 -178.334307) (xy 418.388014 -178.383765)
			(xy 418.357769 -178.429294) (xy 418.321198 -178.469915) (xy 418.279085 -178.504759) (xy 418.255958 -178.519328)
			(xy 418.243724 -178.527237) (xy 418.224058 -178.548714) (xy 418.211257 -178.574871) (xy 418.206364 -178.603578)
			(xy 418.209777 -178.632499) (xy 418.215064 -178.646074) (xy 418.224541 -178.669289) (xy 418.237896 -178.717619)
			(xy 418.244629 -178.767307) (xy 418.245036 -178.792378) (xy 418.244515 -178.820263) (xy 418.236203 -178.87541)
			(xy 418.219765 -178.928702) (xy 418.195567 -178.978948) (xy 418.164151 -179.025027) (xy 418.126218 -179.065909)
			(xy 418.082616 -179.100681) (xy 418.034318 -179.128566) (xy 417.982403 -179.148941) (xy 417.928032 -179.161351)
			(xy 417.872418 -179.165519) (xy 417.816804 -179.161351) (xy 417.762433 -179.148941) (xy 417.710518 -179.128566)
			(xy 417.66222 -179.100681) (xy 417.618618 -179.065909) (xy 417.580685 -179.025027) (xy 417.549269 -178.978948)
			(xy 417.525071 -178.928702) (xy 417.508633 -178.87541) (xy 417.500321 -178.820263) (xy 417.4998 -178.792378)
			(xy 417.216336 -178.792378) (xy 417.216336 -178.940968) (xy 417.469828 -179.19446) (xy 417.490618 -179.216068)
			(xy 417.525876 -179.264566) (xy 417.55311 -179.317984) (xy 417.571647 -179.375007) (xy 417.58103 -179.434228)
			(xy 417.581588 -179.464208) (xy 417.581588 -181.46225) (xy 419.374572 -181.46225) (xy 419.374572 -181.40775)
			(xy 419.382328 -181.353803) (xy 419.397682 -181.30151) (xy 419.420321 -181.251933) (xy 419.449786 -181.206084)
			(xy 419.485475 -181.164893) (xy 419.526663 -181.129201) (xy 419.572511 -181.099734) (xy 419.622085 -181.077091)
			(xy 419.674378 -181.061733) (xy 419.728324 -181.053974) (xy 419.755574 -181.053486) (xy 419.785261 -181.054065)
			(xy 419.843919 -181.06326) (xy 419.900444 -181.081431) (xy 419.953471 -181.108139) (xy 420.001721 -181.142741)
			(xy 420.044027 -181.184399) (xy 420.062152 -181.207918) (xy 420.070578 -181.218525) (xy 420.091891 -181.235232)
			(xy 420.116845 -181.245751) (xy 420.143686 -181.249341) (xy 420.170527 -181.245751) (xy 420.195481 -181.235232)
			(xy 420.216794 -181.218525) (xy 420.22522 -181.207918) (xy 420.243349 -181.184402) (xy 420.285654 -181.142741)
			(xy 420.333902 -181.108136) (xy 420.386928 -181.081424) (xy 420.443453 -181.06325) (xy 420.502111 -181.054051)
			(xy 420.531798 -181.053486) (xy 420.559051 -181.053961) (xy 420.613001 -181.061718) (xy 420.665298 -181.077073)
			(xy 420.714878 -181.099715) (xy 420.76073 -181.129183) (xy 420.801923 -181.164876) (xy 420.837616 -181.206068)
			(xy 420.867084 -181.251921) (xy 420.889726 -181.3015) (xy 420.905082 -181.353797) (xy 420.912839 -181.407747)
			(xy 420.912839 -181.462253) (xy 420.905082 -181.516203) (xy 420.889726 -181.5685) (xy 420.867084 -181.618079)
			(xy 420.837616 -181.663932) (xy 420.801923 -181.705124) (xy 420.76073 -181.740817) (xy 420.714878 -181.770285)
			(xy 420.665298 -181.792927) (xy 420.613001 -181.808282) (xy 420.559051 -181.816039) (xy 420.531798 -181.816502)
			(xy 420.50211 -181.815948) (xy 420.443451 -181.806749) (xy 420.386925 -181.788573) (xy 420.333898 -181.76186)
			(xy 420.285649 -181.727254) (xy 420.243344 -181.685591) (xy 420.22522 -181.66207) (xy 420.216794 -181.651463)
			(xy 420.195481 -181.634756) (xy 420.170527 -181.624237) (xy 420.143686 -181.620647) (xy 420.116845 -181.624237)
			(xy 420.091891 -181.634756) (xy 420.070578 -181.651463) (xy 420.062152 -181.66207) (xy 420.044036 -181.685597)
			(xy 420.001729 -181.727258) (xy 419.953478 -181.761861) (xy 419.900449 -181.788572) (xy 419.843922 -181.806744)
			(xy 419.785262 -181.815939) (xy 419.755574 -181.816502) (xy 419.728324 -181.816026) (xy 419.674378 -181.808267)
			(xy 419.622085 -181.792909) (xy 419.572511 -181.770266) (xy 419.526663 -181.740799) (xy 419.485475 -181.705107)
			(xy 419.449786 -181.663916) (xy 419.420321 -181.618067) (xy 419.397682 -181.56849) (xy 419.382328 -181.516197)
			(xy 419.374572 -181.46225) (xy 417.581588 -181.46225) (xy 417.581588 -181.998874) (xy 417.580968 -182.02885)
			(xy 417.571582 -182.088063) (xy 417.553054 -182.145081) (xy 417.525838 -182.1985) (xy 417.514614 -182.213953)
			(xy 418.557175 -182.213953) (xy 418.564931 -182.160006) (xy 418.580286 -182.107711) (xy 418.602926 -182.058133)
			(xy 418.632392 -182.012282) (xy 418.668083 -181.971091) (xy 418.709272 -181.935399) (xy 418.755122 -181.905932)
			(xy 418.804699 -181.88329) (xy 418.856994 -181.867934) (xy 418.910941 -181.860176) (xy 418.965444 -181.860175)
			(xy 419.019392 -181.867931) (xy 419.071687 -181.883285) (xy 419.121265 -181.905925) (xy 419.167116 -181.93539)
			(xy 419.208307 -181.971081) (xy 419.243999 -182.01227) (xy 419.273467 -182.05812) (xy 419.296109 -182.107697)
			(xy 419.311466 -182.159991) (xy 419.319224 -182.213939) (xy 419.31971 -182.24119) (xy 419.319282 -182.266581)
			(xy 419.312524 -182.316913) (xy 419.306248 -182.34152) (xy 419.302808 -182.356167) (xy 419.303729 -182.386225)
			(xy 419.31336 -182.414715) (xy 419.330866 -182.439167) (xy 419.354731 -182.457465) (xy 419.38289 -182.468023)
			(xy 419.412902 -182.469929) (xy 419.42766 -182.466996) (xy 419.449255 -182.462239) (xy 419.49318 -182.45714)
			(xy 419.51529 -182.456836) (xy 419.542541 -182.457267) (xy 419.59649 -182.465022) (xy 419.648785 -182.480376)
			(xy 419.698364 -182.503015) (xy 419.744216 -182.53248) (xy 419.785408 -182.56817) (xy 419.821101 -182.609359)
			(xy 419.85057 -182.655209) (xy 419.873213 -182.704785) (xy 419.888571 -182.75708) (xy 419.896331 -182.811027)
			(xy 419.896334 -182.86553) (xy 419.88858 -182.919479) (xy 419.873228 -182.971775) (xy 419.85059 -183.021354)
			(xy 419.821127 -183.067207) (xy 419.785438 -183.1084) (xy 419.74425 -183.144094) (xy 419.698401 -183.173564)
			(xy 419.648825 -183.196209) (xy 419.596532 -183.211569) (xy 419.542584 -183.21933) (xy 419.488081 -183.219335)
			(xy 419.434132 -183.211583) (xy 419.381836 -183.196232) (xy 419.332256 -183.173596) (xy 419.286403 -183.144134)
			(xy 419.245208 -183.108446) (xy 419.209512 -183.067259) (xy 419.180041 -183.021411) (xy 419.157395 -182.971836)
			(xy 419.142034 -182.919543) (xy 419.134271 -182.865595) (xy 419.133782 -182.838344) (xy 419.134216 -182.812953)
			(xy 419.14097 -182.762622) (xy 419.147244 -182.738014) (xy 419.150657 -182.723361) (xy 419.149744 -182.693304)
			(xy 419.14012 -182.664815) (xy 419.122618 -182.640362) (xy 419.098755 -182.622064) (xy 419.070599 -182.611507)
			(xy 419.040588 -182.609604) (xy 419.025832 -182.612538) (xy 419.004238 -182.617297) (xy 418.960312 -182.622394)
			(xy 418.938202 -182.622698) (xy 418.910951 -182.622224) (xy 418.857003 -182.614468) (xy 418.804708 -182.599113)
			(xy 418.755131 -182.576473) (xy 418.70928 -182.547007) (xy 418.668089 -182.511315) (xy 418.632397 -182.470125)
			(xy 418.602931 -182.424275) (xy 418.580289 -182.374698) (xy 418.564933 -182.322404) (xy 418.557176 -182.268456)
			(xy 418.557175 -182.213953) (xy 417.514614 -182.213953) (xy 417.490605 -182.247006) (xy 417.469828 -182.268622)
			(xy 417.216336 -182.522114) (xy 417.216336 -182.574184) (xy 417.216738 -182.587899) (xy 417.224115 -182.614322)
			(xy 417.238258 -182.637828) (xy 417.258148 -182.656721) (xy 417.28235 -182.669638) (xy 417.309117 -182.675647)
			(xy 417.336517 -182.674314) (xy 417.349686 -182.67045) (xy 417.378896 -182.66142) (xy 417.439259 -182.651728)
			(xy 417.469828 -182.651146) (xy 417.497075 -182.651726) (xy 417.551013 -182.659485) (xy 417.603298 -182.674841)
			(xy 417.652865 -182.697481) (xy 417.698707 -182.726944) (xy 417.739889 -182.762631) (xy 417.775573 -182.803816)
			(xy 417.805033 -182.849659) (xy 417.827669 -182.899228) (xy 417.843021 -182.951515) (xy 417.850776 -183.005453)
			(xy 417.850776 -183.059947) (xy 417.843021 -183.113885) (xy 417.827669 -183.166172) (xy 417.805033 -183.215741)
			(xy 417.775573 -183.261584) (xy 417.739889 -183.302769) (xy 417.698707 -183.338456) (xy 417.652865 -183.367919)
			(xy 417.603298 -183.390559) (xy 417.551013 -183.405915) (xy 417.497075 -183.413674) (xy 417.469828 -183.414162)
			(xy 417.442458 -183.413689) (xy 417.388279 -183.405874) (xy 417.335775 -183.390387) (xy 417.286028 -183.367547)
			(xy 417.240062 -183.337823) (xy 417.21913 -183.320182) (xy 417.207811 -183.310926) (xy 417.181255 -183.298719)
			(xy 417.152328 -183.294536) (xy 417.123401 -183.298719) (xy 417.096845 -183.310926) (xy 417.085526 -183.320182)
			(xy 417.064567 -183.337773) (xy 417.018584 -183.367429) (xy 416.968837 -183.390214) (xy 416.916346 -183.40566)
			(xy 416.862187 -183.41345) (xy 416.834828 -183.413908) (xy 416.807589 -183.413397) (xy 416.753665 -183.40565)
			(xy 416.701391 -183.390312) (xy 416.65183 -183.367692) (xy 416.605992 -183.338253) (xy 416.564808 -183.302591)
			(xy 416.529117 -183.261434) (xy 416.499643 -183.215617) (xy 416.476987 -183.166074) (xy 416.46161 -183.113811)
			(xy 416.453824 -183.059893) (xy 416.45332 -183.032654) (xy 410.41574 -183.032654) (xy 410.41574 -183.980328)
			(xy 410.7815 -184.346088) (xy 422.15816 -184.346088)
		)
		(stroke
			(width 0)
			(type solid)
		)
		(fill yes)
		(layer "In11.Cu")
		(net "GND")
	)
	(gr_poly
		(pts
			(xy 370.169186 -288.884868) (xy 370.172169 -288.8594) (xy 370.184995 -288.809754) (xy 370.205333 -288.762685)
			(xy 370.232697 -288.719322) (xy 370.26643 -288.680705) (xy 370.305721 -288.64776) (xy 370.349629 -288.621279)
			(xy 370.3971 -288.601897) (xy 370.446995 -288.590078) (xy 370.498116 -288.586107) (xy 370.549237 -288.590078)
			(xy 370.599132 -288.601897) (xy 370.646603 -288.621279) (xy 370.690511 -288.64776) (xy 370.729802 -288.680705)
			(xy 370.763535 -288.719322) (xy 370.790899 -288.762685) (xy 370.811237 -288.809754) (xy 370.824063 -288.8594)
			(xy 370.827046 -288.884868) (xy 370.831364 -288.930588) (xy 371.104668 -288.930588) (xy 371.108986 -288.884868)
			(xy 371.111256 -288.865099) (xy 371.119919 -288.82626) (xy 371.126258 -288.807398) (xy 371.133878 -288.7853)
			(xy 370.93017 -288.43224) (xy 370.90731 -288.427922) (xy 370.882367 -288.422784) (xy 370.834336 -288.405862)
			(xy 370.78947 -288.381771) (xy 370.748831 -288.351083) (xy 370.713381 -288.314523) (xy 370.68396 -288.272958)
			(xy 370.661263 -288.227371) (xy 370.645829 -288.178841) (xy 370.638024 -288.128518) (xy 370.637562 -288.103056)
			(xy 370.638071 -288.077089) (xy 370.646196 -288.025794) (xy 370.662244 -287.976401) (xy 370.685822 -287.930127)
			(xy 370.716348 -287.888111) (xy 370.753071 -287.851388) (xy 370.795087 -287.820862) (xy 370.841361 -287.797284)
			(xy 370.890754 -287.781236) (xy 370.942049 -287.773111) (xy 370.993983 -287.773111) (xy 371.045278 -287.781236)
			(xy 371.094671 -287.797284) (xy 371.140945 -287.820862) (xy 371.182961 -287.851388) (xy 371.219684 -287.888111)
			(xy 371.25021 -287.930127) (xy 371.273788 -287.976401) (xy 371.289836 -288.025794) (xy 371.297961 -288.077089)
			(xy 371.29847 -288.103056) (xy 371.29786 -288.131037) (xy 371.288415 -288.186197) (xy 371.279674 -288.212784)
			(xy 371.272054 -288.234628) (xy 371.476016 -288.587942) (xy 371.498876 -288.59226) (xy 371.524938 -288.597688)
			(xy 371.575011 -288.615752) (xy 371.621541 -288.64161) (xy 371.663326 -288.67459) (xy 371.699283 -288.713842)
			(xy 371.728484 -288.75835) (xy 371.750174 -288.806963) (xy 371.763791 -288.858424) (xy 371.766846 -288.884868)
			(xy 371.771164 -288.930588) (xy 372.044468 -288.930588) (xy 372.048786 -288.884868) (xy 372.051769 -288.8594)
			(xy 372.064595 -288.809754) (xy 372.084933 -288.762685) (xy 372.112297 -288.719322) (xy 372.14603 -288.680705)
			(xy 372.185321 -288.64776) (xy 372.229229 -288.621279) (xy 372.2767 -288.601897) (xy 372.326595 -288.590078)
			(xy 372.377716 -288.586107) (xy 372.428837 -288.590078) (xy 372.478732 -288.601897) (xy 372.526203 -288.621279)
			(xy 372.570111 -288.64776) (xy 372.609402 -288.680705) (xy 372.643135 -288.719322) (xy 372.670499 -288.762685)
			(xy 372.690837 -288.809754) (xy 372.703663 -288.8594) (xy 372.706646 -288.884868) (xy 372.710964 -288.930588)
			(xy 372.984268 -288.930588) (xy 372.988586 -288.884868) (xy 372.990856 -288.865099) (xy 372.999519 -288.82626)
			(xy 373.005858 -288.807398) (xy 373.013478 -288.7853) (xy 372.80977 -288.43224) (xy 372.78691 -288.427922)
			(xy 372.761967 -288.422784) (xy 372.713936 -288.405862) (xy 372.66907 -288.381771) (xy 372.628431 -288.351083)
			(xy 372.592981 -288.314523) (xy 372.56356 -288.272958) (xy 372.540863 -288.227371) (xy 372.525429 -288.178841)
			(xy 372.517624 -288.128518) (xy 372.517162 -288.103056) (xy 372.517671 -288.077089) (xy 372.525796 -288.025794)
			(xy 372.541844 -287.976401) (xy 372.565422 -287.930127) (xy 372.595948 -287.888111) (xy 372.632671 -287.851388)
			(xy 372.674687 -287.820862) (xy 372.720961 -287.797284) (xy 372.770354 -287.781236) (xy 372.821649 -287.773111)
			(xy 372.873583 -287.773111) (xy 372.924878 -287.781236) (xy 372.974271 -287.797284) (xy 373.020545 -287.820862)
			(xy 373.062561 -287.851388) (xy 373.099284 -287.888111) (xy 373.12981 -287.930127) (xy 373.153388 -287.976401)
			(xy 373.169436 -288.025794) (xy 373.177561 -288.077089) (xy 373.17807 -288.103056) (xy 373.17746 -288.131037)
			(xy 373.168015 -288.186197) (xy 373.159274 -288.212784) (xy 373.151654 -288.234628) (xy 373.355616 -288.587942)
			(xy 373.378476 -288.59226) (xy 373.404538 -288.597688) (xy 373.454611 -288.615752) (xy 373.501141 -288.64161)
			(xy 373.542926 -288.67459) (xy 373.578883 -288.713842) (xy 373.608084 -288.75835) (xy 373.629774 -288.806963)
			(xy 373.643391 -288.858424) (xy 373.646446 -288.884868) (xy 373.650764 -288.930588) (xy 373.924068 -288.930588)
			(xy 373.928386 -288.884868) (xy 373.931369 -288.8594) (xy 373.944195 -288.809754) (xy 373.964533 -288.762685)
			(xy 373.991897 -288.719322) (xy 374.02563 -288.680705) (xy 374.064921 -288.64776) (xy 374.108829 -288.621279)
			(xy 374.1563 -288.601897) (xy 374.206195 -288.590078) (xy 374.257316 -288.586107) (xy 374.308437 -288.590078)
			(xy 374.358332 -288.601897) (xy 374.405803 -288.621279) (xy 374.449711 -288.64776) (xy 374.489002 -288.680705)
			(xy 374.522735 -288.719322) (xy 374.550099 -288.762685) (xy 374.570437 -288.809754) (xy 374.583263 -288.8594)
			(xy 374.586246 -288.884868) (xy 374.590564 -288.930588) (xy 374.863868 -288.930588) (xy 374.868186 -288.884868)
			(xy 374.870456 -288.865099) (xy 374.879119 -288.82626) (xy 374.885458 -288.807398) (xy 374.893078 -288.7853)
			(xy 374.68937 -288.43224) (xy 374.66651 -288.427922) (xy 374.641567 -288.422784) (xy 374.593536 -288.405862)
			(xy 374.54867 -288.381771) (xy 374.508031 -288.351083) (xy 374.472581 -288.314523) (xy 374.44316 -288.272958)
			(xy 374.420463 -288.227371) (xy 374.405029 -288.178841) (xy 374.397224 -288.128518) (xy 374.396762 -288.103056)
			(xy 374.397271 -288.077089) (xy 374.405396 -288.025794) (xy 374.421444 -287.976401) (xy 374.445022 -287.930127)
			(xy 374.475548 -287.888111) (xy 374.512271 -287.851388) (xy 374.554287 -287.820862) (xy 374.600561 -287.797284)
			(xy 374.649954 -287.781236) (xy 374.701249 -287.773111) (xy 374.753183 -287.773111) (xy 374.804478 -287.781236)
			(xy 374.853871 -287.797284) (xy 374.900145 -287.820862) (xy 374.942161 -287.851388) (xy 374.978884 -287.888111)
			(xy 375.00941 -287.930127) (xy 375.032988 -287.976401) (xy 375.049036 -288.025794) (xy 375.057161 -288.077089)
			(xy 375.05767 -288.103056) (xy 375.05706 -288.131037) (xy 375.047615 -288.186197) (xy 375.038874 -288.212784)
			(xy 375.031254 -288.234628) (xy 375.235216 -288.587942) (xy 375.258076 -288.59226) (xy 375.284138 -288.597688)
			(xy 375.334211 -288.615752) (xy 375.380741 -288.64161) (xy 375.422526 -288.67459) (xy 375.458483 -288.713842)
			(xy 375.487684 -288.75835) (xy 375.509374 -288.806963) (xy 375.522991 -288.858424) (xy 375.526046 -288.884868)
			(xy 375.530364 -288.930588) (xy 375.803668 -288.930588) (xy 375.807986 -288.884868) (xy 375.810969 -288.8594)
			(xy 375.823795 -288.809754) (xy 375.844133 -288.762685) (xy 375.871497 -288.719322) (xy 375.90523 -288.680705)
			(xy 375.944521 -288.64776) (xy 375.988429 -288.621279) (xy 376.0359 -288.601897) (xy 376.085795 -288.590078)
			(xy 376.136916 -288.586107) (xy 376.188037 -288.590078) (xy 376.237932 -288.601897) (xy 376.285403 -288.621279)
			(xy 376.329311 -288.64776) (xy 376.368602 -288.680705) (xy 376.402335 -288.719322) (xy 376.429699 -288.762685)
			(xy 376.450037 -288.809754) (xy 376.462863 -288.8594) (xy 376.465846 -288.884868) (xy 376.470164 -288.930588)
			(xy 376.743468 -288.930588) (xy 376.747786 -288.884868) (xy 376.750056 -288.865099) (xy 376.758719 -288.82626)
			(xy 376.765058 -288.807398) (xy 376.772678 -288.7853) (xy 376.56897 -288.43224) (xy 376.54611 -288.427922)
			(xy 376.521167 -288.422784) (xy 376.473136 -288.405862) (xy 376.42827 -288.381771) (xy 376.387631 -288.351083)
			(xy 376.352181 -288.314523) (xy 376.32276 -288.272958) (xy 376.300063 -288.227371) (xy 376.284629 -288.178841)
			(xy 376.276824 -288.128518) (xy 376.276362 -288.103056) (xy 376.276871 -288.077089) (xy 376.284996 -288.025794)
			(xy 376.301044 -287.976401) (xy 376.324622 -287.930127) (xy 376.355148 -287.888111) (xy 376.391871 -287.851388)
			(xy 376.433887 -287.820862) (xy 376.480161 -287.797284) (xy 376.529554 -287.781236) (xy 376.580849 -287.773111)
			(xy 376.632783 -287.773111) (xy 376.684078 -287.781236) (xy 376.733471 -287.797284) (xy 376.779745 -287.820862)
			(xy 376.821761 -287.851388) (xy 376.858484 -287.888111) (xy 376.88901 -287.930127) (xy 376.912588 -287.976401)
			(xy 376.928636 -288.025794) (xy 376.936761 -288.077089) (xy 376.93727 -288.103056) (xy 376.93666 -288.131037)
			(xy 376.927215 -288.186197) (xy 376.918474 -288.212784) (xy 376.910854 -288.234628) (xy 377.114816 -288.587942)
			(xy 377.137676 -288.59226) (xy 377.163738 -288.597688) (xy 377.213811 -288.615752) (xy 377.260341 -288.64161)
			(xy 377.302126 -288.67459) (xy 377.338083 -288.713842) (xy 377.367284 -288.75835) (xy 377.388974 -288.806963)
			(xy 377.402591 -288.858424) (xy 377.405646 -288.884868) (xy 377.409964 -288.930588) (xy 377.683268 -288.930588)
			(xy 377.687586 -288.884868) (xy 377.690569 -288.8594) (xy 377.703395 -288.809754) (xy 377.723733 -288.762685)
			(xy 377.751097 -288.719322) (xy 377.78483 -288.680705) (xy 377.824121 -288.64776) (xy 377.868029 -288.621279)
			(xy 377.9155 -288.601897) (xy 377.965395 -288.590078) (xy 378.016516 -288.586107) (xy 378.067637 -288.590078)
			(xy 378.117532 -288.601897) (xy 378.165003 -288.621279) (xy 378.208911 -288.64776) (xy 378.248202 -288.680705)
			(xy 378.281935 -288.719322) (xy 378.309299 -288.762685) (xy 378.329637 -288.809754) (xy 378.342463 -288.8594)
			(xy 378.345446 -288.884868) (xy 378.349764 -288.930588) (xy 378.623068 -288.930588) (xy 378.627386 -288.884868)
			(xy 378.629656 -288.865099) (xy 378.638319 -288.82626) (xy 378.644658 -288.807398) (xy 378.652278 -288.7853)
			(xy 378.44857 -288.43224) (xy 378.42571 -288.427922) (xy 378.400767 -288.422784) (xy 378.352736 -288.405862)
			(xy 378.30787 -288.381771) (xy 378.267231 -288.351083) (xy 378.231781 -288.314523) (xy 378.20236 -288.272958)
			(xy 378.179663 -288.227371) (xy 378.164229 -288.178841) (xy 378.156424 -288.128518) (xy 378.155962 -288.103056)
			(xy 378.156471 -288.077089) (xy 378.164596 -288.025794) (xy 378.180644 -287.976401) (xy 378.204222 -287.930127)
			(xy 378.234748 -287.888111) (xy 378.271471 -287.851388) (xy 378.313487 -287.820862) (xy 378.359761 -287.797284)
			(xy 378.409154 -287.781236) (xy 378.460449 -287.773111) (xy 378.512383 -287.773111) (xy 378.563678 -287.781236)
			(xy 378.613071 -287.797284) (xy 378.659345 -287.820862) (xy 378.701361 -287.851388) (xy 378.738084 -287.888111)
			(xy 378.76861 -287.930127) (xy 378.792188 -287.976401) (xy 378.808236 -288.025794) (xy 378.816361 -288.077089)
			(xy 378.81687 -288.103056) (xy 378.81626 -288.131037) (xy 378.806815 -288.186197) (xy 378.798074 -288.212784)
			(xy 378.790454 -288.234628) (xy 378.994416 -288.587942) (xy 379.017276 -288.59226) (xy 379.043338 -288.597688)
			(xy 379.093411 -288.615752) (xy 379.139941 -288.64161) (xy 379.181726 -288.67459) (xy 379.217683 -288.713842)
			(xy 379.246884 -288.75835) (xy 379.268574 -288.806963) (xy 379.282191 -288.858424) (xy 379.285246 -288.884868)
			(xy 379.289564 -288.930588) (xy 379.562868 -288.930588) (xy 379.567186 -288.884868) (xy 379.570169 -288.8594)
			(xy 379.582995 -288.809754) (xy 379.603333 -288.762685) (xy 379.630697 -288.719322) (xy 379.66443 -288.680705)
			(xy 379.703721 -288.64776) (xy 379.747629 -288.621279) (xy 379.7951 -288.601897) (xy 379.844995 -288.590078)
			(xy 379.896116 -288.586107) (xy 379.947237 -288.590078) (xy 379.997132 -288.601897) (xy 380.044603 -288.621279)
			(xy 380.088511 -288.64776) (xy 380.127802 -288.680705) (xy 380.161535 -288.719322) (xy 380.188899 -288.762685)
			(xy 380.209237 -288.809754) (xy 380.222063 -288.8594) (xy 380.225046 -288.884868) (xy 380.229364 -288.930588)
			(xy 380.502668 -288.930588) (xy 380.506986 -288.884868) (xy 380.509256 -288.865099) (xy 380.517919 -288.82626)
			(xy 380.524258 -288.807398) (xy 380.531878 -288.7853) (xy 380.32817 -288.43224) (xy 380.30531 -288.427922)
			(xy 380.280367 -288.422784) (xy 380.232336 -288.405862) (xy 380.18747 -288.381771) (xy 380.146831 -288.351083)
			(xy 380.111381 -288.314523) (xy 380.08196 -288.272958) (xy 380.059263 -288.227371) (xy 380.043829 -288.178841)
			(xy 380.036024 -288.128518) (xy 380.035562 -288.103056) (xy 380.036071 -288.077089) (xy 380.044196 -288.025794)
			(xy 380.060244 -287.976401) (xy 380.083822 -287.930127) (xy 380.114348 -287.888111) (xy 380.151071 -287.851388)
			(xy 380.193087 -287.820862) (xy 380.239361 -287.797284) (xy 380.288754 -287.781236) (xy 380.340049 -287.773111)
			(xy 380.391983 -287.773111) (xy 380.443278 -287.781236) (xy 380.492671 -287.797284) (xy 380.538945 -287.820862)
			(xy 380.580961 -287.851388) (xy 380.617684 -287.888111) (xy 380.64821 -287.930127) (xy 380.671788 -287.976401)
			(xy 380.687836 -288.025794) (xy 380.695961 -288.077089) (xy 380.69647 -288.103056) (xy 380.695904 -288.129023)
			(xy 381.915671 -288.129023) (xy 381.915671 -288.077089) (xy 381.923796 -288.025794) (xy 381.939844 -287.976401)
			(xy 381.963422 -287.930127) (xy 381.993948 -287.888111) (xy 382.030671 -287.851388) (xy 382.072687 -287.820862)
			(xy 382.118961 -287.797284) (xy 382.168354 -287.781236) (xy 382.219649 -287.773111) (xy 382.271583 -287.773111)
			(xy 382.322878 -287.781236) (xy 382.372271 -287.797284) (xy 382.418545 -287.820862) (xy 382.460561 -287.851388)
			(xy 382.497284 -287.888111) (xy 382.52781 -287.930127) (xy 382.551388 -287.976401) (xy 382.567436 -288.025794)
			(xy 382.575561 -288.077089) (xy 382.57607 -288.103056) (xy 382.575561 -288.129023) (xy 382.567436 -288.180318)
			(xy 382.551388 -288.229711) (xy 382.52781 -288.275985) (xy 382.497284 -288.318001) (xy 382.460561 -288.354724)
			(xy 382.418545 -288.38525) (xy 382.372271 -288.408828) (xy 382.322878 -288.424876) (xy 382.271583 -288.433001)
			(xy 382.219649 -288.433001) (xy 382.168354 -288.424876) (xy 382.118961 -288.408828) (xy 382.072687 -288.38525)
			(xy 382.030671 -288.354724) (xy 381.993948 -288.318001) (xy 381.963422 -288.275985) (xy 381.939844 -288.229711)
			(xy 381.923796 -288.180318) (xy 381.915671 -288.129023) (xy 380.695904 -288.129023) (xy 380.69586 -288.131037)
			(xy 380.686415 -288.186197) (xy 380.677674 -288.212784) (xy 380.670054 -288.234628) (xy 380.874016 -288.587942)
			(xy 380.896876 -288.59226) (xy 380.922938 -288.597688) (xy 380.973011 -288.615752) (xy 381.019541 -288.64161)
			(xy 381.061326 -288.67459) (xy 381.097283 -288.713842) (xy 381.126484 -288.75835) (xy 381.148174 -288.806963)
			(xy 381.161791 -288.858424) (xy 381.164846 -288.884868) (xy 381.169164 -288.930588) (xy 381.442468 -288.930588)
			(xy 381.446786 -288.884868) (xy 381.449769 -288.8594) (xy 381.462595 -288.809754) (xy 381.482933 -288.762685)
			(xy 381.510297 -288.719322) (xy 381.54403 -288.680705) (xy 381.583321 -288.64776) (xy 381.627229 -288.621279)
			(xy 381.6747 -288.601897) (xy 381.724595 -288.590078) (xy 381.775716 -288.586107) (xy 381.826837 -288.590078)
			(xy 381.876732 -288.601897) (xy 381.924203 -288.621279) (xy 381.968111 -288.64776) (xy 382.007402 -288.680705)
			(xy 382.041135 -288.719322) (xy 382.068499 -288.762685) (xy 382.088837 -288.809754) (xy 382.101663 -288.8594)
			(xy 382.104646 -288.884868) (xy 382.108964 -288.930588) (xy 382.23698 -288.930588) (xy 382.459992 -288.707576)
			(xy 382.461516 -288.705798) (xy 382.47131 -288.69429) (xy 382.49268 -288.67292) (xy 382.504188 -288.663126)
			(xy 382.505966 -288.661602) (xy 382.897888 -288.26968) (xy 382.883664 -288.237676) (xy 382.874618 -288.216397)
			(xy 382.861847 -288.171958) (xy 382.855381 -288.126174) (xy 382.854962 -288.103056) (xy 382.855475 -288.077092)
			(xy 382.863604 -288.025803) (xy 382.879657 -287.976417) (xy 382.903237 -287.93015) (xy 382.933765 -287.888142)
			(xy 382.970488 -287.851426) (xy 383.012502 -287.820906) (xy 383.058773 -287.797334) (xy 383.108161 -287.78129)
			(xy 383.159451 -287.77317) (xy 383.185416 -287.772602) (xy 383.208538 -287.772986) (xy 383.254329 -287.779436)
			(xy 383.298769 -287.792222) (xy 383.320036 -287.801304) (xy 383.35204 -287.815528) (xy 383.4638 -287.703768)
			(xy 383.473653 -287.693215) (xy 383.487547 -287.667921) (xy 383.493809 -287.639751) (xy 383.491939 -287.610953)
			(xy 383.482088 -287.583828) (xy 383.465041 -287.560543) (xy 383.453894 -287.551368) (xy 383.434161 -287.53562)
			(xy 383.399252 -287.49915) (xy 383.370293 -287.457797) (xy 383.347958 -287.412521) (xy 383.332766 -287.364377)
			(xy 383.325069 -287.314482) (xy 383.324608 -287.28924) (xy 383.325088 -287.263268) (xy 383.333208 -287.211961)
			(xy 383.349253 -287.162557) (xy 383.37283 -287.116271) (xy 383.403358 -287.074243) (xy 383.440084 -287.037509)
			(xy 383.482105 -287.006971) (xy 383.528385 -286.983383) (xy 383.577785 -286.967326) (xy 383.62909 -286.959194)
			(xy 383.655062 -286.958786) (xy 383.679398 -286.959212) (xy 383.727543 -286.966352) (xy 383.774114 -286.980495)
			(xy 383.796286 -286.990536) (xy 383.809728 -286.996358) (xy 383.838665 -287.000849) (xy 383.867686 -286.996946)
			(xy 383.894408 -286.98497) (xy 383.916634 -286.965905) (xy 383.932539 -286.941319) (xy 383.940816 -286.91323)
			(xy 383.94132 -286.898588) (xy 383.94132 -286.749998) (xy 383.920823 -286.735734) (xy 383.883971 -286.702039)
			(xy 383.852604 -286.663186) (xy 383.827435 -286.620059) (xy 383.809039 -286.573636) (xy 383.797832 -286.524976)
			(xy 383.794069 -286.475183) (xy 383.797837 -286.425391) (xy 383.809049 -286.376732) (xy 383.82745 -286.330311)
			(xy 383.852622 -286.287186) (xy 383.883994 -286.248336) (xy 383.92085 -286.214645) (xy 383.94132 -286.200342)
			(xy 383.94132 -286.051752) (xy 383.940835 -286.037113) (xy 383.932528 -286.009039) (xy 383.91661 -285.984467)
			(xy 383.894383 -285.965411) (xy 383.867668 -285.953432) (xy 383.838654 -285.94951) (xy 383.809718 -285.953967)
			(xy 383.796286 -285.959804) (xy 383.774101 -285.969811) (xy 383.727531 -285.983941) (xy 383.679395 -285.99111)
			(xy 383.655062 -285.991554) (xy 383.629097 -285.991042) (xy 383.577806 -285.982913) (xy 383.528419 -285.966861)
			(xy 383.48215 -285.943281) (xy 383.44014 -285.912754) (xy 383.403421 -285.876032) (xy 383.372899 -285.834017)
			(xy 383.349325 -285.787746) (xy 383.333278 -285.738357) (xy 383.325155 -285.687065) (xy 383.325155 -285.635135)
			(xy 383.333278 -285.583843) (xy 383.349325 -285.534454) (xy 383.372899 -285.488183) (xy 383.403421 -285.446168)
			(xy 383.44014 -285.409446) (xy 383.48215 -285.378919) (xy 383.528419 -285.355339) (xy 383.577806 -285.339287)
			(xy 383.629097 -285.331158) (xy 383.655062 -285.330646) (xy 383.679398 -285.331073) (xy 383.727542 -285.338213)
			(xy 383.774112 -285.352359) (xy 383.796286 -285.362396) (xy 383.809727 -285.36822) (xy 383.83866 -285.372713)
			(xy 383.867679 -285.36881) (xy 383.894398 -285.356833) (xy 383.91662 -285.337767) (xy 383.932518 -285.313178)
			(xy 383.940785 -285.285089) (xy 383.94132 -285.270448) (xy 383.94132 -285.122112) (xy 383.920822 -285.107848)
			(xy 383.883967 -285.074153) (xy 383.852598 -285.035299) (xy 383.827428 -284.992171) (xy 383.80903 -284.945747)
			(xy 383.797821 -284.897085) (xy 383.794057 -284.847291) (xy 383.797824 -284.797497) (xy 383.809035 -284.748836)
			(xy 383.827436 -284.702413) (xy 383.852608 -284.659286) (xy 383.88398 -284.620434) (xy 383.920836 -284.586741)
			(xy 383.94132 -284.572456) (xy 383.94132 -284.038548) (xy 383.65684 -283.754068) (xy 383.108962 -283.754068)
			(xy 383.09445 -283.754585) (xy 383.066598 -283.762751) (xy 383.042162 -283.778413) (xy 383.023111 -283.80031)
			(xy 383.01098 -283.826678) (xy 383.006746 -283.855392) (xy 383.010751 -283.884139) (xy 383.016252 -283.897578)
			(xy 383.025543 -283.91906) (xy 383.038658 -283.96399) (xy 383.045302 -284.01032) (xy 383.045716 -284.033722)
			(xy 383.045207 -284.059689) (xy 383.037082 -284.110984) (xy 383.021034 -284.160377) (xy 382.997456 -284.206651)
			(xy 382.96693 -284.248667) (xy 382.930207 -284.28539) (xy 382.888191 -284.315916) (xy 382.841917 -284.339494)
			(xy 382.792524 -284.355542) (xy 382.741229 -284.363667) (xy 382.689295 -284.363667) (xy 382.638 -284.355542)
			(xy 382.588607 -284.339494) (xy 382.542333 -284.315916) (xy 382.500317 -284.28539) (xy 382.463594 -284.248667)
			(xy 382.433068 -284.206651) (xy 382.40949 -284.160377) (xy 382.393442 -284.110984) (xy 382.385317 -284.059689)
			(xy 382.384808 -284.033722) (xy 382.385429 -284.005041) (xy 382.395345 -283.948543) (xy 382.414865 -283.894605)
			(xy 382.443404 -283.844847) (xy 382.461262 -283.822394) (xy 382.490726 -283.786834) (xy 382.25476 -283.550868)
			(xy 382.234694 -283.550106) (xy 382.209853 -283.548835) (xy 382.160949 -283.53976) (xy 382.113957 -283.523456)
			(xy 382.069941 -283.500293) (xy 382.029894 -283.470793) (xy 381.994722 -283.435623) (xy 381.965219 -283.395578)
			(xy 381.942053 -283.351564) (xy 381.925746 -283.304573) (xy 381.916667 -283.25567) (xy 381.915416 -283.230828)
			(xy 381.914654 -283.210762) (xy 381.271272 -282.56738) (xy 381.260169 -282.557053) (xy 381.233408 -282.54283)
			(xy 381.203654 -282.537071) (xy 381.173518 -282.54028) (xy 381.145644 -282.552175) (xy 381.122477 -282.571714)
			(xy 381.113792 -282.584144) (xy 381.098459 -282.607068) (xy 381.061423 -282.647927) (xy 381.018111 -282.682063)
			(xy 380.969728 -282.708526) (xy 380.91762 -282.72658) (xy 380.863236 -282.735722) (xy 380.835662 -282.73629)
			(xy 380.809696 -282.735778) (xy 380.758403 -282.727649) (xy 380.709013 -282.711598) (xy 380.662742 -282.688018)
			(xy 380.620728 -282.657492) (xy 380.584007 -282.62077) (xy 380.553481 -282.578756) (xy 380.529902 -282.532485)
			(xy 380.51385 -282.483095) (xy 380.505722 -282.431802) (xy 380.505208 -282.405836) (xy 380.505208 -282.40355)
			(xy 380.504903 -282.390161) (xy 380.498133 -282.364257) (xy 380.484861 -282.341005) (xy 380.466 -282.322002)
			(xy 380.442847 -282.308557) (xy 380.416995 -282.301594) (xy 380.403608 -282.301188) (xy 380.327916 -282.301188)
			(xy 380.314527 -282.30159) (xy 380.288669 -282.308549) (xy 380.26551 -282.321993) (xy 380.246644 -282.340996)
			(xy 380.233368 -282.364251) (xy 380.226596 -282.390159) (xy 380.226316 -282.40355) (xy 380.226316 -282.405836)
			(xy 380.225807 -282.431803) (xy 380.217682 -282.483098) (xy 380.201634 -282.532491) (xy 380.178056 -282.578765)
			(xy 380.14753 -282.620781) (xy 380.110807 -282.657504) (xy 380.068791 -282.68803) (xy 380.022517 -282.711608)
			(xy 379.973124 -282.727656) (xy 379.921829 -282.735781) (xy 379.869895 -282.735781) (xy 379.8186 -282.727656)
			(xy 379.769207 -282.711608) (xy 379.722933 -282.68803) (xy 379.680917 -282.657504) (xy 379.644194 -282.620781)
			(xy 379.613668 -282.578765) (xy 379.59009 -282.532491) (xy 379.574042 -282.483098) (xy 379.565917 -282.431803)
			(xy 379.565408 -282.405836) (xy 379.565408 -282.40355) (xy 379.565103 -282.390161) (xy 379.558333 -282.364257)
			(xy 379.545061 -282.341005) (xy 379.5262 -282.322002) (xy 379.503047 -282.308557) (xy 379.477195 -282.301594)
			(xy 379.463808 -282.301188) (xy 379.388116 -282.301188) (xy 379.374727 -282.30159) (xy 379.348869 -282.308549)
			(xy 379.32571 -282.321993) (xy 379.306844 -282.340996) (xy 379.293568 -282.364251) (xy 379.286796 -282.390159)
			(xy 379.286516 -282.40355) (xy 379.286516 -282.405836) (xy 379.286007 -282.431803) (xy 379.277882 -282.483098)
			(xy 379.261834 -282.532491) (xy 379.238256 -282.578765) (xy 379.20773 -282.620781) (xy 379.171007 -282.657504)
			(xy 379.128991 -282.68803) (xy 379.082717 -282.711608) (xy 379.033324 -282.727656) (xy 378.982029 -282.735781)
			(xy 378.930095 -282.735781) (xy 378.8788 -282.727656) (xy 378.829407 -282.711608) (xy 378.783133 -282.68803)
			(xy 378.741117 -282.657504) (xy 378.704394 -282.620781) (xy 378.673868 -282.578765) (xy 378.65029 -282.532491)
			(xy 378.634242 -282.483098) (xy 378.626117 -282.431803) (xy 378.625608 -282.405836) (xy 378.625608 -282.40355)
			(xy 378.625303 -282.390161) (xy 378.618533 -282.364257) (xy 378.605261 -282.341005) (xy 378.5864 -282.322002)
			(xy 378.563247 -282.308557) (xy 378.537395 -282.301594) (xy 378.524008 -282.301188) (xy 378.44857 -282.301188)
			(xy 378.435185 -282.301596) (xy 378.409337 -282.308563) (xy 378.386189 -282.322009) (xy 378.367333 -282.341011)
			(xy 378.354064 -282.364262) (xy 378.347296 -282.390162) (xy 378.34697 -282.40355) (xy 378.34697 -282.405582)
			(xy 378.346461 -282.431549) (xy 378.338336 -282.482844) (xy 378.322288 -282.532237) (xy 378.29871 -282.578511)
			(xy 378.268184 -282.620527) (xy 378.231461 -282.65725) (xy 378.189445 -282.687776) (xy 378.143171 -282.711354)
			(xy 378.093778 -282.727402) (xy 378.042483 -282.735527) (xy 377.990549 -282.735527) (xy 377.939254 -282.727402)
			(xy 377.889861 -282.711354) (xy 377.843587 -282.687776) (xy 377.801571 -282.65725) (xy 377.764848 -282.620527)
			(xy 377.734322 -282.578511) (xy 377.710744 -282.532237) (xy 377.694696 -282.482844) (xy 377.686571 -282.431549)
			(xy 377.686062 -282.405582) (xy 377.686062 -282.40355) (xy 377.685757 -282.390163) (xy 377.678986 -282.364264)
			(xy 377.665713 -282.341017) (xy 377.646851 -282.322022) (xy 377.623697 -282.308586) (xy 377.597847 -282.301634)
			(xy 377.584462 -282.301188) (xy 377.50877 -282.301188) (xy 377.495385 -282.301596) (xy 377.469537 -282.308563)
			(xy 377.446389 -282.322009) (xy 377.427533 -282.341011) (xy 377.414264 -282.364262) (xy 377.407496 -282.390162)
			(xy 377.40717 -282.40355) (xy 377.40717 -282.405582) (xy 377.406661 -282.431549) (xy 377.398536 -282.482844)
			(xy 377.382488 -282.532237) (xy 377.35891 -282.578511) (xy 377.328384 -282.620527) (xy 377.291661 -282.65725)
			(xy 377.249645 -282.687776) (xy 377.203371 -282.711354) (xy 377.153978 -282.727402) (xy 377.102683 -282.735527)
			(xy 377.050749 -282.735527) (xy 376.999454 -282.727402) (xy 376.950061 -282.711354) (xy 376.903787 -282.687776)
			(xy 376.861771 -282.65725) (xy 376.825048 -282.620527) (xy 376.794522 -282.578511) (xy 376.770944 -282.532237)
			(xy 376.754896 -282.482844) (xy 376.746771 -282.431549) (xy 376.746262 -282.405582) (xy 376.746262 -282.40355)
			(xy 376.745957 -282.390163) (xy 376.739186 -282.364264) (xy 376.725913 -282.341017) (xy 376.707051 -282.322022)
			(xy 376.683897 -282.308586) (xy 376.658047 -282.301634) (xy 376.644662 -282.301188) (xy 376.56897 -282.301188)
			(xy 376.555585 -282.301596) (xy 376.529737 -282.308563) (xy 376.506589 -282.322009) (xy 376.487733 -282.341011)
			(xy 376.474464 -282.364262) (xy 376.467696 -282.390162) (xy 376.46737 -282.40355) (xy 376.46737 -282.405582)
			(xy 376.466861 -282.431549) (xy 376.458736 -282.482844) (xy 376.442688 -282.532237) (xy 376.41911 -282.578511)
			(xy 376.388584 -282.620527) (xy 376.351861 -282.65725) (xy 376.309845 -282.687776) (xy 376.263571 -282.711354)
			(xy 376.214178 -282.727402) (xy 376.162883 -282.735527) (xy 376.110949 -282.735527) (xy 376.059654 -282.727402)
			(xy 376.010261 -282.711354) (xy 375.963987 -282.687776) (xy 375.921971 -282.65725) (xy 375.885248 -282.620527)
			(xy 375.854722 -282.578511) (xy 375.831144 -282.532237) (xy 375.815096 -282.482844) (xy 375.806971 -282.431549)
			(xy 375.806462 -282.405582) (xy 375.806462 -282.40355) (xy 375.806157 -282.390163) (xy 375.799386 -282.364264)
			(xy 375.786113 -282.341017) (xy 375.767251 -282.322022) (xy 375.744097 -282.308586) (xy 375.718247 -282.301634)
			(xy 375.704862 -282.301188) (xy 375.62917 -282.301188) (xy 375.615785 -282.301596) (xy 375.589937 -282.308563)
			(xy 375.566789 -282.322009) (xy 375.547933 -282.341011) (xy 375.534664 -282.364262) (xy 375.527896 -282.390162)
			(xy 375.52757 -282.40355) (xy 375.52757 -282.405582) (xy 375.527061 -282.431549) (xy 375.518936 -282.482844)
			(xy 375.502888 -282.532237) (xy 375.47931 -282.578511) (xy 375.448784 -282.620527) (xy 375.412061 -282.65725)
			(xy 375.370045 -282.687776) (xy 375.323771 -282.711354) (xy 375.274378 -282.727402) (xy 375.223083 -282.735527)
			(xy 375.171149 -282.735527) (xy 375.119854 -282.727402) (xy 375.070461 -282.711354) (xy 375.024187 -282.687776)
			(xy 374.982171 -282.65725) (xy 374.945448 -282.620527) (xy 374.914922 -282.578511) (xy 374.891344 -282.532237)
			(xy 374.875296 -282.482844) (xy 374.867171 -282.431549) (xy 374.866662 -282.405582) (xy 374.866662 -282.40355)
			(xy 374.866357 -282.390163) (xy 374.859586 -282.364264) (xy 374.846313 -282.341017) (xy 374.827451 -282.322022)
			(xy 374.804297 -282.308586) (xy 374.778447 -282.301634) (xy 374.765062 -282.301188) (xy 374.68937 -282.301188)
			(xy 374.675985 -282.301596) (xy 374.650137 -282.308563) (xy 374.626989 -282.322009) (xy 374.608133 -282.341011)
			(xy 374.594864 -282.364262) (xy 374.588096 -282.390162) (xy 374.58777 -282.40355) (xy 374.58777 -282.405836)
			(xy 374.587261 -282.431803) (xy 374.579136 -282.483098) (xy 374.563088 -282.532491) (xy 374.53951 -282.578765)
			(xy 374.508984 -282.620781) (xy 374.472261 -282.657504) (xy 374.430245 -282.68803) (xy 374.383971 -282.711608)
			(xy 374.334578 -282.727656) (xy 374.283283 -282.735781) (xy 374.231349 -282.735781) (xy 374.180054 -282.727656)
			(xy 374.130661 -282.711608) (xy 374.084387 -282.68803) (xy 374.042371 -282.657504) (xy 374.005648 -282.620781)
			(xy 373.975122 -282.578765) (xy 373.951544 -282.532491) (xy 373.935496 -282.483098) (xy 373.927371 -282.431803)
			(xy 373.926862 -282.405836) (xy 373.926862 -282.40355) (xy 373.926557 -282.390163) (xy 373.919786 -282.364264)
			(xy 373.906513 -282.341017) (xy 373.887651 -282.322022) (xy 373.864497 -282.308586) (xy 373.838647 -282.301634)
			(xy 373.825262 -282.301188) (xy 373.749316 -282.301188) (xy 373.735927 -282.30159) (xy 373.710069 -282.308549)
			(xy 373.68691 -282.321993) (xy 373.668044 -282.340996) (xy 373.654768 -282.364251) (xy 373.647996 -282.390159)
			(xy 373.647716 -282.40355) (xy 373.647716 -282.405836) (xy 373.647207 -282.431803) (xy 373.639082 -282.483098)
			(xy 373.623034 -282.532491) (xy 373.599456 -282.578765) (xy 373.56893 -282.620781) (xy 373.532207 -282.657504)
			(xy 373.490191 -282.68803) (xy 373.443917 -282.711608) (xy 373.394524 -282.727656) (xy 373.343229 -282.735781)
			(xy 373.291295 -282.735781) (xy 373.24 -282.727656) (xy 373.190607 -282.711608) (xy 373.144333 -282.68803)
			(xy 373.102317 -282.657504) (xy 373.065594 -282.620781) (xy 373.035068 -282.578765) (xy 373.01149 -282.532491)
			(xy 372.995442 -282.483098) (xy 372.987317 -282.431803) (xy 372.986808 -282.405836) (xy 372.986808 -282.40355)
			(xy 372.986503 -282.390161) (xy 372.979733 -282.364257) (xy 372.966461 -282.341005) (xy 372.9476 -282.322002)
			(xy 372.924447 -282.308557) (xy 372.898595 -282.301594) (xy 372.885208 -282.301188) (xy 372.809516 -282.301188)
			(xy 372.796127 -282.30159) (xy 372.770269 -282.308549) (xy 372.74711 -282.321993) (xy 372.728244 -282.340996)
			(xy 372.714968 -282.364251) (xy 372.708196 -282.390159) (xy 372.707916 -282.40355) (xy 372.707916 -282.405836)
			(xy 372.707407 -282.431803) (xy 372.699282 -282.483098) (xy 372.683234 -282.532491) (xy 372.659656 -282.578765)
			(xy 372.62913 -282.620781) (xy 372.592407 -282.657504) (xy 372.550391 -282.68803) (xy 372.504117 -282.711608)
			(xy 372.454724 -282.727656) (xy 372.403429 -282.735781) (xy 372.351495 -282.735781) (xy 372.3002 -282.727656)
			(xy 372.250807 -282.711608) (xy 372.204533 -282.68803) (xy 372.162517 -282.657504) (xy 372.125794 -282.620781)
			(xy 372.095268 -282.578765) (xy 372.07169 -282.532491) (xy 372.055642 -282.483098) (xy 372.047517 -282.431803)
			(xy 372.047008 -282.405836) (xy 372.047008 -282.40355) (xy 372.046703 -282.390161) (xy 372.039933 -282.364257)
			(xy 372.026661 -282.341005) (xy 372.0078 -282.322002) (xy 371.984647 -282.308557) (xy 371.958795 -282.301594)
			(xy 371.945408 -282.301188) (xy 371.869716 -282.301188) (xy 371.856327 -282.30159) (xy 371.830469 -282.308549)
			(xy 371.80731 -282.321993) (xy 371.788444 -282.340996) (xy 371.775168 -282.364251) (xy 371.768396 -282.390159)
			(xy 371.768116 -282.40355) (xy 371.768116 -282.405836) (xy 371.76763 -282.431802) (xy 371.759501 -282.483095)
			(xy 371.743447 -282.532484) (xy 371.719865 -282.578754) (xy 371.689335 -282.620765) (xy 371.652609 -282.657483)
			(xy 371.610591 -282.688004) (xy 371.564316 -282.711576) (xy 371.514923 -282.727618) (xy 371.463628 -282.735736)
			(xy 371.437662 -282.73629) (xy 371.410596 -282.735745) (xy 371.357189 -282.726921) (xy 371.305933 -282.709513)
			(xy 371.258198 -282.683987) (xy 371.215259 -282.651026) (xy 371.196362 -282.631642) (xy 371.18675 -282.621989)
			(xy 371.16356 -282.607717) (xy 371.137419 -282.600093) (xy 371.110192 -282.59966) (xy 371.083822 -282.60645)
			(xy 371.06019 -282.619978) (xy 371.050312 -282.629356) (xy 370.959126 -282.720542) (xy 370.949484 -282.730797)
			(xy 370.935739 -282.755349) (xy 370.929213 -282.782719) (xy 370.930402 -282.810831) (xy 370.939215 -282.837553)
			(xy 370.954984 -282.860857) (xy 370.976512 -282.878975) (xy 371.002166 -282.890532) (xy 371.016022 -282.893008)
			(xy 371.041846 -282.897305) (xy 371.091792 -282.91298) (xy 371.138642 -282.936334) (xy 371.181226 -282.96678)
			(xy 371.218477 -283.003559) (xy 371.249465 -283.04575) (xy 371.273414 -283.092299) (xy 371.289726 -283.142041)
			(xy 371.297993 -283.193732) (xy 371.29847 -283.219906) (xy 371.29796 -283.245873) (xy 372.517671 -283.245873)
			(xy 372.517671 -283.193939) (xy 372.525796 -283.142644) (xy 372.541844 -283.093251) (xy 372.565422 -283.046977)
			(xy 372.595948 -283.004961) (xy 372.632671 -282.968238) (xy 372.674687 -282.937712) (xy 372.720961 -282.914134)
			(xy 372.770354 -282.898086) (xy 372.821649 -282.889961) (xy 372.873583 -282.889961) (xy 372.924878 -282.898086)
			(xy 372.974271 -282.914134) (xy 373.020545 -282.937712) (xy 373.062561 -282.968238) (xy 373.099284 -283.004961)
			(xy 373.12981 -283.046977) (xy 373.153388 -283.093251) (xy 373.169436 -283.142644) (xy 373.177561 -283.193939)
			(xy 373.17807 -283.219906) (xy 373.177561 -283.245873) (xy 373.457471 -283.245873) (xy 373.457471 -283.193939)
			(xy 373.465596 -283.142644) (xy 373.481644 -283.093251) (xy 373.505222 -283.046977) (xy 373.535748 -283.004961)
			(xy 373.572471 -282.968238) (xy 373.614487 -282.937712) (xy 373.660761 -282.914134) (xy 373.710154 -282.898086)
			(xy 373.761449 -282.889961) (xy 373.813383 -282.889961) (xy 373.864678 -282.898086) (xy 373.914071 -282.914134)
			(xy 373.960345 -282.937712) (xy 374.002361 -282.968238) (xy 374.039084 -283.004961) (xy 374.06961 -283.046977)
			(xy 374.093188 -283.093251) (xy 374.109236 -283.142644) (xy 374.117361 -283.193939) (xy 374.11787 -283.219906)
			(xy 374.117361 -283.245873) (xy 374.397017 -283.245873) (xy 374.397017 -283.193939) (xy 374.405142 -283.142644)
			(xy 374.42119 -283.093251) (xy 374.444768 -283.046977) (xy 374.475294 -283.004961) (xy 374.512017 -282.968238)
			(xy 374.554033 -282.937712) (xy 374.600307 -282.914134) (xy 374.6497 -282.898086) (xy 374.700995 -282.889961)
			(xy 374.752929 -282.889961) (xy 374.804224 -282.898086) (xy 374.853617 -282.914134) (xy 374.899891 -282.937712)
			(xy 374.941907 -282.968238) (xy 374.97863 -283.004961) (xy 375.009156 -283.046977) (xy 375.032734 -283.093251)
			(xy 375.048782 -283.142644) (xy 375.056907 -283.193939) (xy 375.057416 -283.219906) (xy 375.056912 -283.245619)
			(xy 376.276617 -283.245619) (xy 376.276617 -283.193685) (xy 376.284742 -283.14239) (xy 376.30079 -283.092997)
			(xy 376.324368 -283.046723) (xy 376.354894 -283.004707) (xy 376.391617 -282.967984) (xy 376.433633 -282.937458)
			(xy 376.479907 -282.91388) (xy 376.5293 -282.897832) (xy 376.580595 -282.889707) (xy 376.632529 -282.889707)
			(xy 376.683824 -282.897832) (xy 376.733217 -282.91388) (xy 376.779491 -282.937458) (xy 376.821507 -282.967984)
			(xy 376.85823 -283.004707) (xy 376.888756 -283.046723) (xy 376.912334 -283.092997) (xy 376.928382 -283.14239)
			(xy 376.936507 -283.193685) (xy 376.937016 -283.219652) (xy 376.936507 -283.245619) (xy 376.936467 -283.245873)
			(xy 377.216417 -283.245873) (xy 377.216417 -283.193939) (xy 377.224542 -283.142644) (xy 377.24059 -283.093251)
			(xy 377.264168 -283.046977) (xy 377.294694 -283.004961) (xy 377.331417 -282.968238) (xy 377.373433 -282.937712)
			(xy 377.419707 -282.914134) (xy 377.4691 -282.898086) (xy 377.520395 -282.889961) (xy 377.572329 -282.889961)
			(xy 377.623624 -282.898086) (xy 377.673017 -282.914134) (xy 377.719291 -282.937712) (xy 377.761307 -282.968238)
			(xy 377.79803 -283.004961) (xy 377.828556 -283.046977) (xy 377.852134 -283.093251) (xy 377.868182 -283.142644)
			(xy 377.876307 -283.193939) (xy 377.876816 -283.219906) (xy 377.876307 -283.245873) (xy 378.156217 -283.245873)
			(xy 378.156217 -283.193939) (xy 378.164342 -283.142644) (xy 378.18039 -283.093251) (xy 378.203968 -283.046977)
			(xy 378.234494 -283.004961) (xy 378.271217 -282.968238) (xy 378.313233 -282.937712) (xy 378.359507 -282.914134)
			(xy 378.4089 -282.898086) (xy 378.460195 -282.889961) (xy 378.512129 -282.889961) (xy 378.563424 -282.898086)
			(xy 378.612817 -282.914134) (xy 378.659091 -282.937712) (xy 378.701107 -282.968238) (xy 378.73783 -283.004961)
			(xy 378.768356 -283.046977) (xy 378.791934 -283.093251) (xy 378.807982 -283.142644) (xy 378.816107 -283.193939)
			(xy 378.816616 -283.219906) (xy 378.816107 -283.245873) (xy 379.096271 -283.245873) (xy 379.096271 -283.193939)
			(xy 379.104396 -283.142644) (xy 379.120444 -283.093251) (xy 379.144022 -283.046977) (xy 379.174548 -283.004961)
			(xy 379.211271 -282.968238) (xy 379.253287 -282.937712) (xy 379.299561 -282.914134) (xy 379.348954 -282.898086)
			(xy 379.400249 -282.889961) (xy 379.452183 -282.889961) (xy 379.503478 -282.898086) (xy 379.552871 -282.914134)
			(xy 379.599145 -282.937712) (xy 379.641161 -282.968238) (xy 379.677884 -283.004961) (xy 379.70841 -283.046977)
			(xy 379.731988 -283.093251) (xy 379.748036 -283.142644) (xy 379.756161 -283.193939) (xy 379.75667 -283.219906)
			(xy 379.756161 -283.245873) (xy 380.035817 -283.245873) (xy 380.035817 -283.193939) (xy 380.043942 -283.142644)
			(xy 380.05999 -283.093251) (xy 380.083568 -283.046977) (xy 380.114094 -283.004961) (xy 380.150817 -282.968238)
			(xy 380.192833 -282.937712) (xy 380.239107 -282.914134) (xy 380.2885 -282.898086) (xy 380.339795 -282.889961)
			(xy 380.391729 -282.889961) (xy 380.443024 -282.898086) (xy 380.492417 -282.914134) (xy 380.538691 -282.937712)
			(xy 380.580707 -282.968238) (xy 380.61743 -283.004961) (xy 380.647956 -283.046977) (xy 380.671534 -283.093251)
			(xy 380.687582 -283.142644) (xy 380.695707 -283.193939) (xy 380.696216 -283.219906) (xy 380.695707 -283.245873)
			(xy 380.975871 -283.245873) (xy 380.975871 -283.193939) (xy 380.983996 -283.142644) (xy 381.000044 -283.093251)
			(xy 381.023622 -283.046977) (xy 381.054148 -283.004961) (xy 381.090871 -282.968238) (xy 381.132887 -282.937712)
			(xy 381.179161 -282.914134) (xy 381.228554 -282.898086) (xy 381.279849 -282.889961) (xy 381.331783 -282.889961)
			(xy 381.383078 -282.898086) (xy 381.432471 -282.914134) (xy 381.478745 -282.937712) (xy 381.520761 -282.968238)
			(xy 381.557484 -283.004961) (xy 381.58801 -283.046977) (xy 381.611588 -283.093251) (xy 381.627636 -283.142644)
			(xy 381.635761 -283.193939) (xy 381.63627 -283.219906) (xy 381.635761 -283.245873) (xy 381.627636 -283.297168)
			(xy 381.611588 -283.346561) (xy 381.58801 -283.392835) (xy 381.557484 -283.434851) (xy 381.520761 -283.471574)
			(xy 381.478745 -283.5021) (xy 381.432471 -283.525678) (xy 381.383078 -283.541726) (xy 381.331783 -283.549851)
			(xy 381.279849 -283.549851) (xy 381.228554 -283.541726) (xy 381.179161 -283.525678) (xy 381.132887 -283.5021)
			(xy 381.090871 -283.471574) (xy 381.054148 -283.434851) (xy 381.023622 -283.392835) (xy 381.000044 -283.346561)
			(xy 380.983996 -283.297168) (xy 380.975871 -283.245873) (xy 380.695707 -283.245873) (xy 380.687582 -283.297168)
			(xy 380.671534 -283.346561) (xy 380.647956 -283.392835) (xy 380.61743 -283.434851) (xy 380.580707 -283.471574)
			(xy 380.538691 -283.5021) (xy 380.492417 -283.525678) (xy 380.443024 -283.541726) (xy 380.391729 -283.549851)
			(xy 380.339795 -283.549851) (xy 380.2885 -283.541726) (xy 380.239107 -283.525678) (xy 380.192833 -283.5021)
			(xy 380.150817 -283.471574) (xy 380.114094 -283.434851) (xy 380.083568 -283.392835) (xy 380.05999 -283.346561)
			(xy 380.043942 -283.297168) (xy 380.035817 -283.245873) (xy 379.756161 -283.245873) (xy 379.748036 -283.297168)
			(xy 379.731988 -283.346561) (xy 379.70841 -283.392835) (xy 379.677884 -283.434851) (xy 379.641161 -283.471574)
			(xy 379.599145 -283.5021) (xy 379.552871 -283.525678) (xy 379.503478 -283.541726) (xy 379.452183 -283.549851)
			(xy 379.400249 -283.549851) (xy 379.348954 -283.541726) (xy 379.299561 -283.525678) (xy 379.253287 -283.5021)
			(xy 379.211271 -283.471574) (xy 379.174548 -283.434851) (xy 379.144022 -283.392835) (xy 379.120444 -283.346561)
			(xy 379.104396 -283.297168) (xy 379.096271 -283.245873) (xy 378.816107 -283.245873) (xy 378.807982 -283.297168)
			(xy 378.791934 -283.346561) (xy 378.768356 -283.392835) (xy 378.73783 -283.434851) (xy 378.701107 -283.471574)
			(xy 378.659091 -283.5021) (xy 378.612817 -283.525678) (xy 378.563424 -283.541726) (xy 378.512129 -283.549851)
			(xy 378.460195 -283.549851) (xy 378.4089 -283.541726) (xy 378.359507 -283.525678) (xy 378.313233 -283.5021)
			(xy 378.271217 -283.471574) (xy 378.234494 -283.434851) (xy 378.203968 -283.392835) (xy 378.18039 -283.346561)
			(xy 378.164342 -283.297168) (xy 378.156217 -283.245873) (xy 377.876307 -283.245873) (xy 377.868182 -283.297168)
			(xy 377.852134 -283.346561) (xy 377.828556 -283.392835) (xy 377.79803 -283.434851) (xy 377.761307 -283.471574)
			(xy 377.719291 -283.5021) (xy 377.673017 -283.525678) (xy 377.623624 -283.541726) (xy 377.572329 -283.549851)
			(xy 377.520395 -283.549851) (xy 377.4691 -283.541726) (xy 377.419707 -283.525678) (xy 377.373433 -283.5021)
			(xy 377.331417 -283.471574) (xy 377.294694 -283.434851) (xy 377.264168 -283.392835) (xy 377.24059 -283.346561)
			(xy 377.224542 -283.297168) (xy 377.216417 -283.245873) (xy 376.936467 -283.245873) (xy 376.928382 -283.296914)
			(xy 376.912334 -283.346307) (xy 376.888756 -283.392581) (xy 376.85823 -283.434597) (xy 376.821507 -283.47132)
			(xy 376.779491 -283.501846) (xy 376.733217 -283.525424) (xy 376.683824 -283.541472) (xy 376.632529 -283.549597)
			(xy 376.580595 -283.549597) (xy 376.5293 -283.541472) (xy 376.479907 -283.525424) (xy 376.433633 -283.501846)
			(xy 376.391617 -283.47132) (xy 376.354894 -283.434597) (xy 376.324368 -283.392581) (xy 376.30079 -283.346307)
			(xy 376.284742 -283.296914) (xy 376.276617 -283.245619) (xy 375.056912 -283.245619) (xy 375.056907 -283.245873)
			(xy 375.048782 -283.297168) (xy 375.032734 -283.346561) (xy 375.009156 -283.392835) (xy 374.97863 -283.434851)
			(xy 374.941907 -283.471574) (xy 374.899891 -283.5021) (xy 374.853617 -283.525678) (xy 374.804224 -283.541726)
			(xy 374.752929 -283.549851) (xy 374.700995 -283.549851) (xy 374.6497 -283.541726) (xy 374.600307 -283.525678)
			(xy 374.554033 -283.5021) (xy 374.512017 -283.471574) (xy 374.475294 -283.434851) (xy 374.444768 -283.392835)
			(xy 374.42119 -283.346561) (xy 374.405142 -283.297168) (xy 374.397017 -283.245873) (xy 374.117361 -283.245873)
			(xy 374.109236 -283.297168) (xy 374.093188 -283.346561) (xy 374.06961 -283.392835) (xy 374.039084 -283.434851)
			(xy 374.002361 -283.471574) (xy 373.960345 -283.5021) (xy 373.914071 -283.525678) (xy 373.864678 -283.541726)
			(xy 373.813383 -283.549851) (xy 373.761449 -283.549851) (xy 373.710154 -283.541726) (xy 373.660761 -283.525678)
			(xy 373.614487 -283.5021) (xy 373.572471 -283.471574) (xy 373.535748 -283.434851) (xy 373.505222 -283.392835)
			(xy 373.481644 -283.346561) (xy 373.465596 -283.297168) (xy 373.457471 -283.245873) (xy 373.177561 -283.245873)
			(xy 373.169436 -283.297168) (xy 373.153388 -283.346561) (xy 373.12981 -283.392835) (xy 373.099284 -283.434851)
			(xy 373.062561 -283.471574) (xy 373.020545 -283.5021) (xy 372.974271 -283.525678) (xy 372.924878 -283.541726)
			(xy 372.873583 -283.549851) (xy 372.821649 -283.549851) (xy 372.770354 -283.541726) (xy 372.720961 -283.525678)
			(xy 372.674687 -283.5021) (xy 372.632671 -283.471574) (xy 372.595948 -283.434851) (xy 372.565422 -283.392835)
			(xy 372.541844 -283.346561) (xy 372.525796 -283.297168) (xy 372.517671 -283.245873) (xy 371.29796 -283.245873)
			(xy 371.289835 -283.297169) (xy 371.273786 -283.346561) (xy 371.250209 -283.392836) (xy 371.219682 -283.434852)
			(xy 371.18296 -283.471576) (xy 371.140944 -283.502103) (xy 371.094671 -283.525683) (xy 371.045278 -283.541733)
			(xy 370.993983 -283.54986) (xy 370.968016 -283.55036) (xy 370.941842 -283.549862) (xy 370.890148 -283.541609)
			(xy 370.840402 -283.525306) (xy 370.79385 -283.501363) (xy 370.751657 -283.470377) (xy 370.714878 -283.433125)
			(xy 370.684434 -283.390539) (xy 370.661088 -283.343685) (xy 370.645422 -283.293735) (xy 370.641118 -283.267912)
			(xy 370.638643 -283.254044) (xy 370.627129 -283.228345) (xy 370.609026 -283.206775) (xy 370.585714 -283.190977)
			(xy 370.558971 -283.182156) (xy 370.530835 -283.180985) (xy 370.503451 -283.187551) (xy 370.478907 -283.201356)
			(xy 370.468652 -283.211016) (xy 370.333524 -283.346144) (xy 370.329714 -283.35478) (xy 370.316468 -283.382715)
			(xy 370.281177 -283.433467) (xy 370.25961 -283.455618) (xy 370.253362 -283.462245) (xy 370.245627 -283.47872)
			(xy 370.244172 -283.496862) (xy 370.249183 -283.514359) (xy 370.254276 -283.521912) (xy 370.282035 -283.560716)
			(xy 370.32977 -283.64333) (xy 370.349526 -283.686758) (xy 370.353499 -283.694929) (xy 370.366129 -283.707971)
			(xy 370.382533 -283.715752) (xy 370.400624 -283.717282) (xy 370.40947 -283.715206) (xy 370.431134 -283.709591)
			(xy 370.475485 -283.703596) (xy 370.497862 -283.703268) (xy 370.523832 -283.703748) (xy 370.575132 -283.711868)
			(xy 370.62453 -283.727913) (xy 370.67081 -283.751489) (xy 370.712832 -283.782015) (xy 370.74956 -283.818739)
			(xy 370.780091 -283.860758) (xy 370.803672 -283.907035) (xy 370.819723 -283.956431) (xy 370.827849 -284.007731)
			(xy 370.827849 -284.059669) (xy 370.827846 -284.059689) (xy 371.107717 -284.059689) (xy 371.107717 -284.007755)
			(xy 371.115842 -283.95646) (xy 371.13189 -283.907067) (xy 371.155468 -283.860793) (xy 371.185994 -283.818777)
			(xy 371.222717 -283.782054) (xy 371.264733 -283.751528) (xy 371.311007 -283.72795) (xy 371.3604 -283.711902)
			(xy 371.411695 -283.703777) (xy 371.463629 -283.703777) (xy 371.514924 -283.711902) (xy 371.564317 -283.72795)
			(xy 371.610591 -283.751528) (xy 371.652607 -283.782054) (xy 371.68933 -283.818777) (xy 371.719856 -283.860793)
			(xy 371.743434 -283.907067) (xy 371.759482 -283.95646) (xy 371.767607 -284.007755) (xy 371.768116 -284.033722)
			(xy 371.767607 -284.059689) (xy 372.047517 -284.059689) (xy 372.047517 -284.007755) (xy 372.055642 -283.95646)
			(xy 372.07169 -283.907067) (xy 372.095268 -283.860793) (xy 372.125794 -283.818777) (xy 372.162517 -283.782054)
			(xy 372.204533 -283.751528) (xy 372.250807 -283.72795) (xy 372.3002 -283.711902) (xy 372.351495 -283.703777)
			(xy 372.403429 -283.703777) (xy 372.454724 -283.711902) (xy 372.504117 -283.72795) (xy 372.550391 -283.751528)
			(xy 372.592407 -283.782054) (xy 372.62913 -283.818777) (xy 372.659656 -283.860793) (xy 372.683234 -283.907067)
			(xy 372.699282 -283.95646) (xy 372.707407 -284.007755) (xy 372.707916 -284.033722) (xy 372.707407 -284.059689)
			(xy 372.987571 -284.059689) (xy 372.987571 -284.007755) (xy 372.995696 -283.95646) (xy 373.011744 -283.907067)
			(xy 373.035322 -283.860793) (xy 373.065848 -283.818777) (xy 373.102571 -283.782054) (xy 373.144587 -283.751528)
			(xy 373.190861 -283.72795) (xy 373.240254 -283.711902) (xy 373.291549 -283.703777) (xy 373.343483 -283.703777)
			(xy 373.394778 -283.711902) (xy 373.444171 -283.72795) (xy 373.490445 -283.751528) (xy 373.532461 -283.782054)
			(xy 373.569184 -283.818777) (xy 373.59971 -283.860793) (xy 373.623288 -283.907067) (xy 373.639336 -283.95646)
			(xy 373.647461 -284.007755) (xy 373.64797 -284.033722) (xy 373.647461 -284.059689) (xy 373.927117 -284.059689)
			(xy 373.927117 -284.007755) (xy 373.935242 -283.95646) (xy 373.95129 -283.907067) (xy 373.974868 -283.860793)
			(xy 374.005394 -283.818777) (xy 374.042117 -283.782054) (xy 374.084133 -283.751528) (xy 374.130407 -283.72795)
			(xy 374.1798 -283.711902) (xy 374.231095 -283.703777) (xy 374.283029 -283.703777) (xy 374.334324 -283.711902)
			(xy 374.383717 -283.72795) (xy 374.429991 -283.751528) (xy 374.472007 -283.782054) (xy 374.50873 -283.818777)
			(xy 374.539256 -283.860793) (xy 374.562834 -283.907067) (xy 374.578882 -283.95646) (xy 374.587007 -284.007755)
			(xy 374.587516 -284.033722) (xy 374.587007 -284.059689) (xy 374.866917 -284.059689) (xy 374.866917 -284.007755)
			(xy 374.875042 -283.95646) (xy 374.89109 -283.907067) (xy 374.914668 -283.860793) (xy 374.945194 -283.818777)
			(xy 374.981917 -283.782054) (xy 375.023933 -283.751528) (xy 375.070207 -283.72795) (xy 375.1196 -283.711902)
			(xy 375.170895 -283.703777) (xy 375.222829 -283.703777) (xy 375.274124 -283.711902) (xy 375.323517 -283.72795)
			(xy 375.369791 -283.751528) (xy 375.411807 -283.782054) (xy 375.44853 -283.818777) (xy 375.479056 -283.860793)
			(xy 375.502634 -283.907067) (xy 375.518682 -283.95646) (xy 375.526807 -284.007755) (xy 375.527316 -284.033722)
			(xy 375.526807 -284.059689) (xy 375.806717 -284.059689) (xy 375.806717 -284.007755) (xy 375.814842 -283.95646)
			(xy 375.83089 -283.907067) (xy 375.854468 -283.860793) (xy 375.884994 -283.818777) (xy 375.921717 -283.782054)
			(xy 375.963733 -283.751528) (xy 376.010007 -283.72795) (xy 376.0594 -283.711902) (xy 376.110695 -283.703777)
			(xy 376.162629 -283.703777) (xy 376.213924 -283.711902) (xy 376.263317 -283.72795) (xy 376.309591 -283.751528)
			(xy 376.351607 -283.782054) (xy 376.38833 -283.818777) (xy 376.418856 -283.860793) (xy 376.442434 -283.907067)
			(xy 376.458482 -283.95646) (xy 376.466607 -284.007755) (xy 376.467116 -284.033722) (xy 376.466607 -284.059689)
			(xy 376.746517 -284.059689) (xy 376.746517 -284.007755) (xy 376.754642 -283.95646) (xy 376.77069 -283.907067)
			(xy 376.794268 -283.860793) (xy 376.824794 -283.818777) (xy 376.861517 -283.782054) (xy 376.903533 -283.751528)
			(xy 376.949807 -283.72795) (xy 376.9992 -283.711902) (xy 377.050495 -283.703777) (xy 377.102429 -283.703777)
			(xy 377.153724 -283.711902) (xy 377.203117 -283.72795) (xy 377.249391 -283.751528) (xy 377.291407 -283.782054)
			(xy 377.32813 -283.818777) (xy 377.358656 -283.860793) (xy 377.382234 -283.907067) (xy 377.398282 -283.95646)
			(xy 377.406407 -284.007755) (xy 377.406916 -284.033722) (xy 377.406407 -284.059689) (xy 377.686317 -284.059689)
			(xy 377.686317 -284.007755) (xy 377.694442 -283.95646) (xy 377.71049 -283.907067) (xy 377.734068 -283.860793)
			(xy 377.764594 -283.818777) (xy 377.801317 -283.782054) (xy 377.843333 -283.751528) (xy 377.889607 -283.72795)
			(xy 377.939 -283.711902) (xy 377.990295 -283.703777) (xy 378.042229 -283.703777) (xy 378.093524 -283.711902)
			(xy 378.142917 -283.72795) (xy 378.189191 -283.751528) (xy 378.231207 -283.782054) (xy 378.26793 -283.818777)
			(xy 378.298456 -283.860793) (xy 378.322034 -283.907067) (xy 378.338082 -283.95646) (xy 378.346207 -284.007755)
			(xy 378.346716 -284.033722) (xy 378.346207 -284.059689) (xy 378.626117 -284.059689) (xy 378.626117 -284.007755)
			(xy 378.634242 -283.95646) (xy 378.65029 -283.907067) (xy 378.673868 -283.860793) (xy 378.704394 -283.818777)
			(xy 378.741117 -283.782054) (xy 378.783133 -283.751528) (xy 378.829407 -283.72795) (xy 378.8788 -283.711902)
			(xy 378.930095 -283.703777) (xy 378.982029 -283.703777) (xy 379.033324 -283.711902) (xy 379.082717 -283.72795)
			(xy 379.128991 -283.751528) (xy 379.171007 -283.782054) (xy 379.20773 -283.818777) (xy 379.238256 -283.860793)
			(xy 379.261834 -283.907067) (xy 379.277882 -283.95646) (xy 379.286007 -284.007755) (xy 379.286516 -284.033722)
			(xy 379.286007 -284.059689) (xy 379.565917 -284.059689) (xy 379.565917 -284.007755) (xy 379.574042 -283.95646)
			(xy 379.59009 -283.907067) (xy 379.613668 -283.860793) (xy 379.644194 -283.818777) (xy 379.680917 -283.782054)
			(xy 379.722933 -283.751528) (xy 379.769207 -283.72795) (xy 379.8186 -283.711902) (xy 379.869895 -283.703777)
			(xy 379.921829 -283.703777) (xy 379.973124 -283.711902) (xy 380.022517 -283.72795) (xy 380.068791 -283.751528)
			(xy 380.110807 -283.782054) (xy 380.14753 -283.818777) (xy 380.178056 -283.860793) (xy 380.201634 -283.907067)
			(xy 380.217682 -283.95646) (xy 380.225807 -284.007755) (xy 380.226316 -284.033722) (xy 380.225807 -284.059689)
			(xy 380.505717 -284.059689) (xy 380.505717 -284.007755) (xy 380.513842 -283.95646) (xy 380.52989 -283.907067)
			(xy 380.553468 -283.860793) (xy 380.583994 -283.818777) (xy 380.620717 -283.782054) (xy 380.662733 -283.751528)
			(xy 380.709007 -283.72795) (xy 380.7584 -283.711902) (xy 380.809695 -283.703777) (xy 380.861629 -283.703777)
			(xy 380.912924 -283.711902) (xy 380.962317 -283.72795) (xy 381.008591 -283.751528) (xy 381.050607 -283.782054)
			(xy 381.08733 -283.818777) (xy 381.117856 -283.860793) (xy 381.141434 -283.907067) (xy 381.157482 -283.95646)
			(xy 381.165607 -284.007755) (xy 381.166116 -284.033722) (xy 381.165607 -284.059689) (xy 381.157482 -284.110984)
			(xy 381.141434 -284.160377) (xy 381.117856 -284.206651) (xy 381.08733 -284.248667) (xy 381.050607 -284.28539)
			(xy 381.008591 -284.315916) (xy 380.962317 -284.339494) (xy 380.912924 -284.355542) (xy 380.861629 -284.363667)
			(xy 380.809695 -284.363667) (xy 380.7584 -284.355542) (xy 380.709007 -284.339494) (xy 380.662733 -284.315916)
			(xy 380.620717 -284.28539) (xy 380.583994 -284.248667) (xy 380.553468 -284.206651) (xy 380.52989 -284.160377)
			(xy 380.513842 -284.110984) (xy 380.505717 -284.059689) (xy 380.225807 -284.059689) (xy 380.217682 -284.110984)
			(xy 380.201634 -284.160377) (xy 380.178056 -284.206651) (xy 380.14753 -284.248667) (xy 380.110807 -284.28539)
			(xy 380.068791 -284.315916) (xy 380.022517 -284.339494) (xy 379.973124 -284.355542) (xy 379.921829 -284.363667)
			(xy 379.869895 -284.363667) (xy 379.8186 -284.355542) (xy 379.769207 -284.339494) (xy 379.722933 -284.315916)
			(xy 379.680917 -284.28539) (xy 379.644194 -284.248667) (xy 379.613668 -284.206651) (xy 379.59009 -284.160377)
			(xy 379.574042 -284.110984) (xy 379.565917 -284.059689) (xy 379.286007 -284.059689) (xy 379.277882 -284.110984)
			(xy 379.261834 -284.160377) (xy 379.238256 -284.206651) (xy 379.20773 -284.248667) (xy 379.171007 -284.28539)
			(xy 379.128991 -284.315916) (xy 379.082717 -284.339494) (xy 379.033324 -284.355542) (xy 378.982029 -284.363667)
			(xy 378.930095 -284.363667) (xy 378.8788 -284.355542) (xy 378.829407 -284.339494) (xy 378.783133 -284.315916)
			(xy 378.741117 -284.28539) (xy 378.704394 -284.248667) (xy 378.673868 -284.206651) (xy 378.65029 -284.160377)
			(xy 378.634242 -284.110984) (xy 378.626117 -284.059689) (xy 378.346207 -284.059689) (xy 378.338082 -284.110984)
			(xy 378.322034 -284.160377) (xy 378.298456 -284.206651) (xy 378.26793 -284.248667) (xy 378.231207 -284.28539)
			(xy 378.189191 -284.315916) (xy 378.142917 -284.339494) (xy 378.093524 -284.355542) (xy 378.042229 -284.363667)
			(xy 377.990295 -284.363667) (xy 377.939 -284.355542) (xy 377.889607 -284.339494) (xy 377.843333 -284.315916)
			(xy 377.801317 -284.28539) (xy 377.764594 -284.248667) (xy 377.734068 -284.206651) (xy 377.71049 -284.160377)
			(xy 377.694442 -284.110984) (xy 377.686317 -284.059689) (xy 377.406407 -284.059689) (xy 377.398282 -284.110984)
			(xy 377.382234 -284.160377) (xy 377.358656 -284.206651) (xy 377.32813 -284.248667) (xy 377.291407 -284.28539)
			(xy 377.249391 -284.315916) (xy 377.203117 -284.339494) (xy 377.153724 -284.355542) (xy 377.102429 -284.363667)
			(xy 377.050495 -284.363667) (xy 376.9992 -284.355542) (xy 376.949807 -284.339494) (xy 376.903533 -284.315916)
			(xy 376.861517 -284.28539) (xy 376.824794 -284.248667) (xy 376.794268 -284.206651) (xy 376.77069 -284.160377)
			(xy 376.754642 -284.110984) (xy 376.746517 -284.059689) (xy 376.466607 -284.059689) (xy 376.458482 -284.110984)
			(xy 376.442434 -284.160377) (xy 376.418856 -284.206651) (xy 376.38833 -284.248667) (xy 376.351607 -284.28539)
			(xy 376.309591 -284.315916) (xy 376.263317 -284.339494) (xy 376.213924 -284.355542) (xy 376.162629 -284.363667)
			(xy 376.110695 -284.363667) (xy 376.0594 -284.355542) (xy 376.010007 -284.339494) (xy 375.963733 -284.315916)
			(xy 375.921717 -284.28539) (xy 375.884994 -284.248667) (xy 375.854468 -284.206651) (xy 375.83089 -284.160377)
			(xy 375.814842 -284.110984) (xy 375.806717 -284.059689) (xy 375.526807 -284.059689) (xy 375.518682 -284.110984)
			(xy 375.502634 -284.160377) (xy 375.479056 -284.206651) (xy 375.44853 -284.248667) (xy 375.411807 -284.28539)
			(xy 375.369791 -284.315916) (xy 375.323517 -284.339494) (xy 375.274124 -284.355542) (xy 375.222829 -284.363667)
			(xy 375.170895 -284.363667) (xy 375.1196 -284.355542) (xy 375.070207 -284.339494) (xy 375.023933 -284.315916)
			(xy 374.981917 -284.28539) (xy 374.945194 -284.248667) (xy 374.914668 -284.206651) (xy 374.89109 -284.160377)
			(xy 374.875042 -284.110984) (xy 374.866917 -284.059689) (xy 374.587007 -284.059689) (xy 374.578882 -284.110984)
			(xy 374.562834 -284.160377) (xy 374.539256 -284.206651) (xy 374.50873 -284.248667) (xy 374.472007 -284.28539)
			(xy 374.429991 -284.315916) (xy 374.383717 -284.339494) (xy 374.334324 -284.355542) (xy 374.283029 -284.363667)
			(xy 374.231095 -284.363667) (xy 374.1798 -284.355542) (xy 374.130407 -284.339494) (xy 374.084133 -284.315916)
			(xy 374.042117 -284.28539) (xy 374.005394 -284.248667) (xy 373.974868 -284.206651) (xy 373.95129 -284.160377)
			(xy 373.935242 -284.110984) (xy 373.927117 -284.059689) (xy 373.647461 -284.059689) (xy 373.639336 -284.110984)
			(xy 373.623288 -284.160377) (xy 373.59971 -284.206651) (xy 373.569184 -284.248667) (xy 373.532461 -284.28539)
			(xy 373.490445 -284.315916) (xy 373.444171 -284.339494) (xy 373.394778 -284.355542) (xy 373.343483 -284.363667)
			(xy 373.291549 -284.363667) (xy 373.240254 -284.355542) (xy 373.190861 -284.339494) (xy 373.144587 -284.315916)
			(xy 373.102571 -284.28539) (xy 373.065848 -284.248667) (xy 373.035322 -284.206651) (xy 373.011744 -284.160377)
			(xy 372.995696 -284.110984) (xy 372.987571 -284.059689) (xy 372.707407 -284.059689) (xy 372.699282 -284.110984)
			(xy 372.683234 -284.160377) (xy 372.659656 -284.206651) (xy 372.62913 -284.248667) (xy 372.592407 -284.28539)
			(xy 372.550391 -284.315916) (xy 372.504117 -284.339494) (xy 372.454724 -284.355542) (xy 372.403429 -284.363667)
			(xy 372.351495 -284.363667) (xy 372.3002 -284.355542) (xy 372.250807 -284.339494) (xy 372.204533 -284.315916)
			(xy 372.162517 -284.28539) (xy 372.125794 -284.248667) (xy 372.095268 -284.206651) (xy 372.07169 -284.160377)
			(xy 372.055642 -284.110984) (xy 372.047517 -284.059689) (xy 371.767607 -284.059689) (xy 371.759482 -284.110984)
			(xy 371.743434 -284.160377) (xy 371.719856 -284.206651) (xy 371.68933 -284.248667) (xy 371.652607 -284.28539)
			(xy 371.610591 -284.315916) (xy 371.564317 -284.339494) (xy 371.514924 -284.355542) (xy 371.463629 -284.363667)
			(xy 371.411695 -284.363667) (xy 371.3604 -284.355542) (xy 371.311007 -284.339494) (xy 371.264733 -284.315916)
			(xy 371.222717 -284.28539) (xy 371.185994 -284.248667) (xy 371.155468 -284.206651) (xy 371.13189 -284.160377)
			(xy 371.115842 -284.110984) (xy 371.107717 -284.059689) (xy 370.827846 -284.059689) (xy 370.819723 -284.110969)
			(xy 370.803672 -284.160365) (xy 370.780091 -284.206642) (xy 370.74956 -284.248661) (xy 370.712832 -284.285385)
			(xy 370.67081 -284.315911) (xy 370.62453 -284.339487) (xy 370.575132 -284.355532) (xy 370.523832 -284.363652)
			(xy 370.497862 -284.364176) (xy 370.47555 -284.363806) (xy 370.431331 -284.357815) (xy 370.409724 -284.352238)
			(xy 370.400855 -284.350138) (xy 370.382706 -284.351664) (xy 370.366239 -284.359447) (xy 370.35354 -284.372503)
			(xy 370.349526 -284.380686) (xy 370.333439 -284.416343) (xy 370.295712 -284.484876) (xy 370.251941 -284.549715)
			(xy 370.202484 -284.610329) (xy 370.147747 -284.666221) (xy 370.088179 -284.716932) (xy 370.024267 -284.762048)
			(xy 369.990624 -284.782006) (xy 369.989354 -284.782514) (xy 369.986052 -284.784546) (xy 369.976007 -284.791865)
			(xy 369.960902 -284.81158) (xy 369.95293 -284.835103) (xy 369.952934 -284.847538) (xy 370.637562 -284.847538)
			(xy 370.638071 -284.821571) (xy 370.646196 -284.770276) (xy 370.662244 -284.720883) (xy 370.685822 -284.674609)
			(xy 370.716348 -284.632593) (xy 370.753071 -284.59587) (xy 370.795087 -284.565344) (xy 370.841361 -284.541766)
			(xy 370.890754 -284.525718) (xy 370.942049 -284.517593) (xy 370.993983 -284.517593) (xy 371.045278 -284.525718)
			(xy 371.094671 -284.541766) (xy 371.140945 -284.565344) (xy 371.182961 -284.59587) (xy 371.219684 -284.632593)
			(xy 371.25021 -284.674609) (xy 371.273788 -284.720883) (xy 371.289836 -284.770276) (xy 371.297961 -284.821571)
			(xy 371.29847 -284.847538) (xy 372.517162 -284.847538) (xy 372.517671 -284.821571) (xy 372.525796 -284.770276)
			(xy 372.541844 -284.720883) (xy 372.565422 -284.674609) (xy 372.595948 -284.632593) (xy 372.632671 -284.59587)
			(xy 372.674687 -284.565344) (xy 372.720961 -284.541766) (xy 372.770354 -284.525718) (xy 372.821649 -284.517593)
			(xy 372.873583 -284.517593) (xy 372.924878 -284.525718) (xy 372.974271 -284.541766) (xy 373.020545 -284.565344)
			(xy 373.062561 -284.59587) (xy 373.099284 -284.632593) (xy 373.12981 -284.674609) (xy 373.153388 -284.720883)
			(xy 373.169436 -284.770276) (xy 373.177561 -284.821571) (xy 373.17807 -284.847538) (xy 373.177567 -284.873505)
			(xy 373.457471 -284.873505) (xy 373.457471 -284.821571) (xy 373.465596 -284.770276) (xy 373.481644 -284.720883)
			(xy 373.505222 -284.674609) (xy 373.535748 -284.632593) (xy 373.572471 -284.59587) (xy 373.614487 -284.565344)
			(xy 373.660761 -284.541766) (xy 373.710154 -284.525718) (xy 373.761449 -284.517593) (xy 373.813383 -284.517593)
			(xy 373.864678 -284.525718) (xy 373.914071 -284.541766) (xy 373.960345 -284.565344) (xy 374.002361 -284.59587)
			(xy 374.039084 -284.632593) (xy 374.06961 -284.674609) (xy 374.093188 -284.720883) (xy 374.109236 -284.770276)
			(xy 374.117361 -284.821571) (xy 374.11787 -284.847538) (xy 374.396762 -284.847538) (xy 374.397271 -284.821571)
			(xy 374.405396 -284.770276) (xy 374.421444 -284.720883) (xy 374.445022 -284.674609) (xy 374.475548 -284.632593)
			(xy 374.512271 -284.59587) (xy 374.554287 -284.565344) (xy 374.600561 -284.541766) (xy 374.649954 -284.525718)
			(xy 374.701249 -284.517593) (xy 374.753183 -284.517593) (xy 374.804478 -284.525718) (xy 374.853871 -284.541766)
			(xy 374.900145 -284.565344) (xy 374.942161 -284.59587) (xy 374.978884 -284.632593) (xy 375.00941 -284.674609)
			(xy 375.032988 -284.720883) (xy 375.049036 -284.770276) (xy 375.057161 -284.821571) (xy 375.05767 -284.847538)
			(xy 376.276362 -284.847538) (xy 376.276871 -284.821571) (xy 376.284996 -284.770276) (xy 376.301044 -284.720883)
			(xy 376.324622 -284.674609) (xy 376.355148 -284.632593) (xy 376.391871 -284.59587) (xy 376.433887 -284.565344)
			(xy 376.480161 -284.541766) (xy 376.529554 -284.525718) (xy 376.580849 -284.517593) (xy 376.632783 -284.517593)
			(xy 376.684078 -284.525718) (xy 376.733471 -284.541766) (xy 376.779745 -284.565344) (xy 376.821761 -284.59587)
			(xy 376.858484 -284.632593) (xy 376.88901 -284.674609) (xy 376.912588 -284.720883) (xy 376.928636 -284.770276)
			(xy 376.936761 -284.821571) (xy 376.93727 -284.847538) (xy 378.155962 -284.847538) (xy 378.156471 -284.821571)
			(xy 378.164596 -284.770276) (xy 378.180644 -284.720883) (xy 378.204222 -284.674609) (xy 378.234748 -284.632593)
			(xy 378.271471 -284.59587) (xy 378.313487 -284.565344) (xy 378.359761 -284.541766) (xy 378.409154 -284.525718)
			(xy 378.460449 -284.517593) (xy 378.512383 -284.517593) (xy 378.563678 -284.525718) (xy 378.613071 -284.541766)
			(xy 378.659345 -284.565344) (xy 378.701361 -284.59587) (xy 378.738084 -284.632593) (xy 378.76861 -284.674609)
			(xy 378.792188 -284.720883) (xy 378.808236 -284.770276) (xy 378.816361 -284.821571) (xy 378.81687 -284.847538)
			(xy 380.035562 -284.847538) (xy 380.036071 -284.821571) (xy 380.044196 -284.770276) (xy 380.060244 -284.720883)
			(xy 380.083822 -284.674609) (xy 380.114348 -284.632593) (xy 380.151071 -284.59587) (xy 380.193087 -284.565344)
			(xy 380.239361 -284.541766) (xy 380.288754 -284.525718) (xy 380.340049 -284.517593) (xy 380.391983 -284.517593)
			(xy 380.443278 -284.525718) (xy 380.492671 -284.541766) (xy 380.538945 -284.565344) (xy 380.580961 -284.59587)
			(xy 380.617684 -284.632593) (xy 380.64821 -284.674609) (xy 380.671788 -284.720883) (xy 380.687836 -284.770276)
			(xy 380.695961 -284.821571) (xy 380.69647 -284.847538) (xy 380.695967 -284.873505) (xy 381.915671 -284.873505)
			(xy 381.915671 -284.821571) (xy 381.923796 -284.770276) (xy 381.939844 -284.720883) (xy 381.963422 -284.674609)
			(xy 381.993948 -284.632593) (xy 382.030671 -284.59587) (xy 382.072687 -284.565344) (xy 382.118961 -284.541766)
			(xy 382.168354 -284.525718) (xy 382.219649 -284.517593) (xy 382.271583 -284.517593) (xy 382.322878 -284.525718)
			(xy 382.372271 -284.541766) (xy 382.418545 -284.565344) (xy 382.460561 -284.59587) (xy 382.497284 -284.632593)
			(xy 382.52781 -284.674609) (xy 382.551388 -284.720883) (xy 382.567436 -284.770276) (xy 382.575561 -284.821571)
			(xy 382.57607 -284.847538) (xy 382.575566 -284.873251) (xy 382.855217 -284.873251) (xy 382.855217 -284.821317)
			(xy 382.863342 -284.770022) (xy 382.87939 -284.720629) (xy 382.902968 -284.674355) (xy 382.933494 -284.632339)
			(xy 382.970217 -284.595616) (xy 383.012233 -284.56509) (xy 383.058507 -284.541512) (xy 383.1079 -284.525464)
			(xy 383.159195 -284.517339) (xy 383.211129 -284.517339) (xy 383.262424 -284.525464) (xy 383.311817 -284.541512)
			(xy 383.358091 -284.56509) (xy 383.400107 -284.595616) (xy 383.43683 -284.632339) (xy 383.467356 -284.674355)
			(xy 383.490934 -284.720629) (xy 383.506982 -284.770022) (xy 383.515107 -284.821317) (xy 383.515616 -284.847284)
			(xy 383.515107 -284.873251) (xy 383.506982 -284.924546) (xy 383.490934 -284.973939) (xy 383.467356 -285.020213)
			(xy 383.43683 -285.062229) (xy 383.400107 -285.098952) (xy 383.358091 -285.129478) (xy 383.311817 -285.153056)
			(xy 383.262424 -285.169104) (xy 383.211129 -285.177229) (xy 383.159195 -285.177229) (xy 383.1079 -285.169104)
			(xy 383.058507 -285.153056) (xy 383.012233 -285.129478) (xy 382.970217 -285.098952) (xy 382.933494 -285.062229)
			(xy 382.902968 -285.020213) (xy 382.87939 -284.973939) (xy 382.863342 -284.924546) (xy 382.855217 -284.873251)
			(xy 382.575566 -284.873251) (xy 382.575561 -284.873505) (xy 382.567436 -284.9248) (xy 382.551388 -284.974193)
			(xy 382.52781 -285.020467) (xy 382.497284 -285.062483) (xy 382.460561 -285.099206) (xy 382.418545 -285.129732)
			(xy 382.372271 -285.15331) (xy 382.322878 -285.169358) (xy 382.271583 -285.177483) (xy 382.219649 -285.177483)
			(xy 382.168354 -285.169358) (xy 382.118961 -285.15331) (xy 382.072687 -285.129732) (xy 382.030671 -285.099206)
			(xy 381.993948 -285.062483) (xy 381.963422 -285.020467) (xy 381.939844 -284.974193) (xy 381.923796 -284.9248)
			(xy 381.915671 -284.873505) (xy 380.695967 -284.873505) (xy 380.695928 -284.875524) (xy 380.686471 -284.930692)
			(xy 380.677674 -284.957266) (xy 380.670054 -284.979364) (xy 380.873762 -285.33217) (xy 380.896622 -285.336488)
			(xy 380.921546 -285.341648) (xy 380.969531 -285.358612) (xy 381.014351 -285.382729) (xy 381.054944 -285.41343)
			(xy 381.090354 -285.449989) (xy 381.119742 -285.491543) (xy 381.142415 -285.537109) (xy 381.157837 -285.585612)
			(xy 381.165644 -285.635906) (xy 381.166116 -285.661354) (xy 381.165607 -285.687321) (xy 381.157482 -285.738616)
			(xy 381.141434 -285.788009) (xy 381.117856 -285.834283) (xy 381.08733 -285.876299) (xy 381.050607 -285.913022)
			(xy 381.008591 -285.943548) (xy 380.962317 -285.967126) (xy 380.912924 -285.983174) (xy 380.861629 -285.991299)
			(xy 380.809695 -285.991299) (xy 380.7584 -285.983174) (xy 380.709007 -285.967126) (xy 380.662733 -285.943548)
			(xy 380.620717 -285.913022) (xy 380.583994 -285.876299) (xy 380.553468 -285.834283) (xy 380.52989 -285.788009)
			(xy 380.513842 -285.738616) (xy 380.505717 -285.687321) (xy 380.505208 -285.661354) (xy 380.505749 -285.633368)
			(xy 380.515207 -285.5782) (xy 380.524004 -285.551626) (xy 380.531624 -285.529528) (xy 380.327916 -285.176722)
			(xy 380.305056 -285.172404) (xy 380.280127 -285.167267) (xy 380.232141 -285.1503) (xy 380.187322 -285.126179)
			(xy 380.146728 -285.095475) (xy 380.111319 -285.058913) (xy 380.081932 -285.017357) (xy 380.05926 -284.971788)
			(xy 380.043839 -284.923282) (xy 380.036033 -284.872987) (xy 380.035562 -284.847538) (xy 378.81687 -284.847538)
			(xy 378.816328 -284.875524) (xy 378.806871 -284.930692) (xy 378.798074 -284.957266) (xy 378.790454 -284.979364)
			(xy 378.994162 -285.33217) (xy 379.017022 -285.336488) (xy 379.041946 -285.341648) (xy 379.089931 -285.358612)
			(xy 379.134751 -285.382729) (xy 379.175344 -285.41343) (xy 379.210754 -285.449989) (xy 379.240142 -285.491543)
			(xy 379.262815 -285.537109) (xy 379.278237 -285.585612) (xy 379.286044 -285.635906) (xy 379.286516 -285.661354)
			(xy 379.286007 -285.687321) (xy 379.277882 -285.738616) (xy 379.261834 -285.788009) (xy 379.238256 -285.834283)
			(xy 379.20773 -285.876299) (xy 379.171007 -285.913022) (xy 379.128991 -285.943548) (xy 379.082717 -285.967126)
			(xy 379.033324 -285.983174) (xy 378.982029 -285.991299) (xy 378.930095 -285.991299) (xy 378.8788 -285.983174)
			(xy 378.829407 -285.967126) (xy 378.783133 -285.943548) (xy 378.741117 -285.913022) (xy 378.704394 -285.876299)
			(xy 378.673868 -285.834283) (xy 378.65029 -285.788009) (xy 378.634242 -285.738616) (xy 378.626117 -285.687321)
			(xy 378.625608 -285.661354) (xy 378.626149 -285.633368) (xy 378.635607 -285.5782) (xy 378.644404 -285.551626)
			(xy 378.652024 -285.529528) (xy 378.448316 -285.176722) (xy 378.425456 -285.172404) (xy 378.400527 -285.167267)
			(xy 378.352541 -285.1503) (xy 378.307722 -285.126179) (xy 378.267128 -285.095475) (xy 378.231719 -285.058913)
			(xy 378.202332 -285.017357) (xy 378.17966 -284.971788) (xy 378.164239 -284.923282) (xy 378.156433 -284.872987)
			(xy 378.155962 -284.847538) (xy 376.93727 -284.847538) (xy 376.936728 -284.875524) (xy 376.927271 -284.930692)
			(xy 376.918474 -284.957266) (xy 376.910854 -284.979364) (xy 377.114562 -285.33217) (xy 377.137422 -285.336488)
			(xy 377.162346 -285.341648) (xy 377.210331 -285.358612) (xy 377.255151 -285.382729) (xy 377.295744 -285.41343)
			(xy 377.331154 -285.449989) (xy 377.360542 -285.491543) (xy 377.383215 -285.537109) (xy 377.398637 -285.585612)
			(xy 377.406444 -285.635906) (xy 377.406916 -285.661354) (xy 377.406407 -285.687321) (xy 377.398282 -285.738616)
			(xy 377.382234 -285.788009) (xy 377.358656 -285.834283) (xy 377.32813 -285.876299) (xy 377.291407 -285.913022)
			(xy 377.249391 -285.943548) (xy 377.203117 -285.967126) (xy 377.153724 -285.983174) (xy 377.102429 -285.991299)
			(xy 377.050495 -285.991299) (xy 376.9992 -285.983174) (xy 376.949807 -285.967126) (xy 376.903533 -285.943548)
			(xy 376.861517 -285.913022) (xy 376.824794 -285.876299) (xy 376.794268 -285.834283) (xy 376.77069 -285.788009)
			(xy 376.754642 -285.738616) (xy 376.746517 -285.687321) (xy 376.746008 -285.661354) (xy 376.746549 -285.633368)
			(xy 376.756007 -285.5782) (xy 376.764804 -285.551626) (xy 376.772424 -285.529528) (xy 376.568716 -285.176722)
			(xy 376.545856 -285.172404) (xy 376.520927 -285.167267) (xy 376.472941 -285.1503) (xy 376.428122 -285.126179)
			(xy 376.387528 -285.095475) (xy 376.352119 -285.058913) (xy 376.322732 -285.017357) (xy 376.30006 -284.971788)
			(xy 376.284639 -284.923282) (xy 376.276833 -284.872987) (xy 376.276362 -284.847538) (xy 375.05767 -284.847538)
			(xy 375.057128 -284.875524) (xy 375.047671 -284.930692) (xy 375.038874 -284.957266) (xy 375.031254 -284.979364)
			(xy 375.234962 -285.33217) (xy 375.257822 -285.336488) (xy 375.282746 -285.341648) (xy 375.330731 -285.358612)
			(xy 375.375551 -285.382729) (xy 375.416144 -285.41343) (xy 375.451554 -285.449989) (xy 375.480942 -285.491543)
			(xy 375.503615 -285.537109) (xy 375.519037 -285.585612) (xy 375.526844 -285.635906) (xy 375.527316 -285.661354)
			(xy 375.526807 -285.687321) (xy 375.518682 -285.738616) (xy 375.502634 -285.788009) (xy 375.479056 -285.834283)
			(xy 375.44853 -285.876299) (xy 375.411807 -285.913022) (xy 375.369791 -285.943548) (xy 375.323517 -285.967126)
			(xy 375.274124 -285.983174) (xy 375.222829 -285.991299) (xy 375.170895 -285.991299) (xy 375.1196 -285.983174)
			(xy 375.070207 -285.967126) (xy 375.023933 -285.943548) (xy 374.981917 -285.913022) (xy 374.945194 -285.876299)
			(xy 374.914668 -285.834283) (xy 374.89109 -285.788009) (xy 374.875042 -285.738616) (xy 374.866917 -285.687321)
			(xy 374.866408 -285.661354) (xy 374.866949 -285.633368) (xy 374.876407 -285.5782) (xy 374.885204 -285.551626)
			(xy 374.892824 -285.529528) (xy 374.689116 -285.176722) (xy 374.666256 -285.172404) (xy 374.641327 -285.167267)
			(xy 374.593341 -285.1503) (xy 374.548522 -285.126179) (xy 374.507928 -285.095475) (xy 374.472519 -285.058913)
			(xy 374.443132 -285.017357) (xy 374.42046 -284.971788) (xy 374.405039 -284.923282) (xy 374.397233 -284.872987)
			(xy 374.396762 -284.847538) (xy 374.11787 -284.847538) (xy 374.117361 -284.873505) (xy 374.109236 -284.9248)
			(xy 374.093188 -284.974193) (xy 374.06961 -285.020467) (xy 374.039084 -285.062483) (xy 374.002361 -285.099206)
			(xy 373.960345 -285.129732) (xy 373.914071 -285.15331) (xy 373.864678 -285.169358) (xy 373.813383 -285.177483)
			(xy 373.761449 -285.177483) (xy 373.710154 -285.169358) (xy 373.660761 -285.15331) (xy 373.614487 -285.129732)
			(xy 373.572471 -285.099206) (xy 373.535748 -285.062483) (xy 373.505222 -285.020467) (xy 373.481644 -284.974193)
			(xy 373.465596 -284.9248) (xy 373.457471 -284.873505) (xy 373.177567 -284.873505) (xy 373.177528 -284.875524)
			(xy 373.168071 -284.930692) (xy 373.159274 -284.957266) (xy 373.151654 -284.979364) (xy 373.355362 -285.33217)
			(xy 373.378222 -285.336488) (xy 373.403146 -285.341648) (xy 373.451131 -285.358612) (xy 373.495951 -285.382729)
			(xy 373.536544 -285.41343) (xy 373.571954 -285.449989) (xy 373.601342 -285.491543) (xy 373.624015 -285.537109)
			(xy 373.639437 -285.585612) (xy 373.647244 -285.635906) (xy 373.647716 -285.661354) (xy 373.647207 -285.687321)
			(xy 373.639082 -285.738616) (xy 373.623034 -285.788009) (xy 373.599456 -285.834283) (xy 373.56893 -285.876299)
			(xy 373.532207 -285.913022) (xy 373.490191 -285.943548) (xy 373.443917 -285.967126) (xy 373.394524 -285.983174)
			(xy 373.343229 -285.991299) (xy 373.291295 -285.991299) (xy 373.24 -285.983174) (xy 373.190607 -285.967126)
			(xy 373.144333 -285.943548) (xy 373.102317 -285.913022) (xy 373.065594 -285.876299) (xy 373.035068 -285.834283)
			(xy 373.01149 -285.788009) (xy 372.995442 -285.738616) (xy 372.987317 -285.687321) (xy 372.986808 -285.661354)
			(xy 372.987349 -285.633368) (xy 372.996807 -285.5782) (xy 373.005604 -285.551626) (xy 373.013224 -285.529528)
			(xy 372.809516 -285.176722) (xy 372.786656 -285.172404) (xy 372.761727 -285.167267) (xy 372.713741 -285.1503)
			(xy 372.668922 -285.126179) (xy 372.628328 -285.095475) (xy 372.592919 -285.058913) (xy 372.563532 -285.017357)
			(xy 372.54086 -284.971788) (xy 372.525439 -284.923282) (xy 372.517633 -284.872987) (xy 372.517162 -284.847538)
			(xy 371.29847 -284.847538) (xy 371.297928 -284.875524) (xy 371.288471 -284.930692) (xy 371.279674 -284.957266)
			(xy 371.272054 -284.979364) (xy 371.475762 -285.33217) (xy 371.498622 -285.336488) (xy 371.523546 -285.341648)
			(xy 371.571531 -285.358612) (xy 371.616351 -285.382729) (xy 371.656944 -285.41343) (xy 371.692354 -285.449989)
			(xy 371.721742 -285.491543) (xy 371.744415 -285.537109) (xy 371.759837 -285.585612) (xy 371.767644 -285.635906)
			(xy 371.768116 -285.661354) (xy 371.767607 -285.687321) (xy 371.759482 -285.738616) (xy 371.743434 -285.788009)
			(xy 371.719856 -285.834283) (xy 371.68933 -285.876299) (xy 371.652607 -285.913022) (xy 371.610591 -285.943548)
			(xy 371.564317 -285.967126) (xy 371.514924 -285.983174) (xy 371.463629 -285.991299) (xy 371.411695 -285.991299)
			(xy 371.3604 -285.983174) (xy 371.311007 -285.967126) (xy 371.264733 -285.943548) (xy 371.222717 -285.913022)
			(xy 371.185994 -285.876299) (xy 371.155468 -285.834283) (xy 371.13189 -285.788009) (xy 371.115842 -285.738616)
			(xy 371.107717 -285.687321) (xy 371.107208 -285.661354) (xy 371.107749 -285.633368) (xy 371.117207 -285.5782)
			(xy 371.126004 -285.551626) (xy 371.133624 -285.529528) (xy 370.929916 -285.176722) (xy 370.907056 -285.172404)
			(xy 370.882127 -285.167267) (xy 370.834141 -285.1503) (xy 370.789322 -285.126179) (xy 370.748728 -285.095475)
			(xy 370.713319 -285.058913) (xy 370.683932 -285.017357) (xy 370.66126 -284.971788) (xy 370.645839 -284.923282)
			(xy 370.638033 -284.872987) (xy 370.637562 -284.847538) (xy 369.952934 -284.847538) (xy 369.952937 -284.859939)
			(xy 369.960922 -284.883458) (xy 369.976038 -284.903164) (xy 369.986052 -284.91053) (xy 369.989354 -284.912562)
			(xy 369.990624 -284.91307) (xy 370.024259 -284.933039) (xy 370.08815 -284.978177) (xy 370.147706 -285.028899)
			(xy 370.202438 -285.084791) (xy 370.2519 -285.145396) (xy 370.295689 -285.21022) (xy 370.333445 -285.278732)
			(xy 370.349526 -285.31439) (xy 370.353557 -285.322553) (xy 370.366272 -285.335566) (xy 370.382724 -285.343334)
			(xy 370.400851 -285.344884) (xy 370.409724 -285.342838) (xy 370.431326 -285.337239) (xy 370.475549 -285.33125)
			(xy 370.497862 -285.3309) (xy 370.523832 -285.331406) (xy 370.575135 -285.339526) (xy 370.624535 -285.35557)
			(xy 370.670818 -285.379145) (xy 370.712843 -285.40967) (xy 370.749575 -285.446393) (xy 370.780111 -285.48841)
			(xy 370.803697 -285.534687) (xy 370.819755 -285.584083) (xy 370.827887 -285.635384) (xy 370.828316 -285.661354)
			(xy 370.827844 -285.686802) (xy 370.820036 -285.737094) (xy 370.804613 -285.785596) (xy 370.781939 -285.831162)
			(xy 370.752551 -285.872715) (xy 370.717141 -285.909273) (xy 370.676548 -285.939973) (xy 370.631729 -285.964089)
			(xy 370.583744 -285.981052) (xy 370.558822 -285.98622) (xy 370.535962 -285.990538) (xy 370.332254 -286.343598)
			(xy 370.339874 -286.365696) (xy 370.348666 -286.39227) (xy 370.358113 -286.447438) (xy 370.35867 -286.475424)
			(xy 370.358159 -286.50139) (xy 370.358159 -286.501391) (xy 370.637817 -286.501391) (xy 370.637817 -286.449457)
			(xy 370.645942 -286.398162) (xy 370.66199 -286.348769) (xy 370.685568 -286.302495) (xy 370.716094 -286.260479)
			(xy 370.752817 -286.223756) (xy 370.794833 -286.19323) (xy 370.841107 -286.169652) (xy 370.8905 -286.153604)
			(xy 370.941795 -286.145479) (xy 370.993729 -286.145479) (xy 371.045024 -286.153604) (xy 371.094417 -286.169652)
			(xy 371.140691 -286.19323) (xy 371.182707 -286.223756) (xy 371.21943 -286.260479) (xy 371.249956 -286.302495)
			(xy 371.273534 -286.348769) (xy 371.289582 -286.398162) (xy 371.297707 -286.449457) (xy 371.298216 -286.475424)
			(xy 371.577362 -286.475424) (xy 371.577767 -286.44997) (xy 371.585557 -286.399662) (xy 371.600971 -286.351145)
			(xy 371.623644 -286.305566) (xy 371.653041 -286.264004) (xy 371.688465 -286.227443) (xy 371.729077 -286.196748)
			(xy 371.773918 -286.172646) (xy 371.821924 -286.155707) (xy 371.846856 -286.150558) (xy 371.869716 -286.14624)
			(xy 372.073424 -285.79318) (xy 372.065804 -285.771082) (xy 372.057062 -285.744495) (xy 372.047617 -285.689335)
			(xy 372.047008 -285.661354) (xy 372.047517 -285.635387) (xy 372.055642 -285.584092) (xy 372.07169 -285.534699)
			(xy 372.095268 -285.488425) (xy 372.125794 -285.446409) (xy 372.162517 -285.409686) (xy 372.204533 -285.37916)
			(xy 372.250807 -285.355582) (xy 372.3002 -285.339534) (xy 372.351495 -285.331409) (xy 372.403429 -285.331409)
			(xy 372.454724 -285.339534) (xy 372.504117 -285.355582) (xy 372.550391 -285.37916) (xy 372.592407 -285.409686)
			(xy 372.62913 -285.446409) (xy 372.659656 -285.488425) (xy 372.683234 -285.534699) (xy 372.699282 -285.584092)
			(xy 372.707407 -285.635387) (xy 372.707916 -285.661354) (xy 372.707509 -285.686808) (xy 372.699722 -285.737117)
			(xy 372.684309 -285.785635) (xy 372.661637 -285.831216) (xy 372.632241 -285.872778) (xy 372.596816 -285.90934)
			(xy 372.556203 -285.940034) (xy 372.511362 -285.964135) (xy 372.463354 -285.981072) (xy 372.438422 -285.98622)
			(xy 372.415562 -285.990538) (xy 372.211854 -286.343598) (xy 372.219474 -286.365696) (xy 372.22821 -286.392285)
			(xy 372.237659 -286.447444) (xy 372.23827 -286.475424) (xy 372.237761 -286.501391) (xy 372.517417 -286.501391)
			(xy 372.517417 -286.449457) (xy 372.525542 -286.398162) (xy 372.54159 -286.348769) (xy 372.565168 -286.302495)
			(xy 372.595694 -286.260479) (xy 372.632417 -286.223756) (xy 372.674433 -286.19323) (xy 372.720707 -286.169652)
			(xy 372.7701 -286.153604) (xy 372.821395 -286.145479) (xy 372.873329 -286.145479) (xy 372.924624 -286.153604)
			(xy 372.974017 -286.169652) (xy 373.020291 -286.19323) (xy 373.062307 -286.223756) (xy 373.09903 -286.260479)
			(xy 373.129556 -286.302495) (xy 373.153134 -286.348769) (xy 373.169182 -286.398162) (xy 373.177307 -286.449457)
			(xy 373.177816 -286.475424) (xy 373.456962 -286.475424) (xy 373.457367 -286.44997) (xy 373.465157 -286.399662)
			(xy 373.480571 -286.351145) (xy 373.503244 -286.305566) (xy 373.532641 -286.264004) (xy 373.568065 -286.227443)
			(xy 373.608677 -286.196748) (xy 373.653518 -286.172646) (xy 373.701524 -286.155707) (xy 373.726456 -286.150558)
			(xy 373.749316 -286.14624) (xy 373.953024 -285.79318) (xy 373.945404 -285.771082) (xy 373.936662 -285.744495)
			(xy 373.927217 -285.689335) (xy 373.926608 -285.661354) (xy 373.927117 -285.635387) (xy 373.935242 -285.584092)
			(xy 373.95129 -285.534699) (xy 373.974868 -285.488425) (xy 374.005394 -285.446409) (xy 374.042117 -285.409686)
			(xy 374.084133 -285.37916) (xy 374.130407 -285.355582) (xy 374.1798 -285.339534) (xy 374.231095 -285.331409)
			(xy 374.283029 -285.331409) (xy 374.334324 -285.339534) (xy 374.383717 -285.355582) (xy 374.429991 -285.37916)
			(xy 374.472007 -285.409686) (xy 374.50873 -285.446409) (xy 374.539256 -285.488425) (xy 374.562834 -285.534699)
			(xy 374.578882 -285.584092) (xy 374.587007 -285.635387) (xy 374.587516 -285.661354) (xy 374.587109 -285.686808)
			(xy 374.579322 -285.737117) (xy 374.563909 -285.785635) (xy 374.541237 -285.831216) (xy 374.511841 -285.872778)
			(xy 374.476416 -285.90934) (xy 374.435803 -285.940034) (xy 374.390962 -285.964135) (xy 374.342954 -285.981072)
			(xy 374.318022 -285.98622) (xy 374.295162 -285.990538) (xy 374.091454 -286.343598) (xy 374.099074 -286.365696)
			(xy 374.10781 -286.392285) (xy 374.117259 -286.447444) (xy 374.11787 -286.475424) (xy 374.117361 -286.501391)
			(xy 374.397017 -286.501391) (xy 374.397017 -286.449457) (xy 374.405142 -286.398162) (xy 374.42119 -286.348769)
			(xy 374.444768 -286.302495) (xy 374.475294 -286.260479) (xy 374.512017 -286.223756) (xy 374.554033 -286.19323)
			(xy 374.600307 -286.169652) (xy 374.6497 -286.153604) (xy 374.700995 -286.145479) (xy 374.752929 -286.145479)
			(xy 374.804224 -286.153604) (xy 374.853617 -286.169652) (xy 374.899891 -286.19323) (xy 374.941907 -286.223756)
			(xy 374.97863 -286.260479) (xy 375.009156 -286.302495) (xy 375.032734 -286.348769) (xy 375.048782 -286.398162)
			(xy 375.056907 -286.449457) (xy 375.057416 -286.475424) (xy 375.336562 -286.475424) (xy 375.336967 -286.44997)
			(xy 375.344757 -286.399662) (xy 375.360171 -286.351145) (xy 375.382844 -286.305566) (xy 375.412241 -286.264004)
			(xy 375.447665 -286.227443) (xy 375.488277 -286.196748) (xy 375.533118 -286.172646) (xy 375.581124 -286.155707)
			(xy 375.606056 -286.150558) (xy 375.628916 -286.14624) (xy 375.832624 -285.79318) (xy 375.825004 -285.771082)
			(xy 375.816262 -285.744495) (xy 375.806817 -285.689335) (xy 375.806208 -285.661354) (xy 375.806717 -285.635387)
			(xy 375.814842 -285.584092) (xy 375.83089 -285.534699) (xy 375.854468 -285.488425) (xy 375.884994 -285.446409)
			(xy 375.921717 -285.409686) (xy 375.963733 -285.37916) (xy 376.010007 -285.355582) (xy 376.0594 -285.339534)
			(xy 376.110695 -285.331409) (xy 376.162629 -285.331409) (xy 376.213924 -285.339534) (xy 376.263317 -285.355582)
			(xy 376.309591 -285.37916) (xy 376.351607 -285.409686) (xy 376.38833 -285.446409) (xy 376.418856 -285.488425)
			(xy 376.442434 -285.534699) (xy 376.458482 -285.584092) (xy 376.466607 -285.635387) (xy 376.467116 -285.661354)
			(xy 376.466709 -285.686808) (xy 376.458922 -285.737117) (xy 376.443509 -285.785635) (xy 376.420837 -285.831216)
			(xy 376.391441 -285.872778) (xy 376.356016 -285.90934) (xy 376.315403 -285.940034) (xy 376.270562 -285.964135)
			(xy 376.222554 -285.981072) (xy 376.197622 -285.98622) (xy 376.174762 -285.990538) (xy 375.971054 -286.343598)
			(xy 375.978674 -286.365696) (xy 375.98741 -286.392285) (xy 375.996859 -286.447444) (xy 375.99747 -286.475424)
			(xy 375.996961 -286.501391) (xy 376.276617 -286.501391) (xy 376.276617 -286.449457) (xy 376.284742 -286.398162)
			(xy 376.30079 -286.348769) (xy 376.324368 -286.302495) (xy 376.354894 -286.260479) (xy 376.391617 -286.223756)
			(xy 376.433633 -286.19323) (xy 376.479907 -286.169652) (xy 376.5293 -286.153604) (xy 376.580595 -286.145479)
			(xy 376.632529 -286.145479) (xy 376.683824 -286.153604) (xy 376.733217 -286.169652) (xy 376.779491 -286.19323)
			(xy 376.821507 -286.223756) (xy 376.85823 -286.260479) (xy 376.888756 -286.302495) (xy 376.912334 -286.348769)
			(xy 376.928382 -286.398162) (xy 376.936507 -286.449457) (xy 376.937016 -286.475424) (xy 377.216162 -286.475424)
			(xy 377.216567 -286.44997) (xy 377.224357 -286.399662) (xy 377.239771 -286.351145) (xy 377.262444 -286.305566)
			(xy 377.291841 -286.264004) (xy 377.327265 -286.227443) (xy 377.367877 -286.196748) (xy 377.412718 -286.172646)
			(xy 377.460724 -286.155707) (xy 377.485656 -286.150558) (xy 377.508516 -286.14624) (xy 377.712224 -285.79318)
			(xy 377.704604 -285.771082) (xy 377.695862 -285.744495) (xy 377.686417 -285.689335) (xy 377.685808 -285.661354)
			(xy 377.686317 -285.635387) (xy 377.694442 -285.584092) (xy 377.71049 -285.534699) (xy 377.734068 -285.488425)
			(xy 377.764594 -285.446409) (xy 377.801317 -285.409686) (xy 377.843333 -285.37916) (xy 377.889607 -285.355582)
			(xy 377.939 -285.339534) (xy 377.990295 -285.331409) (xy 378.042229 -285.331409) (xy 378.093524 -285.339534)
			(xy 378.142917 -285.355582) (xy 378.189191 -285.37916) (xy 378.231207 -285.409686) (xy 378.26793 -285.446409)
			(xy 378.298456 -285.488425) (xy 378.322034 -285.534699) (xy 378.338082 -285.584092) (xy 378.346207 -285.635387)
			(xy 378.346716 -285.661354) (xy 378.346309 -285.686808) (xy 378.338522 -285.737117) (xy 378.323109 -285.785635)
			(xy 378.300437 -285.831216) (xy 378.271041 -285.872778) (xy 378.235616 -285.90934) (xy 378.195003 -285.940034)
			(xy 378.150162 -285.964135) (xy 378.102154 -285.981072) (xy 378.077222 -285.98622) (xy 378.054362 -285.990538)
			(xy 377.850654 -286.343598) (xy 377.858274 -286.365696) (xy 377.86701 -286.392285) (xy 377.876459 -286.447444)
			(xy 377.87707 -286.475424) (xy 377.876561 -286.501391) (xy 378.156217 -286.501391) (xy 378.156217 -286.449457)
			(xy 378.164342 -286.398162) (xy 378.18039 -286.348769) (xy 378.203968 -286.302495) (xy 378.234494 -286.260479)
			(xy 378.271217 -286.223756) (xy 378.313233 -286.19323) (xy 378.359507 -286.169652) (xy 378.4089 -286.153604)
			(xy 378.460195 -286.145479) (xy 378.512129 -286.145479) (xy 378.563424 -286.153604) (xy 378.612817 -286.169652)
			(xy 378.659091 -286.19323) (xy 378.701107 -286.223756) (xy 378.73783 -286.260479) (xy 378.768356 -286.302495)
			(xy 378.791934 -286.348769) (xy 378.807982 -286.398162) (xy 378.816107 -286.449457) (xy 378.816616 -286.475424)
			(xy 379.095762 -286.475424) (xy 379.096167 -286.44997) (xy 379.103957 -286.399662) (xy 379.119371 -286.351145)
			(xy 379.142044 -286.305566) (xy 379.171441 -286.264004) (xy 379.206865 -286.227443) (xy 379.247477 -286.196748)
			(xy 379.292318 -286.172646) (xy 379.340324 -286.155707) (xy 379.365256 -286.150558) (xy 379.388116 -286.14624)
			(xy 379.591824 -285.79318) (xy 379.584204 -285.771082) (xy 379.575462 -285.744495) (xy 379.566017 -285.689335)
			(xy 379.565408 -285.661354) (xy 379.565917 -285.635387) (xy 379.574042 -285.584092) (xy 379.59009 -285.534699)
			(xy 379.613668 -285.488425) (xy 379.644194 -285.446409) (xy 379.680917 -285.409686) (xy 379.722933 -285.37916)
			(xy 379.769207 -285.355582) (xy 379.8186 -285.339534) (xy 379.869895 -285.331409) (xy 379.921829 -285.331409)
			(xy 379.973124 -285.339534) (xy 380.022517 -285.355582) (xy 380.068791 -285.37916) (xy 380.110807 -285.409686)
			(xy 380.14753 -285.446409) (xy 380.178056 -285.488425) (xy 380.201634 -285.534699) (xy 380.217682 -285.584092)
			(xy 380.225807 -285.635387) (xy 380.226316 -285.661354) (xy 380.225909 -285.686808) (xy 380.218122 -285.737117)
			(xy 380.202709 -285.785635) (xy 380.180037 -285.831216) (xy 380.150641 -285.872778) (xy 380.115216 -285.90934)
			(xy 380.074603 -285.940034) (xy 380.029762 -285.964135) (xy 379.981754 -285.981072) (xy 379.956822 -285.98622)
			(xy 379.933962 -285.990538) (xy 379.730254 -286.343598) (xy 379.737874 -286.365696) (xy 379.74661 -286.392285)
			(xy 379.756059 -286.447444) (xy 379.75667 -286.475424) (xy 379.756161 -286.501391) (xy 380.035817 -286.501391)
			(xy 380.035817 -286.449457) (xy 380.043942 -286.398162) (xy 380.05999 -286.348769) (xy 380.083568 -286.302495)
			(xy 380.114094 -286.260479) (xy 380.150817 -286.223756) (xy 380.192833 -286.19323) (xy 380.239107 -286.169652)
			(xy 380.2885 -286.153604) (xy 380.339795 -286.145479) (xy 380.391729 -286.145479) (xy 380.443024 -286.153604)
			(xy 380.492417 -286.169652) (xy 380.538691 -286.19323) (xy 380.580707 -286.223756) (xy 380.61743 -286.260479)
			(xy 380.647956 -286.302495) (xy 380.671534 -286.348769) (xy 380.687582 -286.398162) (xy 380.695707 -286.449457)
			(xy 380.696216 -286.475424) (xy 380.975362 -286.475424) (xy 380.975767 -286.44997) (xy 380.983557 -286.399662)
			(xy 380.998971 -286.351145) (xy 381.021644 -286.305566) (xy 381.051041 -286.264004) (xy 381.086465 -286.227443)
			(xy 381.127077 -286.196748) (xy 381.171918 -286.172646) (xy 381.219924 -286.155707) (xy 381.244856 -286.150558)
			(xy 381.267716 -286.14624) (xy 381.471424 -285.79318) (xy 381.463804 -285.771082) (xy 381.455062 -285.744495)
			(xy 381.445617 -285.689335) (xy 381.445008 -285.661354) (xy 381.445517 -285.635387) (xy 381.453642 -285.584092)
			(xy 381.46969 -285.534699) (xy 381.493268 -285.488425) (xy 381.523794 -285.446409) (xy 381.560517 -285.409686)
			(xy 381.602533 -285.37916) (xy 381.648807 -285.355582) (xy 381.6982 -285.339534) (xy 381.749495 -285.331409)
			(xy 381.801429 -285.331409) (xy 381.852724 -285.339534) (xy 381.902117 -285.355582) (xy 381.948391 -285.37916)
			(xy 381.990407 -285.409686) (xy 382.02713 -285.446409) (xy 382.057656 -285.488425) (xy 382.081234 -285.534699)
			(xy 382.097282 -285.584092) (xy 382.105407 -285.635387) (xy 382.105916 -285.661354) (xy 382.105509 -285.686808)
			(xy 382.10543 -285.687321) (xy 382.385317 -285.687321) (xy 382.385317 -285.635387) (xy 382.393442 -285.584092)
			(xy 382.40949 -285.534699) (xy 382.433068 -285.488425) (xy 382.463594 -285.446409) (xy 382.500317 -285.409686)
			(xy 382.542333 -285.37916) (xy 382.588607 -285.355582) (xy 382.638 -285.339534) (xy 382.689295 -285.331409)
			(xy 382.741229 -285.331409) (xy 382.792524 -285.339534) (xy 382.841917 -285.355582) (xy 382.888191 -285.37916)
			(xy 382.930207 -285.409686) (xy 382.96693 -285.446409) (xy 382.997456 -285.488425) (xy 383.021034 -285.534699)
			(xy 383.037082 -285.584092) (xy 383.045207 -285.635387) (xy 383.045716 -285.661354) (xy 383.045207 -285.687321)
			(xy 383.037082 -285.738616) (xy 383.021034 -285.788009) (xy 382.997456 -285.834283) (xy 382.96693 -285.876299)
			(xy 382.930207 -285.913022) (xy 382.888191 -285.943548) (xy 382.841917 -285.967126) (xy 382.792524 -285.983174)
			(xy 382.741229 -285.991299) (xy 382.689295 -285.991299) (xy 382.638 -285.983174) (xy 382.588607 -285.967126)
			(xy 382.542333 -285.943548) (xy 382.500317 -285.913022) (xy 382.463594 -285.876299) (xy 382.433068 -285.834283)
			(xy 382.40949 -285.788009) (xy 382.393442 -285.738616) (xy 382.385317 -285.687321) (xy 382.10543 -285.687321)
			(xy 382.097722 -285.737117) (xy 382.082309 -285.785635) (xy 382.059637 -285.831216) (xy 382.030241 -285.872778)
			(xy 381.994816 -285.90934) (xy 381.954203 -285.940034) (xy 381.909362 -285.964135) (xy 381.861354 -285.981072)
			(xy 381.836422 -285.98622) (xy 381.813562 -285.990538) (xy 381.609854 -286.343598) (xy 381.617474 -286.365696)
			(xy 381.62621 -286.392285) (xy 381.635659 -286.447444) (xy 381.63627 -286.475424) (xy 381.635761 -286.501391)
			(xy 381.915671 -286.501391) (xy 381.915671 -286.449457) (xy 381.923796 -286.398162) (xy 381.939844 -286.348769)
			(xy 381.963422 -286.302495) (xy 381.993948 -286.260479) (xy 382.030671 -286.223756) (xy 382.072687 -286.19323)
			(xy 382.118961 -286.169652) (xy 382.168354 -286.153604) (xy 382.219649 -286.145479) (xy 382.271583 -286.145479)
			(xy 382.322878 -286.153604) (xy 382.372271 -286.169652) (xy 382.418545 -286.19323) (xy 382.460561 -286.223756)
			(xy 382.497284 -286.260479) (xy 382.52781 -286.302495) (xy 382.551388 -286.348769) (xy 382.567436 -286.398162)
			(xy 382.575561 -286.449457) (xy 382.57607 -286.475424) (xy 382.575566 -286.501137) (xy 382.855217 -286.501137)
			(xy 382.855217 -286.449203) (xy 382.863342 -286.397908) (xy 382.87939 -286.348515) (xy 382.902968 -286.302241)
			(xy 382.933494 -286.260225) (xy 382.970217 -286.223502) (xy 383.012233 -286.192976) (xy 383.058507 -286.169398)
			(xy 383.1079 -286.15335) (xy 383.159195 -286.145225) (xy 383.211129 -286.145225) (xy 383.262424 -286.15335)
			(xy 383.311817 -286.169398) (xy 383.358091 -286.192976) (xy 383.400107 -286.223502) (xy 383.43683 -286.260225)
			(xy 383.467356 -286.302241) (xy 383.490934 -286.348515) (xy 383.506982 -286.397908) (xy 383.515107 -286.449203)
			(xy 383.515616 -286.47517) (xy 383.515107 -286.501137) (xy 383.506982 -286.552432) (xy 383.490934 -286.601825)
			(xy 383.467356 -286.648099) (xy 383.43683 -286.690115) (xy 383.400107 -286.726838) (xy 383.358091 -286.757364)
			(xy 383.311817 -286.780942) (xy 383.262424 -286.79699) (xy 383.211129 -286.805115) (xy 383.159195 -286.805115)
			(xy 383.1079 -286.79699) (xy 383.058507 -286.780942) (xy 383.012233 -286.757364) (xy 382.970217 -286.726838)
			(xy 382.933494 -286.690115) (xy 382.902968 -286.648099) (xy 382.87939 -286.601825) (xy 382.863342 -286.552432)
			(xy 382.855217 -286.501137) (xy 382.575566 -286.501137) (xy 382.575561 -286.501391) (xy 382.567436 -286.552686)
			(xy 382.551388 -286.602079) (xy 382.52781 -286.648353) (xy 382.497284 -286.690369) (xy 382.460561 -286.727092)
			(xy 382.418545 -286.757618) (xy 382.372271 -286.781196) (xy 382.322878 -286.797244) (xy 382.271583 -286.805369)
			(xy 382.219649 -286.805369) (xy 382.168354 -286.797244) (xy 382.118961 -286.781196) (xy 382.072687 -286.757618)
			(xy 382.030671 -286.727092) (xy 381.993948 -286.690369) (xy 381.963422 -286.648353) (xy 381.939844 -286.602079)
			(xy 381.923796 -286.552686) (xy 381.915671 -286.501391) (xy 381.635761 -286.501391) (xy 381.627636 -286.552686)
			(xy 381.611588 -286.602079) (xy 381.58801 -286.648353) (xy 381.557484 -286.690369) (xy 381.520761 -286.727092)
			(xy 381.478745 -286.757618) (xy 381.432471 -286.781196) (xy 381.383078 -286.797244) (xy 381.331783 -286.805369)
			(xy 381.279849 -286.805369) (xy 381.228554 -286.797244) (xy 381.179161 -286.781196) (xy 381.132887 -286.757618)
			(xy 381.090871 -286.727092) (xy 381.054148 -286.690369) (xy 381.023622 -286.648353) (xy 381.000044 -286.602079)
			(xy 380.983996 -286.552686) (xy 380.975871 -286.501391) (xy 380.975362 -286.475424) (xy 380.696216 -286.475424)
			(xy 380.695707 -286.501391) (xy 380.687582 -286.552686) (xy 380.671534 -286.602079) (xy 380.647956 -286.648353)
			(xy 380.61743 -286.690369) (xy 380.580707 -286.727092) (xy 380.538691 -286.757618) (xy 380.492417 -286.781196)
			(xy 380.443024 -286.797244) (xy 380.391729 -286.805369) (xy 380.339795 -286.805369) (xy 380.2885 -286.797244)
			(xy 380.239107 -286.781196) (xy 380.192833 -286.757618) (xy 380.150817 -286.727092) (xy 380.114094 -286.690369)
			(xy 380.083568 -286.648353) (xy 380.05999 -286.602079) (xy 380.043942 -286.552686) (xy 380.035817 -286.501391)
			(xy 379.756161 -286.501391) (xy 379.748036 -286.552686) (xy 379.731988 -286.602079) (xy 379.70841 -286.648353)
			(xy 379.677884 -286.690369) (xy 379.641161 -286.727092) (xy 379.599145 -286.757618) (xy 379.552871 -286.781196)
			(xy 379.503478 -286.797244) (xy 379.452183 -286.805369) (xy 379.400249 -286.805369) (xy 379.348954 -286.797244)
			(xy 379.299561 -286.781196) (xy 379.253287 -286.757618) (xy 379.211271 -286.727092) (xy 379.174548 -286.690369)
			(xy 379.144022 -286.648353) (xy 379.120444 -286.602079) (xy 379.104396 -286.552686) (xy 379.096271 -286.501391)
			(xy 379.095762 -286.475424) (xy 378.816616 -286.475424) (xy 378.816107 -286.501391) (xy 378.807982 -286.552686)
			(xy 378.791934 -286.602079) (xy 378.768356 -286.648353) (xy 378.73783 -286.690369) (xy 378.701107 -286.727092)
			(xy 378.659091 -286.757618) (xy 378.612817 -286.781196) (xy 378.563424 -286.797244) (xy 378.512129 -286.805369)
			(xy 378.460195 -286.805369) (xy 378.4089 -286.797244) (xy 378.359507 -286.781196) (xy 378.313233 -286.757618)
			(xy 378.271217 -286.727092) (xy 378.234494 -286.690369) (xy 378.203968 -286.648353) (xy 378.18039 -286.602079)
			(xy 378.164342 -286.552686) (xy 378.156217 -286.501391) (xy 377.876561 -286.501391) (xy 377.868436 -286.552686)
			(xy 377.852388 -286.602079) (xy 377.82881 -286.648353) (xy 377.798284 -286.690369) (xy 377.761561 -286.727092)
			(xy 377.719545 -286.757618) (xy 377.673271 -286.781196) (xy 377.623878 -286.797244) (xy 377.572583 -286.805369)
			(xy 377.520649 -286.805369) (xy 377.469354 -286.797244) (xy 377.419961 -286.781196) (xy 377.373687 -286.757618)
			(xy 377.331671 -286.727092) (xy 377.294948 -286.690369) (xy 377.264422 -286.648353) (xy 377.240844 -286.602079)
			(xy 377.224796 -286.552686) (xy 377.216671 -286.501391) (xy 377.216162 -286.475424) (xy 376.937016 -286.475424)
			(xy 376.936507 -286.501391) (xy 376.928382 -286.552686) (xy 376.912334 -286.602079) (xy 376.888756 -286.648353)
			(xy 376.85823 -286.690369) (xy 376.821507 -286.727092) (xy 376.779491 -286.757618) (xy 376.733217 -286.781196)
			(xy 376.683824 -286.797244) (xy 376.632529 -286.805369) (xy 376.580595 -286.805369) (xy 376.5293 -286.797244)
			(xy 376.479907 -286.781196) (xy 376.433633 -286.757618) (xy 376.391617 -286.727092) (xy 376.354894 -286.690369)
			(xy 376.324368 -286.648353) (xy 376.30079 -286.602079) (xy 376.284742 -286.552686) (xy 376.276617 -286.501391)
			(xy 375.996961 -286.501391) (xy 375.988836 -286.552686) (xy 375.972788 -286.602079) (xy 375.94921 -286.648353)
			(xy 375.918684 -286.690369) (xy 375.881961 -286.727092) (xy 375.839945 -286.757618) (xy 375.793671 -286.781196)
			(xy 375.744278 -286.797244) (xy 375.692983 -286.805369) (xy 375.641049 -286.805369) (xy 375.589754 -286.797244)
			(xy 375.540361 -286.781196) (xy 375.494087 -286.757618) (xy 375.452071 -286.727092) (xy 375.415348 -286.690369)
			(xy 375.384822 -286.648353) (xy 375.361244 -286.602079) (xy 375.345196 -286.552686) (xy 375.337071 -286.501391)
			(xy 375.336562 -286.475424) (xy 375.057416 -286.475424) (xy 375.056907 -286.501391) (xy 375.048782 -286.552686)
			(xy 375.032734 -286.602079) (xy 375.009156 -286.648353) (xy 374.97863 -286.690369) (xy 374.941907 -286.727092)
			(xy 374.899891 -286.757618) (xy 374.853617 -286.781196) (xy 374.804224 -286.797244) (xy 374.752929 -286.805369)
			(xy 374.700995 -286.805369) (xy 374.6497 -286.797244) (xy 374.600307 -286.781196) (xy 374.554033 -286.757618)
			(xy 374.512017 -286.727092) (xy 374.475294 -286.690369) (xy 374.444768 -286.648353) (xy 374.42119 -286.602079)
			(xy 374.405142 -286.552686) (xy 374.397017 -286.501391) (xy 374.117361 -286.501391) (xy 374.109236 -286.552686)
			(xy 374.093188 -286.602079) (xy 374.06961 -286.648353) (xy 374.039084 -286.690369) (xy 374.002361 -286.727092)
			(xy 373.960345 -286.757618) (xy 373.914071 -286.781196) (xy 373.864678 -286.797244) (xy 373.813383 -286.805369)
			(xy 373.761449 -286.805369) (xy 373.710154 -286.797244) (xy 373.660761 -286.781196) (xy 373.614487 -286.757618)
			(xy 373.572471 -286.727092) (xy 373.535748 -286.690369) (xy 373.505222 -286.648353) (xy 373.481644 -286.602079)
			(xy 373.465596 -286.552686) (xy 373.457471 -286.501391) (xy 373.456962 -286.475424) (xy 373.177816 -286.475424)
			(xy 373.177307 -286.501391) (xy 373.169182 -286.552686) (xy 373.153134 -286.602079) (xy 373.129556 -286.648353)
			(xy 373.09903 -286.690369) (xy 373.062307 -286.727092) (xy 373.020291 -286.757618) (xy 372.974017 -286.781196)
			(xy 372.924624 -286.797244) (xy 372.873329 -286.805369) (xy 372.821395 -286.805369) (xy 372.7701 -286.797244)
			(xy 372.720707 -286.781196) (xy 372.674433 -286.757618) (xy 372.632417 -286.727092) (xy 372.595694 -286.690369)
			(xy 372.565168 -286.648353) (xy 372.54159 -286.602079) (xy 372.525542 -286.552686) (xy 372.517417 -286.501391)
			(xy 372.237761 -286.501391) (xy 372.229636 -286.552686) (xy 372.213588 -286.602079) (xy 372.19001 -286.648353)
			(xy 372.159484 -286.690369) (xy 372.122761 -286.727092) (xy 372.080745 -286.757618) (xy 372.034471 -286.781196)
			(xy 371.985078 -286.797244) (xy 371.933783 -286.805369) (xy 371.881849 -286.805369) (xy 371.830554 -286.797244)
			(xy 371.781161 -286.781196) (xy 371.734887 -286.757618) (xy 371.692871 -286.727092) (xy 371.656148 -286.690369)
			(xy 371.625622 -286.648353) (xy 371.602044 -286.602079) (xy 371.585996 -286.552686) (xy 371.577871 -286.501391)
			(xy 371.577362 -286.475424) (xy 371.298216 -286.475424) (xy 371.297707 -286.501391) (xy 371.289582 -286.552686)
			(xy 371.273534 -286.602079) (xy 371.249956 -286.648353) (xy 371.21943 -286.690369) (xy 371.182707 -286.727092)
			(xy 371.140691 -286.757618) (xy 371.094417 -286.781196) (xy 371.045024 -286.797244) (xy 370.993729 -286.805369)
			(xy 370.941795 -286.805369) (xy 370.8905 -286.797244) (xy 370.841107 -286.781196) (xy 370.794833 -286.757618)
			(xy 370.752817 -286.727092) (xy 370.716094 -286.690369) (xy 370.685568 -286.648353) (xy 370.66199 -286.602079)
			(xy 370.645942 -286.552686) (xy 370.637817 -286.501391) (xy 370.358159 -286.501391) (xy 370.350032 -286.552684)
			(xy 370.333981 -286.602074) (xy 370.310402 -286.648346) (xy 370.279876 -286.69036) (xy 370.243153 -286.727081)
			(xy 370.201139 -286.757607) (xy 370.154866 -286.781184) (xy 370.105476 -286.797234) (xy 370.054182 -286.80536)
			(xy 370.028216 -286.805878) (xy 369.992402 -286.803846) (xy 369.978184 -286.802777) (xy 369.950104 -286.807642)
			(xy 369.924462 -286.820082) (xy 369.90326 -286.839125) (xy 369.888148 -286.863289) (xy 369.880307 -286.890688)
			(xy 369.87988 -286.904938) (xy 369.87988 -287.214056) (xy 369.88115 -287.21939) (xy 369.884616 -287.236644)
			(xy 369.888311 -287.271643) (xy 369.888516 -287.28924) (xy 369.888028 -287.314992) (xy 369.887994 -287.315207)
			(xy 370.167917 -287.315207) (xy 370.167917 -287.263273) (xy 370.176042 -287.211978) (xy 370.19209 -287.162585)
			(xy 370.215668 -287.116311) (xy 370.246194 -287.074295) (xy 370.282917 -287.037572) (xy 370.324933 -287.007046)
			(xy 370.371207 -286.983468) (xy 370.4206 -286.96742) (xy 370.471895 -286.959295) (xy 370.523829 -286.959295)
			(xy 370.575124 -286.96742) (xy 370.624517 -286.983468) (xy 370.670791 -287.007046) (xy 370.712807 -287.037572)
			(xy 370.74953 -287.074295) (xy 370.780056 -287.116311) (xy 370.803634 -287.162585) (xy 370.819682 -287.211978)
			(xy 370.827807 -287.263273) (xy 370.828316 -287.28924) (xy 370.827807 -287.315207) (xy 371.107717 -287.315207)
			(xy 371.107717 -287.263273) (xy 371.115842 -287.211978) (xy 371.13189 -287.162585) (xy 371.155468 -287.116311)
			(xy 371.185994 -287.074295) (xy 371.222717 -287.037572) (xy 371.264733 -287.007046) (xy 371.311007 -286.983468)
			(xy 371.3604 -286.96742) (xy 371.411695 -286.959295) (xy 371.463629 -286.959295) (xy 371.514924 -286.96742)
			(xy 371.564317 -286.983468) (xy 371.610591 -287.007046) (xy 371.652607 -287.037572) (xy 371.68933 -287.074295)
			(xy 371.719856 -287.116311) (xy 371.743434 -287.162585) (xy 371.759482 -287.211978) (xy 371.767607 -287.263273)
			(xy 371.768116 -287.28924) (xy 371.767607 -287.315207) (xy 372.047517 -287.315207) (xy 372.047517 -287.263273)
			(xy 372.055642 -287.211978) (xy 372.07169 -287.162585) (xy 372.095268 -287.116311) (xy 372.125794 -287.074295)
			(xy 372.162517 -287.037572) (xy 372.204533 -287.007046) (xy 372.250807 -286.983468) (xy 372.3002 -286.96742)
			(xy 372.351495 -286.959295) (xy 372.403429 -286.959295) (xy 372.454724 -286.96742) (xy 372.504117 -286.983468)
			(xy 372.550391 -287.007046) (xy 372.592407 -287.037572) (xy 372.62913 -287.074295) (xy 372.659656 -287.116311)
			(xy 372.683234 -287.162585) (xy 372.699282 -287.211978) (xy 372.707407 -287.263273) (xy 372.707916 -287.28924)
			(xy 372.707407 -287.315207) (xy 372.987317 -287.315207) (xy 372.987317 -287.263273) (xy 372.995442 -287.211978)
			(xy 373.01149 -287.162585) (xy 373.035068 -287.116311) (xy 373.065594 -287.074295) (xy 373.102317 -287.037572)
			(xy 373.144333 -287.007046) (xy 373.190607 -286.983468) (xy 373.24 -286.96742) (xy 373.291295 -286.959295)
			(xy 373.343229 -286.959295) (xy 373.394524 -286.96742) (xy 373.443917 -286.983468) (xy 373.490191 -287.007046)
			(xy 373.532207 -287.037572) (xy 373.56893 -287.074295) (xy 373.599456 -287.116311) (xy 373.623034 -287.162585)
			(xy 373.639082 -287.211978) (xy 373.647207 -287.263273) (xy 373.647716 -287.28924) (xy 373.647207 -287.315207)
			(xy 373.927117 -287.315207) (xy 373.927117 -287.263273) (xy 373.935242 -287.211978) (xy 373.95129 -287.162585)
			(xy 373.974868 -287.116311) (xy 374.005394 -287.074295) (xy 374.042117 -287.037572) (xy 374.084133 -287.007046)
			(xy 374.130407 -286.983468) (xy 374.1798 -286.96742) (xy 374.231095 -286.959295) (xy 374.283029 -286.959295)
			(xy 374.334324 -286.96742) (xy 374.383717 -286.983468) (xy 374.429991 -287.007046) (xy 374.472007 -287.037572)
			(xy 374.50873 -287.074295) (xy 374.539256 -287.116311) (xy 374.562834 -287.162585) (xy 374.578882 -287.211978)
			(xy 374.587007 -287.263273) (xy 374.587516 -287.28924) (xy 374.587007 -287.315207) (xy 374.866917 -287.315207)
			(xy 374.866917 -287.263273) (xy 374.875042 -287.211978) (xy 374.89109 -287.162585) (xy 374.914668 -287.116311)
			(xy 374.945194 -287.074295) (xy 374.981917 -287.037572) (xy 375.023933 -287.007046) (xy 375.070207 -286.983468)
			(xy 375.1196 -286.96742) (xy 375.170895 -286.959295) (xy 375.222829 -286.959295) (xy 375.274124 -286.96742)
			(xy 375.323517 -286.983468) (xy 375.369791 -287.007046) (xy 375.411807 -287.037572) (xy 375.44853 -287.074295)
			(xy 375.479056 -287.116311) (xy 375.502634 -287.162585) (xy 375.518682 -287.211978) (xy 375.526807 -287.263273)
			(xy 375.527316 -287.28924) (xy 375.526807 -287.315207) (xy 375.806717 -287.315207) (xy 375.806717 -287.263273)
			(xy 375.814842 -287.211978) (xy 375.83089 -287.162585) (xy 375.854468 -287.116311) (xy 375.884994 -287.074295)
			(xy 375.921717 -287.037572) (xy 375.963733 -287.007046) (xy 376.010007 -286.983468) (xy 376.0594 -286.96742)
			(xy 376.110695 -286.959295) (xy 376.162629 -286.959295) (xy 376.213924 -286.96742) (xy 376.263317 -286.983468)
			(xy 376.309591 -287.007046) (xy 376.351607 -287.037572) (xy 376.38833 -287.074295) (xy 376.418856 -287.116311)
			(xy 376.442434 -287.162585) (xy 376.458482 -287.211978) (xy 376.466607 -287.263273) (xy 376.467116 -287.28924)
			(xy 376.466607 -287.315207) (xy 376.746517 -287.315207) (xy 376.746517 -287.263273) (xy 376.754642 -287.211978)
			(xy 376.77069 -287.162585) (xy 376.794268 -287.116311) (xy 376.824794 -287.074295) (xy 376.861517 -287.037572)
			(xy 376.903533 -287.007046) (xy 376.949807 -286.983468) (xy 376.9992 -286.96742) (xy 377.050495 -286.959295)
			(xy 377.102429 -286.959295) (xy 377.153724 -286.96742) (xy 377.203117 -286.983468) (xy 377.249391 -287.007046)
			(xy 377.291407 -287.037572) (xy 377.32813 -287.074295) (xy 377.358656 -287.116311) (xy 377.382234 -287.162585)
			(xy 377.398282 -287.211978) (xy 377.406407 -287.263273) (xy 377.406916 -287.28924) (xy 377.406407 -287.315207)
			(xy 377.686317 -287.315207) (xy 377.686317 -287.263273) (xy 377.694442 -287.211978) (xy 377.71049 -287.162585)
			(xy 377.734068 -287.116311) (xy 377.764594 -287.074295) (xy 377.801317 -287.037572) (xy 377.843333 -287.007046)
			(xy 377.889607 -286.983468) (xy 377.939 -286.96742) (xy 377.990295 -286.959295) (xy 378.042229 -286.959295)
			(xy 378.093524 -286.96742) (xy 378.142917 -286.983468) (xy 378.189191 -287.007046) (xy 378.231207 -287.037572)
			(xy 378.26793 -287.074295) (xy 378.298456 -287.116311) (xy 378.322034 -287.162585) (xy 378.338082 -287.211978)
			(xy 378.346207 -287.263273) (xy 378.346716 -287.28924) (xy 378.346207 -287.315207) (xy 378.626117 -287.315207)
			(xy 378.626117 -287.263273) (xy 378.634242 -287.211978) (xy 378.65029 -287.162585) (xy 378.673868 -287.116311)
			(xy 378.704394 -287.074295) (xy 378.741117 -287.037572) (xy 378.783133 -287.007046) (xy 378.829407 -286.983468)
			(xy 378.8788 -286.96742) (xy 378.930095 -286.959295) (xy 378.982029 -286.959295) (xy 379.033324 -286.96742)
			(xy 379.082717 -286.983468) (xy 379.128991 -287.007046) (xy 379.171007 -287.037572) (xy 379.20773 -287.074295)
			(xy 379.238256 -287.116311) (xy 379.261834 -287.162585) (xy 379.277882 -287.211978) (xy 379.286007 -287.263273)
			(xy 379.286516 -287.28924) (xy 379.286007 -287.315207) (xy 379.565917 -287.315207) (xy 379.565917 -287.263273)
			(xy 379.574042 -287.211978) (xy 379.59009 -287.162585) (xy 379.613668 -287.116311) (xy 379.644194 -287.074295)
			(xy 379.680917 -287.037572) (xy 379.722933 -287.007046) (xy 379.769207 -286.983468) (xy 379.8186 -286.96742)
			(xy 379.869895 -286.959295) (xy 379.921829 -286.959295) (xy 379.973124 -286.96742) (xy 380.022517 -286.983468)
			(xy 380.068791 -287.007046) (xy 380.110807 -287.037572) (xy 380.14753 -287.074295) (xy 380.178056 -287.116311)
			(xy 380.201634 -287.162585) (xy 380.217682 -287.211978) (xy 380.225807 -287.263273) (xy 380.226316 -287.28924)
			(xy 380.225807 -287.315207) (xy 380.505717 -287.315207) (xy 380.505717 -287.263273) (xy 380.513842 -287.211978)
			(xy 380.52989 -287.162585) (xy 380.553468 -287.116311) (xy 380.583994 -287.074295) (xy 380.620717 -287.037572)
			(xy 380.662733 -287.007046) (xy 380.709007 -286.983468) (xy 380.7584 -286.96742) (xy 380.809695 -286.959295)
			(xy 380.861629 -286.959295) (xy 380.912924 -286.96742) (xy 380.962317 -286.983468) (xy 381.008591 -287.007046)
			(xy 381.050607 -287.037572) (xy 381.08733 -287.074295) (xy 381.117856 -287.116311) (xy 381.141434 -287.162585)
			(xy 381.157482 -287.211978) (xy 381.165607 -287.263273) (xy 381.166116 -287.28924) (xy 381.165607 -287.315207)
			(xy 381.445517 -287.315207) (xy 381.445517 -287.263273) (xy 381.453642 -287.211978) (xy 381.46969 -287.162585)
			(xy 381.493268 -287.116311) (xy 381.523794 -287.074295) (xy 381.560517 -287.037572) (xy 381.602533 -287.007046)
			(xy 381.648807 -286.983468) (xy 381.6982 -286.96742) (xy 381.749495 -286.959295) (xy 381.801429 -286.959295)
			(xy 381.852724 -286.96742) (xy 381.902117 -286.983468) (xy 381.948391 -287.007046) (xy 381.990407 -287.037572)
			(xy 382.02713 -287.074295) (xy 382.057656 -287.116311) (xy 382.081234 -287.162585) (xy 382.097282 -287.211978)
			(xy 382.105407 -287.263273) (xy 382.105916 -287.28924) (xy 382.105407 -287.315207) (xy 382.385317 -287.315207)
			(xy 382.385317 -287.263273) (xy 382.393442 -287.211978) (xy 382.40949 -287.162585) (xy 382.433068 -287.116311)
			(xy 382.463594 -287.074295) (xy 382.500317 -287.037572) (xy 382.542333 -287.007046) (xy 382.588607 -286.983468)
			(xy 382.638 -286.96742) (xy 382.689295 -286.959295) (xy 382.741229 -286.959295) (xy 382.792524 -286.96742)
			(xy 382.841917 -286.983468) (xy 382.888191 -287.007046) (xy 382.930207 -287.037572) (xy 382.96693 -287.074295)
			(xy 382.997456 -287.116311) (xy 383.021034 -287.162585) (xy 383.037082 -287.211978) (xy 383.045207 -287.263273)
			(xy 383.045716 -287.28924) (xy 383.045207 -287.315207) (xy 383.037082 -287.366502) (xy 383.021034 -287.415895)
			(xy 382.997456 -287.462169) (xy 382.96693 -287.504185) (xy 382.930207 -287.540908) (xy 382.888191 -287.571434)
			(xy 382.841917 -287.595012) (xy 382.792524 -287.61106) (xy 382.741229 -287.619185) (xy 382.689295 -287.619185)
			(xy 382.638 -287.61106) (xy 382.588607 -287.595012) (xy 382.542333 -287.571434) (xy 382.500317 -287.540908)
			(xy 382.463594 -287.504185) (xy 382.433068 -287.462169) (xy 382.40949 -287.415895) (xy 382.393442 -287.366502)
			(xy 382.385317 -287.315207) (xy 382.105407 -287.315207) (xy 382.097282 -287.366502) (xy 382.081234 -287.415895)
			(xy 382.057656 -287.462169) (xy 382.02713 -287.504185) (xy 381.990407 -287.540908) (xy 381.948391 -287.571434)
			(xy 381.902117 -287.595012) (xy 381.852724 -287.61106) (xy 381.801429 -287.619185) (xy 381.749495 -287.619185)
			(xy 381.6982 -287.61106) (xy 381.648807 -287.595012) (xy 381.602533 -287.571434) (xy 381.560517 -287.540908)
			(xy 381.523794 -287.504185) (xy 381.493268 -287.462169) (xy 381.46969 -287.415895) (xy 381.453642 -287.366502)
			(xy 381.445517 -287.315207) (xy 381.165607 -287.315207) (xy 381.157482 -287.366502) (xy 381.141434 -287.415895)
			(xy 381.117856 -287.462169) (xy 381.08733 -287.504185) (xy 381.050607 -287.540908) (xy 381.008591 -287.571434)
			(xy 380.962317 -287.595012) (xy 380.912924 -287.61106) (xy 380.861629 -287.619185) (xy 380.809695 -287.619185)
			(xy 380.7584 -287.61106) (xy 380.709007 -287.595012) (xy 380.662733 -287.571434) (xy 380.620717 -287.540908)
			(xy 380.583994 -287.504185) (xy 380.553468 -287.462169) (xy 380.52989 -287.415895) (xy 380.513842 -287.366502)
			(xy 380.505717 -287.315207) (xy 380.225807 -287.315207) (xy 380.217682 -287.366502) (xy 380.201634 -287.415895)
			(xy 380.178056 -287.462169) (xy 380.14753 -287.504185) (xy 380.110807 -287.540908) (xy 380.068791 -287.571434)
			(xy 380.022517 -287.595012) (xy 379.973124 -287.61106) (xy 379.921829 -287.619185) (xy 379.869895 -287.619185)
			(xy 379.8186 -287.61106) (xy 379.769207 -287.595012) (xy 379.722933 -287.571434) (xy 379.680917 -287.540908)
			(xy 379.644194 -287.504185) (xy 379.613668 -287.462169) (xy 379.59009 -287.415895) (xy 379.574042 -287.366502)
			(xy 379.565917 -287.315207) (xy 379.286007 -287.315207) (xy 379.277882 -287.366502) (xy 379.261834 -287.415895)
			(xy 379.238256 -287.462169) (xy 379.20773 -287.504185) (xy 379.171007 -287.540908) (xy 379.128991 -287.571434)
			(xy 379.082717 -287.595012) (xy 379.033324 -287.61106) (xy 378.982029 -287.619185) (xy 378.930095 -287.619185)
			(xy 378.8788 -287.61106) (xy 378.829407 -287.595012) (xy 378.783133 -287.571434) (xy 378.741117 -287.540908)
			(xy 378.704394 -287.504185) (xy 378.673868 -287.462169) (xy 378.65029 -287.415895) (xy 378.634242 -287.366502)
			(xy 378.626117 -287.315207) (xy 378.346207 -287.315207) (xy 378.338082 -287.366502) (xy 378.322034 -287.415895)
			(xy 378.298456 -287.462169) (xy 378.26793 -287.504185) (xy 378.231207 -287.540908) (xy 378.189191 -287.571434)
			(xy 378.142917 -287.595012) (xy 378.093524 -287.61106) (xy 378.042229 -287.619185) (xy 377.990295 -287.619185)
			(xy 377.939 -287.61106) (xy 377.889607 -287.595012) (xy 377.843333 -287.571434) (xy 377.801317 -287.540908)
			(xy 377.764594 -287.504185) (xy 377.734068 -287.462169) (xy 377.71049 -287.415895) (xy 377.694442 -287.366502)
			(xy 377.686317 -287.315207) (xy 377.406407 -287.315207) (xy 377.398282 -287.366502) (xy 377.382234 -287.415895)
			(xy 377.358656 -287.462169) (xy 377.32813 -287.504185) (xy 377.291407 -287.540908) (xy 377.249391 -287.571434)
			(xy 377.203117 -287.595012) (xy 377.153724 -287.61106) (xy 377.102429 -287.619185) (xy 377.050495 -287.619185)
			(xy 376.9992 -287.61106) (xy 376.949807 -287.595012) (xy 376.903533 -287.571434) (xy 376.861517 -287.540908)
			(xy 376.824794 -287.504185) (xy 376.794268 -287.462169) (xy 376.77069 -287.415895) (xy 376.754642 -287.366502)
			(xy 376.746517 -287.315207) (xy 376.466607 -287.315207) (xy 376.458482 -287.366502) (xy 376.442434 -287.415895)
			(xy 376.418856 -287.462169) (xy 376.38833 -287.504185) (xy 376.351607 -287.540908) (xy 376.309591 -287.571434)
			(xy 376.263317 -287.595012) (xy 376.213924 -287.61106) (xy 376.162629 -287.619185) (xy 376.110695 -287.619185)
			(xy 376.0594 -287.61106) (xy 376.010007 -287.595012) (xy 375.963733 -287.571434) (xy 375.921717 -287.540908)
			(xy 375.884994 -287.504185) (xy 375.854468 -287.462169) (xy 375.83089 -287.415895) (xy 375.814842 -287.366502)
			(xy 375.806717 -287.315207) (xy 375.526807 -287.315207) (xy 375.518682 -287.366502) (xy 375.502634 -287.415895)
			(xy 375.479056 -287.462169) (xy 375.44853 -287.504185) (xy 375.411807 -287.540908) (xy 375.369791 -287.571434)
			(xy 375.323517 -287.595012) (xy 375.274124 -287.61106) (xy 375.222829 -287.619185) (xy 375.170895 -287.619185)
			(xy 375.1196 -287.61106) (xy 375.070207 -287.595012) (xy 375.023933 -287.571434) (xy 374.981917 -287.540908)
			(xy 374.945194 -287.504185) (xy 374.914668 -287.462169) (xy 374.89109 -287.415895) (xy 374.875042 -287.366502)
			(xy 374.866917 -287.315207) (xy 374.587007 -287.315207) (xy 374.578882 -287.366502) (xy 374.562834 -287.415895)
			(xy 374.539256 -287.462169) (xy 374.50873 -287.504185) (xy 374.472007 -287.540908) (xy 374.429991 -287.571434)
			(xy 374.383717 -287.595012) (xy 374.334324 -287.61106) (xy 374.283029 -287.619185) (xy 374.231095 -287.619185)
			(xy 374.1798 -287.61106) (xy 374.130407 -287.595012) (xy 374.084133 -287.571434) (xy 374.042117 -287.540908)
			(xy 374.005394 -287.504185) (xy 373.974868 -287.462169) (xy 373.95129 -287.415895) (xy 373.935242 -287.366502)
			(xy 373.927117 -287.315207) (xy 373.647207 -287.315207) (xy 373.639082 -287.366502) (xy 373.623034 -287.415895)
			(xy 373.599456 -287.462169) (xy 373.56893 -287.504185) (xy 373.532207 -287.540908) (xy 373.490191 -287.571434)
			(xy 373.443917 -287.595012) (xy 373.394524 -287.61106) (xy 373.343229 -287.619185) (xy 373.291295 -287.619185)
			(xy 373.24 -287.61106) (xy 373.190607 -287.595012) (xy 373.144333 -287.571434) (xy 373.102317 -287.540908)
			(xy 373.065594 -287.504185) (xy 373.035068 -287.462169) (xy 373.01149 -287.415895) (xy 372.995442 -287.366502)
			(xy 372.987317 -287.315207) (xy 372.707407 -287.315207) (xy 372.699282 -287.366502) (xy 372.683234 -287.415895)
			(xy 372.659656 -287.462169) (xy 372.62913 -287.504185) (xy 372.592407 -287.540908) (xy 372.550391 -287.571434)
			(xy 372.504117 -287.595012) (xy 372.454724 -287.61106) (xy 372.403429 -287.619185) (xy 372.351495 -287.619185)
			(xy 372.3002 -287.61106) (xy 372.250807 -287.595012) (xy 372.204533 -287.571434) (xy 372.162517 -287.540908)
			(xy 372.125794 -287.504185) (xy 372.095268 -287.462169) (xy 372.07169 -287.415895) (xy 372.055642 -287.366502)
			(xy 372.047517 -287.315207) (xy 371.767607 -287.315207) (xy 371.759482 -287.366502) (xy 371.743434 -287.415895)
			(xy 371.719856 -287.462169) (xy 371.68933 -287.504185) (xy 371.652607 -287.540908) (xy 371.610591 -287.571434)
			(xy 371.564317 -287.595012) (xy 371.514924 -287.61106) (xy 371.463629 -287.619185) (xy 371.411695 -287.619185)
			(xy 371.3604 -287.61106) (xy 371.311007 -287.595012) (xy 371.264733 -287.571434) (xy 371.222717 -287.540908)
			(xy 371.185994 -287.504185) (xy 371.155468 -287.462169) (xy 371.13189 -287.415895) (xy 371.115842 -287.366502)
			(xy 371.107717 -287.315207) (xy 370.827807 -287.315207) (xy 370.819682 -287.366502) (xy 370.803634 -287.415895)
			(xy 370.780056 -287.462169) (xy 370.74953 -287.504185) (xy 370.712807 -287.540908) (xy 370.670791 -287.571434)
			(xy 370.624517 -287.595012) (xy 370.575124 -287.61106) (xy 370.523829 -287.619185) (xy 370.471895 -287.619185)
			(xy 370.4206 -287.61106) (xy 370.371207 -287.595012) (xy 370.324933 -287.571434) (xy 370.282917 -287.540908)
			(xy 370.246194 -287.504185) (xy 370.215668 -287.462169) (xy 370.19209 -287.415895) (xy 370.176042 -287.366502)
			(xy 370.167917 -287.315207) (xy 369.887994 -287.315207) (xy 369.880049 -287.365873) (xy 369.864273 -287.414901)
			(xy 369.841083 -287.460889) (xy 369.811041 -287.502722) (xy 369.774873 -287.53939) (xy 369.733455 -287.570003)
			(xy 369.68779 -287.593821) (xy 369.638984 -287.610268) (xy 369.613688 -287.615122) (xy 369.597686 -287.617662)
			(xy 369.54714 -287.668208) (xy 369.54714 -288.502852) (xy 369.596162 -288.587942) (xy 369.619276 -288.59226)
			(xy 369.645338 -288.597688) (xy 369.695411 -288.615752) (xy 369.741941 -288.64161) (xy 369.783726 -288.67459)
			(xy 369.819683 -288.713842) (xy 369.848884 -288.75835) (xy 369.870574 -288.806963) (xy 369.884191 -288.858424)
			(xy 369.887246 -288.884868) (xy 369.891564 -288.930588) (xy 370.164868 -288.930588)
		)
		(stroke
			(width 0)
			(type solid)
		)
		(fill yes)
		(layer "In11.Cu")
		(net "PVCCFA_EHV_FIVRA_CPU0")
	)
	(gr_poly
		(pts
			(xy 122.235468 -288.845244) (xy 122.241682 -288.819694) (xy 122.2611 -288.770831) (xy 122.28801 -288.725659)
			(xy 122.321732 -288.685317) (xy 122.361417 -288.650824) (xy 122.406063 -288.62305) (xy 122.454543 -288.602695)
			(xy 122.505634 -288.590272) (xy 122.558048 -288.586097) (xy 122.610462 -288.590272) (xy 122.661553 -288.602695)
			(xy 122.710033 -288.62305) (xy 122.754679 -288.650824) (xy 122.794364 -288.685317) (xy 122.828086 -288.725659)
			(xy 122.854996 -288.770831) (xy 122.874414 -288.819694) (xy 122.880628 -288.845244) (xy 122.889518 -288.884868)
			(xy 123.166378 -288.884868) (xy 123.175268 -288.845244) (xy 123.177507 -288.835647) (xy 123.182969 -288.816711)
			(xy 123.18619 -288.807398) (xy 123.19381 -288.7853) (xy 122.990102 -288.43224) (xy 122.967242 -288.427922)
			(xy 122.942297 -288.422786) (xy 122.894263 -288.405867) (xy 122.849393 -288.381779) (xy 122.808749 -288.351091)
			(xy 122.773296 -288.314532) (xy 122.743871 -288.272965) (xy 122.721172 -288.227376) (xy 122.705736 -288.178845)
			(xy 122.697929 -288.12852) (xy 122.697494 -288.103056) (xy 122.698003 -288.077089) (xy 122.706128 -288.025794)
			(xy 122.722176 -287.976401) (xy 122.745754 -287.930127) (xy 122.77628 -287.888111) (xy 122.813003 -287.851388)
			(xy 122.855019 -287.820862) (xy 122.901293 -287.797284) (xy 122.950686 -287.781236) (xy 123.001981 -287.773111)
			(xy 123.053915 -287.773111) (xy 123.10521 -287.781236) (xy 123.154603 -287.797284) (xy 123.200877 -287.820862)
			(xy 123.242893 -287.851388) (xy 123.279616 -287.888111) (xy 123.310142 -287.930127) (xy 123.33372 -287.976401)
			(xy 123.349768 -288.025794) (xy 123.357893 -288.077089) (xy 123.358402 -288.103056) (xy 123.357793 -288.131037)
			(xy 123.348348 -288.186197) (xy 123.339606 -288.212784) (xy 123.331986 -288.234628) (xy 123.535948 -288.587942)
			(xy 123.558808 -288.59226) (xy 123.585781 -288.597879) (xy 123.637496 -288.616877) (xy 123.685344 -288.644189)
			(xy 123.727998 -288.679059) (xy 123.764278 -288.720521) (xy 123.793178 -288.767427) (xy 123.813897 -288.818477)
			(xy 123.820428 -288.845244) (xy 123.829318 -288.884868) (xy 124.106178 -288.884868) (xy 124.115068 -288.845244)
			(xy 124.121282 -288.819694) (xy 124.1407 -288.770831) (xy 124.16761 -288.725659) (xy 124.201332 -288.685317)
			(xy 124.241017 -288.650824) (xy 124.285663 -288.62305) (xy 124.334143 -288.602695) (xy 124.385234 -288.590272)
			(xy 124.437648 -288.586097) (xy 124.490062 -288.590272) (xy 124.541153 -288.602695) (xy 124.589633 -288.62305)
			(xy 124.634279 -288.650824) (xy 124.673964 -288.685317) (xy 124.707686 -288.725659) (xy 124.734596 -288.770831)
			(xy 124.754014 -288.819694) (xy 124.760228 -288.845244) (xy 124.769118 -288.884868) (xy 125.045978 -288.884868)
			(xy 125.054868 -288.845244) (xy 125.057107 -288.835647) (xy 125.062569 -288.816711) (xy 125.06579 -288.807398)
			(xy 125.07341 -288.7853) (xy 124.869702 -288.43224) (xy 124.846842 -288.427922) (xy 124.821897 -288.422786)
			(xy 124.773863 -288.405867) (xy 124.728993 -288.381779) (xy 124.688349 -288.351091) (xy 124.652896 -288.314532)
			(xy 124.623471 -288.272965) (xy 124.600772 -288.227376) (xy 124.585336 -288.178845) (xy 124.577529 -288.12852)
			(xy 124.577094 -288.103056) (xy 124.577603 -288.077089) (xy 124.585728 -288.025794) (xy 124.601776 -287.976401)
			(xy 124.625354 -287.930127) (xy 124.65588 -287.888111) (xy 124.692603 -287.851388) (xy 124.734619 -287.820862)
			(xy 124.780893 -287.797284) (xy 124.830286 -287.781236) (xy 124.881581 -287.773111) (xy 124.933515 -287.773111)
			(xy 124.98481 -287.781236) (xy 125.034203 -287.797284) (xy 125.080477 -287.820862) (xy 125.122493 -287.851388)
			(xy 125.159216 -287.888111) (xy 125.189742 -287.930127) (xy 125.21332 -287.976401) (xy 125.229368 -288.025794)
			(xy 125.237493 -288.077089) (xy 125.238002 -288.103056) (xy 125.237393 -288.131037) (xy 125.227948 -288.186197)
			(xy 125.219206 -288.212784) (xy 125.211586 -288.234628) (xy 125.415548 -288.587942) (xy 125.438408 -288.59226)
			(xy 125.465381 -288.597879) (xy 125.517096 -288.616877) (xy 125.564944 -288.644189) (xy 125.607598 -288.679059)
			(xy 125.643878 -288.720521) (xy 125.672778 -288.767427) (xy 125.693497 -288.818477) (xy 125.700028 -288.845244)
			(xy 125.708918 -288.884868) (xy 125.985778 -288.884868) (xy 125.994668 -288.845244) (xy 126.000882 -288.819694)
			(xy 126.0203 -288.770831) (xy 126.04721 -288.725659) (xy 126.080932 -288.685317) (xy 126.120617 -288.650824)
			(xy 126.165263 -288.62305) (xy 126.213743 -288.602695) (xy 126.264834 -288.590272) (xy 126.317248 -288.586097)
			(xy 126.369662 -288.590272) (xy 126.420753 -288.602695) (xy 126.469233 -288.62305) (xy 126.513879 -288.650824)
			(xy 126.553564 -288.685317) (xy 126.587286 -288.725659) (xy 126.614196 -288.770831) (xy 126.633614 -288.819694)
			(xy 126.639828 -288.845244) (xy 126.648718 -288.884868) (xy 126.925578 -288.884868) (xy 126.934468 -288.845244)
			(xy 126.936707 -288.835647) (xy 126.942169 -288.816711) (xy 126.94539 -288.807398) (xy 126.95301 -288.7853)
			(xy 126.749302 -288.43224) (xy 126.726442 -288.427922) (xy 126.701497 -288.422786) (xy 126.653463 -288.405867)
			(xy 126.608593 -288.381779) (xy 126.567949 -288.351091) (xy 126.532496 -288.314532) (xy 126.503071 -288.272965)
			(xy 126.480372 -288.227376) (xy 126.464936 -288.178845) (xy 126.457129 -288.12852) (xy 126.456694 -288.103056)
			(xy 126.457203 -288.077089) (xy 126.465328 -288.025794) (xy 126.481376 -287.976401) (xy 126.504954 -287.930127)
			(xy 126.53548 -287.888111) (xy 126.572203 -287.851388) (xy 126.614219 -287.820862) (xy 126.660493 -287.797284)
			(xy 126.709886 -287.781236) (xy 126.761181 -287.773111) (xy 126.813115 -287.773111) (xy 126.86441 -287.781236)
			(xy 126.913803 -287.797284) (xy 126.960077 -287.820862) (xy 127.002093 -287.851388) (xy 127.038816 -287.888111)
			(xy 127.069342 -287.930127) (xy 127.09292 -287.976401) (xy 127.108968 -288.025794) (xy 127.117093 -288.077089)
			(xy 127.117602 -288.103056) (xy 127.116993 -288.131037) (xy 127.107548 -288.186197) (xy 127.098806 -288.212784)
			(xy 127.091186 -288.234628) (xy 127.295148 -288.587942) (xy 127.318008 -288.59226) (xy 127.344981 -288.597879)
			(xy 127.396696 -288.616877) (xy 127.444544 -288.644189) (xy 127.487198 -288.679059) (xy 127.523478 -288.720521)
			(xy 127.552378 -288.767427) (xy 127.573097 -288.818477) (xy 127.579628 -288.845244) (xy 127.588518 -288.884868)
			(xy 127.865378 -288.884868) (xy 127.874268 -288.845244) (xy 127.880482 -288.819694) (xy 127.8999 -288.770831)
			(xy 127.92681 -288.725659) (xy 127.960532 -288.685317) (xy 128.000217 -288.650824) (xy 128.044863 -288.62305)
			(xy 128.093343 -288.602695) (xy 128.144434 -288.590272) (xy 128.196848 -288.586097) (xy 128.249262 -288.590272)
			(xy 128.300353 -288.602695) (xy 128.348833 -288.62305) (xy 128.393479 -288.650824) (xy 128.433164 -288.685317)
			(xy 128.466886 -288.725659) (xy 128.493796 -288.770831) (xy 128.513214 -288.819694) (xy 128.519428 -288.845244)
			(xy 128.528318 -288.884868) (xy 128.805178 -288.884868) (xy 128.814068 -288.845244) (xy 128.816307 -288.835647)
			(xy 128.821769 -288.816711) (xy 128.82499 -288.807398) (xy 128.83261 -288.7853) (xy 128.628902 -288.43224)
			(xy 128.606042 -288.427922) (xy 128.581097 -288.422786) (xy 128.533063 -288.405867) (xy 128.488193 -288.381779)
			(xy 128.447549 -288.351091) (xy 128.412096 -288.314532) (xy 128.382671 -288.272965) (xy 128.359972 -288.227376)
			(xy 128.344536 -288.178845) (xy 128.336729 -288.12852) (xy 128.336294 -288.103056) (xy 128.336803 -288.077089)
			(xy 128.344928 -288.025794) (xy 128.360976 -287.976401) (xy 128.384554 -287.930127) (xy 128.41508 -287.888111)
			(xy 128.451803 -287.851388) (xy 128.493819 -287.820862) (xy 128.540093 -287.797284) (xy 128.589486 -287.781236)
			(xy 128.640781 -287.773111) (xy 128.692715 -287.773111) (xy 128.74401 -287.781236) (xy 128.793403 -287.797284)
			(xy 128.839677 -287.820862) (xy 128.881693 -287.851388) (xy 128.918416 -287.888111) (xy 128.948942 -287.930127)
			(xy 128.97252 -287.976401) (xy 128.988568 -288.025794) (xy 128.996693 -288.077089) (xy 128.997202 -288.103056)
			(xy 128.996593 -288.131037) (xy 128.987148 -288.186197) (xy 128.978406 -288.212784) (xy 128.970786 -288.234628)
			(xy 129.174748 -288.587942) (xy 129.197608 -288.59226) (xy 129.224581 -288.597879) (xy 129.276296 -288.616877)
			(xy 129.324144 -288.644189) (xy 129.366798 -288.679059) (xy 129.403078 -288.720521) (xy 129.431978 -288.767427)
			(xy 129.452697 -288.818477) (xy 129.459228 -288.845244) (xy 129.468118 -288.884868) (xy 129.744978 -288.884868)
			(xy 129.753868 -288.845244) (xy 129.760082 -288.819694) (xy 129.7795 -288.770831) (xy 129.80641 -288.725659)
			(xy 129.840132 -288.685317) (xy 129.879817 -288.650824) (xy 129.924463 -288.62305) (xy 129.972943 -288.602695)
			(xy 130.024034 -288.590272) (xy 130.076448 -288.586097) (xy 130.128862 -288.590272) (xy 130.179953 -288.602695)
			(xy 130.228433 -288.62305) (xy 130.273079 -288.650824) (xy 130.312764 -288.685317) (xy 130.346486 -288.725659)
			(xy 130.373396 -288.770831) (xy 130.392814 -288.819694) (xy 130.399028 -288.845244) (xy 130.407918 -288.884868)
			(xy 130.684778 -288.884868) (xy 130.693668 -288.845244) (xy 130.695907 -288.835647) (xy 130.701369 -288.816711)
			(xy 130.70459 -288.807398) (xy 130.71221 -288.7853) (xy 130.508502 -288.43224) (xy 130.485642 -288.427922)
			(xy 130.460697 -288.422786) (xy 130.412663 -288.405867) (xy 130.367793 -288.381779) (xy 130.327149 -288.351091)
			(xy 130.291696 -288.314532) (xy 130.262271 -288.272965) (xy 130.239572 -288.227376) (xy 130.224136 -288.178845)
			(xy 130.216329 -288.12852) (xy 130.215894 -288.103056) (xy 130.216403 -288.077089) (xy 130.224528 -288.025794)
			(xy 130.240576 -287.976401) (xy 130.264154 -287.930127) (xy 130.29468 -287.888111) (xy 130.331403 -287.851388)
			(xy 130.373419 -287.820862) (xy 130.419693 -287.797284) (xy 130.469086 -287.781236) (xy 130.520381 -287.773111)
			(xy 130.572315 -287.773111) (xy 130.62361 -287.781236) (xy 130.673003 -287.797284) (xy 130.719277 -287.820862)
			(xy 130.761293 -287.851388) (xy 130.798016 -287.888111) (xy 130.828542 -287.930127) (xy 130.85212 -287.976401)
			(xy 130.868168 -288.025794) (xy 130.876293 -288.077089) (xy 130.876802 -288.103056) (xy 130.876193 -288.131037)
			(xy 130.866748 -288.186197) (xy 130.858006 -288.212784) (xy 130.850386 -288.234628) (xy 131.054348 -288.587942)
			(xy 131.077208 -288.59226) (xy 131.104181 -288.597879) (xy 131.155896 -288.616877) (xy 131.203744 -288.644189)
			(xy 131.246398 -288.679059) (xy 131.282678 -288.720521) (xy 131.311578 -288.767427) (xy 131.332297 -288.818477)
			(xy 131.338828 -288.845244) (xy 131.347718 -288.884868) (xy 131.624578 -288.884868) (xy 131.633468 -288.845244)
			(xy 131.639682 -288.819694) (xy 131.6591 -288.770831) (xy 131.68601 -288.725659) (xy 131.719732 -288.685317)
			(xy 131.759417 -288.650824) (xy 131.804063 -288.62305) (xy 131.852543 -288.602695) (xy 131.903634 -288.590272)
			(xy 131.956048 -288.586097) (xy 132.008462 -288.590272) (xy 132.059553 -288.602695) (xy 132.108033 -288.62305)
			(xy 132.152679 -288.650824) (xy 132.192364 -288.685317) (xy 132.226086 -288.725659) (xy 132.252996 -288.770831)
			(xy 132.272414 -288.819694) (xy 132.278628 -288.845244) (xy 132.287518 -288.884868) (xy 132.564378 -288.884868)
			(xy 132.573268 -288.845244) (xy 132.575507 -288.835647) (xy 132.580969 -288.816711) (xy 132.58419 -288.807398)
			(xy 132.59181 -288.7853) (xy 132.388102 -288.43224) (xy 132.365242 -288.427922) (xy 132.340297 -288.422786)
			(xy 132.292263 -288.405867) (xy 132.247393 -288.381779) (xy 132.206749 -288.351091) (xy 132.171296 -288.314532)
			(xy 132.141871 -288.272965) (xy 132.119172 -288.227376) (xy 132.103736 -288.178845) (xy 132.095929 -288.12852)
			(xy 132.095494 -288.103056) (xy 132.096003 -288.077089) (xy 132.104128 -288.025794) (xy 132.120176 -287.976401)
			(xy 132.143754 -287.930127) (xy 132.17428 -287.888111) (xy 132.211003 -287.851388) (xy 132.253019 -287.820862)
			(xy 132.299293 -287.797284) (xy 132.348686 -287.781236) (xy 132.399981 -287.773111) (xy 132.451915 -287.773111)
			(xy 132.50321 -287.781236) (xy 132.552603 -287.797284) (xy 132.598877 -287.820862) (xy 132.640893 -287.851388)
			(xy 132.677616 -287.888111) (xy 132.708142 -287.930127) (xy 132.73172 -287.976401) (xy 132.747768 -288.025794)
			(xy 132.755893 -288.077089) (xy 132.756402 -288.103056) (xy 132.755837 -288.129023) (xy 133.975349 -288.129023)
			(xy 133.975349 -288.077089) (xy 133.983474 -288.025794) (xy 133.999522 -287.976401) (xy 134.0231 -287.930127)
			(xy 134.053626 -287.888111) (xy 134.090349 -287.851388) (xy 134.132365 -287.820862) (xy 134.178639 -287.797284)
			(xy 134.228032 -287.781236) (xy 134.279327 -287.773111) (xy 134.331261 -287.773111) (xy 134.382556 -287.781236)
			(xy 134.431949 -287.797284) (xy 134.478223 -287.820862) (xy 134.520239 -287.851388) (xy 134.556962 -287.888111)
			(xy 134.587488 -287.930127) (xy 134.611066 -287.976401) (xy 134.627114 -288.025794) (xy 134.635239 -288.077089)
			(xy 134.635748 -288.103056) (xy 134.635239 -288.129023) (xy 134.627114 -288.180318) (xy 134.611066 -288.229711)
			(xy 134.587488 -288.275985) (xy 134.556962 -288.318001) (xy 134.520239 -288.354724) (xy 134.478223 -288.38525)
			(xy 134.431949 -288.408828) (xy 134.382556 -288.424876) (xy 134.331261 -288.433001) (xy 134.279327 -288.433001)
			(xy 134.228032 -288.424876) (xy 134.178639 -288.408828) (xy 134.132365 -288.38525) (xy 134.090349 -288.354724)
			(xy 134.053626 -288.318001) (xy 134.0231 -288.275985) (xy 133.999522 -288.229711) (xy 133.983474 -288.180318)
			(xy 133.975349 -288.129023) (xy 132.755837 -288.129023) (xy 132.755793 -288.131037) (xy 132.746348 -288.186197)
			(xy 132.737606 -288.212784) (xy 132.729986 -288.234628) (xy 132.933948 -288.587942) (xy 132.956808 -288.59226)
			(xy 132.983781 -288.597879) (xy 133.035496 -288.616877) (xy 133.083344 -288.644189) (xy 133.125998 -288.679059)
			(xy 133.162278 -288.720521) (xy 133.191178 -288.767427) (xy 133.211897 -288.818477) (xy 133.218428 -288.845244)
			(xy 133.227318 -288.884868) (xy 133.504178 -288.884868) (xy 133.513068 -288.845244) (xy 133.519282 -288.819694)
			(xy 133.5387 -288.770831) (xy 133.56561 -288.725659) (xy 133.599332 -288.685317) (xy 133.639017 -288.650824)
			(xy 133.683663 -288.62305) (xy 133.732143 -288.602695) (xy 133.783234 -288.590272) (xy 133.835648 -288.586097)
			(xy 133.888062 -288.590272) (xy 133.939153 -288.602695) (xy 133.987633 -288.62305) (xy 134.032279 -288.650824)
			(xy 134.071964 -288.685317) (xy 134.105686 -288.725659) (xy 134.132596 -288.770831) (xy 134.152014 -288.819694)
			(xy 134.158228 -288.845244) (xy 134.167118 -288.884868) (xy 134.29742 -288.884868) (xy 134.942834 -288.239454)
			(xy 134.93242 -288.209736) (xy 134.924214 -288.183834) (xy 134.915405 -288.130222) (xy 134.914894 -288.103056)
			(xy 134.91538 -288.07709) (xy 134.923511 -288.025799) (xy 134.939565 -287.976412) (xy 134.963148 -287.930144)
			(xy 134.993678 -287.888135) (xy 135.030405 -287.851419) (xy 135.072422 -287.8209) (xy 135.118697 -287.79733)
			(xy 135.168089 -287.781289) (xy 135.219382 -287.773173) (xy 135.245348 -287.772602) (xy 135.272515 -287.773108)
			(xy 135.326128 -287.781913) (xy 135.352028 -287.790128) (xy 135.381746 -287.800542) (xy 135.499094 -287.683194)
			(xy 135.508483 -287.673093) (xy 135.521975 -287.649055) (xy 135.528553 -287.622285) (xy 135.527738 -287.59473)
			(xy 135.519591 -287.568396) (xy 135.504703 -287.545196) (xy 135.494776 -287.53562) (xy 135.474413 -287.516652)
			(xy 135.439717 -287.473146) (xy 135.412799 -287.424444) (xy 135.394417 -287.371922) (xy 135.38509 -287.317063)
			(xy 135.38454 -287.28924) (xy 135.38502 -287.263268) (xy 135.39314 -287.211964) (xy 135.409186 -287.162562)
			(xy 135.432764 -287.116278) (xy 135.463291 -287.074253) (xy 135.500018 -287.037521) (xy 135.542039 -287.006988)
			(xy 135.588319 -286.983404) (xy 135.637719 -286.967351) (xy 135.689023 -286.959223) (xy 135.714994 -286.958786)
			(xy 135.73942 -286.95925) (xy 135.787736 -286.966477) (xy 135.834469 -286.980717) (xy 135.856726 -286.99079)
			(xy 135.87017 -286.996624) (xy 135.899116 -287.001132) (xy 135.928152 -286.997239) (xy 135.954888 -286.985264)
			(xy 135.977125 -286.966193) (xy 135.993033 -286.941593) (xy 136.001305 -286.91349) (xy 136.00176 -286.898842)
			(xy 136.00176 -286.750252) (xy 135.981197 -286.736008) (xy 135.944216 -286.702326) (xy 135.912733 -286.663456)
			(xy 135.887468 -286.620285) (xy 135.868999 -286.573799) (xy 135.857747 -286.525061) (xy 135.853969 -286.475183)
			(xy 135.857752 -286.425306) (xy 135.869009 -286.376569) (xy 135.887483 -286.330085) (xy 135.912752 -286.286916)
			(xy 135.944239 -286.248049) (xy 135.981224 -286.214372) (xy 136.00176 -286.200088) (xy 136.00176 -286.051498)
			(xy 136.001267 -286.03687) (xy 135.992953 -286.008819) (xy 135.977034 -285.984272) (xy 135.954814 -285.965239)
			(xy 135.928113 -285.953279) (xy 135.899119 -285.949371) (xy 135.870204 -285.953835) (xy 135.856726 -285.95955)
			(xy 135.834478 -285.969648) (xy 135.787747 -285.983902) (xy 135.739423 -285.9911) (xy 135.714994 -285.991554)
			(xy 135.689027 -285.991044) (xy 135.637733 -285.982919) (xy 135.588341 -285.96687) (xy 135.542068 -285.943292)
			(xy 135.500053 -285.912766) (xy 135.46333 -285.876043) (xy 135.432805 -285.834027) (xy 135.409228 -285.787753)
			(xy 135.393179 -285.738361) (xy 135.385055 -285.687067) (xy 135.385055 -285.635133) (xy 135.393179 -285.583839)
			(xy 135.409228 -285.534447) (xy 135.432805 -285.488173) (xy 135.46333 -285.446157) (xy 135.500053 -285.409434)
			(xy 135.542068 -285.378908) (xy 135.588341 -285.35533) (xy 135.637733 -285.339281) (xy 135.689027 -285.331156)
			(xy 135.714994 -285.330646) (xy 135.73942 -285.331111) (xy 135.787736 -285.338339) (xy 135.834467 -285.352581)
			(xy 135.856726 -285.36265) (xy 135.870173 -285.368482) (xy 135.899123 -285.372987) (xy 135.928162 -285.369093)
			(xy 135.954902 -285.35712) (xy 135.977146 -285.338051) (xy 135.993066 -285.313454) (xy 136.001352 -285.285352)
			(xy 136.00176 -285.270702) (xy 136.00176 -285.122366) (xy 135.981196 -285.108121) (xy 135.944213 -285.07444)
			(xy 135.912728 -285.035569) (xy 135.887461 -284.992397) (xy 135.86899 -284.94591) (xy 135.857737 -284.89717)
			(xy 135.853957 -284.847291) (xy 135.857739 -284.797412) (xy 135.868995 -284.748673) (xy 135.887469 -284.702187)
			(xy 135.912738 -284.659016) (xy 135.944225 -284.620147) (xy 135.98121 -284.586468) (xy 136.00176 -284.572202)
			(xy 136.00176 -283.992828) (xy 135.71728 -283.708348) (xy 135.144764 -283.708348) (xy 135.131307 -283.708753)
			(xy 135.105325 -283.715774) (xy 135.082083 -283.729345) (xy 135.063198 -283.74852) (xy 135.049984 -283.771967)
			(xy 135.043361 -283.798053) (xy 135.043789 -283.824963) (xy 135.051238 -283.850826) (xy 135.057896 -283.862526)
			(xy 135.072875 -283.888543) (xy 135.094175 -283.944665) (xy 135.105 -284.003708) (xy 135.105648 -284.033722)
			(xy 135.105139 -284.059689) (xy 135.097014 -284.110984) (xy 135.080966 -284.160377) (xy 135.057388 -284.206651)
			(xy 135.026862 -284.248667) (xy 134.990139 -284.28539) (xy 134.948123 -284.315916) (xy 134.901849 -284.339494)
			(xy 134.852456 -284.355542) (xy 134.801161 -284.363667) (xy 134.749227 -284.363667) (xy 134.697932 -284.355542)
			(xy 134.648539 -284.339494) (xy 134.602265 -284.315916) (xy 134.560249 -284.28539) (xy 134.523526 -284.248667)
			(xy 134.493 -284.206651) (xy 134.469422 -284.160377) (xy 134.453374 -284.110984) (xy 134.445249 -284.059689)
			(xy 134.44474 -284.033722) (xy 134.445254 -284.007959) (xy 134.45329 -283.957063) (xy 134.469123 -283.908029)
			(xy 134.492371 -283.862044) (xy 134.52247 -283.820223) (xy 134.540244 -283.801566) (xy 134.57555 -283.765498)
			(xy 134.35711 -283.547058) (xy 134.333742 -283.54909) (xy 134.305548 -283.55036) (xy 134.279576 -283.549881)
			(xy 134.228271 -283.541762) (xy 134.178867 -283.525716) (xy 134.132583 -283.502139) (xy 134.090556 -283.471611)
			(xy 134.053824 -283.434885) (xy 134.023289 -283.392863) (xy 133.999705 -283.346583) (xy 133.983651 -283.297182)
			(xy 133.975523 -283.245878) (xy 133.975094 -283.219906) (xy 133.976364 -283.191712) (xy 133.978396 -283.168344)
			(xy 133.348222 -282.53817) (xy 133.338349 -282.528877) (xy 133.314827 -282.515409) (xy 133.288586 -282.508618)
			(xy 133.261484 -282.508984) (xy 133.235437 -282.516482) (xy 133.212287 -282.53058) (xy 133.193673 -282.550282)
			(xy 133.186932 -282.562046) (xy 133.174461 -282.584263) (xy 133.143748 -282.624914) (xy 133.107164 -282.660373)
			(xy 133.065576 -282.689802) (xy 133.019966 -282.712506) (xy 132.971414 -282.727947) (xy 132.921068 -282.735759)
			(xy 132.895594 -282.73629) (xy 132.869626 -282.73578) (xy 132.81833 -282.727655) (xy 132.768936 -282.711607)
			(xy 132.72266 -282.688029) (xy 132.680642 -282.657504) (xy 132.643916 -282.620781) (xy 132.613386 -282.578766)
			(xy 132.589805 -282.532492) (xy 132.573752 -282.4831) (xy 132.565622 -282.431804) (xy 132.56514 -282.405836)
			(xy 132.565182 -282.396482) (xy 132.566196 -282.377801) (xy 132.567172 -282.368498) (xy 132.568296 -282.354266)
			(xy 132.563527 -282.326131) (xy 132.551161 -282.300413) (xy 132.532162 -282.279121) (xy 132.508014 -282.263916)
			(xy 132.480602 -282.255985) (xy 132.466334 -282.255468) (xy 132.385054 -282.255468) (xy 132.370777 -282.255943)
			(xy 132.34334 -282.263847) (xy 132.31917 -282.279048) (xy 132.300163 -282.300356) (xy 132.28781 -282.326099)
			(xy 132.283081 -282.354258) (xy 132.284216 -282.368498) (xy 132.285184 -282.377802) (xy 132.286198 -282.396482)
			(xy 132.286248 -282.405836) (xy 132.285739 -282.431803) (xy 132.277614 -282.483098) (xy 132.261566 -282.532491)
			(xy 132.237988 -282.578765) (xy 132.207462 -282.620781) (xy 132.170739 -282.657504) (xy 132.128723 -282.68803)
			(xy 132.082449 -282.711608) (xy 132.033056 -282.727656) (xy 131.981761 -282.735781) (xy 131.929827 -282.735781)
			(xy 131.878532 -282.727656) (xy 131.829139 -282.711608) (xy 131.782865 -282.68803) (xy 131.740849 -282.657504)
			(xy 131.704126 -282.620781) (xy 131.6736 -282.578765) (xy 131.650022 -282.532491) (xy 131.633974 -282.483098)
			(xy 131.625849 -282.431803) (xy 131.62534 -282.405836) (xy 131.625382 -282.396482) (xy 131.626396 -282.377801)
			(xy 131.627372 -282.368498) (xy 131.628496 -282.354266) (xy 131.623727 -282.326131) (xy 131.611361 -282.300413)
			(xy 131.592362 -282.279121) (xy 131.568214 -282.263916) (xy 131.540802 -282.255985) (xy 131.526534 -282.255468)
			(xy 131.445254 -282.255468) (xy 131.430977 -282.255943) (xy 131.40354 -282.263847) (xy 131.37937 -282.279048)
			(xy 131.360363 -282.300356) (xy 131.34801 -282.326099) (xy 131.343281 -282.354258) (xy 131.344416 -282.368498)
			(xy 131.345384 -282.377802) (xy 131.346398 -282.396482) (xy 131.346448 -282.405836) (xy 131.345939 -282.431803)
			(xy 131.337814 -282.483098) (xy 131.321766 -282.532491) (xy 131.298188 -282.578765) (xy 131.267662 -282.620781)
			(xy 131.230939 -282.657504) (xy 131.188923 -282.68803) (xy 131.142649 -282.711608) (xy 131.093256 -282.727656)
			(xy 131.041961 -282.735781) (xy 130.990027 -282.735781) (xy 130.938732 -282.727656) (xy 130.889339 -282.711608)
			(xy 130.843065 -282.68803) (xy 130.801049 -282.657504) (xy 130.764326 -282.620781) (xy 130.7338 -282.578765)
			(xy 130.710222 -282.532491) (xy 130.694174 -282.483098) (xy 130.686049 -282.431803) (xy 130.68554 -282.405836)
			(xy 130.685582 -282.396482) (xy 130.686596 -282.377801) (xy 130.687572 -282.368498) (xy 130.688696 -282.354266)
			(xy 130.683927 -282.326131) (xy 130.671561 -282.300413) (xy 130.652562 -282.279121) (xy 130.628414 -282.263916)
			(xy 130.601002 -282.255985) (xy 130.586734 -282.255468) (xy 130.505708 -282.255468) (xy 130.491426 -282.255937)
			(xy 130.463975 -282.263831) (xy 130.439792 -282.27903) (xy 130.420773 -282.30034) (xy 130.408413 -282.326091)
			(xy 130.403681 -282.354259) (xy 130.40487 -282.368498) (xy 130.405832 -282.377739) (xy 130.406846 -282.396292)
			(xy 130.406902 -282.405582) (xy 130.406393 -282.431549) (xy 130.398268 -282.482844) (xy 130.38222 -282.532237)
			(xy 130.358642 -282.578511) (xy 130.328116 -282.620527) (xy 130.291393 -282.65725) (xy 130.249377 -282.687776)
			(xy 130.203103 -282.711354) (xy 130.15371 -282.727402) (xy 130.102415 -282.735527) (xy 130.050481 -282.735527)
			(xy 129.999186 -282.727402) (xy 129.949793 -282.711354) (xy 129.903519 -282.687776) (xy 129.861503 -282.65725)
			(xy 129.82478 -282.620527) (xy 129.794254 -282.578511) (xy 129.770676 -282.532237) (xy 129.754628 -282.482844)
			(xy 129.746503 -282.431549) (xy 129.745994 -282.405582) (xy 129.746045 -282.396292) (xy 129.747063 -282.377739)
			(xy 129.748026 -282.368498) (xy 129.74915 -282.354264) (xy 129.744381 -282.326123) (xy 129.732016 -282.300399)
			(xy 129.713019 -282.279099) (xy 129.688871 -282.263883) (xy 129.661458 -282.255938) (xy 129.647188 -282.255468)
			(xy 129.565908 -282.255468) (xy 129.551626 -282.255937) (xy 129.524175 -282.263831) (xy 129.499992 -282.27903)
			(xy 129.480973 -282.30034) (xy 129.468613 -282.326091) (xy 129.463881 -282.354259) (xy 129.46507 -282.368498)
			(xy 129.466032 -282.377739) (xy 129.467046 -282.396292) (xy 129.467102 -282.405582) (xy 129.466593 -282.431549)
			(xy 129.458468 -282.482844) (xy 129.44242 -282.532237) (xy 129.418842 -282.578511) (xy 129.388316 -282.620527)
			(xy 129.351593 -282.65725) (xy 129.309577 -282.687776) (xy 129.263303 -282.711354) (xy 129.21391 -282.727402)
			(xy 129.162615 -282.735527) (xy 129.110681 -282.735527) (xy 129.059386 -282.727402) (xy 129.009993 -282.711354)
			(xy 128.963719 -282.687776) (xy 128.921703 -282.65725) (xy 128.88498 -282.620527) (xy 128.854454 -282.578511)
			(xy 128.830876 -282.532237) (xy 128.814828 -282.482844) (xy 128.806703 -282.431549) (xy 128.806194 -282.405582)
			(xy 128.806245 -282.396292) (xy 128.807263 -282.377739) (xy 128.808226 -282.368498) (xy 128.80935 -282.354264)
			(xy 128.804581 -282.326123) (xy 128.792216 -282.300399) (xy 128.773219 -282.279099) (xy 128.749071 -282.263883)
			(xy 128.721658 -282.255938) (xy 128.707388 -282.255468) (xy 128.626108 -282.255468) (xy 128.611826 -282.255937)
			(xy 128.584375 -282.263831) (xy 128.560192 -282.27903) (xy 128.541173 -282.30034) (xy 128.528813 -282.326091)
			(xy 128.524081 -282.354259) (xy 128.52527 -282.368498) (xy 128.526232 -282.377739) (xy 128.527246 -282.396292)
			(xy 128.527302 -282.405582) (xy 128.526793 -282.431549) (xy 128.518668 -282.482844) (xy 128.50262 -282.532237)
			(xy 128.479042 -282.578511) (xy 128.448516 -282.620527) (xy 128.411793 -282.65725) (xy 128.369777 -282.687776)
			(xy 128.323503 -282.711354) (xy 128.27411 -282.727402) (xy 128.222815 -282.735527) (xy 128.170881 -282.735527)
			(xy 128.119586 -282.727402) (xy 128.070193 -282.711354) (xy 128.023919 -282.687776) (xy 127.981903 -282.65725)
			(xy 127.94518 -282.620527) (xy 127.914654 -282.578511) (xy 127.891076 -282.532237) (xy 127.875028 -282.482844)
			(xy 127.866903 -282.431549) (xy 127.866394 -282.405582) (xy 127.866445 -282.396292) (xy 127.867463 -282.377739)
			(xy 127.868426 -282.368498) (xy 127.86955 -282.354264) (xy 127.864781 -282.326123) (xy 127.852416 -282.300399)
			(xy 127.833419 -282.279099) (xy 127.809271 -282.263883) (xy 127.781858 -282.255938) (xy 127.767588 -282.255468)
			(xy 127.686308 -282.255468) (xy 127.672026 -282.255937) (xy 127.644575 -282.263831) (xy 127.620392 -282.27903)
			(xy 127.601373 -282.30034) (xy 127.589013 -282.326091) (xy 127.584281 -282.354259) (xy 127.58547 -282.368498)
			(xy 127.586432 -282.377739) (xy 127.587446 -282.396292) (xy 127.587502 -282.405582) (xy 127.586993 -282.431549)
			(xy 127.578868 -282.482844) (xy 127.56282 -282.532237) (xy 127.539242 -282.578511) (xy 127.508716 -282.620527)
			(xy 127.471993 -282.65725) (xy 127.429977 -282.687776) (xy 127.383703 -282.711354) (xy 127.33431 -282.727402)
			(xy 127.283015 -282.735527) (xy 127.231081 -282.735527) (xy 127.179786 -282.727402) (xy 127.130393 -282.711354)
			(xy 127.084119 -282.687776) (xy 127.042103 -282.65725) (xy 127.00538 -282.620527) (xy 126.974854 -282.578511)
			(xy 126.951276 -282.532237) (xy 126.935228 -282.482844) (xy 126.927103 -282.431549) (xy 126.926594 -282.405582)
			(xy 126.926645 -282.396292) (xy 126.927663 -282.377739) (xy 126.928626 -282.368498) (xy 126.92975 -282.354264)
			(xy 126.924981 -282.326123) (xy 126.912616 -282.300399) (xy 126.893619 -282.279099) (xy 126.869471 -282.263883)
			(xy 126.842058 -282.255938) (xy 126.827788 -282.255468) (xy 126.746508 -282.255468) (xy 126.732226 -282.255937)
			(xy 126.704775 -282.263831) (xy 126.680592 -282.27903) (xy 126.661573 -282.30034) (xy 126.649213 -282.326091)
			(xy 126.644481 -282.354259) (xy 126.64567 -282.368498) (xy 126.646638 -282.377802) (xy 126.647652 -282.396482)
			(xy 126.647702 -282.405836) (xy 126.647193 -282.431803) (xy 126.639068 -282.483098) (xy 126.62302 -282.532491)
			(xy 126.599442 -282.578765) (xy 126.568916 -282.620781) (xy 126.532193 -282.657504) (xy 126.490177 -282.68803)
			(xy 126.443903 -282.711608) (xy 126.39451 -282.727656) (xy 126.343215 -282.735781) (xy 126.291281 -282.735781)
			(xy 126.239986 -282.727656) (xy 126.190593 -282.711608) (xy 126.144319 -282.68803) (xy 126.102303 -282.657504)
			(xy 126.06558 -282.620781) (xy 126.035054 -282.578765) (xy 126.011476 -282.532491) (xy 125.995428 -282.483098)
			(xy 125.987303 -282.431803) (xy 125.986794 -282.405836) (xy 125.986836 -282.396482) (xy 125.98785 -282.377801)
			(xy 125.988826 -282.368498) (xy 125.98995 -282.354264) (xy 125.985181 -282.326123) (xy 125.972816 -282.300399)
			(xy 125.953819 -282.279099) (xy 125.929671 -282.263883) (xy 125.902258 -282.255938) (xy 125.887988 -282.255468)
			(xy 125.806454 -282.255468) (xy 125.792177 -282.255943) (xy 125.76474 -282.263847) (xy 125.74057 -282.279048)
			(xy 125.721563 -282.300356) (xy 125.70921 -282.326099) (xy 125.704481 -282.354258) (xy 125.705616 -282.368498)
			(xy 125.706584 -282.377802) (xy 125.707598 -282.396482) (xy 125.707648 -282.405836) (xy 125.707139 -282.431803)
			(xy 125.699014 -282.483098) (xy 125.682966 -282.532491) (xy 125.659388 -282.578765) (xy 125.628862 -282.620781)
			(xy 125.592139 -282.657504) (xy 125.550123 -282.68803) (xy 125.503849 -282.711608) (xy 125.454456 -282.727656)
			(xy 125.403161 -282.735781) (xy 125.351227 -282.735781) (xy 125.299932 -282.727656) (xy 125.250539 -282.711608)
			(xy 125.204265 -282.68803) (xy 125.162249 -282.657504) (xy 125.125526 -282.620781) (xy 125.095 -282.578765)
			(xy 125.071422 -282.532491) (xy 125.055374 -282.483098) (xy 125.047249 -282.431803) (xy 125.04674 -282.405836)
			(xy 125.046782 -282.396482) (xy 125.047796 -282.377801) (xy 125.048772 -282.368498) (xy 125.049896 -282.354266)
			(xy 125.045127 -282.326131) (xy 125.032761 -282.300413) (xy 125.013762 -282.279121) (xy 124.989614 -282.263916)
			(xy 124.962202 -282.255985) (xy 124.947934 -282.255468) (xy 124.866654 -282.255468) (xy 124.852377 -282.255943)
			(xy 124.82494 -282.263847) (xy 124.80077 -282.279048) (xy 124.781763 -282.300356) (xy 124.76941 -282.326099)
			(xy 124.764681 -282.354258) (xy 124.765816 -282.368498) (xy 124.766784 -282.377802) (xy 124.767798 -282.396482)
			(xy 124.767848 -282.405836) (xy 124.767339 -282.431803) (xy 124.759214 -282.483098) (xy 124.743166 -282.532491)
			(xy 124.719588 -282.578765) (xy 124.689062 -282.620781) (xy 124.652339 -282.657504) (xy 124.610323 -282.68803)
			(xy 124.564049 -282.711608) (xy 124.514656 -282.727656) (xy 124.463361 -282.735781) (xy 124.411427 -282.735781)
			(xy 124.360132 -282.727656) (xy 124.310739 -282.711608) (xy 124.264465 -282.68803) (xy 124.222449 -282.657504)
			(xy 124.185726 -282.620781) (xy 124.1552 -282.578765) (xy 124.131622 -282.532491) (xy 124.115574 -282.483098)
			(xy 124.107449 -282.431803) (xy 124.10694 -282.405836) (xy 124.106982 -282.396482) (xy 124.107996 -282.377801)
			(xy 124.108972 -282.368498) (xy 124.110096 -282.354266) (xy 124.105327 -282.326131) (xy 124.092961 -282.300413)
			(xy 124.073962 -282.279121) (xy 124.049814 -282.263916) (xy 124.022402 -282.255985) (xy 124.008134 -282.255468)
			(xy 123.926854 -282.255468) (xy 123.912577 -282.255943) (xy 123.88514 -282.263847) (xy 123.86097 -282.279048)
			(xy 123.841963 -282.300356) (xy 123.82961 -282.326099) (xy 123.824881 -282.354258) (xy 123.826016 -282.368498)
			(xy 123.826984 -282.377802) (xy 123.827998 -282.396482) (xy 123.828048 -282.405836) (xy 123.827536 -282.431801)
			(xy 123.819407 -282.483092) (xy 123.803355 -282.532479) (xy 123.779776 -282.578747) (xy 123.749249 -282.620758)
			(xy 123.712526 -282.657476) (xy 123.670512 -282.687998) (xy 123.62424 -282.711571) (xy 123.574851 -282.727617)
			(xy 123.523559 -282.735739) (xy 123.497594 -282.73629) (xy 123.473 -282.735837) (xy 123.424356 -282.728544)
			(xy 123.377331 -282.714119) (xy 123.332965 -282.692882) (xy 123.292237 -282.665302) (xy 123.256048 -282.631989)
			(xy 123.240292 -282.6131) (xy 123.230985 -282.602345) (xy 123.207707 -282.586021) (xy 123.180834 -282.576737)
			(xy 123.152444 -282.57521) (xy 123.124731 -282.581558) (xy 123.099837 -282.595291) (xy 123.089416 -282.604972)
			(xy 122.97791 -282.716478) (xy 122.967873 -282.727194) (xy 122.953864 -282.752984) (xy 122.947755 -282.78169)
			(xy 122.950052 -282.810949) (xy 122.960564 -282.838351) (xy 122.978426 -282.861638) (xy 123.002166 -282.878894)
			(xy 123.02983 -282.888696) (xy 123.044458 -282.88996) (xy 123.069539 -282.891688) (xy 123.118789 -282.90178)
			(xy 123.165943 -282.919214) (xy 123.209913 -282.943586) (xy 123.249685 -282.974336) (xy 123.284342 -283.010754)
			(xy 123.313085 -283.051999) (xy 123.335251 -283.097122) (xy 123.350329 -283.145081) (xy 123.357971 -283.19477)
			(xy 123.358402 -283.219906) (xy 123.357892 -283.245873) (xy 124.577603 -283.245873) (xy 124.577603 -283.193939)
			(xy 124.585728 -283.142644) (xy 124.601776 -283.093251) (xy 124.625354 -283.046977) (xy 124.65588 -283.004961)
			(xy 124.692603 -282.968238) (xy 124.734619 -282.937712) (xy 124.780893 -282.914134) (xy 124.830286 -282.898086)
			(xy 124.881581 -282.889961) (xy 124.933515 -282.889961) (xy 124.98481 -282.898086) (xy 125.034203 -282.914134)
			(xy 125.080477 -282.937712) (xy 125.122493 -282.968238) (xy 125.159216 -283.004961) (xy 125.189742 -283.046977)
			(xy 125.21332 -283.093251) (xy 125.229368 -283.142644) (xy 125.237493 -283.193939) (xy 125.238002 -283.219906)
			(xy 125.237493 -283.245873) (xy 125.517403 -283.245873) (xy 125.517403 -283.193939) (xy 125.525528 -283.142644)
			(xy 125.541576 -283.093251) (xy 125.565154 -283.046977) (xy 125.59568 -283.004961) (xy 125.632403 -282.968238)
			(xy 125.674419 -282.937712) (xy 125.720693 -282.914134) (xy 125.770086 -282.898086) (xy 125.821381 -282.889961)
			(xy 125.873315 -282.889961) (xy 125.92461 -282.898086) (xy 125.974003 -282.914134) (xy 126.020277 -282.937712)
			(xy 126.062293 -282.968238) (xy 126.099016 -283.004961) (xy 126.129542 -283.046977) (xy 126.15312 -283.093251)
			(xy 126.169168 -283.142644) (xy 126.177293 -283.193939) (xy 126.177802 -283.219906) (xy 126.177293 -283.245873)
			(xy 126.456949 -283.245873) (xy 126.456949 -283.193939) (xy 126.465074 -283.142644) (xy 126.481122 -283.093251)
			(xy 126.5047 -283.046977) (xy 126.535226 -283.004961) (xy 126.571949 -282.968238) (xy 126.613965 -282.937712)
			(xy 126.660239 -282.914134) (xy 126.709632 -282.898086) (xy 126.760927 -282.889961) (xy 126.812861 -282.889961)
			(xy 126.864156 -282.898086) (xy 126.913549 -282.914134) (xy 126.959823 -282.937712) (xy 127.001839 -282.968238)
			(xy 127.038562 -283.004961) (xy 127.069088 -283.046977) (xy 127.092666 -283.093251) (xy 127.108714 -283.142644)
			(xy 127.116839 -283.193939) (xy 127.117348 -283.219906) (xy 127.116844 -283.245619) (xy 128.336549 -283.245619)
			(xy 128.336549 -283.193685) (xy 128.344674 -283.14239) (xy 128.360722 -283.092997) (xy 128.3843 -283.046723)
			(xy 128.414826 -283.004707) (xy 128.451549 -282.967984) (xy 128.493565 -282.937458) (xy 128.539839 -282.91388)
			(xy 128.589232 -282.897832) (xy 128.640527 -282.889707) (xy 128.692461 -282.889707) (xy 128.743756 -282.897832)
			(xy 128.793149 -282.91388) (xy 128.839423 -282.937458) (xy 128.881439 -282.967984) (xy 128.918162 -283.004707)
			(xy 128.948688 -283.046723) (xy 128.972266 -283.092997) (xy 128.988314 -283.14239) (xy 128.996439 -283.193685)
			(xy 128.996948 -283.219652) (xy 128.996439 -283.245619) (xy 128.996399 -283.245873) (xy 129.276349 -283.245873)
			(xy 129.276349 -283.193939) (xy 129.284474 -283.142644) (xy 129.300522 -283.093251) (xy 129.3241 -283.046977)
			(xy 129.354626 -283.004961) (xy 129.391349 -282.968238) (xy 129.433365 -282.937712) (xy 129.479639 -282.914134)
			(xy 129.529032 -282.898086) (xy 129.580327 -282.889961) (xy 129.632261 -282.889961) (xy 129.683556 -282.898086)
			(xy 129.732949 -282.914134) (xy 129.779223 -282.937712) (xy 129.821239 -282.968238) (xy 129.857962 -283.004961)
			(xy 129.888488 -283.046977) (xy 129.912066 -283.093251) (xy 129.928114 -283.142644) (xy 129.936239 -283.193939)
			(xy 129.936748 -283.219906) (xy 129.936239 -283.245873) (xy 130.216149 -283.245873) (xy 130.216149 -283.193939)
			(xy 130.224274 -283.142644) (xy 130.240322 -283.093251) (xy 130.2639 -283.046977) (xy 130.294426 -283.004961)
			(xy 130.331149 -282.968238) (xy 130.373165 -282.937712) (xy 130.419439 -282.914134) (xy 130.468832 -282.898086)
			(xy 130.520127 -282.889961) (xy 130.572061 -282.889961) (xy 130.623356 -282.898086) (xy 130.672749 -282.914134)
			(xy 130.719023 -282.937712) (xy 130.761039 -282.968238) (xy 130.797762 -283.004961) (xy 130.828288 -283.046977)
			(xy 130.851866 -283.093251) (xy 130.867914 -283.142644) (xy 130.876039 -283.193939) (xy 130.876548 -283.219906)
			(xy 130.876039 -283.245873) (xy 131.156203 -283.245873) (xy 131.156203 -283.193939) (xy 131.164328 -283.142644)
			(xy 131.180376 -283.093251) (xy 131.203954 -283.046977) (xy 131.23448 -283.004961) (xy 131.271203 -282.968238)
			(xy 131.313219 -282.937712) (xy 131.359493 -282.914134) (xy 131.408886 -282.898086) (xy 131.460181 -282.889961)
			(xy 131.512115 -282.889961) (xy 131.56341 -282.898086) (xy 131.612803 -282.914134) (xy 131.659077 -282.937712)
			(xy 131.701093 -282.968238) (xy 131.737816 -283.004961) (xy 131.768342 -283.046977) (xy 131.79192 -283.093251)
			(xy 131.807968 -283.142644) (xy 131.816093 -283.193939) (xy 131.816602 -283.219906) (xy 131.816093 -283.245873)
			(xy 132.095749 -283.245873) (xy 132.095749 -283.193939) (xy 132.103874 -283.142644) (xy 132.119922 -283.093251)
			(xy 132.1435 -283.046977) (xy 132.174026 -283.004961) (xy 132.210749 -282.968238) (xy 132.252765 -282.937712)
			(xy 132.299039 -282.914134) (xy 132.348432 -282.898086) (xy 132.399727 -282.889961) (xy 132.451661 -282.889961)
			(xy 132.502956 -282.898086) (xy 132.552349 -282.914134) (xy 132.598623 -282.937712) (xy 132.640639 -282.968238)
			(xy 132.677362 -283.004961) (xy 132.707888 -283.046977) (xy 132.731466 -283.093251) (xy 132.747514 -283.142644)
			(xy 132.755639 -283.193939) (xy 132.756148 -283.219906) (xy 132.755639 -283.245873) (xy 133.035803 -283.245873)
			(xy 133.035803 -283.193939) (xy 133.043928 -283.142644) (xy 133.059976 -283.093251) (xy 133.083554 -283.046977)
			(xy 133.11408 -283.004961) (xy 133.150803 -282.968238) (xy 133.192819 -282.937712) (xy 133.239093 -282.914134)
			(xy 133.288486 -282.898086) (xy 133.339781 -282.889961) (xy 133.391715 -282.889961) (xy 133.44301 -282.898086)
			(xy 133.492403 -282.914134) (xy 133.538677 -282.937712) (xy 133.580693 -282.968238) (xy 133.617416 -283.004961)
			(xy 133.647942 -283.046977) (xy 133.67152 -283.093251) (xy 133.687568 -283.142644) (xy 133.695693 -283.193939)
			(xy 133.696202 -283.219906) (xy 133.695693 -283.245873) (xy 133.687568 -283.297168) (xy 133.67152 -283.346561)
			(xy 133.647942 -283.392835) (xy 133.617416 -283.434851) (xy 133.580693 -283.471574) (xy 133.538677 -283.5021)
			(xy 133.492403 -283.525678) (xy 133.44301 -283.541726) (xy 133.391715 -283.549851) (xy 133.339781 -283.549851)
			(xy 133.288486 -283.541726) (xy 133.239093 -283.525678) (xy 133.192819 -283.5021) (xy 133.150803 -283.471574)
			(xy 133.11408 -283.434851) (xy 133.083554 -283.392835) (xy 133.059976 -283.346561) (xy 133.043928 -283.297168)
			(xy 133.035803 -283.245873) (xy 132.755639 -283.245873) (xy 132.747514 -283.297168) (xy 132.731466 -283.346561)
			(xy 132.707888 -283.392835) (xy 132.677362 -283.434851) (xy 132.640639 -283.471574) (xy 132.598623 -283.5021)
			(xy 132.552349 -283.525678) (xy 132.502956 -283.541726) (xy 132.451661 -283.549851) (xy 132.399727 -283.549851)
			(xy 132.348432 -283.541726) (xy 132.299039 -283.525678) (xy 132.252765 -283.5021) (xy 132.210749 -283.471574)
			(xy 132.174026 -283.434851) (xy 132.1435 -283.392835) (xy 132.119922 -283.346561) (xy 132.103874 -283.297168)
			(xy 132.095749 -283.245873) (xy 131.816093 -283.245873) (xy 131.807968 -283.297168) (xy 131.79192 -283.346561)
			(xy 131.768342 -283.392835) (xy 131.737816 -283.434851) (xy 131.701093 -283.471574) (xy 131.659077 -283.5021)
			(xy 131.612803 -283.525678) (xy 131.56341 -283.541726) (xy 131.512115 -283.549851) (xy 131.460181 -283.549851)
			(xy 131.408886 -283.541726) (xy 131.359493 -283.525678) (xy 131.313219 -283.5021) (xy 131.271203 -283.471574)
			(xy 131.23448 -283.434851) (xy 131.203954 -283.392835) (xy 131.180376 -283.346561) (xy 131.164328 -283.297168)
			(xy 131.156203 -283.245873) (xy 130.876039 -283.245873) (xy 130.867914 -283.297168) (xy 130.851866 -283.346561)
			(xy 130.828288 -283.392835) (xy 130.797762 -283.434851) (xy 130.761039 -283.471574) (xy 130.719023 -283.5021)
			(xy 130.672749 -283.525678) (xy 130.623356 -283.541726) (xy 130.572061 -283.549851) (xy 130.520127 -283.549851)
			(xy 130.468832 -283.541726) (xy 130.419439 -283.525678) (xy 130.373165 -283.5021) (xy 130.331149 -283.471574)
			(xy 130.294426 -283.434851) (xy 130.2639 -283.392835) (xy 130.240322 -283.346561) (xy 130.224274 -283.297168)
			(xy 130.216149 -283.245873) (xy 129.936239 -283.245873) (xy 129.928114 -283.297168) (xy 129.912066 -283.346561)
			(xy 129.888488 -283.392835) (xy 129.857962 -283.434851) (xy 129.821239 -283.471574) (xy 129.779223 -283.5021)
			(xy 129.732949 -283.525678) (xy 129.683556 -283.541726) (xy 129.632261 -283.549851) (xy 129.580327 -283.549851)
			(xy 129.529032 -283.541726) (xy 129.479639 -283.525678) (xy 129.433365 -283.5021) (xy 129.391349 -283.471574)
			(xy 129.354626 -283.434851) (xy 129.3241 -283.392835) (xy 129.300522 -283.346561) (xy 129.284474 -283.297168)
			(xy 129.276349 -283.245873) (xy 128.996399 -283.245873) (xy 128.988314 -283.296914) (xy 128.972266 -283.346307)
			(xy 128.948688 -283.392581) (xy 128.918162 -283.434597) (xy 128.881439 -283.47132) (xy 128.839423 -283.501846)
			(xy 128.793149 -283.525424) (xy 128.743756 -283.541472) (xy 128.692461 -283.549597) (xy 128.640527 -283.549597)
			(xy 128.589232 -283.541472) (xy 128.539839 -283.525424) (xy 128.493565 -283.501846) (xy 128.451549 -283.47132)
			(xy 128.414826 -283.434597) (xy 128.3843 -283.392581) (xy 128.360722 -283.346307) (xy 128.344674 -283.296914)
			(xy 128.336549 -283.245619) (xy 127.116844 -283.245619) (xy 127.116839 -283.245873) (xy 127.108714 -283.297168)
			(xy 127.092666 -283.346561) (xy 127.069088 -283.392835) (xy 127.038562 -283.434851) (xy 127.001839 -283.471574)
			(xy 126.959823 -283.5021) (xy 126.913549 -283.525678) (xy 126.864156 -283.541726) (xy 126.812861 -283.549851)
			(xy 126.760927 -283.549851) (xy 126.709632 -283.541726) (xy 126.660239 -283.525678) (xy 126.613965 -283.5021)
			(xy 126.571949 -283.471574) (xy 126.535226 -283.434851) (xy 126.5047 -283.392835) (xy 126.481122 -283.346561)
			(xy 126.465074 -283.297168) (xy 126.456949 -283.245873) (xy 126.177293 -283.245873) (xy 126.169168 -283.297168)
			(xy 126.15312 -283.346561) (xy 126.129542 -283.392835) (xy 126.099016 -283.434851) (xy 126.062293 -283.471574)
			(xy 126.020277 -283.5021) (xy 125.974003 -283.525678) (xy 125.92461 -283.541726) (xy 125.873315 -283.549851)
			(xy 125.821381 -283.549851) (xy 125.770086 -283.541726) (xy 125.720693 -283.525678) (xy 125.674419 -283.5021)
			(xy 125.632403 -283.471574) (xy 125.59568 -283.434851) (xy 125.565154 -283.392835) (xy 125.541576 -283.346561)
			(xy 125.525528 -283.297168) (xy 125.517403 -283.245873) (xy 125.237493 -283.245873) (xy 125.229368 -283.297168)
			(xy 125.21332 -283.346561) (xy 125.189742 -283.392835) (xy 125.159216 -283.434851) (xy 125.122493 -283.471574)
			(xy 125.080477 -283.5021) (xy 125.034203 -283.525678) (xy 124.98481 -283.541726) (xy 124.933515 -283.549851)
			(xy 124.881581 -283.549851) (xy 124.830286 -283.541726) (xy 124.780893 -283.525678) (xy 124.734619 -283.5021)
			(xy 124.692603 -283.471574) (xy 124.65588 -283.434851) (xy 124.625354 -283.392835) (xy 124.601776 -283.346561)
			(xy 124.585728 -283.297168) (xy 124.577603 -283.245873) (xy 123.357892 -283.245873) (xy 123.357892 -283.245874)
			(xy 123.349768 -283.297171) (xy 123.333719 -283.346566) (xy 123.310142 -283.392843) (xy 123.279616 -283.434862)
			(xy 123.242894 -283.471589) (xy 123.200879 -283.50212) (xy 123.154605 -283.525703) (xy 123.105212 -283.541758)
			(xy 123.053916 -283.549889) (xy 123.027948 -283.55036) (xy 123.00281 -283.549893) (xy 122.953115 -283.54228)
			(xy 122.905147 -283.527223) (xy 122.860016 -283.50507) (xy 122.818764 -283.476332) (xy 122.782344 -283.441674)
			(xy 122.751597 -283.401896) (xy 122.727235 -283.357918) (xy 122.70982 -283.310755) (xy 122.699755 -283.261498)
			(xy 122.698002 -283.236416) (xy 122.696804 -283.221752) (xy 122.687074 -283.193998) (xy 122.669836 -283.17017)
			(xy 122.646521 -283.152244) (xy 122.619063 -283.141709) (xy 122.589741 -283.139438) (xy 122.560989 -283.145619)
			(xy 122.535191 -283.159741) (xy 122.52452 -283.169868) (xy 122.41276 -283.281628) (xy 122.409458 -283.295598)
			(xy 122.403767 -283.318156) (xy 122.386901 -283.361513) (xy 122.36411 -283.40207) (xy 122.335847 -283.439023)
			(xy 122.319542 -283.455618) (xy 122.31329 -283.462243) (xy 122.30555 -283.478719) (xy 122.304095 -283.496863)
			(xy 122.30911 -283.514362) (xy 122.314208 -283.521912) (xy 122.341969 -283.560715) (xy 122.389707 -283.643327)
			(xy 122.409458 -283.686758) (xy 122.413432 -283.694925) (xy 122.426062 -283.707959) (xy 122.442464 -283.71573)
			(xy 122.46055 -283.71725) (xy 122.469402 -283.715206) (xy 122.491067 -283.709594) (xy 122.535417 -283.703602)
			(xy 122.557794 -283.703268) (xy 122.583762 -283.70375) (xy 122.635058 -283.711874) (xy 122.684452 -283.727922)
			(xy 122.730728 -283.7515) (xy 122.772745 -283.782027) (xy 122.809469 -283.81875) (xy 122.839997 -283.860767)
			(xy 122.863575 -283.907042) (xy 122.879625 -283.956436) (xy 122.887749 -284.007732) (xy 122.887749 -284.059668)
			(xy 122.887746 -284.059689) (xy 123.167649 -284.059689) (xy 123.167649 -284.007755) (xy 123.175774 -283.95646)
			(xy 123.191822 -283.907067) (xy 123.2154 -283.860793) (xy 123.245926 -283.818777) (xy 123.282649 -283.782054)
			(xy 123.324665 -283.751528) (xy 123.370939 -283.72795) (xy 123.420332 -283.711902) (xy 123.471627 -283.703777)
			(xy 123.523561 -283.703777) (xy 123.574856 -283.711902) (xy 123.624249 -283.72795) (xy 123.670523 -283.751528)
			(xy 123.712539 -283.782054) (xy 123.749262 -283.818777) (xy 123.779788 -283.860793) (xy 123.803366 -283.907067)
			(xy 123.819414 -283.95646) (xy 123.827539 -284.007755) (xy 123.828048 -284.033722) (xy 123.827539 -284.059689)
			(xy 124.107449 -284.059689) (xy 124.107449 -284.007755) (xy 124.115574 -283.95646) (xy 124.131622 -283.907067)
			(xy 124.1552 -283.860793) (xy 124.185726 -283.818777) (xy 124.222449 -283.782054) (xy 124.264465 -283.751528)
			(xy 124.310739 -283.72795) (xy 124.360132 -283.711902) (xy 124.411427 -283.703777) (xy 124.463361 -283.703777)
			(xy 124.514656 -283.711902) (xy 124.564049 -283.72795) (xy 124.610323 -283.751528) (xy 124.652339 -283.782054)
			(xy 124.689062 -283.818777) (xy 124.719588 -283.860793) (xy 124.743166 -283.907067) (xy 124.759214 -283.95646)
			(xy 124.767339 -284.007755) (xy 124.767848 -284.033722) (xy 124.767339 -284.059689) (xy 125.047503 -284.059689)
			(xy 125.047503 -284.007755) (xy 125.055628 -283.95646) (xy 125.071676 -283.907067) (xy 125.095254 -283.860793)
			(xy 125.12578 -283.818777) (xy 125.162503 -283.782054) (xy 125.204519 -283.751528) (xy 125.250793 -283.72795)
			(xy 125.300186 -283.711902) (xy 125.351481 -283.703777) (xy 125.403415 -283.703777) (xy 125.45471 -283.711902)
			(xy 125.504103 -283.72795) (xy 125.550377 -283.751528) (xy 125.592393 -283.782054) (xy 125.629116 -283.818777)
			(xy 125.659642 -283.860793) (xy 125.68322 -283.907067) (xy 125.699268 -283.95646) (xy 125.707393 -284.007755)
			(xy 125.707902 -284.033722) (xy 125.707393 -284.059689) (xy 125.987049 -284.059689) (xy 125.987049 -284.007755)
			(xy 125.995174 -283.95646) (xy 126.011222 -283.907067) (xy 126.0348 -283.860793) (xy 126.065326 -283.818777)
			(xy 126.102049 -283.782054) (xy 126.144065 -283.751528) (xy 126.190339 -283.72795) (xy 126.239732 -283.711902)
			(xy 126.291027 -283.703777) (xy 126.342961 -283.703777) (xy 126.394256 -283.711902) (xy 126.443649 -283.72795)
			(xy 126.489923 -283.751528) (xy 126.531939 -283.782054) (xy 126.568662 -283.818777) (xy 126.599188 -283.860793)
			(xy 126.622766 -283.907067) (xy 126.638814 -283.95646) (xy 126.646939 -284.007755) (xy 126.647448 -284.033722)
			(xy 126.646939 -284.059689) (xy 126.926849 -284.059689) (xy 126.926849 -284.007755) (xy 126.934974 -283.95646)
			(xy 126.951022 -283.907067) (xy 126.9746 -283.860793) (xy 127.005126 -283.818777) (xy 127.041849 -283.782054)
			(xy 127.083865 -283.751528) (xy 127.130139 -283.72795) (xy 127.179532 -283.711902) (xy 127.230827 -283.703777)
			(xy 127.282761 -283.703777) (xy 127.334056 -283.711902) (xy 127.383449 -283.72795) (xy 127.429723 -283.751528)
			(xy 127.471739 -283.782054) (xy 127.508462 -283.818777) (xy 127.538988 -283.860793) (xy 127.562566 -283.907067)
			(xy 127.578614 -283.95646) (xy 127.586739 -284.007755) (xy 127.587248 -284.033722) (xy 127.586739 -284.059689)
			(xy 127.866649 -284.059689) (xy 127.866649 -284.007755) (xy 127.874774 -283.95646) (xy 127.890822 -283.907067)
			(xy 127.9144 -283.860793) (xy 127.944926 -283.818777) (xy 127.981649 -283.782054) (xy 128.023665 -283.751528)
			(xy 128.069939 -283.72795) (xy 128.119332 -283.711902) (xy 128.170627 -283.703777) (xy 128.222561 -283.703777)
			(xy 128.273856 -283.711902) (xy 128.323249 -283.72795) (xy 128.369523 -283.751528) (xy 128.411539 -283.782054)
			(xy 128.448262 -283.818777) (xy 128.478788 -283.860793) (xy 128.502366 -283.907067) (xy 128.518414 -283.95646)
			(xy 128.526539 -284.007755) (xy 128.527048 -284.033722) (xy 128.526539 -284.059689) (xy 128.806449 -284.059689)
			(xy 128.806449 -284.007755) (xy 128.814574 -283.95646) (xy 128.830622 -283.907067) (xy 128.8542 -283.860793)
			(xy 128.884726 -283.818777) (xy 128.921449 -283.782054) (xy 128.963465 -283.751528) (xy 129.009739 -283.72795)
			(xy 129.059132 -283.711902) (xy 129.110427 -283.703777) (xy 129.162361 -283.703777) (xy 129.213656 -283.711902)
			(xy 129.263049 -283.72795) (xy 129.309323 -283.751528) (xy 129.351339 -283.782054) (xy 129.388062 -283.818777)
			(xy 129.418588 -283.860793) (xy 129.442166 -283.907067) (xy 129.458214 -283.95646) (xy 129.466339 -284.007755)
			(xy 129.466848 -284.033722) (xy 129.466339 -284.059689) (xy 129.746249 -284.059689) (xy 129.746249 -284.007755)
			(xy 129.754374 -283.95646) (xy 129.770422 -283.907067) (xy 129.794 -283.860793) (xy 129.824526 -283.818777)
			(xy 129.861249 -283.782054) (xy 129.903265 -283.751528) (xy 129.949539 -283.72795) (xy 129.998932 -283.711902)
			(xy 130.050227 -283.703777) (xy 130.102161 -283.703777) (xy 130.153456 -283.711902) (xy 130.202849 -283.72795)
			(xy 130.249123 -283.751528) (xy 130.291139 -283.782054) (xy 130.327862 -283.818777) (xy 130.358388 -283.860793)
			(xy 130.381966 -283.907067) (xy 130.398014 -283.95646) (xy 130.406139 -284.007755) (xy 130.406648 -284.033722)
			(xy 130.406139 -284.059689) (xy 130.686049 -284.059689) (xy 130.686049 -284.007755) (xy 130.694174 -283.95646)
			(xy 130.710222 -283.907067) (xy 130.7338 -283.860793) (xy 130.764326 -283.818777) (xy 130.801049 -283.782054)
			(xy 130.843065 -283.751528) (xy 130.889339 -283.72795) (xy 130.938732 -283.711902) (xy 130.990027 -283.703777)
			(xy 131.041961 -283.703777) (xy 131.093256 -283.711902) (xy 131.142649 -283.72795) (xy 131.188923 -283.751528)
			(xy 131.230939 -283.782054) (xy 131.267662 -283.818777) (xy 131.298188 -283.860793) (xy 131.321766 -283.907067)
			(xy 131.337814 -283.95646) (xy 131.345939 -284.007755) (xy 131.346448 -284.033722) (xy 131.345939 -284.059689)
			(xy 131.625849 -284.059689) (xy 131.625849 -284.007755) (xy 131.633974 -283.95646) (xy 131.650022 -283.907067)
			(xy 131.6736 -283.860793) (xy 131.704126 -283.818777) (xy 131.740849 -283.782054) (xy 131.782865 -283.751528)
			(xy 131.829139 -283.72795) (xy 131.878532 -283.711902) (xy 131.929827 -283.703777) (xy 131.981761 -283.703777)
			(xy 132.033056 -283.711902) (xy 132.082449 -283.72795) (xy 132.128723 -283.751528) (xy 132.170739 -283.782054)
			(xy 132.207462 -283.818777) (xy 132.237988 -283.860793) (xy 132.261566 -283.907067) (xy 132.277614 -283.95646)
			(xy 132.285739 -284.007755) (xy 132.286248 -284.033722) (xy 132.285739 -284.059689) (xy 132.565649 -284.059689)
			(xy 132.565649 -284.007755) (xy 132.573774 -283.95646) (xy 132.589822 -283.907067) (xy 132.6134 -283.860793)
			(xy 132.643926 -283.818777) (xy 132.680649 -283.782054) (xy 132.722665 -283.751528) (xy 132.768939 -283.72795)
			(xy 132.818332 -283.711902) (xy 132.869627 -283.703777) (xy 132.921561 -283.703777) (xy 132.972856 -283.711902)
			(xy 133.022249 -283.72795) (xy 133.068523 -283.751528) (xy 133.110539 -283.782054) (xy 133.147262 -283.818777)
			(xy 133.177788 -283.860793) (xy 133.201366 -283.907067) (xy 133.217414 -283.95646) (xy 133.225539 -284.007755)
			(xy 133.226048 -284.033722) (xy 133.225539 -284.059689) (xy 133.217414 -284.110984) (xy 133.201366 -284.160377)
			(xy 133.177788 -284.206651) (xy 133.147262 -284.248667) (xy 133.110539 -284.28539) (xy 133.068523 -284.315916)
			(xy 133.022249 -284.339494) (xy 132.972856 -284.355542) (xy 132.921561 -284.363667) (xy 132.869627 -284.363667)
			(xy 132.818332 -284.355542) (xy 132.768939 -284.339494) (xy 132.722665 -284.315916) (xy 132.680649 -284.28539)
			(xy 132.643926 -284.248667) (xy 132.6134 -284.206651) (xy 132.589822 -284.160377) (xy 132.573774 -284.110984)
			(xy 132.565649 -284.059689) (xy 132.285739 -284.059689) (xy 132.277614 -284.110984) (xy 132.261566 -284.160377)
			(xy 132.237988 -284.206651) (xy 132.207462 -284.248667) (xy 132.170739 -284.28539) (xy 132.128723 -284.315916)
			(xy 132.082449 -284.339494) (xy 132.033056 -284.355542) (xy 131.981761 -284.363667) (xy 131.929827 -284.363667)
			(xy 131.878532 -284.355542) (xy 131.829139 -284.339494) (xy 131.782865 -284.315916) (xy 131.740849 -284.28539)
			(xy 131.704126 -284.248667) (xy 131.6736 -284.206651) (xy 131.650022 -284.160377) (xy 131.633974 -284.110984)
			(xy 131.625849 -284.059689) (xy 131.345939 -284.059689) (xy 131.337814 -284.110984) (xy 131.321766 -284.160377)
			(xy 131.298188 -284.206651) (xy 131.267662 -284.248667) (xy 131.230939 -284.28539) (xy 131.188923 -284.315916)
			(xy 131.142649 -284.339494) (xy 131.093256 -284.355542) (xy 131.041961 -284.363667) (xy 130.990027 -284.363667)
			(xy 130.938732 -284.355542) (xy 130.889339 -284.339494) (xy 130.843065 -284.315916) (xy 130.801049 -284.28539)
			(xy 130.764326 -284.248667) (xy 130.7338 -284.206651) (xy 130.710222 -284.160377) (xy 130.694174 -284.110984)
			(xy 130.686049 -284.059689) (xy 130.406139 -284.059689) (xy 130.398014 -284.110984) (xy 130.381966 -284.160377)
			(xy 130.358388 -284.206651) (xy 130.327862 -284.248667) (xy 130.291139 -284.28539) (xy 130.249123 -284.315916)
			(xy 130.202849 -284.339494) (xy 130.153456 -284.355542) (xy 130.102161 -284.363667) (xy 130.050227 -284.363667)
			(xy 129.998932 -284.355542) (xy 129.949539 -284.339494) (xy 129.903265 -284.315916) (xy 129.861249 -284.28539)
			(xy 129.824526 -284.248667) (xy 129.794 -284.206651) (xy 129.770422 -284.160377) (xy 129.754374 -284.110984)
			(xy 129.746249 -284.059689) (xy 129.466339 -284.059689) (xy 129.458214 -284.110984) (xy 129.442166 -284.160377)
			(xy 129.418588 -284.206651) (xy 129.388062 -284.248667) (xy 129.351339 -284.28539) (xy 129.309323 -284.315916)
			(xy 129.263049 -284.339494) (xy 129.213656 -284.355542) (xy 129.162361 -284.363667) (xy 129.110427 -284.363667)
			(xy 129.059132 -284.355542) (xy 129.009739 -284.339494) (xy 128.963465 -284.315916) (xy 128.921449 -284.28539)
			(xy 128.884726 -284.248667) (xy 128.8542 -284.206651) (xy 128.830622 -284.160377) (xy 128.814574 -284.110984)
			(xy 128.806449 -284.059689) (xy 128.526539 -284.059689) (xy 128.518414 -284.110984) (xy 128.502366 -284.160377)
			(xy 128.478788 -284.206651) (xy 128.448262 -284.248667) (xy 128.411539 -284.28539) (xy 128.369523 -284.315916)
			(xy 128.323249 -284.339494) (xy 128.273856 -284.355542) (xy 128.222561 -284.363667) (xy 128.170627 -284.363667)
			(xy 128.119332 -284.355542) (xy 128.069939 -284.339494) (xy 128.023665 -284.315916) (xy 127.981649 -284.28539)
			(xy 127.944926 -284.248667) (xy 127.9144 -284.206651) (xy 127.890822 -284.160377) (xy 127.874774 -284.110984)
			(xy 127.866649 -284.059689) (xy 127.586739 -284.059689) (xy 127.578614 -284.110984) (xy 127.562566 -284.160377)
			(xy 127.538988 -284.206651) (xy 127.508462 -284.248667) (xy 127.471739 -284.28539) (xy 127.429723 -284.315916)
			(xy 127.383449 -284.339494) (xy 127.334056 -284.355542) (xy 127.282761 -284.363667) (xy 127.230827 -284.363667)
			(xy 127.179532 -284.355542) (xy 127.130139 -284.339494) (xy 127.083865 -284.315916) (xy 127.041849 -284.28539)
			(xy 127.005126 -284.248667) (xy 126.9746 -284.206651) (xy 126.951022 -284.160377) (xy 126.934974 -284.110984)
			(xy 126.926849 -284.059689) (xy 126.646939 -284.059689) (xy 126.638814 -284.110984) (xy 126.622766 -284.160377)
			(xy 126.599188 -284.206651) (xy 126.568662 -284.248667) (xy 126.531939 -284.28539) (xy 126.489923 -284.315916)
			(xy 126.443649 -284.339494) (xy 126.394256 -284.355542) (xy 126.342961 -284.363667) (xy 126.291027 -284.363667)
			(xy 126.239732 -284.355542) (xy 126.190339 -284.339494) (xy 126.144065 -284.315916) (xy 126.102049 -284.28539)
			(xy 126.065326 -284.248667) (xy 126.0348 -284.206651) (xy 126.011222 -284.160377) (xy 125.995174 -284.110984)
			(xy 125.987049 -284.059689) (xy 125.707393 -284.059689) (xy 125.699268 -284.110984) (xy 125.68322 -284.160377)
			(xy 125.659642 -284.206651) (xy 125.629116 -284.248667) (xy 125.592393 -284.28539) (xy 125.550377 -284.315916)
			(xy 125.504103 -284.339494) (xy 125.45471 -284.355542) (xy 125.403415 -284.363667) (xy 125.351481 -284.363667)
			(xy 125.300186 -284.355542) (xy 125.250793 -284.339494) (xy 125.204519 -284.315916) (xy 125.162503 -284.28539)
			(xy 125.12578 -284.248667) (xy 125.095254 -284.206651) (xy 125.071676 -284.160377) (xy 125.055628 -284.110984)
			(xy 125.047503 -284.059689) (xy 124.767339 -284.059689) (xy 124.759214 -284.110984) (xy 124.743166 -284.160377)
			(xy 124.719588 -284.206651) (xy 124.689062 -284.248667) (xy 124.652339 -284.28539) (xy 124.610323 -284.315916)
			(xy 124.564049 -284.339494) (xy 124.514656 -284.355542) (xy 124.463361 -284.363667) (xy 124.411427 -284.363667)
			(xy 124.360132 -284.355542) (xy 124.310739 -284.339494) (xy 124.264465 -284.315916) (xy 124.222449 -284.28539)
			(xy 124.185726 -284.248667) (xy 124.1552 -284.206651) (xy 124.131622 -284.160377) (xy 124.115574 -284.110984)
			(xy 124.107449 -284.059689) (xy 123.827539 -284.059689) (xy 123.819414 -284.110984) (xy 123.803366 -284.160377)
			(xy 123.779788 -284.206651) (xy 123.749262 -284.248667) (xy 123.712539 -284.28539) (xy 123.670523 -284.315916)
			(xy 123.624249 -284.339494) (xy 123.574856 -284.355542) (xy 123.523561 -284.363667) (xy 123.471627 -284.363667)
			(xy 123.420332 -284.355542) (xy 123.370939 -284.339494) (xy 123.324665 -284.315916) (xy 123.282649 -284.28539)
			(xy 123.245926 -284.248667) (xy 123.2154 -284.206651) (xy 123.191822 -284.160377) (xy 123.175774 -284.110984)
			(xy 123.167649 -284.059689) (xy 122.887746 -284.059689) (xy 122.879625 -284.110964) (xy 122.863575 -284.160358)
			(xy 122.839997 -284.206633) (xy 122.809469 -284.24865) (xy 122.772745 -284.285373) (xy 122.730728 -284.3159)
			(xy 122.684452 -284.339478) (xy 122.635058 -284.355526) (xy 122.583762 -284.36365) (xy 122.557794 -284.364176)
			(xy 122.535482 -284.363808) (xy 122.491261 -284.357821) (xy 122.469656 -284.352238) (xy 122.460784 -284.350133)
			(xy 122.442627 -284.351649) (xy 122.42615 -284.359429) (xy 122.413441 -284.372485) (xy 122.409458 -284.380686)
			(xy 122.39337 -284.416342) (xy 122.355641 -284.484872) (xy 122.311868 -284.549709) (xy 122.262409 -284.61032)
			(xy 122.20767 -284.666208) (xy 122.148099 -284.716915) (xy 122.084186 -284.762026) (xy 122.050556 -284.782006)
			(xy 122.049286 -284.782514) (xy 122.045984 -284.784546) (xy 122.035936 -284.791863) (xy 122.020824 -284.811577)
			(xy 122.012848 -284.835101) (xy 122.012852 -284.847538) (xy 122.697494 -284.847538) (xy 122.698003 -284.821571)
			(xy 122.706128 -284.770276) (xy 122.722176 -284.720883) (xy 122.745754 -284.674609) (xy 122.77628 -284.632593)
			(xy 122.813003 -284.59587) (xy 122.855019 -284.565344) (xy 122.901293 -284.541766) (xy 122.950686 -284.525718)
			(xy 123.001981 -284.517593) (xy 123.053915 -284.517593) (xy 123.10521 -284.525718) (xy 123.154603 -284.541766)
			(xy 123.200877 -284.565344) (xy 123.242893 -284.59587) (xy 123.279616 -284.632593) (xy 123.310142 -284.674609)
			(xy 123.33372 -284.720883) (xy 123.349768 -284.770276) (xy 123.357893 -284.821571) (xy 123.358402 -284.847538)
			(xy 124.577094 -284.847538) (xy 124.577603 -284.821571) (xy 124.585728 -284.770276) (xy 124.601776 -284.720883)
			(xy 124.625354 -284.674609) (xy 124.65588 -284.632593) (xy 124.692603 -284.59587) (xy 124.734619 -284.565344)
			(xy 124.780893 -284.541766) (xy 124.830286 -284.525718) (xy 124.881581 -284.517593) (xy 124.933515 -284.517593)
			(xy 124.98481 -284.525718) (xy 125.034203 -284.541766) (xy 125.080477 -284.565344) (xy 125.122493 -284.59587)
			(xy 125.159216 -284.632593) (xy 125.189742 -284.674609) (xy 125.21332 -284.720883) (xy 125.229368 -284.770276)
			(xy 125.237493 -284.821571) (xy 125.238002 -284.847538) (xy 125.237498 -284.873505) (xy 125.517403 -284.873505)
			(xy 125.517403 -284.821571) (xy 125.525528 -284.770276) (xy 125.541576 -284.720883) (xy 125.565154 -284.674609)
			(xy 125.59568 -284.632593) (xy 125.632403 -284.59587) (xy 125.674419 -284.565344) (xy 125.720693 -284.541766)
			(xy 125.770086 -284.525718) (xy 125.821381 -284.517593) (xy 125.873315 -284.517593) (xy 125.92461 -284.525718)
			(xy 125.974003 -284.541766) (xy 126.020277 -284.565344) (xy 126.062293 -284.59587) (xy 126.099016 -284.632593)
			(xy 126.129542 -284.674609) (xy 126.15312 -284.720883) (xy 126.169168 -284.770276) (xy 126.177293 -284.821571)
			(xy 126.177802 -284.847538) (xy 126.456694 -284.847538) (xy 126.457203 -284.821571) (xy 126.465328 -284.770276)
			(xy 126.481376 -284.720883) (xy 126.504954 -284.674609) (xy 126.53548 -284.632593) (xy 126.572203 -284.59587)
			(xy 126.614219 -284.565344) (xy 126.660493 -284.541766) (xy 126.709886 -284.525718) (xy 126.761181 -284.517593)
			(xy 126.813115 -284.517593) (xy 126.86441 -284.525718) (xy 126.913803 -284.541766) (xy 126.960077 -284.565344)
			(xy 127.002093 -284.59587) (xy 127.038816 -284.632593) (xy 127.069342 -284.674609) (xy 127.09292 -284.720883)
			(xy 127.108968 -284.770276) (xy 127.117093 -284.821571) (xy 127.117602 -284.847538) (xy 128.336294 -284.847538)
			(xy 128.336803 -284.821571) (xy 128.344928 -284.770276) (xy 128.360976 -284.720883) (xy 128.384554 -284.674609)
			(xy 128.41508 -284.632593) (xy 128.451803 -284.59587) (xy 128.493819 -284.565344) (xy 128.540093 -284.541766)
			(xy 128.589486 -284.525718) (xy 128.640781 -284.517593) (xy 128.692715 -284.517593) (xy 128.74401 -284.525718)
			(xy 128.793403 -284.541766) (xy 128.839677 -284.565344) (xy 128.881693 -284.59587) (xy 128.918416 -284.632593)
			(xy 128.948942 -284.674609) (xy 128.97252 -284.720883) (xy 128.988568 -284.770276) (xy 128.996693 -284.821571)
			(xy 128.997202 -284.847538) (xy 130.215894 -284.847538) (xy 130.216403 -284.821571) (xy 130.224528 -284.770276)
			(xy 130.240576 -284.720883) (xy 130.264154 -284.674609) (xy 130.29468 -284.632593) (xy 130.331403 -284.59587)
			(xy 130.373419 -284.565344) (xy 130.419693 -284.541766) (xy 130.469086 -284.525718) (xy 130.520381 -284.517593)
			(xy 130.572315 -284.517593) (xy 130.62361 -284.525718) (xy 130.673003 -284.541766) (xy 130.719277 -284.565344)
			(xy 130.761293 -284.59587) (xy 130.798016 -284.632593) (xy 130.828542 -284.674609) (xy 130.85212 -284.720883)
			(xy 130.868168 -284.770276) (xy 130.876293 -284.821571) (xy 130.876802 -284.847538) (xy 132.095494 -284.847538)
			(xy 132.096003 -284.821571) (xy 132.104128 -284.770276) (xy 132.120176 -284.720883) (xy 132.143754 -284.674609)
			(xy 132.17428 -284.632593) (xy 132.211003 -284.59587) (xy 132.253019 -284.565344) (xy 132.299293 -284.541766)
			(xy 132.348686 -284.525718) (xy 132.399981 -284.517593) (xy 132.451915 -284.517593) (xy 132.50321 -284.525718)
			(xy 132.552603 -284.541766) (xy 132.598877 -284.565344) (xy 132.640893 -284.59587) (xy 132.677616 -284.632593)
			(xy 132.708142 -284.674609) (xy 132.73172 -284.720883) (xy 132.747768 -284.770276) (xy 132.755893 -284.821571)
			(xy 132.756402 -284.847538) (xy 132.755898 -284.873505) (xy 133.975603 -284.873505) (xy 133.975603 -284.821571)
			(xy 133.983728 -284.770276) (xy 133.999776 -284.720883) (xy 134.023354 -284.674609) (xy 134.05388 -284.632593)
			(xy 134.090603 -284.59587) (xy 134.132619 -284.565344) (xy 134.178893 -284.541766) (xy 134.228286 -284.525718)
			(xy 134.279581 -284.517593) (xy 134.331515 -284.517593) (xy 134.38281 -284.525718) (xy 134.432203 -284.541766)
			(xy 134.478477 -284.565344) (xy 134.520493 -284.59587) (xy 134.557216 -284.632593) (xy 134.587742 -284.674609)
			(xy 134.61132 -284.720883) (xy 134.627368 -284.770276) (xy 134.635493 -284.821571) (xy 134.636002 -284.847538)
			(xy 134.635498 -284.873251) (xy 134.915149 -284.873251) (xy 134.915149 -284.821317) (xy 134.923274 -284.770022)
			(xy 134.939322 -284.720629) (xy 134.9629 -284.674355) (xy 134.993426 -284.632339) (xy 135.030149 -284.595616)
			(xy 135.072165 -284.56509) (xy 135.118439 -284.541512) (xy 135.167832 -284.525464) (xy 135.219127 -284.517339)
			(xy 135.271061 -284.517339) (xy 135.322356 -284.525464) (xy 135.371749 -284.541512) (xy 135.418023 -284.56509)
			(xy 135.460039 -284.595616) (xy 135.496762 -284.632339) (xy 135.527288 -284.674355) (xy 135.550866 -284.720629)
			(xy 135.566914 -284.770022) (xy 135.575039 -284.821317) (xy 135.575548 -284.847284) (xy 135.575039 -284.873251)
			(xy 135.566914 -284.924546) (xy 135.550866 -284.973939) (xy 135.527288 -285.020213) (xy 135.496762 -285.062229)
			(xy 135.460039 -285.098952) (xy 135.418023 -285.129478) (xy 135.371749 -285.153056) (xy 135.322356 -285.169104)
			(xy 135.271061 -285.177229) (xy 135.219127 -285.177229) (xy 135.167832 -285.169104) (xy 135.118439 -285.153056)
			(xy 135.072165 -285.129478) (xy 135.030149 -285.098952) (xy 134.993426 -285.062229) (xy 134.9629 -285.020213)
			(xy 134.939322 -284.973939) (xy 134.923274 -284.924546) (xy 134.915149 -284.873251) (xy 134.635498 -284.873251)
			(xy 134.635493 -284.873505) (xy 134.627368 -284.9248) (xy 134.61132 -284.974193) (xy 134.587742 -285.020467)
			(xy 134.557216 -285.062483) (xy 134.520493 -285.099206) (xy 134.478477 -285.129732) (xy 134.432203 -285.15331)
			(xy 134.38281 -285.169358) (xy 134.331515 -285.177483) (xy 134.279581 -285.177483) (xy 134.228286 -285.169358)
			(xy 134.178893 -285.15331) (xy 134.132619 -285.129732) (xy 134.090603 -285.099206) (xy 134.05388 -285.062483)
			(xy 134.023354 -285.020467) (xy 133.999776 -284.974193) (xy 133.983728 -284.9248) (xy 133.975603 -284.873505)
			(xy 132.755898 -284.873505) (xy 132.755859 -284.875524) (xy 132.746402 -284.930692) (xy 132.737606 -284.957266)
			(xy 132.729986 -284.979364) (xy 132.933694 -285.33217) (xy 132.956554 -285.336488) (xy 132.981483 -285.341625)
			(xy 133.029468 -285.358593) (xy 133.074287 -285.382714) (xy 133.11488 -285.413418) (xy 133.150288 -285.449981)
			(xy 133.179676 -285.491537) (xy 133.202348 -285.537105) (xy 133.21777 -285.58561) (xy 133.225576 -285.635905)
			(xy 133.226048 -285.661354) (xy 133.225539 -285.687321) (xy 133.217414 -285.738616) (xy 133.201366 -285.788009)
			(xy 133.177788 -285.834283) (xy 133.147262 -285.876299) (xy 133.110539 -285.913022) (xy 133.068523 -285.943548)
			(xy 133.022249 -285.967126) (xy 132.972856 -285.983174) (xy 132.921561 -285.991299) (xy 132.869627 -285.991299)
			(xy 132.818332 -285.983174) (xy 132.768939 -285.967126) (xy 132.722665 -285.943548) (xy 132.680649 -285.913022)
			(xy 132.643926 -285.876299) (xy 132.6134 -285.834283) (xy 132.589822 -285.788009) (xy 132.573774 -285.738616)
			(xy 132.565649 -285.687321) (xy 132.56514 -285.661354) (xy 132.565679 -285.633367) (xy 132.575138 -285.5782)
			(xy 132.583936 -285.551626) (xy 132.591556 -285.529528) (xy 132.387848 -285.176722) (xy 132.364988 -285.172404)
			(xy 132.340064 -285.167244) (xy 132.292078 -285.150281) (xy 132.247258 -285.126165) (xy 132.206664 -285.095464)
			(xy 132.171254 -285.058905) (xy 132.141866 -285.017351) (xy 132.119193 -284.971784) (xy 132.103771 -284.92328)
			(xy 132.095965 -284.872986) (xy 132.095494 -284.847538) (xy 130.876802 -284.847538) (xy 130.876259 -284.875524)
			(xy 130.866802 -284.930692) (xy 130.858006 -284.957266) (xy 130.850386 -284.979364) (xy 131.054094 -285.33217)
			(xy 131.076954 -285.336488) (xy 131.101883 -285.341625) (xy 131.149868 -285.358593) (xy 131.194687 -285.382714)
			(xy 131.23528 -285.413418) (xy 131.270688 -285.449981) (xy 131.300076 -285.491537) (xy 131.322748 -285.537105)
			(xy 131.33817 -285.58561) (xy 131.345976 -285.635905) (xy 131.346448 -285.661354) (xy 131.345939 -285.687321)
			(xy 131.337814 -285.738616) (xy 131.321766 -285.788009) (xy 131.298188 -285.834283) (xy 131.267662 -285.876299)
			(xy 131.230939 -285.913022) (xy 131.188923 -285.943548) (xy 131.142649 -285.967126) (xy 131.093256 -285.983174)
			(xy 131.041961 -285.991299) (xy 130.990027 -285.991299) (xy 130.938732 -285.983174) (xy 130.889339 -285.967126)
			(xy 130.843065 -285.943548) (xy 130.801049 -285.913022) (xy 130.764326 -285.876299) (xy 130.7338 -285.834283)
			(xy 130.710222 -285.788009) (xy 130.694174 -285.738616) (xy 130.686049 -285.687321) (xy 130.68554 -285.661354)
			(xy 130.686079 -285.633367) (xy 130.695538 -285.5782) (xy 130.704336 -285.551626) (xy 130.711956 -285.529528)
			(xy 130.508248 -285.176722) (xy 130.485388 -285.172404) (xy 130.460464 -285.167244) (xy 130.412478 -285.150281)
			(xy 130.367658 -285.126165) (xy 130.327064 -285.095464) (xy 130.291654 -285.058905) (xy 130.262266 -285.017351)
			(xy 130.239593 -284.971784) (xy 130.224171 -284.92328) (xy 130.216365 -284.872986) (xy 130.215894 -284.847538)
			(xy 128.997202 -284.847538) (xy 128.996659 -284.875524) (xy 128.987202 -284.930692) (xy 128.978406 -284.957266)
			(xy 128.970786 -284.979364) (xy 129.174494 -285.33217) (xy 129.197354 -285.336488) (xy 129.222283 -285.341625)
			(xy 129.270268 -285.358593) (xy 129.315087 -285.382714) (xy 129.35568 -285.413418) (xy 129.391088 -285.449981)
			(xy 129.420476 -285.491537) (xy 129.443148 -285.537105) (xy 129.45857 -285.58561) (xy 129.466376 -285.635905)
			(xy 129.466848 -285.661354) (xy 129.466339 -285.687321) (xy 129.458214 -285.738616) (xy 129.442166 -285.788009)
			(xy 129.418588 -285.834283) (xy 129.388062 -285.876299) (xy 129.351339 -285.913022) (xy 129.309323 -285.943548)
			(xy 129.263049 -285.967126) (xy 129.213656 -285.983174) (xy 129.162361 -285.991299) (xy 129.110427 -285.991299)
			(xy 129.059132 -285.983174) (xy 129.009739 -285.967126) (xy 128.963465 -285.943548) (xy 128.921449 -285.913022)
			(xy 128.884726 -285.876299) (xy 128.8542 -285.834283) (xy 128.830622 -285.788009) (xy 128.814574 -285.738616)
			(xy 128.806449 -285.687321) (xy 128.80594 -285.661354) (xy 128.806479 -285.633367) (xy 128.815938 -285.5782)
			(xy 128.824736 -285.551626) (xy 128.832356 -285.529528) (xy 128.628648 -285.176722) (xy 128.605788 -285.172404)
			(xy 128.580864 -285.167244) (xy 128.532878 -285.150281) (xy 128.488058 -285.126165) (xy 128.447464 -285.095464)
			(xy 128.412054 -285.058905) (xy 128.382666 -285.017351) (xy 128.359993 -284.971784) (xy 128.344571 -284.92328)
			(xy 128.336765 -284.872986) (xy 128.336294 -284.847538) (xy 127.117602 -284.847538) (xy 127.117059 -284.875524)
			(xy 127.107602 -284.930692) (xy 127.098806 -284.957266) (xy 127.091186 -284.979364) (xy 127.294894 -285.33217)
			(xy 127.317754 -285.336488) (xy 127.342683 -285.341625) (xy 127.390668 -285.358593) (xy 127.435487 -285.382714)
			(xy 127.47608 -285.413418) (xy 127.511488 -285.449981) (xy 127.540876 -285.491537) (xy 127.563548 -285.537105)
			(xy 127.57897 -285.58561) (xy 127.586776 -285.635905) (xy 127.587248 -285.661354) (xy 127.586739 -285.687321)
			(xy 127.578614 -285.738616) (xy 127.562566 -285.788009) (xy 127.538988 -285.834283) (xy 127.508462 -285.876299)
			(xy 127.471739 -285.913022) (xy 127.429723 -285.943548) (xy 127.383449 -285.967126) (xy 127.334056 -285.983174)
			(xy 127.282761 -285.991299) (xy 127.230827 -285.991299) (xy 127.179532 -285.983174) (xy 127.130139 -285.967126)
			(xy 127.083865 -285.943548) (xy 127.041849 -285.913022) (xy 127.005126 -285.876299) (xy 126.9746 -285.834283)
			(xy 126.951022 -285.788009) (xy 126.934974 -285.738616) (xy 126.926849 -285.687321) (xy 126.92634 -285.661354)
			(xy 126.926879 -285.633367) (xy 126.936338 -285.5782) (xy 126.945136 -285.551626) (xy 126.952756 -285.529528)
			(xy 126.749048 -285.176722) (xy 126.726188 -285.172404) (xy 126.701264 -285.167244) (xy 126.653278 -285.150281)
			(xy 126.608458 -285.126165) (xy 126.567864 -285.095464) (xy 126.532454 -285.058905) (xy 126.503066 -285.017351)
			(xy 126.480393 -284.971784) (xy 126.464971 -284.92328) (xy 126.457165 -284.872986) (xy 126.456694 -284.847538)
			(xy 126.177802 -284.847538) (xy 126.177293 -284.873505) (xy 126.169168 -284.9248) (xy 126.15312 -284.974193)
			(xy 126.129542 -285.020467) (xy 126.099016 -285.062483) (xy 126.062293 -285.099206) (xy 126.020277 -285.129732)
			(xy 125.974003 -285.15331) (xy 125.92461 -285.169358) (xy 125.873315 -285.177483) (xy 125.821381 -285.177483)
			(xy 125.770086 -285.169358) (xy 125.720693 -285.15331) (xy 125.674419 -285.129732) (xy 125.632403 -285.099206)
			(xy 125.59568 -285.062483) (xy 125.565154 -285.020467) (xy 125.541576 -284.974193) (xy 125.525528 -284.9248)
			(xy 125.517403 -284.873505) (xy 125.237498 -284.873505) (xy 125.237459 -284.875524) (xy 125.228002 -284.930692)
			(xy 125.219206 -284.957266) (xy 125.211586 -284.979364) (xy 125.415294 -285.33217) (xy 125.438154 -285.336488)
			(xy 125.463083 -285.341625) (xy 125.511068 -285.358593) (xy 125.555887 -285.382714) (xy 125.59648 -285.413418)
			(xy 125.631888 -285.449981) (xy 125.661276 -285.491537) (xy 125.683948 -285.537105) (xy 125.69937 -285.58561)
			(xy 125.707176 -285.635905) (xy 125.707648 -285.661354) (xy 125.707139 -285.687321) (xy 125.699014 -285.738616)
			(xy 125.682966 -285.788009) (xy 125.659388 -285.834283) (xy 125.628862 -285.876299) (xy 125.592139 -285.913022)
			(xy 125.550123 -285.943548) (xy 125.503849 -285.967126) (xy 125.454456 -285.983174) (xy 125.403161 -285.991299)
			(xy 125.351227 -285.991299) (xy 125.299932 -285.983174) (xy 125.250539 -285.967126) (xy 125.204265 -285.943548)
			(xy 125.162249 -285.913022) (xy 125.125526 -285.876299) (xy 125.095 -285.834283) (xy 125.071422 -285.788009)
			(xy 125.055374 -285.738616) (xy 125.047249 -285.687321) (xy 125.04674 -285.661354) (xy 125.047279 -285.633367)
			(xy 125.056738 -285.5782) (xy 125.065536 -285.551626) (xy 125.073156 -285.529528) (xy 124.869448 -285.176722)
			(xy 124.846588 -285.172404) (xy 124.821664 -285.167244) (xy 124.773678 -285.150281) (xy 124.728858 -285.126165)
			(xy 124.688264 -285.095464) (xy 124.652854 -285.058905) (xy 124.623466 -285.017351) (xy 124.600793 -284.971784)
			(xy 124.585371 -284.92328) (xy 124.577565 -284.872986) (xy 124.577094 -284.847538) (xy 123.358402 -284.847538)
			(xy 123.357859 -284.875524) (xy 123.348402 -284.930692) (xy 123.339606 -284.957266) (xy 123.331986 -284.979364)
			(xy 123.535694 -285.33217) (xy 123.558554 -285.336488) (xy 123.583483 -285.341625) (xy 123.631468 -285.358593)
			(xy 123.676287 -285.382714) (xy 123.71688 -285.413418) (xy 123.752288 -285.449981) (xy 123.781676 -285.491537)
			(xy 123.804348 -285.537105) (xy 123.81977 -285.58561) (xy 123.827576 -285.635905) (xy 123.828048 -285.661354)
			(xy 123.827539 -285.687321) (xy 123.819414 -285.738616) (xy 123.803366 -285.788009) (xy 123.779788 -285.834283)
			(xy 123.749262 -285.876299) (xy 123.712539 -285.913022) (xy 123.670523 -285.943548) (xy 123.624249 -285.967126)
			(xy 123.574856 -285.983174) (xy 123.523561 -285.991299) (xy 123.471627 -285.991299) (xy 123.420332 -285.983174)
			(xy 123.370939 -285.967126) (xy 123.324665 -285.943548) (xy 123.282649 -285.913022) (xy 123.245926 -285.876299)
			(xy 123.2154 -285.834283) (xy 123.191822 -285.788009) (xy 123.175774 -285.738616) (xy 123.167649 -285.687321)
			(xy 123.16714 -285.661354) (xy 123.167679 -285.633367) (xy 123.177138 -285.5782) (xy 123.185936 -285.551626)
			(xy 123.193556 -285.529528) (xy 122.989848 -285.176722) (xy 122.966988 -285.172404) (xy 122.942064 -285.167244)
			(xy 122.894078 -285.150281) (xy 122.849258 -285.126165) (xy 122.808664 -285.095464) (xy 122.773254 -285.058905)
			(xy 122.743866 -285.017351) (xy 122.721193 -284.971784) (xy 122.705771 -284.92328) (xy 122.697965 -284.872986)
			(xy 122.697494 -284.847538) (xy 122.012852 -284.847538) (xy 122.012855 -284.859941) (xy 122.020844 -284.883461)
			(xy 122.035967 -284.903166) (xy 122.045984 -284.91053) (xy 122.049286 -284.912562) (xy 122.050556 -284.91307)
			(xy 122.08419 -284.93304) (xy 122.14808 -284.978179) (xy 122.207633 -285.028902) (xy 122.262363 -285.084795)
			(xy 122.311824 -285.145401) (xy 122.355611 -285.210225) (xy 122.393366 -285.278738) (xy 122.409458 -285.31439)
			(xy 122.413487 -285.322561) (xy 122.426202 -285.335592) (xy 122.442658 -285.343381) (xy 122.460796 -285.344952)
			(xy 122.469656 -285.342838) (xy 122.491259 -285.337241) (xy 122.535481 -285.331257) (xy 122.557794 -285.3309)
			(xy 122.583763 -285.331409) (xy 122.635061 -285.339532) (xy 122.684458 -285.35558) (xy 122.730736 -285.379156)
			(xy 122.772756 -285.409682) (xy 122.809485 -285.446404) (xy 122.840017 -285.48842) (xy 122.8636 -285.534694)
			(xy 122.879656 -285.584088) (xy 122.887787 -285.635385) (xy 122.888248 -285.661354) (xy 122.887776 -285.686802)
			(xy 122.879968 -285.737096) (xy 122.864546 -285.7856) (xy 122.841873 -285.831168) (xy 122.812485 -285.872723)
			(xy 122.777077 -285.909284) (xy 122.736484 -285.939988) (xy 122.691666 -285.964108) (xy 122.643681 -285.981075)
			(xy 122.618754 -285.98622) (xy 122.595894 -285.990538) (xy 122.392186 -286.343598) (xy 122.399806 -286.365696)
			(xy 122.408597 -286.392271) (xy 122.418043 -286.447438) (xy 122.418602 -286.475424) (xy 122.418091 -286.501391)
			(xy 122.697749 -286.501391) (xy 122.697749 -286.449457) (xy 122.705874 -286.398162) (xy 122.721922 -286.348769)
			(xy 122.7455 -286.302495) (xy 122.776026 -286.260479) (xy 122.812749 -286.223756) (xy 122.854765 -286.19323)
			(xy 122.901039 -286.169652) (xy 122.950432 -286.153604) (xy 123.001727 -286.145479) (xy 123.053661 -286.145479)
			(xy 123.104956 -286.153604) (xy 123.154349 -286.169652) (xy 123.200623 -286.19323) (xy 123.242639 -286.223756)
			(xy 123.279362 -286.260479) (xy 123.309888 -286.302495) (xy 123.333466 -286.348769) (xy 123.349514 -286.398162)
			(xy 123.357639 -286.449457) (xy 123.358148 -286.475424) (xy 123.637294 -286.475424) (xy 123.637754 -286.449973)
			(xy 123.645542 -286.39967) (xy 123.660952 -286.351157) (xy 123.68362 -286.305582) (xy 123.71301 -286.264021)
			(xy 123.748426 -286.22746) (xy 123.78903 -286.196763) (xy 123.833862 -286.172657) (xy 123.88186 -286.155711)
			(xy 123.906788 -286.150558) (xy 123.929648 -286.14624) (xy 124.133356 -285.79318) (xy 124.125736 -285.771082)
			(xy 124.116995 -285.744495) (xy 124.107549 -285.689335) (xy 124.10694 -285.661354) (xy 124.107449 -285.635387)
			(xy 124.115574 -285.584092) (xy 124.131622 -285.534699) (xy 124.1552 -285.488425) (xy 124.185726 -285.446409)
			(xy 124.222449 -285.409686) (xy 124.264465 -285.37916) (xy 124.310739 -285.355582) (xy 124.360132 -285.339534)
			(xy 124.411427 -285.331409) (xy 124.463361 -285.331409) (xy 124.514656 -285.339534) (xy 124.564049 -285.355582)
			(xy 124.610323 -285.37916) (xy 124.652339 -285.409686) (xy 124.689062 -285.446409) (xy 124.719588 -285.488425)
			(xy 124.743166 -285.534699) (xy 124.759214 -285.584092) (xy 124.767339 -285.635387) (xy 124.767848 -285.661354)
			(xy 124.767415 -285.686807) (xy 124.759629 -285.737113) (xy 124.744218 -285.785629) (xy 124.721548 -285.831208)
			(xy 124.692155 -285.87277) (xy 124.656735 -285.909331) (xy 124.616125 -285.940027) (xy 124.571288 -285.96413)
			(xy 124.523285 -285.98107) (xy 124.498354 -285.98622) (xy 124.475494 -285.990538) (xy 124.271786 -286.343598)
			(xy 124.279406 -286.365696) (xy 124.288143 -286.392284) (xy 124.297591 -286.447444) (xy 124.298202 -286.475424)
			(xy 124.297693 -286.501391) (xy 124.577349 -286.501391) (xy 124.577349 -286.449457) (xy 124.585474 -286.398162)
			(xy 124.601522 -286.348769) (xy 124.6251 -286.302495) (xy 124.655626 -286.260479) (xy 124.692349 -286.223756)
			(xy 124.734365 -286.19323) (xy 124.780639 -286.169652) (xy 124.830032 -286.153604) (xy 124.881327 -286.145479)
			(xy 124.933261 -286.145479) (xy 124.984556 -286.153604) (xy 125.033949 -286.169652) (xy 125.080223 -286.19323)
			(xy 125.122239 -286.223756) (xy 125.158962 -286.260479) (xy 125.189488 -286.302495) (xy 125.213066 -286.348769)
			(xy 125.229114 -286.398162) (xy 125.237239 -286.449457) (xy 125.237748 -286.475424) (xy 125.516894 -286.475424)
			(xy 125.517354 -286.449973) (xy 125.525142 -286.39967) (xy 125.540552 -286.351157) (xy 125.56322 -286.305582)
			(xy 125.59261 -286.264021) (xy 125.628026 -286.22746) (xy 125.66863 -286.196763) (xy 125.713462 -286.172657)
			(xy 125.76146 -286.155711) (xy 125.786388 -286.150558) (xy 125.809248 -286.14624) (xy 126.012956 -285.79318)
			(xy 126.005336 -285.771082) (xy 125.996595 -285.744495) (xy 125.987149 -285.689335) (xy 125.98654 -285.661354)
			(xy 125.987049 -285.635387) (xy 125.995174 -285.584092) (xy 126.011222 -285.534699) (xy 126.0348 -285.488425)
			(xy 126.065326 -285.446409) (xy 126.102049 -285.409686) (xy 126.144065 -285.37916) (xy 126.190339 -285.355582)
			(xy 126.239732 -285.339534) (xy 126.291027 -285.331409) (xy 126.342961 -285.331409) (xy 126.394256 -285.339534)
			(xy 126.443649 -285.355582) (xy 126.489923 -285.37916) (xy 126.531939 -285.409686) (xy 126.568662 -285.446409)
			(xy 126.599188 -285.488425) (xy 126.622766 -285.534699) (xy 126.638814 -285.584092) (xy 126.646939 -285.635387)
			(xy 126.647448 -285.661354) (xy 126.647015 -285.686807) (xy 126.639229 -285.737113) (xy 126.623818 -285.785629)
			(xy 126.601148 -285.831208) (xy 126.571755 -285.87277) (xy 126.536335 -285.909331) (xy 126.495725 -285.940027)
			(xy 126.450888 -285.96413) (xy 126.402885 -285.98107) (xy 126.377954 -285.98622) (xy 126.355094 -285.990538)
			(xy 126.151386 -286.343598) (xy 126.159006 -286.365696) (xy 126.167743 -286.392284) (xy 126.177191 -286.447444)
			(xy 126.177802 -286.475424) (xy 126.177293 -286.501391) (xy 126.456949 -286.501391) (xy 126.456949 -286.449457)
			(xy 126.465074 -286.398162) (xy 126.481122 -286.348769) (xy 126.5047 -286.302495) (xy 126.535226 -286.260479)
			(xy 126.571949 -286.223756) (xy 126.613965 -286.19323) (xy 126.660239 -286.169652) (xy 126.709632 -286.153604)
			(xy 126.760927 -286.145479) (xy 126.812861 -286.145479) (xy 126.864156 -286.153604) (xy 126.913549 -286.169652)
			(xy 126.959823 -286.19323) (xy 127.001839 -286.223756) (xy 127.038562 -286.260479) (xy 127.069088 -286.302495)
			(xy 127.092666 -286.348769) (xy 127.108714 -286.398162) (xy 127.116839 -286.449457) (xy 127.117348 -286.475424)
			(xy 127.396494 -286.475424) (xy 127.396954 -286.449973) (xy 127.404742 -286.39967) (xy 127.420152 -286.351157)
			(xy 127.44282 -286.305582) (xy 127.47221 -286.264021) (xy 127.507626 -286.22746) (xy 127.54823 -286.196763)
			(xy 127.593062 -286.172657) (xy 127.64106 -286.155711) (xy 127.665988 -286.150558) (xy 127.688848 -286.14624)
			(xy 127.892556 -285.79318) (xy 127.884936 -285.771082) (xy 127.876195 -285.744495) (xy 127.866749 -285.689335)
			(xy 127.86614 -285.661354) (xy 127.866649 -285.635387) (xy 127.874774 -285.584092) (xy 127.890822 -285.534699)
			(xy 127.9144 -285.488425) (xy 127.944926 -285.446409) (xy 127.981649 -285.409686) (xy 128.023665 -285.37916)
			(xy 128.069939 -285.355582) (xy 128.119332 -285.339534) (xy 128.170627 -285.331409) (xy 128.222561 -285.331409)
			(xy 128.273856 -285.339534) (xy 128.323249 -285.355582) (xy 128.369523 -285.37916) (xy 128.411539 -285.409686)
			(xy 128.448262 -285.446409) (xy 128.478788 -285.488425) (xy 128.502366 -285.534699) (xy 128.518414 -285.584092)
			(xy 128.526539 -285.635387) (xy 128.527048 -285.661354) (xy 128.526615 -285.686807) (xy 128.518829 -285.737113)
			(xy 128.503418 -285.785629) (xy 128.480748 -285.831208) (xy 128.451355 -285.87277) (xy 128.415935 -285.909331)
			(xy 128.375325 -285.940027) (xy 128.330488 -285.96413) (xy 128.282485 -285.98107) (xy 128.257554 -285.98622)
			(xy 128.234694 -285.990538) (xy 128.030986 -286.343598) (xy 128.038606 -286.365696) (xy 128.047343 -286.392284)
			(xy 128.056791 -286.447444) (xy 128.057402 -286.475424) (xy 128.056893 -286.501391) (xy 128.336549 -286.501391)
			(xy 128.336549 -286.449457) (xy 128.344674 -286.398162) (xy 128.360722 -286.348769) (xy 128.3843 -286.302495)
			(xy 128.414826 -286.260479) (xy 128.451549 -286.223756) (xy 128.493565 -286.19323) (xy 128.539839 -286.169652)
			(xy 128.589232 -286.153604) (xy 128.640527 -286.145479) (xy 128.692461 -286.145479) (xy 128.743756 -286.153604)
			(xy 128.793149 -286.169652) (xy 128.839423 -286.19323) (xy 128.881439 -286.223756) (xy 128.918162 -286.260479)
			(xy 128.948688 -286.302495) (xy 128.972266 -286.348769) (xy 128.988314 -286.398162) (xy 128.996439 -286.449457)
			(xy 128.996948 -286.475424) (xy 129.276094 -286.475424) (xy 129.276554 -286.449973) (xy 129.284342 -286.39967)
			(xy 129.299752 -286.351157) (xy 129.32242 -286.305582) (xy 129.35181 -286.264021) (xy 129.387226 -286.22746)
			(xy 129.42783 -286.196763) (xy 129.472662 -286.172657) (xy 129.52066 -286.155711) (xy 129.545588 -286.150558)
			(xy 129.568448 -286.14624) (xy 129.772156 -285.79318) (xy 129.764536 -285.771082) (xy 129.755795 -285.744495)
			(xy 129.746349 -285.689335) (xy 129.74574 -285.661354) (xy 129.746249 -285.635387) (xy 129.754374 -285.584092)
			(xy 129.770422 -285.534699) (xy 129.794 -285.488425) (xy 129.824526 -285.446409) (xy 129.861249 -285.409686)
			(xy 129.903265 -285.37916) (xy 129.949539 -285.355582) (xy 129.998932 -285.339534) (xy 130.050227 -285.331409)
			(xy 130.102161 -285.331409) (xy 130.153456 -285.339534) (xy 130.202849 -285.355582) (xy 130.249123 -285.37916)
			(xy 130.291139 -285.409686) (xy 130.327862 -285.446409) (xy 130.358388 -285.488425) (xy 130.381966 -285.534699)
			(xy 130.398014 -285.584092) (xy 130.406139 -285.635387) (xy 130.406648 -285.661354) (xy 130.406215 -285.686807)
			(xy 130.398429 -285.737113) (xy 130.383018 -285.785629) (xy 130.360348 -285.831208) (xy 130.330955 -285.87277)
			(xy 130.295535 -285.909331) (xy 130.254925 -285.940027) (xy 130.210088 -285.96413) (xy 130.162085 -285.98107)
			(xy 130.137154 -285.98622) (xy 130.114294 -285.990538) (xy 129.910586 -286.343598) (xy 129.918206 -286.365696)
			(xy 129.926943 -286.392284) (xy 129.936391 -286.447444) (xy 129.937002 -286.475424) (xy 129.936493 -286.501391)
			(xy 130.216149 -286.501391) (xy 130.216149 -286.449457) (xy 130.224274 -286.398162) (xy 130.240322 -286.348769)
			(xy 130.2639 -286.302495) (xy 130.294426 -286.260479) (xy 130.331149 -286.223756) (xy 130.373165 -286.19323)
			(xy 130.419439 -286.169652) (xy 130.468832 -286.153604) (xy 130.520127 -286.145479) (xy 130.572061 -286.145479)
			(xy 130.623356 -286.153604) (xy 130.672749 -286.169652) (xy 130.719023 -286.19323) (xy 130.761039 -286.223756)
			(xy 130.797762 -286.260479) (xy 130.828288 -286.302495) (xy 130.851866 -286.348769) (xy 130.867914 -286.398162)
			(xy 130.876039 -286.449457) (xy 130.876548 -286.475424) (xy 131.155694 -286.475424) (xy 131.156154 -286.449973)
			(xy 131.163942 -286.39967) (xy 131.179352 -286.351157) (xy 131.20202 -286.305582) (xy 131.23141 -286.264021)
			(xy 131.266826 -286.22746) (xy 131.30743 -286.196763) (xy 131.352262 -286.172657) (xy 131.40026 -286.155711)
			(xy 131.425188 -286.150558) (xy 131.448048 -286.14624) (xy 131.651756 -285.79318) (xy 131.644136 -285.771082)
			(xy 131.635395 -285.744495) (xy 131.625949 -285.689335) (xy 131.62534 -285.661354) (xy 131.625849 -285.635387)
			(xy 131.633974 -285.584092) (xy 131.650022 -285.534699) (xy 131.6736 -285.488425) (xy 131.704126 -285.446409)
			(xy 131.740849 -285.409686) (xy 131.782865 -285.37916) (xy 131.829139 -285.355582) (xy 131.878532 -285.339534)
			(xy 131.929827 -285.331409) (xy 131.981761 -285.331409) (xy 132.033056 -285.339534) (xy 132.082449 -285.355582)
			(xy 132.128723 -285.37916) (xy 132.170739 -285.409686) (xy 132.207462 -285.446409) (xy 132.237988 -285.488425)
			(xy 132.261566 -285.534699) (xy 132.277614 -285.584092) (xy 132.285739 -285.635387) (xy 132.286248 -285.661354)
			(xy 132.285815 -285.686807) (xy 132.278029 -285.737113) (xy 132.262618 -285.785629) (xy 132.239948 -285.831208)
			(xy 132.210555 -285.87277) (xy 132.175135 -285.909331) (xy 132.134525 -285.940027) (xy 132.089688 -285.96413)
			(xy 132.041685 -285.98107) (xy 132.016754 -285.98622) (xy 131.993894 -285.990538) (xy 131.790186 -286.343598)
			(xy 131.797806 -286.365696) (xy 131.806543 -286.392284) (xy 131.815991 -286.447444) (xy 131.816602 -286.475424)
			(xy 131.816093 -286.501391) (xy 132.095749 -286.501391) (xy 132.095749 -286.449457) (xy 132.103874 -286.398162)
			(xy 132.119922 -286.348769) (xy 132.1435 -286.302495) (xy 132.174026 -286.260479) (xy 132.210749 -286.223756)
			(xy 132.252765 -286.19323) (xy 132.299039 -286.169652) (xy 132.348432 -286.153604) (xy 132.399727 -286.145479)
			(xy 132.451661 -286.145479) (xy 132.502956 -286.153604) (xy 132.552349 -286.169652) (xy 132.598623 -286.19323)
			(xy 132.640639 -286.223756) (xy 132.677362 -286.260479) (xy 132.707888 -286.302495) (xy 132.731466 -286.348769)
			(xy 132.747514 -286.398162) (xy 132.755639 -286.449457) (xy 132.756148 -286.475424) (xy 133.035294 -286.475424)
			(xy 133.035754 -286.449973) (xy 133.043542 -286.39967) (xy 133.058952 -286.351157) (xy 133.08162 -286.305582)
			(xy 133.11101 -286.264021) (xy 133.146426 -286.22746) (xy 133.18703 -286.196763) (xy 133.231862 -286.172657)
			(xy 133.27986 -286.155711) (xy 133.304788 -286.150558) (xy 133.327648 -286.14624) (xy 133.531356 -285.79318)
			(xy 133.523736 -285.771082) (xy 133.514995 -285.744495) (xy 133.505549 -285.689335) (xy 133.50494 -285.661354)
			(xy 133.505449 -285.635387) (xy 133.513574 -285.584092) (xy 133.529622 -285.534699) (xy 133.5532 -285.488425)
			(xy 133.583726 -285.446409) (xy 133.620449 -285.409686) (xy 133.662465 -285.37916) (xy 133.708739 -285.355582)
			(xy 133.758132 -285.339534) (xy 133.809427 -285.331409) (xy 133.861361 -285.331409) (xy 133.912656 -285.339534)
			(xy 133.962049 -285.355582) (xy 134.008323 -285.37916) (xy 134.050339 -285.409686) (xy 134.087062 -285.446409)
			(xy 134.117588 -285.488425) (xy 134.141166 -285.534699) (xy 134.157214 -285.584092) (xy 134.165339 -285.635387)
			(xy 134.165848 -285.661354) (xy 134.165415 -285.686807) (xy 134.165335 -285.687321) (xy 134.445249 -285.687321)
			(xy 134.445249 -285.635387) (xy 134.453374 -285.584092) (xy 134.469422 -285.534699) (xy 134.493 -285.488425)
			(xy 134.523526 -285.446409) (xy 134.560249 -285.409686) (xy 134.602265 -285.37916) (xy 134.648539 -285.355582)
			(xy 134.697932 -285.339534) (xy 134.749227 -285.331409) (xy 134.801161 -285.331409) (xy 134.852456 -285.339534)
			(xy 134.901849 -285.355582) (xy 134.948123 -285.37916) (xy 134.990139 -285.409686) (xy 135.026862 -285.446409)
			(xy 135.057388 -285.488425) (xy 135.080966 -285.534699) (xy 135.097014 -285.584092) (xy 135.105139 -285.635387)
			(xy 135.105648 -285.661354) (xy 135.105139 -285.687321) (xy 135.097014 -285.738616) (xy 135.080966 -285.788009)
			(xy 135.057388 -285.834283) (xy 135.026862 -285.876299) (xy 134.990139 -285.913022) (xy 134.948123 -285.943548)
			(xy 134.901849 -285.967126) (xy 134.852456 -285.983174) (xy 134.801161 -285.991299) (xy 134.749227 -285.991299)
			(xy 134.697932 -285.983174) (xy 134.648539 -285.967126) (xy 134.602265 -285.943548) (xy 134.560249 -285.913022)
			(xy 134.523526 -285.876299) (xy 134.493 -285.834283) (xy 134.469422 -285.788009) (xy 134.453374 -285.738616)
			(xy 134.445249 -285.687321) (xy 134.165335 -285.687321) (xy 134.157629 -285.737113) (xy 134.142218 -285.785629)
			(xy 134.119548 -285.831208) (xy 134.090155 -285.87277) (xy 134.054735 -285.909331) (xy 134.014125 -285.940027)
			(xy 133.969288 -285.96413) (xy 133.921285 -285.98107) (xy 133.896354 -285.98622) (xy 133.873494 -285.990538)
			(xy 133.669786 -286.343598) (xy 133.677406 -286.365696) (xy 133.686143 -286.392284) (xy 133.695591 -286.447444)
			(xy 133.696202 -286.475424) (xy 133.695693 -286.501391) (xy 133.975349 -286.501391) (xy 133.975349 -286.449457)
			(xy 133.983474 -286.398162) (xy 133.999522 -286.348769) (xy 134.0231 -286.302495) (xy 134.053626 -286.260479)
			(xy 134.090349 -286.223756) (xy 134.132365 -286.19323) (xy 134.178639 -286.169652) (xy 134.228032 -286.153604)
			(xy 134.279327 -286.145479) (xy 134.331261 -286.145479) (xy 134.382556 -286.153604) (xy 134.431949 -286.169652)
			(xy 134.478223 -286.19323) (xy 134.520239 -286.223756) (xy 134.556962 -286.260479) (xy 134.587488 -286.302495)
			(xy 134.611066 -286.348769) (xy 134.627114 -286.398162) (xy 134.635239 -286.449457) (xy 134.635748 -286.475424)
			(xy 134.635244 -286.501137) (xy 134.915149 -286.501137) (xy 134.915149 -286.449203) (xy 134.923274 -286.397908)
			(xy 134.939322 -286.348515) (xy 134.9629 -286.302241) (xy 134.993426 -286.260225) (xy 135.030149 -286.223502)
			(xy 135.072165 -286.192976) (xy 135.118439 -286.169398) (xy 135.167832 -286.15335) (xy 135.219127 -286.145225)
			(xy 135.271061 -286.145225) (xy 135.322356 -286.15335) (xy 135.371749 -286.169398) (xy 135.418023 -286.192976)
			(xy 135.460039 -286.223502) (xy 135.496762 -286.260225) (xy 135.527288 -286.302241) (xy 135.550866 -286.348515)
			(xy 135.566914 -286.397908) (xy 135.575039 -286.449203) (xy 135.575548 -286.47517) (xy 135.575039 -286.501137)
			(xy 135.566914 -286.552432) (xy 135.550866 -286.601825) (xy 135.527288 -286.648099) (xy 135.496762 -286.690115)
			(xy 135.460039 -286.726838) (xy 135.418023 -286.757364) (xy 135.371749 -286.780942) (xy 135.322356 -286.79699)
			(xy 135.271061 -286.805115) (xy 135.219127 -286.805115) (xy 135.167832 -286.79699) (xy 135.118439 -286.780942)
			(xy 135.072165 -286.757364) (xy 135.030149 -286.726838) (xy 134.993426 -286.690115) (xy 134.9629 -286.648099)
			(xy 134.939322 -286.601825) (xy 134.923274 -286.552432) (xy 134.915149 -286.501137) (xy 134.635244 -286.501137)
			(xy 134.635239 -286.501391) (xy 134.627114 -286.552686) (xy 134.611066 -286.602079) (xy 134.587488 -286.648353)
			(xy 134.556962 -286.690369) (xy 134.520239 -286.727092) (xy 134.478223 -286.757618) (xy 134.431949 -286.781196)
			(xy 134.382556 -286.797244) (xy 134.331261 -286.805369) (xy 134.279327 -286.805369) (xy 134.228032 -286.797244)
			(xy 134.178639 -286.781196) (xy 134.132365 -286.757618) (xy 134.090349 -286.727092) (xy 134.053626 -286.690369)
			(xy 134.0231 -286.648353) (xy 133.999522 -286.602079) (xy 133.983474 -286.552686) (xy 133.975349 -286.501391)
			(xy 133.695693 -286.501391) (xy 133.687568 -286.552686) (xy 133.67152 -286.602079) (xy 133.647942 -286.648353)
			(xy 133.617416 -286.690369) (xy 133.580693 -286.727092) (xy 133.538677 -286.757618) (xy 133.492403 -286.781196)
			(xy 133.44301 -286.797244) (xy 133.391715 -286.805369) (xy 133.339781 -286.805369) (xy 133.288486 -286.797244)
			(xy 133.239093 -286.781196) (xy 133.192819 -286.757618) (xy 133.150803 -286.727092) (xy 133.11408 -286.690369)
			(xy 133.083554 -286.648353) (xy 133.059976 -286.602079) (xy 133.043928 -286.552686) (xy 133.035803 -286.501391)
			(xy 133.035294 -286.475424) (xy 132.756148 -286.475424) (xy 132.755639 -286.501391) (xy 132.747514 -286.552686)
			(xy 132.731466 -286.602079) (xy 132.707888 -286.648353) (xy 132.677362 -286.690369) (xy 132.640639 -286.727092)
			(xy 132.598623 -286.757618) (xy 132.552349 -286.781196) (xy 132.502956 -286.797244) (xy 132.451661 -286.805369)
			(xy 132.399727 -286.805369) (xy 132.348432 -286.797244) (xy 132.299039 -286.781196) (xy 132.252765 -286.757618)
			(xy 132.210749 -286.727092) (xy 132.174026 -286.690369) (xy 132.1435 -286.648353) (xy 132.119922 -286.602079)
			(xy 132.103874 -286.552686) (xy 132.095749 -286.501391) (xy 131.816093 -286.501391) (xy 131.807968 -286.552686)
			(xy 131.79192 -286.602079) (xy 131.768342 -286.648353) (xy 131.737816 -286.690369) (xy 131.701093 -286.727092)
			(xy 131.659077 -286.757618) (xy 131.612803 -286.781196) (xy 131.56341 -286.797244) (xy 131.512115 -286.805369)
			(xy 131.460181 -286.805369) (xy 131.408886 -286.797244) (xy 131.359493 -286.781196) (xy 131.313219 -286.757618)
			(xy 131.271203 -286.727092) (xy 131.23448 -286.690369) (xy 131.203954 -286.648353) (xy 131.180376 -286.602079)
			(xy 131.164328 -286.552686) (xy 131.156203 -286.501391) (xy 131.155694 -286.475424) (xy 130.876548 -286.475424)
			(xy 130.876039 -286.501391) (xy 130.867914 -286.552686) (xy 130.851866 -286.602079) (xy 130.828288 -286.648353)
			(xy 130.797762 -286.690369) (xy 130.761039 -286.727092) (xy 130.719023 -286.757618) (xy 130.672749 -286.781196)
			(xy 130.623356 -286.797244) (xy 130.572061 -286.805369) (xy 130.520127 -286.805369) (xy 130.468832 -286.797244)
			(xy 130.419439 -286.781196) (xy 130.373165 -286.757618) (xy 130.331149 -286.727092) (xy 130.294426 -286.690369)
			(xy 130.2639 -286.648353) (xy 130.240322 -286.602079) (xy 130.224274 -286.552686) (xy 130.216149 -286.501391)
			(xy 129.936493 -286.501391) (xy 129.928368 -286.552686) (xy 129.91232 -286.602079) (xy 129.888742 -286.648353)
			(xy 129.858216 -286.690369) (xy 129.821493 -286.727092) (xy 129.779477 -286.757618) (xy 129.733203 -286.781196)
			(xy 129.68381 -286.797244) (xy 129.632515 -286.805369) (xy 129.580581 -286.805369) (xy 129.529286 -286.797244)
			(xy 129.479893 -286.781196) (xy 129.433619 -286.757618) (xy 129.391603 -286.727092) (xy 129.35488 -286.690369)
			(xy 129.324354 -286.648353) (xy 129.300776 -286.602079) (xy 129.284728 -286.552686) (xy 129.276603 -286.501391)
			(xy 129.276094 -286.475424) (xy 128.996948 -286.475424) (xy 128.996439 -286.501391) (xy 128.988314 -286.552686)
			(xy 128.972266 -286.602079) (xy 128.948688 -286.648353) (xy 128.918162 -286.690369) (xy 128.881439 -286.727092)
			(xy 128.839423 -286.757618) (xy 128.793149 -286.781196) (xy 128.743756 -286.797244) (xy 128.692461 -286.805369)
			(xy 128.640527 -286.805369) (xy 128.589232 -286.797244) (xy 128.539839 -286.781196) (xy 128.493565 -286.757618)
			(xy 128.451549 -286.727092) (xy 128.414826 -286.690369) (xy 128.3843 -286.648353) (xy 128.360722 -286.602079)
			(xy 128.344674 -286.552686) (xy 128.336549 -286.501391) (xy 128.056893 -286.501391) (xy 128.048768 -286.552686)
			(xy 128.03272 -286.602079) (xy 128.009142 -286.648353) (xy 127.978616 -286.690369) (xy 127.941893 -286.727092)
			(xy 127.899877 -286.757618) (xy 127.853603 -286.781196) (xy 127.80421 -286.797244) (xy 127.752915 -286.805369)
			(xy 127.700981 -286.805369) (xy 127.649686 -286.797244) (xy 127.600293 -286.781196) (xy 127.554019 -286.757618)
			(xy 127.512003 -286.727092) (xy 127.47528 -286.690369) (xy 127.444754 -286.648353) (xy 127.421176 -286.602079)
			(xy 127.405128 -286.552686) (xy 127.397003 -286.501391) (xy 127.396494 -286.475424) (xy 127.117348 -286.475424)
			(xy 127.116839 -286.501391) (xy 127.108714 -286.552686) (xy 127.092666 -286.602079) (xy 127.069088 -286.648353)
			(xy 127.038562 -286.690369) (xy 127.001839 -286.727092) (xy 126.959823 -286.757618) (xy 126.913549 -286.781196)
			(xy 126.864156 -286.797244) (xy 126.812861 -286.805369) (xy 126.760927 -286.805369) (xy 126.709632 -286.797244)
			(xy 126.660239 -286.781196) (xy 126.613965 -286.757618) (xy 126.571949 -286.727092) (xy 126.535226 -286.690369)
			(xy 126.5047 -286.648353) (xy 126.481122 -286.602079) (xy 126.465074 -286.552686) (xy 126.456949 -286.501391)
			(xy 126.177293 -286.501391) (xy 126.169168 -286.552686) (xy 126.15312 -286.602079) (xy 126.129542 -286.648353)
			(xy 126.099016 -286.690369) (xy 126.062293 -286.727092) (xy 126.020277 -286.757618) (xy 125.974003 -286.781196)
			(xy 125.92461 -286.797244) (xy 125.873315 -286.805369) (xy 125.821381 -286.805369) (xy 125.770086 -286.797244)
			(xy 125.720693 -286.781196) (xy 125.674419 -286.757618) (xy 125.632403 -286.727092) (xy 125.59568 -286.690369)
			(xy 125.565154 -286.648353) (xy 125.541576 -286.602079) (xy 125.525528 -286.552686) (xy 125.517403 -286.501391)
			(xy 125.516894 -286.475424) (xy 125.237748 -286.475424) (xy 125.237239 -286.501391) (xy 125.229114 -286.552686)
			(xy 125.213066 -286.602079) (xy 125.189488 -286.648353) (xy 125.158962 -286.690369) (xy 125.122239 -286.727092)
			(xy 125.080223 -286.757618) (xy 125.033949 -286.781196) (xy 124.984556 -286.797244) (xy 124.933261 -286.805369)
			(xy 124.881327 -286.805369) (xy 124.830032 -286.797244) (xy 124.780639 -286.781196) (xy 124.734365 -286.757618)
			(xy 124.692349 -286.727092) (xy 124.655626 -286.690369) (xy 124.6251 -286.648353) (xy 124.601522 -286.602079)
			(xy 124.585474 -286.552686) (xy 124.577349 -286.501391) (xy 124.297693 -286.501391) (xy 124.289568 -286.552686)
			(xy 124.27352 -286.602079) (xy 124.249942 -286.648353) (xy 124.219416 -286.690369) (xy 124.182693 -286.727092)
			(xy 124.140677 -286.757618) (xy 124.094403 -286.781196) (xy 124.04501 -286.797244) (xy 123.993715 -286.805369)
			(xy 123.941781 -286.805369) (xy 123.890486 -286.797244) (xy 123.841093 -286.781196) (xy 123.794819 -286.757618)
			(xy 123.752803 -286.727092) (xy 123.71608 -286.690369) (xy 123.685554 -286.648353) (xy 123.661976 -286.602079)
			(xy 123.645928 -286.552686) (xy 123.637803 -286.501391) (xy 123.637294 -286.475424) (xy 123.358148 -286.475424)
			(xy 123.357639 -286.501391) (xy 123.349514 -286.552686) (xy 123.333466 -286.602079) (xy 123.309888 -286.648353)
			(xy 123.279362 -286.690369) (xy 123.242639 -286.727092) (xy 123.200623 -286.757618) (xy 123.154349 -286.781196)
			(xy 123.104956 -286.797244) (xy 123.053661 -286.805369) (xy 123.001727 -286.805369) (xy 122.950432 -286.797244)
			(xy 122.901039 -286.781196) (xy 122.854765 -286.757618) (xy 122.812749 -286.727092) (xy 122.776026 -286.690369)
			(xy 122.7455 -286.648353) (xy 122.721922 -286.602079) (xy 122.705874 -286.552686) (xy 122.697749 -286.501391)
			(xy 122.418091 -286.501391) (xy 122.409964 -286.552686) (xy 122.393914 -286.602079) (xy 122.370336 -286.648353)
			(xy 122.33981 -286.690369) (xy 122.303088 -286.727094) (xy 122.261073 -286.757623) (xy 122.214801 -286.781205)
			(xy 122.16541 -286.797258) (xy 122.114115 -286.805389) (xy 122.088148 -286.805878) (xy 122.052842 -286.8041)
			(xy 122.038653 -286.803052) (xy 122.010634 -286.807929) (xy 121.985045 -286.820339) (xy 121.963865 -286.839319)
			(xy 121.948736 -286.863401) (xy 121.940828 -286.890719) (xy 121.94032 -286.904938) (xy 121.94032 -287.216088)
			(xy 121.941336 -287.221422) (xy 121.944633 -287.238183) (xy 121.948191 -287.272159) (xy 121.948448 -287.28924)
			(xy 121.947936 -287.315207) (xy 122.227849 -287.315207) (xy 122.227849 -287.263273) (xy 122.235974 -287.211978)
			(xy 122.252022 -287.162585) (xy 122.2756 -287.116311) (xy 122.306126 -287.074295) (xy 122.342849 -287.037572)
			(xy 122.384865 -287.007046) (xy 122.431139 -286.983468) (xy 122.480532 -286.96742) (xy 122.531827 -286.959295)
			(xy 122.583761 -286.959295) (xy 122.635056 -286.96742) (xy 122.684449 -286.983468) (xy 122.730723 -287.007046)
			(xy 122.772739 -287.037572) (xy 122.809462 -287.074295) (xy 122.839988 -287.116311) (xy 122.863566 -287.162585)
			(xy 122.879614 -287.211978) (xy 122.887739 -287.263273) (xy 122.888248 -287.28924) (xy 122.887739 -287.315207)
			(xy 123.167649 -287.315207) (xy 123.167649 -287.263273) (xy 123.175774 -287.211978) (xy 123.191822 -287.162585)
			(xy 123.2154 -287.116311) (xy 123.245926 -287.074295) (xy 123.282649 -287.037572) (xy 123.324665 -287.007046)
			(xy 123.370939 -286.983468) (xy 123.420332 -286.96742) (xy 123.471627 -286.959295) (xy 123.523561 -286.959295)
			(xy 123.574856 -286.96742) (xy 123.624249 -286.983468) (xy 123.670523 -287.007046) (xy 123.712539 -287.037572)
			(xy 123.749262 -287.074295) (xy 123.779788 -287.116311) (xy 123.803366 -287.162585) (xy 123.819414 -287.211978)
			(xy 123.827539 -287.263273) (xy 123.828048 -287.28924) (xy 123.827539 -287.315207) (xy 124.107449 -287.315207)
			(xy 124.107449 -287.263273) (xy 124.115574 -287.211978) (xy 124.131622 -287.162585) (xy 124.1552 -287.116311)
			(xy 124.185726 -287.074295) (xy 124.222449 -287.037572) (xy 124.264465 -287.007046) (xy 124.310739 -286.983468)
			(xy 124.360132 -286.96742) (xy 124.411427 -286.959295) (xy 124.463361 -286.959295) (xy 124.514656 -286.96742)
			(xy 124.564049 -286.983468) (xy 124.610323 -287.007046) (xy 124.652339 -287.037572) (xy 124.689062 -287.074295)
			(xy 124.719588 -287.116311) (xy 124.743166 -287.162585) (xy 124.759214 -287.211978) (xy 124.767339 -287.263273)
			(xy 124.767848 -287.28924) (xy 124.767339 -287.315207) (xy 125.047249 -287.315207) (xy 125.047249 -287.263273)
			(xy 125.055374 -287.211978) (xy 125.071422 -287.162585) (xy 125.095 -287.116311) (xy 125.125526 -287.074295)
			(xy 125.162249 -287.037572) (xy 125.204265 -287.007046) (xy 125.250539 -286.983468) (xy 125.299932 -286.96742)
			(xy 125.351227 -286.959295) (xy 125.403161 -286.959295) (xy 125.454456 -286.96742) (xy 125.503849 -286.983468)
			(xy 125.550123 -287.007046) (xy 125.592139 -287.037572) (xy 125.628862 -287.074295) (xy 125.659388 -287.116311)
			(xy 125.682966 -287.162585) (xy 125.699014 -287.211978) (xy 125.707139 -287.263273) (xy 125.707648 -287.28924)
			(xy 125.707139 -287.315207) (xy 125.987049 -287.315207) (xy 125.987049 -287.263273) (xy 125.995174 -287.211978)
			(xy 126.011222 -287.162585) (xy 126.0348 -287.116311) (xy 126.065326 -287.074295) (xy 126.102049 -287.037572)
			(xy 126.144065 -287.007046) (xy 126.190339 -286.983468) (xy 126.239732 -286.96742) (xy 126.291027 -286.959295)
			(xy 126.342961 -286.959295) (xy 126.394256 -286.96742) (xy 126.443649 -286.983468) (xy 126.489923 -287.007046)
			(xy 126.531939 -287.037572) (xy 126.568662 -287.074295) (xy 126.599188 -287.116311) (xy 126.622766 -287.162585)
			(xy 126.638814 -287.211978) (xy 126.646939 -287.263273) (xy 126.647448 -287.28924) (xy 126.646939 -287.315207)
			(xy 126.926849 -287.315207) (xy 126.926849 -287.263273) (xy 126.934974 -287.211978) (xy 126.951022 -287.162585)
			(xy 126.9746 -287.116311) (xy 127.005126 -287.074295) (xy 127.041849 -287.037572) (xy 127.083865 -287.007046)
			(xy 127.130139 -286.983468) (xy 127.179532 -286.96742) (xy 127.230827 -286.959295) (xy 127.282761 -286.959295)
			(xy 127.334056 -286.96742) (xy 127.383449 -286.983468) (xy 127.429723 -287.007046) (xy 127.471739 -287.037572)
			(xy 127.508462 -287.074295) (xy 127.538988 -287.116311) (xy 127.562566 -287.162585) (xy 127.578614 -287.211978)
			(xy 127.586739 -287.263273) (xy 127.587248 -287.28924) (xy 127.586739 -287.315207) (xy 127.866649 -287.315207)
			(xy 127.866649 -287.263273) (xy 127.874774 -287.211978) (xy 127.890822 -287.162585) (xy 127.9144 -287.116311)
			(xy 127.944926 -287.074295) (xy 127.981649 -287.037572) (xy 128.023665 -287.007046) (xy 128.069939 -286.983468)
			(xy 128.119332 -286.96742) (xy 128.170627 -286.959295) (xy 128.222561 -286.959295) (xy 128.273856 -286.96742)
			(xy 128.323249 -286.983468) (xy 128.369523 -287.007046) (xy 128.411539 -287.037572) (xy 128.448262 -287.074295)
			(xy 128.478788 -287.116311) (xy 128.502366 -287.162585) (xy 128.518414 -287.211978) (xy 128.526539 -287.263273)
			(xy 128.527048 -287.28924) (xy 128.526539 -287.315207) (xy 128.806449 -287.315207) (xy 128.806449 -287.263273)
			(xy 128.814574 -287.211978) (xy 128.830622 -287.162585) (xy 128.8542 -287.116311) (xy 128.884726 -287.074295)
			(xy 128.921449 -287.037572) (xy 128.963465 -287.007046) (xy 129.009739 -286.983468) (xy 129.059132 -286.96742)
			(xy 129.110427 -286.959295) (xy 129.162361 -286.959295) (xy 129.213656 -286.96742) (xy 129.263049 -286.983468)
			(xy 129.309323 -287.007046) (xy 129.351339 -287.037572) (xy 129.388062 -287.074295) (xy 129.418588 -287.116311)
			(xy 129.442166 -287.162585) (xy 129.458214 -287.211978) (xy 129.466339 -287.263273) (xy 129.466848 -287.28924)
			(xy 129.466339 -287.315207) (xy 129.746249 -287.315207) (xy 129.746249 -287.263273) (xy 129.754374 -287.211978)
			(xy 129.770422 -287.162585) (xy 129.794 -287.116311) (xy 129.824526 -287.074295) (xy 129.861249 -287.037572)
			(xy 129.903265 -287.007046) (xy 129.949539 -286.983468) (xy 129.998932 -286.96742) (xy 130.050227 -286.959295)
			(xy 130.102161 -286.959295) (xy 130.153456 -286.96742) (xy 130.202849 -286.983468) (xy 130.249123 -287.007046)
			(xy 130.291139 -287.037572) (xy 130.327862 -287.074295) (xy 130.358388 -287.116311) (xy 130.381966 -287.162585)
			(xy 130.398014 -287.211978) (xy 130.406139 -287.263273) (xy 130.406648 -287.28924) (xy 130.406139 -287.315207)
			(xy 130.686049 -287.315207) (xy 130.686049 -287.263273) (xy 130.694174 -287.211978) (xy 130.710222 -287.162585)
			(xy 130.7338 -287.116311) (xy 130.764326 -287.074295) (xy 130.801049 -287.037572) (xy 130.843065 -287.007046)
			(xy 130.889339 -286.983468) (xy 130.938732 -286.96742) (xy 130.990027 -286.959295) (xy 131.041961 -286.959295)
			(xy 131.093256 -286.96742) (xy 131.142649 -286.983468) (xy 131.188923 -287.007046) (xy 131.230939 -287.037572)
			(xy 131.267662 -287.074295) (xy 131.298188 -287.116311) (xy 131.321766 -287.162585) (xy 131.337814 -287.211978)
			(xy 131.345939 -287.263273) (xy 131.346448 -287.28924) (xy 131.345939 -287.315207) (xy 131.625849 -287.315207)
			(xy 131.625849 -287.263273) (xy 131.633974 -287.211978) (xy 131.650022 -287.162585) (xy 131.6736 -287.116311)
			(xy 131.704126 -287.074295) (xy 131.740849 -287.037572) (xy 131.782865 -287.007046) (xy 131.829139 -286.983468)
			(xy 131.878532 -286.96742) (xy 131.929827 -286.959295) (xy 131.981761 -286.959295) (xy 132.033056 -286.96742)
			(xy 132.082449 -286.983468) (xy 132.128723 -287.007046) (xy 132.170739 -287.037572) (xy 132.207462 -287.074295)
			(xy 132.237988 -287.116311) (xy 132.261566 -287.162585) (xy 132.277614 -287.211978) (xy 132.285739 -287.263273)
			(xy 132.286248 -287.28924) (xy 132.285739 -287.315207) (xy 132.565649 -287.315207) (xy 132.565649 -287.263273)
			(xy 132.573774 -287.211978) (xy 132.589822 -287.162585) (xy 132.6134 -287.116311) (xy 132.643926 -287.074295)
			(xy 132.680649 -287.037572) (xy 132.722665 -287.007046) (xy 132.768939 -286.983468) (xy 132.818332 -286.96742)
			(xy 132.869627 -286.959295) (xy 132.921561 -286.959295) (xy 132.972856 -286.96742) (xy 133.022249 -286.983468)
			(xy 133.068523 -287.007046) (xy 133.110539 -287.037572) (xy 133.147262 -287.074295) (xy 133.177788 -287.116311)
			(xy 133.201366 -287.162585) (xy 133.217414 -287.211978) (xy 133.225539 -287.263273) (xy 133.226048 -287.28924)
			(xy 133.225539 -287.315207) (xy 133.505703 -287.315207) (xy 133.505703 -287.263273) (xy 133.513828 -287.211978)
			(xy 133.529876 -287.162585) (xy 133.553454 -287.116311) (xy 133.58398 -287.074295) (xy 133.620703 -287.037572)
			(xy 133.662719 -287.007046) (xy 133.708993 -286.983468) (xy 133.758386 -286.96742) (xy 133.809681 -286.959295)
			(xy 133.861615 -286.959295) (xy 133.91291 -286.96742) (xy 133.962303 -286.983468) (xy 134.008577 -287.007046)
			(xy 134.050593 -287.037572) (xy 134.087316 -287.074295) (xy 134.117842 -287.116311) (xy 134.14142 -287.162585)
			(xy 134.157468 -287.211978) (xy 134.165593 -287.263273) (xy 134.166102 -287.28924) (xy 134.165593 -287.315207)
			(xy 134.445503 -287.315207) (xy 134.445503 -287.263273) (xy 134.453628 -287.211978) (xy 134.469676 -287.162585)
			(xy 134.493254 -287.116311) (xy 134.52378 -287.074295) (xy 134.560503 -287.037572) (xy 134.602519 -287.007046)
			(xy 134.648793 -286.983468) (xy 134.698186 -286.96742) (xy 134.749481 -286.959295) (xy 134.801415 -286.959295)
			(xy 134.85271 -286.96742) (xy 134.902103 -286.983468) (xy 134.948377 -287.007046) (xy 134.990393 -287.037572)
			(xy 135.027116 -287.074295) (xy 135.057642 -287.116311) (xy 135.08122 -287.162585) (xy 135.097268 -287.211978)
			(xy 135.105393 -287.263273) (xy 135.105902 -287.28924) (xy 135.105393 -287.315207) (xy 135.097268 -287.366502)
			(xy 135.08122 -287.415895) (xy 135.057642 -287.462169) (xy 135.027116 -287.504185) (xy 134.990393 -287.540908)
			(xy 134.948377 -287.571434) (xy 134.902103 -287.595012) (xy 134.85271 -287.61106) (xy 134.801415 -287.619185)
			(xy 134.749481 -287.619185) (xy 134.698186 -287.61106) (xy 134.648793 -287.595012) (xy 134.602519 -287.571434)
			(xy 134.560503 -287.540908) (xy 134.52378 -287.504185) (xy 134.493254 -287.462169) (xy 134.469676 -287.415895)
			(xy 134.453628 -287.366502) (xy 134.445503 -287.315207) (xy 134.165593 -287.315207) (xy 134.157468 -287.366502)
			(xy 134.14142 -287.415895) (xy 134.117842 -287.462169) (xy 134.087316 -287.504185) (xy 134.050593 -287.540908)
			(xy 134.008577 -287.571434) (xy 133.962303 -287.595012) (xy 133.91291 -287.61106) (xy 133.861615 -287.619185)
			(xy 133.809681 -287.619185) (xy 133.758386 -287.61106) (xy 133.708993 -287.595012) (xy 133.662719 -287.571434)
			(xy 133.620703 -287.540908) (xy 133.58398 -287.504185) (xy 133.553454 -287.462169) (xy 133.529876 -287.415895)
			(xy 133.513828 -287.366502) (xy 133.505703 -287.315207) (xy 133.225539 -287.315207) (xy 133.217414 -287.366502)
			(xy 133.201366 -287.415895) (xy 133.177788 -287.462169) (xy 133.147262 -287.504185) (xy 133.110539 -287.540908)
			(xy 133.068523 -287.571434) (xy 133.022249 -287.595012) (xy 132.972856 -287.61106) (xy 132.921561 -287.619185)
			(xy 132.869627 -287.619185) (xy 132.818332 -287.61106) (xy 132.768939 -287.595012) (xy 132.722665 -287.571434)
			(xy 132.680649 -287.540908) (xy 132.643926 -287.504185) (xy 132.6134 -287.462169) (xy 132.589822 -287.415895)
			(xy 132.573774 -287.366502) (xy 132.565649 -287.315207) (xy 132.285739 -287.315207) (xy 132.277614 -287.366502)
			(xy 132.261566 -287.415895) (xy 132.237988 -287.462169) (xy 132.207462 -287.504185) (xy 132.170739 -287.540908)
			(xy 132.128723 -287.571434) (xy 132.082449 -287.595012) (xy 132.033056 -287.61106) (xy 131.981761 -287.619185)
			(xy 131.929827 -287.619185) (xy 131.878532 -287.61106) (xy 131.829139 -287.595012) (xy 131.782865 -287.571434)
			(xy 131.740849 -287.540908) (xy 131.704126 -287.504185) (xy 131.6736 -287.462169) (xy 131.650022 -287.415895)
			(xy 131.633974 -287.366502) (xy 131.625849 -287.315207) (xy 131.345939 -287.315207) (xy 131.337814 -287.366502)
			(xy 131.321766 -287.415895) (xy 131.298188 -287.462169) (xy 131.267662 -287.504185) (xy 131.230939 -287.540908)
			(xy 131.188923 -287.571434) (xy 131.142649 -287.595012) (xy 131.093256 -287.61106) (xy 131.041961 -287.619185)
			(xy 130.990027 -287.619185) (xy 130.938732 -287.61106) (xy 130.889339 -287.595012) (xy 130.843065 -287.571434)
			(xy 130.801049 -287.540908) (xy 130.764326 -287.504185) (xy 130.7338 -287.462169) (xy 130.710222 -287.415895)
			(xy 130.694174 -287.366502) (xy 130.686049 -287.315207) (xy 130.406139 -287.315207) (xy 130.398014 -287.366502)
			(xy 130.381966 -287.415895) (xy 130.358388 -287.462169) (xy 130.327862 -287.504185) (xy 130.291139 -287.540908)
			(xy 130.249123 -287.571434) (xy 130.202849 -287.595012) (xy 130.153456 -287.61106) (xy 130.102161 -287.619185)
			(xy 130.050227 -287.619185) (xy 129.998932 -287.61106) (xy 129.949539 -287.595012) (xy 129.903265 -287.571434)
			(xy 129.861249 -287.540908) (xy 129.824526 -287.504185) (xy 129.794 -287.462169) (xy 129.770422 -287.415895)
			(xy 129.754374 -287.366502) (xy 129.746249 -287.315207) (xy 129.466339 -287.315207) (xy 129.458214 -287.366502)
			(xy 129.442166 -287.415895) (xy 129.418588 -287.462169) (xy 129.388062 -287.504185) (xy 129.351339 -287.540908)
			(xy 129.309323 -287.571434) (xy 129.263049 -287.595012) (xy 129.213656 -287.61106) (xy 129.162361 -287.619185)
			(xy 129.110427 -287.619185) (xy 129.059132 -287.61106) (xy 129.009739 -287.595012) (xy 128.963465 -287.571434)
			(xy 128.921449 -287.540908) (xy 128.884726 -287.504185) (xy 128.8542 -287.462169) (xy 128.830622 -287.415895)
			(xy 128.814574 -287.366502) (xy 128.806449 -287.315207) (xy 128.526539 -287.315207) (xy 128.518414 -287.366502)
			(xy 128.502366 -287.415895) (xy 128.478788 -287.462169) (xy 128.448262 -287.504185) (xy 128.411539 -287.540908)
			(xy 128.369523 -287.571434) (xy 128.323249 -287.595012) (xy 128.273856 -287.61106) (xy 128.222561 -287.619185)
			(xy 128.170627 -287.619185) (xy 128.119332 -287.61106) (xy 128.069939 -287.595012) (xy 128.023665 -287.571434)
			(xy 127.981649 -287.540908) (xy 127.944926 -287.504185) (xy 127.9144 -287.462169) (xy 127.890822 -287.415895)
			(xy 127.874774 -287.366502) (xy 127.866649 -287.315207) (xy 127.586739 -287.315207) (xy 127.578614 -287.366502)
			(xy 127.562566 -287.415895) (xy 127.538988 -287.462169) (xy 127.508462 -287.504185) (xy 127.471739 -287.540908)
			(xy 127.429723 -287.571434) (xy 127.383449 -287.595012) (xy 127.334056 -287.61106) (xy 127.282761 -287.619185)
			(xy 127.230827 -287.619185) (xy 127.179532 -287.61106) (xy 127.130139 -287.595012) (xy 127.083865 -287.571434)
			(xy 127.041849 -287.540908) (xy 127.005126 -287.504185) (xy 126.9746 -287.462169) (xy 126.951022 -287.415895)
			(xy 126.934974 -287.366502) (xy 126.926849 -287.315207) (xy 126.646939 -287.315207) (xy 126.638814 -287.366502)
			(xy 126.622766 -287.415895) (xy 126.599188 -287.462169) (xy 126.568662 -287.504185) (xy 126.531939 -287.540908)
			(xy 126.489923 -287.571434) (xy 126.443649 -287.595012) (xy 126.394256 -287.61106) (xy 126.342961 -287.619185)
			(xy 126.291027 -287.619185) (xy 126.239732 -287.61106) (xy 126.190339 -287.595012) (xy 126.144065 -287.571434)
			(xy 126.102049 -287.540908) (xy 126.065326 -287.504185) (xy 126.0348 -287.462169) (xy 126.011222 -287.415895)
			(xy 125.995174 -287.366502) (xy 125.987049 -287.315207) (xy 125.707139 -287.315207) (xy 125.699014 -287.366502)
			(xy 125.682966 -287.415895) (xy 125.659388 -287.462169) (xy 125.628862 -287.504185) (xy 125.592139 -287.540908)
			(xy 125.550123 -287.571434) (xy 125.503849 -287.595012) (xy 125.454456 -287.61106) (xy 125.403161 -287.619185)
			(xy 125.351227 -287.619185) (xy 125.299932 -287.61106) (xy 125.250539 -287.595012) (xy 125.204265 -287.571434)
			(xy 125.162249 -287.540908) (xy 125.125526 -287.504185) (xy 125.095 -287.462169) (xy 125.071422 -287.415895)
			(xy 125.055374 -287.366502) (xy 125.047249 -287.315207) (xy 124.767339 -287.315207) (xy 124.759214 -287.366502)
			(xy 124.743166 -287.415895) (xy 124.719588 -287.462169) (xy 124.689062 -287.504185) (xy 124.652339 -287.540908)
			(xy 124.610323 -287.571434) (xy 124.564049 -287.595012) (xy 124.514656 -287.61106) (xy 124.463361 -287.619185)
			(xy 124.411427 -287.619185) (xy 124.360132 -287.61106) (xy 124.310739 -287.595012) (xy 124.264465 -287.571434)
			(xy 124.222449 -287.540908) (xy 124.185726 -287.504185) (xy 124.1552 -287.462169) (xy 124.131622 -287.415895)
			(xy 124.115574 -287.366502) (xy 124.107449 -287.315207) (xy 123.827539 -287.315207) (xy 123.819414 -287.366502)
			(xy 123.803366 -287.415895) (xy 123.779788 -287.462169) (xy 123.749262 -287.504185) (xy 123.712539 -287.540908)
			(xy 123.670523 -287.571434) (xy 123.624249 -287.595012) (xy 123.574856 -287.61106) (xy 123.523561 -287.619185)
			(xy 123.471627 -287.619185) (xy 123.420332 -287.61106) (xy 123.370939 -287.595012) (xy 123.324665 -287.571434)
			(xy 123.282649 -287.540908) (xy 123.245926 -287.504185) (xy 123.2154 -287.462169) (xy 123.191822 -287.415895)
			(xy 123.175774 -287.366502) (xy 123.167649 -287.315207) (xy 122.887739 -287.315207) (xy 122.879614 -287.366502)
			(xy 122.863566 -287.415895) (xy 122.839988 -287.462169) (xy 122.809462 -287.504185) (xy 122.772739 -287.540908)
			(xy 122.730723 -287.571434) (xy 122.684449 -287.595012) (xy 122.635056 -287.61106) (xy 122.583761 -287.619185)
			(xy 122.531827 -287.619185) (xy 122.480532 -287.61106) (xy 122.431139 -287.595012) (xy 122.384865 -287.571434)
			(xy 122.342849 -287.540908) (xy 122.306126 -287.504185) (xy 122.2756 -287.462169) (xy 122.252022 -287.415895)
			(xy 122.235974 -287.366502) (xy 122.227849 -287.315207) (xy 121.947936 -287.315207) (xy 121.947917 -287.316146)
			(xy 121.939196 -287.369248) (xy 121.921991 -287.420237) (xy 121.896757 -287.467767) (xy 121.864159 -287.510583)
			(xy 121.825058 -287.547555) (xy 121.780486 -287.577707) (xy 121.731619 -287.600244) (xy 121.679748 -287.61457)
			(xy 121.653046 -287.617916) (xy 121.60758 -287.622742) (xy 121.60758 -288.503868) (xy 121.656094 -288.587942)
			(xy 121.679208 -288.59226) (xy 121.706181 -288.597879) (xy 121.757896 -288.616877) (xy 121.805744 -288.644189)
			(xy 121.848398 -288.679059) (xy 121.884678 -288.720521) (xy 121.913578 -288.767427) (xy 121.934297 -288.818477)
			(xy 121.940828 -288.845244) (xy 121.949718 -288.884868) (xy 122.226578 -288.884868)
		)
		(stroke
			(width 0)
			(type solid)
		)
		(fill yes)
		(layer "In11.Cu")
		(net "PVCCFA_EHV_FIVRA_CPU1")
	)
	(gr_poly
		(pts
			(xy 55.465218 -366.907572) (xy 55.465218 -366.84712) (xy 55.456836 -366.83442) (xy 55.44189 -366.810903)
			(xy 55.418243 -366.760451) (xy 55.402192 -366.707093) (xy 55.394079 -366.651968) (xy 55.39359 -366.624108)
			(xy 55.39359 -366.619282) (xy 55.394402 -366.592256) (xy 55.402712 -366.538829) (xy 55.418481 -366.487111)
			(xy 55.441393 -366.438138) (xy 55.47099 -366.392889) (xy 55.506679 -366.352272) (xy 55.547744 -366.3171)
			(xy 55.593363 -366.288078) (xy 55.642623 -366.265787) (xy 55.694537 -366.250673) (xy 55.748064 -366.24304)
			(xy 55.802132 -366.24304) (xy 55.855659 -366.250673) (xy 55.907573 -366.265787) (xy 55.956833 -366.288078)
			(xy 56.002452 -366.3171) (xy 56.043517 -366.352272) (xy 56.079206 -366.392889) (xy 56.108803 -366.438138)
			(xy 56.131715 -366.487111) (xy 56.147484 -366.538829) (xy 56.155794 -366.592256) (xy 56.156606 -366.619282)
			(xy 56.156606 -366.624362) (xy 56.156041 -366.654075) (xy 56.146828 -366.712781) (xy 56.128619 -366.769348)
			(xy 56.101855 -366.822405) (xy 56.084978 -366.846866) (xy 56.06669 -366.872266) (xy 56.136286 -367.007648)
			(xy 56.6928 -367.007648) (xy 57.861708 -365.83874) (xy 57.861708 -362.452158) (xy 57.780428 -360.855006)
			(xy 56.090566 -356.77475) (xy 56.087264 -356.766368) (xy 56.07923 -356.744579) (xy 56.067931 -356.699534)
			(xy 56.062232 -356.653444) (xy 56.061864 -356.630224) (xy 56.061864 -337.711288) (xy 54.921404 -334.973676)
			(xy 54.918102 -334.965802) (xy 54.661308 -334.672686) (xy 54.196234 -334.141318) (xy 54.066694 -333.99349)
			(xy 35.595814 -333.99349) (xy 34.902394 -334.68691) (xy 34.902394 -335.51361) (xy 39.617392 -335.51361)
			(xy 39.617392 -335.428914) (xy 39.625443 -335.3446) (xy 39.641472 -335.261434) (xy 39.665333 -335.180167)
			(xy 39.696812 -335.101537) (xy 39.735623 -335.026256) (xy 39.781413 -334.955004) (xy 39.833769 -334.888428)
			(xy 39.892217 -334.82713) (xy 39.956227 -334.771665) (xy 40.025219 -334.722536) (xy 40.098569 -334.680187)
			(xy 40.175612 -334.645003) (xy 40.255651 -334.617301) (xy 40.33796 -334.597333) (xy 40.421795 -334.58528)
			(xy 40.506396 -334.58125) (xy 40.590997 -334.58528) (xy 40.674832 -334.597333) (xy 40.757141 -334.617301)
			(xy 40.83718 -334.645003) (xy 40.914223 -334.680187) (xy 40.987573 -334.722536) (xy 41.056565 -334.771665)
			(xy 41.120575 -334.82713) (xy 41.179023 -334.888428) (xy 41.231379 -334.955004) (xy 41.277169 -335.026256)
			(xy 41.31598 -335.101537) (xy 41.347459 -335.180167) (xy 41.37132 -335.261434) (xy 41.387349 -335.3446)
			(xy 41.3954 -335.428914) (xy 41.395904 -335.471262) (xy 41.3954 -335.51361) (xy 41.394794 -335.51996)
			(xy 45.808134 -335.51996) (xy 45.808134 -335.435264) (xy 45.816185 -335.35095) (xy 45.832214 -335.267784)
			(xy 45.856075 -335.186517) (xy 45.887554 -335.107887) (xy 45.926365 -335.032606) (xy 45.972155 -334.961354)
			(xy 46.024511 -334.894778) (xy 46.082959 -334.83348) (xy 46.146969 -334.778015) (xy 46.215961 -334.728886)
			(xy 46.289311 -334.686537) (xy 46.366354 -334.651353) (xy 46.446393 -334.623651) (xy 46.528702 -334.603683)
			(xy 46.612537 -334.59163) (xy 46.697138 -334.5876) (xy 46.781739 -334.59163) (xy 46.865574 -334.603683)
			(xy 46.947883 -334.623651) (xy 47.027922 -334.651353) (xy 47.104965 -334.686537) (xy 47.178315 -334.728886)
			(xy 47.247307 -334.778015) (xy 47.311317 -334.83348) (xy 47.369765 -334.894778) (xy 47.422121 -334.961354)
			(xy 47.467911 -335.032606) (xy 47.506722 -335.107887) (xy 47.538201 -335.186517) (xy 47.562062 -335.267784)
			(xy 47.578091 -335.35095) (xy 47.586142 -335.435264) (xy 47.586646 -335.477612) (xy 47.586142 -335.51996)
			(xy 52.005734 -335.51996) (xy 52.005734 -335.435264) (xy 52.013785 -335.35095) (xy 52.029814 -335.267784)
			(xy 52.053675 -335.186517) (xy 52.085154 -335.107887) (xy 52.123965 -335.032606) (xy 52.169755 -334.961354)
			(xy 52.222111 -334.894778) (xy 52.280559 -334.83348) (xy 52.344569 -334.778015) (xy 52.413561 -334.728886)
			(xy 52.486911 -334.686537) (xy 52.563954 -334.651353) (xy 52.643993 -334.623651) (xy 52.726302 -334.603683)
			(xy 52.810137 -334.59163) (xy 52.894738 -334.5876) (xy 52.979339 -334.59163) (xy 53.063174 -334.603683)
			(xy 53.145483 -334.623651) (xy 53.225522 -334.651353) (xy 53.302565 -334.686537) (xy 53.375915 -334.728886)
			(xy 53.444907 -334.778015) (xy 53.508917 -334.83348) (xy 53.567365 -334.894778) (xy 53.619721 -334.961354)
			(xy 53.665511 -335.032606) (xy 53.704322 -335.107887) (xy 53.735801 -335.186517) (xy 53.759662 -335.267784)
			(xy 53.775691 -335.35095) (xy 53.783742 -335.435264) (xy 53.784246 -335.477612) (xy 53.783742 -335.51996)
			(xy 53.775691 -335.604274) (xy 53.759662 -335.68744) (xy 53.735801 -335.768707) (xy 53.704322 -335.847337)
			(xy 53.665511 -335.922618) (xy 53.619721 -335.99387) (xy 53.567365 -336.060446) (xy 53.508917 -336.121744)
			(xy 53.444907 -336.177209) (xy 53.375915 -336.226338) (xy 53.302565 -336.268687) (xy 53.225522 -336.303871)
			(xy 53.145483 -336.331573) (xy 53.063174 -336.351541) (xy 52.979339 -336.363594) (xy 52.894738 -336.367625)
			(xy 52.810137 -336.363594) (xy 52.726302 -336.351541) (xy 52.643993 -336.331573) (xy 52.563954 -336.303871)
			(xy 52.486911 -336.268687) (xy 52.413561 -336.226338) (xy 52.344569 -336.177209) (xy 52.280559 -336.121744)
			(xy 52.222111 -336.060446) (xy 52.169755 -335.99387) (xy 52.123965 -335.922618) (xy 52.085154 -335.847337)
			(xy 52.053675 -335.768707) (xy 52.029814 -335.68744) (xy 52.013785 -335.604274) (xy 52.005734 -335.51996)
			(xy 47.586142 -335.51996) (xy 47.578091 -335.604274) (xy 47.562062 -335.68744) (xy 47.538201 -335.768707)
			(xy 47.506722 -335.847337) (xy 47.467911 -335.922618) (xy 47.422121 -335.99387) (xy 47.369765 -336.060446)
			(xy 47.311317 -336.121744) (xy 47.247307 -336.177209) (xy 47.178315 -336.226338) (xy 47.104965 -336.268687)
			(xy 47.027922 -336.303871) (xy 46.947883 -336.331573) (xy 46.865574 -336.351541) (xy 46.781739 -336.363594)
			(xy 46.697138 -336.367625) (xy 46.612537 -336.363594) (xy 46.528702 -336.351541) (xy 46.446393 -336.331573)
			(xy 46.366354 -336.303871) (xy 46.289311 -336.268687) (xy 46.215961 -336.226338) (xy 46.146969 -336.177209)
			(xy 46.082959 -336.121744) (xy 46.024511 -336.060446) (xy 45.972155 -335.99387) (xy 45.926365 -335.922618)
			(xy 45.887554 -335.847337) (xy 45.856075 -335.768707) (xy 45.832214 -335.68744) (xy 45.816185 -335.604274)
			(xy 45.808134 -335.51996) (xy 41.394794 -335.51996) (xy 41.387349 -335.597924) (xy 41.37132 -335.68109)
			(xy 41.347459 -335.762357) (xy 41.31598 -335.840987) (xy 41.277169 -335.916268) (xy 41.231379 -335.98752)
			(xy 41.179023 -336.054096) (xy 41.120575 -336.115394) (xy 41.056565 -336.170859) (xy 40.987573 -336.219988)
			(xy 40.914223 -336.262337) (xy 40.83718 -336.297521) (xy 40.757141 -336.325223) (xy 40.674832 -336.345191)
			(xy 40.590997 -336.357244) (xy 40.506396 -336.361275) (xy 40.421795 -336.357244) (xy 40.33796 -336.345191)
			(xy 40.255651 -336.325223) (xy 40.175612 -336.297521) (xy 40.098569 -336.262337) (xy 40.025219 -336.219988)
			(xy 39.956227 -336.170859) (xy 39.892217 -336.115394) (xy 39.833769 -336.054096) (xy 39.781413 -335.98752)
			(xy 39.735623 -335.916268) (xy 39.696812 -335.840987) (xy 39.665333 -335.762357) (xy 39.641472 -335.68109)
			(xy 39.625443 -335.597924) (xy 39.617392 -335.51361) (xy 34.902394 -335.51361) (xy 34.902394 -337.231228)
			(xy 34.662364 -337.471258) (xy 39.590985 -337.471258) (xy 39.595007 -337.385538) (xy 39.607038 -337.30057)
			(xy 39.626974 -337.217103) (xy 39.654637 -337.135869) (xy 39.689786 -337.057583) (xy 39.732112 -336.982932)
			(xy 39.781241 -336.912573) (xy 39.836744 -336.847123) (xy 39.898131 -336.787159) (xy 39.964864 -336.733206)
			(xy 40.036356 -336.685739) (xy 40.111978 -336.645175) (xy 40.191067 -336.611871) (xy 40.272927 -336.586119)
			(xy 40.356838 -336.568146) (xy 40.442064 -336.55811) (xy 40.527856 -336.556098) (xy 40.613458 -336.562129)
			(xy 40.69812 -336.576149) (xy 40.781097 -336.598035) (xy 40.86166 -336.627596) (xy 40.9391 -336.66457)
			(xy 41.012739 -336.708634) (xy 41.081927 -336.7594) (xy 41.146058 -336.816421) (xy 41.204567 -336.879197)
			(xy 41.25694 -336.947177) (xy 41.302718 -337.019762) (xy 41.341498 -337.096314) (xy 41.372939 -337.176162)
			(xy 41.396765 -337.258603) (xy 41.412766 -337.342913) (xy 41.420801 -337.428351) (xy 41.421304 -337.471258)
			(xy 41.42123 -337.477608) (xy 45.781727 -337.477608) (xy 45.785749 -337.391888) (xy 45.79778 -337.30692)
			(xy 45.817716 -337.223453) (xy 45.845379 -337.142219) (xy 45.880528 -337.063933) (xy 45.922854 -336.989282)
			(xy 45.971983 -336.918923) (xy 46.027486 -336.853473) (xy 46.088873 -336.793509) (xy 46.155606 -336.739556)
			(xy 46.227098 -336.692089) (xy 46.30272 -336.651525) (xy 46.381809 -336.618221) (xy 46.463669 -336.592469)
			(xy 46.54758 -336.574496) (xy 46.632806 -336.56446) (xy 46.718598 -336.562448) (xy 46.8042 -336.568479)
			(xy 46.888862 -336.582499) (xy 46.971839 -336.604385) (xy 47.052402 -336.633946) (xy 47.129842 -336.67092)
			(xy 47.203481 -336.714984) (xy 47.272669 -336.76575) (xy 47.3368 -336.822771) (xy 47.395309 -336.885547)
			(xy 47.447682 -336.953527) (xy 47.49346 -337.026112) (xy 47.53224 -337.102664) (xy 47.563681 -337.182512)
			(xy 47.587507 -337.264953) (xy 47.603508 -337.349263) (xy 47.611543 -337.434701) (xy 47.612046 -337.477608)
			(xy 51.97983 -337.477608) (xy 51.980318 -337.435332) (xy 51.98812 -337.35114) (xy 52.003656 -337.268027)
			(xy 52.026795 -337.186703) (xy 52.057339 -337.10786) (xy 52.095027 -337.032172) (xy 52.139538 -336.960284)
			(xy 52.190492 -336.89281) (xy 52.247455 -336.830325) (xy 52.30994 -336.773362) (xy 52.377414 -336.722408)
			(xy 52.449302 -336.677897) (xy 52.52499 -336.640209) (xy 52.603833 -336.609665) (xy 52.685157 -336.586526)
			(xy 52.76827 -336.57099) (xy 52.852462 -336.563188) (xy 52.937014 -336.563188) (xy 53.021206 -336.57099)
			(xy 53.104319 -336.586526) (xy 53.185643 -336.609665) (xy 53.264486 -336.640209) (xy 53.340174 -336.677897)
			(xy 53.412062 -336.722408) (xy 53.479536 -336.773362) (xy 53.542021 -336.830325) (xy 53.598984 -336.89281)
			(xy 53.649938 -336.960284) (xy 53.694449 -337.032172) (xy 53.732137 -337.10786) (xy 53.762681 -337.186703)
			(xy 53.78582 -337.268027) (xy 53.801356 -337.35114) (xy 53.809158 -337.435332) (xy 53.809646 -337.477608)
			(xy 53.809142 -337.519569) (xy 53.801456 -337.603139) (xy 53.786148 -337.685654) (xy 53.763347 -337.766421)
			(xy 53.733246 -337.844759) (xy 53.696097 -337.920012) (xy 53.652212 -337.991547) (xy 53.60196 -338.058761)
			(xy 53.545764 -338.121091) (xy 53.484096 -338.178013) (xy 53.417474 -338.229047) (xy 53.346458 -338.273766)
			(xy 53.309266 -338.293202) (xy 53.296167 -338.300524) (xy 53.274558 -338.321321) (xy 53.259912 -338.347494)
			(xy 53.25349 -338.37679) (xy 53.255844 -338.406689) (xy 53.266772 -338.434619) (xy 53.285333 -338.458177)
			(xy 53.297328 -338.467192) (xy 53.308811 -338.475301) (xy 53.330676 -338.492974) (xy 53.341016 -338.502498)
			(xy 53.35255 -338.51257) (xy 53.380096 -338.525912) (xy 53.410358 -338.530497) (xy 53.44062 -338.525912)
			(xy 53.468166 -338.51257) (xy 53.4797 -338.502498) (xy 53.501027 -338.483228) (xy 53.54839 -338.450663)
			(xy 53.600101 -338.425572) (xy 53.654992 -338.408522) (xy 53.711819 -338.3999) (xy 53.769297 -338.3999)
			(xy 53.826124 -338.408522) (xy 53.881015 -338.425572) (xy 53.932726 -338.450663) (xy 53.980089 -338.483228)
			(xy 54.001416 -338.502498) (xy 54.01295 -338.51257) (xy 54.040496 -338.525912) (xy 54.070758 -338.530497)
			(xy 54.10102 -338.525912) (xy 54.128566 -338.51257) (xy 54.1401 -338.502498) (xy 54.161412 -338.48321)
			(xy 54.208777 -338.450644) (xy 54.260493 -338.425554) (xy 54.315387 -338.408508) (xy 54.372218 -338.399891)
			(xy 54.400958 -338.399374) (xy 54.428209 -338.399894) (xy 54.482157 -338.407645) (xy 54.534453 -338.422995)
			(xy 54.584031 -338.445631) (xy 54.629884 -338.475093) (xy 54.671077 -338.510781) (xy 54.706771 -338.551968)
			(xy 54.73624 -338.597816) (xy 54.758884 -338.647391) (xy 54.774242 -338.699684) (xy 54.782001 -338.753631)
			(xy 54.782466 -338.780882) (xy 54.781914 -338.80962) (xy 54.773295 -338.866445) (xy 54.756251 -338.921335)
			(xy 54.731166 -338.973047) (xy 54.698609 -339.020411) (xy 54.679342 -339.04174) (xy 54.669287 -339.053288)
			(xy 54.655941 -339.080829) (xy 54.651353 -339.111087) (xy 54.655934 -339.141346) (xy 54.669272 -339.16889)
			(xy 54.679342 -339.180424) (xy 54.698601 -339.201761) (xy 54.73117 -339.24912) (xy 54.756265 -339.300829)
			(xy 54.773318 -339.355718) (xy 54.781944 -339.412544) (xy 54.782466 -339.441282) (xy 54.782015 -339.468272)
			(xy 54.774408 -339.521712) (xy 54.759344 -339.573547) (xy 54.737124 -339.622741) (xy 54.70819 -339.668311)
			(xy 54.673122 -339.709347) (xy 54.65318 -339.72754) (xy 54.642465 -339.737466) (xy 54.626852 -339.762143)
			(xy 54.618868 -339.790231) (xy 54.619166 -339.819431) (xy 54.627722 -339.84735) (xy 54.643835 -339.871703)
			(xy 54.654704 -339.881464) (xy 54.675503 -339.899686) (xy 54.712176 -339.941068) (xy 54.742483 -339.987316)
			(xy 54.765788 -340.037458) (xy 54.781602 -340.090442) (xy 54.789593 -340.145155) (xy 54.790086 -340.172802)
			(xy 54.789559 -340.202244) (xy 54.780511 -340.26043) (xy 54.76263 -340.316534) (xy 54.736341 -340.369224)
			(xy 54.702268 -340.417249) (xy 54.682136 -340.43874) (xy 54.671747 -340.450216) (xy 54.657858 -340.477865)
			(xy 54.652857 -340.508401) (xy 54.657201 -340.539036) (xy 54.670494 -340.566978) (xy 54.680612 -340.578694)
			(xy 54.699625 -340.600011) (xy 54.731799 -340.647204) (xy 54.75658 -340.698665) (xy 54.773417 -340.753245)
			(xy 54.781931 -340.809723) (xy 54.782466 -340.838282) (xy 54.781998 -340.865652) (xy 54.774182 -340.919832)
			(xy 54.758694 -340.972335) (xy 54.735852 -341.022082) (xy 54.706127 -341.068049) (xy 54.688486 -341.08898)
			(xy 54.679268 -341.100321) (xy 54.66709 -341.126874) (xy 54.662914 -341.155786) (xy 54.667082 -341.1847)
			(xy 54.679253 -341.211256) (xy 54.688486 -341.222584) (xy 54.706109 -341.243531) (xy 54.735833 -341.289497)
			(xy 54.758679 -341.339241) (xy 54.774176 -341.391741) (xy 54.782006 -341.445917) (xy 54.782008 -341.500656)
			(xy 54.774182 -341.554833) (xy 54.758688 -341.607334) (xy 54.735846 -341.657079) (xy 54.706125 -341.703047)
			(xy 54.688486 -341.72398) (xy 54.679268 -341.735321) (xy 54.66709 -341.761874) (xy 54.662914 -341.790786)
			(xy 54.667082 -341.8197) (xy 54.679253 -341.846256) (xy 54.688486 -341.857584) (xy 54.706109 -341.878531)
			(xy 54.735833 -341.924497) (xy 54.758679 -341.974241) (xy 54.774176 -342.026741) (xy 54.782006 -342.080917)
			(xy 54.782008 -342.135656) (xy 54.774182 -342.189833) (xy 54.758688 -342.242334) (xy 54.735846 -342.292079)
			(xy 54.706125 -342.338047) (xy 54.688486 -342.35898) (xy 54.679268 -342.370321) (xy 54.66709 -342.396874)
			(xy 54.662914 -342.425786) (xy 54.667082 -342.4547) (xy 54.679253 -342.481256) (xy 54.688486 -342.492584)
			(xy 54.706129 -342.513513) (xy 54.735841 -342.559486) (xy 54.758676 -342.609235) (xy 54.774166 -342.661736)
			(xy 54.781993 -342.715913) (xy 54.782466 -342.743282) (xy 54.782028 -342.770536) (xy 54.774272 -342.82449)
			(xy 54.758916 -342.876791) (xy 54.736273 -342.926374) (xy 54.706803 -342.972229) (xy 54.671106 -343.013423)
			(xy 54.62991 -343.049117) (xy 54.584053 -343.078584) (xy 54.534469 -343.101225) (xy 54.482167 -343.116577)
			(xy 54.428212 -343.12433) (xy 54.400958 -343.12479) (xy 54.372218 -343.124294) (xy 54.315389 -343.115665)
			(xy 54.260498 -343.098609) (xy 54.208787 -343.073511) (xy 54.161426 -343.04094) (xy 54.1401 -343.021666)
			(xy 54.128566 -343.011594) (xy 54.10102 -342.998252) (xy 54.070758 -342.993667) (xy 54.040496 -342.998252)
			(xy 54.01295 -343.011594) (xy 54.001416 -343.021666) (xy 53.980089 -343.040936) (xy 53.932726 -343.073501)
			(xy 53.881015 -343.098592) (xy 53.826124 -343.115642) (xy 53.769297 -343.124264) (xy 53.711819 -343.124264)
			(xy 53.654992 -343.115642) (xy 53.600101 -343.098592) (xy 53.54839 -343.073501) (xy 53.501027 -343.040936)
			(xy 53.4797 -343.021666) (xy 53.468166 -343.011594) (xy 53.44062 -342.998252) (xy 53.410358 -342.993667)
			(xy 53.380096 -342.998252) (xy 53.35255 -343.011594) (xy 53.341016 -343.021666) (xy 53.319707 -343.040957)
			(xy 53.27234 -343.073521) (xy 53.220624 -343.098609) (xy 53.165729 -343.115655) (xy 53.108898 -343.124272)
			(xy 53.080158 -343.12479) (xy 53.052905 -343.124361) (xy 52.998954 -343.116599) (xy 52.946657 -343.101237)
			(xy 52.897079 -343.07859) (xy 52.851228 -343.049117) (xy 52.810037 -343.01342) (xy 52.774347 -342.972224)
			(xy 52.744881 -342.926369) (xy 52.722242 -342.876786) (xy 52.706889 -342.824487) (xy 52.699135 -342.770535)
			(xy 52.69865 -342.743282) (xy 52.699093 -342.715911) (xy 52.706915 -342.66173) (xy 52.722408 -342.609226)
			(xy 52.745256 -342.55948) (xy 52.774986 -342.513514) (xy 52.79263 -342.492584) (xy 52.801882 -342.481269)
			(xy 52.814053 -342.454706) (xy 52.818221 -342.425786) (xy 52.814046 -342.396868) (xy 52.801867 -342.370308)
			(xy 52.79263 -342.35898) (xy 52.774972 -342.338062) (xy 52.745247 -342.292091) (xy 52.722403 -342.242343)
			(xy 52.706908 -342.189839) (xy 52.699081 -342.135658) (xy 52.699083 -342.080915) (xy 52.706914 -342.026735)
			(xy 52.722412 -341.974232) (xy 52.74526 -341.924485) (xy 52.774988 -341.878517) (xy 52.79263 -341.857584)
			(xy 52.801882 -341.846269) (xy 52.814053 -341.819706) (xy 52.818221 -341.790786) (xy 52.814046 -341.761868)
			(xy 52.801867 -341.735308) (xy 52.79263 -341.72398) (xy 52.774972 -341.703062) (xy 52.745247 -341.657091)
			(xy 52.722403 -341.607343) (xy 52.706908 -341.554839) (xy 52.699081 -341.500658) (xy 52.699083 -341.445915)
			(xy 52.706914 -341.391735) (xy 52.722412 -341.339232) (xy 52.74526 -341.289485) (xy 52.774988 -341.243517)
			(xy 52.79263 -341.222584) (xy 52.801882 -341.211269) (xy 52.814053 -341.184706) (xy 52.818221 -341.155786)
			(xy 52.814046 -341.126868) (xy 52.801867 -341.100308) (xy 52.79263 -341.08898) (xy 52.77502 -341.068025)
			(xy 52.745302 -341.022059) (xy 52.72246 -340.972317) (xy 52.706963 -340.919822) (xy 52.699128 -340.86565)
			(xy 52.69865 -340.838282) (xy 52.69922 -340.808841) (xy 52.708256 -340.750657) (xy 52.726126 -340.694554)
			(xy 52.752406 -340.641862) (xy 52.786471 -340.593836) (xy 52.8066 -340.572344) (xy 52.817009 -340.560883)
			(xy 52.830906 -340.53323) (xy 52.835907 -340.502688) (xy 52.831556 -340.472046) (xy 52.81825 -340.444104)
			(xy 52.808124 -340.43239) (xy 52.789093 -340.411088) (xy 52.756924 -340.36389) (xy 52.732147 -340.312425)
			(xy 52.715315 -340.257843) (xy 52.706803 -340.201361) (xy 52.70627 -340.172802) (xy 52.706698 -340.145811)
			(xy 52.714308 -340.092369) (xy 52.729376 -340.040533) (xy 52.7516 -339.99134) (xy 52.780538 -339.94577)
			(xy 52.815611 -339.904735) (xy 52.835556 -339.886544) (xy 52.846182 -339.876532) (xy 52.861793 -339.851879)
			(xy 52.869785 -339.823814) (xy 52.869503 -339.794635) (xy 52.86097 -339.766729) (xy 52.844886 -339.742382)
			(xy 52.834032 -339.73262) (xy 52.813233 -339.714399) (xy 52.776559 -339.673017) (xy 52.74625 -339.62677)
			(xy 52.722945 -339.576627) (xy 52.707131 -339.523643) (xy 52.699142 -339.468929) (xy 52.69865 -339.441282)
			(xy 52.699176 -339.412543) (xy 52.7078 -339.355717) (xy 52.72485 -339.300827) (xy 52.749941 -339.249115)
			(xy 52.782504 -339.201752) (xy 52.801774 -339.180424) (xy 52.811863 -339.168904) (xy 52.825203 -339.141353)
			(xy 52.829784 -339.111087) (xy 52.825195 -339.080822) (xy 52.811848 -339.053274) (xy 52.801774 -339.04174)
			(xy 52.782501 -339.020415) (xy 52.749933 -338.973053) (xy 52.724841 -338.921341) (xy 52.707791 -338.86645)
			(xy 52.69917 -338.809621) (xy 52.69865 -338.780882) (xy 52.699093 -338.754848) (xy 52.706182 -338.703265)
			(xy 52.720212 -338.653124) (xy 52.740924 -338.605353) (xy 52.767933 -338.560838) (xy 52.783994 -338.540344)
			(xy 52.792995 -338.528305) (xy 52.804369 -338.500505) (xy 52.807153 -338.470597) (xy 52.801105 -338.441174)
			(xy 52.78675 -338.414789) (xy 52.765333 -338.393729) (xy 52.73871 -338.37982) (xy 52.72405 -338.376514)
			(xy 52.682679 -338.368223) (xy 52.601583 -338.344902) (xy 52.522979 -338.314214) (xy 52.447534 -338.276419)
			(xy 52.375889 -338.231838) (xy 52.308653 -338.180851) (xy 52.246397 -338.12389) (xy 52.189649 -338.061439)
			(xy 52.138892 -337.994029) (xy 52.094557 -337.922232) (xy 52.05702 -337.846659) (xy 52.0266 -337.76795)
			(xy 52.003557 -337.686775) (xy 51.988084 -337.603823) (xy 51.980315 -337.519799) (xy 51.97983 -337.477608)
			(xy 47.612046 -337.477608) (xy 47.611543 -337.520515) (xy 47.603508 -337.605953) (xy 47.587507 -337.690263)
			(xy 47.563681 -337.772704) (xy 47.53224 -337.852552) (xy 47.49346 -337.929104) (xy 47.447682 -338.001689)
			(xy 47.395309 -338.069669) (xy 47.3368 -338.132445) (xy 47.272669 -338.189466) (xy 47.203481 -338.240232)
			(xy 47.129842 -338.284296) (xy 47.052402 -338.32127) (xy 46.971839 -338.350831) (xy 46.888862 -338.372717)
			(xy 46.8042 -338.386737) (xy 46.718598 -338.392768) (xy 46.632806 -338.390756) (xy 46.54758 -338.38072)
			(xy 46.463669 -338.362747) (xy 46.381809 -338.336995) (xy 46.30272 -338.303691) (xy 46.227098 -338.263127)
			(xy 46.155606 -338.21566) (xy 46.088873 -338.161707) (xy 46.027486 -338.101743) (xy 45.971983 -338.036293)
			(xy 45.922854 -337.965934) (xy 45.880528 -337.891283) (xy 45.845379 -337.812997) (xy 45.817716 -337.731763)
			(xy 45.79778 -337.648296) (xy 45.785749 -337.563328) (xy 45.781727 -337.477608) (xy 41.42123 -337.477608)
			(xy 41.420801 -337.514165) (xy 41.412766 -337.599603) (xy 41.396765 -337.683913) (xy 41.372939 -337.766354)
			(xy 41.341498 -337.846202) (xy 41.302718 -337.922754) (xy 41.25694 -337.995339) (xy 41.204567 -338.063319)
			(xy 41.146058 -338.126095) (xy 41.081927 -338.183116) (xy 41.012739 -338.233882) (xy 40.9391 -338.277946)
			(xy 40.86166 -338.31492) (xy 40.781097 -338.344481) (xy 40.69812 -338.366367) (xy 40.613458 -338.380387)
			(xy 40.527856 -338.386418) (xy 40.442064 -338.384406) (xy 40.356838 -338.37437) (xy 40.272927 -338.356397)
			(xy 40.191067 -338.330645) (xy 40.111978 -338.297341) (xy 40.036356 -338.256777) (xy 39.964864 -338.20931)
			(xy 39.898131 -338.155357) (xy 39.836744 -338.095393) (xy 39.781241 -338.029943) (xy 39.732112 -337.959584)
			(xy 39.689786 -337.884933) (xy 39.654637 -337.806647) (xy 39.626974 -337.725413) (xy 39.607038 -337.641946)
			(xy 39.595007 -337.556978) (xy 39.590985 -337.471258) (xy 34.662364 -337.471258) (xy 32.6898 -339.443822)
			(xy 38.02761 -339.443822) (xy 38.028087 -339.416452) (xy 38.035901 -339.362273) (xy 38.051388 -339.30977)
			(xy 38.074227 -339.260023) (xy 38.10395 -339.214056) (xy 38.12159 -339.193124) (xy 38.130806 -339.181781)
			(xy 38.142988 -339.155229) (xy 38.147165 -339.126317) (xy 38.142997 -339.097403) (xy 38.130825 -339.070847)
			(xy 38.12159 -339.05952) (xy 38.103945 -339.038593) (xy 38.074235 -338.992618) (xy 38.0514 -338.94287)
			(xy 38.03591 -338.890368) (xy 38.028083 -338.836191) (xy 38.02761 -338.808822) (xy 38.028076 -338.781569)
			(xy 38.03583 -338.727617) (xy 38.051184 -338.675318) (xy 38.073826 -338.625737) (xy 38.103293 -338.579883)
			(xy 38.138987 -338.538689) (xy 38.18018 -338.502995) (xy 38.226033 -338.473528) (xy 38.275614 -338.450886)
			(xy 38.327913 -338.435531) (xy 38.381865 -338.427776) (xy 38.409118 -338.427314) (xy 38.437856 -338.42785)
			(xy 38.494682 -338.436473) (xy 38.549572 -338.453521) (xy 38.601284 -338.47861) (xy 38.648648 -338.51117)
			(xy 38.669976 -338.530438) (xy 38.68151 -338.54051) (xy 38.709056 -338.553852) (xy 38.739318 -338.558437)
			(xy 38.76958 -338.553852) (xy 38.797126 -338.54051) (xy 38.80866 -338.530438) (xy 38.829987 -338.511168)
			(xy 38.87735 -338.478603) (xy 38.929061 -338.453512) (xy 38.983952 -338.436462) (xy 39.040779 -338.42784)
			(xy 39.098257 -338.42784) (xy 39.155084 -338.436462) (xy 39.209975 -338.453512) (xy 39.261686 -338.478603)
			(xy 39.309049 -338.511168) (xy 39.330376 -338.530438) (xy 39.341283 -338.539936) (xy 39.367057 -338.553021)
			(xy 39.395469 -338.558337) (xy 39.42423 -338.555455) (xy 39.437818 -338.550504) (xy 39.456048 -338.52959)
			(xy 39.497498 -338.492717) (xy 39.543854 -338.462239) (xy 39.594137 -338.4388) (xy 39.647286 -338.422894)
			(xy 39.702179 -338.414858) (xy 39.729918 -338.41436) (xy 39.75719 -338.414785) (xy 39.81118 -338.42255)
			(xy 39.863515 -338.43792) (xy 39.913129 -338.460581) (xy 39.959014 -338.490072) (xy 40.000234 -338.525794)
			(xy 40.035952 -338.567018) (xy 40.065438 -338.612906) (xy 40.088094 -338.662523) (xy 40.103459 -338.714859)
			(xy 40.111218 -338.768849) (xy 40.11168 -338.796122) (xy 40.111426 -338.810092) (xy 40.110907 -338.837335)
			(xy 40.102977 -338.891244) (xy 40.087449 -338.943474) (xy 40.06464 -338.99296) (xy 40.035015 -339.038692)
			(xy 40.017446 -339.05952) (xy 40.009031 -339.069826) (xy 39.997353 -339.093722) (xy 39.992231 -339.119822)
			(xy 39.994012 -339.146359) (xy 39.997888 -339.159088) (xy 40.019063 -339.180757) (xy 40.054942 -339.229573)
			(xy 40.082668 -339.283439) (xy 40.101546 -339.341006) (xy 40.111103 -339.40083) (xy 40.11168 -339.431122)
			(xy 40.111426 -339.445092) (xy 40.110952 -339.470505) (xy 40.104043 -339.520863) (xy 40.090504 -339.569857)
			(xy 40.070578 -339.616618) (xy 40.044616 -339.660317) (xy 40.013079 -339.70018) (xy 39.995094 -339.718142)
			(xy 39.985339 -339.728135) (xy 39.971307 -339.752272) (xy 39.964343 -339.779309) (xy 39.964969 -339.807221)
			(xy 39.973137 -339.833919) (xy 39.988236 -339.857403) (xy 39.998396 -339.866986) (xy 40.018206 -339.885169)
			(xy 40.052996 -339.926171) (xy 40.081692 -339.971647) (xy 40.103726 -340.020698) (xy 40.118662 -340.072355)
			(xy 40.126207 -340.125596) (xy 40.126666 -340.152482) (xy 40.126079 -340.182605) (xy 40.116601 -340.2421)
			(xy 40.097894 -340.299368) (xy 40.070422 -340.352985) (xy 40.034867 -340.40162) (xy 40.01389 -340.423246)
			(xy 40.004689 -340.432983) (xy 39.99124 -340.45614) (xy 39.984274 -340.481998) (xy 39.984271 -340.508777)
			(xy 39.99123 -340.534636) (xy 40.004673 -340.557797) (xy 40.01389 -340.567518) (xy 40.034854 -340.589158)
			(xy 40.070425 -340.637782) (xy 40.097908 -340.691395) (xy 40.11662 -340.748662) (xy 40.126095 -340.808159)
			(xy 40.126666 -340.838282) (xy 40.126198 -340.865652) (xy 40.118382 -340.919832) (xy 40.102894 -340.972335)
			(xy 40.080052 -341.022082) (xy 40.050327 -341.068049) (xy 40.032686 -341.08898) (xy 40.023468 -341.100321)
			(xy 40.01129 -341.126874) (xy 40.007114 -341.155786) (xy 40.011282 -341.1847) (xy 40.023453 -341.211256)
			(xy 40.032686 -341.222584) (xy 40.050309 -341.243531) (xy 40.080033 -341.289497) (xy 40.102879 -341.339241)
			(xy 40.118376 -341.391741) (xy 40.126206 -341.445917) (xy 40.126208 -341.500656) (xy 40.118382 -341.554833)
			(xy 40.102888 -341.607334) (xy 40.080046 -341.657079) (xy 40.050325 -341.703047) (xy 40.032686 -341.72398)
			(xy 40.023468 -341.735321) (xy 40.01129 -341.761874) (xy 40.007114 -341.790786) (xy 40.011282 -341.8197)
			(xy 40.023453 -341.846256) (xy 40.032686 -341.857584) (xy 40.050309 -341.878531) (xy 40.080033 -341.924497)
			(xy 40.102879 -341.974241) (xy 40.118376 -342.026741) (xy 40.126206 -342.080917) (xy 40.126208 -342.135656)
			(xy 40.118382 -342.189833) (xy 40.102888 -342.242334) (xy 40.080046 -342.292079) (xy 40.050325 -342.338047)
			(xy 40.032686 -342.35898) (xy 40.023468 -342.370321) (xy 40.01129 -342.396874) (xy 40.007114 -342.425786)
			(xy 40.011282 -342.4547) (xy 40.023453 -342.481256) (xy 40.032686 -342.492584) (xy 40.050329 -342.513513)
			(xy 40.080041 -342.559486) (xy 40.102876 -342.609235) (xy 40.118366 -342.661736) (xy 40.126193 -342.715913)
			(xy 40.126666 -342.743282) (xy 43.02125 -342.743282) (xy 43.021693 -342.715911) (xy 43.029515 -342.66173)
			(xy 43.045008 -342.609226) (xy 43.067856 -342.55948) (xy 43.097586 -342.513514) (xy 43.11523 -342.492584)
			(xy 43.124482 -342.481269) (xy 43.136653 -342.454706) (xy 43.140821 -342.425786) (xy 43.136646 -342.396868)
			(xy 43.124467 -342.370308) (xy 43.11523 -342.35898) (xy 43.097572 -342.338062) (xy 43.067847 -342.292091)
			(xy 43.045003 -342.242343) (xy 43.029508 -342.189839) (xy 43.021681 -342.135658) (xy 43.021683 -342.080915)
			(xy 43.029514 -342.026735) (xy 43.045012 -341.974232) (xy 43.06786 -341.924485) (xy 43.097588 -341.878517)
			(xy 43.11523 -341.857584) (xy 43.124482 -341.846269) (xy 43.136653 -341.819706) (xy 43.140821 -341.790786)
			(xy 43.136646 -341.761868) (xy 43.124467 -341.735308) (xy 43.11523 -341.72398) (xy 43.097572 -341.703062)
			(xy 43.067847 -341.657091) (xy 43.045003 -341.607343) (xy 43.029508 -341.554839) (xy 43.021681 -341.500658)
			(xy 43.021683 -341.445915) (xy 43.029514 -341.391735) (xy 43.045012 -341.339232) (xy 43.06786 -341.289485)
			(xy 43.097588 -341.243517) (xy 43.11523 -341.222584) (xy 43.124482 -341.211269) (xy 43.136653 -341.184706)
			(xy 43.140821 -341.155786) (xy 43.136646 -341.126868) (xy 43.124467 -341.100308) (xy 43.11523 -341.08898)
			(xy 43.09762 -341.068025) (xy 43.067902 -341.022059) (xy 43.04506 -340.972317) (xy 43.029563 -340.919822)
			(xy 43.021728 -340.86565) (xy 43.02125 -340.838282) (xy 43.02125 -340.838028) (xy 43.021846 -340.808195)
			(xy 43.031143 -340.749256) (xy 43.049499 -340.692483) (xy 43.076467 -340.639258) (xy 43.11139 -340.590879)
			(xy 43.131994 -340.569296) (xy 43.142625 -340.557741) (xy 43.157002 -340.529852) (xy 43.162226 -340.498914)
			(xy 43.157801 -340.467851) (xy 43.144146 -340.439601) (xy 43.133772 -340.427818) (xy 43.114184 -340.406442)
			(xy 43.081067 -340.358854) (xy 43.055538 -340.3068) (xy 43.038186 -340.25148) (xy 43.02941 -340.194171)
			(xy 43.02887 -340.165182) (xy 43.029319 -340.138581) (xy 43.036697 -340.085893) (xy 43.051322 -340.034741)
			(xy 43.07291 -339.986116) (xy 43.101043 -339.940961) (xy 43.135174 -339.900151) (xy 43.1546 -339.881972)
			(xy 43.164941 -339.872005) (xy 43.180033 -339.847581) (xy 43.187736 -339.819924) (xy 43.187444 -339.791215)
			(xy 43.179179 -339.76372) (xy 43.163593 -339.739609) (xy 43.153076 -339.729826) (xy 43.132762 -339.711618)
			(xy 43.097025 -339.670401) (xy 43.067521 -339.624515) (xy 43.044852 -339.574896) (xy 43.029478 -339.522555)
			(xy 43.021713 -339.468558) (xy 43.02125 -339.441282) (xy 43.021776 -339.412543) (xy 43.0304 -339.355717)
			(xy 43.04745 -339.300827) (xy 43.072541 -339.249115) (xy 43.105104 -339.201752) (xy 43.124374 -339.180424)
			(xy 43.134463 -339.168904) (xy 43.147803 -339.141353) (xy 43.152384 -339.111087) (xy 43.147795 -339.080822)
			(xy 43.134448 -339.053274) (xy 43.124374 -339.04174) (xy 43.105101 -339.020415) (xy 43.072533 -338.973053)
			(xy 43.047441 -338.921341) (xy 43.030391 -338.86645) (xy 43.02177 -338.809621) (xy 43.02125 -338.780882)
			(xy 43.021761 -338.753632) (xy 43.029519 -338.699688) (xy 43.044874 -338.647396) (xy 43.067514 -338.597821)
			(xy 43.096979 -338.551973) (xy 43.132667 -338.510784) (xy 43.173854 -338.475093) (xy 43.2197 -338.445626)
			(xy 43.269273 -338.422982) (xy 43.321564 -338.407624) (xy 43.375508 -338.399863) (xy 43.402758 -338.399374)
			(xy 43.431498 -338.399869) (xy 43.488326 -338.4085) (xy 43.543217 -338.425557) (xy 43.594928 -338.450655)
			(xy 43.64229 -338.483225) (xy 43.663616 -338.502498) (xy 43.67515 -338.51257) (xy 43.702696 -338.525912)
			(xy 43.732958 -338.530497) (xy 43.76322 -338.525912) (xy 43.790766 -338.51257) (xy 43.8023 -338.502498)
			(xy 43.823627 -338.483228) (xy 43.87099 -338.450663) (xy 43.922701 -338.425572) (xy 43.977592 -338.408522)
			(xy 44.034419 -338.3999) (xy 44.091897 -338.3999) (xy 44.148724 -338.408522) (xy 44.203615 -338.425572)
			(xy 44.255326 -338.450663) (xy 44.302689 -338.483228) (xy 44.324016 -338.502498) (xy 44.33555 -338.51257)
			(xy 44.363096 -338.525912) (xy 44.393358 -338.530497) (xy 44.42362 -338.525912) (xy 44.451166 -338.51257)
			(xy 44.4627 -338.502498) (xy 44.484012 -338.48321) (xy 44.531377 -338.450644) (xy 44.583093 -338.425554)
			(xy 44.637987 -338.408508) (xy 44.694818 -338.399891) (xy 44.723558 -338.399374) (xy 44.750809 -338.399894)
			(xy 44.804757 -338.407645) (xy 44.857053 -338.422995) (xy 44.906631 -338.445631) (xy 44.952484 -338.475093)
			(xy 44.993677 -338.510781) (xy 45.029371 -338.551968) (xy 45.05884 -338.597816) (xy 45.081484 -338.647391)
			(xy 45.096842 -338.699684) (xy 45.104601 -338.753631) (xy 45.105066 -338.780882) (xy 45.104514 -338.80962)
			(xy 45.095895 -338.866445) (xy 45.078851 -338.921335) (xy 45.053766 -338.973047) (xy 45.021209 -339.020411)
			(xy 45.001942 -339.04174) (xy 44.991887 -339.053288) (xy 44.978541 -339.080829) (xy 44.973953 -339.111087)
			(xy 44.978534 -339.141346) (xy 44.991872 -339.16889) (xy 45.001942 -339.180424) (xy 45.021201 -339.201761)
			(xy 45.05377 -339.24912) (xy 45.078865 -339.300829) (xy 45.095918 -339.355718) (xy 45.104544 -339.412544)
			(xy 45.105066 -339.441282) (xy 45.104581 -339.467882) (xy 45.097208 -339.520567) (xy 45.08259 -339.571718)
			(xy 45.061009 -339.620343) (xy 45.032883 -339.665499) (xy 44.998758 -339.706312) (xy 44.979336 -339.724492)
			(xy 44.969028 -339.734492) (xy 44.953929 -339.758905) (xy 44.946218 -339.786555) (xy 44.946504 -339.815258)
			(xy 44.954764 -339.842749) (xy 44.970345 -339.866857) (xy 44.98086 -339.876638) (xy 45.001164 -339.894857)
			(xy 45.0369 -339.936073) (xy 45.066404 -339.981956) (xy 45.089075 -340.031573) (xy 45.104452 -340.083912)
			(xy 45.112221 -340.137907) (xy 45.112686 -340.165182) (xy 45.112686 -340.165436) (xy 45.112546 -340.172802)
			(xy 47.71263 -340.172802) (xy 47.713127 -340.145156) (xy 47.721126 -340.090444) (xy 47.736942 -340.037461)
			(xy 47.760243 -339.987318) (xy 47.790542 -339.941065) (xy 47.827203 -339.899672) (xy 47.848012 -339.881464)
			(xy 47.858786 -339.871635) (xy 47.874807 -339.847284) (xy 47.883311 -339.819404) (xy 47.883608 -339.790257)
			(xy 47.875673 -339.762209) (xy 47.860151 -339.737538) (xy 47.849536 -339.72754) (xy 47.829588 -339.709355)
			(xy 47.794526 -339.668314) (xy 47.765598 -339.622741) (xy 47.743382 -339.573546) (xy 47.728321 -339.521712)
			(xy 47.720716 -339.468271) (xy 47.72025 -339.441282) (xy 47.720776 -339.412543) (xy 47.7294 -339.355717)
			(xy 47.74645 -339.300827) (xy 47.771541 -339.249115) (xy 47.804104 -339.201752) (xy 47.823374 -339.180424)
			(xy 47.833463 -339.168904) (xy 47.846803 -339.141353) (xy 47.851384 -339.111087) (xy 47.846795 -339.080822)
			(xy 47.833448 -339.053274) (xy 47.823374 -339.04174) (xy 47.804101 -339.020415) (xy 47.771533 -338.973053)
			(xy 47.746441 -338.921341) (xy 47.729391 -338.86645) (xy 47.72077 -338.809621) (xy 47.72025 -338.780882)
			(xy 47.720761 -338.753632) (xy 47.728519 -338.699688) (xy 47.743874 -338.647396) (xy 47.766514 -338.597821)
			(xy 47.795979 -338.551973) (xy 47.831667 -338.510784) (xy 47.872854 -338.475093) (xy 47.9187 -338.445626)
			(xy 47.968273 -338.422982) (xy 48.020564 -338.407624) (xy 48.074508 -338.399863) (xy 48.101758 -338.399374)
			(xy 48.130498 -338.399869) (xy 48.187326 -338.4085) (xy 48.242217 -338.425557) (xy 48.293928 -338.450655)
			(xy 48.34129 -338.483225) (xy 48.362616 -338.502498) (xy 48.37415 -338.51257) (xy 48.401696 -338.525912)
			(xy 48.431958 -338.530497) (xy 48.46222 -338.525912) (xy 48.489766 -338.51257) (xy 48.5013 -338.502498)
			(xy 48.522627 -338.483228) (xy 48.56999 -338.450663) (xy 48.621701 -338.425572) (xy 48.676592 -338.408522)
			(xy 48.733419 -338.3999) (xy 48.790897 -338.3999) (xy 48.847724 -338.408522) (xy 48.902615 -338.425572)
			(xy 48.954326 -338.450663) (xy 49.001689 -338.483228) (xy 49.023016 -338.502498) (xy 49.03455 -338.51257)
			(xy 49.062096 -338.525912) (xy 49.092358 -338.530497) (xy 49.12262 -338.525912) (xy 49.150166 -338.51257)
			(xy 49.1617 -338.502498) (xy 49.183012 -338.48321) (xy 49.230377 -338.450644) (xy 49.282093 -338.425554)
			(xy 49.336987 -338.408508) (xy 49.393818 -338.399891) (xy 49.422558 -338.399374) (xy 49.449809 -338.399894)
			(xy 49.503757 -338.407645) (xy 49.556053 -338.422995) (xy 49.605631 -338.445631) (xy 49.651484 -338.475093)
			(xy 49.692677 -338.510781) (xy 49.728371 -338.551968) (xy 49.75784 -338.597816) (xy 49.780484 -338.647391)
			(xy 49.795842 -338.699684) (xy 49.803601 -338.753631) (xy 49.804066 -338.780882) (xy 49.803514 -338.80962)
			(xy 49.794895 -338.866445) (xy 49.777851 -338.921335) (xy 49.752766 -338.973047) (xy 49.720209 -339.020411)
			(xy 49.700942 -339.04174) (xy 49.690887 -339.053288) (xy 49.677541 -339.080829) (xy 49.672953 -339.111087)
			(xy 49.677534 -339.141346) (xy 49.690872 -339.16889) (xy 49.700942 -339.180424) (xy 49.720201 -339.201761)
			(xy 49.75277 -339.24912) (xy 49.777865 -339.300829) (xy 49.794918 -339.355718) (xy 49.803544 -339.412544)
			(xy 49.804066 -339.441282) (xy 49.80356 -339.468928) (xy 49.795563 -339.523639) (xy 49.779749 -339.576622)
			(xy 49.756449 -339.626766) (xy 49.726152 -339.673019) (xy 49.689493 -339.714412) (xy 49.668684 -339.73262)
			(xy 49.657819 -339.742361) (xy 49.641786 -339.766732) (xy 49.633283 -339.794638) (xy 49.633002 -339.823809)
			(xy 49.640965 -339.851874) (xy 49.656525 -339.87655) (xy 49.66716 -339.886544) (xy 49.687099 -339.904738)
			(xy 49.722162 -339.945777) (xy 49.751091 -339.991348) (xy 49.773309 -340.040541) (xy 49.788372 -340.092374)
			(xy 49.795979 -340.145813) (xy 49.796446 -340.172802) (xy 49.795882 -340.20136) (xy 49.787374 -340.257838)
			(xy 49.770547 -340.312419) (xy 49.745777 -340.363885) (xy 49.713618 -340.411086) (xy 49.694592 -340.43239)
			(xy 49.684469 -340.444114) (xy 49.671114 -340.472041) (xy 49.666746 -340.502687) (xy 49.671766 -340.533234)
			(xy 49.685713 -340.56087) (xy 49.696116 -340.572344) (xy 49.71624 -340.593841) (xy 49.750307 -340.641867)
			(xy 49.776592 -340.694557) (xy 49.794471 -340.750658) (xy 49.803519 -340.808841) (xy 49.804066 -340.838282)
			(xy 49.803598 -340.865652) (xy 49.795782 -340.919832) (xy 49.780294 -340.972335) (xy 49.757452 -341.022082)
			(xy 49.727727 -341.068049) (xy 49.710086 -341.08898) (xy 49.700868 -341.100321) (xy 49.68869 -341.126874)
			(xy 49.684514 -341.155786) (xy 49.688682 -341.1847) (xy 49.700853 -341.211256) (xy 49.710086 -341.222584)
			(xy 49.727709 -341.243531) (xy 49.757433 -341.289497) (xy 49.780279 -341.339241) (xy 49.795776 -341.391741)
			(xy 49.803606 -341.445917) (xy 49.803608 -341.500656) (xy 49.795782 -341.554833) (xy 49.780288 -341.607334)
			(xy 49.757446 -341.657079) (xy 49.727725 -341.703047) (xy 49.710086 -341.72398) (xy 49.700868 -341.735321)
			(xy 49.68869 -341.761874) (xy 49.684514 -341.790786) (xy 49.688682 -341.8197) (xy 49.700853 -341.846256)
			(xy 49.710086 -341.857584) (xy 49.727709 -341.878531) (xy 49.757433 -341.924497) (xy 49.780279 -341.974241)
			(xy 49.795776 -342.026741) (xy 49.803606 -342.080917) (xy 49.803608 -342.135656) (xy 49.795782 -342.189833)
			(xy 49.780288 -342.242334) (xy 49.757446 -342.292079) (xy 49.727725 -342.338047) (xy 49.710086 -342.35898)
			(xy 49.700868 -342.370321) (xy 49.68869 -342.396874) (xy 49.684514 -342.425786) (xy 49.688682 -342.4547)
			(xy 49.700853 -342.481256) (xy 49.710086 -342.492584) (xy 49.727729 -342.513513) (xy 49.757441 -342.559486)
			(xy 49.780276 -342.609235) (xy 49.795766 -342.661736) (xy 49.803593 -342.715913) (xy 49.804066 -342.743282)
			(xy 49.803628 -342.770536) (xy 49.795872 -342.82449) (xy 49.780516 -342.876791) (xy 49.757873 -342.926374)
			(xy 49.728403 -342.972229) (xy 49.692706 -343.013423) (xy 49.65151 -343.049117) (xy 49.605653 -343.078584)
			(xy 49.556069 -343.101225) (xy 49.503767 -343.116577) (xy 49.449812 -343.12433) (xy 49.422558 -343.12479)
			(xy 49.393818 -343.124294) (xy 49.336989 -343.115665) (xy 49.282098 -343.098609) (xy 49.230387 -343.073511)
			(xy 49.183026 -343.04094) (xy 49.1617 -343.021666) (xy 49.150166 -343.011594) (xy 49.12262 -342.998252)
			(xy 49.092358 -342.993667) (xy 49.062096 -342.998252) (xy 49.03455 -343.011594) (xy 49.023016 -343.021666)
			(xy 49.001689 -343.040936) (xy 48.954326 -343.073501) (xy 48.902615 -343.098592) (xy 48.847724 -343.115642)
			(xy 48.790897 -343.124264) (xy 48.733419 -343.124264) (xy 48.676592 -343.115642) (xy 48.621701 -343.098592)
			(xy 48.56999 -343.073501) (xy 48.522627 -343.040936) (xy 48.5013 -343.021666) (xy 48.489766 -343.011594)
			(xy 48.46222 -342.998252) (xy 48.431958 -342.993667) (xy 48.401696 -342.998252) (xy 48.37415 -343.011594)
			(xy 48.362616 -343.021666) (xy 48.341307 -343.040957) (xy 48.29394 -343.073521) (xy 48.242224 -343.098609)
			(xy 48.187329 -343.115655) (xy 48.130498 -343.124272) (xy 48.101758 -343.12479) (xy 48.074505 -343.124361)
			(xy 48.020554 -343.116599) (xy 47.968257 -343.101237) (xy 47.918679 -343.07859) (xy 47.872828 -343.049117)
			(xy 47.831637 -343.01342) (xy 47.795947 -342.972224) (xy 47.766481 -342.926369) (xy 47.743842 -342.876786)
			(xy 47.728489 -342.824487) (xy 47.720735 -342.770535) (xy 47.72025 -342.743282) (xy 47.720693 -342.715911)
			(xy 47.728515 -342.66173) (xy 47.744008 -342.609226) (xy 47.766856 -342.55948) (xy 47.796586 -342.513514)
			(xy 47.81423 -342.492584) (xy 47.823482 -342.481269) (xy 47.835653 -342.454706) (xy 47.839821 -342.425786)
			(xy 47.835646 -342.396868) (xy 47.823467 -342.370308) (xy 47.81423 -342.35898) (xy 47.796572 -342.338062)
			(xy 47.766847 -342.292091) (xy 47.744003 -342.242343) (xy 47.728508 -342.189839) (xy 47.720681 -342.135658)
			(xy 47.720683 -342.080915) (xy 47.728514 -342.026735) (xy 47.744012 -341.974232) (xy 47.76686 -341.924485)
			(xy 47.796588 -341.878517) (xy 47.81423 -341.857584) (xy 47.823482 -341.846269) (xy 47.835653 -341.819706)
			(xy 47.839821 -341.790786) (xy 47.835646 -341.761868) (xy 47.823467 -341.735308) (xy 47.81423 -341.72398)
			(xy 47.796572 -341.703062) (xy 47.766847 -341.657091) (xy 47.744003 -341.607343) (xy 47.728508 -341.554839)
			(xy 47.720681 -341.500658) (xy 47.720683 -341.445915) (xy 47.728514 -341.391735) (xy 47.744012 -341.339232)
			(xy 47.76686 -341.289485) (xy 47.796588 -341.243517) (xy 47.81423 -341.222584) (xy 47.823482 -341.211269)
			(xy 47.835653 -341.184706) (xy 47.839821 -341.155786) (xy 47.835646 -341.126868) (xy 47.823467 -341.100308)
			(xy 47.81423 -341.08898) (xy 47.79662 -341.068025) (xy 47.766902 -341.022059) (xy 47.74406 -340.972317)
			(xy 47.728563 -340.919822) (xy 47.720728 -340.86565) (xy 47.72025 -340.838282) (xy 47.720805 -340.809724)
			(xy 47.729316 -340.753245) (xy 47.746145 -340.698664) (xy 47.770916 -340.647199) (xy 47.803078 -340.599998)
			(xy 47.822104 -340.578694) (xy 47.832243 -340.566983) (xy 47.845597 -340.539051) (xy 47.849963 -340.508401)
			(xy 47.844938 -340.477852) (xy 47.830985 -340.450214) (xy 47.82058 -340.43874) (xy 47.800448 -340.417251)
			(xy 47.766382 -340.369222) (xy 47.740099 -340.316531) (xy 47.722222 -340.260427) (xy 47.713176 -340.202243)
			(xy 47.71263 -340.172802) (xy 45.112546 -340.172802) (xy 45.11212 -340.19527) (xy 45.102814 -340.254209)
			(xy 45.08445 -340.310983) (xy 45.057476 -340.364207) (xy 45.022548 -340.412585) (xy 45.001942 -340.434168)
			(xy 44.991253 -340.445671) (xy 44.976891 -340.47358) (xy 44.971683 -340.504532) (xy 44.976121 -340.535604)
			(xy 44.989785 -340.56386) (xy 45.000164 -340.575646) (xy 45.019724 -340.597046) (xy 45.052847 -340.644627)
			(xy 45.078382 -340.696675) (xy 45.095741 -340.751989) (xy 45.104523 -340.809295) (xy 45.105066 -340.838282)
			(xy 45.104598 -340.865652) (xy 45.096782 -340.919832) (xy 45.081294 -340.972335) (xy 45.058452 -341.022082)
			(xy 45.028727 -341.068049) (xy 45.011086 -341.08898) (xy 45.001868 -341.100321) (xy 44.98969 -341.126874)
			(xy 44.985514 -341.155786) (xy 44.989682 -341.1847) (xy 45.001853 -341.211256) (xy 45.011086 -341.222584)
			(xy 45.028709 -341.243531) (xy 45.058433 -341.289497) (xy 45.081279 -341.339241) (xy 45.096776 -341.391741)
			(xy 45.104606 -341.445917) (xy 45.104608 -341.500656) (xy 45.096782 -341.554833) (xy 45.081288 -341.607334)
			(xy 45.058446 -341.657079) (xy 45.028725 -341.703047) (xy 45.011086 -341.72398) (xy 45.001868 -341.735321)
			(xy 44.98969 -341.761874) (xy 44.985514 -341.790786) (xy 44.989682 -341.8197) (xy 45.001853 -341.846256)
			(xy 45.011086 -341.857584) (xy 45.028709 -341.878531) (xy 45.058433 -341.924497) (xy 45.081279 -341.974241)
			(xy 45.096776 -342.026741) (xy 45.104606 -342.080917) (xy 45.104608 -342.135656) (xy 45.096782 -342.189833)
			(xy 45.081288 -342.242334) (xy 45.058446 -342.292079) (xy 45.028725 -342.338047) (xy 45.011086 -342.35898)
			(xy 45.001868 -342.370321) (xy 44.98969 -342.396874) (xy 44.985514 -342.425786) (xy 44.989682 -342.4547)
			(xy 45.001853 -342.481256) (xy 45.011086 -342.492584) (xy 45.028729 -342.513513) (xy 45.058441 -342.559486)
			(xy 45.081276 -342.609235) (xy 45.096766 -342.661736) (xy 45.104593 -342.715913) (xy 45.105066 -342.743282)
			(xy 45.104628 -342.770536) (xy 45.096872 -342.82449) (xy 45.081516 -342.876791) (xy 45.058873 -342.926374)
			(xy 45.029403 -342.972229) (xy 44.993706 -343.013423) (xy 44.95251 -343.049117) (xy 44.906653 -343.078584)
			(xy 44.857069 -343.101225) (xy 44.804767 -343.116577) (xy 44.750812 -343.12433) (xy 44.723558 -343.12479)
			(xy 44.694818 -343.124294) (xy 44.637989 -343.115665) (xy 44.583098 -343.098609) (xy 44.531387 -343.073511)
			(xy 44.484026 -343.04094) (xy 44.4627 -343.021666) (xy 44.451166 -343.011594) (xy 44.42362 -342.998252)
			(xy 44.393358 -342.993667) (xy 44.363096 -342.998252) (xy 44.33555 -343.011594) (xy 44.324016 -343.021666)
			(xy 44.302689 -343.040936) (xy 44.255326 -343.073501) (xy 44.203615 -343.098592) (xy 44.148724 -343.115642)
			(xy 44.091897 -343.124264) (xy 44.034419 -343.124264) (xy 43.977592 -343.115642) (xy 43.922701 -343.098592)
			(xy 43.87099 -343.073501) (xy 43.823627 -343.040936) (xy 43.8023 -343.021666) (xy 43.790766 -343.011594)
			(xy 43.76322 -342.998252) (xy 43.732958 -342.993667) (xy 43.702696 -342.998252) (xy 43.67515 -343.011594)
			(xy 43.663616 -343.021666) (xy 43.642307 -343.040957) (xy 43.59494 -343.073521) (xy 43.543224 -343.098609)
			(xy 43.488329 -343.115655) (xy 43.431498 -343.124272) (xy 43.402758 -343.12479) (xy 43.375505 -343.124361)
			(xy 43.321554 -343.116599) (xy 43.269257 -343.101237) (xy 43.219679 -343.07859) (xy 43.173828 -343.049117)
			(xy 43.132637 -343.01342) (xy 43.096947 -342.972224) (xy 43.067481 -342.926369) (xy 43.044842 -342.876786)
			(xy 43.029489 -342.824487) (xy 43.021735 -342.770535) (xy 43.02125 -342.743282) (xy 40.126666 -342.743282)
			(xy 40.126228 -342.770536) (xy 40.118472 -342.82449) (xy 40.103116 -342.876791) (xy 40.080473 -342.926374)
			(xy 40.051003 -342.972229) (xy 40.015306 -343.013423) (xy 39.97411 -343.049117) (xy 39.928253 -343.078584)
			(xy 39.878669 -343.101225) (xy 39.826367 -343.116577) (xy 39.772412 -343.12433) (xy 39.745158 -343.12479)
			(xy 39.716418 -343.124294) (xy 39.659589 -343.115665) (xy 39.604698 -343.098609) (xy 39.552987 -343.073511)
			(xy 39.505626 -343.04094) (xy 39.4843 -343.021666) (xy 39.472766 -343.011594) (xy 39.44522 -342.998252)
			(xy 39.414958 -342.993667) (xy 39.384696 -342.998252) (xy 39.35715 -343.011594) (xy 39.345616 -343.021666)
			(xy 39.324289 -343.040936) (xy 39.276926 -343.073501) (xy 39.225215 -343.098592) (xy 39.170324 -343.115642)
			(xy 39.113497 -343.124264) (xy 39.056019 -343.124264) (xy 38.999192 -343.115642) (xy 38.944301 -343.098592)
			(xy 38.89259 -343.073501) (xy 38.845227 -343.040936) (xy 38.8239 -343.021666) (xy 38.812366 -343.011594)
			(xy 38.78482 -342.998252) (xy 38.754558 -342.993667) (xy 38.724296 -342.998252) (xy 38.69675 -343.011594)
			(xy 38.685216 -343.021666) (xy 38.663907 -343.040957) (xy 38.61654 -343.073521) (xy 38.564824 -343.098609)
			(xy 38.509929 -343.115655) (xy 38.453098 -343.124272) (xy 38.424358 -343.12479) (xy 38.397105 -343.124361)
			(xy 38.343154 -343.116599) (xy 38.290857 -343.101237) (xy 38.241279 -343.07859) (xy 38.195428 -343.049117)
			(xy 38.154237 -343.01342) (xy 38.118547 -342.972224) (xy 38.089081 -342.926369) (xy 38.066442 -342.876786)
			(xy 38.051089 -342.824487) (xy 38.043335 -342.770535) (xy 38.04285 -342.743282) (xy 38.043293 -342.715911)
			(xy 38.051115 -342.66173) (xy 38.066608 -342.609226) (xy 38.089456 -342.55948) (xy 38.119186 -342.513514)
			(xy 38.13683 -342.492584) (xy 38.146082 -342.481269) (xy 38.158253 -342.454706) (xy 38.162421 -342.425786)
			(xy 38.158246 -342.396868) (xy 38.146067 -342.370308) (xy 38.13683 -342.35898) (xy 38.119172 -342.338062)
			(xy 38.089447 -342.292091) (xy 38.066603 -342.242343) (xy 38.051108 -342.189839) (xy 38.043281 -342.135658)
			(xy 38.043283 -342.080915) (xy 38.051114 -342.026735) (xy 38.066612 -341.974232) (xy 38.08946 -341.924485)
			(xy 38.119188 -341.878517) (xy 38.13683 -341.857584) (xy 38.146082 -341.846269) (xy 38.158253 -341.819706)
			(xy 38.162421 -341.790786) (xy 38.158246 -341.761868) (xy 38.146067 -341.735308) (xy 38.13683 -341.72398)
			(xy 38.119172 -341.703062) (xy 38.089447 -341.657091) (xy 38.066603 -341.607343) (xy 38.051108 -341.554839)
			(xy 38.043281 -341.500658) (xy 38.043283 -341.445915) (xy 38.051114 -341.391735) (xy 38.066612 -341.339232)
			(xy 38.08946 -341.289485) (xy 38.119188 -341.243517) (xy 38.13683 -341.222584) (xy 38.146082 -341.211269)
			(xy 38.158253 -341.184706) (xy 38.162421 -341.155786) (xy 38.158246 -341.126868) (xy 38.146067 -341.100308)
			(xy 38.13683 -341.08898) (xy 38.11922 -341.068025) (xy 38.089502 -341.022059) (xy 38.06666 -340.972317)
			(xy 38.051163 -340.919822) (xy 38.043328 -340.86565) (xy 38.04285 -340.838282) (xy 38.043409 -340.808158)
			(xy 38.052893 -340.748661) (xy 38.071607 -340.691393) (xy 38.099085 -340.637776) (xy 38.134646 -340.589142)
			(xy 38.155626 -340.567518) (xy 38.164862 -340.557812) (xy 38.178306 -340.534645) (xy 38.185266 -340.50878)
			(xy 38.185263 -340.481995) (xy 38.178297 -340.456131) (xy 38.164846 -340.432968) (xy 38.155626 -340.423246)
			(xy 38.134647 -340.40162) (xy 38.099078 -340.352992) (xy 38.071597 -340.299376) (xy 38.052888 -340.242106)
			(xy 38.043418 -340.182606) (xy 38.04285 -340.152482) (xy 38.043236 -340.126961) (xy 38.050033 -340.076373)
			(xy 38.063518 -340.027143) (xy 38.083448 -339.980152) (xy 38.109469 -339.93624) (xy 38.141114 -339.896191)
			(xy 38.159182 -339.878162) (xy 38.168936 -339.868167) (xy 38.182971 -339.844031) (xy 38.189938 -339.816994)
			(xy 38.189313 -339.789081) (xy 38.181143 -339.762383) (xy 38.166041 -339.7389) (xy 38.15588 -339.729318)
			(xy 38.136067 -339.711138) (xy 38.101279 -339.670134) (xy 38.072584 -339.624658) (xy 38.05055 -339.575606)
			(xy 38.035614 -339.523949) (xy 38.02807 -339.470708) (xy 38.02761 -339.443822) (xy 32.6898 -339.443822)
			(xy 31.60268 -340.530942) (xy 31.60268 -353.70643) (xy 35.21405 -353.70643) (xy 35.218121 -353.650808)
			(xy 35.230247 -353.596371) (xy 35.25017 -353.54428) (xy 35.277466 -353.495645) (xy 35.311552 -353.451502)
			(xy 35.351701 -353.412793) (xy 35.397059 -353.380342) (xy 35.446659 -353.354841) (xy 35.499443 -353.336834)
			(xy 35.554286 -353.326704) (xy 35.61002 -353.324667) (xy 35.665457 -353.330767) (xy 35.719414 -353.344873)
			(xy 35.770743 -353.366685) (xy 35.818349 -353.395739) (xy 35.861217 -353.431414) (xy 35.898434 -353.472951)
			(xy 35.929207 -353.519464) (xy 35.952879 -353.569961) (xy 35.968947 -353.623368) (xy 35.977067 -353.678544)
			(xy 35.977576 -353.70643) (xy 35.977067 -353.734316) (xy 35.968947 -353.789492) (xy 35.952879 -353.842899)
			(xy 35.929207 -353.893396) (xy 35.898434 -353.939909) (xy 35.861217 -353.981446) (xy 35.818349 -354.017121)
			(xy 35.770743 -354.046175) (xy 35.719414 -354.067987) (xy 35.665457 -354.082093) (xy 35.61002 -354.088193)
			(xy 35.554286 -354.086156) (xy 35.499443 -354.076026) (xy 35.446659 -354.058019) (xy 35.397059 -354.032518)
			(xy 35.351701 -354.000067) (xy 35.311552 -353.961358) (xy 35.277466 -353.917215) (xy 35.25017 -353.86858)
			(xy 35.230247 -353.816489) (xy 35.218121 -353.762052) (xy 35.21405 -353.70643) (xy 31.60268 -353.70643)
			(xy 31.60268 -354.65385) (xy 35.21405 -354.65385) (xy 35.218121 -354.598228) (xy 35.230247 -354.543791)
			(xy 35.25017 -354.4917) (xy 35.277466 -354.443065) (xy 35.311552 -354.398922) (xy 35.351701 -354.360213)
			(xy 35.397059 -354.327762) (xy 35.446659 -354.302261) (xy 35.499443 -354.284254) (xy 35.554286 -354.274124)
			(xy 35.61002 -354.272087) (xy 35.665457 -354.278187) (xy 35.719414 -354.292293) (xy 35.770743 -354.314105)
			(xy 35.818349 -354.343159) (xy 35.861217 -354.378834) (xy 35.898434 -354.420371) (xy 35.929207 -354.466884)
			(xy 35.952879 -354.517381) (xy 35.968947 -354.570788) (xy 35.977067 -354.625964) (xy 35.977576 -354.65385)
			(xy 35.977067 -354.681736) (xy 35.968947 -354.736912) (xy 35.952879 -354.790319) (xy 35.929207 -354.840816)
			(xy 35.898434 -354.887329) (xy 35.861217 -354.928866) (xy 35.818349 -354.964541) (xy 35.770743 -354.993595)
			(xy 35.721478 -355.01453) (xy 37.608764 -355.01453) (xy 37.608764 -355.014276) (xy 37.609295 -354.986262)
			(xy 37.617514 -354.93084) (xy 37.633742 -354.877213) (xy 37.657631 -354.826533) (xy 37.688668 -354.779887)
			(xy 37.707062 -354.758752) (xy 37.716729 -354.747326) (xy 37.729509 -354.720278) (xy 37.733892 -354.690685)
			(xy 37.7295 -354.661093) (xy 37.716712 -354.634049) (xy 37.707062 -354.622608) (xy 37.688634 -354.601497)
			(xy 37.657566 -354.55486) (xy 37.633664 -354.504176) (xy 37.617442 -354.450538) (xy 37.609252 -354.395103)
			(xy 37.608764 -354.367084) (xy 37.608764 -354.36683) (xy 37.60925 -354.339579) (xy 37.617006 -354.285631)
			(xy 37.632361 -354.233336) (xy 37.655003 -354.183759) (xy 37.684469 -354.137909) (xy 37.72016 -354.096718)
			(xy 37.761351 -354.061027) (xy 37.807201 -354.031561) (xy 37.856778 -354.008919) (xy 37.909073 -353.993564)
			(xy 37.963021 -353.985808) (xy 38.017523 -353.985808) (xy 38.071471 -353.993564) (xy 38.123766 -354.008919)
			(xy 38.173343 -354.031561) (xy 38.219193 -354.061027) (xy 38.260384 -354.096718) (xy 38.296075 -354.137909)
			(xy 38.325541 -354.183759) (xy 38.348183 -354.233336) (xy 38.363538 -354.285631) (xy 38.371294 -354.339579)
			(xy 38.37178 -354.36683) (xy 38.37178 -354.367084) (xy 38.371299 -354.3951) (xy 38.36307 -354.450525)
			(xy 38.346831 -354.504153) (xy 38.322931 -354.554832) (xy 38.291882 -354.601475) (xy 38.273482 -354.622608)
			(xy 38.269002 -354.627942) (xy 45.58614 -354.627942) (xy 45.590211 -354.57232) (xy 45.602337 -354.517883)
			(xy 45.62226 -354.465792) (xy 45.649556 -354.417157) (xy 45.683642 -354.373014) (xy 45.723791 -354.334305)
			(xy 45.769149 -354.301854) (xy 45.818749 -354.276353) (xy 45.871533 -354.258346) (xy 45.926376 -354.248216)
			(xy 45.98211 -354.246179) (xy 46.037547 -354.252279) (xy 46.091504 -354.266385) (xy 46.142833 -354.288197)
			(xy 46.190439 -354.317251) (xy 46.233307 -354.352926) (xy 46.270524 -354.394463) (xy 46.301297 -354.440976)
			(xy 46.324969 -354.491473) (xy 46.341037 -354.54488) (xy 46.349157 -354.600056) (xy 46.349666 -354.627942)
			(xy 46.349157 -354.655828) (xy 46.341037 -354.711004) (xy 46.324969 -354.764411) (xy 46.301297 -354.814908)
			(xy 46.270524 -354.861421) (xy 46.233307 -354.902958) (xy 46.190439 -354.938633) (xy 46.142833 -354.967687)
			(xy 46.091504 -354.989499) (xy 46.037547 -355.003605) (xy 45.995969 -355.00818) (xy 47.297086 -355.00818)
			(xy 47.297544 -354.98081) (xy 47.305364 -354.92663) (xy 47.320855 -354.874127) (xy 47.343699 -354.82438)
			(xy 47.373424 -354.778414) (xy 47.391066 -354.757482) (xy 47.400325 -354.74617) (xy 47.412504 -354.719608)
			(xy 47.416674 -354.690685) (xy 47.412495 -354.661763) (xy 47.400308 -354.635204) (xy 47.391066 -354.623878)
			(xy 47.373445 -354.602932) (xy 47.343731 -354.556962) (xy 47.320893 -354.507218) (xy 47.305397 -354.454721)
			(xy 47.297563 -354.400548) (xy 47.297086 -354.37318) (xy 47.297572 -354.345929) (xy 47.305328 -354.291981)
			(xy 47.320683 -354.239686) (xy 47.343325 -354.190109) (xy 47.372791 -354.144259) (xy 47.408482 -354.103068)
			(xy 47.449673 -354.067377) (xy 47.495523 -354.037911) (xy 47.5451 -354.015269) (xy 47.597395 -353.999914)
			(xy 47.651343 -353.992158) (xy 47.705845 -353.992158) (xy 47.759793 -353.999914) (xy 47.812088 -354.015269)
			(xy 47.861665 -354.037911) (xy 47.907515 -354.067377) (xy 47.948706 -354.103068) (xy 47.984397 -354.144259)
			(xy 48.013863 -354.190109) (xy 48.036505 -354.239686) (xy 48.05186 -354.291981) (xy 48.059616 -354.345929)
			(xy 48.060102 -354.37318) (xy 48.059624 -354.40055) (xy 48.051809 -354.454728) (xy 48.036323 -354.507231)
			(xy 48.013484 -354.556978) (xy 47.983762 -354.602946) (xy 47.966122 -354.623878) (xy 47.956903 -354.635219)
			(xy 47.94472 -354.661771) (xy 47.940543 -354.690685) (xy 47.944712 -354.7196) (xy 47.956886 -354.746156)
			(xy 47.966122 -354.757482) (xy 47.98377 -354.778407) (xy 48.013479 -354.824382) (xy 48.036313 -354.874132)
			(xy 48.051802 -354.926634) (xy 48.059629 -354.98081) (xy 48.060102 -355.00818) (xy 48.059616 -355.035431)
			(xy 48.05186 -355.089379) (xy 48.036505 -355.141674) (xy 48.013863 -355.191251) (xy 47.984397 -355.237101)
			(xy 47.948706 -355.278292) (xy 47.907515 -355.313983) (xy 47.861665 -355.343449) (xy 47.812088 -355.366091)
			(xy 47.759793 -355.381446) (xy 47.705845 -355.389202) (xy 47.651343 -355.389202) (xy 47.597395 -355.381446)
			(xy 47.5451 -355.366091) (xy 47.495523 -355.343449) (xy 47.449673 -355.313983) (xy 47.408482 -355.278292)
			(xy 47.372791 -355.237101) (xy 47.343325 -355.191251) (xy 47.320683 -355.141674) (xy 47.305328 -355.089379)
			(xy 47.297572 -355.035431) (xy 47.297086 -355.00818) (xy 45.995969 -355.00818) (xy 45.98211 -355.009705)
			(xy 45.926376 -355.007668) (xy 45.871533 -354.997538) (xy 45.818749 -354.979531) (xy 45.769149 -354.95403)
			(xy 45.723791 -354.921579) (xy 45.683642 -354.88287) (xy 45.649556 -354.838727) (xy 45.62226 -354.790092)
			(xy 45.602337 -354.738001) (xy 45.590211 -354.683564) (xy 45.58614 -354.627942) (xy 38.269002 -354.627942)
			(xy 38.263859 -354.634066) (xy 38.251081 -354.661104) (xy 38.246693 -354.690685) (xy 38.251072 -354.720268)
			(xy 38.263843 -354.747309) (xy 38.273482 -354.758752) (xy 38.291898 -354.779873) (xy 38.322967 -354.826507)
			(xy 38.346871 -354.877189) (xy 38.363095 -354.930825) (xy 38.37129 -354.986258) (xy 38.37178 -355.014276)
			(xy 38.37178 -355.01453) (xy 38.371294 -355.041781) (xy 38.363538 -355.095729) (xy 38.348183 -355.148024)
			(xy 38.325541 -355.197601) (xy 38.296075 -355.243451) (xy 38.260384 -355.284642) (xy 38.219193 -355.320333)
			(xy 38.173343 -355.349799) (xy 38.123766 -355.372441) (xy 38.071471 -355.387796) (xy 38.017523 -355.395552)
			(xy 37.963021 -355.395552) (xy 37.909073 -355.387796) (xy 37.856778 -355.372441) (xy 37.807201 -355.349799)
			(xy 37.761351 -355.320333) (xy 37.72016 -355.284642) (xy 37.684469 -355.243451) (xy 37.655003 -355.197601)
			(xy 37.632361 -355.148024) (xy 37.617006 -355.095729) (xy 37.60925 -355.041781) (xy 37.608764 -355.01453)
			(xy 35.721478 -355.01453) (xy 35.719414 -355.015407) (xy 35.665457 -355.029513) (xy 35.61002 -355.035613)
			(xy 35.554286 -355.033576) (xy 35.499443 -355.023446) (xy 35.446659 -355.005439) (xy 35.397059 -354.979938)
			(xy 35.351701 -354.947487) (xy 35.311552 -354.908778) (xy 35.277466 -354.864635) (xy 35.25017 -354.816)
			(xy 35.230247 -354.763909) (xy 35.218121 -354.709472) (xy 35.21405 -354.65385) (xy 31.60268 -354.65385)
			(xy 31.60268 -355.4108) (xy 41.857303 -355.4108) (xy 41.861472 -355.355173) (xy 41.873886 -355.30079)
			(xy 41.894268 -355.248864) (xy 41.922161 -355.200556) (xy 41.956943 -355.156945) (xy 41.997837 -355.119006)
			(xy 42.04393 -355.087586) (xy 42.09419 -355.063388) (xy 42.147496 -355.046951) (xy 42.202657 -355.038644)
			(xy 42.230548 -355.038152) (xy 42.25788 -355.038623) (xy 42.31196 -355.046592) (xy 42.364295 -355.062379)
			(xy 42.41376 -355.085647) (xy 42.459292 -355.115895) (xy 42.499914 -355.152474) (xy 42.534753 -355.194597)
			(xy 42.549318 -355.21773) (xy 42.557239 -355.229955) (xy 42.578713 -355.249623) (xy 42.604866 -355.262425)
			(xy 42.633571 -355.267321) (xy 42.66249 -355.26391) (xy 42.676064 -355.258624) (xy 42.69928 -355.249149)
			(xy 42.74761 -355.235794) (xy 42.797297 -355.229059) (xy 42.822368 -355.228652) (xy 42.847438 -355.229064)
			(xy 42.897121 -355.235818) (xy 42.945455 -355.249155) (xy 42.968672 -355.258624) (xy 42.982249 -355.263871)
			(xy 43.011149 -355.267234) (xy 43.039827 -355.262322) (xy 43.065961 -355.249534) (xy 43.087437 -355.229904)
			(xy 43.095418 -355.21773) (xy 43.109987 -355.194599) (xy 43.14483 -355.152478) (xy 43.185453 -355.115899)
			(xy 43.230984 -355.085648) (xy 43.280446 -355.062372) (xy 43.332777 -355.046572) (xy 43.386856 -355.038586)
			(xy 43.44152 -355.038586) (xy 43.495599 -355.046572) (xy 43.54793 -355.062372) (xy 43.597392 -355.085648)
			(xy 43.642923 -355.115899) (xy 43.683546 -355.152478) (xy 43.718389 -355.194599) (xy 43.732958 -355.21773)
			(xy 43.740841 -355.229983) (xy 43.762325 -355.24965) (xy 43.788489 -355.262449) (xy 43.817203 -355.267337)
			(xy 43.846128 -355.263916) (xy 43.859704 -355.258624) (xy 43.882915 -355.249137) (xy 43.931247 -355.235786)
			(xy 43.980937 -355.229057) (xy 44.006008 -355.228652) (xy 44.033193 -355.229125) (xy 44.086987 -355.237015)
			(xy 44.139062 -355.252639) (xy 44.188314 -355.275667) (xy 44.233695 -355.305609) (xy 44.274243 -355.34183)
			(xy 44.309095 -355.383559) (xy 44.337512 -355.429911) (xy 44.348654 -355.454712) (xy 44.354556 -355.467303)
			(xy 44.371962 -355.48897) (xy 44.394568 -355.50514) (xy 44.420697 -355.514612) (xy 44.448413 -355.516686)
			(xy 44.475661 -355.511206) (xy 44.500421 -355.498581) (xy 44.51096 -355.48951) (xy 44.532202 -355.470607)
			(xy 44.579249 -355.438674) (xy 44.630518 -355.414084) (xy 44.684871 -355.397383) (xy 44.741102 -355.388941)
			(xy 44.769532 -355.388418) (xy 44.787551 -355.38864) (xy 44.823426 -355.392074) (xy 44.84116 -355.395276)
			(xy 44.856375 -355.397561) (xy 44.88692 -355.394044) (xy 44.915035 -355.381595) (xy 44.93817 -355.361343)
			(xy 44.954229 -355.335122) (xy 44.958508 -355.320346) (xy 44.965907 -355.293302) (xy 44.987537 -355.241577)
			(xy 45.016502 -355.193572) (xy 45.052177 -355.15032) (xy 45.093796 -355.112754) (xy 45.140463 -355.081679)
			(xy 45.191174 -355.057766) (xy 45.244838 -355.041529) (xy 45.300299 -355.033317) (xy 45.328332 -355.032818)
			(xy 45.355585 -355.033248) (xy 45.409536 -355.04101) (xy 45.461834 -355.05637) (xy 45.511413 -355.079017)
			(xy 45.557264 -355.108489) (xy 45.598455 -355.144186) (xy 45.634146 -355.185382) (xy 45.663611 -355.231238)
			(xy 45.68625 -355.280821) (xy 45.701603 -355.33312) (xy 45.709356 -355.387073) (xy 45.709777 -355.4108)
			(xy 51.545729 -355.4108) (xy 51.549897 -355.355185) (xy 51.562307 -355.300812) (xy 51.582681 -355.248895)
			(xy 51.610566 -355.200595) (xy 51.645337 -355.15699) (xy 51.686219 -355.119054) (xy 51.732297 -355.087635)
			(xy 51.782544 -355.063434) (xy 51.835837 -355.046991) (xy 51.890984 -355.038675) (xy 51.91887 -355.038152)
			(xy 51.946203 -355.038606) (xy 52.000284 -355.046577) (xy 52.052619 -355.062368) (xy 52.102083 -355.085639)
			(xy 52.147616 -355.115889) (xy 52.188237 -355.15247) (xy 52.223075 -355.194596) (xy 52.23764 -355.21773)
			(xy 52.24554 -355.22997) (xy 52.267019 -355.249638) (xy 52.293179 -355.262438) (xy 52.321888 -355.26733)
			(xy 52.350811 -355.263914) (xy 52.364386 -355.258624) (xy 52.387599 -355.249143) (xy 52.43593 -355.235789)
			(xy 52.485619 -355.229058) (xy 52.51069 -355.228652) (xy 52.535759 -355.229089) (xy 52.585442 -355.235833)
			(xy 52.633776 -355.24916) (xy 52.656994 -355.258624) (xy 52.670599 -355.263789) (xy 52.699485 -355.267169)
			(xy 52.728153 -355.262276) (xy 52.754282 -355.249507) (xy 52.775757 -355.229895) (xy 52.78374 -355.21773)
			(xy 52.798309 -355.194599) (xy 52.833152 -355.152478) (xy 52.873775 -355.115899) (xy 52.919306 -355.085648)
			(xy 52.968768 -355.062372) (xy 53.021099 -355.046572) (xy 53.075178 -355.038586) (xy 53.129842 -355.038586)
			(xy 53.183921 -355.046572) (xy 53.236252 -355.062372) (xy 53.285714 -355.085648) (xy 53.331245 -355.115899)
			(xy 53.371868 -355.152478) (xy 53.406711 -355.194599) (xy 53.42128 -355.21773) (xy 53.429237 -355.229929)
			(xy 53.450701 -355.249597) (xy 53.476845 -355.262403) (xy 53.505541 -355.267305) (xy 53.534453 -355.263904)
			(xy 53.548026 -355.258624) (xy 53.571234 -355.24913) (xy 53.619568 -355.235782) (xy 53.669258 -355.229055)
			(xy 53.69433 -355.228652) (xy 53.721172 -355.22911) (xy 53.774301 -355.236818) (xy 53.825774 -355.25207)
			(xy 53.874526 -355.27455) (xy 53.919548 -355.303792) (xy 53.959907 -355.339193) (xy 53.994769 -355.380018)
			(xy 54.023412 -355.425424) (xy 54.045244 -355.47447) (xy 54.052978 -355.500178) (xy 54.057673 -355.514662)
			(xy 54.074188 -355.540221) (xy 54.097497 -355.559782) (xy 54.125532 -355.571613) (xy 54.155809 -355.574663)
			(xy 54.185641 -355.568663) (xy 54.199282 -355.5619) (xy 54.227424 -355.547258) (xy 54.287377 -355.526534)
			(xy 54.349937 -355.516039) (xy 54.381654 -355.515418) (xy 54.409825 -355.515918) (xy 54.465554 -355.524209)
			(xy 54.492652 -355.531928) (xy 54.506084 -355.535519) (xy 54.533869 -355.53613) (xy 54.56079 -355.529225)
			(xy 54.584851 -355.515317) (xy 54.60427 -355.495435) (xy 54.617608 -355.471053) (xy 54.623877 -355.443977)
			(xy 54.623716 -355.430074) (xy 54.623208 -355.413056) (xy 54.623208 -355.412802) (xy 54.623654 -355.385561)
			(xy 54.631447 -355.331638) (xy 54.64683 -355.279371) (xy 54.669492 -355.229825) (xy 54.698971 -355.184006)
			(xy 54.734668 -355.142846) (xy 54.775858 -355.107183) (xy 54.821701 -355.077741) (xy 54.871266 -355.05512)
			(xy 54.923545 -355.03978) (xy 54.977474 -355.032032) (xy 55.004716 -355.031548) (xy 55.031966 -355.032063)
			(xy 55.08591 -355.03982) (xy 55.138202 -355.055175) (xy 55.187776 -355.077815) (xy 55.233624 -355.107279)
			(xy 55.274813 -355.142967) (xy 55.310504 -355.184153) (xy 55.339972 -355.229999) (xy 55.362615 -355.279572)
			(xy 55.377974 -355.331863) (xy 55.385735 -355.385806) (xy 55.386224 -355.413056) (xy 55.38572 -355.440629)
			(xy 55.377774 -355.4952) (xy 55.362056 -355.548059) (xy 55.338893 -355.598105) (xy 55.308768 -355.644295)
			(xy 55.272308 -355.685669) (xy 55.251604 -355.703886) (xy 55.240751 -355.713829) (xy 55.224677 -355.738467)
			(xy 55.216288 -355.766663) (xy 55.216279 -355.79608) (xy 55.224653 -355.824281) (xy 55.240713 -355.848928)
			(xy 55.251604 -355.858826) (xy 55.272265 -355.87709) (xy 55.308728 -355.918455) (xy 55.338855 -355.964639)
			(xy 55.362019 -356.01468) (xy 55.377736 -356.067534) (xy 55.38568 -356.122101) (xy 55.385684 -356.177242)
			(xy 55.377749 -356.23181) (xy 55.362039 -356.284667) (xy 55.338883 -356.334711) (xy 55.308763 -356.3809)
			(xy 55.272306 -356.42227) (xy 55.251604 -356.440486) (xy 55.240751 -356.450429) (xy 55.224677 -356.475067)
			(xy 55.216288 -356.503263) (xy 55.216279 -356.53268) (xy 55.224653 -356.560881) (xy 55.240713 -356.585528)
			(xy 55.251604 -356.595426) (xy 55.272332 -356.613619) (xy 55.308801 -356.654992) (xy 55.338931 -356.701185)
			(xy 55.362093 -356.751237) (xy 55.377806 -356.804103) (xy 55.385741 -356.85868) (xy 55.386224 -356.886256)
			(xy 55.385704 -356.913507) (xy 55.377953 -356.967455) (xy 55.362604 -357.019751) (xy 55.339967 -357.06933)
			(xy 55.310505 -357.115182) (xy 55.274818 -357.156375) (xy 55.23363 -357.192069) (xy 55.187783 -357.221539)
			(xy 55.138207 -357.244183) (xy 55.085914 -357.25954) (xy 55.031967 -357.2673) (xy 55.004716 -357.267764)
			(xy 54.978798 -357.267319) (xy 54.927439 -357.26031) (xy 54.877503 -357.246404) (xy 54.829912 -357.22586)
			(xy 54.785546 -357.199055) (xy 54.745221 -357.166484) (xy 54.709682 -357.128749) (xy 54.679585 -357.086546)
			(xy 54.66715 -357.063802) (xy 54.659833 -357.051012) (xy 54.639245 -357.029952) (xy 54.613507 -357.015635)
			(xy 54.584755 -357.009251) (xy 54.555377 -357.011328) (xy 54.54142 -357.01605) (xy 54.509071 -357.027446)
			(xy 54.441598 -357.039713) (xy 54.407308 -357.040434) (xy 54.407054 -357.040434) (xy 54.392905 -357.040345)
			(xy 54.364682 -357.038308) (xy 54.350666 -357.03637) (xy 54.337314 -357.034836) (xy 54.31063 -357.037929)
			(xy 54.285681 -357.04789) (xy 54.264204 -357.064025) (xy 54.24769 -357.085213) (xy 54.237288 -357.10998)
			(xy 54.235096 -357.123238) (xy 54.231023 -357.150394) (xy 54.21605 -357.203226) (xy 54.193657 -357.253366)
			(xy 54.164308 -357.299777) (xy 54.12861 -357.341502) (xy 54.087298 -357.377679) (xy 54.041227 -357.407559)
			(xy 53.991348 -357.430527) (xy 53.938692 -357.446107) (xy 53.884346 -357.453977) (xy 53.85689 -357.454454)
			(xy 53.829641 -357.453932) (xy 53.775697 -357.446175) (xy 53.723405 -357.430821) (xy 53.673831 -357.408182)
			(xy 53.627983 -357.378719) (xy 53.586794 -357.343031) (xy 53.551103 -357.301846) (xy 53.521635 -357.256001)
			(xy 53.498992 -357.206428) (xy 53.483633 -357.154139) (xy 53.475871 -357.100195) (xy 53.475382 -357.072946)
			(xy 53.475886 -357.045373) (xy 53.483831 -356.990802) (xy 53.499549 -356.937943) (xy 53.522712 -356.887897)
			(xy 53.552838 -356.841707) (xy 53.589298 -356.800333) (xy 53.610002 -356.782116) (xy 53.620852 -356.77217)
			(xy 53.636926 -356.747533) (xy 53.645315 -356.719338) (xy 53.645323 -356.689921) (xy 53.636951 -356.661721)
			(xy 53.620892 -356.637075) (xy 53.610002 -356.627176) (xy 53.589276 -356.608981) (xy 53.552807 -356.567609)
			(xy 53.522677 -356.521415) (xy 53.499513 -356.471364) (xy 53.4838 -356.418499) (xy 53.475865 -356.363922)
			(xy 53.475382 -356.336346) (xy 53.475827 -356.309845) (xy 53.483175 -356.257353) (xy 53.497722 -356.206386)
			(xy 53.519187 -356.157924) (xy 53.547156 -356.112901) (xy 53.563774 -356.092252) (xy 53.573204 -356.080099)
			(xy 53.584989 -356.051701) (xy 53.587811 -356.021084) (xy 53.581417 -355.991011) (xy 53.566382 -355.964191)
			(xy 53.544063 -355.943044) (xy 53.5305 -355.935788) (xy 53.506801 -355.923703) (xy 53.462822 -355.893775)
			(xy 53.423543 -355.857899) (xy 53.389762 -355.816804) (xy 53.37556 -355.79431) (xy 53.36765 -355.782076)
			(xy 53.346176 -355.762403) (xy 53.320019 -355.749599) (xy 53.29131 -355.744707) (xy 53.262388 -355.748125)
			(xy 53.248814 -355.753416) (xy 53.2256 -355.762894) (xy 53.177269 -355.776249) (xy 53.127581 -355.782982)
			(xy 53.10251 -355.783388) (xy 53.077441 -355.782948) (xy 53.027759 -355.776205) (xy 52.979424 -355.762879)
			(xy 52.956206 -355.753416) (xy 52.942619 -355.748185) (xy 52.913715 -355.744801) (xy 52.885029 -355.749698)
			(xy 52.858885 -355.762479) (xy 52.837401 -355.782108) (xy 52.82946 -355.79431) (xy 52.814891 -355.817441)
			(xy 52.780048 -355.859562) (xy 52.739425 -355.896141) (xy 52.693894 -355.926392) (xy 52.644432 -355.949668)
			(xy 52.592101 -355.965468) (xy 52.538022 -355.973454) (xy 52.483358 -355.973454) (xy 52.429279 -355.965468)
			(xy 52.376948 -355.949668) (xy 52.327486 -355.926392) (xy 52.281955 -355.896141) (xy 52.241332 -355.859562)
			(xy 52.206489 -355.817441) (xy 52.19192 -355.79431) (xy 52.183953 -355.782117) (xy 52.162494 -355.762445)
			(xy 52.136353 -355.749635) (xy 52.107657 -355.744732) (xy 52.078746 -355.748134) (xy 52.065174 -355.753416)
			(xy 52.041965 -355.762907) (xy 51.993631 -355.776257) (xy 51.943942 -355.782985) (xy 51.91887 -355.783388)
			(xy 51.890984 -355.782925) (xy 51.835837 -355.774609) (xy 51.782544 -355.758166) (xy 51.732297 -355.733965)
			(xy 51.686219 -355.702546) (xy 51.645337 -355.66461) (xy 51.610566 -355.621005) (xy 51.582681 -355.572705)
			(xy 51.562307 -355.520788) (xy 51.549897 -355.466415) (xy 51.545729 -355.4108) (xy 45.709777 -355.4108)
			(xy 45.70984 -355.414326) (xy 45.709344 -355.4419) (xy 45.701401 -355.496472) (xy 45.685683 -355.549332)
			(xy 45.662519 -355.599379) (xy 45.632391 -355.645569) (xy 45.595926 -355.68694) (xy 45.57522 -355.705156)
			(xy 45.564295 -355.715027) (xy 45.548221 -355.739685) (xy 45.539839 -355.7679) (xy 45.539844 -355.797334)
			(xy 45.548235 -355.825546) (xy 45.564318 -355.850198) (xy 45.57522 -355.860096) (xy 45.595951 -355.878284)
			(xy 45.632412 -355.91966) (xy 45.662537 -355.965854) (xy 45.685697 -356.015904) (xy 45.70141 -356.068768)
			(xy 45.709347 -356.123342) (xy 45.709345 -356.178491) (xy 45.701402 -356.233065) (xy 45.685685 -356.285927)
			(xy 45.662521 -356.335976) (xy 45.632392 -356.382167) (xy 45.595927 -356.42354) (xy 45.57522 -356.441756)
			(xy 45.564295 -356.451627) (xy 45.548221 -356.476285) (xy 45.548141 -356.476554) (xy 48.08804 -356.476554)
			(xy 48.092111 -356.420932) (xy 48.104237 -356.366495) (xy 48.12416 -356.314404) (xy 48.151456 -356.265769)
			(xy 48.185542 -356.221626) (xy 48.225691 -356.182917) (xy 48.271049 -356.150466) (xy 48.320649 -356.124965)
			(xy 48.373433 -356.106958) (xy 48.428276 -356.096828) (xy 48.48401 -356.094791) (xy 48.539447 -356.100891)
			(xy 48.593404 -356.114997) (xy 48.644733 -356.136809) (xy 48.692339 -356.165863) (xy 48.735207 -356.201538)
			(xy 48.772424 -356.243075) (xy 48.803197 -356.289588) (xy 48.826869 -356.340085) (xy 48.842937 -356.393492)
			(xy 48.851057 -356.448668) (xy 48.851566 -356.476554) (xy 48.851057 -356.50444) (xy 48.842937 -356.559616)
			(xy 48.826869 -356.613023) (xy 48.803197 -356.66352) (xy 48.772424 -356.710033) (xy 48.735207 -356.75157)
			(xy 48.692339 -356.787245) (xy 48.644733 -356.816299) (xy 48.593404 -356.838111) (xy 48.539447 -356.852217)
			(xy 48.48401 -356.858317) (xy 48.428276 -356.85628) (xy 48.373433 -356.84615) (xy 48.320649 -356.828143)
			(xy 48.271049 -356.802642) (xy 48.225691 -356.770191) (xy 48.185542 -356.731482) (xy 48.151456 -356.687339)
			(xy 48.12416 -356.638704) (xy 48.104237 -356.586613) (xy 48.092111 -356.532176) (xy 48.08804 -356.476554)
			(xy 45.548141 -356.476554) (xy 45.539839 -356.5045) (xy 45.539844 -356.533934) (xy 45.548235 -356.562146)
			(xy 45.564318 -356.586798) (xy 45.57522 -356.596696) (xy 45.595936 -356.614901) (xy 45.632405 -356.656272)
			(xy 45.662536 -356.702463) (xy 45.685701 -356.752512) (xy 45.701417 -356.805375) (xy 45.709355 -356.859951)
			(xy 45.70984 -356.887526) (xy 45.709346 -356.914776) (xy 45.701587 -356.968722) (xy 45.68623 -357.021015)
			(xy 45.663589 -357.07059) (xy 45.634123 -357.116439) (xy 45.598432 -357.157628) (xy 45.557244 -357.193319)
			(xy 45.511395 -357.222786) (xy 45.46182 -357.245428) (xy 45.409528 -357.260786) (xy 45.355582 -357.268546)
			(xy 45.328332 -357.269034) (xy 45.300479 -357.268457) (xy 45.245367 -357.260339) (xy 45.192019 -357.244299)
			(xy 45.141568 -357.220679) (xy 45.095084 -357.189979) (xy 45.053555 -357.15285) (xy 45.01786 -357.110082)
			(xy 44.988758 -357.062581) (xy 44.966867 -357.011356) (xy 44.95927 -356.984554) (xy 44.955023 -356.97043)
			(xy 44.939621 -356.945288) (xy 44.917696 -356.925576) (xy 44.891063 -356.912927) (xy 44.861931 -356.90839)
			(xy 44.847256 -356.909878) (xy 44.834303 -356.911544) (xy 44.808245 -356.913321) (xy 44.795186 -356.913434)
			(xy 44.794932 -356.913434) (xy 44.794678 -356.913434) (xy 44.765642 -356.912893) (xy 44.708242 -356.90409)
			(xy 44.680378 -356.895908) (xy 44.66662 -356.892054) (xy 44.638072 -356.891306) (xy 44.610434 -356.898498)
			(xy 44.58587 -356.913066) (xy 44.566305 -356.933869) (xy 44.553269 -356.959279) (xy 44.547784 -356.987305)
			(xy 44.548552 -357.001572) (xy 44.550076 -357.034846) (xy 44.549665 -357.0621) (xy 44.541901 -357.116052)
			(xy 44.526539 -357.16835) (xy 44.50389 -357.21793) (xy 44.474416 -357.263781) (xy 44.443447 -357.299514)
			(xy 47.423576 -357.299514) (xy 47.427647 -357.243892) (xy 47.439773 -357.189455) (xy 47.459696 -357.137364)
			(xy 47.486992 -357.088729) (xy 47.521078 -357.044586) (xy 47.561227 -357.005877) (xy 47.606585 -356.973426)
			(xy 47.656185 -356.947925) (xy 47.708969 -356.929918) (xy 47.763812 -356.919788) (xy 47.819546 -356.917751)
			(xy 47.874983 -356.923851) (xy 47.92894 -356.937957) (xy 47.980269 -356.959769) (xy 48.027875 -356.988823)
			(xy 48.070743 -357.024498) (xy 48.10796 -357.066035) (xy 48.138733 -357.112548) (xy 48.162405 -357.163045)
			(xy 48.178473 -357.216452) (xy 48.186593 -357.271628) (xy 48.187102 -357.299514) (xy 48.186593 -357.3274)
			(xy 48.178473 -357.382576) (xy 48.162405 -357.435983) (xy 48.138733 -357.48648) (xy 48.10796 -357.532993)
			(xy 48.070743 -357.57453) (xy 48.027875 -357.610205) (xy 47.980269 -357.639259) (xy 47.92894 -357.661071)
			(xy 47.874983 -357.675177) (xy 47.819546 -357.681277) (xy 47.763812 -357.67924) (xy 47.708969 -357.66911)
			(xy 47.656185 -357.651103) (xy 47.606585 -357.625602) (xy 47.561227 -357.593151) (xy 47.521078 -357.554442)
			(xy 47.486992 -357.510299) (xy 47.459696 -357.461664) (xy 47.439773 -357.409573) (xy 47.427647 -357.355136)
			(xy 47.423576 -357.299514) (xy 44.443447 -357.299514) (xy 44.438717 -357.304972) (xy 44.397519 -357.340663)
			(xy 44.351661 -357.370127) (xy 44.302077 -357.392766) (xy 44.249776 -357.408118) (xy 44.195822 -357.41587)
			(xy 44.168568 -357.416354) (xy 44.141318 -357.415852) (xy 44.087373 -357.408092) (xy 44.035082 -357.392736)
			(xy 43.985507 -357.370094) (xy 43.939659 -357.340629) (xy 43.898471 -357.304939) (xy 43.86278 -357.263752)
			(xy 43.833313 -357.217905) (xy 43.810669 -357.168331) (xy 43.795311 -357.11604) (xy 43.787549 -357.062096)
			(xy 43.78706 -357.034846) (xy 43.787536 -357.007272) (xy 43.795484 -356.952698) (xy 43.811205 -356.899838)
			(xy 43.834373 -356.849791) (xy 43.864505 -356.803602) (xy 43.900973 -356.762231) (xy 43.92168 -356.744016)
			(xy 43.932533 -356.734071) (xy 43.948609 -356.709435) (xy 43.957 -356.681239) (xy 43.957009 -356.651821)
			(xy 43.948635 -356.623619) (xy 43.932572 -356.598973) (xy 43.92168 -356.589076) (xy 43.90095 -356.570885)
			(xy 43.864482 -356.529512) (xy 43.834353 -356.483317) (xy 43.81119 -356.433265) (xy 43.795478 -356.3804)
			(xy 43.787543 -356.325822) (xy 43.78706 -356.298246) (xy 43.787663 -356.268495) (xy 43.796938 -356.209719)
			(xy 43.81521 -356.15309) (xy 43.842036 -356.099976) (xy 43.858942 -356.075488) (xy 43.866861 -356.063559)
			(xy 43.87646 -356.036601) (xy 43.878193 -356.008037) (xy 43.871925 -355.980115) (xy 43.85815 -355.955033)
			(xy 43.83795 -355.934763) (xy 43.825668 -355.927406) (xy 43.804606 -355.915307) (xy 43.765515 -355.886475)
			(xy 43.7305 -355.852809) (xy 43.700154 -355.814881) (xy 43.687238 -355.79431) (xy 43.679349 -355.782061)
			(xy 43.657869 -355.762388) (xy 43.631706 -355.749586) (xy 43.602992 -355.744698) (xy 43.574067 -355.748121)
			(xy 43.560492 -355.753416) (xy 43.53728 -355.762901) (xy 43.488948 -355.776254) (xy 43.439259 -355.782984)
			(xy 43.414188 -355.783388) (xy 43.389119 -355.782955) (xy 43.339436 -355.776209) (xy 43.291102 -355.76288)
			(xy 43.267884 -355.753416) (xy 43.254305 -355.748162) (xy 43.225397 -355.744783) (xy 43.196708 -355.749685)
			(xy 43.170562 -355.762471) (xy 43.149078 -355.782106) (xy 43.141138 -355.79431) (xy 43.126569 -355.817441)
			(xy 43.091726 -355.859562) (xy 43.051103 -355.896141) (xy 43.005572 -355.926392) (xy 42.95611 -355.949668)
			(xy 42.903779 -355.965468) (xy 42.8497 -355.973454) (xy 42.795036 -355.973454) (xy 42.740957 -355.965468)
			(xy 42.688626 -355.949668) (xy 42.639164 -355.926392) (xy 42.593633 -355.896141) (xy 42.55301 -355.859562)
			(xy 42.518167 -355.817441) (xy 42.503598 -355.79431) (xy 42.495652 -355.782102) (xy 42.474188 -355.76243)
			(xy 42.44804 -355.749622) (xy 42.41934 -355.744723) (xy 42.390425 -355.748131) (xy 42.376852 -355.753416)
			(xy 42.353645 -355.762913) (xy 42.305311 -355.776261) (xy 42.25562 -355.782986) (xy 42.230548 -355.783388)
			(xy 42.202657 -355.782956) (xy 42.147496 -355.774649) (xy 42.09419 -355.758212) (xy 42.04393 -355.734014)
			(xy 41.997837 -355.702594) (xy 41.956943 -355.664655) (xy 41.922161 -355.621044) (xy 41.894268 -355.572736)
			(xy 41.873886 -355.52081) (xy 41.861472 -355.466427) (xy 41.857303 -355.4108) (xy 31.60268 -355.4108)
			(xy 31.60268 -356.80523) (xy 37.03396 -356.80523) (xy 37.038031 -356.749608) (xy 37.050157 -356.695171)
			(xy 37.07008 -356.64308) (xy 37.097376 -356.594445) (xy 37.131462 -356.550302) (xy 37.171611 -356.511593)
			(xy 37.216969 -356.479142) (xy 37.266569 -356.453641) (xy 37.319353 -356.435634) (xy 37.374196 -356.425504)
			(xy 37.42993 -356.423467) (xy 37.485367 -356.429567) (xy 37.539324 -356.443673) (xy 37.590653 -356.465485)
			(xy 37.60879 -356.476554) (xy 38.399718 -356.476554) (xy 38.403789 -356.420932) (xy 38.415915 -356.366495)
			(xy 38.435838 -356.314404) (xy 38.463134 -356.265769) (xy 38.49722 -356.221626) (xy 38.537369 -356.182917)
			(xy 38.582727 -356.150466) (xy 38.632327 -356.124965) (xy 38.685111 -356.106958) (xy 38.739954 -356.096828)
			(xy 38.795688 -356.094791) (xy 38.851125 -356.100891) (xy 38.905082 -356.114997) (xy 38.956411 -356.136809)
			(xy 39.004017 -356.165863) (xy 39.046885 -356.201538) (xy 39.084102 -356.243075) (xy 39.114875 -356.289588)
			(xy 39.138547 -356.340085) (xy 39.154615 -356.393492) (xy 39.162735 -356.448668) (xy 39.163244 -356.476554)
			(xy 39.162735 -356.50444) (xy 39.154615 -356.559616) (xy 39.138547 -356.613023) (xy 39.114875 -356.66352)
			(xy 39.084102 -356.710033) (xy 39.046885 -356.75157) (xy 39.004017 -356.787245) (xy 38.956411 -356.816299)
			(xy 38.905082 -356.838111) (xy 38.851125 -356.852217) (xy 38.795688 -356.858317) (xy 38.739954 -356.85628)
			(xy 38.685111 -356.84615) (xy 38.632327 -356.828143) (xy 38.582727 -356.802642) (xy 38.537369 -356.770191)
			(xy 38.49722 -356.731482) (xy 38.463134 -356.687339) (xy 38.435838 -356.638704) (xy 38.415915 -356.586613)
			(xy 38.403789 -356.532176) (xy 38.399718 -356.476554) (xy 37.60879 -356.476554) (xy 37.638259 -356.494539)
			(xy 37.681127 -356.530214) (xy 37.718344 -356.571751) (xy 37.749117 -356.618264) (xy 37.772789 -356.668761)
			(xy 37.788857 -356.722168) (xy 37.796977 -356.777344) (xy 37.797486 -356.80523) (xy 37.796977 -356.833116)
			(xy 37.788857 -356.888292) (xy 37.772789 -356.941699) (xy 37.749117 -356.992196) (xy 37.718344 -357.038709)
			(xy 37.681127 -357.080246) (xy 37.638259 -357.115921) (xy 37.590653 -357.144975) (xy 37.539324 -357.166787)
			(xy 37.485367 -357.180893) (xy 37.42993 -357.186993) (xy 37.374196 -357.184956) (xy 37.319353 -357.174826)
			(xy 37.266569 -357.156819) (xy 37.216969 -357.131318) (xy 37.171611 -357.098867) (xy 37.131462 -357.060158)
			(xy 37.097376 -357.016015) (xy 37.07008 -356.96738) (xy 37.050157 -356.915289) (xy 37.038031 -356.860852)
			(xy 37.03396 -356.80523) (xy 31.60268 -356.80523) (xy 31.60268 -357.98506) (xy 39.206424 -357.98506)
			(xy 39.206805 -357.95972) (xy 39.21352 -357.909488) (xy 39.226827 -357.860586) (xy 39.246491 -357.813877)
			(xy 39.272166 -357.770183) (xy 39.3034 -357.730272) (xy 39.321232 -357.712264) (xy 39.330672 -357.702529)
			(xy 39.344468 -357.679196) (xy 39.351619 -357.653049) (xy 39.351618 -357.625942) (xy 39.344464 -357.599795)
			(xy 39.330666 -357.576463) (xy 39.321232 -357.566722) (xy 39.30342 -357.548696) (xy 39.27219 -357.508788)
			(xy 39.246518 -357.465096) (xy 39.226857 -357.41839) (xy 39.213553 -357.369493) (xy 39.20684 -357.319264)
			(xy 39.206424 -357.293926) (xy 39.20691 -357.266675) (xy 39.214666 -357.212727) (xy 39.230021 -357.160432)
			(xy 39.252663 -357.110855) (xy 39.282129 -357.065005) (xy 39.31782 -357.023814) (xy 39.359011 -356.988123)
			(xy 39.404861 -356.958657) (xy 39.454438 -356.936015) (xy 39.506733 -356.92066) (xy 39.560681 -356.912904)
			(xy 39.615183 -356.912904) (xy 39.669131 -356.92066) (xy 39.721426 -356.936015) (xy 39.771003 -356.958657)
			(xy 39.816853 -356.988123) (xy 39.858044 -357.023814) (xy 39.893735 -357.065005) (xy 39.923201 -357.110855)
			(xy 39.945843 -357.160432) (xy 39.961198 -357.212727) (xy 39.968954 -357.266675) (xy 39.9691 -357.274876)
			(xy 40.83177 -357.274876) (xy 40.832255 -357.247625) (xy 40.840015 -357.193679) (xy 40.855372 -357.141385)
			(xy 40.878014 -357.091809) (xy 40.907481 -357.04596) (xy 40.943172 -357.004771) (xy 40.984362 -356.96908)
			(xy 41.030211 -356.939613) (xy 41.079787 -356.916971) (xy 41.132081 -356.901614) (xy 41.186027 -356.893855)
			(xy 41.213278 -356.893368) (xy 41.240528 -356.893899) (xy 41.294472 -356.901652) (xy 41.346765 -356.917003)
			(xy 41.39634 -356.939639) (xy 41.44219 -356.969101) (xy 41.483379 -357.004788) (xy 41.519071 -357.045974)
			(xy 41.548538 -357.091819) (xy 41.571181 -357.141392) (xy 41.586539 -357.193683) (xy 41.594298 -357.247626)
			(xy 41.594786 -357.274876) (xy 41.594544 -357.293543) (xy 41.590858 -357.330695) (xy 41.58742 -357.349044)
			(xy 41.585129 -357.363318) (xy 41.587649 -357.3921) (xy 41.598137 -357.419022) (xy 41.615752 -357.441924)
			(xy 41.63908 -357.458969) (xy 41.666252 -357.468792) (xy 41.680638 -357.470202) (xy 41.70929 -357.472578)
			(xy 41.765453 -357.484869) (xy 41.819137 -357.505447) (xy 41.869127 -357.533844) (xy 41.914291 -357.569419)
			(xy 41.953607 -357.611366) (xy 41.986186 -357.658737) (xy 42.01129 -357.710459) (xy 42.028351 -357.765361)
			(xy 42.036983 -357.822202) (xy 42.037508 -357.850948) (xy 42.037067 -357.8782) (xy 42.029304 -357.93215)
			(xy 42.013943 -357.984445) (xy 41.991296 -358.034023) (xy 41.963993 -358.0765) (xy 48.879506 -358.0765)
			(xy 48.879919 -358.051161) (xy 48.886628 -358.00093) (xy 48.899929 -357.95203) (xy 48.919587 -357.905321)
			(xy 48.945256 -357.861625) (xy 48.976485 -357.821713) (xy 48.994314 -357.803704) (xy 49.003707 -357.79393)
			(xy 49.017495 -357.770605) (xy 49.024645 -357.74447) (xy 49.024651 -357.717375) (xy 49.017513 -357.691237)
			(xy 49.003736 -357.667906) (xy 48.994314 -357.658162) (xy 48.97647 -357.640167) (xy 48.945243 -357.600252)
			(xy 48.919576 -357.556553) (xy 48.899921 -357.509842) (xy 48.886624 -357.460938) (xy 48.879918 -357.410705)
			(xy 48.879506 -357.385366) (xy 48.879992 -357.358115) (xy 48.887748 -357.304167) (xy 48.903103 -357.251872)
			(xy 48.925745 -357.202295) (xy 48.955211 -357.156445) (xy 48.990902 -357.115254) (xy 49.032093 -357.079563)
			(xy 49.077943 -357.050097) (xy 49.12752 -357.027455) (xy 49.179815 -357.0121) (xy 49.233763 -357.004344)
			(xy 49.288265 -357.004344) (xy 49.342213 -357.0121) (xy 49.394508 -357.027455) (xy 49.444085 -357.050097)
			(xy 49.489935 -357.079563) (xy 49.531126 -357.115254) (xy 49.566817 -357.156445) (xy 49.596283 -357.202295)
			(xy 49.618925 -357.251872) (xy 49.63428 -357.304167) (xy 49.642036 -357.358115) (xy 49.642522 -357.385366)
			(xy 49.642079 -357.410704) (xy 49.635374 -357.460933) (xy 49.622079 -357.509833) (xy 49.602426 -357.556542)
			(xy 49.576763 -357.600238) (xy 49.54554 -357.640151) (xy 49.527714 -357.658162) (xy 49.518299 -357.667899)
			(xy 49.504594 -357.691253) (xy 49.497496 -357.717384) (xy 49.497502 -357.744462) (xy 49.504612 -357.77059)
			(xy 49.518328 -357.793937) (xy 49.527714 -357.803704) (xy 49.545547 -357.82171) (xy 49.576774 -357.861623)
			(xy 49.602441 -357.905319) (xy 49.622098 -357.952029) (xy 49.635398 -358.00093) (xy 49.635935 -358.00495)
			(xy 49.911272 -358.00495) (xy 49.911272 -357.95045) (xy 49.919027 -357.896506) (xy 49.93438 -357.844214)
			(xy 49.957018 -357.794639) (xy 49.986481 -357.74879) (xy 50.022168 -357.7076) (xy 50.063353 -357.671908)
			(xy 50.109199 -357.64244) (xy 50.158771 -357.619796) (xy 50.211061 -357.604437) (xy 50.265004 -357.596675)
			(xy 50.292254 -357.596186) (xy 50.32106 -357.596711) (xy 50.378016 -357.605388) (xy 50.433023 -357.62252)
			(xy 50.484832 -357.647721) (xy 50.532268 -357.680417) (xy 50.574256 -357.719867) (xy 50.609841 -357.765176)
			(xy 50.624486 -357.789988) (xy 50.707798 -357.7971) (xy 50.730404 -357.772208) (xy 50.740446 -357.761125)
			(xy 50.754329 -357.734658) (xy 50.759967 -357.705307) (xy 50.756878 -357.67558) (xy 50.745326 -357.648016)
			(xy 50.726298 -357.624968) (xy 50.714148 -357.616252) (xy 50.69202 -357.601012) (xy 50.651853 -357.565328)
			(xy 50.617087 -357.524363) (xy 50.588411 -357.478927) (xy 50.566391 -357.429918) (xy 50.551463 -357.378305)
			(xy 50.543921 -357.325108) (xy 50.54346 -357.298244) (xy 50.543946 -357.270993) (xy 50.551702 -357.217045)
			(xy 50.567057 -357.16475) (xy 50.589699 -357.115173) (xy 50.619165 -357.069323) (xy 50.654856 -357.028132)
			(xy 50.696047 -356.992441) (xy 50.741897 -356.962975) (xy 50.791474 -356.940333) (xy 50.843769 -356.924978)
			(xy 50.897717 -356.917222) (xy 50.952219 -356.917222) (xy 51.006167 -356.924978) (xy 51.058462 -356.940333)
			(xy 51.108039 -356.962975) (xy 51.153889 -356.992441) (xy 51.19508 -357.028132) (xy 51.230771 -357.069323)
			(xy 51.260237 -357.115173) (xy 51.282879 -357.16475) (xy 51.298234 -357.217045) (xy 51.30599 -357.270993)
			(xy 51.306476 -357.298244) (xy 51.305909 -357.327899) (xy 51.296725 -357.386495) (xy 51.278585 -357.442963)
			(xy 51.251926 -357.495945) (xy 51.217391 -357.544164) (xy 51.197002 -357.565706) (xy 51.186943 -357.576775)
			(xy 51.17306 -357.603246) (xy 51.167424 -357.632601) (xy 51.170516 -357.662332) (xy 51.182073 -357.689898)
			(xy 51.201106 -357.712946) (xy 51.213258 -357.721662) (xy 51.235394 -357.736891) (xy 51.275561 -357.772577)
			(xy 51.310325 -357.813544) (xy 51.339 -357.858982) (xy 51.361019 -357.907993) (xy 51.375946 -357.959607)
			(xy 51.383486 -358.012805) (xy 51.383946 -358.03967) (xy 51.383394 -358.066919) (xy 51.375643 -358.120862)
			(xy 51.360293 -358.173153) (xy 51.337658 -358.222728) (xy 51.308199 -358.268576) (xy 51.272514 -358.309766)
			(xy 51.231331 -358.345458) (xy 51.185487 -358.374926) (xy 51.135917 -358.397569) (xy 51.083629 -358.412928)
			(xy 51.029687 -358.420689) (xy 51.002438 -358.421178) (xy 50.97328 -358.420631) (xy 50.915643 -358.411762)
			(xy 50.860027 -358.394223) (xy 50.807728 -358.368424) (xy 50.759965 -358.334966) (xy 50.717851 -358.294628)
			(xy 50.69967 -358.271826) (xy 50.690711 -358.260963) (xy 50.668153 -358.244136) (xy 50.64186 -358.234099)
			(xy 50.613827 -358.231613) (xy 50.586179 -358.236866) (xy 50.561011 -358.24946) (xy 50.550318 -358.258618)
			(xy 50.529074 -358.27741) (xy 50.482094 -358.309185) (xy 50.430927 -358.333651) (xy 50.376701 -358.350272)
			(xy 50.320612 -358.358678) (xy 50.292254 -358.359202) (xy 50.265004 -358.358725) (xy 50.211061 -358.350963)
			(xy 50.158771 -358.335604) (xy 50.109199 -358.31296) (xy 50.063353 -358.283492) (xy 50.022168 -358.2478)
			(xy 49.986481 -358.20661) (xy 49.957018 -358.160761) (xy 49.93438 -358.111186) (xy 49.919027 -358.058894)
			(xy 49.911272 -358.00495) (xy 49.635935 -358.00495) (xy 49.642108 -358.051161) (xy 49.642522 -358.0765)
			(xy 49.642036 -358.103751) (xy 49.63428 -358.157699) (xy 49.618925 -358.209994) (xy 49.596283 -358.259571)
			(xy 49.566817 -358.305421) (xy 49.531126 -358.346612) (xy 49.489935 -358.382303) (xy 49.444085 -358.411769)
			(xy 49.394508 -358.434411) (xy 49.342213 -358.449766) (xy 49.288265 -358.457522) (xy 49.233763 -358.457522)
			(xy 49.179815 -358.449766) (xy 49.12752 -358.434411) (xy 49.077943 -358.411769) (xy 49.032093 -358.382303)
			(xy 48.990902 -358.346612) (xy 48.955211 -358.305421) (xy 48.925745 -358.259571) (xy 48.903103 -358.209994)
			(xy 48.887748 -358.157699) (xy 48.879992 -358.103751) (xy 48.879506 -358.0765) (xy 41.963993 -358.0765)
			(xy 41.961825 -358.079873) (xy 41.926129 -358.121063) (xy 41.884934 -358.156753) (xy 41.839081 -358.186219)
			(xy 41.7895 -358.208859) (xy 41.737203 -358.224214) (xy 41.683252 -358.23197) (xy 41.656 -358.232456)
			(xy 41.628751 -358.231922) (xy 41.574807 -358.224167) (xy 41.522516 -358.208814) (xy 41.472942 -358.186177)
			(xy 41.427094 -358.156715) (xy 41.385905 -358.121029) (xy 41.350214 -358.079844) (xy 41.320746 -358.034)
			(xy 41.298102 -357.984429) (xy 41.282743 -357.93214) (xy 41.274981 -357.878197) (xy 41.274492 -357.850948)
			(xy 41.27473 -357.832281) (xy 41.278424 -357.79513) (xy 41.281858 -357.77678) (xy 41.284144 -357.762505)
			(xy 41.28163 -357.733721) (xy 41.271145 -357.706797) (xy 41.25353 -357.683894) (xy 41.2302 -357.666849)
			(xy 41.203027 -357.65703) (xy 41.18864 -357.655622) (xy 41.159985 -357.653254) (xy 41.103817 -357.64097)
			(xy 41.050129 -357.620398) (xy 41.000134 -357.592003) (xy 40.954967 -357.556428) (xy 40.915648 -357.514478)
			(xy 40.88307 -357.467103) (xy 40.857969 -357.415376) (xy 40.840913 -357.360469) (xy 40.83229 -357.303624)
			(xy 40.83177 -357.274876) (xy 39.9691 -357.274876) (xy 39.96944 -357.293926) (xy 39.969031 -357.319265)
			(xy 39.962318 -357.369495) (xy 39.949016 -357.418395) (xy 39.929357 -357.465104) (xy 39.903688 -357.508799)
			(xy 39.87246 -357.548712) (xy 39.854632 -357.566722) (xy 39.845256 -357.576494) (xy 39.831545 -357.599837)
			(xy 39.82444 -357.625959) (xy 39.824439 -357.653031) (xy 39.831541 -357.679154) (xy 39.84525 -357.702498)
			(xy 39.854632 -357.712264) (xy 39.872449 -357.730285) (xy 39.903676 -357.770195) (xy 39.929346 -357.813888)
			(xy 39.949006 -357.860595) (xy 39.962309 -357.909493) (xy 39.969023 -357.959722) (xy 39.969319 -357.977694)
			(xy 40.221914 -357.977694) (xy 40.225985 -357.922072) (xy 40.238111 -357.867635) (xy 40.258034 -357.815544)
			(xy 40.28533 -357.766909) (xy 40.319416 -357.722766) (xy 40.359565 -357.684057) (xy 40.404923 -357.651606)
			(xy 40.454523 -357.626105) (xy 40.507307 -357.608098) (xy 40.56215 -357.597968) (xy 40.617884 -357.595931)
			(xy 40.673321 -357.602031) (xy 40.727278 -357.616137) (xy 40.778607 -357.637949) (xy 40.826213 -357.667003)
			(xy 40.869081 -357.702678) (xy 40.906298 -357.744215) (xy 40.937071 -357.790728) (xy 40.960743 -357.841225)
			(xy 40.976811 -357.894632) (xy 40.984931 -357.949808) (xy 40.98544 -357.977694) (xy 40.984931 -358.00558)
			(xy 40.976811 -358.060756) (xy 40.960743 -358.114163) (xy 40.937071 -358.16466) (xy 40.906298 -358.211173)
			(xy 40.869081 -358.25271) (xy 40.826213 -358.288385) (xy 40.778607 -358.317439) (xy 40.727278 -358.339251)
			(xy 40.673321 -358.353357) (xy 40.617884 -358.359457) (xy 40.56215 -358.35742) (xy 40.507307 -358.34729)
			(xy 40.454523 -358.329283) (xy 40.404923 -358.303782) (xy 40.359565 -358.271331) (xy 40.319416 -358.232622)
			(xy 40.28533 -358.188479) (xy 40.258034 -358.139844) (xy 40.238111 -358.087753) (xy 40.225985 -358.033316)
			(xy 40.221914 -357.977694) (xy 39.969319 -357.977694) (xy 39.96944 -357.98506) (xy 39.968954 -358.012311)
			(xy 39.961198 -358.066259) (xy 39.945843 -358.118554) (xy 39.923201 -358.168131) (xy 39.893735 -358.213981)
			(xy 39.858044 -358.255172) (xy 39.816853 -358.290863) (xy 39.771003 -358.320329) (xy 39.721426 -358.342971)
			(xy 39.669131 -358.358326) (xy 39.615183 -358.366082) (xy 39.560681 -358.366082) (xy 39.506733 -358.358326)
			(xy 39.454438 -358.342971) (xy 39.404861 -358.320329) (xy 39.359011 -358.290863) (xy 39.31782 -358.255172)
			(xy 39.282129 -358.213981) (xy 39.252663 -358.168131) (xy 39.230021 -358.118554) (xy 39.214666 -358.066259)
			(xy 39.20691 -358.012311) (xy 39.206424 -357.98506) (xy 31.60268 -357.98506) (xy 31.60268 -361.023408)
			(xy 31.628588 -361.049316) (xy 38.985952 -361.049316) (xy 38.986493 -361.022067) (xy 38.994246 -360.968123)
			(xy 39.009597 -360.915832) (xy 39.032234 -360.866258) (xy 39.061695 -360.820409) (xy 39.09738 -360.77922)
			(xy 39.138564 -360.743528) (xy 39.184409 -360.714061) (xy 39.23398 -360.691417) (xy 39.286269 -360.676058)
			(xy 39.340211 -360.668297) (xy 39.36746 -360.667808) (xy 39.394829 -360.668296) (xy 39.449008 -360.676108)
			(xy 39.501511 -360.691592) (xy 39.551258 -360.714429) (xy 39.597226 -360.744149) (xy 39.618158 -360.761788)
			(xy 39.629486 -360.771024) (xy 39.656043 -360.7832) (xy 39.68496 -360.787373) (xy 39.713877 -360.7832)
			(xy 39.740434 -360.771024) (xy 39.751762 -360.761788) (xy 39.772696 -360.744151) (xy 39.818668 -360.71444)
			(xy 39.868416 -360.691603) (xy 39.920916 -360.676112) (xy 39.975091 -360.668283) (xy 40.00246 -360.667808)
			(xy 40.031376 -360.668352) (xy 40.088546 -360.677075) (xy 40.143745 -360.694328) (xy 40.195706 -360.719715)
			(xy 40.243241 -360.752654) (xy 40.285259 -360.792391) (xy 40.30345 -360.814874) (xy 40.313347 -360.826679)
			(xy 40.338671 -360.844198) (xy 40.368064 -360.853374) (xy 40.398856 -360.853374) (xy 40.428249 -360.844198)
			(xy 40.453573 -360.826679) (xy 40.46347 -360.814874) (xy 40.481671 -360.792399) (xy 40.52369 -360.752665)
			(xy 40.571223 -360.719726) (xy 40.623182 -360.694336) (xy 40.678377 -360.677077) (xy 40.735545 -360.668345)
			(xy 40.76446 -360.667808) (xy 40.791713 -360.668293) (xy 40.845664 -360.676045) (xy 40.897962 -360.691396)
			(xy 40.947543 -360.714035) (xy 40.993397 -360.743501) (xy 41.034591 -360.779192) (xy 41.070285 -360.820384)
			(xy 41.099753 -360.866236) (xy 41.122395 -360.915815) (xy 41.13775 -360.968113) (xy 41.145506 -361.022063)
			(xy 41.145968 -361.049316) (xy 41.145407 -361.078446) (xy 41.136539 -361.136027) (xy 41.119011 -361.191589)
			(xy 41.093232 -361.243835) (xy 41.059802 -361.29155) (xy 41.04005 -361.312968) (xy 41.031213 -361.322807)
			(xy 41.018431 -361.345945) (xy 41.012034 -361.371593) (xy 41.012456 -361.398024) (xy 41.019666 -361.423456)
			(xy 41.033179 -361.446175) (xy 41.042336 -361.455716) (xy 41.063488 -361.477374) (xy 41.089422 -361.512612)
			(xy 44.706032 -361.512612) (xy 44.706601 -361.483444) (xy 44.715499 -361.425789) (xy 44.733074 -361.370162)
			(xy 44.758916 -361.317861) (xy 44.792423 -361.270106) (xy 44.832811 -361.228011) (xy 44.855638 -361.209844)
			(xy 44.866037 -361.201446) (xy 44.882331 -361.180263) (xy 44.892574 -361.155579) (xy 44.896065 -361.129083)
			(xy 44.892565 -361.102588) (xy 44.882314 -361.077908) (xy 44.866013 -361.05673) (xy 44.855638 -361.0483)
			(xy 44.832794 -361.03015) (xy 44.792392 -360.988061) (xy 44.758878 -360.940306) (xy 44.733034 -360.888)
			(xy 44.715466 -360.832365) (xy 44.706583 -360.774703) (xy 44.706032 -360.745532) (xy 44.706485 -360.718278)
			(xy 44.714239 -360.664325) (xy 44.729593 -360.612024) (xy 44.752235 -360.562442) (xy 44.781703 -360.516586)
			(xy 44.817398 -360.475392) (xy 44.858593 -360.439698) (xy 44.904449 -360.410231) (xy 44.954032 -360.38759)
			(xy 45.006333 -360.372237) (xy 45.060286 -360.364485) (xy 45.08754 -360.364024) (xy 45.116456 -360.364576)
			(xy 45.173626 -360.373297) (xy 45.228824 -360.390547) (xy 45.280786 -360.415933) (xy 45.328321 -360.448871)
			(xy 45.370339 -360.488607) (xy 45.38853 -360.51109) (xy 45.398427 -360.522895) (xy 45.423751 -360.540414)
			(xy 45.453144 -360.54959) (xy 45.483936 -360.54959) (xy 45.513329 -360.540414) (xy 45.538653 -360.522895)
			(xy 45.54855 -360.51109) (xy 45.566767 -360.488628) (xy 45.608781 -360.448892) (xy 45.656311 -360.415951)
			(xy 45.708267 -360.390559) (xy 45.76346 -360.373298) (xy 45.820626 -360.364563) (xy 45.84954 -360.364024)
			(xy 45.878086 -360.364584) (xy 45.934539 -360.373094) (xy 45.989094 -360.389919) (xy 46.040535 -360.414683)
			(xy 46.064424 -360.430318) (xy 46.075556 -360.4374) (xy 46.100412 -360.446212) (xy 46.126699 -360.448341)
			(xy 46.152649 -360.443643) (xy 46.176521 -360.432435) (xy 46.196711 -360.415469) (xy 46.204632 -360.404918)
			(xy 46.22004 -360.383903) (xy 46.255641 -360.345851) (xy 46.296087 -360.312995) (xy 46.340626 -360.285946)
			(xy 46.38843 -360.265206) (xy 46.438611 -360.251161) (xy 46.490235 -360.244072) (xy 46.51629 -360.243628)
			(xy 46.545207 -360.244143) (xy 46.602379 -360.252871) (xy 46.657578 -360.270129) (xy 46.70954 -360.295521)
			(xy 46.757074 -360.328466) (xy 46.79909 -360.368208) (xy 46.81728 -360.390694) (xy 46.827177 -360.402499)
			(xy 46.852501 -360.420018) (xy 46.881894 -360.429194) (xy 46.912686 -360.429194) (xy 46.942079 -360.420018)
			(xy 46.967403 -360.402499) (xy 46.9773 -360.390694) (xy 46.995489 -360.368209) (xy 47.03751 -360.328474)
			(xy 47.085045 -360.295536) (xy 47.137007 -360.270148) (xy 47.192204 -360.252892) (xy 47.249374 -360.244163)
			(xy 47.27829 -360.243628) (xy 47.305544 -360.244065) (xy 47.359498 -360.251821) (xy 47.411799 -360.267178)
			(xy 47.461381 -360.289822) (xy 47.507236 -360.319292) (xy 47.54843 -360.354989) (xy 47.584123 -360.396185)
			(xy 47.613591 -360.442042) (xy 47.636231 -360.491626) (xy 47.651584 -360.543927) (xy 47.659337 -360.597882)
			(xy 47.659798 -360.625136) (xy 47.659322 -360.651178) (xy 47.652244 -360.702778) (xy 47.638212 -360.752936)
			(xy 47.617485 -360.800718) (xy 47.59045 -360.845235) (xy 47.557609 -360.88566) (xy 47.538894 -360.903774)
			(xy 47.528968 -360.91375) (xy 47.514501 -360.937875) (xy 47.507156 -360.965029) (xy 47.507487 -360.993157)
			(xy 47.515471 -361.020131) (xy 47.530501 -361.043909) (xy 47.540672 -361.053634) (xy 47.56026 -361.07179)
			(xy 47.59465 -361.112652) (xy 47.623006 -361.157912) (xy 47.644772 -361.206684) (xy 47.659523 -361.258015)
			(xy 47.666971 -361.310902) (xy 47.667418 -361.337606) (xy 47.66692 -361.365376) (xy 47.658866 -361.420328)
			(xy 47.64293 -361.473533) (xy 47.619447 -361.523864) (xy 47.588915 -361.570258) (xy 47.551979 -361.611735)
			(xy 47.53102 -361.62996) (xy 47.520368 -361.639481) (xy 47.504384 -361.663145) (xy 47.495592 -361.690314)
			(xy 47.494682 -361.718856) (xy 47.501726 -361.74653) (xy 47.516171 -361.771164) (xy 47.526194 -361.781344)
			(xy 47.544559 -361.799414) (xy 47.576728 -361.839658) (xy 47.603195 -361.883862) (xy 47.623477 -361.931223)
			(xy 47.637207 -361.980882) (xy 47.644135 -362.031935) (xy 47.644558 -362.057696) (xy 47.6441 -362.085067)
			(xy 47.636282 -362.139246) (xy 47.620791 -362.19175) (xy 47.597948 -362.241497) (xy 47.568221 -362.287463)
			(xy 47.550578 -362.308394) (xy 47.541347 -362.319725) (xy 47.529172 -362.346282) (xy 47.524999 -362.375197)
			(xy 47.52917 -362.404112) (xy 47.541343 -362.43067) (xy 47.550578 -362.441998) (xy 47.568215 -362.462934)
			(xy 47.597939 -362.508901) (xy 47.620784 -362.558647) (xy 47.636281 -362.611149) (xy 47.64411 -362.665327)
			(xy 47.64411 -362.720067) (xy 47.636282 -362.774245) (xy 47.620787 -362.826747) (xy 47.597942 -362.876493)
			(xy 47.568218 -362.922461) (xy 47.550578 -362.943394) (xy 47.541347 -362.954725) (xy 47.529172 -362.981282)
			(xy 47.524999 -363.010197) (xy 47.52917 -363.039112) (xy 47.541343 -363.06567) (xy 47.550578 -363.076998)
			(xy 47.568215 -363.097934) (xy 47.597939 -363.143901) (xy 47.620784 -363.193647) (xy 47.636281 -363.246149)
			(xy 47.63987 -363.270984) (xy 48.72126 -363.270984) (xy 48.72126 -363.186288) (xy 48.729311 -363.101974)
			(xy 48.74534 -363.018808) (xy 48.769201 -362.937541) (xy 48.80068 -362.858911) (xy 48.839491 -362.78363)
			(xy 48.885281 -362.712378) (xy 48.937637 -362.645802) (xy 48.996085 -362.584504) (xy 49.060095 -362.529039)
			(xy 49.129087 -362.47991) (xy 49.202437 -362.437561) (xy 49.27948 -362.402377) (xy 49.359519 -362.374675)
			(xy 49.441828 -362.354707) (xy 49.525663 -362.342654) (xy 49.610264 -362.338624) (xy 49.694865 -362.342654)
			(xy 49.7787 -362.354707) (xy 49.861009 -362.374675) (xy 49.941048 -362.402377) (xy 50.018091 -362.437561)
			(xy 50.091441 -362.47991) (xy 50.160433 -362.529039) (xy 50.224443 -362.584504) (xy 50.282891 -362.645802)
			(xy 50.335247 -362.712378) (xy 50.381037 -362.78363) (xy 50.419848 -362.858911) (xy 50.451327 -362.937541)
			(xy 50.475188 -363.018808) (xy 50.491217 -363.101974) (xy 50.499268 -363.186288) (xy 50.499772 -363.228636)
			(xy 51.245773 -363.228636) (xy 51.249809 -363.145189) (xy 51.261881 -363.062521) (xy 51.281874 -362.981404)
			(xy 51.309603 -362.902595) (xy 51.344809 -362.82683) (xy 51.387163 -362.754817) (xy 51.436269 -362.687228)
			(xy 51.49167 -362.624694) (xy 51.552847 -362.567799) (xy 51.61923 -362.517073) (xy 51.690198 -362.472992)
			(xy 51.76509 -362.435966) (xy 51.843206 -362.40634) (xy 51.923816 -362.384392) (xy 52.006168 -362.370327)
			(xy 52.089494 -362.364275) (xy 52.173014 -362.366294) (xy 52.25595 -362.376364) (xy 52.337526 -362.394392)
			(xy 52.416982 -362.420209) (xy 52.493575 -362.453574) (xy 52.566591 -362.494175) (xy 52.635347 -362.541634)
			(xy 52.699201 -362.595507) (xy 52.757558 -362.655292) (xy 52.809873 -362.720429) (xy 52.855656 -362.790312)
			(xy 52.894481 -362.864287) (xy 52.925986 -362.941664) (xy 52.949875 -363.021721) (xy 52.965926 -363.103709)
			(xy 52.973989 -363.186864) (xy 52.974494 -363.228636) (xy 52.973989 -363.270408) (xy 52.965926 -363.353563)
			(xy 52.949875 -363.435551) (xy 52.925986 -363.515608) (xy 52.894481 -363.592985) (xy 52.855656 -363.66696)
			(xy 52.809873 -363.736843) (xy 52.757558 -363.80198) (xy 52.699201 -363.861765) (xy 52.635347 -363.915638)
			(xy 52.566591 -363.963097) (xy 52.493575 -364.003698) (xy 52.416982 -364.037063) (xy 52.337526 -364.06288)
			(xy 52.25595 -364.080908) (xy 52.173014 -364.090978) (xy 52.089494 -364.092997) (xy 52.006168 -364.086945)
			(xy 51.923816 -364.07288) (xy 51.843206 -364.050932) (xy 51.76509 -364.021306) (xy 51.690198 -363.98428)
			(xy 51.61923 -363.940199) (xy 51.552847 -363.889473) (xy 51.49167 -363.832578) (xy 51.436269 -363.770044)
			(xy 51.387163 -363.702455) (xy 51.344809 -363.630442) (xy 51.309603 -363.554677) (xy 51.281874 -363.475868)
			(xy 51.261881 -363.394751) (xy 51.249809 -363.312083) (xy 51.245773 -363.228636) (xy 50.499772 -363.228636)
			(xy 50.499268 -363.270984) (xy 50.491217 -363.355298) (xy 50.475188 -363.438464) (xy 50.451327 -363.519731)
			(xy 50.419848 -363.598361) (xy 50.381037 -363.673642) (xy 50.335247 -363.744894) (xy 50.282891 -363.81147)
			(xy 50.224443 -363.872768) (xy 50.160433 -363.928233) (xy 50.091441 -363.977362) (xy 50.018091 -364.019711)
			(xy 49.941048 -364.054895) (xy 49.861009 -364.082597) (xy 49.7787 -364.102565) (xy 49.694865 -364.114618)
			(xy 49.610264 -364.118649) (xy 49.525663 -364.114618) (xy 49.441828 -364.102565) (xy 49.359519 -364.082597)
			(xy 49.27948 -364.054895) (xy 49.202437 -364.019711) (xy 49.129087 -363.977362) (xy 49.060095 -363.928233)
			(xy 48.996085 -363.872768) (xy 48.937637 -363.81147) (xy 48.885281 -363.744894) (xy 48.839491 -363.673642)
			(xy 48.80068 -363.598361) (xy 48.769201 -363.519731) (xy 48.74534 -363.438464) (xy 48.729311 -363.355298)
			(xy 48.72126 -363.270984) (xy 47.63987 -363.270984) (xy 47.64411 -363.300327) (xy 47.64411 -363.355067)
			(xy 47.636282 -363.409245) (xy 47.620787 -363.461747) (xy 47.597942 -363.511493) (xy 47.568218 -363.557461)
			(xy 47.550578 -363.578394) (xy 47.541347 -363.589725) (xy 47.529172 -363.616282) (xy 47.524999 -363.645197)
			(xy 47.52917 -363.674112) (xy 47.541343 -363.70067) (xy 47.550578 -363.711998) (xy 47.568226 -363.732923)
			(xy 47.597937 -363.778897) (xy 47.620772 -363.828647) (xy 47.636261 -363.881149) (xy 47.644086 -363.935326)
			(xy 47.644558 -363.962696) (xy 47.644141 -363.989951) (xy 47.636383 -364.043906) (xy 47.621025 -364.096208)
			(xy 47.598379 -364.145791) (xy 47.568907 -364.191647) (xy 47.533208 -364.232841) (xy 47.49201 -364.268535)
			(xy 47.446151 -364.298001) (xy 47.396565 -364.320641) (xy 47.344261 -364.335993) (xy 47.290305 -364.343744)
			(xy 47.26305 -364.344204) (xy 47.234133 -364.343686) (xy 47.17696 -364.334962) (xy 47.121759 -364.317706)
			(xy 47.069797 -364.292315) (xy 47.022263 -364.259369) (xy 46.980249 -364.219625) (xy 46.96206 -364.197138)
			(xy 46.952163 -364.185333) (xy 46.926839 -364.167814) (xy 46.897446 -364.158638) (xy 46.866654 -364.158638)
			(xy 46.837261 -364.167814) (xy 46.811937 -364.185333) (xy 46.80204 -364.197138) (xy 46.783836 -364.21961)
			(xy 46.741818 -364.259344) (xy 46.694285 -364.292284) (xy 46.642327 -364.317674) (xy 46.587132 -364.334933)
			(xy 46.529965 -364.343666) (xy 46.50105 -364.344204) (xy 46.473798 -364.343698) (xy 46.419849 -364.335948)
			(xy 46.367551 -364.320598) (xy 46.317971 -364.297961) (xy 46.272117 -364.268498) (xy 46.230924 -364.232808)
			(xy 46.19523 -364.191619) (xy 46.165761 -364.145769) (xy 46.143118 -364.096192) (xy 46.127762 -364.043896)
			(xy 46.120005 -363.989948) (xy 46.119542 -363.962696) (xy 46.119995 -363.935325) (xy 46.127815 -363.881145)
			(xy 46.143306 -363.828642) (xy 46.166151 -363.778895) (xy 46.195879 -363.732929) (xy 46.213522 -363.711998)
			(xy 46.222761 -363.700673) (xy 46.234935 -363.674114) (xy 46.239106 -363.645197) (xy 46.234933 -363.61628)
			(xy 46.222758 -363.589722) (xy 46.213522 -363.578394) (xy 46.195878 -363.557464) (xy 46.166153 -363.511496)
			(xy 46.143309 -363.461749) (xy 46.127813 -363.409247) (xy 46.119985 -363.355068) (xy 46.119985 -363.300326)
			(xy 46.127814 -363.246148) (xy 46.143311 -363.193645) (xy 46.166156 -363.143899) (xy 46.195881 -363.097931)
			(xy 46.213522 -363.076998) (xy 46.222761 -363.065673) (xy 46.234935 -363.039114) (xy 46.239106 -363.010197)
			(xy 46.234933 -362.98128) (xy 46.222758 -362.954722) (xy 46.213522 -362.943394) (xy 46.195878 -362.922464)
			(xy 46.166153 -362.876496) (xy 46.143309 -362.826749) (xy 46.127813 -362.774247) (xy 46.119985 -362.720068)
			(xy 46.119985 -362.665326) (xy 46.127814 -362.611148) (xy 46.143311 -362.558645) (xy 46.166156 -362.508899)
			(xy 46.195881 -362.462931) (xy 46.213522 -362.441998) (xy 46.222761 -362.430673) (xy 46.234935 -362.404114)
			(xy 46.239106 -362.375197) (xy 46.234933 -362.34628) (xy 46.222758 -362.319722) (xy 46.213522 -362.308394)
			(xy 46.19587 -362.287472) (xy 46.166159 -362.241497) (xy 46.143326 -362.191747) (xy 46.127838 -362.139244)
			(xy 46.120014 -362.085066) (xy 46.119542 -362.057696) (xy 46.119779 -362.038641) (xy 46.123595 -362.000723)
			(xy 46.127162 -361.982004) (xy 46.129464 -361.968526) (xy 46.127624 -361.941254) (xy 46.118615 -361.915448)
			(xy 46.103081 -361.892958) (xy 46.082137 -361.875395) (xy 46.057284 -361.864018) (xy 46.030303 -361.859643)
			(xy 46.003128 -361.862584) (xy 45.990256 -361.867196) (xy 45.967794 -361.875742) (xy 45.921251 -361.887724)
			(xy 45.87357 -361.893759) (xy 45.84954 -361.89412) (xy 45.820623 -361.893603) (xy 45.76345 -361.884878)
			(xy 45.70825 -361.867622) (xy 45.656288 -361.84223) (xy 45.608754 -361.809285) (xy 45.566739 -361.769541)
			(xy 45.54855 -361.747054) (xy 45.538653 -361.735249) (xy 45.513329 -361.71773) (xy 45.483936 -361.708554)
			(xy 45.453144 -361.708554) (xy 45.423751 -361.71773) (xy 45.398427 -361.735249) (xy 45.38853 -361.747054)
			(xy 45.370336 -361.769534) (xy 45.328315 -361.809267) (xy 45.28078 -361.842205) (xy 45.22882 -361.867593)
			(xy 45.173624 -361.884851) (xy 45.116456 -361.893583) (xy 45.08754 -361.89412) (xy 45.060289 -361.893608)
			(xy 45.00634 -361.885856) (xy 44.954044 -361.870506) (xy 44.904465 -361.847869) (xy 44.858612 -361.818406)
			(xy 44.817419 -361.782718) (xy 44.781725 -361.74153) (xy 44.752256 -361.695681) (xy 44.729612 -361.646105)
			(xy 44.714255 -361.593811) (xy 44.706496 -361.539863) (xy 44.706032 -361.512612) (xy 41.089422 -361.512612)
			(xy 41.09937 -361.526129) (xy 41.127101 -361.579939) (xy 41.145985 -361.637453) (xy 41.155547 -361.697228)
			(xy 41.156128 -361.727496) (xy 41.155677 -361.754867) (xy 41.147858 -361.809047) (xy 41.132367 -361.861551)
			(xy 41.109521 -361.911298) (xy 41.079792 -361.957264) (xy 41.062148 -361.978194) (xy 41.052919 -361.989526)
			(xy 41.040748 -362.016083) (xy 41.036577 -362.044997) (xy 41.040746 -362.073911) (xy 41.052916 -362.100469)
			(xy 41.062148 -362.111798) (xy 41.079786 -362.132733) (xy 41.109513 -362.1787) (xy 41.13236 -362.228446)
			(xy 41.147857 -362.280948) (xy 41.155687 -362.335126) (xy 41.155687 -362.389868) (xy 41.147859 -362.444046)
			(xy 41.132362 -362.496549) (xy 41.109516 -362.546295) (xy 41.079789 -362.592262) (xy 41.062148 -362.613194)
			(xy 41.052919 -362.624526) (xy 41.040748 -362.651083) (xy 41.036577 -362.679997) (xy 41.040746 -362.708911)
			(xy 41.052916 -362.735469) (xy 41.062148 -362.746798) (xy 41.079792 -362.767727) (xy 41.109504 -362.8137)
			(xy 41.13234 -362.863448) (xy 41.14783 -362.91595) (xy 41.155656 -362.970126) (xy 41.156128 -362.997496)
			(xy 41.155634 -363.026414) (xy 41.146904 -363.083588) (xy 41.129643 -363.138788) (xy 41.104247 -363.19075)
			(xy 41.071298 -363.238283) (xy 41.031551 -363.280298) (xy 41.009062 -363.298486) (xy 40.997256 -363.308385)
			(xy 40.97973 -363.333706) (xy 40.970549 -363.3631) (xy 40.970548 -363.393895) (xy 40.979728 -363.42329)
			(xy 40.997253 -363.448611) (xy 41.009062 -363.458506) (xy 41.02984 -363.475265) (xy 41.066968 -363.513618)
			(xy 41.098388 -363.556773) (xy 41.123486 -363.603885) (xy 41.141771 -363.654037) (xy 41.152887 -363.706247)
			(xy 41.156617 -363.759498) (xy 41.152888 -363.812748) (xy 41.141773 -363.864959) (xy 41.123488 -363.91511)
			(xy 41.098391 -363.962223) (xy 41.066972 -364.005378) (xy 41.029844 -364.043732) (xy 41.009062 -364.060486)
			(xy 40.997256 -364.070385) (xy 40.97973 -364.095706) (xy 40.970549 -364.1251) (xy 40.970548 -364.155895)
			(xy 40.979728 -364.18529) (xy 40.997253 -364.210611) (xy 41.009062 -364.220506) (xy 41.03154 -364.238703)
			(xy 41.071278 -364.280721) (xy 41.104218 -364.328254) (xy 41.129608 -364.380214) (xy 41.146865 -364.435411)
			(xy 41.155593 -364.49258) (xy 41.156128 -364.521496) (xy 41.155566 -364.550626) (xy 41.149178 -364.592108)
			(xy 55.39308 -364.592108) (xy 55.397151 -364.536486) (xy 55.409277 -364.482049) (xy 55.4292 -364.429958)
			(xy 55.456496 -364.381323) (xy 55.490582 -364.33718) (xy 55.530731 -364.298471) (xy 55.576089 -364.26602)
			(xy 55.625689 -364.240519) (xy 55.678473 -364.222512) (xy 55.733316 -364.212382) (xy 55.78905 -364.210345)
			(xy 55.844487 -364.216445) (xy 55.898444 -364.230551) (xy 55.949773 -364.252363) (xy 55.997379 -364.281417)
			(xy 56.040247 -364.317092) (xy 56.077464 -364.358629) (xy 56.108237 -364.405142) (xy 56.131909 -364.455639)
			(xy 56.147977 -364.509046) (xy 56.156097 -364.564222) (xy 56.156606 -364.592108) (xy 56.156097 -364.619994)
			(xy 56.147977 -364.67517) (xy 56.131909 -364.728577) (xy 56.108237 -364.779074) (xy 56.077464 -364.825587)
			(xy 56.040247 -364.867124) (xy 55.997379 -364.902799) (xy 55.949773 -364.931853) (xy 55.898444 -364.953665)
			(xy 55.844487 -364.967771) (xy 55.78905 -364.973871) (xy 55.733316 -364.971834) (xy 55.678473 -364.961704)
			(xy 55.625689 -364.943697) (xy 55.576089 -364.918196) (xy 55.530731 -364.885745) (xy 55.490582 -364.847036)
			(xy 55.456496 -364.802893) (xy 55.4292 -364.754258) (xy 55.409277 -364.702167) (xy 55.397151 -364.64773)
			(xy 55.39308 -364.592108) (xy 41.149178 -364.592108) (xy 41.146699 -364.608208) (xy 41.129172 -364.66377)
			(xy 41.103393 -364.716016) (xy 41.069963 -364.763731) (xy 41.05021 -364.785148) (xy 41.039828 -364.796775)
			(xy 41.026037 -364.824712) (xy 41.021295 -364.855504) (xy 41.02604 -364.886296) (xy 41.039833 -364.914232)
			(xy 41.05021 -364.925864) (xy 41.069921 -364.947315) (xy 41.10333 -364.995035) (xy 41.129104 -365.047275)
			(xy 41.146646 -365.102823) (xy 41.15555 -365.16039) (xy 41.156128 -365.189516) (xy 41.155637 -365.216767)
			(xy 41.147879 -365.270713) (xy 41.132523 -365.323007) (xy 41.109881 -365.372583) (xy 41.080415 -365.418432)
			(xy 41.044724 -365.459622) (xy 41.003535 -365.495313) (xy 40.957686 -365.524779) (xy 40.90811 -365.547421)
			(xy 40.855817 -365.562778) (xy 40.801871 -365.570537) (xy 40.77462 -365.571024) (xy 40.745702 -365.57052)
			(xy 40.688529 -365.561792) (xy 40.633329 -365.544533) (xy 40.581366 -365.519139) (xy 40.533833 -365.486192)
			(xy 40.491818 -365.446446) (xy 40.47363 -365.423958) (xy 40.463733 -365.412153) (xy 40.438409 -365.394634)
			(xy 40.409016 -365.385458) (xy 40.378224 -365.385458) (xy 40.348831 -365.394634) (xy 40.323507 -365.412153)
			(xy 40.31361 -365.423958) (xy 40.295403 -365.446428) (xy 40.253388 -365.486166) (xy 40.205856 -365.519108)
			(xy 40.153898 -365.544499) (xy 40.098703 -365.561757) (xy 40.041535 -365.570488) (xy 40.01262 -365.571024)
			(xy 39.985249 -365.570565) (xy 39.931069 -365.562748) (xy 39.878565 -365.547258) (xy 39.828818 -365.524415)
			(xy 39.782853 -365.494687) (xy 39.761922 -365.477044) (xy 39.750594 -365.467808) (xy 39.724037 -365.455632)
			(xy 39.69512 -365.451459) (xy 39.666203 -365.455632) (xy 39.639646 -365.467808) (xy 39.628318 -365.477044)
			(xy 39.607396 -365.494695) (xy 39.56142 -365.524404) (xy 39.51167 -365.547237) (xy 39.459167 -365.562725)
			(xy 39.40499 -365.570551) (xy 39.37762 -365.571024) (xy 39.350368 -365.570526) (xy 39.29642 -365.562772)
			(xy 39.244123 -365.54742) (xy 39.194544 -365.524781) (xy 39.148692 -365.495316) (xy 39.107499 -365.459626)
			(xy 39.071805 -365.418437) (xy 39.042337 -365.372587) (xy 39.019693 -365.32301) (xy 39.004335 -365.270716)
			(xy 38.996576 -365.216768) (xy 38.996112 -365.189516) (xy 38.996698 -365.160387) (xy 39.005561 -365.102807)
			(xy 39.023083 -365.047246) (xy 39.048857 -364.994999) (xy 39.082281 -364.947283) (xy 39.10203 -364.925864)
			(xy 39.112397 -364.914226) (xy 39.126184 -364.886292) (xy 39.130927 -364.855504) (xy 39.126186 -364.824716)
			(xy 39.112402 -364.796781) (xy 39.10203 -364.785148) (xy 39.082267 -364.763743) (xy 39.048868 -364.71601)
			(xy 39.023104 -364.663758) (xy 39.005574 -364.6082) (xy 38.996683 -364.550625) (xy 38.996112 -364.521496)
			(xy 38.996623 -364.492579) (xy 39.005353 -364.435407) (xy 39.022612 -364.380208) (xy 39.048005 -364.328246)
			(xy 39.08095 -364.280713) (xy 39.120692 -364.238696) (xy 39.143178 -364.220506) (xy 39.154988 -364.210613)
			(xy 39.172507 -364.185289) (xy 39.181683 -364.155894) (xy 39.181682 -364.125101) (xy 39.172505 -364.095707)
			(xy 39.154984 -364.070383) (xy 39.143178 -364.060486) (xy 39.12239 -364.043738) (xy 39.085258 -364.005385)
			(xy 39.053835 -363.96223) (xy 39.028735 -363.915116) (xy 39.010448 -363.864963) (xy 38.999331 -363.81275)
			(xy 38.995601 -363.759498) (xy 38.999331 -363.706245) (xy 39.010449 -363.654032) (xy 39.028737 -363.60388)
			(xy 39.053838 -363.556766) (xy 39.085261 -363.513611) (xy 39.122394 -363.475259) (xy 39.143178 -363.458506)
			(xy 39.154988 -363.448613) (xy 39.172507 -363.423289) (xy 39.181683 -363.393894) (xy 39.181682 -363.363101)
			(xy 39.172505 -363.333707) (xy 39.154984 -363.308383) (xy 39.143178 -363.298486) (xy 39.120683 -363.280308)
			(xy 39.08095 -363.238285) (xy 39.048013 -363.190747) (xy 39.022626 -363.138784) (xy 39.005372 -363.083584)
			(xy 38.996646 -363.026413) (xy 38.996112 -362.997496) (xy 38.996573 -362.970126) (xy 39.004391 -362.915946)
			(xy 39.019882 -362.863443) (xy 39.042725 -362.813696) (xy 39.07245 -362.767729) (xy 39.090092 -362.746798)
			(xy 39.099333 -362.735474) (xy 39.111511 -362.708915) (xy 39.115683 -362.679997) (xy 39.11151 -362.651079)
			(xy 39.09933 -362.624521) (xy 39.090092 -362.613194) (xy 39.072449 -362.592264) (xy 39.042727 -362.546295)
			(xy 39.019884 -362.496548) (xy 39.004389 -362.444046) (xy 38.996562 -362.389867) (xy 38.996562 -362.335127)
			(xy 39.004391 -362.280948) (xy 39.019886 -362.228447) (xy 39.04273 -362.1787) (xy 39.072452 -362.132731)
			(xy 39.090092 -362.111798) (xy 39.099333 -362.100474) (xy 39.111511 -362.073915) (xy 39.115683 -362.044997)
			(xy 39.11151 -362.016079) (xy 39.09933 -361.989521) (xy 39.090092 -361.978194) (xy 39.072435 -361.957276)
			(xy 39.042726 -361.911299) (xy 39.019894 -361.861548) (xy 39.004407 -361.809044) (xy 38.996584 -361.754866)
			(xy 38.996112 -361.727496) (xy 38.996686 -361.698366) (xy 39.005552 -361.640786) (xy 39.023077 -361.585225)
			(xy 39.048853 -361.532978) (xy 39.08228 -361.485263) (xy 39.10203 -361.463844) (xy 39.110857 -361.453996)
			(xy 39.123643 -361.430861) (xy 39.130042 -361.405215) (xy 39.129623 -361.378785) (xy 39.122414 -361.353354)
			(xy 39.108901 -361.330636) (xy 39.099744 -361.321096) (xy 39.078595 -361.299436) (xy 39.042713 -361.250681)
			(xy 39.014981 -361.196872) (xy 38.996097 -361.139358) (xy 38.986534 -361.079583) (xy 38.985952 -361.049316)
			(xy 31.628588 -361.049316) (xy 36.43122 -365.851948) (xy 41.654982 -365.851948) (xy 41.659053 -365.796326)
			(xy 41.671179 -365.741889) (xy 41.691102 -365.689798) (xy 41.718398 -365.641163) (xy 41.752484 -365.59702)
			(xy 41.792633 -365.558311) (xy 41.837991 -365.52586) (xy 41.887591 -365.500359) (xy 41.940375 -365.482352)
			(xy 41.995218 -365.472222) (xy 42.050952 -365.470185) (xy 42.106389 -365.476285) (xy 42.160346 -365.490391)
			(xy 42.211675 -365.512203) (xy 42.259281 -365.541257) (xy 42.302149 -365.576932) (xy 42.330083 -365.608108)
			(xy 55.39308 -365.608108) (xy 55.397151 -365.552486) (xy 55.409277 -365.498049) (xy 55.4292 -365.445958)
			(xy 55.456496 -365.397323) (xy 55.490582 -365.35318) (xy 55.530731 -365.314471) (xy 55.576089 -365.28202)
			(xy 55.625689 -365.256519) (xy 55.678473 -365.238512) (xy 55.733316 -365.228382) (xy 55.78905 -365.226345)
			(xy 55.844487 -365.232445) (xy 55.898444 -365.246551) (xy 55.949773 -365.268363) (xy 55.997379 -365.297417)
			(xy 56.040247 -365.333092) (xy 56.077464 -365.374629) (xy 56.108237 -365.421142) (xy 56.131909 -365.471639)
			(xy 56.147977 -365.525046) (xy 56.156097 -365.580222) (xy 56.156606 -365.608108) (xy 56.156097 -365.635994)
			(xy 56.147977 -365.69117) (xy 56.131909 -365.744577) (xy 56.108237 -365.795074) (xy 56.077464 -365.841587)
			(xy 56.040247 -365.883124) (xy 55.997379 -365.918799) (xy 55.949773 -365.947853) (xy 55.898444 -365.969665)
			(xy 55.844487 -365.983771) (xy 55.78905 -365.989871) (xy 55.733316 -365.987834) (xy 55.678473 -365.977704)
			(xy 55.625689 -365.959697) (xy 55.576089 -365.934196) (xy 55.530731 -365.901745) (xy 55.490582 -365.863036)
			(xy 55.456496 -365.818893) (xy 55.4292 -365.770258) (xy 55.409277 -365.718167) (xy 55.397151 -365.66373)
			(xy 55.39308 -365.608108) (xy 42.330083 -365.608108) (xy 42.339366 -365.618469) (xy 42.370139 -365.664982)
			(xy 42.393811 -365.715479) (xy 42.409879 -365.768886) (xy 42.417999 -365.824062) (xy 42.418508 -365.851948)
			(xy 42.417999 -365.879834) (xy 42.409879 -365.93501) (xy 42.393811 -365.988417) (xy 42.370139 -366.038914)
			(xy 42.339366 -366.085427) (xy 42.302149 -366.126964) (xy 42.259281 -366.162639) (xy 42.211675 -366.191693)
			(xy 42.160346 -366.213505) (xy 42.106389 -366.227611) (xy 42.050952 -366.233711) (xy 41.995218 -366.231674)
			(xy 41.940375 -366.221544) (xy 41.887591 -366.203537) (xy 41.837991 -366.178036) (xy 41.792633 -366.145585)
			(xy 41.752484 -366.106876) (xy 41.718398 -366.062733) (xy 41.691102 -366.014098) (xy 41.671179 -365.962007)
			(xy 41.659053 -365.90757) (xy 41.654982 -365.851948) (xy 36.43122 -365.851948) (xy 37.571934 -366.992662)
			(xy 41.734486 -366.992662) (xy 41.749218 -367.007648) (xy 55.413656 -367.007648)
		)
		(stroke
			(width 0)
			(type solid)
		)
		(fill yes)
		(layer "In11.Cu")
		(net "GND")
	)
	(gr_poly
		(pts
			(xy 356.191058 -238.015526) (xy 356.205381 -238.015044) (xy 356.232901 -238.007094) (xy 356.257128 -237.991808)
			(xy 356.276152 -237.970392) (xy 356.288474 -237.944532) (xy 356.293123 -237.916266) (xy 356.291896 -237.901988)
			(xy 356.290821 -237.892309) (xy 356.289678 -237.872865) (xy 356.28961 -237.863126) (xy 356.290117 -237.837156)
			(xy 356.298238 -237.785856) (xy 356.314284 -237.736458) (xy 356.33786 -237.690178) (xy 356.368385 -237.648155)
			(xy 356.405108 -237.611425) (xy 356.447125 -237.580892) (xy 356.4934 -237.557308) (xy 356.542796 -237.541253)
			(xy 356.594095 -237.533122) (xy 356.620064 -237.532672) (xy 356.644861 -237.53312) (xy 356.693896 -237.540539)
			(xy 356.741273 -237.555201) (xy 356.785927 -237.576776) (xy 356.826857 -237.604781) (xy 356.863144 -237.638586)
			(xy 356.893973 -237.677433) (xy 356.918652 -237.72045) (xy 356.936627 -237.766671) (xy 356.947495 -237.815059)
			(xy 356.949756 -237.839758) (xy 356.951187 -237.853711) (xy 356.960694 -237.880087) (xy 356.977016 -237.902884)
			(xy 356.998922 -237.920382) (xy 357.024762 -237.931264) (xy 357.052587 -237.934708) (xy 357.0803 -237.930455)
			(xy 357.093266 -237.925102) (xy 357.114933 -237.915662) (xy 357.160274 -237.902324) (xy 357.20705 -237.895564)
			(xy 357.23068 -237.89513) (xy 357.254971 -237.895566) (xy 357.303027 -237.902692) (xy 357.349522 -237.91678)
			(xy 357.393452 -237.937525) (xy 357.43387 -237.964479) (xy 357.469905 -237.997063) (xy 357.485696 -238.015526)
			(xy 357.915464 -238.015526) (xy 357.932709 -237.995393) (xy 357.972493 -237.960364) (xy 358.017362 -237.932139)
			(xy 358.066163 -237.911445) (xy 358.117643 -237.898812) (xy 358.17048 -237.894564) (xy 358.223317 -237.898812)
			(xy 358.274797 -237.911445) (xy 358.323598 -237.932139) (xy 358.368467 -237.960364) (xy 358.408251 -237.995393)
			(xy 358.425496 -238.015526) (xy 358.855264 -238.015526) (xy 358.872509 -237.995393) (xy 358.912293 -237.960364)
			(xy 358.957162 -237.932139) (xy 359.005963 -237.911445) (xy 359.057443 -237.898812) (xy 359.11028 -237.894564)
			(xy 359.163117 -237.898812) (xy 359.214597 -237.911445) (xy 359.263398 -237.932139) (xy 359.308267 -237.960364)
			(xy 359.348051 -237.995393) (xy 359.365296 -238.015526) (xy 359.795064 -238.015526) (xy 359.812309 -237.995393)
			(xy 359.852093 -237.960364) (xy 359.896962 -237.932139) (xy 359.945763 -237.911445) (xy 359.997243 -237.898812)
			(xy 360.05008 -237.894564) (xy 360.102917 -237.898812) (xy 360.154397 -237.911445) (xy 360.203198 -237.932139)
			(xy 360.248067 -237.960364) (xy 360.287851 -237.995393) (xy 360.305096 -238.015526) (xy 360.734864 -238.015526)
			(xy 360.752109 -237.995393) (xy 360.791893 -237.960364) (xy 360.836762 -237.932139) (xy 360.885563 -237.911445)
			(xy 360.937043 -237.898812) (xy 360.98988 -237.894564) (xy 361.042717 -237.898812) (xy 361.094197 -237.911445)
			(xy 361.142998 -237.932139) (xy 361.187867 -237.960364) (xy 361.227651 -237.995393) (xy 361.244896 -238.015526)
			(xy 361.674664 -238.015526) (xy 361.68467 -238.003665) (xy 361.706546 -237.981654) (xy 361.718352 -237.971584)
			(xy 361.72013 -237.97006) (xy 361.998514 -237.691676) (xy 361.998514 -237.028736) (xy 361.997943 -237.013536)
			(xy 361.98899 -236.984483) (xy 361.971893 -236.959345) (xy 361.948163 -236.940342) (xy 361.919897 -236.929153)
			(xy 361.904788 -236.92739) (xy 361.878897 -236.924929) (xy 361.8283 -236.912899) (xy 361.780214 -236.893089)
			(xy 361.735825 -236.86599) (xy 361.696231 -236.83227) (xy 361.662409 -236.792763) (xy 361.635196 -236.748444)
			(xy 361.615263 -236.700408) (xy 361.603103 -236.649843) (xy 361.599017 -236.597996) (xy 361.603104 -236.54615)
			(xy 361.615265 -236.495585) (xy 361.635199 -236.44755) (xy 361.662413 -236.403232) (xy 361.696236 -236.363725)
			(xy 361.735831 -236.330006) (xy 361.78022 -236.302907) (xy 361.828307 -236.283099) (xy 361.878904 -236.27107)
			(xy 361.904788 -236.268514) (xy 361.919908 -236.266783) (xy 361.948201 -236.255618) (xy 361.971949 -236.236613)
			(xy 361.989044 -236.211455) (xy 361.997967 -236.182377) (xy 361.998514 -236.167168) (xy 361.998514 -235.40085)
			(xy 361.997945 -235.385649) (xy 361.988994 -235.356593) (xy 361.971898 -235.331451) (xy 361.948168 -235.312445)
			(xy 361.919899 -235.301254) (xy 361.904788 -235.299504) (xy 361.878896 -235.297043) (xy 361.828297 -235.285012)
			(xy 361.780208 -235.265202) (xy 361.735818 -235.238102) (xy 361.696222 -235.204381) (xy 361.662399 -235.164872)
			(xy 361.635184 -235.120551) (xy 361.61525 -235.072513) (xy 361.60309 -235.021946) (xy 361.599003 -234.970097)
			(xy 361.60309 -234.918249) (xy 361.615252 -234.867682) (xy 361.635186 -234.819644) (xy 361.662402 -234.775324)
			(xy 361.696225 -234.735816) (xy 361.735822 -234.702095) (xy 361.780213 -234.674995) (xy 361.828302 -234.655186)
			(xy 361.878901 -234.643156) (xy 361.904788 -234.640628) (xy 361.919909 -234.638897) (xy 361.948204 -234.627733)
			(xy 361.971954 -234.608728) (xy 361.989052 -234.58357) (xy 361.997979 -234.554492) (xy 361.998514 -234.539282)
			(xy 361.998514 -233.772964) (xy 361.997947 -233.757761) (xy 361.988999 -233.728702) (xy 361.971904 -233.703557)
			(xy 361.948172 -233.684547) (xy 361.919901 -233.673354) (xy 361.904788 -233.671618) (xy 361.878894 -233.669157)
			(xy 361.828294 -233.657126) (xy 361.780203 -233.637315) (xy 361.73581 -233.610214) (xy 361.696212 -233.576491)
			(xy 361.662388 -233.536981) (xy 361.635172 -233.492658) (xy 361.615237 -233.444619) (xy 361.603076 -233.394049)
			(xy 361.598989 -233.342198) (xy 361.603076 -233.290348) (xy 361.615238 -233.239778) (xy 361.635173 -233.191739)
			(xy 361.66239 -233.147417) (xy 361.696215 -233.107907) (xy 361.735813 -233.074184) (xy 361.780206 -233.047083)
			(xy 361.828296 -233.027273) (xy 361.878897 -233.015243) (xy 361.904788 -233.012742) (xy 361.91991 -233.011012)
			(xy 361.948207 -232.999847) (xy 361.971959 -232.980843) (xy 361.98906 -232.955685) (xy 361.997991 -232.926606)
			(xy 361.998514 -232.911396) (xy 361.998514 -232.145332) (xy 361.997943 -232.130132) (xy 361.988989 -232.101081)
			(xy 361.971892 -232.075944) (xy 361.948162 -232.056942) (xy 361.919896 -232.045753) (xy 361.904788 -232.043986)
			(xy 361.878905 -232.041503) (xy 361.828331 -232.029436) (xy 361.78027 -232.009599) (xy 361.735908 -231.982479)
			(xy 361.69634 -231.948748) (xy 361.662543 -231.909236) (xy 361.635351 -231.86492) (xy 361.615433 -231.816892)
			(xy 361.603282 -231.766337) (xy 361.599198 -231.714504) (xy 361.603281 -231.66267) (xy 361.615431 -231.612115)
			(xy 361.635347 -231.564087) (xy 361.662539 -231.51977) (xy 361.696335 -231.480257) (xy 361.735902 -231.446525)
			(xy 361.780263 -231.419405) (xy 361.828324 -231.399566) (xy 361.878898 -231.387498) (xy 361.904788 -231.38511)
			(xy 361.919908 -231.383379) (xy 361.9482 -231.372214) (xy 361.971948 -231.353209) (xy 361.989041 -231.328051)
			(xy 361.997964 -231.298973) (xy 361.998514 -231.283764) (xy 361.998514 -230.693976) (xy 361.467654 -230.163116)
			(xy 361.456993 -230.15318) (xy 361.431379 -230.139305) (xy 361.402891 -230.13322) (xy 361.373843 -230.135418)
			(xy 361.346595 -230.145721) (xy 361.323359 -230.163292) (xy 361.306025 -230.186704) (xy 361.300522 -230.2002)
			(xy 361.291414 -230.223717) (xy 361.267095 -230.267897) (xy 361.236346 -230.307868) (xy 361.199881 -230.342703)
			(xy 361.158545 -230.371592) (xy 361.1133 -230.393864) (xy 361.065195 -230.409003) (xy 361.015349 -230.416656)
			(xy 360.990134 -230.417116) (xy 360.964164 -230.416636) (xy 360.912863 -230.408515) (xy 360.863464 -230.392467)
			(xy 360.817185 -230.368889) (xy 360.775164 -230.33836) (xy 360.738437 -230.301633) (xy 360.707909 -230.259612)
			(xy 360.684331 -230.213332) (xy 360.668284 -230.163933) (xy 360.660164 -230.112632) (xy 360.65968 -230.086662)
			(xy 360.660158 -230.061448) (xy 360.667821 -230.011607) (xy 360.682965 -229.963507) (xy 360.705237 -229.918265)
			(xy 360.734121 -229.876929) (xy 360.768947 -229.84046) (xy 360.808907 -229.809701) (xy 360.853075 -229.785368)
			(xy 360.876596 -229.776274) (xy 360.890149 -229.770852) (xy 360.91364 -229.753546) (xy 360.931272 -229.730298)
			(xy 360.941603 -229.70301) (xy 360.943788 -229.673914) (xy 360.937649 -229.645389) (xy 360.923686 -229.619768)
			(xy 360.91368 -229.609142) (xy 360.783378 -229.47884) (xy 360.747564 -229.512876) (xy 360.729026 -229.529763)
			(xy 360.687805 -229.558316) (xy 360.642745 -229.580317) (xy 360.59488 -229.595262) (xy 360.545306 -229.602809)
			(xy 360.520234 -229.6033) (xy 360.494264 -229.602793) (xy 360.442962 -229.594674) (xy 360.393562 -229.578628)
			(xy 360.34728 -229.555053) (xy 360.305256 -229.524528) (xy 360.268524 -229.487805) (xy 360.237989 -229.445788)
			(xy 360.214402 -229.399512) (xy 360.198345 -229.350116) (xy 360.190213 -229.298816) (xy 360.18978 -229.272846)
			(xy 360.19022 -229.247769) (xy 360.197752 -229.198184) (xy 360.212696 -229.150309) (xy 360.234707 -229.105244)
			(xy 360.26328 -229.064026) (xy 360.280204 -229.045516) (xy 360.31424 -229.009702) (xy 360.092244 -228.787706)
			(xy 360.069384 -228.788976) (xy 360.05008 -228.789484) (xy 360.024113 -228.788973) (xy 359.972819 -228.780847)
			(xy 359.923427 -228.764797) (xy 359.877153 -228.741218) (xy 359.835138 -228.710692) (xy 359.798414 -228.67397)
			(xy 359.767887 -228.631955) (xy 359.744307 -228.585682) (xy 359.728256 -228.536291) (xy 359.720128 -228.484997)
			(xy 359.719626 -228.45903) (xy 359.720134 -228.439726) (xy 359.721404 -228.416866) (xy 359.287064 -227.982526)
			(xy 351.643188 -227.982526) (xy 351.336864 -228.28885) (xy 351.336864 -228.439472) (xy 351.65665 -228.759258)
			(xy 352.147886 -228.759258) (xy 352.162809 -228.758782) (xy 352.191404 -228.750244) (xy 352.21631 -228.733805)
			(xy 352.235402 -228.710868) (xy 352.247048 -228.683392) (xy 352.250254 -228.653722) (xy 352.244748 -228.624392)
			(xy 352.23831 -228.610922) (xy 352.226641 -228.58732) (xy 352.210119 -228.537331) (xy 352.201741 -228.485354)
			(xy 352.201226 -228.45903) (xy 352.201707 -228.433058) (xy 352.209828 -228.381754) (xy 352.225875 -228.332351)
			(xy 352.249454 -228.286068) (xy 352.279982 -228.244042) (xy 352.316709 -228.20731) (xy 352.358731 -228.176776)
			(xy 352.405011 -228.153192) (xy 352.454411 -228.137138) (xy 352.505715 -228.12901) (xy 352.557658 -228.129008)
			(xy 352.608963 -228.137132) (xy 352.658364 -228.153182) (xy 352.704647 -228.176762) (xy 352.74667 -228.207293)
			(xy 352.7834 -228.244022) (xy 352.813932 -228.286045) (xy 352.837514 -228.332327) (xy 352.853566 -228.381728)
			(xy 352.861691 -228.433032) (xy 352.861691 -228.484975) (xy 352.861688 -228.484997) (xy 354.081335 -228.484997)
			(xy 354.081335 -228.433063) (xy 354.08946 -228.381768) (xy 354.105508 -228.332375) (xy 354.129086 -228.286101)
			(xy 354.159612 -228.244085) (xy 354.196335 -228.207362) (xy 354.238351 -228.176836) (xy 354.284625 -228.153258)
			(xy 354.334018 -228.13721) (xy 354.385313 -228.129085) (xy 354.437247 -228.129085) (xy 354.488542 -228.13721)
			(xy 354.537935 -228.153258) (xy 354.584209 -228.176836) (xy 354.626225 -228.207362) (xy 354.662948 -228.244085)
			(xy 354.693474 -228.286101) (xy 354.717052 -228.332375) (xy 354.7331 -228.381768) (xy 354.741225 -228.433063)
			(xy 354.741734 -228.45903) (xy 354.741225 -228.484997) (xy 355.960935 -228.484997) (xy 355.960935 -228.433063)
			(xy 355.96906 -228.381768) (xy 355.985108 -228.332375) (xy 356.008686 -228.286101) (xy 356.039212 -228.244085)
			(xy 356.075935 -228.207362) (xy 356.117951 -228.176836) (xy 356.164225 -228.153258) (xy 356.213618 -228.13721)
			(xy 356.264913 -228.129085) (xy 356.316847 -228.129085) (xy 356.368142 -228.13721) (xy 356.417535 -228.153258)
			(xy 356.463809 -228.176836) (xy 356.505825 -228.207362) (xy 356.542548 -228.244085) (xy 356.573074 -228.286101)
			(xy 356.596652 -228.332375) (xy 356.6127 -228.381768) (xy 356.620825 -228.433063) (xy 356.621334 -228.45903)
			(xy 356.620825 -228.484997) (xy 357.840535 -228.484997) (xy 357.840535 -228.433063) (xy 357.84866 -228.381768)
			(xy 357.864708 -228.332375) (xy 357.888286 -228.286101) (xy 357.918812 -228.244085) (xy 357.955535 -228.207362)
			(xy 357.997551 -228.176836) (xy 358.043825 -228.153258) (xy 358.093218 -228.13721) (xy 358.144513 -228.129085)
			(xy 358.196447 -228.129085) (xy 358.247742 -228.13721) (xy 358.297135 -228.153258) (xy 358.343409 -228.176836)
			(xy 358.385425 -228.207362) (xy 358.422148 -228.244085) (xy 358.452674 -228.286101) (xy 358.476252 -228.332375)
			(xy 358.4923 -228.381768) (xy 358.500425 -228.433063) (xy 358.500934 -228.45903) (xy 358.500425 -228.484997)
			(xy 358.780589 -228.484997) (xy 358.780589 -228.433063) (xy 358.788714 -228.381768) (xy 358.804762 -228.332375)
			(xy 358.82834 -228.286101) (xy 358.858866 -228.244085) (xy 358.895589 -228.207362) (xy 358.937605 -228.176836)
			(xy 358.983879 -228.153258) (xy 359.033272 -228.13721) (xy 359.084567 -228.129085) (xy 359.136501 -228.129085)
			(xy 359.187796 -228.13721) (xy 359.237189 -228.153258) (xy 359.283463 -228.176836) (xy 359.325479 -228.207362)
			(xy 359.362202 -228.244085) (xy 359.392728 -228.286101) (xy 359.416306 -228.332375) (xy 359.432354 -228.381768)
			(xy 359.440479 -228.433063) (xy 359.440988 -228.45903) (xy 359.440479 -228.484997) (xy 359.432354 -228.536292)
			(xy 359.416306 -228.585685) (xy 359.392728 -228.631959) (xy 359.362202 -228.673975) (xy 359.325479 -228.710698)
			(xy 359.283463 -228.741224) (xy 359.237189 -228.764802) (xy 359.187796 -228.78085) (xy 359.136501 -228.788975)
			(xy 359.084567 -228.788975) (xy 359.033272 -228.78085) (xy 358.983879 -228.764802) (xy 358.937605 -228.741224)
			(xy 358.895589 -228.710698) (xy 358.858866 -228.673975) (xy 358.82834 -228.631959) (xy 358.804762 -228.585685)
			(xy 358.788714 -228.536292) (xy 358.780589 -228.484997) (xy 358.500425 -228.484997) (xy 358.4923 -228.536292)
			(xy 358.476252 -228.585685) (xy 358.452674 -228.631959) (xy 358.422148 -228.673975) (xy 358.385425 -228.710698)
			(xy 358.343409 -228.741224) (xy 358.297135 -228.764802) (xy 358.247742 -228.78085) (xy 358.196447 -228.788975)
			(xy 358.144513 -228.788975) (xy 358.093218 -228.78085) (xy 358.043825 -228.764802) (xy 357.997551 -228.741224)
			(xy 357.955535 -228.710698) (xy 357.918812 -228.673975) (xy 357.888286 -228.631959) (xy 357.864708 -228.585685)
			(xy 357.84866 -228.536292) (xy 357.840535 -228.484997) (xy 356.620825 -228.484997) (xy 356.6127 -228.536292)
			(xy 356.596652 -228.585685) (xy 356.573074 -228.631959) (xy 356.542548 -228.673975) (xy 356.505825 -228.710698)
			(xy 356.463809 -228.741224) (xy 356.417535 -228.764802) (xy 356.368142 -228.78085) (xy 356.316847 -228.788975)
			(xy 356.264913 -228.788975) (xy 356.213618 -228.78085) (xy 356.164225 -228.764802) (xy 356.117951 -228.741224)
			(xy 356.075935 -228.710698) (xy 356.039212 -228.673975) (xy 356.008686 -228.631959) (xy 355.985108 -228.585685)
			(xy 355.96906 -228.536292) (xy 355.960935 -228.484997) (xy 354.741225 -228.484997) (xy 354.7331 -228.536292)
			(xy 354.717052 -228.585685) (xy 354.693474 -228.631959) (xy 354.662948 -228.673975) (xy 354.626225 -228.710698)
			(xy 354.584209 -228.741224) (xy 354.537935 -228.764802) (xy 354.488542 -228.78085) (xy 354.437247 -228.788975)
			(xy 354.385313 -228.788975) (xy 354.334018 -228.78085) (xy 354.284625 -228.764802) (xy 354.238351 -228.741224)
			(xy 354.196335 -228.710698) (xy 354.159612 -228.673975) (xy 354.129086 -228.631959) (xy 354.105508 -228.585685)
			(xy 354.08946 -228.536292) (xy 354.081335 -228.484997) (xy 352.861688 -228.484997) (xy 352.853564 -228.536279)
			(xy 352.837512 -228.58568) (xy 352.813929 -228.631961) (xy 352.783396 -228.673983) (xy 352.746665 -228.710711)
			(xy 352.704641 -228.741241) (xy 352.658358 -228.764821) (xy 352.608956 -228.78087) (xy 352.557652 -228.788993)
			(xy 352.53168 -228.789484) (xy 352.506675 -228.789022) (xy 352.457236 -228.781482) (xy 352.409499 -228.766577)
			(xy 352.364553 -228.744647) (xy 352.34372 -228.73081) (xy 352.308922 -228.70668) (xy 352.243136 -228.77272)
			(xy 352.378518 -228.908102) (xy 352.378518 -229.110032) (xy 352.360738 -229.127812) (xy 352.371914 -229.158292)
			(xy 352.381492 -229.185958) (xy 352.391836 -229.243576) (xy 352.392488 -229.272846) (xy 352.391975 -229.298812)
			(xy 352.391975 -229.298813) (xy 352.671889 -229.298813) (xy 352.671889 -229.246879) (xy 352.680014 -229.195584)
			(xy 352.696062 -229.146191) (xy 352.71964 -229.099917) (xy 352.750166 -229.057901) (xy 352.786889 -229.021178)
			(xy 352.828905 -228.990652) (xy 352.875179 -228.967074) (xy 352.924572 -228.951026) (xy 352.975867 -228.942901)
			(xy 353.027801 -228.942901) (xy 353.079096 -228.951026) (xy 353.128489 -228.967074) (xy 353.174763 -228.990652)
			(xy 353.216779 -229.021178) (xy 353.253502 -229.057901) (xy 353.284028 -229.099917) (xy 353.307606 -229.146191)
			(xy 353.323654 -229.195584) (xy 353.331779 -229.246879) (xy 353.332288 -229.272846) (xy 353.331779 -229.298813)
			(xy 353.611689 -229.298813) (xy 353.611689 -229.246879) (xy 353.619814 -229.195584) (xy 353.635862 -229.146191)
			(xy 353.65944 -229.099917) (xy 353.689966 -229.057901) (xy 353.726689 -229.021178) (xy 353.768705 -228.990652)
			(xy 353.814979 -228.967074) (xy 353.864372 -228.951026) (xy 353.915667 -228.942901) (xy 353.967601 -228.942901)
			(xy 354.018896 -228.951026) (xy 354.068289 -228.967074) (xy 354.114563 -228.990652) (xy 354.156579 -229.021178)
			(xy 354.193302 -229.057901) (xy 354.223828 -229.099917) (xy 354.247406 -229.146191) (xy 354.263454 -229.195584)
			(xy 354.271579 -229.246879) (xy 354.272088 -229.272846) (xy 354.271579 -229.298813) (xy 354.551489 -229.298813)
			(xy 354.551489 -229.246879) (xy 354.559614 -229.195584) (xy 354.575662 -229.146191) (xy 354.59924 -229.099917)
			(xy 354.629766 -229.057901) (xy 354.666489 -229.021178) (xy 354.708505 -228.990652) (xy 354.754779 -228.967074)
			(xy 354.804172 -228.951026) (xy 354.855467 -228.942901) (xy 354.907401 -228.942901) (xy 354.958696 -228.951026)
			(xy 355.008089 -228.967074) (xy 355.054363 -228.990652) (xy 355.096379 -229.021178) (xy 355.133102 -229.057901)
			(xy 355.163628 -229.099917) (xy 355.187206 -229.146191) (xy 355.203254 -229.195584) (xy 355.211379 -229.246879)
			(xy 355.211888 -229.272846) (xy 355.211379 -229.298813) (xy 355.491289 -229.298813) (xy 355.491289 -229.246879)
			(xy 355.499414 -229.195584) (xy 355.515462 -229.146191) (xy 355.53904 -229.099917) (xy 355.569566 -229.057901)
			(xy 355.606289 -229.021178) (xy 355.648305 -228.990652) (xy 355.694579 -228.967074) (xy 355.743972 -228.951026)
			(xy 355.795267 -228.942901) (xy 355.847201 -228.942901) (xy 355.898496 -228.951026) (xy 355.947889 -228.967074)
			(xy 355.994163 -228.990652) (xy 356.036179 -229.021178) (xy 356.072902 -229.057901) (xy 356.103428 -229.099917)
			(xy 356.127006 -229.146191) (xy 356.143054 -229.195584) (xy 356.151179 -229.246879) (xy 356.151688 -229.272846)
			(xy 356.151179 -229.298813) (xy 356.431089 -229.298813) (xy 356.431089 -229.246879) (xy 356.439214 -229.195584)
			(xy 356.455262 -229.146191) (xy 356.47884 -229.099917) (xy 356.509366 -229.057901) (xy 356.546089 -229.021178)
			(xy 356.588105 -228.990652) (xy 356.634379 -228.967074) (xy 356.683772 -228.951026) (xy 356.735067 -228.942901)
			(xy 356.787001 -228.942901) (xy 356.838296 -228.951026) (xy 356.887689 -228.967074) (xy 356.933963 -228.990652)
			(xy 356.975979 -229.021178) (xy 357.012702 -229.057901) (xy 357.043228 -229.099917) (xy 357.066806 -229.146191)
			(xy 357.082854 -229.195584) (xy 357.090979 -229.246879) (xy 357.091488 -229.272846) (xy 357.090979 -229.298813)
			(xy 357.370889 -229.298813) (xy 357.370889 -229.246879) (xy 357.379014 -229.195584) (xy 357.395062 -229.146191)
			(xy 357.41864 -229.099917) (xy 357.449166 -229.057901) (xy 357.485889 -229.021178) (xy 357.527905 -228.990652)
			(xy 357.574179 -228.967074) (xy 357.623572 -228.951026) (xy 357.674867 -228.942901) (xy 357.726801 -228.942901)
			(xy 357.778096 -228.951026) (xy 357.827489 -228.967074) (xy 357.873763 -228.990652) (xy 357.915779 -229.021178)
			(xy 357.952502 -229.057901) (xy 357.983028 -229.099917) (xy 358.006606 -229.146191) (xy 358.022654 -229.195584)
			(xy 358.030779 -229.246879) (xy 358.031288 -229.272846) (xy 358.030779 -229.298813) (xy 358.310689 -229.298813)
			(xy 358.310689 -229.246879) (xy 358.318814 -229.195584) (xy 358.334862 -229.146191) (xy 358.35844 -229.099917)
			(xy 358.388966 -229.057901) (xy 358.425689 -229.021178) (xy 358.467705 -228.990652) (xy 358.513979 -228.967074)
			(xy 358.563372 -228.951026) (xy 358.614667 -228.942901) (xy 358.666601 -228.942901) (xy 358.717896 -228.951026)
			(xy 358.767289 -228.967074) (xy 358.813563 -228.990652) (xy 358.855579 -229.021178) (xy 358.892302 -229.057901)
			(xy 358.922828 -229.099917) (xy 358.946406 -229.146191) (xy 358.962454 -229.195584) (xy 358.970579 -229.246879)
			(xy 358.971088 -229.272846) (xy 358.970579 -229.298813) (xy 359.250235 -229.298813) (xy 359.250235 -229.246879)
			(xy 359.25836 -229.195584) (xy 359.274408 -229.146191) (xy 359.297986 -229.099917) (xy 359.328512 -229.057901)
			(xy 359.365235 -229.021178) (xy 359.407251 -228.990652) (xy 359.453525 -228.967074) (xy 359.502918 -228.951026)
			(xy 359.554213 -228.942901) (xy 359.606147 -228.942901) (xy 359.657442 -228.951026) (xy 359.706835 -228.967074)
			(xy 359.753109 -228.990652) (xy 359.795125 -229.021178) (xy 359.831848 -229.057901) (xy 359.862374 -229.099917)
			(xy 359.885952 -229.146191) (xy 359.902 -229.195584) (xy 359.910125 -229.246879) (xy 359.910634 -229.272846)
			(xy 359.910125 -229.298813) (xy 359.902 -229.350108) (xy 359.885952 -229.399501) (xy 359.862374 -229.445775)
			(xy 359.831848 -229.487791) (xy 359.795125 -229.524514) (xy 359.753109 -229.55504) (xy 359.706835 -229.578618)
			(xy 359.657442 -229.594666) (xy 359.606147 -229.602791) (xy 359.554213 -229.602791) (xy 359.502918 -229.594666)
			(xy 359.453525 -229.578618) (xy 359.407251 -229.55504) (xy 359.365235 -229.524514) (xy 359.328512 -229.487791)
			(xy 359.297986 -229.445775) (xy 359.274408 -229.399501) (xy 359.25836 -229.350108) (xy 359.250235 -229.298813)
			(xy 358.970579 -229.298813) (xy 358.962454 -229.350108) (xy 358.946406 -229.399501) (xy 358.922828 -229.445775)
			(xy 358.892302 -229.487791) (xy 358.855579 -229.524514) (xy 358.813563 -229.55504) (xy 358.767289 -229.578618)
			(xy 358.717896 -229.594666) (xy 358.666601 -229.602791) (xy 358.614667 -229.602791) (xy 358.563372 -229.594666)
			(xy 358.513979 -229.578618) (xy 358.467705 -229.55504) (xy 358.425689 -229.524514) (xy 358.388966 -229.487791)
			(xy 358.35844 -229.445775) (xy 358.334862 -229.399501) (xy 358.318814 -229.350108) (xy 358.310689 -229.298813)
			(xy 358.030779 -229.298813) (xy 358.022654 -229.350108) (xy 358.006606 -229.399501) (xy 357.983028 -229.445775)
			(xy 357.952502 -229.487791) (xy 357.915779 -229.524514) (xy 357.873763 -229.55504) (xy 357.827489 -229.578618)
			(xy 357.778096 -229.594666) (xy 357.726801 -229.602791) (xy 357.674867 -229.602791) (xy 357.623572 -229.594666)
			(xy 357.574179 -229.578618) (xy 357.527905 -229.55504) (xy 357.485889 -229.524514) (xy 357.449166 -229.487791)
			(xy 357.41864 -229.445775) (xy 357.395062 -229.399501) (xy 357.379014 -229.350108) (xy 357.370889 -229.298813)
			(xy 357.090979 -229.298813) (xy 357.082854 -229.350108) (xy 357.066806 -229.399501) (xy 357.043228 -229.445775)
			(xy 357.012702 -229.487791) (xy 356.975979 -229.524514) (xy 356.933963 -229.55504) (xy 356.887689 -229.578618)
			(xy 356.838296 -229.594666) (xy 356.787001 -229.602791) (xy 356.735067 -229.602791) (xy 356.683772 -229.594666)
			(xy 356.634379 -229.578618) (xy 356.588105 -229.55504) (xy 356.546089 -229.524514) (xy 356.509366 -229.487791)
			(xy 356.47884 -229.445775) (xy 356.455262 -229.399501) (xy 356.439214 -229.350108) (xy 356.431089 -229.298813)
			(xy 356.151179 -229.298813) (xy 356.143054 -229.350108) (xy 356.127006 -229.399501) (xy 356.103428 -229.445775)
			(xy 356.072902 -229.487791) (xy 356.036179 -229.524514) (xy 355.994163 -229.55504) (xy 355.947889 -229.578618)
			(xy 355.898496 -229.594666) (xy 355.847201 -229.602791) (xy 355.795267 -229.602791) (xy 355.743972 -229.594666)
			(xy 355.694579 -229.578618) (xy 355.648305 -229.55504) (xy 355.606289 -229.524514) (xy 355.569566 -229.487791)
			(xy 355.53904 -229.445775) (xy 355.515462 -229.399501) (xy 355.499414 -229.350108) (xy 355.491289 -229.298813)
			(xy 355.211379 -229.298813) (xy 355.203254 -229.350108) (xy 355.187206 -229.399501) (xy 355.163628 -229.445775)
			(xy 355.133102 -229.487791) (xy 355.096379 -229.524514) (xy 355.054363 -229.55504) (xy 355.008089 -229.578618)
			(xy 354.958696 -229.594666) (xy 354.907401 -229.602791) (xy 354.855467 -229.602791) (xy 354.804172 -229.594666)
			(xy 354.754779 -229.578618) (xy 354.708505 -229.55504) (xy 354.666489 -229.524514) (xy 354.629766 -229.487791)
			(xy 354.59924 -229.445775) (xy 354.575662 -229.399501) (xy 354.559614 -229.350108) (xy 354.551489 -229.298813)
			(xy 354.271579 -229.298813) (xy 354.263454 -229.350108) (xy 354.247406 -229.399501) (xy 354.223828 -229.445775)
			(xy 354.193302 -229.487791) (xy 354.156579 -229.524514) (xy 354.114563 -229.55504) (xy 354.068289 -229.578618)
			(xy 354.018896 -229.594666) (xy 353.967601 -229.602791) (xy 353.915667 -229.602791) (xy 353.864372 -229.594666)
			(xy 353.814979 -229.578618) (xy 353.768705 -229.55504) (xy 353.726689 -229.524514) (xy 353.689966 -229.487791)
			(xy 353.65944 -229.445775) (xy 353.635862 -229.399501) (xy 353.619814 -229.350108) (xy 353.611689 -229.298813)
			(xy 353.331779 -229.298813) (xy 353.323654 -229.350108) (xy 353.307606 -229.399501) (xy 353.284028 -229.445775)
			(xy 353.253502 -229.487791) (xy 353.216779 -229.524514) (xy 353.174763 -229.55504) (xy 353.128489 -229.578618)
			(xy 353.079096 -229.594666) (xy 353.027801 -229.602791) (xy 352.975867 -229.602791) (xy 352.924572 -229.594666)
			(xy 352.875179 -229.578618) (xy 352.828905 -229.55504) (xy 352.786889 -229.524514) (xy 352.750166 -229.487791)
			(xy 352.71964 -229.445775) (xy 352.696062 -229.399501) (xy 352.680014 -229.350108) (xy 352.671889 -229.298813)
			(xy 352.391975 -229.298813) (xy 352.383846 -229.350103) (xy 352.367793 -229.399492) (xy 352.344214 -229.445762)
			(xy 352.313687 -229.487774) (xy 352.276965 -229.524495) (xy 352.234952 -229.55502) (xy 352.188681 -229.578598)
			(xy 352.139292 -229.594648) (xy 352.088 -229.602776) (xy 352.062034 -229.6033) (xy 352.032764 -229.60265)
			(xy 351.975145 -229.592305) (xy 351.94748 -229.582726) (xy 351.917 -229.57155) (xy 351.80143 -229.68712)
			(xy 351.791897 -229.697321) (xy 351.778305 -229.721698) (xy 351.771817 -229.748844) (xy 351.772917 -229.776733)
			(xy 351.781523 -229.803283) (xy 351.796992 -229.826514) (xy 351.807272 -229.835964) (xy 351.824986 -229.851746)
			(xy 351.856156 -229.887511) (xy 351.881897 -229.927363) (xy 351.901681 -229.970483) (xy 351.915103 -230.015986)
			(xy 351.921885 -230.062941) (xy 351.922334 -230.086662) (xy 351.921854 -230.112629) (xy 352.201735 -230.112629)
			(xy 352.201735 -230.060695) (xy 352.20986 -230.0094) (xy 352.225908 -229.960007) (xy 352.249486 -229.913733)
			(xy 352.280012 -229.871717) (xy 352.316735 -229.834994) (xy 352.358751 -229.804468) (xy 352.405025 -229.78089)
			(xy 352.454418 -229.764842) (xy 352.505713 -229.756717) (xy 352.557647 -229.756717) (xy 352.608942 -229.764842)
			(xy 352.658335 -229.78089) (xy 352.704609 -229.804468) (xy 352.746625 -229.834994) (xy 352.783348 -229.871717)
			(xy 352.813874 -229.913733) (xy 352.837452 -229.960007) (xy 352.8535 -230.0094) (xy 352.861625 -230.060695)
			(xy 352.862134 -230.086662) (xy 352.861625 -230.112629) (xy 353.141535 -230.112629) (xy 353.141535 -230.060695)
			(xy 353.14966 -230.0094) (xy 353.165708 -229.960007) (xy 353.189286 -229.913733) (xy 353.219812 -229.871717)
			(xy 353.256535 -229.834994) (xy 353.298551 -229.804468) (xy 353.344825 -229.78089) (xy 353.394218 -229.764842)
			(xy 353.445513 -229.756717) (xy 353.497447 -229.756717) (xy 353.548742 -229.764842) (xy 353.598135 -229.78089)
			(xy 353.644409 -229.804468) (xy 353.686425 -229.834994) (xy 353.723148 -229.871717) (xy 353.753674 -229.913733)
			(xy 353.777252 -229.960007) (xy 353.7933 -230.0094) (xy 353.801425 -230.060695) (xy 353.801934 -230.086662)
			(xy 353.801425 -230.112629) (xy 354.081589 -230.112629) (xy 354.081589 -230.060695) (xy 354.089714 -230.0094)
			(xy 354.105762 -229.960007) (xy 354.12934 -229.913733) (xy 354.159866 -229.871717) (xy 354.196589 -229.834994)
			(xy 354.238605 -229.804468) (xy 354.284879 -229.78089) (xy 354.334272 -229.764842) (xy 354.385567 -229.756717)
			(xy 354.437501 -229.756717) (xy 354.488796 -229.764842) (xy 354.538189 -229.78089) (xy 354.584463 -229.804468)
			(xy 354.626479 -229.834994) (xy 354.663202 -229.871717) (xy 354.693728 -229.913733) (xy 354.717306 -229.960007)
			(xy 354.733354 -230.0094) (xy 354.741479 -230.060695) (xy 354.741988 -230.086662) (xy 354.741479 -230.112629)
			(xy 355.021135 -230.112629) (xy 355.021135 -230.060695) (xy 355.02926 -230.0094) (xy 355.045308 -229.960007)
			(xy 355.068886 -229.913733) (xy 355.099412 -229.871717) (xy 355.136135 -229.834994) (xy 355.178151 -229.804468)
			(xy 355.224425 -229.78089) (xy 355.273818 -229.764842) (xy 355.325113 -229.756717) (xy 355.377047 -229.756717)
			(xy 355.428342 -229.764842) (xy 355.477735 -229.78089) (xy 355.524009 -229.804468) (xy 355.566025 -229.834994)
			(xy 355.602748 -229.871717) (xy 355.633274 -229.913733) (xy 355.656852 -229.960007) (xy 355.6729 -230.0094)
			(xy 355.681025 -230.060695) (xy 355.681534 -230.086662) (xy 355.681025 -230.112629) (xy 355.960935 -230.112629)
			(xy 355.960935 -230.060695) (xy 355.96906 -230.0094) (xy 355.985108 -229.960007) (xy 356.008686 -229.913733)
			(xy 356.039212 -229.871717) (xy 356.075935 -229.834994) (xy 356.117951 -229.804468) (xy 356.164225 -229.78089)
			(xy 356.213618 -229.764842) (xy 356.264913 -229.756717) (xy 356.316847 -229.756717) (xy 356.368142 -229.764842)
			(xy 356.417535 -229.78089) (xy 356.463809 -229.804468) (xy 356.505825 -229.834994) (xy 356.542548 -229.871717)
			(xy 356.573074 -229.913733) (xy 356.596652 -229.960007) (xy 356.6127 -230.0094) (xy 356.620825 -230.060695)
			(xy 356.621334 -230.086662) (xy 356.620825 -230.112629) (xy 356.900735 -230.112629) (xy 356.900735 -230.060695)
			(xy 356.90886 -230.0094) (xy 356.924908 -229.960007) (xy 356.948486 -229.913733) (xy 356.979012 -229.871717)
			(xy 357.015735 -229.834994) (xy 357.057751 -229.804468) (xy 357.104025 -229.78089) (xy 357.153418 -229.764842)
			(xy 357.204713 -229.756717) (xy 357.256647 -229.756717) (xy 357.307942 -229.764842) (xy 357.357335 -229.78089)
			(xy 357.403609 -229.804468) (xy 357.445625 -229.834994) (xy 357.482348 -229.871717) (xy 357.512874 -229.913733)
			(xy 357.536452 -229.960007) (xy 357.5525 -230.0094) (xy 357.560625 -230.060695) (xy 357.561134 -230.086662)
			(xy 357.560625 -230.112629) (xy 357.840535 -230.112629) (xy 357.840535 -230.060695) (xy 357.84866 -230.0094)
			(xy 357.864708 -229.960007) (xy 357.888286 -229.913733) (xy 357.918812 -229.871717) (xy 357.955535 -229.834994)
			(xy 357.997551 -229.804468) (xy 358.043825 -229.78089) (xy 358.093218 -229.764842) (xy 358.144513 -229.756717)
			(xy 358.196447 -229.756717) (xy 358.247742 -229.764842) (xy 358.297135 -229.78089) (xy 358.343409 -229.804468)
			(xy 358.385425 -229.834994) (xy 358.422148 -229.871717) (xy 358.452674 -229.913733) (xy 358.476252 -229.960007)
			(xy 358.4923 -230.0094) (xy 358.500425 -230.060695) (xy 358.500934 -230.086662) (xy 358.500425 -230.112629)
			(xy 358.780589 -230.112629) (xy 358.780589 -230.060695) (xy 358.788714 -230.0094) (xy 358.804762 -229.960007)
			(xy 358.82834 -229.913733) (xy 358.858866 -229.871717) (xy 358.895589 -229.834994) (xy 358.937605 -229.804468)
			(xy 358.983879 -229.78089) (xy 359.033272 -229.764842) (xy 359.084567 -229.756717) (xy 359.136501 -229.756717)
			(xy 359.187796 -229.764842) (xy 359.237189 -229.78089) (xy 359.283463 -229.804468) (xy 359.325479 -229.834994)
			(xy 359.362202 -229.871717) (xy 359.392728 -229.913733) (xy 359.416306 -229.960007) (xy 359.432354 -230.0094)
			(xy 359.440479 -230.060695) (xy 359.440988 -230.086662) (xy 359.440479 -230.112629) (xy 359.720389 -230.112629)
			(xy 359.720389 -230.060695) (xy 359.728514 -230.0094) (xy 359.744562 -229.960007) (xy 359.76814 -229.913733)
			(xy 359.798666 -229.871717) (xy 359.835389 -229.834994) (xy 359.877405 -229.804468) (xy 359.923679 -229.78089)
			(xy 359.973072 -229.764842) (xy 360.024367 -229.756717) (xy 360.076301 -229.756717) (xy 360.127596 -229.764842)
			(xy 360.176989 -229.78089) (xy 360.223263 -229.804468) (xy 360.265279 -229.834994) (xy 360.302002 -229.871717)
			(xy 360.332528 -229.913733) (xy 360.356106 -229.960007) (xy 360.372154 -230.0094) (xy 360.380279 -230.060695)
			(xy 360.380788 -230.086662) (xy 360.380279 -230.112629) (xy 360.372154 -230.163924) (xy 360.356106 -230.213317)
			(xy 360.332528 -230.259591) (xy 360.302002 -230.301607) (xy 360.265279 -230.33833) (xy 360.223263 -230.368856)
			(xy 360.176989 -230.392434) (xy 360.127596 -230.408482) (xy 360.076301 -230.416607) (xy 360.024367 -230.416607)
			(xy 359.973072 -230.408482) (xy 359.923679 -230.392434) (xy 359.877405 -230.368856) (xy 359.835389 -230.33833)
			(xy 359.798666 -230.301607) (xy 359.76814 -230.259591) (xy 359.744562 -230.213317) (xy 359.728514 -230.163924)
			(xy 359.720389 -230.112629) (xy 359.440479 -230.112629) (xy 359.432354 -230.163924) (xy 359.416306 -230.213317)
			(xy 359.392728 -230.259591) (xy 359.362202 -230.301607) (xy 359.325479 -230.33833) (xy 359.283463 -230.368856)
			(xy 359.237189 -230.392434) (xy 359.187796 -230.408482) (xy 359.136501 -230.416607) (xy 359.084567 -230.416607)
			(xy 359.033272 -230.408482) (xy 358.983879 -230.392434) (xy 358.937605 -230.368856) (xy 358.895589 -230.33833)
			(xy 358.858866 -230.301607) (xy 358.82834 -230.259591) (xy 358.804762 -230.213317) (xy 358.788714 -230.163924)
			(xy 358.780589 -230.112629) (xy 358.500425 -230.112629) (xy 358.4923 -230.163924) (xy 358.476252 -230.213317)
			(xy 358.452674 -230.259591) (xy 358.422148 -230.301607) (xy 358.385425 -230.33833) (xy 358.343409 -230.368856)
			(xy 358.297135 -230.392434) (xy 358.247742 -230.408482) (xy 358.196447 -230.416607) (xy 358.144513 -230.416607)
			(xy 358.093218 -230.408482) (xy 358.043825 -230.392434) (xy 357.997551 -230.368856) (xy 357.955535 -230.33833)
			(xy 357.918812 -230.301607) (xy 357.888286 -230.259591) (xy 357.864708 -230.213317) (xy 357.84866 -230.163924)
			(xy 357.840535 -230.112629) (xy 357.560625 -230.112629) (xy 357.5525 -230.163924) (xy 357.536452 -230.213317)
			(xy 357.512874 -230.259591) (xy 357.482348 -230.301607) (xy 357.445625 -230.33833) (xy 357.403609 -230.368856)
			(xy 357.357335 -230.392434) (xy 357.307942 -230.408482) (xy 357.256647 -230.416607) (xy 357.204713 -230.416607)
			(xy 357.153418 -230.408482) (xy 357.104025 -230.392434) (xy 357.057751 -230.368856) (xy 357.015735 -230.33833)
			(xy 356.979012 -230.301607) (xy 356.948486 -230.259591) (xy 356.924908 -230.213317) (xy 356.90886 -230.163924)
			(xy 356.900735 -230.112629) (xy 356.620825 -230.112629) (xy 356.6127 -230.163924) (xy 356.596652 -230.213317)
			(xy 356.573074 -230.259591) (xy 356.542548 -230.301607) (xy 356.505825 -230.33833) (xy 356.463809 -230.368856)
			(xy 356.417535 -230.392434) (xy 356.368142 -230.408482) (xy 356.316847 -230.416607) (xy 356.264913 -230.416607)
			(xy 356.213618 -230.408482) (xy 356.164225 -230.392434) (xy 356.117951 -230.368856) (xy 356.075935 -230.33833)
			(xy 356.039212 -230.301607) (xy 356.008686 -230.259591) (xy 355.985108 -230.213317) (xy 355.96906 -230.163924)
			(xy 355.960935 -230.112629) (xy 355.681025 -230.112629) (xy 355.6729 -230.163924) (xy 355.656852 -230.213317)
			(xy 355.633274 -230.259591) (xy 355.602748 -230.301607) (xy 355.566025 -230.33833) (xy 355.524009 -230.368856)
			(xy 355.477735 -230.392434) (xy 355.428342 -230.408482) (xy 355.377047 -230.416607) (xy 355.325113 -230.416607)
			(xy 355.273818 -230.408482) (xy 355.224425 -230.392434) (xy 355.178151 -230.368856) (xy 355.136135 -230.33833)
			(xy 355.099412 -230.301607) (xy 355.068886 -230.259591) (xy 355.045308 -230.213317) (xy 355.02926 -230.163924)
			(xy 355.021135 -230.112629) (xy 354.741479 -230.112629) (xy 354.733354 -230.163924) (xy 354.717306 -230.213317)
			(xy 354.693728 -230.259591) (xy 354.663202 -230.301607) (xy 354.626479 -230.33833) (xy 354.584463 -230.368856)
			(xy 354.538189 -230.392434) (xy 354.488796 -230.408482) (xy 354.437501 -230.416607) (xy 354.385567 -230.416607)
			(xy 354.334272 -230.408482) (xy 354.284879 -230.392434) (xy 354.238605 -230.368856) (xy 354.196589 -230.33833)
			(xy 354.159866 -230.301607) (xy 354.12934 -230.259591) (xy 354.105762 -230.213317) (xy 354.089714 -230.163924)
			(xy 354.081589 -230.112629) (xy 353.801425 -230.112629) (xy 353.7933 -230.163924) (xy 353.777252 -230.213317)
			(xy 353.753674 -230.259591) (xy 353.723148 -230.301607) (xy 353.686425 -230.33833) (xy 353.644409 -230.368856)
			(xy 353.598135 -230.392434) (xy 353.548742 -230.408482) (xy 353.497447 -230.416607) (xy 353.445513 -230.416607)
			(xy 353.394218 -230.408482) (xy 353.344825 -230.392434) (xy 353.298551 -230.368856) (xy 353.256535 -230.33833)
			(xy 353.219812 -230.301607) (xy 353.189286 -230.259591) (xy 353.165708 -230.213317) (xy 353.14966 -230.163924)
			(xy 353.141535 -230.112629) (xy 352.861625 -230.112629) (xy 352.8535 -230.163924) (xy 352.837452 -230.213317)
			(xy 352.813874 -230.259591) (xy 352.783348 -230.301607) (xy 352.746625 -230.33833) (xy 352.704609 -230.368856)
			(xy 352.658335 -230.392434) (xy 352.608942 -230.408482) (xy 352.557647 -230.416607) (xy 352.505713 -230.416607)
			(xy 352.454418 -230.408482) (xy 352.405025 -230.392434) (xy 352.358751 -230.368856) (xy 352.316735 -230.33833)
			(xy 352.280012 -230.301607) (xy 352.249486 -230.259591) (xy 352.225908 -230.213317) (xy 352.20986 -230.163924)
			(xy 352.201735 -230.112629) (xy 351.921854 -230.112629) (xy 351.921854 -230.112633) (xy 351.913734 -230.163935)
			(xy 351.897687 -230.213336) (xy 351.874109 -230.259617) (xy 351.84358 -230.30164) (xy 351.806853 -230.338369)
			(xy 351.764832 -230.368899) (xy 351.718552 -230.39248) (xy 351.669153 -230.408529) (xy 351.617851 -230.416653)
			(xy 351.59188 -230.417116) (xy 351.566312 -230.416635) (xy 351.515787 -230.408752) (xy 351.467081 -230.393176)
			(xy 351.421357 -230.370281) (xy 351.379708 -230.340612) (xy 351.343128 -230.304879) (xy 351.312492 -230.263936)
			(xy 351.300034 -230.241602) (xy 351.28581 -230.214678) (xy 350.95815 -230.214678) (xy 350.943926 -230.241602)
			(xy 350.931955 -230.263165) (xy 350.902607 -230.302799) (xy 350.8677 -230.337637) (xy 350.828007 -230.366906)
			(xy 350.784409 -230.389958) (xy 350.7613 -230.398574) (xy 350.727264 -230.410512) (xy 350.727264 -230.583232)
			(xy 350.727725 -230.598002) (xy 350.736104 -230.626324) (xy 350.75224 -230.651064) (xy 350.774781 -230.670151)
			(xy 350.801842 -230.681987) (xy 350.831159 -230.685583) (xy 350.860278 -230.680637) (xy 350.886764 -230.667563)
			(xy 350.897952 -230.657908) (xy 350.916368 -230.641488) (xy 350.957159 -230.613733) (xy 351.001626 -230.592356)
			(xy 351.048777 -230.577831) (xy 351.097565 -230.570482) (xy 351.122234 -230.570024) (xy 351.148201 -230.570536)
			(xy 351.199496 -230.578665) (xy 351.248887 -230.594718) (xy 351.295159 -230.618299) (xy 351.337173 -230.648828)
			(xy 351.373894 -230.685553) (xy 351.404419 -230.72757) (xy 351.427995 -230.773845) (xy 351.444043 -230.823238)
			(xy 351.452167 -230.874533) (xy 351.452167 -230.926445) (xy 351.732089 -230.926445) (xy 351.732089 -230.874511)
			(xy 351.740214 -230.823216) (xy 351.756262 -230.773823) (xy 351.77984 -230.727549) (xy 351.810366 -230.685533)
			(xy 351.847089 -230.64881) (xy 351.889105 -230.618284) (xy 351.935379 -230.594706) (xy 351.984772 -230.578658)
			(xy 352.036067 -230.570533) (xy 352.088001 -230.570533) (xy 352.139296 -230.578658) (xy 352.188689 -230.594706)
			(xy 352.234963 -230.618284) (xy 352.276979 -230.64881) (xy 352.313702 -230.685533) (xy 352.344228 -230.727549)
			(xy 352.367806 -230.773823) (xy 352.383854 -230.823216) (xy 352.391979 -230.874511) (xy 352.392488 -230.900478)
			(xy 352.391979 -230.926445) (xy 352.671889 -230.926445) (xy 352.671889 -230.874511) (xy 352.680014 -230.823216)
			(xy 352.696062 -230.773823) (xy 352.71964 -230.727549) (xy 352.750166 -230.685533) (xy 352.786889 -230.64881)
			(xy 352.828905 -230.618284) (xy 352.875179 -230.594706) (xy 352.924572 -230.578658) (xy 352.975867 -230.570533)
			(xy 353.027801 -230.570533) (xy 353.079096 -230.578658) (xy 353.128489 -230.594706) (xy 353.174763 -230.618284)
			(xy 353.216779 -230.64881) (xy 353.253502 -230.685533) (xy 353.284028 -230.727549) (xy 353.307606 -230.773823)
			(xy 353.323654 -230.823216) (xy 353.331779 -230.874511) (xy 353.332288 -230.900478) (xy 353.331779 -230.926445)
			(xy 353.611689 -230.926445) (xy 353.611689 -230.874511) (xy 353.619814 -230.823216) (xy 353.635862 -230.773823)
			(xy 353.65944 -230.727549) (xy 353.689966 -230.685533) (xy 353.726689 -230.64881) (xy 353.768705 -230.618284)
			(xy 353.814979 -230.594706) (xy 353.864372 -230.578658) (xy 353.915667 -230.570533) (xy 353.967601 -230.570533)
			(xy 354.018896 -230.578658) (xy 354.068289 -230.594706) (xy 354.114563 -230.618284) (xy 354.156579 -230.64881)
			(xy 354.193302 -230.685533) (xy 354.223828 -230.727549) (xy 354.247406 -230.773823) (xy 354.263454 -230.823216)
			(xy 354.271579 -230.874511) (xy 354.272088 -230.900478) (xy 354.271579 -230.926445) (xy 354.551489 -230.926445)
			(xy 354.551489 -230.874511) (xy 354.559614 -230.823216) (xy 354.575662 -230.773823) (xy 354.59924 -230.727549)
			(xy 354.629766 -230.685533) (xy 354.666489 -230.64881) (xy 354.708505 -230.618284) (xy 354.754779 -230.594706)
			(xy 354.804172 -230.578658) (xy 354.855467 -230.570533) (xy 354.907401 -230.570533) (xy 354.958696 -230.578658)
			(xy 355.008089 -230.594706) (xy 355.054363 -230.618284) (xy 355.096379 -230.64881) (xy 355.133102 -230.685533)
			(xy 355.163628 -230.727549) (xy 355.187206 -230.773823) (xy 355.203254 -230.823216) (xy 355.211379 -230.874511)
			(xy 355.211888 -230.900478) (xy 355.211379 -230.926445) (xy 355.491035 -230.926445) (xy 355.491035 -230.874511)
			(xy 355.49916 -230.823216) (xy 355.515208 -230.773823) (xy 355.538786 -230.727549) (xy 355.569312 -230.685533)
			(xy 355.606035 -230.64881) (xy 355.648051 -230.618284) (xy 355.694325 -230.594706) (xy 355.743718 -230.578658)
			(xy 355.795013 -230.570533) (xy 355.846947 -230.570533) (xy 355.898242 -230.578658) (xy 355.947635 -230.594706)
			(xy 355.993909 -230.618284) (xy 356.035925 -230.64881) (xy 356.072648 -230.685533) (xy 356.103174 -230.727549)
			(xy 356.126752 -230.773823) (xy 356.1428 -230.823216) (xy 356.150925 -230.874511) (xy 356.151434 -230.900478)
			(xy 356.150925 -230.926445) (xy 356.431089 -230.926445) (xy 356.431089 -230.874511) (xy 356.439214 -230.823216)
			(xy 356.455262 -230.773823) (xy 356.47884 -230.727549) (xy 356.509366 -230.685533) (xy 356.546089 -230.64881)
			(xy 356.588105 -230.618284) (xy 356.634379 -230.594706) (xy 356.683772 -230.578658) (xy 356.735067 -230.570533)
			(xy 356.787001 -230.570533) (xy 356.838296 -230.578658) (xy 356.887689 -230.594706) (xy 356.933963 -230.618284)
			(xy 356.975979 -230.64881) (xy 357.012702 -230.685533) (xy 357.043228 -230.727549) (xy 357.066806 -230.773823)
			(xy 357.082854 -230.823216) (xy 357.090979 -230.874511) (xy 357.091488 -230.900478) (xy 357.090979 -230.926445)
			(xy 357.370635 -230.926445) (xy 357.370635 -230.874511) (xy 357.37876 -230.823216) (xy 357.394808 -230.773823)
			(xy 357.418386 -230.727549) (xy 357.448912 -230.685533) (xy 357.485635 -230.64881) (xy 357.527651 -230.618284)
			(xy 357.573925 -230.594706) (xy 357.623318 -230.578658) (xy 357.674613 -230.570533) (xy 357.726547 -230.570533)
			(xy 357.777842 -230.578658) (xy 357.827235 -230.594706) (xy 357.873509 -230.618284) (xy 357.915525 -230.64881)
			(xy 357.952248 -230.685533) (xy 357.982774 -230.727549) (xy 358.006352 -230.773823) (xy 358.0224 -230.823216)
			(xy 358.030525 -230.874511) (xy 358.031034 -230.900478) (xy 358.030525 -230.926445) (xy 358.310689 -230.926445)
			(xy 358.310689 -230.874511) (xy 358.318814 -230.823216) (xy 358.334862 -230.773823) (xy 358.35844 -230.727549)
			(xy 358.388966 -230.685533) (xy 358.425689 -230.64881) (xy 358.467705 -230.618284) (xy 358.513979 -230.594706)
			(xy 358.563372 -230.578658) (xy 358.614667 -230.570533) (xy 358.666601 -230.570533) (xy 358.717896 -230.578658)
			(xy 358.767289 -230.594706) (xy 358.813563 -230.618284) (xy 358.855579 -230.64881) (xy 358.892302 -230.685533)
			(xy 358.922828 -230.727549) (xy 358.946406 -230.773823) (xy 358.962454 -230.823216) (xy 358.970579 -230.874511)
			(xy 358.971088 -230.900478) (xy 358.970579 -230.926445) (xy 359.250489 -230.926445) (xy 359.250489 -230.874511)
			(xy 359.258614 -230.823216) (xy 359.274662 -230.773823) (xy 359.29824 -230.727549) (xy 359.328766 -230.685533)
			(xy 359.365489 -230.64881) (xy 359.407505 -230.618284) (xy 359.453779 -230.594706) (xy 359.503172 -230.578658)
			(xy 359.554467 -230.570533) (xy 359.606401 -230.570533) (xy 359.657696 -230.578658) (xy 359.707089 -230.594706)
			(xy 359.753363 -230.618284) (xy 359.795379 -230.64881) (xy 359.832102 -230.685533) (xy 359.862628 -230.727549)
			(xy 359.886206 -230.773823) (xy 359.902254 -230.823216) (xy 359.910379 -230.874511) (xy 359.910888 -230.900478)
			(xy 359.910379 -230.926445) (xy 360.190289 -230.926445) (xy 360.190289 -230.874511) (xy 360.198414 -230.823216)
			(xy 360.214462 -230.773823) (xy 360.23804 -230.727549) (xy 360.268566 -230.685533) (xy 360.305289 -230.64881)
			(xy 360.347305 -230.618284) (xy 360.393579 -230.594706) (xy 360.442972 -230.578658) (xy 360.494267 -230.570533)
			(xy 360.546201 -230.570533) (xy 360.597496 -230.578658) (xy 360.646889 -230.594706) (xy 360.693163 -230.618284)
			(xy 360.735179 -230.64881) (xy 360.771902 -230.685533) (xy 360.802428 -230.727549) (xy 360.826006 -230.773823)
			(xy 360.842054 -230.823216) (xy 360.850179 -230.874511) (xy 360.850688 -230.900478) (xy 360.850179 -230.926445)
			(xy 361.130089 -230.926445) (xy 361.130089 -230.874511) (xy 361.138214 -230.823216) (xy 361.154262 -230.773823)
			(xy 361.17784 -230.727549) (xy 361.208366 -230.685533) (xy 361.245089 -230.64881) (xy 361.287105 -230.618284)
			(xy 361.333379 -230.594706) (xy 361.382772 -230.578658) (xy 361.434067 -230.570533) (xy 361.486001 -230.570533)
			(xy 361.537296 -230.578658) (xy 361.586689 -230.594706) (xy 361.632963 -230.618284) (xy 361.674979 -230.64881)
			(xy 361.711702 -230.685533) (xy 361.742228 -230.727549) (xy 361.765806 -230.773823) (xy 361.781854 -230.823216)
			(xy 361.789979 -230.874511) (xy 361.790488 -230.900478) (xy 361.789979 -230.926445) (xy 361.781854 -230.97774)
			(xy 361.765806 -231.027133) (xy 361.742228 -231.073407) (xy 361.711702 -231.115423) (xy 361.674979 -231.152146)
			(xy 361.632963 -231.182672) (xy 361.586689 -231.20625) (xy 361.537296 -231.222298) (xy 361.486001 -231.230423)
			(xy 361.434067 -231.230423) (xy 361.382772 -231.222298) (xy 361.333379 -231.20625) (xy 361.287105 -231.182672)
			(xy 361.245089 -231.152146) (xy 361.208366 -231.115423) (xy 361.17784 -231.073407) (xy 361.154262 -231.027133)
			(xy 361.138214 -230.97774) (xy 361.130089 -230.926445) (xy 360.850179 -230.926445) (xy 360.842054 -230.97774)
			(xy 360.826006 -231.027133) (xy 360.802428 -231.073407) (xy 360.771902 -231.115423) (xy 360.735179 -231.152146)
			(xy 360.693163 -231.182672) (xy 360.646889 -231.20625) (xy 360.597496 -231.222298) (xy 360.546201 -231.230423)
			(xy 360.494267 -231.230423) (xy 360.442972 -231.222298) (xy 360.393579 -231.20625) (xy 360.347305 -231.182672)
			(xy 360.305289 -231.152146) (xy 360.268566 -231.115423) (xy 360.23804 -231.073407) (xy 360.214462 -231.027133)
			(xy 360.198414 -230.97774) (xy 360.190289 -230.926445) (xy 359.910379 -230.926445) (xy 359.902254 -230.97774)
			(xy 359.886206 -231.027133) (xy 359.862628 -231.073407) (xy 359.832102 -231.115423) (xy 359.795379 -231.152146)
			(xy 359.753363 -231.182672) (xy 359.707089 -231.20625) (xy 359.657696 -231.222298) (xy 359.606401 -231.230423)
			(xy 359.554467 -231.230423) (xy 359.503172 -231.222298) (xy 359.453779 -231.20625) (xy 359.407505 -231.182672)
			(xy 359.365489 -231.152146) (xy 359.328766 -231.115423) (xy 359.29824 -231.073407) (xy 359.274662 -231.027133)
			(xy 359.258614 -230.97774) (xy 359.250489 -230.926445) (xy 358.970579 -230.926445) (xy 358.962454 -230.97774)
			(xy 358.946406 -231.027133) (xy 358.922828 -231.073407) (xy 358.892302 -231.115423) (xy 358.855579 -231.152146)
			(xy 358.813563 -231.182672) (xy 358.767289 -231.20625) (xy 358.717896 -231.222298) (xy 358.666601 -231.230423)
			(xy 358.614667 -231.230423) (xy 358.563372 -231.222298) (xy 358.513979 -231.20625) (xy 358.467705 -231.182672)
			(xy 358.425689 -231.152146) (xy 358.388966 -231.115423) (xy 358.35844 -231.073407) (xy 358.334862 -231.027133)
			(xy 358.318814 -230.97774) (xy 358.310689 -230.926445) (xy 358.030525 -230.926445) (xy 358.0224 -230.97774)
			(xy 358.006352 -231.027133) (xy 357.982774 -231.073407) (xy 357.952248 -231.115423) (xy 357.915525 -231.152146)
			(xy 357.873509 -231.182672) (xy 357.827235 -231.20625) (xy 357.777842 -231.222298) (xy 357.726547 -231.230423)
			(xy 357.674613 -231.230423) (xy 357.623318 -231.222298) (xy 357.573925 -231.20625) (xy 357.527651 -231.182672)
			(xy 357.485635 -231.152146) (xy 357.448912 -231.115423) (xy 357.418386 -231.073407) (xy 357.394808 -231.027133)
			(xy 357.37876 -230.97774) (xy 357.370635 -230.926445) (xy 357.090979 -230.926445) (xy 357.082854 -230.97774)
			(xy 357.066806 -231.027133) (xy 357.043228 -231.073407) (xy 357.012702 -231.115423) (xy 356.975979 -231.152146)
			(xy 356.933963 -231.182672) (xy 356.887689 -231.20625) (xy 356.838296 -231.222298) (xy 356.787001 -231.230423)
			(xy 356.735067 -231.230423) (xy 356.683772 -231.222298) (xy 356.634379 -231.20625) (xy 356.588105 -231.182672)
			(xy 356.546089 -231.152146) (xy 356.509366 -231.115423) (xy 356.47884 -231.073407) (xy 356.455262 -231.027133)
			(xy 356.439214 -230.97774) (xy 356.431089 -230.926445) (xy 356.150925 -230.926445) (xy 356.1428 -230.97774)
			(xy 356.126752 -231.027133) (xy 356.103174 -231.073407) (xy 356.072648 -231.115423) (xy 356.035925 -231.152146)
			(xy 355.993909 -231.182672) (xy 355.947635 -231.20625) (xy 355.898242 -231.222298) (xy 355.846947 -231.230423)
			(xy 355.795013 -231.230423) (xy 355.743718 -231.222298) (xy 355.694325 -231.20625) (xy 355.648051 -231.182672)
			(xy 355.606035 -231.152146) (xy 355.569312 -231.115423) (xy 355.538786 -231.073407) (xy 355.515208 -231.027133)
			(xy 355.49916 -230.97774) (xy 355.491035 -230.926445) (xy 355.211379 -230.926445) (xy 355.203254 -230.97774)
			(xy 355.187206 -231.027133) (xy 355.163628 -231.073407) (xy 355.133102 -231.115423) (xy 355.096379 -231.152146)
			(xy 355.054363 -231.182672) (xy 355.008089 -231.20625) (xy 354.958696 -231.222298) (xy 354.907401 -231.230423)
			(xy 354.855467 -231.230423) (xy 354.804172 -231.222298) (xy 354.754779 -231.20625) (xy 354.708505 -231.182672)
			(xy 354.666489 -231.152146) (xy 354.629766 -231.115423) (xy 354.59924 -231.073407) (xy 354.575662 -231.027133)
			(xy 354.559614 -230.97774) (xy 354.551489 -230.926445) (xy 354.271579 -230.926445) (xy 354.263454 -230.97774)
			(xy 354.247406 -231.027133) (xy 354.223828 -231.073407) (xy 354.193302 -231.115423) (xy 354.156579 -231.152146)
			(xy 354.114563 -231.182672) (xy 354.068289 -231.20625) (xy 354.018896 -231.222298) (xy 353.967601 -231.230423)
			(xy 353.915667 -231.230423) (xy 353.864372 -231.222298) (xy 353.814979 -231.20625) (xy 353.768705 -231.182672)
			(xy 353.726689 -231.152146) (xy 353.689966 -231.115423) (xy 353.65944 -231.073407) (xy 353.635862 -231.027133)
			(xy 353.619814 -230.97774) (xy 353.611689 -230.926445) (xy 353.331779 -230.926445) (xy 353.323654 -230.97774)
			(xy 353.307606 -231.027133) (xy 353.284028 -231.073407) (xy 353.253502 -231.115423) (xy 353.216779 -231.152146)
			(xy 353.174763 -231.182672) (xy 353.128489 -231.20625) (xy 353.079096 -231.222298) (xy 353.027801 -231.230423)
			(xy 352.975867 -231.230423) (xy 352.924572 -231.222298) (xy 352.875179 -231.20625) (xy 352.828905 -231.182672)
			(xy 352.786889 -231.152146) (xy 352.750166 -231.115423) (xy 352.71964 -231.073407) (xy 352.696062 -231.027133)
			(xy 352.680014 -230.97774) (xy 352.671889 -230.926445) (xy 352.391979 -230.926445) (xy 352.383854 -230.97774)
			(xy 352.367806 -231.027133) (xy 352.344228 -231.073407) (xy 352.313702 -231.115423) (xy 352.276979 -231.152146)
			(xy 352.234963 -231.182672) (xy 352.188689 -231.20625) (xy 352.139296 -231.222298) (xy 352.088001 -231.230423)
			(xy 352.036067 -231.230423) (xy 351.984772 -231.222298) (xy 351.935379 -231.20625) (xy 351.889105 -231.182672)
			(xy 351.847089 -231.152146) (xy 351.810366 -231.115423) (xy 351.77984 -231.073407) (xy 351.756262 -231.027133)
			(xy 351.740214 -230.97774) (xy 351.732089 -230.926445) (xy 351.452167 -230.926445) (xy 351.452167 -230.926467)
			(xy 351.444043 -230.977762) (xy 351.427995 -231.027155) (xy 351.404419 -231.07343) (xy 351.373894 -231.115447)
			(xy 351.337173 -231.152172) (xy 351.295159 -231.182701) (xy 351.248887 -231.206282) (xy 351.199496 -231.222335)
			(xy 351.148201 -231.230464) (xy 351.122234 -231.230932) (xy 351.097564 -231.230475) (xy 351.048774 -231.223135)
			(xy 351.00162 -231.208613) (xy 350.957154 -231.187233) (xy 350.916366 -231.159471) (xy 350.897952 -231.143048)
			(xy 350.886791 -231.133377) (xy 350.860308 -231.120332) (xy 350.831202 -231.115408) (xy 350.801902 -231.119015)
			(xy 350.774859 -231.130853) (xy 350.752332 -231.149932) (xy 350.736204 -231.174657) (xy 350.727822 -231.202962)
			(xy 350.727264 -231.217724) (xy 350.727264 -231.390698) (xy 350.7613 -231.402636) (xy 350.78521 -231.411509)
			(xy 350.830182 -231.435558) (xy 350.870925 -231.466231) (xy 350.906472 -231.5028) (xy 350.935978 -231.544396)
			(xy 350.958742 -231.590032) (xy 350.974225 -231.638623) (xy 350.982058 -231.689017) (xy 350.982056 -231.740015)
			(xy 350.981978 -231.740515) (xy 351.261935 -231.740515) (xy 351.261935 -231.688581) (xy 351.27006 -231.637286)
			(xy 351.286108 -231.587893) (xy 351.309686 -231.541619) (xy 351.340212 -231.499603) (xy 351.376935 -231.46288)
			(xy 351.418951 -231.432354) (xy 351.465225 -231.408776) (xy 351.514618 -231.392728) (xy 351.565913 -231.384603)
			(xy 351.617847 -231.384603) (xy 351.669142 -231.392728) (xy 351.718535 -231.408776) (xy 351.764809 -231.432354)
			(xy 351.806825 -231.46288) (xy 351.843548 -231.499603) (xy 351.874074 -231.541619) (xy 351.897652 -231.587893)
			(xy 351.9137 -231.637286) (xy 351.921825 -231.688581) (xy 351.922334 -231.714548) (xy 351.921825 -231.740515)
			(xy 352.201735 -231.740515) (xy 352.201735 -231.688581) (xy 352.20986 -231.637286) (xy 352.225908 -231.587893)
			(xy 352.249486 -231.541619) (xy 352.280012 -231.499603) (xy 352.316735 -231.46288) (xy 352.358751 -231.432354)
			(xy 352.405025 -231.408776) (xy 352.454418 -231.392728) (xy 352.505713 -231.384603) (xy 352.557647 -231.384603)
			(xy 352.608942 -231.392728) (xy 352.658335 -231.408776) (xy 352.704609 -231.432354) (xy 352.746625 -231.46288)
			(xy 352.783348 -231.499603) (xy 352.813874 -231.541619) (xy 352.837452 -231.587893) (xy 352.8535 -231.637286)
			(xy 352.861625 -231.688581) (xy 352.862134 -231.714548) (xy 352.861625 -231.740515) (xy 353.141535 -231.740515)
			(xy 353.141535 -231.688581) (xy 353.14966 -231.637286) (xy 353.165708 -231.587893) (xy 353.189286 -231.541619)
			(xy 353.219812 -231.499603) (xy 353.256535 -231.46288) (xy 353.298551 -231.432354) (xy 353.344825 -231.408776)
			(xy 353.394218 -231.392728) (xy 353.445513 -231.384603) (xy 353.497447 -231.384603) (xy 353.548742 -231.392728)
			(xy 353.598135 -231.408776) (xy 353.644409 -231.432354) (xy 353.686425 -231.46288) (xy 353.723148 -231.499603)
			(xy 353.753674 -231.541619) (xy 353.777252 -231.587893) (xy 353.7933 -231.637286) (xy 353.801425 -231.688581)
			(xy 353.801934 -231.714548) (xy 353.801425 -231.740515) (xy 354.081335 -231.740515) (xy 354.081335 -231.688581)
			(xy 354.08946 -231.637286) (xy 354.105508 -231.587893) (xy 354.129086 -231.541619) (xy 354.159612 -231.499603)
			(xy 354.196335 -231.46288) (xy 354.238351 -231.432354) (xy 354.284625 -231.408776) (xy 354.334018 -231.392728)
			(xy 354.385313 -231.384603) (xy 354.437247 -231.384603) (xy 354.488542 -231.392728) (xy 354.537935 -231.408776)
			(xy 354.584209 -231.432354) (xy 354.626225 -231.46288) (xy 354.662948 -231.499603) (xy 354.693474 -231.541619)
			(xy 354.717052 -231.587893) (xy 354.7331 -231.637286) (xy 354.741225 -231.688581) (xy 354.741734 -231.714548)
			(xy 354.741225 -231.740515) (xy 355.021135 -231.740515) (xy 355.021135 -231.688581) (xy 355.02926 -231.637286)
			(xy 355.045308 -231.587893) (xy 355.068886 -231.541619) (xy 355.099412 -231.499603) (xy 355.136135 -231.46288)
			(xy 355.178151 -231.432354) (xy 355.224425 -231.408776) (xy 355.273818 -231.392728) (xy 355.325113 -231.384603)
			(xy 355.377047 -231.384603) (xy 355.428342 -231.392728) (xy 355.477735 -231.408776) (xy 355.524009 -231.432354)
			(xy 355.566025 -231.46288) (xy 355.602748 -231.499603) (xy 355.633274 -231.541619) (xy 355.656852 -231.587893)
			(xy 355.6729 -231.637286) (xy 355.681025 -231.688581) (xy 355.681534 -231.714548) (xy 355.681025 -231.740515)
			(xy 355.960935 -231.740515) (xy 355.960935 -231.688581) (xy 355.96906 -231.637286) (xy 355.985108 -231.587893)
			(xy 356.008686 -231.541619) (xy 356.039212 -231.499603) (xy 356.075935 -231.46288) (xy 356.117951 -231.432354)
			(xy 356.164225 -231.408776) (xy 356.213618 -231.392728) (xy 356.264913 -231.384603) (xy 356.316847 -231.384603)
			(xy 356.368142 -231.392728) (xy 356.417535 -231.408776) (xy 356.463809 -231.432354) (xy 356.505825 -231.46288)
			(xy 356.542548 -231.499603) (xy 356.573074 -231.541619) (xy 356.596652 -231.587893) (xy 356.6127 -231.637286)
			(xy 356.620825 -231.688581) (xy 356.621334 -231.714548) (xy 356.620825 -231.740515) (xy 356.900735 -231.740515)
			(xy 356.900735 -231.688581) (xy 356.90886 -231.637286) (xy 356.924908 -231.587893) (xy 356.948486 -231.541619)
			(xy 356.979012 -231.499603) (xy 357.015735 -231.46288) (xy 357.057751 -231.432354) (xy 357.104025 -231.408776)
			(xy 357.153418 -231.392728) (xy 357.204713 -231.384603) (xy 357.256647 -231.384603) (xy 357.307942 -231.392728)
			(xy 357.357335 -231.408776) (xy 357.403609 -231.432354) (xy 357.445625 -231.46288) (xy 357.482348 -231.499603)
			(xy 357.512874 -231.541619) (xy 357.536452 -231.587893) (xy 357.5525 -231.637286) (xy 357.560625 -231.688581)
			(xy 357.561134 -231.714548) (xy 357.560625 -231.740515) (xy 357.840789 -231.740515) (xy 357.840789 -231.688581)
			(xy 357.848914 -231.637286) (xy 357.864962 -231.587893) (xy 357.88854 -231.541619) (xy 357.919066 -231.499603)
			(xy 357.955789 -231.46288) (xy 357.997805 -231.432354) (xy 358.044079 -231.408776) (xy 358.093472 -231.392728)
			(xy 358.144767 -231.384603) (xy 358.196701 -231.384603) (xy 358.247996 -231.392728) (xy 358.297389 -231.408776)
			(xy 358.343663 -231.432354) (xy 358.385679 -231.46288) (xy 358.422402 -231.499603) (xy 358.452928 -231.541619)
			(xy 358.476506 -231.587893) (xy 358.492554 -231.637286) (xy 358.500679 -231.688581) (xy 358.501188 -231.714548)
			(xy 358.500679 -231.740515) (xy 358.780335 -231.740515) (xy 358.780335 -231.688581) (xy 358.78846 -231.637286)
			(xy 358.804508 -231.587893) (xy 358.828086 -231.541619) (xy 358.858612 -231.499603) (xy 358.895335 -231.46288)
			(xy 358.937351 -231.432354) (xy 358.983625 -231.408776) (xy 359.033018 -231.392728) (xy 359.084313 -231.384603)
			(xy 359.136247 -231.384603) (xy 359.187542 -231.392728) (xy 359.236935 -231.408776) (xy 359.283209 -231.432354)
			(xy 359.325225 -231.46288) (xy 359.361948 -231.499603) (xy 359.392474 -231.541619) (xy 359.416052 -231.587893)
			(xy 359.4321 -231.637286) (xy 359.440225 -231.688581) (xy 359.440734 -231.714548) (xy 359.440225 -231.740515)
			(xy 359.720643 -231.740515) (xy 359.720643 -231.688581) (xy 359.728768 -231.637286) (xy 359.744816 -231.587893)
			(xy 359.768394 -231.541619) (xy 359.79892 -231.499603) (xy 359.835643 -231.46288) (xy 359.877659 -231.432354)
			(xy 359.923933 -231.408776) (xy 359.973326 -231.392728) (xy 360.024621 -231.384603) (xy 360.076555 -231.384603)
			(xy 360.12785 -231.392728) (xy 360.177243 -231.408776) (xy 360.223517 -231.432354) (xy 360.265533 -231.46288)
			(xy 360.302256 -231.499603) (xy 360.332782 -231.541619) (xy 360.35636 -231.587893) (xy 360.372408 -231.637286)
			(xy 360.380533 -231.688581) (xy 360.381042 -231.714548) (xy 360.380533 -231.740515) (xy 360.660443 -231.740515)
			(xy 360.660443 -231.688581) (xy 360.668568 -231.637286) (xy 360.684616 -231.587893) (xy 360.708194 -231.541619)
			(xy 360.73872 -231.499603) (xy 360.775443 -231.46288) (xy 360.817459 -231.432354) (xy 360.863733 -231.408776)
			(xy 360.913126 -231.392728) (xy 360.964421 -231.384603) (xy 361.016355 -231.384603) (xy 361.06765 -231.392728)
			(xy 361.117043 -231.408776) (xy 361.163317 -231.432354) (xy 361.205333 -231.46288) (xy 361.242056 -231.499603)
			(xy 361.272582 -231.541619) (xy 361.29616 -231.587893) (xy 361.312208 -231.637286) (xy 361.320333 -231.688581)
			(xy 361.320842 -231.714548) (xy 361.320333 -231.740515) (xy 361.312208 -231.79181) (xy 361.29616 -231.841203)
			(xy 361.272582 -231.887477) (xy 361.242056 -231.929493) (xy 361.205333 -231.966216) (xy 361.163317 -231.996742)
			(xy 361.117043 -232.02032) (xy 361.06765 -232.036368) (xy 361.016355 -232.044493) (xy 360.964421 -232.044493)
			(xy 360.913126 -232.036368) (xy 360.863733 -232.02032) (xy 360.817459 -231.996742) (xy 360.775443 -231.966216)
			(xy 360.73872 -231.929493) (xy 360.708194 -231.887477) (xy 360.684616 -231.841203) (xy 360.668568 -231.79181)
			(xy 360.660443 -231.740515) (xy 360.380533 -231.740515) (xy 360.372408 -231.79181) (xy 360.35636 -231.841203)
			(xy 360.332782 -231.887477) (xy 360.302256 -231.929493) (xy 360.265533 -231.966216) (xy 360.223517 -231.996742)
			(xy 360.177243 -232.02032) (xy 360.12785 -232.036368) (xy 360.076555 -232.044493) (xy 360.024621 -232.044493)
			(xy 359.973326 -232.036368) (xy 359.923933 -232.02032) (xy 359.877659 -231.996742) (xy 359.835643 -231.966216)
			(xy 359.79892 -231.929493) (xy 359.768394 -231.887477) (xy 359.744816 -231.841203) (xy 359.728768 -231.79181)
			(xy 359.720643 -231.740515) (xy 359.440225 -231.740515) (xy 359.4321 -231.79181) (xy 359.416052 -231.841203)
			(xy 359.392474 -231.887477) (xy 359.361948 -231.929493) (xy 359.325225 -231.966216) (xy 359.283209 -231.996742)
			(xy 359.236935 -232.02032) (xy 359.187542 -232.036368) (xy 359.136247 -232.044493) (xy 359.084313 -232.044493)
			(xy 359.033018 -232.036368) (xy 358.983625 -232.02032) (xy 358.937351 -231.996742) (xy 358.895335 -231.966216)
			(xy 358.858612 -231.929493) (xy 358.828086 -231.887477) (xy 358.804508 -231.841203) (xy 358.78846 -231.79181)
			(xy 358.780335 -231.740515) (xy 358.500679 -231.740515) (xy 358.492554 -231.79181) (xy 358.476506 -231.841203)
			(xy 358.452928 -231.887477) (xy 358.422402 -231.929493) (xy 358.385679 -231.966216) (xy 358.343663 -231.996742)
			(xy 358.297389 -232.02032) (xy 358.247996 -232.036368) (xy 358.196701 -232.044493) (xy 358.144767 -232.044493)
			(xy 358.093472 -232.036368) (xy 358.044079 -232.02032) (xy 357.997805 -231.996742) (xy 357.955789 -231.966216)
			(xy 357.919066 -231.929493) (xy 357.88854 -231.887477) (xy 357.864962 -231.841203) (xy 357.848914 -231.79181)
			(xy 357.840789 -231.740515) (xy 357.560625 -231.740515) (xy 357.5525 -231.79181) (xy 357.536452 -231.841203)
			(xy 357.512874 -231.887477) (xy 357.482348 -231.929493) (xy 357.445625 -231.966216) (xy 357.403609 -231.996742)
			(xy 357.357335 -232.02032) (xy 357.307942 -232.036368) (xy 357.256647 -232.044493) (xy 357.204713 -232.044493)
			(xy 357.153418 -232.036368) (xy 357.104025 -232.02032) (xy 357.057751 -231.996742) (xy 357.015735 -231.966216)
			(xy 356.979012 -231.929493) (xy 356.948486 -231.887477) (xy 356.924908 -231.841203) (xy 356.90886 -231.79181)
			(xy 356.900735 -231.740515) (xy 356.620825 -231.740515) (xy 356.6127 -231.79181) (xy 356.596652 -231.841203)
			(xy 356.573074 -231.887477) (xy 356.542548 -231.929493) (xy 356.505825 -231.966216) (xy 356.463809 -231.996742)
			(xy 356.417535 -232.02032) (xy 356.368142 -232.036368) (xy 356.316847 -232.044493) (xy 356.264913 -232.044493)
			(xy 356.213618 -232.036368) (xy 356.164225 -232.02032) (xy 356.117951 -231.996742) (xy 356.075935 -231.966216)
			(xy 356.039212 -231.929493) (xy 356.008686 -231.887477) (xy 355.985108 -231.841203) (xy 355.96906 -231.79181)
			(xy 355.960935 -231.740515) (xy 355.681025 -231.740515) (xy 355.6729 -231.79181) (xy 355.656852 -231.841203)
			(xy 355.633274 -231.887477) (xy 355.602748 -231.929493) (xy 355.566025 -231.966216) (xy 355.524009 -231.996742)
			(xy 355.477735 -232.02032) (xy 355.428342 -232.036368) (xy 355.377047 -232.044493) (xy 355.325113 -232.044493)
			(xy 355.273818 -232.036368) (xy 355.224425 -232.02032) (xy 355.178151 -231.996742) (xy 355.136135 -231.966216)
			(xy 355.099412 -231.929493) (xy 355.068886 -231.887477) (xy 355.045308 -231.841203) (xy 355.02926 -231.79181)
			(xy 355.021135 -231.740515) (xy 354.741225 -231.740515) (xy 354.7331 -231.79181) (xy 354.717052 -231.841203)
			(xy 354.693474 -231.887477) (xy 354.662948 -231.929493) (xy 354.626225 -231.966216) (xy 354.584209 -231.996742)
			(xy 354.537935 -232.02032) (xy 354.488542 -232.036368) (xy 354.437247 -232.044493) (xy 354.385313 -232.044493)
			(xy 354.334018 -232.036368) (xy 354.284625 -232.02032) (xy 354.238351 -231.996742) (xy 354.196335 -231.966216)
			(xy 354.159612 -231.929493) (xy 354.129086 -231.887477) (xy 354.105508 -231.841203) (xy 354.08946 -231.79181)
			(xy 354.081335 -231.740515) (xy 353.801425 -231.740515) (xy 353.7933 -231.79181) (xy 353.777252 -231.841203)
			(xy 353.753674 -231.887477) (xy 353.723148 -231.929493) (xy 353.686425 -231.966216) (xy 353.644409 -231.996742)
			(xy 353.598135 -232.02032) (xy 353.548742 -232.036368) (xy 353.497447 -232.044493) (xy 353.445513 -232.044493)
			(xy 353.394218 -232.036368) (xy 353.344825 -232.02032) (xy 353.298551 -231.996742) (xy 353.256535 -231.966216)
			(xy 353.219812 -231.929493) (xy 353.189286 -231.887477) (xy 353.165708 -231.841203) (xy 353.14966 -231.79181)
			(xy 353.141535 -231.740515) (xy 352.861625 -231.740515) (xy 352.8535 -231.79181) (xy 352.837452 -231.841203)
			(xy 352.813874 -231.887477) (xy 352.783348 -231.929493) (xy 352.746625 -231.966216) (xy 352.704609 -231.996742)
			(xy 352.658335 -232.02032) (xy 352.608942 -232.036368) (xy 352.557647 -232.044493) (xy 352.505713 -232.044493)
			(xy 352.454418 -232.036368) (xy 352.405025 -232.02032) (xy 352.358751 -231.996742) (xy 352.316735 -231.966216)
			(xy 352.280012 -231.929493) (xy 352.249486 -231.887477) (xy 352.225908 -231.841203) (xy 352.20986 -231.79181)
			(xy 352.201735 -231.740515) (xy 351.921825 -231.740515) (xy 351.9137 -231.79181) (xy 351.897652 -231.841203)
			(xy 351.874074 -231.887477) (xy 351.843548 -231.929493) (xy 351.806825 -231.966216) (xy 351.764809 -231.996742)
			(xy 351.718535 -232.02032) (xy 351.669142 -232.036368) (xy 351.617847 -232.044493) (xy 351.565913 -232.044493)
			(xy 351.514618 -232.036368) (xy 351.465225 -232.02032) (xy 351.418951 -231.996742) (xy 351.376935 -231.966216)
			(xy 351.340212 -231.929493) (xy 351.309686 -231.887477) (xy 351.286108 -231.841203) (xy 351.27006 -231.79181)
			(xy 351.261935 -231.740515) (xy 350.981978 -231.740515) (xy 350.974218 -231.790408) (xy 350.95873 -231.838997)
			(xy 350.935961 -231.884631) (xy 350.906451 -231.926224) (xy 350.870901 -231.96279) (xy 350.830155 -231.993459)
			(xy 350.785181 -232.017504) (xy 350.7613 -232.02646) (xy 350.727264 -232.038398) (xy 350.727264 -232.211118)
			(xy 350.727723 -232.225889) (xy 350.7361 -232.254216) (xy 350.752235 -232.278959) (xy 350.774778 -232.298049)
			(xy 350.801841 -232.309887) (xy 350.831161 -232.313483) (xy 350.860283 -232.308535) (xy 350.886771 -232.295459)
			(xy 350.897952 -232.285794) (xy 350.916368 -232.269374) (xy 350.95716 -232.241621) (xy 351.001626 -232.220244)
			(xy 351.048778 -232.20572) (xy 351.097565 -232.198371) (xy 351.122234 -232.19791) (xy 351.148202 -232.198422)
			(xy 351.199499 -232.206551) (xy 351.248892 -232.222605) (xy 351.295166 -232.246187) (xy 351.337182 -232.276717)
			(xy 351.373905 -232.313444) (xy 351.404431 -232.355463) (xy 351.428008 -232.401739) (xy 351.444057 -232.451134)
			(xy 351.452181 -232.502432) (xy 351.452181 -232.554331) (xy 351.732089 -232.554331) (xy 351.732089 -232.502397)
			(xy 351.740214 -232.451102) (xy 351.756262 -232.401709) (xy 351.77984 -232.355435) (xy 351.810366 -232.313419)
			(xy 351.847089 -232.276696) (xy 351.889105 -232.24617) (xy 351.935379 -232.222592) (xy 351.984772 -232.206544)
			(xy 352.036067 -232.198419) (xy 352.088001 -232.198419) (xy 352.139296 -232.206544) (xy 352.188689 -232.222592)
			(xy 352.234963 -232.24617) (xy 352.276979 -232.276696) (xy 352.313702 -232.313419) (xy 352.344228 -232.355435)
			(xy 352.367806 -232.401709) (xy 352.383854 -232.451102) (xy 352.391979 -232.502397) (xy 352.392488 -232.528364)
			(xy 352.391979 -232.554331) (xy 352.671889 -232.554331) (xy 352.671889 -232.502397) (xy 352.680014 -232.451102)
			(xy 352.696062 -232.401709) (xy 352.71964 -232.355435) (xy 352.750166 -232.313419) (xy 352.786889 -232.276696)
			(xy 352.828905 -232.24617) (xy 352.875179 -232.222592) (xy 352.924572 -232.206544) (xy 352.975867 -232.198419)
			(xy 353.027801 -232.198419) (xy 353.079096 -232.206544) (xy 353.128489 -232.222592) (xy 353.174763 -232.24617)
			(xy 353.216779 -232.276696) (xy 353.253502 -232.313419) (xy 353.284028 -232.355435) (xy 353.307606 -232.401709)
			(xy 353.323654 -232.451102) (xy 353.331779 -232.502397) (xy 353.332288 -232.528364) (xy 353.331779 -232.554331)
			(xy 353.611689 -232.554331) (xy 353.611689 -232.502397) (xy 353.619814 -232.451102) (xy 353.635862 -232.401709)
			(xy 353.65944 -232.355435) (xy 353.689966 -232.313419) (xy 353.726689 -232.276696) (xy 353.768705 -232.24617)
			(xy 353.814979 -232.222592) (xy 353.864372 -232.206544) (xy 353.915667 -232.198419) (xy 353.967601 -232.198419)
			(xy 354.018896 -232.206544) (xy 354.068289 -232.222592) (xy 354.114563 -232.24617) (xy 354.156579 -232.276696)
			(xy 354.193302 -232.313419) (xy 354.223828 -232.355435) (xy 354.247406 -232.401709) (xy 354.263454 -232.451102)
			(xy 354.271579 -232.502397) (xy 354.272088 -232.528364) (xy 354.271579 -232.554331) (xy 354.551489 -232.554331)
			(xy 354.551489 -232.502397) (xy 354.559614 -232.451102) (xy 354.575662 -232.401709) (xy 354.59924 -232.355435)
			(xy 354.629766 -232.313419) (xy 354.666489 -232.276696) (xy 354.708505 -232.24617) (xy 354.754779 -232.222592)
			(xy 354.804172 -232.206544) (xy 354.855467 -232.198419) (xy 354.907401 -232.198419) (xy 354.958696 -232.206544)
			(xy 355.008089 -232.222592) (xy 355.054363 -232.24617) (xy 355.096379 -232.276696) (xy 355.133102 -232.313419)
			(xy 355.163628 -232.355435) (xy 355.187206 -232.401709) (xy 355.203254 -232.451102) (xy 355.211379 -232.502397)
			(xy 355.211888 -232.528364) (xy 355.211379 -232.554331) (xy 355.491289 -232.554331) (xy 355.491289 -232.502397)
			(xy 355.499414 -232.451102) (xy 355.515462 -232.401709) (xy 355.53904 -232.355435) (xy 355.569566 -232.313419)
			(xy 355.606289 -232.276696) (xy 355.648305 -232.24617) (xy 355.694579 -232.222592) (xy 355.743972 -232.206544)
			(xy 355.795267 -232.198419) (xy 355.847201 -232.198419) (xy 355.898496 -232.206544) (xy 355.947889 -232.222592)
			(xy 355.994163 -232.24617) (xy 356.036179 -232.276696) (xy 356.072902 -232.313419) (xy 356.103428 -232.355435)
			(xy 356.127006 -232.401709) (xy 356.143054 -232.451102) (xy 356.151179 -232.502397) (xy 356.151688 -232.528364)
			(xy 356.151179 -232.554331) (xy 356.431089 -232.554331) (xy 356.431089 -232.502397) (xy 356.439214 -232.451102)
			(xy 356.455262 -232.401709) (xy 356.47884 -232.355435) (xy 356.509366 -232.313419) (xy 356.546089 -232.276696)
			(xy 356.588105 -232.24617) (xy 356.634379 -232.222592) (xy 356.683772 -232.206544) (xy 356.735067 -232.198419)
			(xy 356.787001 -232.198419) (xy 356.838296 -232.206544) (xy 356.887689 -232.222592) (xy 356.933963 -232.24617)
			(xy 356.975979 -232.276696) (xy 357.012702 -232.313419) (xy 357.043228 -232.355435) (xy 357.066806 -232.401709)
			(xy 357.082854 -232.451102) (xy 357.090979 -232.502397) (xy 357.091488 -232.528364) (xy 357.090979 -232.554331)
			(xy 357.370889 -232.554331) (xy 357.370889 -232.502397) (xy 357.379014 -232.451102) (xy 357.395062 -232.401709)
			(xy 357.41864 -232.355435) (xy 357.449166 -232.313419) (xy 357.485889 -232.276696) (xy 357.527905 -232.24617)
			(xy 357.574179 -232.222592) (xy 357.623572 -232.206544) (xy 357.674867 -232.198419) (xy 357.726801 -232.198419)
			(xy 357.778096 -232.206544) (xy 357.827489 -232.222592) (xy 357.873763 -232.24617) (xy 357.915779 -232.276696)
			(xy 357.952502 -232.313419) (xy 357.983028 -232.355435) (xy 358.006606 -232.401709) (xy 358.022654 -232.451102)
			(xy 358.030779 -232.502397) (xy 358.031288 -232.528364) (xy 358.030779 -232.554331) (xy 358.310689 -232.554331)
			(xy 358.310689 -232.502397) (xy 358.318814 -232.451102) (xy 358.334862 -232.401709) (xy 358.35844 -232.355435)
			(xy 358.388966 -232.313419) (xy 358.425689 -232.276696) (xy 358.467705 -232.24617) (xy 358.513979 -232.222592)
			(xy 358.563372 -232.206544) (xy 358.614667 -232.198419) (xy 358.666601 -232.198419) (xy 358.717896 -232.206544)
			(xy 358.767289 -232.222592) (xy 358.813563 -232.24617) (xy 358.855579 -232.276696) (xy 358.892302 -232.313419)
			(xy 358.922828 -232.355435) (xy 358.946406 -232.401709) (xy 358.962454 -232.451102) (xy 358.970579 -232.502397)
			(xy 358.971088 -232.528364) (xy 358.970579 -232.554331) (xy 359.250489 -232.554331) (xy 359.250489 -232.502397)
			(xy 359.258614 -232.451102) (xy 359.274662 -232.401709) (xy 359.29824 -232.355435) (xy 359.328766 -232.313419)
			(xy 359.365489 -232.276696) (xy 359.407505 -232.24617) (xy 359.453779 -232.222592) (xy 359.503172 -232.206544)
			(xy 359.554467 -232.198419) (xy 359.606401 -232.198419) (xy 359.657696 -232.206544) (xy 359.707089 -232.222592)
			(xy 359.753363 -232.24617) (xy 359.795379 -232.276696) (xy 359.832102 -232.313419) (xy 359.862628 -232.355435)
			(xy 359.886206 -232.401709) (xy 359.902254 -232.451102) (xy 359.910379 -232.502397) (xy 359.910888 -232.528364)
			(xy 359.910379 -232.554331) (xy 360.190289 -232.554331) (xy 360.190289 -232.502397) (xy 360.198414 -232.451102)
			(xy 360.214462 -232.401709) (xy 360.23804 -232.355435) (xy 360.268566 -232.313419) (xy 360.305289 -232.276696)
			(xy 360.347305 -232.24617) (xy 360.393579 -232.222592) (xy 360.442972 -232.206544) (xy 360.494267 -232.198419)
			(xy 360.546201 -232.198419) (xy 360.597496 -232.206544) (xy 360.646889 -232.222592) (xy 360.693163 -232.24617)
			(xy 360.735179 -232.276696) (xy 360.771902 -232.313419) (xy 360.802428 -232.355435) (xy 360.826006 -232.401709)
			(xy 360.842054 -232.451102) (xy 360.850179 -232.502397) (xy 360.850688 -232.528364) (xy 360.850179 -232.554331)
			(xy 361.130089 -232.554331) (xy 361.130089 -232.502397) (xy 361.138214 -232.451102) (xy 361.154262 -232.401709)
			(xy 361.17784 -232.355435) (xy 361.208366 -232.313419) (xy 361.245089 -232.276696) (xy 361.287105 -232.24617)
			(xy 361.333379 -232.222592) (xy 361.382772 -232.206544) (xy 361.434067 -232.198419) (xy 361.486001 -232.198419)
			(xy 361.537296 -232.206544) (xy 361.586689 -232.222592) (xy 361.632963 -232.24617) (xy 361.674979 -232.276696)
			(xy 361.711702 -232.313419) (xy 361.742228 -232.355435) (xy 361.765806 -232.401709) (xy 361.781854 -232.451102)
			(xy 361.789979 -232.502397) (xy 361.790488 -232.528364) (xy 361.789979 -232.554331) (xy 361.781854 -232.605626)
			(xy 361.765806 -232.655019) (xy 361.742228 -232.701293) (xy 361.711702 -232.743309) (xy 361.674979 -232.780032)
			(xy 361.632963 -232.810558) (xy 361.586689 -232.834136) (xy 361.537296 -232.850184) (xy 361.486001 -232.858309)
			(xy 361.434067 -232.858309) (xy 361.382772 -232.850184) (xy 361.333379 -232.834136) (xy 361.287105 -232.810558)
			(xy 361.245089 -232.780032) (xy 361.208366 -232.743309) (xy 361.17784 -232.701293) (xy 361.154262 -232.655019)
			(xy 361.138214 -232.605626) (xy 361.130089 -232.554331) (xy 360.850179 -232.554331) (xy 360.842054 -232.605626)
			(xy 360.826006 -232.655019) (xy 360.802428 -232.701293) (xy 360.771902 -232.743309) (xy 360.735179 -232.780032)
			(xy 360.693163 -232.810558) (xy 360.646889 -232.834136) (xy 360.597496 -232.850184) (xy 360.546201 -232.858309)
			(xy 360.494267 -232.858309) (xy 360.442972 -232.850184) (xy 360.393579 -232.834136) (xy 360.347305 -232.810558)
			(xy 360.305289 -232.780032) (xy 360.268566 -232.743309) (xy 360.23804 -232.701293) (xy 360.214462 -232.655019)
			(xy 360.198414 -232.605626) (xy 360.190289 -232.554331) (xy 359.910379 -232.554331) (xy 359.902254 -232.605626)
			(xy 359.886206 -232.655019) (xy 359.862628 -232.701293) (xy 359.832102 -232.743309) (xy 359.795379 -232.780032)
			(xy 359.753363 -232.810558) (xy 359.707089 -232.834136) (xy 359.657696 -232.850184) (xy 359.606401 -232.858309)
			(xy 359.554467 -232.858309) (xy 359.503172 -232.850184) (xy 359.453779 -232.834136) (xy 359.407505 -232.810558)
			(xy 359.365489 -232.780032) (xy 359.328766 -232.743309) (xy 359.29824 -232.701293) (xy 359.274662 -232.655019)
			(xy 359.258614 -232.605626) (xy 359.250489 -232.554331) (xy 358.970579 -232.554331) (xy 358.962454 -232.605626)
			(xy 358.946406 -232.655019) (xy 358.922828 -232.701293) (xy 358.892302 -232.743309) (xy 358.855579 -232.780032)
			(xy 358.813563 -232.810558) (xy 358.767289 -232.834136) (xy 358.717896 -232.850184) (xy 358.666601 -232.858309)
			(xy 358.614667 -232.858309) (xy 358.563372 -232.850184) (xy 358.513979 -232.834136) (xy 358.467705 -232.810558)
			(xy 358.425689 -232.780032) (xy 358.388966 -232.743309) (xy 358.35844 -232.701293) (xy 358.334862 -232.655019)
			(xy 358.318814 -232.605626) (xy 358.310689 -232.554331) (xy 358.030779 -232.554331) (xy 358.022654 -232.605626)
			(xy 358.006606 -232.655019) (xy 357.983028 -232.701293) (xy 357.952502 -232.743309) (xy 357.915779 -232.780032)
			(xy 357.873763 -232.810558) (xy 357.827489 -232.834136) (xy 357.778096 -232.850184) (xy 357.726801 -232.858309)
			(xy 357.674867 -232.858309) (xy 357.623572 -232.850184) (xy 357.574179 -232.834136) (xy 357.527905 -232.810558)
			(xy 357.485889 -232.780032) (xy 357.449166 -232.743309) (xy 357.41864 -232.701293) (xy 357.395062 -232.655019)
			(xy 357.379014 -232.605626) (xy 357.370889 -232.554331) (xy 357.090979 -232.554331) (xy 357.082854 -232.605626)
			(xy 357.066806 -232.655019) (xy 357.043228 -232.701293) (xy 357.012702 -232.743309) (xy 356.975979 -232.780032)
			(xy 356.933963 -232.810558) (xy 356.887689 -232.834136) (xy 356.838296 -232.850184) (xy 356.787001 -232.858309)
			(xy 356.735067 -232.858309) (xy 356.683772 -232.850184) (xy 356.634379 -232.834136) (xy 356.588105 -232.810558)
			(xy 356.546089 -232.780032) (xy 356.509366 -232.743309) (xy 356.47884 -232.701293) (xy 356.455262 -232.655019)
			(xy 356.439214 -232.605626) (xy 356.431089 -232.554331) (xy 356.151179 -232.554331) (xy 356.143054 -232.605626)
			(xy 356.127006 -232.655019) (xy 356.103428 -232.701293) (xy 356.072902 -232.743309) (xy 356.036179 -232.780032)
			(xy 355.994163 -232.810558) (xy 355.947889 -232.834136) (xy 355.898496 -232.850184) (xy 355.847201 -232.858309)
			(xy 355.795267 -232.858309) (xy 355.743972 -232.850184) (xy 355.694579 -232.834136) (xy 355.648305 -232.810558)
			(xy 355.606289 -232.780032) (xy 355.569566 -232.743309) (xy 355.53904 -232.701293) (xy 355.515462 -232.655019)
			(xy 355.499414 -232.605626) (xy 355.491289 -232.554331) (xy 355.211379 -232.554331) (xy 355.203254 -232.605626)
			(xy 355.187206 -232.655019) (xy 355.163628 -232.701293) (xy 355.133102 -232.743309) (xy 355.096379 -232.780032)
			(xy 355.054363 -232.810558) (xy 355.008089 -232.834136) (xy 354.958696 -232.850184) (xy 354.907401 -232.858309)
			(xy 354.855467 -232.858309) (xy 354.804172 -232.850184) (xy 354.754779 -232.834136) (xy 354.708505 -232.810558)
			(xy 354.666489 -232.780032) (xy 354.629766 -232.743309) (xy 354.59924 -232.701293) (xy 354.575662 -232.655019)
			(xy 354.559614 -232.605626) (xy 354.551489 -232.554331) (xy 354.271579 -232.554331) (xy 354.263454 -232.605626)
			(xy 354.247406 -232.655019) (xy 354.223828 -232.701293) (xy 354.193302 -232.743309) (xy 354.156579 -232.780032)
			(xy 354.114563 -232.810558) (xy 354.068289 -232.834136) (xy 354.018896 -232.850184) (xy 353.967601 -232.858309)
			(xy 353.915667 -232.858309) (xy 353.864372 -232.850184) (xy 353.814979 -232.834136) (xy 353.768705 -232.810558)
			(xy 353.726689 -232.780032) (xy 353.689966 -232.743309) (xy 353.65944 -232.701293) (xy 353.635862 -232.655019)
			(xy 353.619814 -232.605626) (xy 353.611689 -232.554331) (xy 353.331779 -232.554331) (xy 353.323654 -232.605626)
			(xy 353.307606 -232.655019) (xy 353.284028 -232.701293) (xy 353.253502 -232.743309) (xy 353.216779 -232.780032)
			(xy 353.174763 -232.810558) (xy 353.128489 -232.834136) (xy 353.079096 -232.850184) (xy 353.027801 -232.858309)
			(xy 352.975867 -232.858309) (xy 352.924572 -232.850184) (xy 352.875179 -232.834136) (xy 352.828905 -232.810558)
			(xy 352.786889 -232.780032) (xy 352.750166 -232.743309) (xy 352.71964 -232.701293) (xy 352.696062 -232.655019)
			(xy 352.680014 -232.605626) (xy 352.671889 -232.554331) (xy 352.391979 -232.554331) (xy 352.383854 -232.605626)
			(xy 352.367806 -232.655019) (xy 352.344228 -232.701293) (xy 352.313702 -232.743309) (xy 352.276979 -232.780032)
			(xy 352.234963 -232.810558) (xy 352.188689 -232.834136) (xy 352.139296 -232.850184) (xy 352.088001 -232.858309)
			(xy 352.036067 -232.858309) (xy 351.984772 -232.850184) (xy 351.935379 -232.834136) (xy 351.889105 -232.810558)
			(xy 351.847089 -232.780032) (xy 351.810366 -232.743309) (xy 351.77984 -232.701293) (xy 351.756262 -232.655019)
			(xy 351.740214 -232.605626) (xy 351.732089 -232.554331) (xy 351.452181 -232.554331) (xy 351.452181 -232.554368)
			(xy 351.444057 -232.605666) (xy 351.428008 -232.655061) (xy 351.404431 -232.701337) (xy 351.373905 -232.743356)
			(xy 351.337182 -232.780083) (xy 351.295166 -232.810613) (xy 351.248892 -232.834195) (xy 351.199499 -232.850249)
			(xy 351.148202 -232.858378) (xy 351.122234 -232.858818) (xy 351.097564 -232.858361) (xy 351.048774 -232.851021)
			(xy 351.001621 -232.836498) (xy 350.957155 -232.815117) (xy 350.916368 -232.787355) (xy 350.897952 -232.770934)
			(xy 350.88679 -232.761263) (xy 350.860307 -232.748221) (xy 350.8312 -232.743298) (xy 350.8019 -232.746905)
			(xy 350.774857 -232.758742) (xy 350.752329 -232.77782) (xy 350.736199 -232.802544) (xy 350.727814 -232.830849)
			(xy 350.727264 -232.84561) (xy 350.727264 -233.01833) (xy 350.7613 -233.030268) (xy 350.785215 -233.039141)
			(xy 350.830198 -233.063192) (xy 350.870951 -233.093868) (xy 350.906507 -233.130442) (xy 350.936021 -233.172044)
			(xy 350.958793 -233.217687) (xy 350.974282 -233.266287) (xy 350.98212 -233.316689) (xy 350.982121 -233.367698)
			(xy 350.982051 -233.368147) (xy 351.261935 -233.368147) (xy 351.261935 -233.316213) (xy 351.27006 -233.264918)
			(xy 351.286108 -233.215525) (xy 351.309686 -233.169251) (xy 351.340212 -233.127235) (xy 351.376935 -233.090512)
			(xy 351.418951 -233.059986) (xy 351.465225 -233.036408) (xy 351.514618 -233.02036) (xy 351.565913 -233.012235)
			(xy 351.617847 -233.012235) (xy 351.669142 -233.02036) (xy 351.718535 -233.036408) (xy 351.764809 -233.059986)
			(xy 351.806825 -233.090512) (xy 351.843548 -233.127235) (xy 351.874074 -233.169251) (xy 351.897652 -233.215525)
			(xy 351.9137 -233.264918) (xy 351.921825 -233.316213) (xy 351.922334 -233.34218) (xy 351.921825 -233.368147)
			(xy 352.201989 -233.368147) (xy 352.201989 -233.316213) (xy 352.210114 -233.264918) (xy 352.226162 -233.215525)
			(xy 352.24974 -233.169251) (xy 352.280266 -233.127235) (xy 352.316989 -233.090512) (xy 352.359005 -233.059986)
			(xy 352.405279 -233.036408) (xy 352.454672 -233.02036) (xy 352.505967 -233.012235) (xy 352.557901 -233.012235)
			(xy 352.609196 -233.02036) (xy 352.658589 -233.036408) (xy 352.704863 -233.059986) (xy 352.746879 -233.090512)
			(xy 352.783602 -233.127235) (xy 352.814128 -233.169251) (xy 352.837706 -233.215525) (xy 352.853754 -233.264918)
			(xy 352.861879 -233.316213) (xy 352.862388 -233.34218) (xy 352.861879 -233.368147) (xy 353.141789 -233.368147)
			(xy 353.141789 -233.316213) (xy 353.149914 -233.264918) (xy 353.165962 -233.215525) (xy 353.18954 -233.169251)
			(xy 353.220066 -233.127235) (xy 353.256789 -233.090512) (xy 353.298805 -233.059986) (xy 353.345079 -233.036408)
			(xy 353.394472 -233.02036) (xy 353.445767 -233.012235) (xy 353.497701 -233.012235) (xy 353.548996 -233.02036)
			(xy 353.598389 -233.036408) (xy 353.644663 -233.059986) (xy 353.686679 -233.090512) (xy 353.723402 -233.127235)
			(xy 353.753928 -233.169251) (xy 353.777506 -233.215525) (xy 353.793554 -233.264918) (xy 353.801679 -233.316213)
			(xy 353.802188 -233.34218) (xy 353.801679 -233.368147) (xy 354.081335 -233.368147) (xy 354.081335 -233.316213)
			(xy 354.08946 -233.264918) (xy 354.105508 -233.215525) (xy 354.129086 -233.169251) (xy 354.159612 -233.127235)
			(xy 354.196335 -233.090512) (xy 354.238351 -233.059986) (xy 354.284625 -233.036408) (xy 354.334018 -233.02036)
			(xy 354.385313 -233.012235) (xy 354.437247 -233.012235) (xy 354.488542 -233.02036) (xy 354.537935 -233.036408)
			(xy 354.584209 -233.059986) (xy 354.626225 -233.090512) (xy 354.662948 -233.127235) (xy 354.693474 -233.169251)
			(xy 354.717052 -233.215525) (xy 354.7331 -233.264918) (xy 354.741225 -233.316213) (xy 354.741734 -233.34218)
			(xy 354.741225 -233.368147) (xy 355.021135 -233.368147) (xy 355.021135 -233.316213) (xy 355.02926 -233.264918)
			(xy 355.045308 -233.215525) (xy 355.068886 -233.169251) (xy 355.099412 -233.127235) (xy 355.136135 -233.090512)
			(xy 355.178151 -233.059986) (xy 355.224425 -233.036408) (xy 355.273818 -233.02036) (xy 355.325113 -233.012235)
			(xy 355.377047 -233.012235) (xy 355.428342 -233.02036) (xy 355.477735 -233.036408) (xy 355.524009 -233.059986)
			(xy 355.566025 -233.090512) (xy 355.602748 -233.127235) (xy 355.633274 -233.169251) (xy 355.656852 -233.215525)
			(xy 355.6729 -233.264918) (xy 355.681025 -233.316213) (xy 355.681534 -233.34218) (xy 355.681025 -233.368147)
			(xy 355.960935 -233.368147) (xy 355.960935 -233.316213) (xy 355.96906 -233.264918) (xy 355.985108 -233.215525)
			(xy 356.008686 -233.169251) (xy 356.039212 -233.127235) (xy 356.075935 -233.090512) (xy 356.117951 -233.059986)
			(xy 356.164225 -233.036408) (xy 356.213618 -233.02036) (xy 356.264913 -233.012235) (xy 356.316847 -233.012235)
			(xy 356.368142 -233.02036) (xy 356.417535 -233.036408) (xy 356.463809 -233.059986) (xy 356.505825 -233.090512)
			(xy 356.542548 -233.127235) (xy 356.573074 -233.169251) (xy 356.596652 -233.215525) (xy 356.6127 -233.264918)
			(xy 356.620825 -233.316213) (xy 356.621334 -233.34218) (xy 356.620825 -233.368147) (xy 356.900735 -233.368147)
			(xy 356.900735 -233.316213) (xy 356.90886 -233.264918) (xy 356.924908 -233.215525) (xy 356.948486 -233.169251)
			(xy 356.979012 -233.127235) (xy 357.015735 -233.090512) (xy 357.057751 -233.059986) (xy 357.104025 -233.036408)
			(xy 357.153418 -233.02036) (xy 357.204713 -233.012235) (xy 357.256647 -233.012235) (xy 357.307942 -233.02036)
			(xy 357.357335 -233.036408) (xy 357.403609 -233.059986) (xy 357.445625 -233.090512) (xy 357.482348 -233.127235)
			(xy 357.512874 -233.169251) (xy 357.536452 -233.215525) (xy 357.5525 -233.264918) (xy 357.560625 -233.316213)
			(xy 357.561134 -233.34218) (xy 357.560625 -233.368147) (xy 357.840789 -233.368147) (xy 357.840789 -233.316213)
			(xy 357.848914 -233.264918) (xy 357.864962 -233.215525) (xy 357.88854 -233.169251) (xy 357.919066 -233.127235)
			(xy 357.955789 -233.090512) (xy 357.997805 -233.059986) (xy 358.044079 -233.036408) (xy 358.093472 -233.02036)
			(xy 358.144767 -233.012235) (xy 358.196701 -233.012235) (xy 358.247996 -233.02036) (xy 358.297389 -233.036408)
			(xy 358.343663 -233.059986) (xy 358.385679 -233.090512) (xy 358.422402 -233.127235) (xy 358.452928 -233.169251)
			(xy 358.476506 -233.215525) (xy 358.492554 -233.264918) (xy 358.500679 -233.316213) (xy 358.501188 -233.34218)
			(xy 358.500679 -233.368147) (xy 358.780335 -233.368147) (xy 358.780335 -233.316213) (xy 358.78846 -233.264918)
			(xy 358.804508 -233.215525) (xy 358.828086 -233.169251) (xy 358.858612 -233.127235) (xy 358.895335 -233.090512)
			(xy 358.937351 -233.059986) (xy 358.983625 -233.036408) (xy 359.033018 -233.02036) (xy 359.084313 -233.012235)
			(xy 359.136247 -233.012235) (xy 359.187542 -233.02036) (xy 359.236935 -233.036408) (xy 359.283209 -233.059986)
			(xy 359.325225 -233.090512) (xy 359.361948 -233.127235) (xy 359.392474 -233.169251) (xy 359.416052 -233.215525)
			(xy 359.4321 -233.264918) (xy 359.440225 -233.316213) (xy 359.440734 -233.34218) (xy 359.440225 -233.368147)
			(xy 359.720135 -233.368147) (xy 359.720135 -233.316213) (xy 359.72826 -233.264918) (xy 359.744308 -233.215525)
			(xy 359.767886 -233.169251) (xy 359.798412 -233.127235) (xy 359.835135 -233.090512) (xy 359.877151 -233.059986)
			(xy 359.923425 -233.036408) (xy 359.972818 -233.02036) (xy 360.024113 -233.012235) (xy 360.076047 -233.012235)
			(xy 360.127342 -233.02036) (xy 360.176735 -233.036408) (xy 360.223009 -233.059986) (xy 360.265025 -233.090512)
			(xy 360.301748 -233.127235) (xy 360.332274 -233.169251) (xy 360.355852 -233.215525) (xy 360.3719 -233.264918)
			(xy 360.380025 -233.316213) (xy 360.380534 -233.34218) (xy 360.380025 -233.368147) (xy 360.659935 -233.368147)
			(xy 360.659935 -233.316213) (xy 360.66806 -233.264918) (xy 360.684108 -233.215525) (xy 360.707686 -233.169251)
			(xy 360.738212 -233.127235) (xy 360.774935 -233.090512) (xy 360.816951 -233.059986) (xy 360.863225 -233.036408)
			(xy 360.912618 -233.02036) (xy 360.963913 -233.012235) (xy 361.015847 -233.012235) (xy 361.067142 -233.02036)
			(xy 361.116535 -233.036408) (xy 361.162809 -233.059986) (xy 361.204825 -233.090512) (xy 361.241548 -233.127235)
			(xy 361.272074 -233.169251) (xy 361.295652 -233.215525) (xy 361.3117 -233.264918) (xy 361.319825 -233.316213)
			(xy 361.320334 -233.34218) (xy 361.319825 -233.368147) (xy 361.3117 -233.419442) (xy 361.295652 -233.468835)
			(xy 361.272074 -233.515109) (xy 361.241548 -233.557125) (xy 361.204825 -233.593848) (xy 361.162809 -233.624374)
			(xy 361.116535 -233.647952) (xy 361.067142 -233.664) (xy 361.015847 -233.672125) (xy 360.963913 -233.672125)
			(xy 360.912618 -233.664) (xy 360.863225 -233.647952) (xy 360.816951 -233.624374) (xy 360.774935 -233.593848)
			(xy 360.738212 -233.557125) (xy 360.707686 -233.515109) (xy 360.684108 -233.468835) (xy 360.66806 -233.419442)
			(xy 360.659935 -233.368147) (xy 360.380025 -233.368147) (xy 360.3719 -233.419442) (xy 360.355852 -233.468835)
			(xy 360.332274 -233.515109) (xy 360.301748 -233.557125) (xy 360.265025 -233.593848) (xy 360.223009 -233.624374)
			(xy 360.176735 -233.647952) (xy 360.127342 -233.664) (xy 360.076047 -233.672125) (xy 360.024113 -233.672125)
			(xy 359.972818 -233.664) (xy 359.923425 -233.647952) (xy 359.877151 -233.624374) (xy 359.835135 -233.593848)
			(xy 359.798412 -233.557125) (xy 359.767886 -233.515109) (xy 359.744308 -233.468835) (xy 359.72826 -233.419442)
			(xy 359.720135 -233.368147) (xy 359.440225 -233.368147) (xy 359.4321 -233.419442) (xy 359.416052 -233.468835)
			(xy 359.392474 -233.515109) (xy 359.361948 -233.557125) (xy 359.325225 -233.593848) (xy 359.283209 -233.624374)
			(xy 359.236935 -233.647952) (xy 359.187542 -233.664) (xy 359.136247 -233.672125) (xy 359.084313 -233.672125)
			(xy 359.033018 -233.664) (xy 358.983625 -233.647952) (xy 358.937351 -233.624374) (xy 358.895335 -233.593848)
			(xy 358.858612 -233.557125) (xy 358.828086 -233.515109) (xy 358.804508 -233.468835) (xy 358.78846 -233.419442)
			(xy 358.780335 -233.368147) (xy 358.500679 -233.368147) (xy 358.492554 -233.419442) (xy 358.476506 -233.468835)
			(xy 358.452928 -233.515109) (xy 358.422402 -233.557125) (xy 358.385679 -233.593848) (xy 358.343663 -233.624374)
			(xy 358.297389 -233.647952) (xy 358.247996 -233.664) (xy 358.196701 -233.672125) (xy 358.144767 -233.672125)
			(xy 358.093472 -233.664) (xy 358.044079 -233.647952) (xy 357.997805 -233.624374) (xy 357.955789 -233.593848)
			(xy 357.919066 -233.557125) (xy 357.88854 -233.515109) (xy 357.864962 -233.468835) (xy 357.848914 -233.419442)
			(xy 357.840789 -233.368147) (xy 357.560625 -233.368147) (xy 357.5525 -233.419442) (xy 357.536452 -233.468835)
			(xy 357.512874 -233.515109) (xy 357.482348 -233.557125) (xy 357.445625 -233.593848) (xy 357.403609 -233.624374)
			(xy 357.357335 -233.647952) (xy 357.307942 -233.664) (xy 357.256647 -233.672125) (xy 357.204713 -233.672125)
			(xy 357.153418 -233.664) (xy 357.104025 -233.647952) (xy 357.057751 -233.624374) (xy 357.015735 -233.593848)
			(xy 356.979012 -233.557125) (xy 356.948486 -233.515109) (xy 356.924908 -233.468835) (xy 356.90886 -233.419442)
			(xy 356.900735 -233.368147) (xy 356.620825 -233.368147) (xy 356.6127 -233.419442) (xy 356.596652 -233.468835)
			(xy 356.573074 -233.515109) (xy 356.542548 -233.557125) (xy 356.505825 -233.593848) (xy 356.463809 -233.624374)
			(xy 356.417535 -233.647952) (xy 356.368142 -233.664) (xy 356.316847 -233.672125) (xy 356.264913 -233.672125)
			(xy 356.213618 -233.664) (xy 356.164225 -233.647952) (xy 356.117951 -233.624374) (xy 356.075935 -233.593848)
			(xy 356.039212 -233.557125) (xy 356.008686 -233.515109) (xy 355.985108 -233.468835) (xy 355.96906 -233.419442)
			(xy 355.960935 -233.368147) (xy 355.681025 -233.368147) (xy 355.6729 -233.419442) (xy 355.656852 -233.468835)
			(xy 355.633274 -233.515109) (xy 355.602748 -233.557125) (xy 355.566025 -233.593848) (xy 355.524009 -233.624374)
			(xy 355.477735 -233.647952) (xy 355.428342 -233.664) (xy 355.377047 -233.672125) (xy 355.325113 -233.672125)
			(xy 355.273818 -233.664) (xy 355.224425 -233.647952) (xy 355.178151 -233.624374) (xy 355.136135 -233.593848)
			(xy 355.099412 -233.557125) (xy 355.068886 -233.515109) (xy 355.045308 -233.468835) (xy 355.02926 -233.419442)
			(xy 355.021135 -233.368147) (xy 354.741225 -233.368147) (xy 354.7331 -233.419442) (xy 354.717052 -233.468835)
			(xy 354.693474 -233.515109) (xy 354.662948 -233.557125) (xy 354.626225 -233.593848) (xy 354.584209 -233.624374)
			(xy 354.537935 -233.647952) (xy 354.488542 -233.664) (xy 354.437247 -233.672125) (xy 354.385313 -233.672125)
			(xy 354.334018 -233.664) (xy 354.284625 -233.647952) (xy 354.238351 -233.624374) (xy 354.196335 -233.593848)
			(xy 354.159612 -233.557125) (xy 354.129086 -233.515109) (xy 354.105508 -233.468835) (xy 354.08946 -233.419442)
			(xy 354.081335 -233.368147) (xy 353.801679 -233.368147) (xy 353.793554 -233.419442) (xy 353.777506 -233.468835)
			(xy 353.753928 -233.515109) (xy 353.723402 -233.557125) (xy 353.686679 -233.593848) (xy 353.644663 -233.624374)
			(xy 353.598389 -233.647952) (xy 353.548996 -233.664) (xy 353.497701 -233.672125) (xy 353.445767 -233.672125)
			(xy 353.394472 -233.664) (xy 353.345079 -233.647952) (xy 353.298805 -233.624374) (xy 353.256789 -233.593848)
			(xy 353.220066 -233.557125) (xy 353.18954 -233.515109) (xy 353.165962 -233.468835) (xy 353.149914 -233.419442)
			(xy 353.141789 -233.368147) (xy 352.861879 -233.368147) (xy 352.853754 -233.419442) (xy 352.837706 -233.468835)
			(xy 352.814128 -233.515109) (xy 352.783602 -233.557125) (xy 352.746879 -233.593848) (xy 352.704863 -233.624374)
			(xy 352.658589 -233.647952) (xy 352.609196 -233.664) (xy 352.557901 -233.672125) (xy 352.505967 -233.672125)
			(xy 352.454672 -233.664) (xy 352.405279 -233.647952) (xy 352.359005 -233.624374) (xy 352.316989 -233.593848)
			(xy 352.280266 -233.557125) (xy 352.24974 -233.515109) (xy 352.226162 -233.468835) (xy 352.210114 -233.419442)
			(xy 352.201989 -233.368147) (xy 351.921825 -233.368147) (xy 351.9137 -233.419442) (xy 351.897652 -233.468835)
			(xy 351.874074 -233.515109) (xy 351.843548 -233.557125) (xy 351.806825 -233.593848) (xy 351.764809 -233.624374)
			(xy 351.718535 -233.647952) (xy 351.669142 -233.664) (xy 351.617847 -233.672125) (xy 351.565913 -233.672125)
			(xy 351.514618 -233.664) (xy 351.465225 -233.647952) (xy 351.418951 -233.624374) (xy 351.376935 -233.593848)
			(xy 351.340212 -233.557125) (xy 351.309686 -233.515109) (xy 351.286108 -233.468835) (xy 351.27006 -233.419442)
			(xy 351.261935 -233.368147) (xy 350.982051 -233.368147) (xy 350.974285 -233.4181) (xy 350.958798 -233.466701)
			(xy 350.936028 -233.512345) (xy 350.906515 -233.553948) (xy 350.870961 -233.590523) (xy 350.830209 -233.621201)
			(xy 350.785228 -233.645253) (xy 350.7613 -233.654092) (xy 350.727264 -233.66603) (xy 350.727264 -233.839004)
			(xy 350.727721 -233.853777) (xy 350.736096 -233.882107) (xy 350.752231 -233.906854) (xy 350.774775 -233.925947)
			(xy 350.801841 -233.937787) (xy 350.831163 -233.941383) (xy 350.860288 -233.936434) (xy 350.886777 -233.923354)
			(xy 350.897952 -233.91368) (xy 350.916368 -233.897261) (xy 350.957161 -233.869509) (xy 351.001627 -233.848133)
			(xy 351.048778 -233.83361) (xy 351.097565 -233.826261) (xy 351.122234 -233.825796) (xy 351.148196 -233.826308)
			(xy 351.199479 -233.834435) (xy 351.248859 -233.850484) (xy 351.295121 -233.87406) (xy 351.337126 -233.904582)
			(xy 351.37384 -233.9413) (xy 351.404358 -233.983308) (xy 351.427929 -234.029572) (xy 351.443973 -234.078954)
			(xy 351.452095 -234.130238) (xy 351.452095 -234.182162) (xy 351.452086 -234.182217) (xy 351.732089 -234.182217)
			(xy 351.732089 -234.130283) (xy 351.740214 -234.078988) (xy 351.756262 -234.029595) (xy 351.77984 -233.983321)
			(xy 351.810366 -233.941305) (xy 351.847089 -233.904582) (xy 351.889105 -233.874056) (xy 351.935379 -233.850478)
			(xy 351.984772 -233.83443) (xy 352.036067 -233.826305) (xy 352.088001 -233.826305) (xy 352.139296 -233.83443)
			(xy 352.188689 -233.850478) (xy 352.234963 -233.874056) (xy 352.276979 -233.904582) (xy 352.313702 -233.941305)
			(xy 352.344228 -233.983321) (xy 352.367806 -234.029595) (xy 352.383854 -234.078988) (xy 352.391979 -234.130283)
			(xy 352.392488 -234.15625) (xy 352.391979 -234.182217) (xy 353.611689 -234.182217) (xy 353.611689 -234.130283)
			(xy 353.619814 -234.078988) (xy 353.635862 -234.029595) (xy 353.65944 -233.983321) (xy 353.689966 -233.941305)
			(xy 353.726689 -233.904582) (xy 353.768705 -233.874056) (xy 353.814979 -233.850478) (xy 353.864372 -233.83443)
			(xy 353.915667 -233.826305) (xy 353.967601 -233.826305) (xy 354.018896 -233.83443) (xy 354.068289 -233.850478)
			(xy 354.114563 -233.874056) (xy 354.156579 -233.904582) (xy 354.193302 -233.941305) (xy 354.223828 -233.983321)
			(xy 354.247406 -234.029595) (xy 354.263454 -234.078988) (xy 354.271579 -234.130283) (xy 354.272088 -234.15625)
			(xy 354.271579 -234.182217) (xy 354.551489 -234.182217) (xy 354.551489 -234.130283) (xy 354.559614 -234.078988)
			(xy 354.575662 -234.029595) (xy 354.59924 -233.983321) (xy 354.629766 -233.941305) (xy 354.666489 -233.904582)
			(xy 354.708505 -233.874056) (xy 354.754779 -233.850478) (xy 354.804172 -233.83443) (xy 354.855467 -233.826305)
			(xy 354.907401 -233.826305) (xy 354.958696 -233.83443) (xy 355.008089 -233.850478) (xy 355.054363 -233.874056)
			(xy 355.096379 -233.904582) (xy 355.133102 -233.941305) (xy 355.163628 -233.983321) (xy 355.187206 -234.029595)
			(xy 355.203254 -234.078988) (xy 355.211379 -234.130283) (xy 355.211888 -234.15625) (xy 355.211379 -234.182217)
			(xy 355.491289 -234.182217) (xy 355.491289 -234.130283) (xy 355.499414 -234.078988) (xy 355.515462 -234.029595)
			(xy 355.53904 -233.983321) (xy 355.569566 -233.941305) (xy 355.606289 -233.904582) (xy 355.648305 -233.874056)
			(xy 355.694579 -233.850478) (xy 355.743972 -233.83443) (xy 355.795267 -233.826305) (xy 355.847201 -233.826305)
			(xy 355.898496 -233.83443) (xy 355.947889 -233.850478) (xy 355.994163 -233.874056) (xy 356.036179 -233.904582)
			(xy 356.072902 -233.941305) (xy 356.103428 -233.983321) (xy 356.127006 -234.029595) (xy 356.143054 -234.078988)
			(xy 356.151179 -234.130283) (xy 356.151688 -234.15625) (xy 356.151179 -234.182217) (xy 356.431089 -234.182217)
			(xy 356.431089 -234.130283) (xy 356.439214 -234.078988) (xy 356.455262 -234.029595) (xy 356.47884 -233.983321)
			(xy 356.509366 -233.941305) (xy 356.546089 -233.904582) (xy 356.588105 -233.874056) (xy 356.634379 -233.850478)
			(xy 356.683772 -233.83443) (xy 356.735067 -233.826305) (xy 356.787001 -233.826305) (xy 356.838296 -233.83443)
			(xy 356.887689 -233.850478) (xy 356.933963 -233.874056) (xy 356.975979 -233.904582) (xy 357.012702 -233.941305)
			(xy 357.043228 -233.983321) (xy 357.066806 -234.029595) (xy 357.082854 -234.078988) (xy 357.090979 -234.130283)
			(xy 357.091488 -234.15625) (xy 357.090979 -234.182217) (xy 357.370889 -234.182217) (xy 357.370889 -234.130283)
			(xy 357.379014 -234.078988) (xy 357.395062 -234.029595) (xy 357.41864 -233.983321) (xy 357.449166 -233.941305)
			(xy 357.485889 -233.904582) (xy 357.527905 -233.874056) (xy 357.574179 -233.850478) (xy 357.623572 -233.83443)
			(xy 357.674867 -233.826305) (xy 357.726801 -233.826305) (xy 357.778096 -233.83443) (xy 357.827489 -233.850478)
			(xy 357.873763 -233.874056) (xy 357.915779 -233.904582) (xy 357.952502 -233.941305) (xy 357.983028 -233.983321)
			(xy 358.006606 -234.029595) (xy 358.022654 -234.078988) (xy 358.030779 -234.130283) (xy 358.031288 -234.15625)
			(xy 358.030779 -234.182217) (xy 358.310689 -234.182217) (xy 358.310689 -234.130283) (xy 358.318814 -234.078988)
			(xy 358.334862 -234.029595) (xy 358.35844 -233.983321) (xy 358.388966 -233.941305) (xy 358.425689 -233.904582)
			(xy 358.467705 -233.874056) (xy 358.513979 -233.850478) (xy 358.563372 -233.83443) (xy 358.614667 -233.826305)
			(xy 358.666601 -233.826305) (xy 358.717896 -233.83443) (xy 358.767289 -233.850478) (xy 358.813563 -233.874056)
			(xy 358.855579 -233.904582) (xy 358.892302 -233.941305) (xy 358.922828 -233.983321) (xy 358.946406 -234.029595)
			(xy 358.962454 -234.078988) (xy 358.970579 -234.130283) (xy 358.971088 -234.15625) (xy 358.970579 -234.182217)
			(xy 359.250489 -234.182217) (xy 359.250489 -234.130283) (xy 359.258614 -234.078988) (xy 359.274662 -234.029595)
			(xy 359.29824 -233.983321) (xy 359.328766 -233.941305) (xy 359.365489 -233.904582) (xy 359.407505 -233.874056)
			(xy 359.453779 -233.850478) (xy 359.503172 -233.83443) (xy 359.554467 -233.826305) (xy 359.606401 -233.826305)
			(xy 359.657696 -233.83443) (xy 359.707089 -233.850478) (xy 359.753363 -233.874056) (xy 359.795379 -233.904582)
			(xy 359.832102 -233.941305) (xy 359.862628 -233.983321) (xy 359.886206 -234.029595) (xy 359.902254 -234.078988)
			(xy 359.910379 -234.130283) (xy 359.910888 -234.15625) (xy 359.910379 -234.182217) (xy 360.190289 -234.182217)
			(xy 360.190289 -234.130283) (xy 360.198414 -234.078988) (xy 360.214462 -234.029595) (xy 360.23804 -233.983321)
			(xy 360.268566 -233.941305) (xy 360.305289 -233.904582) (xy 360.347305 -233.874056) (xy 360.393579 -233.850478)
			(xy 360.442972 -233.83443) (xy 360.494267 -233.826305) (xy 360.546201 -233.826305) (xy 360.597496 -233.83443)
			(xy 360.646889 -233.850478) (xy 360.693163 -233.874056) (xy 360.735179 -233.904582) (xy 360.771902 -233.941305)
			(xy 360.802428 -233.983321) (xy 360.826006 -234.029595) (xy 360.842054 -234.078988) (xy 360.850179 -234.130283)
			(xy 360.850688 -234.15625) (xy 360.850179 -234.182217) (xy 361.130089 -234.182217) (xy 361.130089 -234.130283)
			(xy 361.138214 -234.078988) (xy 361.154262 -234.029595) (xy 361.17784 -233.983321) (xy 361.208366 -233.941305)
			(xy 361.245089 -233.904582) (xy 361.287105 -233.874056) (xy 361.333379 -233.850478) (xy 361.382772 -233.83443)
			(xy 361.434067 -233.826305) (xy 361.486001 -233.826305) (xy 361.537296 -233.83443) (xy 361.586689 -233.850478)
			(xy 361.632963 -233.874056) (xy 361.674979 -233.904582) (xy 361.711702 -233.941305) (xy 361.742228 -233.983321)
			(xy 361.765806 -234.029595) (xy 361.781854 -234.078988) (xy 361.789979 -234.130283) (xy 361.790488 -234.15625)
			(xy 361.789979 -234.182217) (xy 361.781854 -234.233512) (xy 361.765806 -234.282905) (xy 361.742228 -234.329179)
			(xy 361.711702 -234.371195) (xy 361.674979 -234.407918) (xy 361.632963 -234.438444) (xy 361.586689 -234.462022)
			(xy 361.537296 -234.47807) (xy 361.486001 -234.486195) (xy 361.434067 -234.486195) (xy 361.382772 -234.47807)
			(xy 361.333379 -234.462022) (xy 361.287105 -234.438444) (xy 361.245089 -234.407918) (xy 361.208366 -234.371195)
			(xy 361.17784 -234.329179) (xy 361.154262 -234.282905) (xy 361.138214 -234.233512) (xy 361.130089 -234.182217)
			(xy 360.850179 -234.182217) (xy 360.842054 -234.233512) (xy 360.826006 -234.282905) (xy 360.802428 -234.329179)
			(xy 360.771902 -234.371195) (xy 360.735179 -234.407918) (xy 360.693163 -234.438444) (xy 360.646889 -234.462022)
			(xy 360.597496 -234.47807) (xy 360.546201 -234.486195) (xy 360.494267 -234.486195) (xy 360.442972 -234.47807)
			(xy 360.393579 -234.462022) (xy 360.347305 -234.438444) (xy 360.305289 -234.407918) (xy 360.268566 -234.371195)
			(xy 360.23804 -234.329179) (xy 360.214462 -234.282905) (xy 360.198414 -234.233512) (xy 360.190289 -234.182217)
			(xy 359.910379 -234.182217) (xy 359.902254 -234.233512) (xy 359.886206 -234.282905) (xy 359.862628 -234.329179)
			(xy 359.832102 -234.371195) (xy 359.795379 -234.407918) (xy 359.753363 -234.438444) (xy 359.707089 -234.462022)
			(xy 359.657696 -234.47807) (xy 359.606401 -234.486195) (xy 359.554467 -234.486195) (xy 359.503172 -234.47807)
			(xy 359.453779 -234.462022) (xy 359.407505 -234.438444) (xy 359.365489 -234.407918) (xy 359.328766 -234.371195)
			(xy 359.29824 -234.329179) (xy 359.274662 -234.282905) (xy 359.258614 -234.233512) (xy 359.250489 -234.182217)
			(xy 358.970579 -234.182217) (xy 358.962454 -234.233512) (xy 358.946406 -234.282905) (xy 358.922828 -234.329179)
			(xy 358.892302 -234.371195) (xy 358.855579 -234.407918) (xy 358.813563 -234.438444) (xy 358.767289 -234.462022)
			(xy 358.717896 -234.47807) (xy 358.666601 -234.486195) (xy 358.614667 -234.486195) (xy 358.563372 -234.47807)
			(xy 358.513979 -234.462022) (xy 358.467705 -234.438444) (xy 358.425689 -234.407918) (xy 358.388966 -234.371195)
			(xy 358.35844 -234.329179) (xy 358.334862 -234.282905) (xy 358.318814 -234.233512) (xy 358.310689 -234.182217)
			(xy 358.030779 -234.182217) (xy 358.022654 -234.233512) (xy 358.006606 -234.282905) (xy 357.983028 -234.329179)
			(xy 357.952502 -234.371195) (xy 357.915779 -234.407918) (xy 357.873763 -234.438444) (xy 357.827489 -234.462022)
			(xy 357.778096 -234.47807) (xy 357.726801 -234.486195) (xy 357.674867 -234.486195) (xy 357.623572 -234.47807)
			(xy 357.574179 -234.462022) (xy 357.527905 -234.438444) (xy 357.485889 -234.407918) (xy 357.449166 -234.371195)
			(xy 357.41864 -234.329179) (xy 357.395062 -234.282905) (xy 357.379014 -234.233512) (xy 357.370889 -234.182217)
			(xy 357.090979 -234.182217) (xy 357.082854 -234.233512) (xy 357.066806 -234.282905) (xy 357.043228 -234.329179)
			(xy 357.012702 -234.371195) (xy 356.975979 -234.407918) (xy 356.933963 -234.438444) (xy 356.887689 -234.462022)
			(xy 356.838296 -234.47807) (xy 356.787001 -234.486195) (xy 356.735067 -234.486195) (xy 356.683772 -234.47807)
			(xy 356.634379 -234.462022) (xy 356.588105 -234.438444) (xy 356.546089 -234.407918) (xy 356.509366 -234.371195)
			(xy 356.47884 -234.329179) (xy 356.455262 -234.282905) (xy 356.439214 -234.233512) (xy 356.431089 -234.182217)
			(xy 356.151179 -234.182217) (xy 356.143054 -234.233512) (xy 356.127006 -234.282905) (xy 356.103428 -234.329179)
			(xy 356.072902 -234.371195) (xy 356.036179 -234.407918) (xy 355.994163 -234.438444) (xy 355.947889 -234.462022)
			(xy 355.898496 -234.47807) (xy 355.847201 -234.486195) (xy 355.795267 -234.486195) (xy 355.743972 -234.47807)
			(xy 355.694579 -234.462022) (xy 355.648305 -234.438444) (xy 355.606289 -234.407918) (xy 355.569566 -234.371195)
			(xy 355.53904 -234.329179) (xy 355.515462 -234.282905) (xy 355.499414 -234.233512) (xy 355.491289 -234.182217)
			(xy 355.211379 -234.182217) (xy 355.203254 -234.233512) (xy 355.187206 -234.282905) (xy 355.163628 -234.329179)
			(xy 355.133102 -234.371195) (xy 355.096379 -234.407918) (xy 355.054363 -234.438444) (xy 355.008089 -234.462022)
			(xy 354.958696 -234.47807) (xy 354.907401 -234.486195) (xy 354.855467 -234.486195) (xy 354.804172 -234.47807)
			(xy 354.754779 -234.462022) (xy 354.708505 -234.438444) (xy 354.666489 -234.407918) (xy 354.629766 -234.371195)
			(xy 354.59924 -234.329179) (xy 354.575662 -234.282905) (xy 354.559614 -234.233512) (xy 354.551489 -234.182217)
			(xy 354.271579 -234.182217) (xy 354.263454 -234.233512) (xy 354.247406 -234.282905) (xy 354.223828 -234.329179)
			(xy 354.193302 -234.371195) (xy 354.156579 -234.407918) (xy 354.114563 -234.438444) (xy 354.068289 -234.462022)
			(xy 354.018896 -234.47807) (xy 353.967601 -234.486195) (xy 353.915667 -234.486195) (xy 353.864372 -234.47807)
			(xy 353.814979 -234.462022) (xy 353.768705 -234.438444) (xy 353.726689 -234.407918) (xy 353.689966 -234.371195)
			(xy 353.65944 -234.329179) (xy 353.635862 -234.282905) (xy 353.619814 -234.233512) (xy 353.611689 -234.182217)
			(xy 352.391979 -234.182217) (xy 352.383854 -234.233512) (xy 352.367806 -234.282905) (xy 352.344228 -234.329179)
			(xy 352.313702 -234.371195) (xy 352.276979 -234.407918) (xy 352.234963 -234.438444) (xy 352.188689 -234.462022)
			(xy 352.139296 -234.47807) (xy 352.088001 -234.486195) (xy 352.036067 -234.486195) (xy 351.984772 -234.47807)
			(xy 351.935379 -234.462022) (xy 351.889105 -234.438444) (xy 351.847089 -234.407918) (xy 351.810366 -234.371195)
			(xy 351.77984 -234.329179) (xy 351.756262 -234.282905) (xy 351.740214 -234.233512) (xy 351.732089 -234.182217)
			(xy 351.452086 -234.182217) (xy 351.443973 -234.233446) (xy 351.427929 -234.282828) (xy 351.404358 -234.329092)
			(xy 351.37384 -234.3711) (xy 351.337126 -234.407818) (xy 351.295121 -234.43834) (xy 351.248859 -234.461916)
			(xy 351.199479 -234.477965) (xy 351.148196 -234.486092) (xy 351.122234 -234.486704) (xy 351.097564 -234.486248)
			(xy 351.048772 -234.478909) (xy 351.001617 -234.464389) (xy 350.957148 -234.443013) (xy 350.916356 -234.415255)
			(xy 350.897952 -234.39882) (xy 350.886789 -234.38915) (xy 350.860305 -234.376109) (xy 350.831198 -234.371187)
			(xy 350.801898 -234.374795) (xy 350.774855 -234.386632) (xy 350.752326 -234.405708) (xy 350.736193 -234.430431)
			(xy 350.727805 -234.458735) (xy 350.727264 -234.473496) (xy 350.727264 -235.031593) (xy 353.123755 -235.031593)
			(xy 353.123755 -234.979659) (xy 353.13188 -234.928364) (xy 353.147928 -234.878971) (xy 353.171506 -234.832697)
			(xy 353.202032 -234.790681) (xy 353.238755 -234.753958) (xy 353.280771 -234.723432) (xy 353.327045 -234.699854)
			(xy 353.376438 -234.683806) (xy 353.427733 -234.675681) (xy 353.479667 -234.675681) (xy 353.530962 -234.683806)
			(xy 353.580355 -234.699854) (xy 353.626629 -234.723432) (xy 353.668645 -234.753958) (xy 353.705368 -234.790681)
			(xy 353.735894 -234.832697) (xy 353.759472 -234.878971) (xy 353.77552 -234.928364) (xy 353.783645 -234.979659)
			(xy 353.784154 -235.005626) (xy 353.783645 -235.031593) (xy 353.77552 -235.082888) (xy 353.759472 -235.132281)
			(xy 353.735894 -235.178555) (xy 353.705368 -235.220571) (xy 353.668645 -235.257294) (xy 353.626629 -235.28782)
			(xy 353.608069 -235.297277) (xy 354.047553 -235.297277) (xy 354.047553 -235.245343) (xy 354.055678 -235.194048)
			(xy 354.071726 -235.144655) (xy 354.095304 -235.098381) (xy 354.12583 -235.056365) (xy 354.162553 -235.019642)
			(xy 354.204569 -234.989116) (xy 354.250843 -234.965538) (xy 354.300236 -234.94949) (xy 354.351531 -234.941365)
			(xy 354.403465 -234.941365) (xy 354.45476 -234.94949) (xy 354.504153 -234.965538) (xy 354.550427 -234.989116)
			(xy 354.559948 -234.996033) (xy 356.900735 -234.996033) (xy 356.900735 -234.944099) (xy 356.90886 -234.892804)
			(xy 356.924908 -234.843411) (xy 356.948486 -234.797137) (xy 356.979012 -234.755121) (xy 357.015735 -234.718398)
			(xy 357.057751 -234.687872) (xy 357.104025 -234.664294) (xy 357.153418 -234.648246) (xy 357.204713 -234.640121)
			(xy 357.256647 -234.640121) (xy 357.307942 -234.648246) (xy 357.357335 -234.664294) (xy 357.403609 -234.687872)
			(xy 357.445625 -234.718398) (xy 357.482348 -234.755121) (xy 357.512874 -234.797137) (xy 357.536452 -234.843411)
			(xy 357.5525 -234.892804) (xy 357.560625 -234.944099) (xy 357.561134 -234.970066) (xy 357.560625 -234.996033)
			(xy 357.840789 -234.996033) (xy 357.840789 -234.944099) (xy 357.848914 -234.892804) (xy 357.864962 -234.843411)
			(xy 357.88854 -234.797137) (xy 357.919066 -234.755121) (xy 357.955789 -234.718398) (xy 357.997805 -234.687872)
			(xy 358.044079 -234.664294) (xy 358.093472 -234.648246) (xy 358.144767 -234.640121) (xy 358.196701 -234.640121)
			(xy 358.247996 -234.648246) (xy 358.297389 -234.664294) (xy 358.343663 -234.687872) (xy 358.385679 -234.718398)
			(xy 358.422402 -234.755121) (xy 358.452928 -234.797137) (xy 358.476506 -234.843411) (xy 358.492554 -234.892804)
			(xy 358.500679 -234.944099) (xy 358.501188 -234.970066) (xy 358.500679 -234.996033) (xy 358.780335 -234.996033)
			(xy 358.780335 -234.944099) (xy 358.78846 -234.892804) (xy 358.804508 -234.843411) (xy 358.828086 -234.797137)
			(xy 358.858612 -234.755121) (xy 358.895335 -234.718398) (xy 358.937351 -234.687872) (xy 358.983625 -234.664294)
			(xy 359.033018 -234.648246) (xy 359.084313 -234.640121) (xy 359.136247 -234.640121) (xy 359.187542 -234.648246)
			(xy 359.236935 -234.664294) (xy 359.283209 -234.687872) (xy 359.325225 -234.718398) (xy 359.361948 -234.755121)
			(xy 359.392474 -234.797137) (xy 359.416052 -234.843411) (xy 359.4321 -234.892804) (xy 359.440225 -234.944099)
			(xy 359.440734 -234.970066) (xy 359.440225 -234.996033) (xy 359.720135 -234.996033) (xy 359.720135 -234.944099)
			(xy 359.72826 -234.892804) (xy 359.744308 -234.843411) (xy 359.767886 -234.797137) (xy 359.798412 -234.755121)
			(xy 359.835135 -234.718398) (xy 359.877151 -234.687872) (xy 359.923425 -234.664294) (xy 359.972818 -234.648246)
			(xy 360.024113 -234.640121) (xy 360.076047 -234.640121) (xy 360.127342 -234.648246) (xy 360.176735 -234.664294)
			(xy 360.223009 -234.687872) (xy 360.265025 -234.718398) (xy 360.301748 -234.755121) (xy 360.332274 -234.797137)
			(xy 360.355852 -234.843411) (xy 360.3719 -234.892804) (xy 360.380025 -234.944099) (xy 360.380534 -234.970066)
			(xy 360.380025 -234.996033) (xy 360.659935 -234.996033) (xy 360.659935 -234.944099) (xy 360.66806 -234.892804)
			(xy 360.684108 -234.843411) (xy 360.707686 -234.797137) (xy 360.738212 -234.755121) (xy 360.774935 -234.718398)
			(xy 360.816951 -234.687872) (xy 360.863225 -234.664294) (xy 360.912618 -234.648246) (xy 360.963913 -234.640121)
			(xy 361.015847 -234.640121) (xy 361.067142 -234.648246) (xy 361.116535 -234.664294) (xy 361.162809 -234.687872)
			(xy 361.204825 -234.718398) (xy 361.241548 -234.755121) (xy 361.272074 -234.797137) (xy 361.295652 -234.843411)
			(xy 361.3117 -234.892804) (xy 361.319825 -234.944099) (xy 361.320334 -234.970066) (xy 361.319825 -234.996033)
			(xy 361.3117 -235.047328) (xy 361.295652 -235.096721) (xy 361.272074 -235.142995) (xy 361.241548 -235.185011)
			(xy 361.204825 -235.221734) (xy 361.162809 -235.25226) (xy 361.116535 -235.275838) (xy 361.067142 -235.291886)
			(xy 361.015847 -235.300011) (xy 360.963913 -235.300011) (xy 360.912618 -235.291886) (xy 360.863225 -235.275838)
			(xy 360.816951 -235.25226) (xy 360.774935 -235.221734) (xy 360.738212 -235.185011) (xy 360.707686 -235.142995)
			(xy 360.684108 -235.096721) (xy 360.66806 -235.047328) (xy 360.659935 -234.996033) (xy 360.380025 -234.996033)
			(xy 360.3719 -235.047328) (xy 360.355852 -235.096721) (xy 360.332274 -235.142995) (xy 360.301748 -235.185011)
			(xy 360.265025 -235.221734) (xy 360.223009 -235.25226) (xy 360.176735 -235.275838) (xy 360.127342 -235.291886)
			(xy 360.076047 -235.300011) (xy 360.024113 -235.300011) (xy 359.972818 -235.291886) (xy 359.923425 -235.275838)
			(xy 359.877151 -235.25226) (xy 359.835135 -235.221734) (xy 359.798412 -235.185011) (xy 359.767886 -235.142995)
			(xy 359.744308 -235.096721) (xy 359.72826 -235.047328) (xy 359.720135 -234.996033) (xy 359.440225 -234.996033)
			(xy 359.4321 -235.047328) (xy 359.416052 -235.096721) (xy 359.392474 -235.142995) (xy 359.361948 -235.185011)
			(xy 359.325225 -235.221734) (xy 359.283209 -235.25226) (xy 359.236935 -235.275838) (xy 359.187542 -235.291886)
			(xy 359.136247 -235.300011) (xy 359.084313 -235.300011) (xy 359.033018 -235.291886) (xy 358.983625 -235.275838)
			(xy 358.937351 -235.25226) (xy 358.895335 -235.221734) (xy 358.858612 -235.185011) (xy 358.828086 -235.142995)
			(xy 358.804508 -235.096721) (xy 358.78846 -235.047328) (xy 358.780335 -234.996033) (xy 358.500679 -234.996033)
			(xy 358.492554 -235.047328) (xy 358.476506 -235.096721) (xy 358.452928 -235.142995) (xy 358.422402 -235.185011)
			(xy 358.385679 -235.221734) (xy 358.343663 -235.25226) (xy 358.297389 -235.275838) (xy 358.247996 -235.291886)
			(xy 358.196701 -235.300011) (xy 358.144767 -235.300011) (xy 358.093472 -235.291886) (xy 358.044079 -235.275838)
			(xy 357.997805 -235.25226) (xy 357.955789 -235.221734) (xy 357.919066 -235.185011) (xy 357.88854 -235.142995)
			(xy 357.864962 -235.096721) (xy 357.848914 -235.047328) (xy 357.840789 -234.996033) (xy 357.560625 -234.996033)
			(xy 357.5525 -235.047328) (xy 357.536452 -235.096721) (xy 357.512874 -235.142995) (xy 357.482348 -235.185011)
			(xy 357.445625 -235.221734) (xy 357.403609 -235.25226) (xy 357.357335 -235.275838) (xy 357.307942 -235.291886)
			(xy 357.256647 -235.300011) (xy 357.204713 -235.300011) (xy 357.153418 -235.291886) (xy 357.104025 -235.275838)
			(xy 357.057751 -235.25226) (xy 357.015735 -235.221734) (xy 356.979012 -235.185011) (xy 356.948486 -235.142995)
			(xy 356.924908 -235.096721) (xy 356.90886 -235.047328) (xy 356.900735 -234.996033) (xy 354.559948 -234.996033)
			(xy 354.592443 -235.019642) (xy 354.629166 -235.056365) (xy 354.659692 -235.098381) (xy 354.68327 -235.144655)
			(xy 354.699318 -235.194048) (xy 354.707443 -235.245343) (xy 354.707952 -235.27131) (xy 354.707443 -235.297277)
			(xy 354.699318 -235.348572) (xy 354.68327 -235.397965) (xy 354.659692 -235.444239) (xy 354.629166 -235.486255)
			(xy 354.592443 -235.522978) (xy 354.550427 -235.553504) (xy 354.504153 -235.577082) (xy 354.45476 -235.59313)
			(xy 354.403465 -235.601255) (xy 354.351531 -235.601255) (xy 354.300236 -235.59313) (xy 354.250843 -235.577082)
			(xy 354.204569 -235.553504) (xy 354.162553 -235.522978) (xy 354.12583 -235.486255) (xy 354.095304 -235.444239)
			(xy 354.071726 -235.397965) (xy 354.055678 -235.348572) (xy 354.047553 -235.297277) (xy 353.608069 -235.297277)
			(xy 353.580355 -235.311398) (xy 353.530962 -235.327446) (xy 353.479667 -235.335571) (xy 353.427733 -235.335571)
			(xy 353.376438 -235.327446) (xy 353.327045 -235.311398) (xy 353.280771 -235.28782) (xy 353.238755 -235.257294)
			(xy 353.202032 -235.220571) (xy 353.171506 -235.178555) (xy 353.147928 -235.132281) (xy 353.13188 -235.082888)
			(xy 353.123755 -235.031593) (xy 350.727264 -235.031593) (xy 350.727264 -235.734363) (xy 350.903599 -235.734363)
			(xy 350.903599 -235.682437) (xy 350.911722 -235.63115) (xy 350.927768 -235.581765) (xy 350.951341 -235.535498)
			(xy 350.981862 -235.493489) (xy 351.018578 -235.456771) (xy 351.060586 -235.426248) (xy 351.106852 -235.402673)
			(xy 351.156236 -235.386625) (xy 351.207523 -235.3785) (xy 351.233486 -235.37799) (xy 351.25987 -235.378481)
			(xy 351.31197 -235.386852) (xy 351.362076 -235.403399) (xy 351.408915 -235.427701) (xy 351.451294 -235.459141)
			(xy 351.488136 -235.496918) (xy 351.503742 -235.518198) (xy 351.51301 -235.53023) (xy 351.537054 -235.54875)
			(xy 351.565472 -235.559406) (xy 351.595766 -235.561259) (xy 351.625272 -235.554147) (xy 351.638616 -235.5469)
			(xy 351.664386 -235.532291) (xy 351.719869 -235.511551) (xy 351.778163 -235.501047) (xy 351.80778 -235.500418)
			(xy 351.833748 -235.500955) (xy 351.885045 -235.509077) (xy 351.93444 -235.525124) (xy 351.980717 -235.5487)
			(xy 352.022735 -235.579226) (xy 352.059461 -235.61595) (xy 352.089989 -235.657966) (xy 352.113568 -235.704241)
			(xy 352.129618 -235.753635) (xy 352.137743 -235.804932) (xy 352.137743 -235.809849) (xy 357.370889 -235.809849)
			(xy 357.370889 -235.757915) (xy 357.379014 -235.70662) (xy 357.395062 -235.657227) (xy 357.41864 -235.610953)
			(xy 357.449166 -235.568937) (xy 357.485889 -235.532214) (xy 357.527905 -235.501688) (xy 357.574179 -235.47811)
			(xy 357.623572 -235.462062) (xy 357.674867 -235.453937) (xy 357.726801 -235.453937) (xy 357.778096 -235.462062)
			(xy 357.827489 -235.47811) (xy 357.873763 -235.501688) (xy 357.915779 -235.532214) (xy 357.952502 -235.568937)
			(xy 357.983028 -235.610953) (xy 358.006606 -235.657227) (xy 358.022654 -235.70662) (xy 358.030779 -235.757915)
			(xy 358.031288 -235.783882) (xy 358.030779 -235.809849) (xy 358.310689 -235.809849) (xy 358.310689 -235.757915)
			(xy 358.318814 -235.70662) (xy 358.334862 -235.657227) (xy 358.35844 -235.610953) (xy 358.388966 -235.568937)
			(xy 358.425689 -235.532214) (xy 358.467705 -235.501688) (xy 358.513979 -235.47811) (xy 358.563372 -235.462062)
			(xy 358.614667 -235.453937) (xy 358.666601 -235.453937) (xy 358.717896 -235.462062) (xy 358.767289 -235.47811)
			(xy 358.813563 -235.501688) (xy 358.855579 -235.532214) (xy 358.892302 -235.568937) (xy 358.922828 -235.610953)
			(xy 358.946406 -235.657227) (xy 358.962454 -235.70662) (xy 358.970579 -235.757915) (xy 358.971088 -235.783882)
			(xy 358.970579 -235.809849) (xy 359.250489 -235.809849) (xy 359.250489 -235.757915) (xy 359.258614 -235.70662)
			(xy 359.274662 -235.657227) (xy 359.29824 -235.610953) (xy 359.328766 -235.568937) (xy 359.365489 -235.532214)
			(xy 359.407505 -235.501688) (xy 359.453779 -235.47811) (xy 359.503172 -235.462062) (xy 359.554467 -235.453937)
			(xy 359.606401 -235.453937) (xy 359.657696 -235.462062) (xy 359.707089 -235.47811) (xy 359.753363 -235.501688)
			(xy 359.795379 -235.532214) (xy 359.832102 -235.568937) (xy 359.862628 -235.610953) (xy 359.886206 -235.657227)
			(xy 359.902254 -235.70662) (xy 359.910379 -235.757915) (xy 359.910888 -235.783882) (xy 359.910379 -235.809849)
			(xy 360.190289 -235.809849) (xy 360.190289 -235.757915) (xy 360.198414 -235.70662) (xy 360.214462 -235.657227)
			(xy 360.23804 -235.610953) (xy 360.268566 -235.568937) (xy 360.305289 -235.532214) (xy 360.347305 -235.501688)
			(xy 360.393579 -235.47811) (xy 360.442972 -235.462062) (xy 360.494267 -235.453937) (xy 360.546201 -235.453937)
			(xy 360.597496 -235.462062) (xy 360.646889 -235.47811) (xy 360.693163 -235.501688) (xy 360.735179 -235.532214)
			(xy 360.771902 -235.568937) (xy 360.802428 -235.610953) (xy 360.826006 -235.657227) (xy 360.842054 -235.70662)
			(xy 360.850179 -235.757915) (xy 360.850688 -235.783882) (xy 360.850179 -235.809849) (xy 361.130089 -235.809849)
			(xy 361.130089 -235.757915) (xy 361.138214 -235.70662) (xy 361.154262 -235.657227) (xy 361.17784 -235.610953)
			(xy 361.208366 -235.568937) (xy 361.245089 -235.532214) (xy 361.287105 -235.501688) (xy 361.333379 -235.47811)
			(xy 361.382772 -235.462062) (xy 361.434067 -235.453937) (xy 361.486001 -235.453937) (xy 361.537296 -235.462062)
			(xy 361.586689 -235.47811) (xy 361.632963 -235.501688) (xy 361.674979 -235.532214) (xy 361.711702 -235.568937)
			(xy 361.742228 -235.610953) (xy 361.765806 -235.657227) (xy 361.781854 -235.70662) (xy 361.789979 -235.757915)
			(xy 361.790488 -235.783882) (xy 361.789979 -235.809849) (xy 361.781854 -235.861144) (xy 361.765806 -235.910537)
			(xy 361.742228 -235.956811) (xy 361.711702 -235.998827) (xy 361.674979 -236.03555) (xy 361.632963 -236.066076)
			(xy 361.586689 -236.089654) (xy 361.537296 -236.105702) (xy 361.486001 -236.113827) (xy 361.434067 -236.113827)
			(xy 361.382772 -236.105702) (xy 361.333379 -236.089654) (xy 361.287105 -236.066076) (xy 361.245089 -236.03555)
			(xy 361.208366 -235.998827) (xy 361.17784 -235.956811) (xy 361.154262 -235.910537) (xy 361.138214 -235.861144)
			(xy 361.130089 -235.809849) (xy 360.850179 -235.809849) (xy 360.842054 -235.861144) (xy 360.826006 -235.910537)
			(xy 360.802428 -235.956811) (xy 360.771902 -235.998827) (xy 360.735179 -236.03555) (xy 360.693163 -236.066076)
			(xy 360.646889 -236.089654) (xy 360.597496 -236.105702) (xy 360.546201 -236.113827) (xy 360.494267 -236.113827)
			(xy 360.442972 -236.105702) (xy 360.393579 -236.089654) (xy 360.347305 -236.066076) (xy 360.305289 -236.03555)
			(xy 360.268566 -235.998827) (xy 360.23804 -235.956811) (xy 360.214462 -235.910537) (xy 360.198414 -235.861144)
			(xy 360.190289 -235.809849) (xy 359.910379 -235.809849) (xy 359.902254 -235.861144) (xy 359.886206 -235.910537)
			(xy 359.862628 -235.956811) (xy 359.832102 -235.998827) (xy 359.795379 -236.03555) (xy 359.753363 -236.066076)
			(xy 359.707089 -236.089654) (xy 359.657696 -236.105702) (xy 359.606401 -236.113827) (xy 359.554467 -236.113827)
			(xy 359.503172 -236.105702) (xy 359.453779 -236.089654) (xy 359.407505 -236.066076) (xy 359.365489 -236.03555)
			(xy 359.328766 -235.998827) (xy 359.29824 -235.956811) (xy 359.274662 -235.910537) (xy 359.258614 -235.861144)
			(xy 359.250489 -235.809849) (xy 358.970579 -235.809849) (xy 358.962454 -235.861144) (xy 358.946406 -235.910537)
			(xy 358.922828 -235.956811) (xy 358.892302 -235.998827) (xy 358.855579 -236.03555) (xy 358.813563 -236.066076)
			(xy 358.767289 -236.089654) (xy 358.717896 -236.105702) (xy 358.666601 -236.113827) (xy 358.614667 -236.113827)
			(xy 358.563372 -236.105702) (xy 358.513979 -236.089654) (xy 358.467705 -236.066076) (xy 358.425689 -236.03555)
			(xy 358.388966 -235.998827) (xy 358.35844 -235.956811) (xy 358.334862 -235.910537) (xy 358.318814 -235.861144)
			(xy 358.310689 -235.809849) (xy 358.030779 -235.809849) (xy 358.022654 -235.861144) (xy 358.006606 -235.910537)
			(xy 357.983028 -235.956811) (xy 357.952502 -235.998827) (xy 357.915779 -236.03555) (xy 357.873763 -236.066076)
			(xy 357.827489 -236.089654) (xy 357.778096 -236.105702) (xy 357.726801 -236.113827) (xy 357.674867 -236.113827)
			(xy 357.623572 -236.105702) (xy 357.574179 -236.089654) (xy 357.527905 -236.066076) (xy 357.485889 -236.03555)
			(xy 357.449166 -235.998827) (xy 357.41864 -235.956811) (xy 357.395062 -235.910537) (xy 357.379014 -235.861144)
			(xy 357.370889 -235.809849) (xy 352.137743 -235.809849) (xy 352.137743 -235.856868) (xy 352.129618 -235.908165)
			(xy 352.113568 -235.957559) (xy 352.089989 -236.003834) (xy 352.059461 -236.04585) (xy 352.022735 -236.082574)
			(xy 351.980717 -236.1131) (xy 351.93444 -236.136676) (xy 351.885045 -236.152723) (xy 351.833748 -236.160845)
			(xy 351.80778 -236.161326) (xy 351.781398 -236.160779) (xy 351.729301 -236.152419) (xy 351.679197 -236.135883)
			(xy 351.632358 -236.111591) (xy 351.589977 -236.080161) (xy 351.553132 -236.042393) (xy 351.537524 -236.021118)
			(xy 351.528286 -236.009061) (xy 351.504234 -235.990539) (xy 351.475807 -235.979886) (xy 351.445505 -235.97804)
			(xy 351.415995 -235.985163) (xy 351.40265 -235.992416) (xy 351.376862 -236.006993) (xy 351.321389 -236.027746)
			(xy 351.263101 -236.038263) (xy 351.233486 -236.038898) (xy 351.207523 -236.0383) (xy 351.156236 -236.030175)
			(xy 351.106852 -236.014127) (xy 351.060586 -235.990552) (xy 351.018578 -235.960029) (xy 350.981862 -235.923311)
			(xy 350.951341 -235.881302) (xy 350.927768 -235.835035) (xy 350.911722 -235.78565) (xy 350.903599 -235.734363)
			(xy 350.727264 -235.734363) (xy 350.727264 -235.99394) (xy 350.727687 -236.00713) (xy 350.734458 -236.032628)
			(xy 350.747537 -236.055539) (xy 350.766052 -236.074332) (xy 350.788764 -236.087753) (xy 350.814158 -236.094904)
			(xy 350.82734 -236.09554) (xy 350.85303 -236.096444) (xy 350.903677 -236.105224) (xy 350.952354 -236.121742)
			(xy 350.997885 -236.145599) (xy 351.039172 -236.176219) (xy 351.075219 -236.212864) (xy 351.105156 -236.254649)
			(xy 351.128261 -236.300566) (xy 351.143976 -236.349508) (xy 351.151922 -236.400293) (xy 351.15246 -236.425994)
			(xy 351.15202 -236.450138) (xy 351.144991 -236.497912) (xy 351.131082 -236.544153) (xy 351.110589 -236.587877)
			(xy 351.086748 -236.623919) (xy 356.900735 -236.623919) (xy 356.900735 -236.571985) (xy 356.90886 -236.52069)
			(xy 356.924908 -236.471297) (xy 356.948486 -236.425023) (xy 356.979012 -236.383007) (xy 357.015735 -236.346284)
			(xy 357.057751 -236.315758) (xy 357.104025 -236.29218) (xy 357.153418 -236.276132) (xy 357.204713 -236.268007)
			(xy 357.256647 -236.268007) (xy 357.307942 -236.276132) (xy 357.357335 -236.29218) (xy 357.403609 -236.315758)
			(xy 357.445625 -236.346284) (xy 357.482348 -236.383007) (xy 357.512874 -236.425023) (xy 357.536452 -236.471297)
			(xy 357.5525 -236.52069) (xy 357.560625 -236.571985) (xy 357.561134 -236.597952) (xy 357.560625 -236.623919)
			(xy 357.840789 -236.623919) (xy 357.840789 -236.571985) (xy 357.848914 -236.52069) (xy 357.864962 -236.471297)
			(xy 357.88854 -236.425023) (xy 357.919066 -236.383007) (xy 357.955789 -236.346284) (xy 357.997805 -236.315758)
			(xy 358.044079 -236.29218) (xy 358.093472 -236.276132) (xy 358.144767 -236.268007) (xy 358.196701 -236.268007)
			(xy 358.247996 -236.276132) (xy 358.297389 -236.29218) (xy 358.343663 -236.315758) (xy 358.385679 -236.346284)
			(xy 358.422402 -236.383007) (xy 358.452928 -236.425023) (xy 358.476506 -236.471297) (xy 358.492554 -236.52069)
			(xy 358.500679 -236.571985) (xy 358.501188 -236.597952) (xy 358.500679 -236.623919) (xy 358.780335 -236.623919)
			(xy 358.780335 -236.571985) (xy 358.78846 -236.52069) (xy 358.804508 -236.471297) (xy 358.828086 -236.425023)
			(xy 358.858612 -236.383007) (xy 358.895335 -236.346284) (xy 358.937351 -236.315758) (xy 358.983625 -236.29218)
			(xy 359.033018 -236.276132) (xy 359.084313 -236.268007) (xy 359.136247 -236.268007) (xy 359.187542 -236.276132)
			(xy 359.236935 -236.29218) (xy 359.283209 -236.315758) (xy 359.325225 -236.346284) (xy 359.361948 -236.383007)
			(xy 359.392474 -236.425023) (xy 359.416052 -236.471297) (xy 359.4321 -236.52069) (xy 359.440225 -236.571985)
			(xy 359.440734 -236.597952) (xy 359.440225 -236.623919) (xy 359.720135 -236.623919) (xy 359.720135 -236.571985)
			(xy 359.72826 -236.52069) (xy 359.744308 -236.471297) (xy 359.767886 -236.425023) (xy 359.798412 -236.383007)
			(xy 359.835135 -236.346284) (xy 359.877151 -236.315758) (xy 359.923425 -236.29218) (xy 359.972818 -236.276132)
			(xy 360.024113 -236.268007) (xy 360.076047 -236.268007) (xy 360.127342 -236.276132) (xy 360.176735 -236.29218)
			(xy 360.223009 -236.315758) (xy 360.265025 -236.346284) (xy 360.301748 -236.383007) (xy 360.332274 -236.425023)
			(xy 360.355852 -236.471297) (xy 360.3719 -236.52069) (xy 360.380025 -236.571985) (xy 360.380534 -236.597952)
			(xy 360.380025 -236.623919) (xy 360.659935 -236.623919) (xy 360.659935 -236.571985) (xy 360.66806 -236.52069)
			(xy 360.684108 -236.471297) (xy 360.707686 -236.425023) (xy 360.738212 -236.383007) (xy 360.774935 -236.346284)
			(xy 360.816951 -236.315758) (xy 360.863225 -236.29218) (xy 360.912618 -236.276132) (xy 360.963913 -236.268007)
			(xy 361.015847 -236.268007) (xy 361.067142 -236.276132) (xy 361.116535 -236.29218) (xy 361.162809 -236.315758)
			(xy 361.204825 -236.346284) (xy 361.241548 -236.383007) (xy 361.272074 -236.425023) (xy 361.295652 -236.471297)
			(xy 361.3117 -236.52069) (xy 361.319825 -236.571985) (xy 361.320334 -236.597952) (xy 361.319825 -236.623919)
			(xy 361.3117 -236.675214) (xy 361.295652 -236.724607) (xy 361.272074 -236.770881) (xy 361.241548 -236.812897)
			(xy 361.204825 -236.84962) (xy 361.162809 -236.880146) (xy 361.116535 -236.903724) (xy 361.067142 -236.919772)
			(xy 361.015847 -236.927897) (xy 360.963913 -236.927897) (xy 360.912618 -236.919772) (xy 360.863225 -236.903724)
			(xy 360.816951 -236.880146) (xy 360.774935 -236.84962) (xy 360.738212 -236.812897) (xy 360.707686 -236.770881)
			(xy 360.684108 -236.724607) (xy 360.66806 -236.675214) (xy 360.659935 -236.623919) (xy 360.380025 -236.623919)
			(xy 360.3719 -236.675214) (xy 360.355852 -236.724607) (xy 360.332274 -236.770881) (xy 360.301748 -236.812897)
			(xy 360.265025 -236.84962) (xy 360.223009 -236.880146) (xy 360.176735 -236.903724) (xy 360.127342 -236.919772)
			(xy 360.076047 -236.927897) (xy 360.024113 -236.927897) (xy 359.972818 -236.919772) (xy 359.923425 -236.903724)
			(xy 359.877151 -236.880146) (xy 359.835135 -236.84962) (xy 359.798412 -236.812897) (xy 359.767886 -236.770881)
			(xy 359.744308 -236.724607) (xy 359.72826 -236.675214) (xy 359.720135 -236.623919) (xy 359.440225 -236.623919)
			(xy 359.4321 -236.675214) (xy 359.416052 -236.724607) (xy 359.392474 -236.770881) (xy 359.361948 -236.812897)
			(xy 359.325225 -236.84962) (xy 359.283209 -236.880146) (xy 359.236935 -236.903724) (xy 359.187542 -236.919772)
			(xy 359.136247 -236.927897) (xy 359.084313 -236.927897) (xy 359.033018 -236.919772) (xy 358.983625 -236.903724)
			(xy 358.937351 -236.880146) (xy 358.895335 -236.84962) (xy 358.858612 -236.812897) (xy 358.828086 -236.770881)
			(xy 358.804508 -236.724607) (xy 358.78846 -236.675214) (xy 358.780335 -236.623919) (xy 358.500679 -236.623919)
			(xy 358.492554 -236.675214) (xy 358.476506 -236.724607) (xy 358.452928 -236.770881) (xy 358.422402 -236.812897)
			(xy 358.385679 -236.84962) (xy 358.343663 -236.880146) (xy 358.297389 -236.903724) (xy 358.247996 -236.919772)
			(xy 358.196701 -236.927897) (xy 358.144767 -236.927897) (xy 358.093472 -236.919772) (xy 358.044079 -236.903724)
			(xy 357.997805 -236.880146) (xy 357.955789 -236.84962) (xy 357.919066 -236.812897) (xy 357.88854 -236.770881)
			(xy 357.864962 -236.724607) (xy 357.848914 -236.675214) (xy 357.840789 -236.623919) (xy 357.560625 -236.623919)
			(xy 357.5525 -236.675214) (xy 357.536452 -236.724607) (xy 357.512874 -236.770881) (xy 357.482348 -236.812897)
			(xy 357.445625 -236.84962) (xy 357.403609 -236.880146) (xy 357.357335 -236.903724) (xy 357.307942 -236.919772)
			(xy 357.256647 -236.927897) (xy 357.204713 -236.927897) (xy 357.153418 -236.919772) (xy 357.104025 -236.903724)
			(xy 357.057751 -236.880146) (xy 357.015735 -236.84962) (xy 356.979012 -236.812897) (xy 356.948486 -236.770881)
			(xy 356.924908 -236.724607) (xy 356.90886 -236.675214) (xy 356.900735 -236.623919) (xy 351.086748 -236.623919)
			(xy 351.083949 -236.628151) (xy 351.051729 -236.664118) (xy 351.014617 -236.695012) (xy 350.994218 -236.707934)
			(xy 350.981349 -236.716366) (xy 350.961008 -236.739427) (xy 350.948463 -236.767503) (xy 350.944856 -236.798042)
			(xy 350.950515 -236.828268) (xy 350.964924 -236.855434) (xy 350.975422 -236.866684) (xy 351.546219 -237.437481)
			(xy 357.370889 -237.437481) (xy 357.370889 -237.385547) (xy 357.379014 -237.334252) (xy 357.395062 -237.284859)
			(xy 357.41864 -237.238585) (xy 357.449166 -237.196569) (xy 357.485889 -237.159846) (xy 357.527905 -237.12932)
			(xy 357.574179 -237.105742) (xy 357.623572 -237.089694) (xy 357.674867 -237.081569) (xy 357.726801 -237.081569)
			(xy 357.778096 -237.089694) (xy 357.827489 -237.105742) (xy 357.873763 -237.12932) (xy 357.915779 -237.159846)
			(xy 357.952502 -237.196569) (xy 357.983028 -237.238585) (xy 358.006606 -237.284859) (xy 358.022654 -237.334252)
			(xy 358.030779 -237.385547) (xy 358.031288 -237.411514) (xy 358.030779 -237.437481) (xy 358.310689 -237.437481)
			(xy 358.310689 -237.385547) (xy 358.318814 -237.334252) (xy 358.334862 -237.284859) (xy 358.35844 -237.238585)
			(xy 358.388966 -237.196569) (xy 358.425689 -237.159846) (xy 358.467705 -237.12932) (xy 358.513979 -237.105742)
			(xy 358.563372 -237.089694) (xy 358.614667 -237.081569) (xy 358.666601 -237.081569) (xy 358.717896 -237.089694)
			(xy 358.767289 -237.105742) (xy 358.813563 -237.12932) (xy 358.855579 -237.159846) (xy 358.892302 -237.196569)
			(xy 358.922828 -237.238585) (xy 358.946406 -237.284859) (xy 358.962454 -237.334252) (xy 358.970579 -237.385547)
			(xy 358.971088 -237.411514) (xy 358.970579 -237.437481) (xy 359.250489 -237.437481) (xy 359.250489 -237.385547)
			(xy 359.258614 -237.334252) (xy 359.274662 -237.284859) (xy 359.29824 -237.238585) (xy 359.328766 -237.196569)
			(xy 359.365489 -237.159846) (xy 359.407505 -237.12932) (xy 359.453779 -237.105742) (xy 359.503172 -237.089694)
			(xy 359.554467 -237.081569) (xy 359.606401 -237.081569) (xy 359.657696 -237.089694) (xy 359.707089 -237.105742)
			(xy 359.753363 -237.12932) (xy 359.795379 -237.159846) (xy 359.832102 -237.196569) (xy 359.862628 -237.238585)
			(xy 359.886206 -237.284859) (xy 359.902254 -237.334252) (xy 359.910379 -237.385547) (xy 359.910888 -237.411514)
			(xy 359.910379 -237.437481) (xy 360.190289 -237.437481) (xy 360.190289 -237.385547) (xy 360.198414 -237.334252)
			(xy 360.214462 -237.284859) (xy 360.23804 -237.238585) (xy 360.268566 -237.196569) (xy 360.305289 -237.159846)
			(xy 360.347305 -237.12932) (xy 360.393579 -237.105742) (xy 360.442972 -237.089694) (xy 360.494267 -237.081569)
			(xy 360.546201 -237.081569) (xy 360.597496 -237.089694) (xy 360.646889 -237.105742) (xy 360.693163 -237.12932)
			(xy 360.735179 -237.159846) (xy 360.771902 -237.196569) (xy 360.802428 -237.238585) (xy 360.826006 -237.284859)
			(xy 360.842054 -237.334252) (xy 360.850179 -237.385547) (xy 360.850688 -237.411514) (xy 360.850179 -237.437481)
			(xy 361.130089 -237.437481) (xy 361.130089 -237.385547) (xy 361.138214 -237.334252) (xy 361.154262 -237.284859)
			(xy 361.17784 -237.238585) (xy 361.208366 -237.196569) (xy 361.245089 -237.159846) (xy 361.287105 -237.12932)
			(xy 361.333379 -237.105742) (xy 361.382772 -237.089694) (xy 361.434067 -237.081569) (xy 361.486001 -237.081569)
			(xy 361.537296 -237.089694) (xy 361.586689 -237.105742) (xy 361.632963 -237.12932) (xy 361.674979 -237.159846)
			(xy 361.711702 -237.196569) (xy 361.742228 -237.238585) (xy 361.765806 -237.284859) (xy 361.781854 -237.334252)
			(xy 361.789979 -237.385547) (xy 361.790488 -237.411514) (xy 361.789979 -237.437481) (xy 361.781854 -237.488776)
			(xy 361.765806 -237.538169) (xy 361.742228 -237.584443) (xy 361.711702 -237.626459) (xy 361.674979 -237.663182)
			(xy 361.632963 -237.693708) (xy 361.586689 -237.717286) (xy 361.537296 -237.733334) (xy 361.486001 -237.741459)
			(xy 361.434067 -237.741459) (xy 361.382772 -237.733334) (xy 361.333379 -237.717286) (xy 361.287105 -237.693708)
			(xy 361.245089 -237.663182) (xy 361.208366 -237.626459) (xy 361.17784 -237.584443) (xy 361.154262 -237.538169)
			(xy 361.138214 -237.488776) (xy 361.130089 -237.437481) (xy 360.850179 -237.437481) (xy 360.842054 -237.488776)
			(xy 360.826006 -237.538169) (xy 360.802428 -237.584443) (xy 360.771902 -237.626459) (xy 360.735179 -237.663182)
			(xy 360.693163 -237.693708) (xy 360.646889 -237.717286) (xy 360.597496 -237.733334) (xy 360.546201 -237.741459)
			(xy 360.494267 -237.741459) (xy 360.442972 -237.733334) (xy 360.393579 -237.717286) (xy 360.347305 -237.693708)
			(xy 360.305289 -237.663182) (xy 360.268566 -237.626459) (xy 360.23804 -237.584443) (xy 360.214462 -237.538169)
			(xy 360.198414 -237.488776) (xy 360.190289 -237.437481) (xy 359.910379 -237.437481) (xy 359.902254 -237.488776)
			(xy 359.886206 -237.538169) (xy 359.862628 -237.584443) (xy 359.832102 -237.626459) (xy 359.795379 -237.663182)
			(xy 359.753363 -237.693708) (xy 359.707089 -237.717286) (xy 359.657696 -237.733334) (xy 359.606401 -237.741459)
			(xy 359.554467 -237.741459) (xy 359.503172 -237.733334) (xy 359.453779 -237.717286) (xy 359.407505 -237.693708)
			(xy 359.365489 -237.663182) (xy 359.328766 -237.626459) (xy 359.29824 -237.584443) (xy 359.274662 -237.538169)
			(xy 359.258614 -237.488776) (xy 359.250489 -237.437481) (xy 358.970579 -237.437481) (xy 358.962454 -237.488776)
			(xy 358.946406 -237.538169) (xy 358.922828 -237.584443) (xy 358.892302 -237.626459) (xy 358.855579 -237.663182)
			(xy 358.813563 -237.693708) (xy 358.767289 -237.717286) (xy 358.717896 -237.733334) (xy 358.666601 -237.741459)
			(xy 358.614667 -237.741459) (xy 358.563372 -237.733334) (xy 358.513979 -237.717286) (xy 358.467705 -237.693708)
			(xy 358.425689 -237.663182) (xy 358.388966 -237.626459) (xy 358.35844 -237.584443) (xy 358.334862 -237.538169)
			(xy 358.318814 -237.488776) (xy 358.310689 -237.437481) (xy 358.030779 -237.437481) (xy 358.022654 -237.488776)
			(xy 358.006606 -237.538169) (xy 357.983028 -237.584443) (xy 357.952502 -237.626459) (xy 357.915779 -237.663182)
			(xy 357.873763 -237.693708) (xy 357.827489 -237.717286) (xy 357.778096 -237.733334) (xy 357.726801 -237.741459)
			(xy 357.674867 -237.741459) (xy 357.623572 -237.733334) (xy 357.574179 -237.717286) (xy 357.527905 -237.693708)
			(xy 357.485889 -237.663182) (xy 357.449166 -237.626459) (xy 357.41864 -237.584443) (xy 357.395062 -237.538169)
			(xy 357.379014 -237.488776) (xy 357.370889 -237.437481) (xy 351.546219 -237.437481) (xy 352.124264 -238.015526)
		)
		(stroke
			(width 0)
			(type solid)
		)
		(fill yes)
		(layer "In11.Cu")
		(net "PVNN_MAIN_CPU0")
	)
	(gr_poly
		(pts
			(xy 84.96808 -42.840148) (xy 95.55988 -42.840148) (xy 98.897186 -39.502842) (xy 98.900742 -39.489126)
			(xy 98.90842 -39.460665) (xy 98.931338 -39.406357) (xy 98.962339 -39.35622) (xy 99.000683 -39.31145)
			(xy 99.045458 -39.273111) (xy 99.095598 -39.242117) (xy 99.149909 -39.219205) (xy 99.178364 -39.211504)
			(xy 99.19208 -39.207948) (xy 100.28428 -38.115748) (xy 100.28428 -37.903404) (xy 100.267934 -37.882838)
			(xy 100.240448 -37.838068) (xy 100.219365 -37.789951) (xy 100.205085 -37.739395) (xy 100.197878 -37.687358)
			(xy 100.197879 -37.634824) (xy 100.205089 -37.582787) (xy 100.219372 -37.532232) (xy 100.240457 -37.484115)
			(xy 100.267945 -37.439347) (xy 100.28428 -37.418772) (xy 100.28428 -30.571948) (xy 98.78568 -29.073348)
			(xy 87.53348 -29.073348) (xy 81.387188 -22.927056) (xy 81.361026 -22.931628) (xy 81.344526 -22.934369)
			(xy 81.311203 -22.937294) (xy 81.294478 -22.93747) (xy 81.267227 -22.937005) (xy 81.213281 -22.929245)
			(xy 81.160988 -22.913887) (xy 81.111413 -22.891243) (xy 81.065565 -22.861774) (xy 81.024378 -22.826079)
			(xy 80.98869 -22.784887) (xy 80.959228 -22.739035) (xy 80.936592 -22.689456) (xy 80.921242 -22.637161)
			(xy 80.913491 -22.583213) (xy 80.91297 -22.555962) (xy 80.91315 -22.539237) (xy 80.916075 -22.505915)
			(xy 80.918812 -22.489414) (xy 80.923384 -22.463252) (xy 75.87488 -17.414748) (xy 75.87488 -13.539216)
			(xy 75.874419 -13.529333) (xy 75.86695 -13.511034) (xy 75.853114 -13.49692) (xy 75.834967 -13.489087)
			(xy 75.825096 -13.488416) (xy 75.796112 -13.487378) (xy 75.738944 -13.477613) (xy 75.683916 -13.459298)
			(xy 75.632298 -13.432856) (xy 75.585284 -13.398898) (xy 75.564238 -13.378942) (xy 75.554211 -13.36973)
			(xy 75.530423 -13.356499) (xy 75.503986 -13.350019) (xy 75.476776 -13.35075) (xy 75.450725 -13.35864)
			(xy 75.427682 -13.373129) (xy 75.409283 -13.393188) (xy 75.402694 -13.405104) (xy 75.39038 -13.428221)
			(xy 75.360371 -13.471147) (xy 75.324772 -13.509565) (xy 75.284253 -13.542753) (xy 75.239575 -13.570087)
			(xy 75.191579 -13.591054) (xy 75.141166 -13.60526) (xy 75.089284 -13.612436) (xy 75.063096 -13.612876)
			(xy 75.035844 -13.612412) (xy 74.981895 -13.604655) (xy 74.9296 -13.589298) (xy 74.880022 -13.566655)
			(xy 74.834172 -13.537186) (xy 74.792982 -13.501492) (xy 74.757292 -13.460299) (xy 74.727828 -13.414446)
			(xy 74.705189 -13.364866) (xy 74.689838 -13.312569) (xy 74.682085 -13.25862) (xy 74.681588 -13.231368)
			(xy 74.681588 -13.18006) (xy 74.620628 -13.18006) (xy 74.610976 -13.184124) (xy 74.587451 -13.1936)
			(xy 74.538521 -13.206943) (xy 74.488252 -13.213667) (xy 74.462894 -13.214096) (xy 74.435644 -13.213609)
			(xy 74.381699 -13.205852) (xy 74.329406 -13.190497) (xy 74.279831 -13.167856) (xy 74.233983 -13.138391)
			(xy 74.192795 -13.102701) (xy 74.157105 -13.061512) (xy 74.127641 -13.015663) (xy 74.105001 -12.966088)
			(xy 74.089646 -12.913796) (xy 74.08189 -12.85985) (xy 74.08189 -12.80535) (xy 74.089646 -12.751404)
			(xy 74.105001 -12.699112) (xy 74.127641 -12.649537) (xy 74.157105 -12.603688) (xy 74.192795 -12.562499)
			(xy 74.233983 -12.526809) (xy 74.279831 -12.497344) (xy 74.329406 -12.474703) (xy 74.381699 -12.459348)
			(xy 74.435644 -12.451591) (xy 74.490144 -12.45159) (xy 74.54409 -12.459345) (xy 74.596382 -12.474699)
			(xy 74.645958 -12.497338) (xy 74.691807 -12.526802) (xy 74.732996 -12.562491) (xy 74.768687 -12.603678)
			(xy 74.798154 -12.649526) (xy 74.820795 -12.699101) (xy 74.836151 -12.751393) (xy 74.843909 -12.805338)
			(xy 74.844402 -12.832588) (xy 74.844402 -12.883896) (xy 74.905362 -12.883896) (xy 74.915014 -12.879832)
			(xy 74.938539 -12.870354) (xy 74.987468 -12.857008) (xy 75.037737 -12.850282) (xy 75.063096 -12.84986)
			(xy 75.092752 -12.850423) (xy 75.151349 -12.859603) (xy 75.207818 -12.877742) (xy 75.2608 -12.904404)
			(xy 75.309016 -12.938944) (xy 75.330558 -12.959334) (xy 75.340584 -12.968549) (xy 75.364372 -12.981784)
			(xy 75.39081 -12.988266) (xy 75.418022 -12.987536) (xy 75.444074 -12.979645) (xy 75.467117 -12.965153)
			(xy 75.485515 -12.94509) (xy 75.492102 -12.933172) (xy 75.506014 -12.907197) (xy 75.540605 -12.859498)
			(xy 75.582111 -12.817677) (xy 75.629549 -12.782729) (xy 75.681792 -12.755482) (xy 75.737601 -12.736584)
			(xy 75.79565 -12.726482) (xy 75.825096 -12.7254) (xy 75.834971 -12.724742) (xy 75.853125 -12.716908)
			(xy 75.866969 -12.70279) (xy 75.874446 -12.684486) (xy 75.87488 -12.6746) (xy 75.87488 -10.548366)
			(xy 75.830176 -10.543286) (xy 75.802682 -10.53954) (xy 75.749101 -10.525126) (xy 75.698172 -10.503103)
			(xy 75.650969 -10.473938) (xy 75.608488 -10.438243) (xy 75.571623 -10.396773) (xy 75.541153 -10.350401)
			(xy 75.51772 -10.300106) (xy 75.501818 -10.246947) (xy 75.493782 -10.192045) (xy 75.493782 -10.136559)
			(xy 75.501817 -10.081657) (xy 75.517719 -10.028498) (xy 75.541151 -9.978202) (xy 75.571621 -9.93183)
			(xy 75.608484 -9.89036) (xy 75.650966 -9.854665) (xy 75.698168 -9.825499) (xy 75.749097 -9.803476)
			(xy 75.802678 -9.789061) (xy 75.830176 -9.78535) (xy 75.87488 -9.78027) (xy 75.87488 -8.110728) (xy 75.438254 -7.674102)
			(xy 75.420895 -7.656119) (xy 75.391485 -7.615709) (xy 75.368767 -7.571191) (xy 75.353302 -7.523664)
			(xy 75.345472 -7.474302) (xy 75.345036 -7.449312) (xy 75.345036 -7.14375) (xy 75.344558 -7.129538)
			(xy 75.336713 -7.102218) (xy 75.321643 -7.078116) (xy 75.300517 -7.0591) (xy 75.274968 -7.046641)
			(xy 75.246976 -7.041704) (xy 75.218707 -7.044671) (xy 75.205336 -7.049516) (xy 75.182502 -7.058364)
			(xy 75.135135 -7.070797) (xy 75.086566 -7.077063) (xy 75.06208 -7.077456) (xy 75.034826 -7.076969)
			(xy 74.980874 -7.069209) (xy 74.928575 -7.05385) (xy 74.878994 -7.031205) (xy 74.83314 -7.001734)
			(xy 74.791947 -6.966038) (xy 74.756254 -6.924844) (xy 74.726785 -6.878988) (xy 74.704143 -6.829406)
			(xy 74.688787 -6.777107) (xy 74.68103 -6.723154) (xy 74.68103 -6.668646) (xy 74.688787 -6.614693)
			(xy 74.704143 -6.562394) (xy 74.726785 -6.512812) (xy 74.756254 -6.466956) (xy 74.791947 -6.425762)
			(xy 74.83314 -6.390066) (xy 74.878994 -6.360595) (xy 74.928575 -6.33795) (xy 74.980874 -6.322591)
			(xy 75.034826 -6.314831) (xy 75.06208 -6.31444) (xy 75.086567 -6.314816) (xy 75.135137 -6.321084)
			(xy 75.182505 -6.333521) (xy 75.205336 -6.34238) (xy 75.218692 -6.347269) (xy 75.246966 -6.350241)
			(xy 75.274963 -6.345303) (xy 75.300513 -6.332836) (xy 75.321636 -6.313808) (xy 75.336693 -6.289693)
			(xy 75.344517 -6.262361) (xy 75.345036 -6.248146) (xy 75.345036 -6.216904) (xy 75.345554 -6.191923)
			(xy 75.353418 -6.142583) (xy 75.36889 -6.095077) (xy 75.391591 -6.050569) (xy 75.420964 -6.010153)
			(xy 75.438254 -5.992114) (xy 75.698604 -5.731764) (xy 75.70216 -5.717794) (xy 75.709725 -5.688636)
			(xy 75.732786 -5.632988) (xy 75.764314 -5.581662) (xy 75.803524 -5.535934) (xy 75.849439 -5.496943)
			(xy 75.87488 -5.480812) (xy 75.87488 -3.012948) (xy 75.49388 -2.631948) (xy 70.15988 -2.631948) (xy 69.55028 -3.241548)
			(xy 73.664062 -3.241548) (xy 73.668133 -3.185926) (xy 73.680259 -3.131489) (xy 73.700182 -3.079398)
			(xy 73.727478 -3.030763) (xy 73.761564 -2.98662) (xy 73.801713 -2.947911) (xy 73.847071 -2.91546)
			(xy 73.896671 -2.889959) (xy 73.949455 -2.871952) (xy 74.004298 -2.861822) (xy 74.060032 -2.859785)
			(xy 74.115469 -2.865885) (xy 74.169426 -2.879991) (xy 74.220755 -2.901803) (xy 74.268361 -2.930857)
			(xy 74.311229 -2.966532) (xy 74.348446 -3.008069) (xy 74.379219 -3.054582) (xy 74.402891 -3.105079)
			(xy 74.418959 -3.158486) (xy 74.427079 -3.213662) (xy 74.427588 -3.241548) (xy 74.427079 -3.269434)
			(xy 74.418959 -3.32461) (xy 74.402891 -3.378017) (xy 74.379219 -3.428514) (xy 74.348446 -3.475027)
			(xy 74.311229 -3.516564) (xy 74.268361 -3.552239) (xy 74.220755 -3.581293) (xy 74.169426 -3.603105)
			(xy 74.115469 -3.617211) (xy 74.060032 -3.623311) (xy 74.004298 -3.621274) (xy 73.949455 -3.611144)
			(xy 73.896671 -3.593137) (xy 73.847071 -3.567636) (xy 73.801713 -3.535185) (xy 73.761564 -3.496476)
			(xy 73.727478 -3.452333) (xy 73.700182 -3.403698) (xy 73.680259 -3.351607) (xy 73.668133 -3.29717)
			(xy 73.664062 -3.241548) (xy 69.55028 -3.241548) (xy 68.50888 -4.282948) (xy 60.63488 -4.282948)
			(xy 59.96178 -4.956048) (xy 59.951789 -4.966706) (xy 59.937819 -4.99235) (xy 59.931675 -5.020898)
			(xy 59.933857 -5.050018) (xy 59.944189 -5.077331) (xy 59.961825 -5.100606) (xy 59.985325 -5.117941)
			(xy 59.998864 -5.123434) (xy 60.026037 -5.133935) (xy 60.076719 -5.161788) (xy 60.910722 -5.161788)
			(xy 60.914793 -5.106166) (xy 60.926919 -5.051729) (xy 60.946842 -4.999638) (xy 60.974138 -4.951003)
			(xy 61.008224 -4.90686) (xy 61.048373 -4.868151) (xy 61.093731 -4.8357) (xy 61.143331 -4.810199)
			(xy 61.196115 -4.792192) (xy 61.250958 -4.782062) (xy 61.306692 -4.780025) (xy 61.362129 -4.786125)
			(xy 61.416086 -4.800231) (xy 61.467415 -4.822043) (xy 61.515021 -4.851097) (xy 61.557889 -4.886772)
			(xy 61.595106 -4.928309) (xy 61.625879 -4.974822) (xy 61.649551 -5.025319) (xy 61.665619 -5.078726)
			(xy 61.673739 -5.133902) (xy 61.674248 -5.161788) (xy 61.674063 -5.171948) (xy 62.231522 -5.171948)
			(xy 62.235593 -5.116326) (xy 62.247719 -5.061889) (xy 62.267642 -5.009798) (xy 62.294938 -4.961163)
			(xy 62.329024 -4.91702) (xy 62.369173 -4.878311) (xy 62.414531 -4.84586) (xy 62.464131 -4.820359)
			(xy 62.516915 -4.802352) (xy 62.571758 -4.792222) (xy 62.627492 -4.790185) (xy 62.682929 -4.796285)
			(xy 62.736886 -4.810391) (xy 62.788215 -4.832203) (xy 62.835821 -4.861257) (xy 62.878689 -4.896932)
			(xy 62.915906 -4.938469) (xy 62.946679 -4.984982) (xy 62.970351 -5.035479) (xy 62.986419 -5.088886)
			(xy 62.994539 -5.144062) (xy 62.995048 -5.171948) (xy 62.994539 -5.199834) (xy 62.986419 -5.25501)
			(xy 62.970351 -5.308417) (xy 62.946679 -5.358914) (xy 62.915906 -5.405427) (xy 62.878689 -5.446964)
			(xy 62.835821 -5.482639) (xy 62.788215 -5.511693) (xy 62.736886 -5.533505) (xy 62.682929 -5.547611)
			(xy 62.627492 -5.553711) (xy 62.571758 -5.551674) (xy 62.516915 -5.541544) (xy 62.464131 -5.523537)
			(xy 62.414531 -5.498036) (xy 62.369173 -5.465585) (xy 62.329024 -5.426876) (xy 62.294938 -5.382733)
			(xy 62.267642 -5.334098) (xy 62.247719 -5.282007) (xy 62.235593 -5.22757) (xy 62.231522 -5.171948)
			(xy 61.674063 -5.171948) (xy 61.673739 -5.189674) (xy 61.665619 -5.24485) (xy 61.649551 -5.298257)
			(xy 61.625879 -5.348754) (xy 61.595106 -5.395267) (xy 61.557889 -5.436804) (xy 61.515021 -5.472479)
			(xy 61.467415 -5.501533) (xy 61.416086 -5.523345) (xy 61.362129 -5.537451) (xy 61.306692 -5.543551)
			(xy 61.250958 -5.541514) (xy 61.196115 -5.531384) (xy 61.143331 -5.513377) (xy 61.093731 -5.487876)
			(xy 61.048373 -5.455425) (xy 61.008224 -5.416716) (xy 60.974138 -5.372573) (xy 60.946842 -5.323938)
			(xy 60.926919 -5.271847) (xy 60.914793 -5.21741) (xy 60.910722 -5.161788) (xy 60.076719 -5.161788)
			(xy 60.077087 -5.16199) (xy 60.123279 -5.197481) (xy 60.163539 -5.239581) (xy 60.19693 -5.287313)
			(xy 60.222675 -5.339566) (xy 60.240178 -5.395127) (xy 60.24903 -5.452702) (xy 60.249562 -5.481828)
			(xy 60.249097 -5.509078) (xy 60.241336 -5.563024) (xy 60.225977 -5.615316) (xy 60.203333 -5.664889)
			(xy 60.173863 -5.710736) (xy 60.138169 -5.751921) (xy 60.096976 -5.787608) (xy 60.051124 -5.817068)
			(xy 60.001546 -5.839703) (xy 59.991989 -5.842508) (xy 61.464442 -5.842508) (xy 61.468513 -5.786886)
			(xy 61.480639 -5.732449) (xy 61.500562 -5.680358) (xy 61.527858 -5.631723) (xy 61.561944 -5.58758)
			(xy 61.602093 -5.548871) (xy 61.647451 -5.51642) (xy 61.697051 -5.490919) (xy 61.749835 -5.472912)
			(xy 61.804678 -5.462782) (xy 61.860412 -5.460745) (xy 61.915849 -5.466845) (xy 61.969806 -5.480951)
			(xy 62.021135 -5.502763) (xy 62.068741 -5.531817) (xy 62.111609 -5.567492) (xy 62.148826 -5.609029)
			(xy 62.179599 -5.655542) (xy 62.203271 -5.706039) (xy 62.219339 -5.759446) (xy 62.227459 -5.814622)
			(xy 62.227968 -5.842508) (xy 62.227459 -5.870394) (xy 62.219339 -5.92557) (xy 62.203271 -5.978977)
			(xy 62.179599 -6.029474) (xy 62.148826 -6.075987) (xy 62.111609 -6.117524) (xy 62.068741 -6.153199)
			(xy 62.021135 -6.182253) (xy 61.969806 -6.204065) (xy 61.915849 -6.218171) (xy 61.860412 -6.224271)
			(xy 61.804678 -6.222234) (xy 61.749835 -6.212104) (xy 61.697051 -6.194097) (xy 61.647451 -6.168596)
			(xy 61.602093 -6.136145) (xy 61.561944 -6.097436) (xy 61.527858 -6.053293) (xy 61.500562 -6.004658)
			(xy 61.480639 -5.952567) (xy 61.468513 -5.89813) (xy 61.464442 -5.842508) (xy 59.991989 -5.842508)
			(xy 59.949251 -5.855052) (xy 59.895304 -5.862802) (xy 59.868054 -5.863336) (xy 59.838931 -5.862783)
			(xy 59.781363 -5.853923) (xy 59.72581 -5.836416) (xy 59.673564 -5.810668) (xy 59.625838 -5.777279)
			(xy 59.583742 -5.737024) (xy 59.548254 -5.690838) (xy 59.520197 -5.639794) (xy 59.50966 -5.612638)
			(xy 59.504219 -5.59907) (xy 59.486871 -5.575555) (xy 59.46358 -5.557907) (xy 59.436249 -5.547567)
			(xy 59.407109 -5.545378) (xy 59.378541 -5.551521) (xy 59.352875 -5.565493) (xy 59.342274 -5.575554)
			(xy 59.11088 -5.806948) (xy 59.11088 -6.662928) (xy 60.085984 -6.662928) (xy 60.090055 -6.607306)
			(xy 60.102181 -6.552869) (xy 60.122104 -6.500778) (xy 60.1494 -6.452143) (xy 60.183486 -6.408) (xy 60.223635 -6.369291)
			(xy 60.268993 -6.33684) (xy 60.318593 -6.311339) (xy 60.371377 -6.293332) (xy 60.42622 -6.283202)
			(xy 60.481954 -6.281165) (xy 60.537391 -6.287265) (xy 60.591348 -6.301371) (xy 60.642677 -6.323183)
			(xy 60.690283 -6.352237) (xy 60.733151 -6.387912) (xy 60.770368 -6.429449) (xy 60.801141 -6.475962)
			(xy 60.824813 -6.526459) (xy 60.840881 -6.579866) (xy 60.849001 -6.635042) (xy 60.84951 -6.662928)
			(xy 60.849001 -6.690814) (xy 60.840881 -6.74599) (xy 60.824813 -6.799397) (xy 60.814963 -6.820408)
			(xy 62.193422 -6.820408) (xy 62.197493 -6.764786) (xy 62.209619 -6.710349) (xy 62.229542 -6.658258)
			(xy 62.256838 -6.609623) (xy 62.290924 -6.56548) (xy 62.331073 -6.526771) (xy 62.376431 -6.49432)
			(xy 62.426031 -6.468819) (xy 62.478815 -6.450812) (xy 62.533658 -6.440682) (xy 62.589392 -6.438645)
			(xy 62.644829 -6.444745) (xy 62.698786 -6.458851) (xy 62.750115 -6.480663) (xy 62.797721 -6.509717)
			(xy 62.840589 -6.545392) (xy 62.877806 -6.586929) (xy 62.908579 -6.633442) (xy 62.932251 -6.683939)
			(xy 62.948319 -6.737346) (xy 62.956439 -6.792522) (xy 62.956948 -6.820408) (xy 62.956439 -6.848294)
			(xy 62.948319 -6.90347) (xy 62.932251 -6.956877) (xy 62.908579 -7.007374) (xy 62.877806 -7.053887)
			(xy 62.840589 -7.095424) (xy 62.797721 -7.131099) (xy 62.750115 -7.160153) (xy 62.698786 -7.181965)
			(xy 62.644829 -7.196071) (xy 62.589392 -7.202171) (xy 62.533658 -7.200134) (xy 62.478815 -7.190004)
			(xy 62.426031 -7.171997) (xy 62.376431 -7.146496) (xy 62.331073 -7.114045) (xy 62.290924 -7.075336)
			(xy 62.256838 -7.031193) (xy 62.229542 -6.982558) (xy 62.209619 -6.930467) (xy 62.197493 -6.87603)
			(xy 62.193422 -6.820408) (xy 60.814963 -6.820408) (xy 60.801141 -6.849894) (xy 60.770368 -6.896407)
			(xy 60.733151 -6.937944) (xy 60.690283 -6.973619) (xy 60.642677 -7.002673) (xy 60.591348 -7.024485)
			(xy 60.537391 -7.038591) (xy 60.481954 -7.044691) (xy 60.42622 -7.042654) (xy 60.371377 -7.032524)
			(xy 60.318593 -7.014517) (xy 60.268993 -6.989016) (xy 60.223635 -6.956565) (xy 60.183486 -6.917856)
			(xy 60.1494 -6.873713) (xy 60.122104 -6.825078) (xy 60.102181 -6.772987) (xy 60.090055 -6.71855)
			(xy 60.085984 -6.662928) (xy 59.11088 -6.662928) (xy 59.11088 -7.203948) (xy 62.990982 -7.203948)
			(xy 62.995053 -7.148326) (xy 63.007179 -7.093889) (xy 63.027102 -7.041798) (xy 63.054398 -6.993163)
			(xy 63.088484 -6.94902) (xy 63.128633 -6.910311) (xy 63.173991 -6.87786) (xy 63.223591 -6.852359)
			(xy 63.276375 -6.834352) (xy 63.331218 -6.824222) (xy 63.386952 -6.822185) (xy 63.442389 -6.828285)
			(xy 63.496346 -6.842391) (xy 63.547675 -6.864203) (xy 63.595281 -6.893257) (xy 63.638149 -6.928932)
			(xy 63.675366 -6.970469) (xy 63.706139 -7.016982) (xy 63.729811 -7.067479) (xy 63.745879 -7.120886)
			(xy 63.753999 -7.176062) (xy 63.754508 -7.203948) (xy 63.879982 -7.203948) (xy 63.884053 -7.148326)
			(xy 63.896179 -7.093889) (xy 63.916102 -7.041798) (xy 63.943398 -6.993163) (xy 63.977484 -6.94902)
			(xy 64.017633 -6.910311) (xy 64.062991 -6.87786) (xy 64.112591 -6.852359) (xy 64.165375 -6.834352)
			(xy 64.220218 -6.824222) (xy 64.275952 -6.822185) (xy 64.331389 -6.828285) (xy 64.385346 -6.842391)
			(xy 64.436675 -6.864203) (xy 64.484281 -6.893257) (xy 64.527149 -6.928932) (xy 64.564366 -6.970469)
			(xy 64.595139 -7.016982) (xy 64.618811 -7.067479) (xy 64.634879 -7.120886) (xy 64.642999 -7.176062)
			(xy 64.643508 -7.203948) (xy 64.768982 -7.203948) (xy 64.773053 -7.148326) (xy 64.785179 -7.093889)
			(xy 64.805102 -7.041798) (xy 64.832398 -6.993163) (xy 64.866484 -6.94902) (xy 64.906633 -6.910311)
			(xy 64.951991 -6.87786) (xy 65.001591 -6.852359) (xy 65.054375 -6.834352) (xy 65.109218 -6.824222)
			(xy 65.164952 -6.822185) (xy 65.220389 -6.828285) (xy 65.274346 -6.842391) (xy 65.325675 -6.864203)
			(xy 65.373281 -6.893257) (xy 65.416149 -6.928932) (xy 65.453366 -6.970469) (xy 65.484139 -7.016982)
			(xy 65.507811 -7.067479) (xy 65.523879 -7.120886) (xy 65.531999 -7.176062) (xy 65.532508 -7.203948)
			(xy 65.657982 -7.203948) (xy 65.662053 -7.148326) (xy 65.674179 -7.093889) (xy 65.694102 -7.041798)
			(xy 65.721398 -6.993163) (xy 65.755484 -6.94902) (xy 65.795633 -6.910311) (xy 65.840991 -6.87786)
			(xy 65.890591 -6.852359) (xy 65.943375 -6.834352) (xy 65.998218 -6.824222) (xy 66.053952 -6.822185)
			(xy 66.109389 -6.828285) (xy 66.163346 -6.842391) (xy 66.214675 -6.864203) (xy 66.262281 -6.893257)
			(xy 66.305149 -6.928932) (xy 66.307404 -6.931449) (xy 68.859406 -6.931449) (xy 68.859406 -6.876951)
			(xy 68.867162 -6.823007) (xy 68.882516 -6.770716) (xy 68.905156 -6.721143) (xy 68.93462 -6.675296)
			(xy 68.970309 -6.634109) (xy 69.011496 -6.59842) (xy 69.057343 -6.568956) (xy 69.106916 -6.546316)
			(xy 69.159207 -6.530962) (xy 69.213151 -6.523206) (xy 69.2404 -6.52272) (xy 69.269188 -6.52321) (xy 69.326112 -6.531862)
			(xy 69.381088 -6.54897) (xy 69.43287 -6.574144) (xy 69.480281 -6.606813) (xy 69.522245 -6.646236)
			(xy 69.557808 -6.691517) (xy 69.586163 -6.741628) (xy 69.606666 -6.795431) (xy 69.613272 -6.823456)
			(xy 69.616887 -6.837524) (xy 69.6308 -6.863003) (xy 69.651317 -6.883541) (xy 69.676783 -6.897478)
			(xy 69.705141 -6.90369) (xy 69.734101 -6.901674) (xy 69.747892 -6.897116) (xy 69.779906 -6.885998)
			(xy 69.846598 -6.873993) (xy 69.88048 -6.87324) (xy 69.907737 -6.873606) (xy 69.961697 -6.881361)
			(xy 70.014004 -6.896717) (xy 70.063593 -6.919362) (xy 70.109454 -6.948833) (xy 70.150655 -6.984531)
			(xy 70.186355 -7.02573) (xy 70.215829 -7.071589) (xy 70.238476 -7.121177) (xy 70.253835 -7.173483)
			(xy 70.259822 -7.215124) (xy 70.480428 -7.215124) (xy 70.480882 -7.188363) (xy 70.488386 -7.135369)
			(xy 70.503222 -7.083944) (xy 70.525098 -7.035097) (xy 70.553585 -6.989786) (xy 70.588125 -6.9489)
			(xy 70.62804 -6.913242) (xy 70.672546 -6.883512) (xy 70.720769 -6.860293) (xy 70.771764 -6.84404)
			(xy 70.82453 -6.835073) (xy 70.851268 -6.83387) (xy 70.864495 -6.833152) (xy 70.889887 -6.825622)
			(xy 70.912489 -6.811817) (xy 70.93078 -6.792663) (xy 70.943532 -6.769451) (xy 70.949886 -6.74374)
			(xy 70.950074 -6.730492) (xy 70.94982 -6.724396) (xy 70.950252 -6.69713) (xy 70.958017 -6.643154)
			(xy 70.973388 -6.590834) (xy 70.996052 -6.541235) (xy 71.025546 -6.495368) (xy 71.061271 -6.454168)
			(xy 71.102498 -6.418475) (xy 71.148386 -6.389014) (xy 71.198002 -6.366388) (xy 71.250334 -6.351056)
			(xy 71.304316 -6.343332) (xy 71.331582 -6.342888) (xy 72.195182 -6.342888) (xy 72.204976 -6.342893)
			(xy 72.224544 -6.343783) (xy 72.234298 -6.344666) (xy 72.245396 -6.34522) (xy 72.266376 -6.337983)
			(xy 72.282357 -6.322583) (xy 72.290366 -6.301886) (xy 72.288914 -6.27974) (xy 72.284082 -6.269736)
			(xy 72.269317 -6.241445) (xy 72.248368 -6.181172) (xy 72.237741 -6.118253) (xy 72.237092 -6.086348)
			(xy 72.237543 -6.059916) (xy 72.244861 -6.00756) (xy 72.259335 -5.956715) (xy 72.280689 -5.908355)
			(xy 72.308513 -5.863405) (xy 72.342276 -5.822726) (xy 72.38133 -5.787096) (xy 72.424928 -5.757198)
			(xy 72.472236 -5.733604) (xy 72.522347 -5.716766) (xy 72.548242 -5.711444) (xy 72.563095 -5.708136)
			(xy 72.59005 -5.694049) (xy 72.61166 -5.672647) (xy 72.626009 -5.645831) (xy 72.631823 -5.615977)
			(xy 72.628587 -5.585736) (xy 72.616588 -5.557789) (xy 72.60717 -5.545836) (xy 72.590112 -5.525076)
			(xy 72.561429 -5.479641) (xy 72.539407 -5.43063) (xy 72.524481 -5.379014) (xy 72.516947 -5.325814)
			(xy 72.516492 -5.298948) (xy 72.516978 -5.271697) (xy 72.524734 -5.217749) (xy 72.540089 -5.165454)
			(xy 72.562731 -5.115877) (xy 72.592197 -5.070027) (xy 72.627888 -5.028836) (xy 72.669079 -4.993145)
			(xy 72.714929 -4.963679) (xy 72.764506 -4.941037) (xy 72.816801 -4.925682) (xy 72.870749 -4.917926)
			(xy 72.925251 -4.917926) (xy 72.979199 -4.925682) (xy 73.031494 -4.941037) (xy 73.081071 -4.963679)
			(xy 73.126921 -4.993145) (xy 73.168112 -5.028836) (xy 73.203803 -5.070027) (xy 73.233269 -5.115877)
			(xy 73.255911 -5.165454) (xy 73.271266 -5.217749) (xy 73.279022 -5.271697) (xy 73.279508 -5.298948)
			(xy 73.279053 -5.32538) (xy 73.271736 -5.377736) (xy 73.257262 -5.428581) (xy 73.235909 -5.476941)
			(xy 73.22345 -5.497068) (xy 73.700132 -5.497068) (xy 73.700618 -5.469817) (xy 73.708374 -5.415869)
			(xy 73.723729 -5.363574) (xy 73.746371 -5.313997) (xy 73.775837 -5.268147) (xy 73.811528 -5.226956)
			(xy 73.852719 -5.191265) (xy 73.898569 -5.161799) (xy 73.948146 -5.139157) (xy 74.000441 -5.123802)
			(xy 74.054389 -5.116046) (xy 74.108891 -5.116046) (xy 74.162839 -5.123802) (xy 74.215134 -5.139157)
			(xy 74.264711 -5.161799) (xy 74.310561 -5.191265) (xy 74.351752 -5.226956) (xy 74.387443 -5.268147)
			(xy 74.416909 -5.313997) (xy 74.439551 -5.363574) (xy 74.454906 -5.415869) (xy 74.462662 -5.469817)
			(xy 74.463148 -5.497068) (xy 74.462659 -5.524165) (xy 74.454982 -5.577813) (xy 74.439794 -5.629836)
			(xy 74.417399 -5.679187) (xy 74.388247 -5.724873) (xy 74.370946 -5.745734) (xy 74.362002 -5.757033)
			(xy 74.350137 -5.783276) (xy 74.346053 -5.811786) (xy 74.350073 -5.840305) (xy 74.36188 -5.866575)
			(xy 74.380539 -5.888515) (xy 74.392282 -5.896864) (xy 74.414628 -5.912039) (xy 74.455192 -5.947708)
			(xy 74.490317 -5.988744) (xy 74.5193 -6.034326) (xy 74.541561 -6.083541) (xy 74.556654 -6.135405)
			(xy 74.564278 -6.18888) (xy 74.564748 -6.215888) (xy 74.564262 -6.243139) (xy 74.556506 -6.297087)
			(xy 74.541151 -6.349382) (xy 74.518509 -6.398959) (xy 74.489043 -6.444809) (xy 74.453352 -6.486)
			(xy 74.412161 -6.521691) (xy 74.366311 -6.551157) (xy 74.316734 -6.573799) (xy 74.264439 -6.589154)
			(xy 74.210491 -6.59691) (xy 74.155989 -6.59691) (xy 74.102041 -6.589154) (xy 74.049746 -6.573799)
			(xy 74.000169 -6.551157) (xy 73.954319 -6.521691) (xy 73.913128 -6.486) (xy 73.877437 -6.444809)
			(xy 73.847971 -6.398959) (xy 73.825329 -6.349382) (xy 73.809974 -6.297087) (xy 73.802218 -6.243139)
			(xy 73.801732 -6.215888) (xy 73.802201 -6.18879) (xy 73.809883 -6.135141) (xy 73.825076 -6.083118)
			(xy 73.847476 -6.033768) (xy 73.876631 -5.988082) (xy 73.893934 -5.967222) (xy 73.902932 -5.955962)
			(xy 73.914795 -5.929706) (xy 73.918873 -5.901185) (xy 73.914842 -5.872656) (xy 73.903022 -5.846381)
			(xy 73.884349 -5.82444) (xy 73.872598 -5.816092) (xy 73.850273 -5.800887) (xy 73.80971 -5.765223)
			(xy 73.774584 -5.724191) (xy 73.745599 -5.678615) (xy 73.723335 -5.629404) (xy 73.708236 -5.577545)
			(xy 73.700606 -5.524074) (xy 73.700132 -5.497068) (xy 73.22345 -5.497068) (xy 73.208085 -5.521891)
			(xy 73.174323 -5.56257) (xy 73.135269 -5.598199) (xy 73.091671 -5.628097) (xy 73.044364 -5.651692)
			(xy 72.994253 -5.66853) (xy 72.968358 -5.673852) (xy 72.953506 -5.677166) (xy 72.926553 -5.691253)
			(xy 72.904943 -5.712653) (xy 72.890595 -5.739469) (xy 72.88478 -5.76932) (xy 72.888015 -5.799561)
			(xy 72.900013 -5.827507) (xy 72.90943 -5.83946) (xy 72.926486 -5.860221) (xy 72.955169 -5.905656)
			(xy 72.977192 -5.954666) (xy 72.992118 -6.006282) (xy 72.999652 -6.059482) (xy 73.000108 -6.086348)
			(xy 72.999556 -6.114985) (xy 72.990974 -6.171614) (xy 72.974025 -6.226323) (xy 72.949089 -6.277885)
			(xy 72.916727 -6.325141) (xy 72.877666 -6.36703) (xy 72.832783 -6.40261) (xy 72.783086 -6.431082)
			(xy 72.729693 -6.451807) (xy 72.673801 -6.464319) (xy 72.64527 -6.46684) (xy 72.632026 -6.468197)
			(xy 72.60687 -6.476889) (xy 72.584817 -6.491788) (xy 72.567365 -6.511882) (xy 72.5557 -6.535804)
			(xy 72.550616 -6.561929) (xy 72.552458 -6.588479) (xy 72.55637 -6.601206) (xy 72.565919 -6.631107)
			(xy 72.576263 -6.693014) (xy 72.576944 -6.724396) (xy 72.57669 -6.730746) (xy 72.576902 -6.743927)
			(xy 72.583258 -6.7695) (xy 72.595951 -6.792594) (xy 72.614133 -6.811668) (xy 72.636593 -6.825452)
			(xy 72.661833 -6.833025) (xy 72.674988 -6.83387) (xy 72.70162 -6.835221) (xy 72.754144 -6.844428)
			(xy 72.804874 -6.860861) (xy 72.85282 -6.884199) (xy 72.897049 -6.913987) (xy 72.936697 -6.949646)
			(xy 72.970993 -6.990479) (xy 72.999267 -7.03569) (xy 73.020969 -7.084399) (xy 73.035675 -7.135656)
			(xy 73.043099 -7.188462) (xy 73.043356 -7.203948) (xy 73.480928 -7.203948) (xy 73.484999 -7.148326)
			(xy 73.497125 -7.093889) (xy 73.517048 -7.041798) (xy 73.544344 -6.993163) (xy 73.57843 -6.94902)
			(xy 73.618579 -6.910311) (xy 73.663937 -6.87786) (xy 73.713537 -6.852359) (xy 73.766321 -6.834352)
			(xy 73.821164 -6.824222) (xy 73.876898 -6.822185) (xy 73.932335 -6.828285) (xy 73.986292 -6.842391)
			(xy 74.037621 -6.864203) (xy 74.085227 -6.893257) (xy 74.128095 -6.928932) (xy 74.165312 -6.970469)
			(xy 74.196085 -7.016982) (xy 74.219757 -7.067479) (xy 74.235825 -7.120886) (xy 74.243945 -7.176062)
			(xy 74.244454 -7.203948) (xy 74.243945 -7.231834) (xy 74.235825 -7.28701) (xy 74.219757 -7.340417)
			(xy 74.196085 -7.390914) (xy 74.165312 -7.437427) (xy 74.128095 -7.478964) (xy 74.085227 -7.514639)
			(xy 74.037621 -7.543693) (xy 73.986292 -7.565505) (xy 73.932335 -7.579611) (xy 73.876898 -7.585711)
			(xy 73.821164 -7.583674) (xy 73.766321 -7.573544) (xy 73.713537 -7.555537) (xy 73.663937 -7.530036)
			(xy 73.618579 -7.497585) (xy 73.57843 -7.458876) (xy 73.544344 -7.414733) (xy 73.517048 -7.366098)
			(xy 73.497125 -7.314007) (xy 73.484999 -7.25957) (xy 73.480928 -7.203948) (xy 73.043356 -7.203948)
			(xy 73.043542 -7.215124) (xy 73.043056 -7.242375) (xy 73.0353 -7.296323) (xy 73.019945 -7.348618)
			(xy 72.997303 -7.398195) (xy 72.967837 -7.444045) (xy 72.932146 -7.485236) (xy 72.890955 -7.520927)
			(xy 72.845105 -7.550393) (xy 72.795528 -7.573035) (xy 72.743233 -7.58839) (xy 72.689285 -7.596146)
			(xy 72.634783 -7.596146) (xy 72.580835 -7.58839) (xy 72.52854 -7.573035) (xy 72.478963 -7.550393)
			(xy 72.433113 -7.520927) (xy 72.391922 -7.485236) (xy 72.356231 -7.444045) (xy 72.326765 -7.398195)
			(xy 72.304123 -7.348618) (xy 72.288768 -7.296323) (xy 72.281012 -7.242375) (xy 72.280526 -7.215124)
			(xy 72.280661 -7.201806) (xy 72.282568 -7.175239) (xy 72.284336 -7.162038) (xy 72.285219 -7.1529)
			(xy 72.2812 -7.135002) (xy 72.271137 -7.119664) (xy 72.256319 -7.108852) (xy 72.238642 -7.103949)
			(xy 72.229472 -7.10438) (xy 72.195182 -7.105904) (xy 71.331582 -7.105904) (xy 71.295006 -7.10438)
			(xy 71.285812 -7.103797) (xy 71.268028 -7.108572) (xy 71.253077 -7.119321) (xy 71.242889 -7.13466)
			(xy 71.238776 -7.152609) (xy 71.239634 -7.161784) (xy 71.241401 -7.175049) (xy 71.243307 -7.201743)
			(xy 71.243444 -7.215124) (xy 71.242958 -7.242375) (xy 71.235202 -7.296323) (xy 71.219847 -7.348618)
			(xy 71.197205 -7.398195) (xy 71.167739 -7.444045) (xy 71.132048 -7.485236) (xy 71.090857 -7.520927)
			(xy 71.045007 -7.550393) (xy 70.99543 -7.573035) (xy 70.943135 -7.58839) (xy 70.889187 -7.596146)
			(xy 70.834685 -7.596146) (xy 70.780737 -7.58839) (xy 70.728442 -7.573035) (xy 70.678865 -7.550393)
			(xy 70.633015 -7.520927) (xy 70.591824 -7.485236) (xy 70.556133 -7.444045) (xy 70.526667 -7.398195)
			(xy 70.504025 -7.348618) (xy 70.48867 -7.296323) (xy 70.480914 -7.242375) (xy 70.480428 -7.215124)
			(xy 70.259822 -7.215124) (xy 70.261593 -7.227443) (xy 70.261593 -7.281957) (xy 70.253835 -7.335917)
			(xy 70.238476 -7.388223) (xy 70.215829 -7.437811) (xy 70.186355 -7.48367) (xy 70.150655 -7.524869)
			(xy 70.109454 -7.560567) (xy 70.063593 -7.590038) (xy 70.014004 -7.612683) (xy 69.961697 -7.628039)
			(xy 69.907737 -7.635794) (xy 69.88048 -7.636256) (xy 69.85169 -7.635803) (xy 69.794764 -7.627147)
			(xy 69.739786 -7.610036) (xy 69.688003 -7.584857) (xy 69.640591 -7.552183) (xy 69.598628 -7.512755)
			(xy 69.563066 -7.46747) (xy 69.534712 -7.417354) (xy 69.514212 -7.363547) (xy 69.507608 -7.33552)
			(xy 69.504031 -7.321441) (xy 69.49011 -7.29596) (xy 69.469584 -7.275423) (xy 69.444111 -7.261488)
			(xy 69.415746 -7.25528) (xy 69.386781 -7.2573) (xy 69.372988 -7.26186) (xy 69.340968 -7.27296) (xy 69.27428 -7.284976)
			(xy 69.2404 -7.285736) (xy 69.213151 -7.285194) (xy 69.159207 -7.277438) (xy 69.106916 -7.262084)
			(xy 69.057343 -7.239444) (xy 69.011496 -7.20998) (xy 68.970309 -7.174291) (xy 68.93462 -7.133104)
			(xy 68.905156 -7.087257) (xy 68.882516 -7.037684) (xy 68.867162 -6.985393) (xy 68.859406 -6.931449)
			(xy 66.307404 -6.931449) (xy 66.342366 -6.970469) (xy 66.373139 -7.016982) (xy 66.396811 -7.067479)
			(xy 66.412879 -7.120886) (xy 66.420999 -7.176062) (xy 66.421508 -7.203948) (xy 66.420999 -7.231834)
			(xy 66.412879 -7.28701) (xy 66.396811 -7.340417) (xy 66.373139 -7.390914) (xy 66.342366 -7.437427)
			(xy 66.305149 -7.478964) (xy 66.262281 -7.514639) (xy 66.214675 -7.543693) (xy 66.163346 -7.565505)
			(xy 66.109389 -7.579611) (xy 66.053952 -7.585711) (xy 65.998218 -7.583674) (xy 65.943375 -7.573544)
			(xy 65.890591 -7.555537) (xy 65.840991 -7.530036) (xy 65.795633 -7.497585) (xy 65.755484 -7.458876)
			(xy 65.721398 -7.414733) (xy 65.694102 -7.366098) (xy 65.674179 -7.314007) (xy 65.662053 -7.25957)
			(xy 65.657982 -7.203948) (xy 65.532508 -7.203948) (xy 65.531999 -7.231834) (xy 65.523879 -7.28701)
			(xy 65.507811 -7.340417) (xy 65.484139 -7.390914) (xy 65.453366 -7.437427) (xy 65.416149 -7.478964)
			(xy 65.373281 -7.514639) (xy 65.325675 -7.543693) (xy 65.274346 -7.565505) (xy 65.220389 -7.579611)
			(xy 65.164952 -7.585711) (xy 65.109218 -7.583674) (xy 65.054375 -7.573544) (xy 65.001591 -7.555537)
			(xy 64.951991 -7.530036) (xy 64.906633 -7.497585) (xy 64.866484 -7.458876) (xy 64.832398 -7.414733)
			(xy 64.805102 -7.366098) (xy 64.785179 -7.314007) (xy 64.773053 -7.25957) (xy 64.768982 -7.203948)
			(xy 64.643508 -7.203948) (xy 64.642999 -7.231834) (xy 64.634879 -7.28701) (xy 64.618811 -7.340417)
			(xy 64.595139 -7.390914) (xy 64.564366 -7.437427) (xy 64.527149 -7.478964) (xy 64.484281 -7.514639)
			(xy 64.436675 -7.543693) (xy 64.385346 -7.565505) (xy 64.331389 -7.579611) (xy 64.275952 -7.585711)
			(xy 64.220218 -7.583674) (xy 64.165375 -7.573544) (xy 64.112591 -7.555537) (xy 64.062991 -7.530036)
			(xy 64.017633 -7.497585) (xy 63.977484 -7.458876) (xy 63.943398 -7.414733) (xy 63.916102 -7.366098)
			(xy 63.896179 -7.314007) (xy 63.884053 -7.25957) (xy 63.879982 -7.203948) (xy 63.754508 -7.203948)
			(xy 63.753999 -7.231834) (xy 63.745879 -7.28701) (xy 63.729811 -7.340417) (xy 63.706139 -7.390914)
			(xy 63.675366 -7.437427) (xy 63.638149 -7.478964) (xy 63.595281 -7.514639) (xy 63.547675 -7.543693)
			(xy 63.496346 -7.565505) (xy 63.442389 -7.579611) (xy 63.386952 -7.585711) (xy 63.331218 -7.583674)
			(xy 63.276375 -7.573544) (xy 63.223591 -7.555537) (xy 63.173991 -7.530036) (xy 63.128633 -7.497585)
			(xy 63.088484 -7.458876) (xy 63.054398 -7.414733) (xy 63.027102 -7.366098) (xy 63.007179 -7.314007)
			(xy 62.995053 -7.25957) (xy 62.990982 -7.203948) (xy 59.11088 -7.203948) (xy 59.11088 -9.439148)
			(xy 60.085984 -9.439148) (xy 60.090055 -9.383526) (xy 60.102181 -9.329089) (xy 60.122104 -9.276998)
			(xy 60.1494 -9.228363) (xy 60.183486 -9.18422) (xy 60.223635 -9.145511) (xy 60.268993 -9.11306) (xy 60.318593 -9.087559)
			(xy 60.371377 -9.069552) (xy 60.42622 -9.059422) (xy 60.481954 -9.057385) (xy 60.537391 -9.063485)
			(xy 60.591348 -9.077591) (xy 60.642677 -9.099403) (xy 60.690283 -9.128457) (xy 60.733151 -9.164132)
			(xy 60.770368 -9.205669) (xy 60.801141 -9.252182) (xy 60.824813 -9.302679) (xy 60.840881 -9.356086)
			(xy 60.849001 -9.411262) (xy 60.84951 -9.439148) (xy 60.849001 -9.467034) (xy 60.840881 -9.52221)
			(xy 60.824813 -9.575617) (xy 60.801141 -9.626114) (xy 60.770368 -9.672627) (xy 60.761085 -9.682988)
			(xy 66.481452 -9.682988) (xy 66.481871 -9.656088) (xy 66.489426 -9.60282) (xy 66.504397 -9.551145)
			(xy 66.526487 -9.502089) (xy 66.555258 -9.456627) (xy 66.590136 -9.415664) (xy 66.609976 -9.397492)
			(xy 66.620211 -9.387779) (xy 66.635375 -9.363998) (xy 66.643457 -9.336976) (xy 66.643841 -9.308773)
			(xy 66.636496 -9.281542) (xy 66.621983 -9.257357) (xy 66.612008 -9.247378) (xy 66.593352 -9.229288)
			(xy 66.56064 -9.188909) (xy 66.533714 -9.144462) (xy 66.513072 -9.09677) (xy 66.499097 -9.046718)
			(xy 66.492048 -8.995231) (xy 66.491612 -8.969248) (xy 66.492098 -8.941997) (xy 66.499854 -8.888049)
			(xy 66.515209 -8.835754) (xy 66.537851 -8.786177) (xy 66.567317 -8.740327) (xy 66.603008 -8.699136)
			(xy 66.644199 -8.663445) (xy 66.690049 -8.633979) (xy 66.739626 -8.611337) (xy 66.791921 -8.595982)
			(xy 66.845869 -8.588226) (xy 66.900371 -8.588226) (xy 66.954319 -8.595982) (xy 67.006614 -8.611337)
			(xy 67.056191 -8.633979) (xy 67.102041 -8.663445) (xy 67.143232 -8.699136) (xy 67.178923 -8.740327)
			(xy 67.208389 -8.786177) (xy 67.231031 -8.835754) (xy 67.246386 -8.888049) (xy 67.254142 -8.941997)
			(xy 67.254628 -8.969248) (xy 67.254139 -8.996146) (xy 67.246595 -9.049409) (xy 67.231635 -9.101082)
			(xy 67.209558 -9.150138) (xy 67.180801 -9.195601) (xy 67.145937 -9.236569) (xy 67.126104 -9.254744)
			(xy 67.115835 -9.264423) (xy 67.100675 -9.288215) (xy 67.092599 -9.315245) (xy 67.092222 -9.343454)
			(xy 67.099574 -9.37069) (xy 67.114094 -9.394878) (xy 67.124072 -9.404858) (xy 67.142694 -9.422983)
			(xy 67.175409 -9.463354) (xy 67.202341 -9.507793) (xy 67.222988 -9.555478) (xy 67.23697 -9.605525)
			(xy 67.244028 -9.657006) (xy 67.244468 -9.682988) (xy 67.243982 -9.710239) (xy 67.236226 -9.764187)
			(xy 67.220871 -9.816482) (xy 67.198229 -9.866059) (xy 67.168763 -9.911909) (xy 67.133072 -9.9531)
			(xy 67.091881 -9.988791) (xy 67.046031 -10.018257) (xy 66.996454 -10.040899) (xy 66.944159 -10.056254)
			(xy 66.890211 -10.06401) (xy 66.835709 -10.06401) (xy 66.781761 -10.056254) (xy 66.729466 -10.040899)
			(xy 66.679889 -10.018257) (xy 66.634039 -9.988791) (xy 66.592848 -9.9531) (xy 66.557157 -9.911909)
			(xy 66.527691 -9.866059) (xy 66.505049 -9.816482) (xy 66.489694 -9.764187) (xy 66.481938 -9.710239)
			(xy 66.481452 -9.682988) (xy 60.761085 -9.682988) (xy 60.733151 -9.714164) (xy 60.690283 -9.749839)
			(xy 60.642677 -9.778893) (xy 60.591348 -9.800705) (xy 60.537391 -9.814811) (xy 60.481954 -9.820911)
			(xy 60.42622 -9.818874) (xy 60.371377 -9.808744) (xy 60.318593 -9.790737) (xy 60.268993 -9.765236)
			(xy 60.223635 -9.732785) (xy 60.183486 -9.694076) (xy 60.1494 -9.649933) (xy 60.122104 -9.601298)
			(xy 60.102181 -9.549207) (xy 60.090055 -9.49477) (xy 60.085984 -9.439148) (xy 59.11088 -9.439148)
			(xy 59.11088 -9.616948) (xy 59.69508 -10.201148) (xy 68.604382 -10.201148) (xy 68.608453 -10.145526)
			(xy 68.620579 -10.091089) (xy 68.640502 -10.038998) (xy 68.667798 -9.990363) (xy 68.701884 -9.94622)
			(xy 68.742033 -9.907511) (xy 68.787391 -9.87506) (xy 68.836991 -9.849559) (xy 68.889775 -9.831552)
			(xy 68.944618 -9.821422) (xy 69.000352 -9.819385) (xy 69.055789 -9.825485) (xy 69.109746 -9.839591)
			(xy 69.161075 -9.861403) (xy 69.208681 -9.890457) (xy 69.251549 -9.926132) (xy 69.288766 -9.967669)
			(xy 69.319539 -10.014182) (xy 69.343211 -10.064679) (xy 69.359279 -10.118086) (xy 69.364849 -10.155936)
			(xy 72.75779 -10.155936) (xy 72.761861 -10.100314) (xy 72.773987 -10.045877) (xy 72.79391 -9.993786)
			(xy 72.821206 -9.945151) (xy 72.855292 -9.901008) (xy 72.895441 -9.862299) (xy 72.940799 -9.829848)
			(xy 72.990399 -9.804347) (xy 73.043183 -9.78634) (xy 73.098026 -9.77621) (xy 73.15376 -9.774173)
			(xy 73.209197 -9.780273) (xy 73.263154 -9.794379) (xy 73.314483 -9.816191) (xy 73.362089 -9.845245)
			(xy 73.404957 -9.88092) (xy 73.442174 -9.922457) (xy 73.472947 -9.96897) (xy 73.496619 -10.019467)
			(xy 73.512687 -10.072874) (xy 73.520807 -10.12805) (xy 73.521316 -10.155936) (xy 73.520807 -10.183822)
			(xy 73.512687 -10.238998) (xy 73.496619 -10.292405) (xy 73.472947 -10.342902) (xy 73.442174 -10.389415)
			(xy 73.404957 -10.430952) (xy 73.362089 -10.466627) (xy 73.314483 -10.495681) (xy 73.263154 -10.517493)
			(xy 73.209197 -10.531599) (xy 73.15376 -10.537699) (xy 73.098026 -10.535662) (xy 73.043183 -10.525532)
			(xy 72.990399 -10.507525) (xy 72.940799 -10.482024) (xy 72.895441 -10.449573) (xy 72.855292 -10.410864)
			(xy 72.821206 -10.366721) (xy 72.79391 -10.318086) (xy 72.773987 -10.265995) (xy 72.761861 -10.211558)
			(xy 72.75779 -10.155936) (xy 69.364849 -10.155936) (xy 69.367399 -10.173262) (xy 69.367908 -10.201148)
			(xy 69.367399 -10.229034) (xy 69.359279 -10.28421) (xy 69.343211 -10.337617) (xy 69.319539 -10.388114)
			(xy 69.288766 -10.434627) (xy 69.251549 -10.476164) (xy 69.208681 -10.511839) (xy 69.161075 -10.540893)
			(xy 69.109746 -10.562705) (xy 69.055789 -10.576811) (xy 69.000352 -10.582911) (xy 68.944618 -10.580874)
			(xy 68.889775 -10.570744) (xy 68.836991 -10.552737) (xy 68.787391 -10.527236) (xy 68.742033 -10.494785)
			(xy 68.701884 -10.456076) (xy 68.667798 -10.411933) (xy 68.640502 -10.363298) (xy 68.620579 -10.311207)
			(xy 68.608453 -10.25677) (xy 68.604382 -10.201148) (xy 59.69508 -10.201148) (xy 60.11926 -10.625328)
			(xy 67.433442 -10.625328) (xy 67.437513 -10.569706) (xy 67.449639 -10.515269) (xy 67.469562 -10.463178)
			(xy 67.496858 -10.414543) (xy 67.530944 -10.3704) (xy 67.571093 -10.331691) (xy 67.616451 -10.29924)
			(xy 67.666051 -10.273739) (xy 67.718835 -10.255732) (xy 67.773678 -10.245602) (xy 67.829412 -10.243565)
			(xy 67.884849 -10.249665) (xy 67.938806 -10.263771) (xy 67.990135 -10.285583) (xy 68.037741 -10.314637)
			(xy 68.080609 -10.350312) (xy 68.117826 -10.391849) (xy 68.148599 -10.438362) (xy 68.172271 -10.488859)
			(xy 68.188339 -10.542266) (xy 68.196459 -10.597442) (xy 68.196968 -10.625328) (xy 68.196459 -10.653214)
			(xy 68.188339 -10.70839) (xy 68.172271 -10.761797) (xy 68.148599 -10.812294) (xy 68.117826 -10.858807)
			(xy 68.080609 -10.900344) (xy 68.037741 -10.936019) (xy 67.990135 -10.965073) (xy 67.938806 -10.986885)
			(xy 67.884849 -11.000991) (xy 67.829412 -11.007091) (xy 67.773678 -11.005054) (xy 67.718835 -10.994924)
			(xy 67.666051 -10.976917) (xy 67.616451 -10.951416) (xy 67.571093 -10.918965) (xy 67.530944 -10.880256)
			(xy 67.496858 -10.836113) (xy 67.469562 -10.787478) (xy 67.449639 -10.735387) (xy 67.437513 -10.68095)
			(xy 67.433442 -10.625328) (xy 60.11926 -10.625328) (xy 61.93028 -12.436348) (xy 62.818772 -12.436348)
			(xy 62.819258 -12.409097) (xy 62.827014 -12.355149) (xy 62.842369 -12.302854) (xy 62.865011 -12.253277)
			(xy 62.894477 -12.207427) (xy 62.930168 -12.166236) (xy 62.971359 -12.130545) (xy 63.017209 -12.101079)
			(xy 63.066786 -12.078437) (xy 63.119081 -12.063082) (xy 63.173029 -12.055326) (xy 63.227531 -12.055326)
			(xy 63.281479 -12.063082) (xy 63.333774 -12.078437) (xy 63.383351 -12.101079) (xy 63.429201 -12.130545)
			(xy 63.470392 -12.166236) (xy 63.506083 -12.207427) (xy 63.535549 -12.253277) (xy 63.558191 -12.302854)
			(xy 63.573546 -12.355149) (xy 63.581302 -12.409097) (xy 63.581788 -12.436348) (xy 63.581296 -12.463562)
			(xy 63.573551 -12.517437) (xy 63.558226 -12.569663) (xy 63.535631 -12.61918) (xy 63.521336 -12.642342)
			(xy 63.51639 -12.650818) (xy 63.512664 -12.670066) (xy 63.51644 -12.689304) (xy 63.527164 -12.705715)
			(xy 63.543267 -12.716898) (xy 63.562391 -12.721214) (xy 63.572136 -12.720066) (xy 63.58702 -12.717816)
			(xy 63.617028 -12.715404) (xy 63.63208 -12.71524) (xy 63.638176 -12.71524) (xy 63.652463 -12.71498)
			(xy 63.680038 -12.70754) (xy 63.704476 -12.692757) (xy 63.723866 -12.671786) (xy 63.736692 -12.646267)
			(xy 63.741952 -12.618194) (xy 63.739236 -12.589763) (xy 63.734442 -12.576302) (xy 63.726025 -12.553938)
			(xy 63.714162 -12.507648) (xy 63.708163 -12.46024) (xy 63.707772 -12.436348) (xy 63.708258 -12.409097)
			(xy 63.716014 -12.355149) (xy 63.731369 -12.302854) (xy 63.754011 -12.253277) (xy 63.783477 -12.207427)
			(xy 63.819168 -12.166236) (xy 63.860359 -12.130545) (xy 63.906209 -12.101079) (xy 63.955786 -12.078437)
			(xy 64.008081 -12.063082) (xy 64.062029 -12.055326) (xy 64.116531 -12.055326) (xy 64.170479 -12.063082)
			(xy 64.222774 -12.078437) (xy 64.272351 -12.101079) (xy 64.318201 -12.130545) (xy 64.359392 -12.166236)
			(xy 64.395083 -12.207427) (xy 64.424549 -12.253277) (xy 64.447191 -12.302854) (xy 64.462546 -12.355149)
			(xy 64.470302 -12.409097) (xy 64.470788 -12.436348) (xy 64.470296 -12.463562) (xy 64.462551 -12.517437)
			(xy 64.447226 -12.569663) (xy 64.424631 -12.61918) (xy 64.410336 -12.642342) (xy 64.40539 -12.650818)
			(xy 64.401664 -12.670066) (xy 64.40544 -12.689304) (xy 64.416164 -12.705715) (xy 64.432267 -12.716898)
			(xy 64.451391 -12.721214) (xy 64.461136 -12.720066) (xy 64.47602 -12.717816) (xy 64.506028 -12.715404)
			(xy 64.52108 -12.71524) (xy 64.527176 -12.71524) (xy 64.541463 -12.71498) (xy 64.569038 -12.70754)
			(xy 64.593476 -12.692757) (xy 64.612866 -12.671786) (xy 64.625692 -12.646267) (xy 64.630952 -12.618194)
			(xy 64.628236 -12.589763) (xy 64.623442 -12.576302) (xy 64.615025 -12.553938) (xy 64.603162 -12.507648)
			(xy 64.597163 -12.46024) (xy 64.596772 -12.436348) (xy 64.597258 -12.409097) (xy 64.605014 -12.355149)
			(xy 64.620369 -12.302854) (xy 64.643011 -12.253277) (xy 64.672477 -12.207427) (xy 64.708168 -12.166236)
			(xy 64.749359 -12.130545) (xy 64.795209 -12.101079) (xy 64.844786 -12.078437) (xy 64.897081 -12.063082)
			(xy 64.951029 -12.055326) (xy 65.005531 -12.055326) (xy 65.059479 -12.063082) (xy 65.111774 -12.078437)
			(xy 65.161351 -12.101079) (xy 65.207201 -12.130545) (xy 65.248392 -12.166236) (xy 65.284083 -12.207427)
			(xy 65.313549 -12.253277) (xy 65.336191 -12.302854) (xy 65.351546 -12.355149) (xy 65.359302 -12.409097)
			(xy 65.359788 -12.436348) (xy 65.359296 -12.463562) (xy 65.351551 -12.517437) (xy 65.336226 -12.569663)
			(xy 65.313631 -12.61918) (xy 65.299336 -12.642342) (xy 65.29439 -12.650818) (xy 65.290664 -12.670066)
			(xy 65.29444 -12.689304) (xy 65.305164 -12.705715) (xy 65.321267 -12.716898) (xy 65.340391 -12.721214)
			(xy 65.350136 -12.720066) (xy 65.36502 -12.717816) (xy 65.395028 -12.715404) (xy 65.41008 -12.71524)
			(xy 65.416176 -12.71524) (xy 65.430463 -12.71498) (xy 65.458038 -12.70754) (xy 65.482476 -12.692757)
			(xy 65.501866 -12.671786) (xy 65.514692 -12.646267) (xy 65.519952 -12.618194) (xy 65.517236 -12.589763)
			(xy 65.512442 -12.576302) (xy 65.504025 -12.553938) (xy 65.492162 -12.507648) (xy 65.486163 -12.46024)
			(xy 65.485772 -12.436348) (xy 65.4863 -12.409097) (xy 65.49405 -12.35515) (xy 65.509399 -12.302854)
			(xy 65.532034 -12.253276) (xy 65.561495 -12.207423) (xy 65.597182 -12.16623) (xy 65.638369 -12.130536)
			(xy 65.684216 -12.101067) (xy 65.73379 -12.078423) (xy 65.786083 -12.063064) (xy 65.840029 -12.055305)
			(xy 65.86728 -12.05484) (xy 65.89465 -12.055308) (xy 65.94883 -12.063124) (xy 66.001333 -12.078612)
			(xy 66.05108 -12.101454) (xy 66.097047 -12.131178) (xy 66.117978 -12.14882) (xy 66.129306 -12.158056)
			(xy 66.155863 -12.170232) (xy 66.18478 -12.174405) (xy 66.213697 -12.170232) (xy 66.240254 -12.158056)
			(xy 66.251582 -12.14882) (xy 66.272513 -12.131179) (xy 66.318485 -12.101467) (xy 66.368233 -12.078631)
			(xy 66.420734 -12.06314) (xy 66.474911 -12.055313) (xy 66.50228 -12.05484) (xy 66.528282 -12.05526)
			(xy 66.579801 -12.062334) (xy 66.629883 -12.076338) (xy 66.6776 -12.097014) (xy 66.722066 -12.123979)
			(xy 66.762458 -12.156733) (xy 66.798027 -12.194669) (xy 66.81343 -12.215622) (xy 66.822536 -12.227428)
			(xy 66.846063 -12.245714) (xy 66.873866 -12.25643) (xy 66.903578 -12.258665) (xy 66.932672 -12.252228)
			(xy 66.958669 -12.237668) (xy 66.969386 -12.227306) (xy 66.987433 -12.209216) (xy 67.02751 -12.177516)
			(xy 67.071458 -12.151446) (xy 67.118492 -12.131473) (xy 67.16777 -12.117955) (xy 67.218411 -12.111132)
			(xy 67.24396 -12.11072) (xy 67.271213 -12.111193) (xy 67.325165 -12.118945) (xy 67.377465 -12.134297)
			(xy 67.427046 -12.156937) (xy 67.472901 -12.186404) (xy 67.514095 -12.222097) (xy 67.549789 -12.263289)
			(xy 67.579257 -12.309143) (xy 67.601899 -12.358724) (xy 67.617253 -12.411023) (xy 67.621526 -12.440752)
			(xy 69.697566 -12.440752) (xy 69.697566 -12.386248) (xy 69.705323 -12.332298) (xy 69.720678 -12.280002)
			(xy 69.74332 -12.230423) (xy 69.772787 -12.184571) (xy 69.80848 -12.14338) (xy 69.849671 -12.107687)
			(xy 69.895523 -12.07822) (xy 69.945102 -12.055578) (xy 69.997398 -12.040223) (xy 70.051348 -12.032466)
			(xy 70.0786 -12.03198) (xy 70.107167 -12.032537) (xy 70.163661 -12.041063) (xy 70.218254 -12.05791)
			(xy 70.269728 -12.082703) (xy 70.316934 -12.114887) (xy 70.358819 -12.153744) (xy 70.37705 -12.175744)
			(xy 70.385953 -12.186244) (xy 70.408235 -12.202395) (xy 70.434025 -12.212001) (xy 70.461444 -12.214361)
			(xy 70.488496 -12.209303) (xy 70.51321 -12.197197) (xy 70.533788 -12.178924) (xy 70.541642 -12.167616)
			(xy 70.556771 -12.145047) (xy 70.592467 -12.104083) (xy 70.633613 -12.068598) (xy 70.679378 -12.039309)
			(xy 70.728835 -12.016809) (xy 70.780983 -12.001553) (xy 70.834769 -11.993849) (xy 70.861936 -11.993372)
			(xy 70.889187 -11.993844) (xy 70.943134 -12.001605) (xy 70.995428 -12.016964) (xy 71.045004 -12.039608)
			(xy 71.090853 -12.069076) (xy 71.132043 -12.104769) (xy 71.167734 -12.145959) (xy 71.1972 -12.19181)
			(xy 71.219842 -12.241387) (xy 71.235198 -12.293681) (xy 71.242957 -12.347629) (xy 71.243444 -12.37488)
			(xy 71.24334 -12.387876) (xy 71.241558 -12.413807) (xy 71.239888 -12.426696) (xy 71.239081 -12.435842)
			(xy 71.243156 -12.453725) (xy 71.253276 -12.469023) (xy 71.268141 -12.479768) (xy 71.28584 -12.484582)
			(xy 71.295006 -12.4841) (xy 71.33082 -12.482576) (xy 72.19442 -12.482576) (xy 72.229218 -12.4841)
			(xy 72.238393 -12.484623) (xy 72.256098 -12.479722) (xy 72.270935 -12.46889) (xy 72.280997 -12.453521)
			(xy 72.28499 -12.43559) (xy 72.284082 -12.426442) (xy 72.282429 -12.413615) (xy 72.280653 -12.387812)
			(xy 72.280526 -12.37488) (xy 72.281 -12.347631) (xy 72.288758 -12.293688) (xy 72.304114 -12.241398)
			(xy 72.326755 -12.191826) (xy 72.356221 -12.145981) (xy 72.391911 -12.104795) (xy 72.433098 -12.069108)
			(xy 72.478946 -12.039645) (xy 72.528519 -12.017006) (xy 72.58081 -12.001653) (xy 72.634753 -11.993898)
			(xy 72.689251 -11.993898) (xy 72.743194 -12.001654) (xy 72.795485 -12.017008) (xy 72.845058 -12.039647)
			(xy 72.890905 -12.06911) (xy 72.932092 -12.104798) (xy 72.967782 -12.145984) (xy 72.997247 -12.19183)
			(xy 73.019887 -12.241402) (xy 73.035243 -12.293692) (xy 73.043001 -12.347635) (xy 73.043003 -12.402133)
			(xy 73.03525 -12.456077) (xy 73.019898 -12.508368) (xy 72.997262 -12.557942) (xy 72.967801 -12.60379)
			(xy 72.932115 -12.644979) (xy 72.89093 -12.680671) (xy 72.845086 -12.710138) (xy 72.795515 -12.732781)
			(xy 72.743225 -12.748139) (xy 72.689283 -12.755899) (xy 72.662034 -12.756388) (xy 72.62749 -12.754864)
			(xy 72.618344 -12.754423) (xy 72.600704 -12.759283) (xy 72.585901 -12.770037) (xy 72.575827 -12.785311)
			(xy 72.571769 -12.803152) (xy 72.572626 -12.812268) (xy 72.573962 -12.822699) (xy 72.575613 -12.843666)
			(xy 72.575928 -12.854178) (xy 72.576847 -12.868883) (xy 72.586088 -12.896848) (xy 72.602912 -12.921022)
			(xy 72.625926 -12.939402) (xy 72.653222 -12.950463) (xy 72.682538 -12.953291) (xy 72.697086 -12.950952)
			(xy 72.715381 -12.947606) (xy 72.752403 -12.944041) (xy 72.771 -12.94384) (xy 72.798255 -12.944255)
			(xy 72.85221 -12.952014) (xy 72.904512 -12.967372) (xy 72.954095 -12.990018) (xy 72.999951 -13.019491)
			(xy 73.041145 -13.055189) (xy 73.076838 -13.096388) (xy 73.106305 -13.142247) (xy 73.128945 -13.191833)
			(xy 73.144297 -13.244137) (xy 73.152048 -13.298093) (xy 73.152508 -13.325348) (xy 73.151492 -13.354304)
			(xy 73.150799 -13.368308) (xy 73.156377 -13.39578) (xy 73.169209 -13.420703) (xy 73.188331 -13.441203)
			(xy 73.212302 -13.455736) (xy 73.23932 -13.463209) (xy 73.267353 -13.46306) (xy 73.29429 -13.455301)
			(xy 73.306432 -13.448284) (xy 73.329186 -13.434693) (xy 73.377645 -13.413225) (xy 73.42861 -13.39868)
			(xy 73.4811 -13.391336) (xy 73.5076 -13.39088) (xy 73.537001 -13.391388) (xy 73.595104 -13.40043)
			(xy 73.651136 -13.41827) (xy 73.703771 -13.444486) (xy 73.751767 -13.47846) (xy 73.793989 -13.519387)
			(xy 73.812146 -13.542518) (xy 73.821376 -13.553709) (xy 73.844684 -13.570945) (xy 73.871897 -13.580934)
			(xy 73.900821 -13.582868) (xy 73.929123 -13.576592) (xy 73.954517 -13.562612) (xy 73.974958 -13.542056)
			(xy 73.982326 -13.529564) (xy 73.996797 -13.504094) (xy 74.032277 -13.457483) (xy 74.074459 -13.416838)
			(xy 74.122355 -13.383113) (xy 74.174839 -13.3571) (xy 74.230682 -13.33941) (xy 74.288571 -13.330456)
			(xy 74.31786 -13.32992) (xy 74.345117 -13.330324) (xy 74.399076 -13.338077) (xy 74.451383 -13.353431)
			(xy 74.500971 -13.376073) (xy 74.546833 -13.405542) (xy 74.588034 -13.441238) (xy 74.623734 -13.482435)
			(xy 74.653208 -13.528293) (xy 74.675855 -13.57788) (xy 74.691214 -13.630185) (xy 74.698973 -13.684143)
			(xy 74.698973 -13.738657) (xy 74.691214 -13.792615) (xy 74.675855 -13.84492) (xy 74.653208 -13.894507)
			(xy 74.623734 -13.940365) (xy 74.588034 -13.981562) (xy 74.546833 -14.017258) (xy 74.500971 -14.046727)
			(xy 74.451383 -14.069369) (xy 74.399076 -14.084723) (xy 74.345117 -14.092476) (xy 74.31786 -14.092936)
			(xy 74.288461 -14.092379) (xy 74.23036 -14.083346) (xy 74.17433 -14.065515) (xy 74.121695 -14.039308)
			(xy 74.073698 -14.005344) (xy 74.031473 -13.964425) (xy 74.013314 -13.941298) (xy 74.004134 -13.930062)
			(xy 73.980815 -13.912823) (xy 73.953589 -13.902835) (xy 73.924654 -13.900906) (xy 73.896344 -13.907191)
			(xy 73.870943 -13.921183) (xy 73.850501 -13.941753) (xy 73.843134 -13.954252) (xy 73.828698 -13.979743)
			(xy 73.793212 -14.026354) (xy 73.751024 -14.066997) (xy 73.703122 -14.100719) (xy 73.650632 -14.126729)
			(xy 73.594784 -14.144415) (xy 73.536891 -14.153363) (xy 73.5076 -14.153896) (xy 73.480347 -14.153445)
			(xy 73.426395 -14.145687) (xy 73.374096 -14.130331) (xy 73.324515 -14.107687) (xy 73.278661 -14.078218)
			(xy 73.237468 -14.042523) (xy 73.201775 -14.001329) (xy 73.172307 -13.955475) (xy 73.149665 -13.905893)
			(xy 73.13431 -13.853594) (xy 73.126555 -13.799641) (xy 73.126092 -13.772388) (xy 73.127108 -13.743432)
			(xy 73.127772 -13.729427) (xy 73.122202 -13.701955) (xy 73.109376 -13.67703) (xy 73.090259 -13.656529)
			(xy 73.06629 -13.641995) (xy 73.039274 -13.634522) (xy 73.011243 -13.634672) (xy 72.984308 -13.642434)
			(xy 72.972168 -13.649452) (xy 72.949416 -13.663047) (xy 72.900956 -13.684512) (xy 72.84999 -13.699057)
			(xy 72.7975 -13.7064) (xy 72.771 -13.706856) (xy 72.744216 -13.706424) (xy 72.691177 -13.698904)
			(xy 72.639711 -13.68404) (xy 72.59083 -13.662124) (xy 72.545495 -13.633587) (xy 72.504596 -13.59899)
			(xy 72.468939 -13.559013) (xy 72.439222 -13.514442) (xy 72.416032 -13.466152) (xy 72.399823 -13.415094)
			(xy 72.390915 -13.362271) (xy 72.389746 -13.335508) (xy 72.388835 -13.320755) (xy 72.37964 -13.292678)
			(xy 72.362801 -13.268403) (xy 72.339723 -13.249957) (xy 72.312334 -13.23888) (xy 72.282921 -13.236097)
			(xy 72.268334 -13.23848) (xy 72.250041 -13.241837) (xy 72.213017 -13.245395) (xy 72.19442 -13.245592)
			(xy 71.33082 -13.245592) (xy 71.303567 -13.245126) (xy 71.249615 -13.237371) (xy 71.197316 -13.222017)
			(xy 71.147735 -13.199376) (xy 71.101881 -13.169908) (xy 71.060688 -13.134215) (xy 71.024994 -13.093022)
			(xy 70.995526 -13.047168) (xy 70.972884 -12.997587) (xy 70.957529 -12.945289) (xy 70.949774 -12.891337)
			(xy 70.949312 -12.864084) (xy 70.949312 -12.859004) (xy 70.949057 -12.845825) (xy 70.942638 -12.82027)
			(xy 70.929891 -12.79721) (xy 70.911663 -12.778183) (xy 70.889172 -12.764456) (xy 70.863916 -12.756946)
			(xy 70.85076 -12.756134) (xy 70.823154 -12.754825) (xy 70.76872 -12.745274) (xy 70.716233 -12.727969)
			(xy 70.666793 -12.703274) (xy 70.621431 -12.671705) (xy 70.581099 -12.633922) (xy 70.563486 -12.612624)
			(xy 70.554539 -12.602166) (xy 70.532266 -12.58602) (xy 70.506487 -12.576415) (xy 70.479079 -12.574051)
			(xy 70.452036 -12.5791) (xy 70.427327 -12.591193) (xy 70.40675 -12.609452) (xy 70.398894 -12.620752)
			(xy 70.38373 -12.643297) (xy 70.348041 -12.684263) (xy 70.306902 -12.719751) (xy 70.261143 -12.749043)
			(xy 70.211691 -12.771547) (xy 70.159547 -12.786808) (xy 70.105766 -12.794516) (xy 70.0786 -12.794996)
			(xy 70.051348 -12.794534) (xy 69.997398 -12.786777) (xy 69.945102 -12.771422) (xy 69.895523 -12.74878)
			(xy 69.849671 -12.719313) (xy 69.80848 -12.68362) (xy 69.772787 -12.642429) (xy 69.74332 -12.596577)
			(xy 69.720678 -12.546998) (xy 69.705323 -12.494702) (xy 69.697566 -12.440752) (xy 67.621526 -12.440752)
			(xy 67.625007 -12.464975) (xy 67.625468 -12.492228) (xy 67.624996 -12.518803) (xy 67.617628 -12.571438)
			(xy 67.603023 -12.622541) (xy 67.581466 -12.671122) (xy 67.553373 -12.71624) (xy 67.519288 -12.75702)
			(xy 67.479873 -12.792674) (xy 67.435889 -12.822511) (xy 67.388189 -12.845952) (xy 67.363086 -12.854686)
			(xy 67.350653 -12.859187) (xy 67.32849 -12.873593) (xy 67.310773 -12.89321) (xy 67.298691 -12.91672)
			(xy 67.293055 -12.942546) (xy 67.294244 -12.968952) (xy 67.297808 -12.981686) (xy 67.306137 -13.009718)
			(xy 67.31506 -13.06751) (xy 67.315588 -13.096748) (xy 67.315167 -13.124001) (xy 67.307403 -13.177952)
			(xy 67.292041 -13.23025) (xy 67.269393 -13.279828) (xy 67.23992 -13.325679) (xy 67.204221 -13.36687)
			(xy 67.163025 -13.40256) (xy 67.117169 -13.432025) (xy 67.067586 -13.454665) (xy 67.015286 -13.470018)
			(xy 66.961333 -13.477772) (xy 66.93408 -13.478256) (xy 66.906709 -13.477812) (xy 66.852528 -13.469991)
			(xy 66.800025 -13.454497) (xy 66.750278 -13.43165) (xy 66.704313 -13.40192) (xy 66.683382 -13.384276)
			(xy 66.672054 -13.37504) (xy 66.645497 -13.362864) (xy 66.61658 -13.358691) (xy 66.587663 -13.362864)
			(xy 66.561106 -13.37504) (xy 66.549778 -13.384276) (xy 66.528824 -13.401888) (xy 66.482858 -13.431605)
			(xy 66.433116 -13.454446) (xy 66.38062 -13.469944) (xy 66.326448 -13.477779) (xy 66.29908 -13.478256)
			(xy 66.27183 -13.477741) (xy 66.217886 -13.469983) (xy 66.165595 -13.454628) (xy 66.116021 -13.431988)
			(xy 66.070173 -13.402524) (xy 66.028984 -13.366836) (xy 65.993293 -13.32565) (xy 65.963826 -13.279804)
			(xy 65.941182 -13.230231) (xy 65.925823 -13.177941) (xy 65.918061 -13.123998) (xy 65.917572 -13.096748)
			(xy 65.918053 -13.069533) (xy 65.925799 -13.015658) (xy 65.941128 -12.963432) (xy 65.963726 -12.913915)
			(xy 65.978024 -12.890754) (xy 65.982915 -12.882253) (xy 65.98663 -12.863022) (xy 65.982857 -12.843802)
			(xy 65.972146 -12.827403) (xy 65.956064 -12.816222) (xy 65.936962 -12.811894) (xy 65.927224 -12.81303)
			(xy 65.912339 -12.815273) (xy 65.882332 -12.81769) (xy 65.86728 -12.817856) (xy 65.861184 -12.817856)
			(xy 65.846898 -12.81817) (xy 65.819324 -12.825596) (xy 65.794885 -12.840367) (xy 65.775493 -12.86133)
			(xy 65.762665 -12.886842) (xy 65.757405 -12.91491) (xy 65.760123 -12.943337) (xy 65.764918 -12.956794)
			(xy 65.773337 -12.979158) (xy 65.785198 -13.025448) (xy 65.791197 -13.072855) (xy 65.791588 -13.096748)
			(xy 65.791102 -13.123999) (xy 65.783346 -13.177947) (xy 65.767991 -13.230242) (xy 65.745349 -13.279819)
			(xy 65.715883 -13.325669) (xy 65.680192 -13.36686) (xy 65.639001 -13.402551) (xy 65.593151 -13.432017)
			(xy 65.543574 -13.454659) (xy 65.491279 -13.470014) (xy 65.437331 -13.47777) (xy 65.382829 -13.47777)
			(xy 65.328881 -13.470014) (xy 65.276586 -13.454659) (xy 65.227009 -13.432017) (xy 65.181159 -13.402551)
			(xy 65.139968 -13.36686) (xy 65.104277 -13.325669) (xy 65.074811 -13.279819) (xy 65.052169 -13.230242)
			(xy 65.036814 -13.177947) (xy 65.029058 -13.123999) (xy 65.028572 -13.096748) (xy 65.029053 -13.069533)
			(xy 65.036799 -13.015658) (xy 65.052128 -12.963432) (xy 65.074726 -12.913915) (xy 65.089024 -12.890754)
			(xy 65.093915 -12.882253) (xy 65.09763 -12.863022) (xy 65.093857 -12.843802) (xy 65.083146 -12.827403)
			(xy 65.067064 -12.816222) (xy 65.047962 -12.811894) (xy 65.038224 -12.81303) (xy 65.023339 -12.815273)
			(xy 64.993332 -12.81769) (xy 64.97828 -12.817856) (xy 64.972184 -12.817856) (xy 64.957898 -12.81817)
			(xy 64.930324 -12.825596) (xy 64.905885 -12.840367) (xy 64.886493 -12.86133) (xy 64.873665 -12.886842)
			(xy 64.868405 -12.91491) (xy 64.871123 -12.943337) (xy 64.875918 -12.956794) (xy 64.884337 -12.979158)
			(xy 64.896198 -13.025448) (xy 64.902197 -13.072855) (xy 64.902588 -13.096748) (xy 64.902102 -13.123999)
			(xy 64.894346 -13.177947) (xy 64.878991 -13.230242) (xy 64.856349 -13.279819) (xy 64.826883 -13.325669)
			(xy 64.791192 -13.36686) (xy 64.750001 -13.402551) (xy 64.704151 -13.432017) (xy 64.654574 -13.454659)
			(xy 64.602279 -13.470014) (xy 64.548331 -13.47777) (xy 64.493829 -13.47777) (xy 64.439881 -13.470014)
			(xy 64.387586 -13.454659) (xy 64.338009 -13.432017) (xy 64.292159 -13.402551) (xy 64.250968 -13.36686)
			(xy 64.215277 -13.325669) (xy 64.185811 -13.279819) (xy 64.163169 -13.230242) (xy 64.147814 -13.177947)
			(xy 64.140058 -13.123999) (xy 64.139572 -13.096748) (xy 64.140053 -13.069533) (xy 64.147799 -13.015658)
			(xy 64.163128 -12.963432) (xy 64.185726 -12.913915) (xy 64.200024 -12.890754) (xy 64.204915 -12.882253)
			(xy 64.20863 -12.863022) (xy 64.204857 -12.843802) (xy 64.194146 -12.827403) (xy 64.178064 -12.816222)
			(xy 64.158962 -12.811894) (xy 64.149224 -12.81303) (xy 64.134339 -12.815273) (xy 64.104332 -12.81769)
			(xy 64.08928 -12.817856) (xy 64.083184 -12.817856) (xy 64.068898 -12.81817) (xy 64.041324 -12.825596)
			(xy 64.016885 -12.840367) (xy 63.997493 -12.86133) (xy 63.984665 -12.886842) (xy 63.979405 -12.91491)
			(xy 63.982123 -12.943337) (xy 63.986918 -12.956794) (xy 63.995337 -12.979158) (xy 64.007198 -13.025448)
			(xy 64.013197 -13.072855) (xy 64.013588 -13.096748) (xy 64.013102 -13.123999) (xy 64.005346 -13.177947)
			(xy 63.989991 -13.230242) (xy 63.967349 -13.279819) (xy 63.937883 -13.325669) (xy 63.902192 -13.36686)
			(xy 63.861001 -13.402551) (xy 63.815151 -13.432017) (xy 63.765574 -13.454659) (xy 63.713279 -13.470014)
			(xy 63.659331 -13.47777) (xy 63.604829 -13.47777) (xy 63.550881 -13.470014) (xy 63.498586 -13.454659)
			(xy 63.449009 -13.432017) (xy 63.403159 -13.402551) (xy 63.361968 -13.36686) (xy 63.326277 -13.325669)
			(xy 63.296811 -13.279819) (xy 63.274169 -13.230242) (xy 63.258814 -13.177947) (xy 63.251058 -13.123999)
			(xy 63.250572 -13.096748) (xy 63.250934 -13.072811) (xy 63.256904 -13.025311) (xy 63.26878 -12.978934)
			(xy 63.277242 -12.95654) (xy 63.281898 -12.943447) (xy 63.284793 -12.915824) (xy 63.280132 -12.888444)
			(xy 63.26826 -12.863335) (xy 63.250058 -12.842356) (xy 63.226874 -12.827063) (xy 63.200424 -12.818588)
			(xy 63.186564 -12.817602) (xy 63.159965 -12.816259) (xy 63.107525 -12.806957) (xy 63.056887 -12.790451)
			(xy 63.009038 -12.767063) (xy 62.964907 -12.737248) (xy 62.925351 -12.701584) (xy 62.89114 -12.660765)
			(xy 62.862939 -12.615585) (xy 62.841296 -12.566921) (xy 62.826632 -12.51572) (xy 62.819232 -12.462978)
			(xy 62.818772 -12.436348) (xy 61.93028 -12.436348) (xy 63.60668 -14.112748) (xy 63.60668 -14.315948)
			(xy 66.856862 -14.315948) (xy 66.860933 -14.260326) (xy 66.873059 -14.205889) (xy 66.892982 -14.153798)
			(xy 66.920278 -14.105163) (xy 66.954364 -14.06102) (xy 66.994513 -14.022311) (xy 67.039871 -13.98986)
			(xy 67.089471 -13.964359) (xy 67.142255 -13.946352) (xy 67.197098 -13.936222) (xy 67.252832 -13.934185)
			(xy 67.308269 -13.940285) (xy 67.362226 -13.954391) (xy 67.413555 -13.976203) (xy 67.461161 -14.005257)
			(xy 67.504029 -14.040932) (xy 67.541246 -14.082469) (xy 67.572019 -14.128982) (xy 67.595691 -14.179479)
			(xy 67.611759 -14.232886) (xy 67.619879 -14.288062) (xy 67.620388 -14.315948) (xy 67.619879 -14.343834)
			(xy 67.611759 -14.39901) (xy 67.595691 -14.452417) (xy 67.572019 -14.502914) (xy 67.541246 -14.549427)
			(xy 67.504029 -14.590964) (xy 67.461161 -14.626639) (xy 67.413555 -14.655693) (xy 67.362226 -14.677505)
			(xy 67.308269 -14.691611) (xy 67.252832 -14.697711) (xy 67.197098 -14.695674) (xy 67.142255 -14.685544)
			(xy 67.089471 -14.667537) (xy 67.039871 -14.642036) (xy 66.994513 -14.609585) (xy 66.954364 -14.570876)
			(xy 66.920278 -14.526733) (xy 66.892982 -14.478098) (xy 66.873059 -14.426007) (xy 66.860933 -14.37157)
			(xy 66.856862 -14.315948) (xy 63.60668 -14.315948) (xy 63.60668 -15.331948) (xy 66.856862 -15.331948)
			(xy 66.860933 -15.276326) (xy 66.873059 -15.221889) (xy 66.892982 -15.169798) (xy 66.920278 -15.121163)
			(xy 66.954364 -15.07702) (xy 66.994513 -15.038311) (xy 67.039871 -15.00586) (xy 67.089471 -14.980359)
			(xy 67.142255 -14.962352) (xy 67.197098 -14.952222) (xy 67.252832 -14.950185) (xy 67.308269 -14.956285)
			(xy 67.362226 -14.970391) (xy 67.413555 -14.992203) (xy 67.461161 -15.021257) (xy 67.504029 -15.056932)
			(xy 67.541246 -15.098469) (xy 67.572019 -15.144982) (xy 67.595691 -15.195479) (xy 67.611759 -15.248886)
			(xy 67.612769 -15.255748) (xy 72.719182 -15.255748) (xy 72.723253 -15.200126) (xy 72.735379 -15.145689)
			(xy 72.755302 -15.093598) (xy 72.782598 -15.044963) (xy 72.816684 -15.00082) (xy 72.856833 -14.962111)
			(xy 72.902191 -14.92966) (xy 72.951791 -14.904159) (xy 73.004575 -14.886152) (xy 73.059418 -14.876022)
			(xy 73.115152 -14.873985) (xy 73.170589 -14.880085) (xy 73.224546 -14.894191) (xy 73.275875 -14.916003)
			(xy 73.323481 -14.945057) (xy 73.366349 -14.980732) (xy 73.403566 -15.022269) (xy 73.434339 -15.068782)
			(xy 73.458011 -15.119279) (xy 73.474079 -15.172686) (xy 73.482199 -15.227862) (xy 73.482708 -15.255748)
			(xy 73.482199 -15.283634) (xy 73.474079 -15.33881) (xy 73.458011 -15.392217) (xy 73.434339 -15.442714)
			(xy 73.403566 -15.489227) (xy 73.366349 -15.530764) (xy 73.323481 -15.566439) (xy 73.275875 -15.595493)
			(xy 73.224546 -15.617305) (xy 73.170589 -15.631411) (xy 73.115152 -15.637511) (xy 73.059418 -15.635474)
			(xy 73.004575 -15.625344) (xy 72.951791 -15.607337) (xy 72.902191 -15.581836) (xy 72.856833 -15.549385)
			(xy 72.816684 -15.510676) (xy 72.782598 -15.466533) (xy 72.755302 -15.417898) (xy 72.735379 -15.365807)
			(xy 72.723253 -15.31137) (xy 72.719182 -15.255748) (xy 67.612769 -15.255748) (xy 67.619879 -15.304062)
			(xy 67.620388 -15.331948) (xy 67.619879 -15.359834) (xy 67.611759 -15.41501) (xy 67.595691 -15.468417)
			(xy 67.572019 -15.518914) (xy 67.541246 -15.565427) (xy 67.504029 -15.606964) (xy 67.461161 -15.642639)
			(xy 67.413555 -15.671693) (xy 67.362226 -15.693505) (xy 67.308269 -15.707611) (xy 67.252832 -15.713711)
			(xy 67.197098 -15.711674) (xy 67.142255 -15.701544) (xy 67.089471 -15.683537) (xy 67.039871 -15.658036)
			(xy 66.994513 -15.625585) (xy 66.954364 -15.586876) (xy 66.920278 -15.542733) (xy 66.892982 -15.494098)
			(xy 66.873059 -15.442007) (xy 66.860933 -15.38757) (xy 66.856862 -15.331948) (xy 63.60668 -15.331948)
			(xy 63.60668 -16.347948) (xy 66.856862 -16.347948) (xy 66.860933 -16.292326) (xy 66.873059 -16.237889)
			(xy 66.892982 -16.185798) (xy 66.920278 -16.137163) (xy 66.954364 -16.09302) (xy 66.994513 -16.054311)
			(xy 67.039871 -16.02186) (xy 67.089471 -15.996359) (xy 67.142255 -15.978352) (xy 67.197098 -15.968222)
			(xy 67.252832 -15.966185) (xy 67.308269 -15.972285) (xy 67.362226 -15.986391) (xy 67.413555 -16.008203)
			(xy 67.461161 -16.037257) (xy 67.504029 -16.072932) (xy 67.541246 -16.114469) (xy 67.572019 -16.160982)
			(xy 67.595691 -16.211479) (xy 67.611759 -16.264886) (xy 67.619879 -16.320062) (xy 67.620388 -16.347948)
			(xy 67.619879 -16.375834) (xy 67.611759 -16.43101) (xy 67.595691 -16.484417) (xy 67.572019 -16.534914)
			(xy 67.541246 -16.581427) (xy 67.504029 -16.622964) (xy 67.461161 -16.658639) (xy 67.413555 -16.687693)
			(xy 67.362226 -16.709505) (xy 67.308269 -16.723611) (xy 67.252832 -16.729711) (xy 67.197098 -16.727674)
			(xy 67.142255 -16.717544) (xy 67.089471 -16.699537) (xy 67.039871 -16.674036) (xy 66.994513 -16.641585)
			(xy 66.954364 -16.602876) (xy 66.920278 -16.558733) (xy 66.892982 -16.510098) (xy 66.873059 -16.458007)
			(xy 66.860933 -16.40357) (xy 66.856862 -16.347948) (xy 63.60668 -16.347948) (xy 63.60668 -17.148302)
			(xy 74.02525 -17.148302) (xy 74.029321 -17.09268) (xy 74.041447 -17.038243) (xy 74.06137 -16.986152)
			(xy 74.088666 -16.937517) (xy 74.122752 -16.893374) (xy 74.162901 -16.854665) (xy 74.208259 -16.822214)
			(xy 74.257859 -16.796713) (xy 74.310643 -16.778706) (xy 74.365486 -16.768576) (xy 74.42122 -16.766539)
			(xy 74.476657 -16.772639) (xy 74.530614 -16.786745) (xy 74.581943 -16.808557) (xy 74.629549 -16.837611)
			(xy 74.672417 -16.873286) (xy 74.709634 -16.914823) (xy 74.740407 -16.961336) (xy 74.764079 -17.011833)
			(xy 74.780147 -17.06524) (xy 74.788267 -17.120416) (xy 74.788776 -17.148302) (xy 74.788267 -17.176188)
			(xy 74.780147 -17.231364) (xy 74.764079 -17.284771) (xy 74.740407 -17.335268) (xy 74.709634 -17.381781)
			(xy 74.672417 -17.423318) (xy 74.629549 -17.458993) (xy 74.581943 -17.488047) (xy 74.530614 -17.509859)
			(xy 74.476657 -17.523965) (xy 74.42122 -17.530065) (xy 74.365486 -17.528028) (xy 74.310643 -17.517898)
			(xy 74.257859 -17.499891) (xy 74.208259 -17.47439) (xy 74.162901 -17.441939) (xy 74.122752 -17.40323)
			(xy 74.088666 -17.359087) (xy 74.06137 -17.310452) (xy 74.041447 -17.258361) (xy 74.029321 -17.203924)
			(xy 74.02525 -17.148302) (xy 63.60668 -17.148302) (xy 63.60668 -17.326356) (xy 63.635636 -17.340072)
			(xy 63.659613 -17.352082) (xy 63.704237 -17.381821) (xy 63.74426 -17.417513) (xy 63.778893 -17.458456)
			(xy 63.807454 -17.503843) (xy 63.829381 -17.552781) (xy 63.844242 -17.604307) (xy 63.851746 -17.657405)
			(xy 63.851743 -17.711031) (xy 63.844235 -17.764129) (xy 63.829368 -17.815653) (xy 63.807437 -17.864589)
			(xy 63.778871 -17.909973) (xy 63.744235 -17.950913) (xy 63.704209 -17.986601) (xy 63.659582 -18.016336)
			(xy 63.635636 -18.028412) (xy 63.60668 -18.042128) (xy 63.60668 -18.297144) (xy 67.30873 -18.297144)
			(xy 67.309215 -18.269774) (xy 67.317027 -18.215596) (xy 67.332511 -18.163093) (xy 67.355349 -18.113345)
			(xy 67.38507 -18.067378) (xy 67.40271 -18.046446) (xy 67.411904 -18.035087) (xy 67.424085 -18.00854)
			(xy 67.428265 -17.979633) (xy 67.424104 -17.950724) (xy 67.41194 -17.924169) (xy 67.40271 -17.912842)
			(xy 67.385079 -17.891904) (xy 67.355365 -17.845933) (xy 67.332528 -17.796187) (xy 67.317035 -17.743687)
			(xy 67.309205 -17.689513) (xy 67.30873 -17.662144) (xy 67.309216 -17.634893) (xy 67.316972 -17.580945)
			(xy 67.332327 -17.52865) (xy 67.354969 -17.479073) (xy 67.384435 -17.433223) (xy 67.420126 -17.392032)
			(xy 67.461317 -17.356341) (xy 67.507167 -17.326875) (xy 67.556744 -17.304233) (xy 67.609039 -17.288878)
			(xy 67.662987 -17.281122) (xy 67.717489 -17.281122) (xy 67.771437 -17.288878) (xy 67.823732 -17.304233)
			(xy 67.873309 -17.326875) (xy 67.919159 -17.356341) (xy 67.96035 -17.392032) (xy 67.996041 -17.433223)
			(xy 68.025507 -17.479073) (xy 68.048149 -17.52865) (xy 68.063504 -17.580945) (xy 68.07126 -17.634893)
			(xy 68.071746 -17.662144) (xy 68.07126 -17.689514) (xy 68.063449 -17.743692) (xy 68.047965 -17.796196)
			(xy 68.025128 -17.845943) (xy 67.995406 -17.89191) (xy 67.977766 -17.912842) (xy 67.968489 -17.924139)
			(xy 67.956321 -17.950708) (xy 67.952159 -17.979633) (xy 67.95634 -18.008556) (xy 67.968526 -18.035117)
			(xy 67.977766 -18.046446) (xy 67.995388 -18.067392) (xy 68.025104 -18.11336) (xy 68.04686 -18.160746)
			(xy 74.02525 -18.160746) (xy 74.029321 -18.105124) (xy 74.041447 -18.050687) (xy 74.06137 -17.998596)
			(xy 74.088666 -17.949961) (xy 74.122752 -17.905818) (xy 74.162901 -17.867109) (xy 74.208259 -17.834658)
			(xy 74.257859 -17.809157) (xy 74.310643 -17.79115) (xy 74.365486 -17.78102) (xy 74.42122 -17.778983)
			(xy 74.476657 -17.785083) (xy 74.530614 -17.799189) (xy 74.581943 -17.821001) (xy 74.629549 -17.850055)
			(xy 74.672417 -17.88573) (xy 74.709634 -17.927267) (xy 74.740407 -17.97378) (xy 74.764079 -18.024277)
			(xy 74.780147 -18.077684) (xy 74.788267 -18.13286) (xy 74.788776 -18.160746) (xy 74.788267 -18.188632)
			(xy 74.780147 -18.243808) (xy 74.764079 -18.297215) (xy 74.740407 -18.347712) (xy 74.709634 -18.394225)
			(xy 74.672417 -18.435762) (xy 74.629549 -18.471437) (xy 74.581943 -18.500491) (xy 74.530614 -18.522303)
			(xy 74.476657 -18.536409) (xy 74.42122 -18.542509) (xy 74.365486 -18.540472) (xy 74.310643 -18.530342)
			(xy 74.257859 -18.512335) (xy 74.208259 -18.486834) (xy 74.162901 -18.454383) (xy 74.122752 -18.415674)
			(xy 74.088666 -18.371531) (xy 74.06137 -18.322896) (xy 74.041447 -18.270805) (xy 74.029321 -18.216368)
			(xy 74.02525 -18.160746) (xy 68.04686 -18.160746) (xy 68.047943 -18.163104) (xy 68.063438 -18.215602)
			(xy 68.07127 -18.269776) (xy 68.071746 -18.297144) (xy 68.07126 -18.324395) (xy 68.063504 -18.378343)
			(xy 68.048149 -18.430638) (xy 68.025507 -18.480215) (xy 67.996041 -18.526065) (xy 67.96035 -18.567256)
			(xy 67.919159 -18.602947) (xy 67.873309 -18.632413) (xy 67.823732 -18.655055) (xy 67.771437 -18.67041)
			(xy 67.717489 -18.678166) (xy 67.662987 -18.678166) (xy 67.609039 -18.67041) (xy 67.556744 -18.655055)
			(xy 67.507167 -18.632413) (xy 67.461317 -18.602947) (xy 67.420126 -18.567256) (xy 67.384435 -18.526065)
			(xy 67.354969 -18.480215) (xy 67.332327 -18.430638) (xy 67.316972 -18.378343) (xy 67.309216 -18.324395)
			(xy 67.30873 -18.297144) (xy 63.60668 -18.297144) (xy 63.60668 -19.220942) (xy 76.404722 -19.220942)
			(xy 76.408793 -19.16532) (xy 76.420919 -19.110883) (xy 76.440842 -19.058792) (xy 76.468138 -19.010157)
			(xy 76.502224 -18.966014) (xy 76.542373 -18.927305) (xy 76.587731 -18.894854) (xy 76.637331 -18.869353)
			(xy 76.690115 -18.851346) (xy 76.744958 -18.841216) (xy 76.800692 -18.839179) (xy 76.856129 -18.845279)
			(xy 76.910086 -18.859385) (xy 76.961415 -18.881197) (xy 77.009021 -18.910251) (xy 77.051889 -18.945926)
			(xy 77.089106 -18.987463) (xy 77.119879 -19.033976) (xy 77.143551 -19.084473) (xy 77.159619 -19.13788)
			(xy 77.167739 -19.193056) (xy 77.168248 -19.220942) (xy 77.167739 -19.248828) (xy 77.159619 -19.304004)
			(xy 77.143551 -19.357411) (xy 77.119879 -19.407908) (xy 77.089106 -19.454421) (xy 77.051889 -19.495958)
			(xy 77.009021 -19.531633) (xy 76.961415 -19.560687) (xy 76.910086 -19.582499) (xy 76.856129 -19.596605)
			(xy 76.800692 -19.602705) (xy 76.744958 -19.600668) (xy 76.690115 -19.590538) (xy 76.637331 -19.572531)
			(xy 76.587731 -19.54703) (xy 76.542373 -19.514579) (xy 76.502224 -19.47587) (xy 76.468138 -19.431727)
			(xy 76.440842 -19.383092) (xy 76.420919 -19.331001) (xy 76.408793 -19.276564) (xy 76.404722 -19.220942)
			(xy 63.60668 -19.220942) (xy 63.60668 -20.326604) (xy 67.33413 -20.326604) (xy 67.334591 -20.299234)
			(xy 67.342409 -20.245054) (xy 67.357899 -20.19255) (xy 67.380742 -20.142804) (xy 67.410468 -20.096837)
			(xy 67.42811 -20.075906) (xy 67.437342 -20.064576) (xy 67.449519 -20.038019) (xy 67.453692 -20.009103)
			(xy 67.449521 -19.980187) (xy 67.437345 -19.95363) (xy 67.42811 -19.942302) (xy 67.41046 -19.921379)
			(xy 67.380749 -19.875404) (xy 67.357915 -19.825654) (xy 67.342427 -19.773151) (xy 67.334602 -19.718974)
			(xy 67.33413 -19.691604) (xy 67.334616 -19.664353) (xy 67.342372 -19.610405) (xy 67.357727 -19.55811)
			(xy 67.380369 -19.508533) (xy 67.409835 -19.462683) (xy 67.445526 -19.421492) (xy 67.486717 -19.385801)
			(xy 67.532567 -19.356335) (xy 67.582144 -19.333693) (xy 67.634439 -19.318338) (xy 67.688387 -19.310582)
			(xy 67.742889 -19.310582) (xy 67.796837 -19.318338) (xy 67.849132 -19.333693) (xy 67.898709 -19.356335)
			(xy 67.944559 -19.385801) (xy 67.98575 -19.421492) (xy 68.021441 -19.462683) (xy 68.050907 -19.508533)
			(xy 68.073549 -19.55811) (xy 68.088904 -19.610405) (xy 68.09666 -19.664353) (xy 68.097146 -19.691604)
			(xy 68.096695 -19.718975) (xy 68.088876 -19.773155) (xy 68.073384 -19.825659) (xy 68.050538 -19.875406)
			(xy 68.02081 -19.921371) (xy 68.003166 -19.942302) (xy 67.993928 -19.953628) (xy 67.992134 -19.957542)
			(xy 74.15352 -19.957542) (xy 74.157591 -19.90192) (xy 74.169717 -19.847483) (xy 74.18964 -19.795392)
			(xy 74.216936 -19.746757) (xy 74.251022 -19.702614) (xy 74.291171 -19.663905) (xy 74.336529 -19.631454)
			(xy 74.386129 -19.605953) (xy 74.438913 -19.587946) (xy 74.493756 -19.577816) (xy 74.54949 -19.575779)
			(xy 74.604927 -19.581879) (xy 74.658884 -19.595985) (xy 74.710213 -19.617797) (xy 74.757819 -19.646851)
			(xy 74.800687 -19.682526) (xy 74.837904 -19.724063) (xy 74.868677 -19.770576) (xy 74.892349 -19.821073)
			(xy 74.908417 -19.87448) (xy 74.916537 -19.929656) (xy 74.917046 -19.957542) (xy 74.916537 -19.985428)
			(xy 74.908417 -20.040604) (xy 74.892349 -20.094011) (xy 74.868677 -20.144508) (xy 74.856739 -20.162552)
			(xy 75.805497 -20.162552) (xy 75.805497 -20.108048) (xy 75.813254 -20.0541) (xy 75.828611 -20.001805)
			(xy 75.851253 -19.952228) (xy 75.880722 -19.906378) (xy 75.916416 -19.865189) (xy 75.957608 -19.829499)
			(xy 76.003461 -19.800035) (xy 76.053041 -19.777397) (xy 76.105337 -19.762046) (xy 76.159286 -19.754295)
			(xy 76.186538 -19.753834) (xy 76.213406 -19.754243) (xy 76.266611 -19.761777) (xy 76.318232 -19.776704)
			(xy 76.367247 -19.798728) (xy 76.412685 -19.827414) (xy 76.453647 -19.862194) (xy 76.489322 -19.902379)
			(xy 76.504546 -19.924522) (xy 76.512535 -19.935871) (xy 76.5335 -19.954042) (xy 76.558586 -19.965892)
			(xy 76.585938 -19.970543) (xy 76.613531 -19.96765) (xy 76.639324 -19.957428) (xy 76.661408 -19.940634)
			(xy 76.670154 -19.929856) (xy 76.688315 -19.906862) (xy 76.730491 -19.86619) (xy 76.778389 -19.832443)
			(xy 76.830882 -19.806414) (xy 76.886738 -19.788717) (xy 76.944642 -19.779766) (xy 76.973938 -19.779234)
			(xy 77.00119 -19.779638) (xy 77.05514 -19.7874) (xy 77.107436 -19.80276) (xy 77.157014 -19.825406)
			(xy 77.202865 -19.854877) (xy 77.244055 -19.890572) (xy 77.279746 -19.931766) (xy 77.309212 -19.97762)
			(xy 77.331853 -20.0272) (xy 77.347208 -20.079497) (xy 77.354964 -20.133447) (xy 77.354964 -20.187953)
			(xy 77.347208 -20.241903) (xy 77.331853 -20.2942) (xy 77.309212 -20.34378) (xy 77.279746 -20.389634)
			(xy 77.244055 -20.430828) (xy 77.202865 -20.466523) (xy 77.157014 -20.495994) (xy 77.107436 -20.51864)
			(xy 77.05514 -20.534) (xy 77.00119 -20.541762) (xy 76.973938 -20.54225) (xy 76.947072 -20.54179)
			(xy 76.893869 -20.534266) (xy 76.842249 -20.519349) (xy 76.793234 -20.497333) (xy 76.747794 -20.468655)
			(xy 76.706831 -20.433882) (xy 76.671154 -20.393703) (xy 76.65593 -20.371562) (xy 76.647848 -20.360286)
			(xy 76.626902 -20.34212) (xy 76.601836 -20.330268) (xy 76.574504 -20.32561) (xy 76.546928 -20.328488)
			(xy 76.521147 -20.33869) (xy 76.499068 -20.355462) (xy 76.490322 -20.366228) (xy 76.47217 -20.38923)
			(xy 76.429993 -20.429903) (xy 76.382094 -20.463649) (xy 76.329598 -20.489676) (xy 76.273741 -20.507372)
			(xy 76.215835 -20.51632) (xy 76.186538 -20.51685) (xy 76.159286 -20.516305) (xy 76.105337 -20.508554)
			(xy 76.053041 -20.493203) (xy 76.003461 -20.470565) (xy 75.957608 -20.441101) (xy 75.916416 -20.405411)
			(xy 75.880722 -20.364222) (xy 75.851253 -20.318372) (xy 75.828611 -20.268795) (xy 75.813254 -20.2165)
			(xy 75.805497 -20.162552) (xy 74.856739 -20.162552) (xy 74.837904 -20.191021) (xy 74.800687 -20.232558)
			(xy 74.757819 -20.268233) (xy 74.710213 -20.297287) (xy 74.658884 -20.319099) (xy 74.604927 -20.333205)
			(xy 74.54949 -20.339305) (xy 74.493756 -20.337268) (xy 74.438913 -20.327138) (xy 74.386129 -20.309131)
			(xy 74.336529 -20.28363) (xy 74.291171 -20.251179) (xy 74.251022 -20.21247) (xy 74.216936 -20.168327)
			(xy 74.18964 -20.119692) (xy 74.169717 -20.067601) (xy 74.157591 -20.013164) (xy 74.15352 -19.957542)
			(xy 67.992134 -19.957542) (xy 67.981755 -19.980187) (xy 67.977585 -20.009103) (xy 67.981757 -20.038019)
			(xy 67.993931 -20.064578) (xy 68.003166 -20.075906) (xy 68.020816 -20.096829) (xy 68.050527 -20.142804)
			(xy 68.073362 -20.192554) (xy 68.08885 -20.245056) (xy 68.096674 -20.299234) (xy 68.097146 -20.326604)
			(xy 68.09666 -20.353855) (xy 68.088904 -20.407803) (xy 68.073549 -20.460098) (xy 68.050907 -20.509675)
			(xy 68.021441 -20.555525) (xy 67.98575 -20.596716) (xy 67.944559 -20.632407) (xy 67.898709 -20.661873)
			(xy 67.849132 -20.684515) (xy 67.796837 -20.69987) (xy 67.742889 -20.707626) (xy 67.688387 -20.707626)
			(xy 67.634439 -20.69987) (xy 67.582144 -20.684515) (xy 67.532567 -20.661873) (xy 67.486717 -20.632407)
			(xy 67.445526 -20.596716) (xy 67.409835 -20.555525) (xy 67.380369 -20.509675) (xy 67.357727 -20.460098)
			(xy 67.342372 -20.407803) (xy 67.334616 -20.353855) (xy 67.33413 -20.326604) (xy 63.60668 -20.326604)
			(xy 63.60668 -20.950682) (xy 74.15479 -20.950682) (xy 74.158861 -20.89506) (xy 74.170987 -20.840623)
			(xy 74.19091 -20.788532) (xy 74.218206 -20.739897) (xy 74.252292 -20.695754) (xy 74.292441 -20.657045)
			(xy 74.337799 -20.624594) (xy 74.387399 -20.599093) (xy 74.440183 -20.581086) (xy 74.495026 -20.570956)
			(xy 74.55076 -20.568919) (xy 74.606197 -20.575019) (xy 74.660154 -20.589125) (xy 74.711483 -20.610937)
			(xy 74.759089 -20.639991) (xy 74.801957 -20.675666) (xy 74.839174 -20.717203) (xy 74.869947 -20.763716)
			(xy 74.893619 -20.814213) (xy 74.909687 -20.86762) (xy 74.917807 -20.922796) (xy 74.918195 -20.944078)
			(xy 76.224382 -20.944078) (xy 76.228453 -20.888456) (xy 76.240579 -20.834019) (xy 76.260502 -20.781928)
			(xy 76.287798 -20.733293) (xy 76.321884 -20.68915) (xy 76.362033 -20.650441) (xy 76.407391 -20.61799)
			(xy 76.456991 -20.592489) (xy 76.509775 -20.574482) (xy 76.564618 -20.564352) (xy 76.620352 -20.562315)
			(xy 76.675789 -20.568415) (xy 76.729746 -20.582521) (xy 76.781075 -20.604333) (xy 76.828681 -20.633387)
			(xy 76.871549 -20.669062) (xy 76.908766 -20.710599) (xy 76.939539 -20.757112) (xy 76.963211 -20.807609)
			(xy 76.979279 -20.861016) (xy 76.987399 -20.916192) (xy 76.987908 -20.944078) (xy 76.987399 -20.971964)
			(xy 76.979279 -21.02714) (xy 76.963211 -21.080547) (xy 76.939539 -21.131044) (xy 76.908766 -21.177557)
			(xy 76.871549 -21.219094) (xy 76.828681 -21.254769) (xy 76.781075 -21.283823) (xy 76.729746 -21.305635)
			(xy 76.675789 -21.319741) (xy 76.620352 -21.325841) (xy 76.564618 -21.323804) (xy 76.509775 -21.313674)
			(xy 76.456991 -21.295667) (xy 76.407391 -21.270166) (xy 76.362033 -21.237715) (xy 76.321884 -21.199006)
			(xy 76.287798 -21.154863) (xy 76.260502 -21.106228) (xy 76.240579 -21.054137) (xy 76.228453 -20.9997)
			(xy 76.224382 -20.944078) (xy 74.918195 -20.944078) (xy 74.918316 -20.950682) (xy 74.917807 -20.978568)
			(xy 74.909687 -21.033744) (xy 74.893619 -21.087151) (xy 74.869947 -21.137648) (xy 74.839174 -21.184161)
			(xy 74.801957 -21.225698) (xy 74.759089 -21.261373) (xy 74.711483 -21.290427) (xy 74.660154 -21.312239)
			(xy 74.606197 -21.326345) (xy 74.55076 -21.332445) (xy 74.495026 -21.330408) (xy 74.440183 -21.320278)
			(xy 74.387399 -21.302271) (xy 74.337799 -21.27677) (xy 74.292441 -21.244319) (xy 74.252292 -21.20561)
			(xy 74.218206 -21.161467) (xy 74.19091 -21.112832) (xy 74.170987 -21.060741) (xy 74.158861 -21.006304)
			(xy 74.15479 -20.950682) (xy 63.60668 -20.950682) (xy 63.60668 -21.839682) (xy 74.15479 -21.839682)
			(xy 74.158861 -21.78406) (xy 74.170987 -21.729623) (xy 74.19091 -21.677532) (xy 74.218206 -21.628897)
			(xy 74.252292 -21.584754) (xy 74.292441 -21.546045) (xy 74.337799 -21.513594) (xy 74.387399 -21.488093)
			(xy 74.440183 -21.470086) (xy 74.495026 -21.459956) (xy 74.55076 -21.457919) (xy 74.606197 -21.464019)
			(xy 74.660154 -21.478125) (xy 74.711483 -21.499937) (xy 74.759089 -21.528991) (xy 74.801957 -21.564666)
			(xy 74.839174 -21.606203) (xy 74.869947 -21.652716) (xy 74.893619 -21.703213) (xy 74.909687 -21.75662)
			(xy 74.917807 -21.811796) (xy 74.918316 -21.839682) (xy 74.917807 -21.867568) (xy 74.909687 -21.922744)
			(xy 74.893619 -21.976151) (xy 74.869947 -22.026648) (xy 74.839174 -22.073161) (xy 74.801957 -22.114698)
			(xy 74.759089 -22.150373) (xy 74.711483 -22.179427) (xy 74.660154 -22.201239) (xy 74.606197 -22.215345)
			(xy 74.55076 -22.221445) (xy 74.495026 -22.219408) (xy 74.440183 -22.209278) (xy 74.387399 -22.191271)
			(xy 74.337799 -22.16577) (xy 74.292441 -22.133319) (xy 74.252292 -22.09461) (xy 74.218206 -22.050467)
			(xy 74.19091 -22.001832) (xy 74.170987 -21.949741) (xy 74.158861 -21.895304) (xy 74.15479 -21.839682)
			(xy 63.60668 -21.839682) (xy 63.60668 -22.266148) (xy 66.501262 -22.266148) (xy 66.505333 -22.210526)
			(xy 66.517459 -22.156089) (xy 66.537382 -22.103998) (xy 66.564678 -22.055363) (xy 66.598764 -22.01122)
			(xy 66.638913 -21.972511) (xy 66.684271 -21.94006) (xy 66.733871 -21.914559) (xy 66.786655 -21.896552)
			(xy 66.841498 -21.886422) (xy 66.897232 -21.884385) (xy 66.952669 -21.890485) (xy 67.006626 -21.904591)
			(xy 67.057955 -21.926403) (xy 67.105561 -21.955457) (xy 67.148429 -21.991132) (xy 67.185646 -22.032669)
			(xy 67.216419 -22.079182) (xy 67.240091 -22.129679) (xy 67.256159 -22.183086) (xy 67.264279 -22.238262)
			(xy 67.264788 -22.266148) (xy 67.264279 -22.294034) (xy 67.256159 -22.34921) (xy 67.240091 -22.402617)
			(xy 67.216419 -22.453114) (xy 67.185646 -22.499627) (xy 67.148429 -22.541164) (xy 67.105561 -22.576839)
			(xy 67.09815 -22.581362) (xy 74.63866 -22.581362) (xy 74.642731 -22.52574) (xy 74.654857 -22.471303)
			(xy 74.67478 -22.419212) (xy 74.702076 -22.370577) (xy 74.736162 -22.326434) (xy 74.776311 -22.287725)
			(xy 74.821669 -22.255274) (xy 74.871269 -22.229773) (xy 74.924053 -22.211766) (xy 74.978896 -22.201636)
			(xy 75.03463 -22.199599) (xy 75.090067 -22.205699) (xy 75.144024 -22.219805) (xy 75.195353 -22.241617)
			(xy 75.242959 -22.270671) (xy 75.285827 -22.306346) (xy 75.323044 -22.347883) (xy 75.353817 -22.394396)
			(xy 75.377489 -22.444893) (xy 75.393557 -22.4983) (xy 75.401677 -22.553476) (xy 75.402186 -22.581362)
			(xy 75.401677 -22.609248) (xy 75.393557 -22.664424) (xy 75.377489 -22.717831) (xy 75.357227 -22.761053)
			(xy 79.21164 -22.761053) (xy 79.21164 -22.706547) (xy 79.219397 -22.652596) (xy 79.234752 -22.600298)
			(xy 79.257394 -22.550717) (xy 79.286861 -22.504863) (xy 79.322554 -22.463669) (xy 79.363745 -22.427974)
			(xy 79.409598 -22.398504) (xy 79.459177 -22.37586) (xy 79.511474 -22.360501) (xy 79.565425 -22.352741)
			(xy 79.592678 -22.352254) (xy 79.618793 -22.352689) (xy 79.670533 -22.35983) (xy 79.720814 -22.373967)
			(xy 79.768694 -22.394835) (xy 79.813277 -22.422045) (xy 79.853729 -22.455085) (xy 79.871824 -22.47392)
			(xy 79.881243 -22.483397) (xy 79.903906 -22.497534) (xy 79.929458 -22.505316) (xy 79.956154 -22.506211)
			(xy 79.98217 -22.500157) (xy 80.005729 -22.487569) (xy 80.025221 -22.469307) (xy 80.032606 -22.458172)
			(xy 80.047649 -22.43498) (xy 80.083338 -22.392766) (xy 80.124745 -22.356144) (xy 80.171003 -22.325881)
			(xy 80.221144 -22.302609) (xy 80.274118 -22.286817) (xy 80.328817 -22.278834) (xy 80.356456 -22.27834)
			(xy 80.383714 -22.278704) (xy 80.437677 -22.286457) (xy 80.489987 -22.301811) (xy 80.539579 -22.324454)
			(xy 80.585443 -22.353924) (xy 80.626646 -22.389623) (xy 80.662349 -22.430822) (xy 80.691825 -22.476683)
			(xy 80.714474 -22.526272) (xy 80.729834 -22.57858) (xy 80.737593 -22.632542) (xy 80.737593 -22.687058)
			(xy 80.729834 -22.74102) (xy 80.714474 -22.793328) (xy 80.691825 -22.842917) (xy 80.662349 -22.888778)
			(xy 80.626646 -22.929977) (xy 80.585443 -22.965676) (xy 80.539579 -22.995146) (xy 80.489987 -23.017789)
			(xy 80.437677 -23.033143) (xy 80.383714 -23.040896) (xy 80.356456 -23.041356) (xy 80.33034 -23.040961)
			(xy 80.278598 -23.033812) (xy 80.228317 -23.019667) (xy 80.180437 -22.998791) (xy 80.135854 -22.971575)
			(xy 80.095404 -22.938528) (xy 80.07731 -22.91969) (xy 80.067857 -22.910248) (xy 80.045203 -22.896108)
			(xy 80.019659 -22.888321) (xy 79.992969 -22.887421) (xy 79.966958 -22.893469) (xy 79.943403 -22.90605)
			(xy 79.923913 -22.924307) (xy 79.916528 -22.935438) (xy 79.901532 -22.958663) (xy 79.865835 -23.000875)
			(xy 79.82442 -23.037495) (xy 79.778154 -23.067754) (xy 79.728005 -23.091021) (xy 79.675024 -23.106806)
			(xy 79.620319 -23.114781) (xy 79.592678 -23.11527) (xy 79.565425 -23.114859) (xy 79.511474 -23.107099)
			(xy 79.459177 -23.09174) (xy 79.409598 -23.069096) (xy 79.363745 -23.039626) (xy 79.322554 -23.003931)
			(xy 79.286861 -22.962737) (xy 79.257394 -22.916883) (xy 79.234752 -22.867302) (xy 79.219397 -22.815004)
			(xy 79.21164 -22.761053) (xy 75.357227 -22.761053) (xy 75.353817 -22.768328) (xy 75.323044 -22.814841)
			(xy 75.285827 -22.856378) (xy 75.242959 -22.892053) (xy 75.195353 -22.921107) (xy 75.144024 -22.942919)
			(xy 75.090067 -22.957025) (xy 75.03463 -22.963125) (xy 74.978896 -22.961088) (xy 74.924053 -22.950958)
			(xy 74.871269 -22.932951) (xy 74.821669 -22.90745) (xy 74.776311 -22.874999) (xy 74.736162 -22.83629)
			(xy 74.702076 -22.792147) (xy 74.67478 -22.743512) (xy 74.654857 -22.691421) (xy 74.642731 -22.636984)
			(xy 74.63866 -22.581362) (xy 67.09815 -22.581362) (xy 67.057955 -22.605893) (xy 67.006626 -22.627705)
			(xy 66.952669 -22.641811) (xy 66.897232 -22.647911) (xy 66.841498 -22.645874) (xy 66.786655 -22.635744)
			(xy 66.733871 -22.617737) (xy 66.684271 -22.592236) (xy 66.638913 -22.559785) (xy 66.598764 -22.521076)
			(xy 66.564678 -22.476933) (xy 66.537382 -22.428298) (xy 66.517459 -22.376207) (xy 66.505333 -22.32177)
			(xy 66.501262 -22.266148) (xy 63.60668 -22.266148) (xy 63.60668 -23.495762) (xy 75.73086 -23.495762)
			(xy 75.734931 -23.44014) (xy 75.747057 -23.385703) (xy 75.76698 -23.333612) (xy 75.794276 -23.284977)
			(xy 75.828362 -23.240834) (xy 75.868511 -23.202125) (xy 75.913869 -23.169674) (xy 75.963469 -23.144173)
			(xy 76.016253 -23.126166) (xy 76.071096 -23.116036) (xy 76.12683 -23.113999) (xy 76.182267 -23.120099)
			(xy 76.236224 -23.134205) (xy 76.287553 -23.156017) (xy 76.335159 -23.185071) (xy 76.378027 -23.220746)
			(xy 76.415244 -23.262283) (xy 76.446017 -23.308796) (xy 76.469689 -23.359293) (xy 76.485757 -23.4127)
			(xy 76.493877 -23.467876) (xy 76.494386 -23.495762) (xy 76.493877 -23.523648) (xy 76.485757 -23.578824)
			(xy 76.469689 -23.632231) (xy 76.446017 -23.682728) (xy 76.415244 -23.729241) (xy 76.378027 -23.770778)
			(xy 76.335159 -23.806453) (xy 76.287553 -23.835507) (xy 76.236224 -23.857319) (xy 76.182267 -23.871425)
			(xy 76.12683 -23.877525) (xy 76.071096 -23.875488) (xy 76.016253 -23.865358) (xy 75.963469 -23.847351)
			(xy 75.913869 -23.82185) (xy 75.868511 -23.789399) (xy 75.828362 -23.75069) (xy 75.794276 -23.706547)
			(xy 75.76698 -23.657912) (xy 75.747057 -23.605821) (xy 75.734931 -23.551384) (xy 75.73086 -23.495762)
			(xy 63.60668 -23.495762) (xy 63.60668 -25.199594) (xy 63.607076 -25.213017) (xy 63.614054 -25.238941)
			(xy 63.627553 -25.262146) (xy 63.64664 -25.281025) (xy 63.669991 -25.29427) (xy 63.695989 -25.300963)
			(xy 63.722833 -25.300642) (xy 63.748663 -25.293328) (xy 63.76035 -25.286716) (xy 63.782665 -25.273863)
			(xy 63.830014 -25.253616) (xy 63.879656 -25.239921) (xy 63.930689 -25.233027) (xy 63.956438 -25.232614)
			(xy 63.983686 -25.233103) (xy 64.037626 -25.240863) (xy 64.089913 -25.256221) (xy 64.139483 -25.278863)
			(xy 64.185326 -25.308328) (xy 64.226509 -25.344018) (xy 64.262194 -25.385205) (xy 64.291655 -25.43105)
			(xy 64.314293 -25.480622) (xy 64.329645 -25.532911) (xy 64.334711 -25.568148) (xy 66.019172 -25.568148)
			(xy 66.019706 -25.540386) (xy 66.027747 -25.485449) (xy 66.043668 -25.432258) (xy 66.067132 -25.381936)
			(xy 66.097642 -25.335547) (xy 66.134555 -25.294072) (xy 66.17709 -25.258385) (xy 66.224349 -25.229241)
			(xy 66.275334 -25.207256) (xy 66.328968 -25.192894) (xy 66.356484 -25.18918) (xy 66.370108 -25.187096)
			(xy 66.395616 -25.176695) (xy 66.417412 -25.159849) (xy 66.433905 -25.137784) (xy 66.443893 -25.112112)
			(xy 66.446647 -25.084702) (xy 66.441968 -25.057556) (xy 66.436494 -25.044908) (xy 66.425012 -25.019366)
			(xy 66.408841 -24.96575) (xy 66.400665 -24.910349) (xy 66.400172 -24.882348) (xy 66.400658 -24.855097)
			(xy 66.408414 -24.801149) (xy 66.423769 -24.748854) (xy 66.446411 -24.699277) (xy 66.475877 -24.653427)
			(xy 66.511568 -24.612236) (xy 66.552759 -24.576545) (xy 66.598609 -24.547079) (xy 66.648186 -24.524437)
			(xy 66.700481 -24.509082) (xy 66.754429 -24.501326) (xy 66.808931 -24.501326) (xy 66.862879 -24.509082)
			(xy 66.915174 -24.524437) (xy 66.964751 -24.547079) (xy 67.010601 -24.576545) (xy 67.051792 -24.612236)
			(xy 67.087483 -24.653427) (xy 67.116949 -24.699277) (xy 67.139591 -24.748854) (xy 67.154946 -24.801149)
			(xy 67.162702 -24.855097) (xy 67.163188 -24.882348) (xy 67.162706 -24.910674) (xy 67.154363 -24.966709)
			(xy 67.137823 -25.020893) (xy 67.126104 -25.046686) (xy 67.120615 -25.059312) (xy 67.115846 -25.086415)
			(xy 67.118487 -25.113808) (xy 67.128346 -25.139501) (xy 67.144706 -25.161629) (xy 67.166381 -25.178585)
			(xy 67.191796 -25.189139) (xy 67.219106 -25.192524) (xy 67.232784 -25.190958) (xy 67.245484 -25.18918)
			(xy 67.259108 -25.187096) (xy 67.284616 -25.176695) (xy 67.306412 -25.159849) (xy 67.322905 -25.137784)
			(xy 67.332893 -25.112112) (xy 67.335647 -25.084702) (xy 67.330968 -25.057556) (xy 67.325494 -25.044908)
			(xy 67.314012 -25.019366) (xy 67.297841 -24.96575) (xy 67.289665 -24.910349) (xy 67.289172 -24.882348)
			(xy 67.289658 -24.855097) (xy 67.297414 -24.801149) (xy 67.312769 -24.748854) (xy 67.335411 -24.699277)
			(xy 67.364877 -24.653427) (xy 67.400568 -24.612236) (xy 67.441759 -24.576545) (xy 67.487609 -24.547079)
			(xy 67.537186 -24.524437) (xy 67.589481 -24.509082) (xy 67.643429 -24.501326) (xy 67.697931 -24.501326)
			(xy 67.751879 -24.509082) (xy 67.804174 -24.524437) (xy 67.853751 -24.547079) (xy 67.899601 -24.576545)
			(xy 67.940792 -24.612236) (xy 67.976483 -24.653427) (xy 68.005949 -24.699277) (xy 68.028591 -24.748854)
			(xy 68.043946 -24.801149) (xy 68.051702 -24.855097) (xy 68.052188 -24.882348) (xy 68.051706 -24.910674)
			(xy 68.043363 -24.966709) (xy 68.026823 -25.020893) (xy 68.015104 -25.046686) (xy 68.009615 -25.059312)
			(xy 68.004846 -25.086415) (xy 68.007487 -25.113808) (xy 68.017346 -25.139501) (xy 68.033706 -25.161629)
			(xy 68.055381 -25.178585) (xy 68.080796 -25.189139) (xy 68.108106 -25.192524) (xy 68.121784 -25.190958)
			(xy 68.134484 -25.18918) (xy 68.148108 -25.187096) (xy 68.173616 -25.176695) (xy 68.195412 -25.159849)
			(xy 68.211905 -25.137784) (xy 68.221893 -25.112112) (xy 68.224647 -25.084702) (xy 68.219968 -25.057556)
			(xy 68.214494 -25.044908) (xy 68.203012 -25.019366) (xy 68.186841 -24.96575) (xy 68.178665 -24.910349)
			(xy 68.178172 -24.882348) (xy 68.178658 -24.855097) (xy 68.186414 -24.801149) (xy 68.201769 -24.748854)
			(xy 68.224411 -24.699277) (xy 68.253877 -24.653427) (xy 68.289568 -24.612236) (xy 68.330759 -24.576545)
			(xy 68.376609 -24.547079) (xy 68.426186 -24.524437) (xy 68.478481 -24.509082) (xy 68.532429 -24.501326)
			(xy 68.586931 -24.501326) (xy 68.640879 -24.509082) (xy 68.693174 -24.524437) (xy 68.742751 -24.547079)
			(xy 68.750639 -24.552148) (xy 69.117462 -24.552148) (xy 69.121533 -24.496526) (xy 69.133659 -24.442089)
			(xy 69.153582 -24.389998) (xy 69.180878 -24.341363) (xy 69.214964 -24.29722) (xy 69.255113 -24.258511)
			(xy 69.300471 -24.22606) (xy 69.350071 -24.200559) (xy 69.402855 -24.182552) (xy 69.457698 -24.172422)
			(xy 69.513432 -24.170385) (xy 69.568869 -24.176485) (xy 69.622826 -24.190591) (xy 69.674155 -24.212403)
			(xy 69.721761 -24.241457) (xy 69.764629 -24.277132) (xy 69.797569 -24.313896) (xy 77.804262 -24.313896)
			(xy 77.808333 -24.258274) (xy 77.820459 -24.203837) (xy 77.840382 -24.151746) (xy 77.867678 -24.103111)
			(xy 77.901764 -24.058968) (xy 77.941913 -24.020259) (xy 77.987271 -23.987808) (xy 78.036871 -23.962307)
			(xy 78.089655 -23.9443) (xy 78.144498 -23.93417) (xy 78.200232 -23.932133) (xy 78.255669 -23.938233)
			(xy 78.309626 -23.952339) (xy 78.360955 -23.974151) (xy 78.408561 -24.003205) (xy 78.451429 -24.03888)
			(xy 78.488646 -24.080417) (xy 78.519419 -24.12693) (xy 78.543091 -24.177427) (xy 78.559159 -24.230834)
			(xy 78.567279 -24.28601) (xy 78.567788 -24.313896) (xy 78.567279 -24.341782) (xy 78.559159 -24.396958)
			(xy 78.543091 -24.450365) (xy 78.519419 -24.500862) (xy 78.488646 -24.547375) (xy 78.45228 -24.587962)
			(xy 79.23606 -24.587962) (xy 79.240131 -24.53234) (xy 79.252257 -24.477903) (xy 79.27218 -24.425812)
			(xy 79.299476 -24.377177) (xy 79.333562 -24.333034) (xy 79.373711 -24.294325) (xy 79.419069 -24.261874)
			(xy 79.468669 -24.236373) (xy 79.521453 -24.218366) (xy 79.576296 -24.208236) (xy 79.63203 -24.206199)
			(xy 79.687467 -24.212299) (xy 79.741424 -24.226405) (xy 79.792753 -24.248217) (xy 79.840359 -24.277271)
			(xy 79.883227 -24.312946) (xy 79.920444 -24.354483) (xy 79.951217 -24.400996) (xy 79.974889 -24.451493)
			(xy 79.990957 -24.5049) (xy 79.999077 -24.560076) (xy 79.999586 -24.587962) (xy 79.999077 -24.615848)
			(xy 79.990957 -24.671024) (xy 79.974889 -24.724431) (xy 79.951217 -24.774928) (xy 79.920444 -24.821441)
			(xy 79.883227 -24.862978) (xy 79.840359 -24.898653) (xy 79.792753 -24.927707) (xy 79.741424 -24.949519)
			(xy 79.687467 -24.963625) (xy 79.63203 -24.969725) (xy 79.576296 -24.967688) (xy 79.521453 -24.957558)
			(xy 79.468669 -24.939551) (xy 79.419069 -24.91405) (xy 79.373711 -24.881599) (xy 79.333562 -24.84289)
			(xy 79.299476 -24.798747) (xy 79.27218 -24.750112) (xy 79.252257 -24.698021) (xy 79.240131 -24.643584)
			(xy 79.23606 -24.587962) (xy 78.45228 -24.587962) (xy 78.451429 -24.588912) (xy 78.408561 -24.624587)
			(xy 78.360955 -24.653641) (xy 78.309626 -24.675453) (xy 78.255669 -24.689559) (xy 78.200232 -24.695659)
			(xy 78.144498 -24.693622) (xy 78.089655 -24.683492) (xy 78.036871 -24.665485) (xy 77.987271 -24.639984)
			(xy 77.941913 -24.607533) (xy 77.901764 -24.568824) (xy 77.867678 -24.524681) (xy 77.840382 -24.476046)
			(xy 77.820459 -24.423955) (xy 77.808333 -24.369518) (xy 77.804262 -24.313896) (xy 69.797569 -24.313896)
			(xy 69.801846 -24.318669) (xy 69.832619 -24.365182) (xy 69.856291 -24.415679) (xy 69.872359 -24.469086)
			(xy 69.880479 -24.524262) (xy 69.880988 -24.552148) (xy 69.880479 -24.580034) (xy 69.872359 -24.63521)
			(xy 69.856291 -24.688617) (xy 69.832619 -24.739114) (xy 69.801846 -24.785627) (xy 69.764629 -24.827164)
			(xy 69.721761 -24.862839) (xy 69.674155 -24.891893) (xy 69.622826 -24.913705) (xy 69.568869 -24.927811)
			(xy 69.513432 -24.933911) (xy 69.457698 -24.931874) (xy 69.402855 -24.921744) (xy 69.350071 -24.903737)
			(xy 69.300471 -24.878236) (xy 69.255113 -24.845785) (xy 69.214964 -24.807076) (xy 69.180878 -24.762933)
			(xy 69.153582 -24.714298) (xy 69.133659 -24.662207) (xy 69.121533 -24.60777) (xy 69.117462 -24.552148)
			(xy 68.750639 -24.552148) (xy 68.788601 -24.576545) (xy 68.829792 -24.612236) (xy 68.865483 -24.653427)
			(xy 68.894949 -24.699277) (xy 68.917591 -24.748854) (xy 68.932946 -24.801149) (xy 68.940702 -24.855097)
			(xy 68.941188 -24.882348) (xy 68.940686 -24.910111) (xy 68.932644 -24.965052) (xy 68.916721 -25.018246)
			(xy 68.893255 -25.068569) (xy 68.862742 -25.11496) (xy 68.825825 -25.156436) (xy 68.783285 -25.192122)
			(xy 68.782701 -25.192482) (xy 70.55434 -25.192482) (xy 70.558411 -25.13686) (xy 70.570537 -25.082423)
			(xy 70.59046 -25.030332) (xy 70.617756 -24.981697) (xy 70.651842 -24.937554) (xy 70.691991 -24.898845)
			(xy 70.737349 -24.866394) (xy 70.786949 -24.840893) (xy 70.839733 -24.822886) (xy 70.894576 -24.812756)
			(xy 70.95031 -24.810719) (xy 71.005747 -24.816819) (xy 71.059704 -24.830925) (xy 71.111033 -24.852737)
			(xy 71.158639 -24.881791) (xy 71.201507 -24.917466) (xy 71.238724 -24.959003) (xy 71.269497 -25.005516)
			(xy 71.293169 -25.056013) (xy 71.309237 -25.10942) (xy 71.317357 -25.164596) (xy 71.317866 -25.192482)
			(xy 71.317357 -25.220368) (xy 71.309237 -25.275544) (xy 71.293169 -25.328951) (xy 71.269497 -25.379448)
			(xy 71.238724 -25.425961) (xy 71.201507 -25.467498) (xy 71.158639 -25.503173) (xy 71.111033 -25.532227)
			(xy 71.059704 -25.554039) (xy 71.005747 -25.568145) (xy 70.95031 -25.574245) (xy 70.894576 -25.572208)
			(xy 70.839733 -25.562078) (xy 70.786949 -25.544071) (xy 70.737349 -25.51857) (xy 70.691991 -25.486119)
			(xy 70.651842 -25.44741) (xy 70.617756 -25.403267) (xy 70.59046 -25.354632) (xy 70.570537 -25.302541)
			(xy 70.558411 -25.248104) (xy 70.55434 -25.192482) (xy 68.782701 -25.192482) (xy 68.736021 -25.221264)
			(xy 68.685032 -25.243246) (xy 68.631394 -25.257604) (xy 68.603876 -25.261316) (xy 68.590232 -25.263308)
			(xy 68.564703 -25.273709) (xy 68.542892 -25.290567) (xy 68.526392 -25.31265) (xy 68.516408 -25.338345)
			(xy 68.513669 -25.365775) (xy 68.518376 -25.392937) (xy 68.523866 -25.405588) (xy 68.535351 -25.431129)
			(xy 68.551519 -25.484746) (xy 68.559695 -25.540147) (xy 68.560188 -25.568148) (xy 68.559702 -25.595399)
			(xy 68.551946 -25.649347) (xy 68.536591 -25.701642) (xy 68.513949 -25.751219) (xy 68.484483 -25.797069)
			(xy 68.448792 -25.83826) (xy 68.407601 -25.873951) (xy 68.361751 -25.903417) (xy 68.312174 -25.926059)
			(xy 68.259879 -25.941414) (xy 68.205931 -25.94917) (xy 68.151429 -25.94917) (xy 68.097481 -25.941414)
			(xy 68.045186 -25.926059) (xy 67.995609 -25.903417) (xy 67.949759 -25.873951) (xy 67.908568 -25.83826)
			(xy 67.872877 -25.797069) (xy 67.843411 -25.751219) (xy 67.820769 -25.701642) (xy 67.805414 -25.649347)
			(xy 67.797658 -25.595399) (xy 67.797172 -25.568148) (xy 67.797656 -25.539822) (xy 67.805999 -25.483787)
			(xy 67.822537 -25.429603) (xy 67.834256 -25.40381) (xy 67.839791 -25.391201) (xy 67.844563 -25.364089)
			(xy 67.841922 -25.336687) (xy 67.832058 -25.310986) (xy 67.81569 -25.288853) (xy 67.794005 -25.271895)
			(xy 67.768578 -25.261344) (xy 67.741258 -25.257966) (xy 67.727576 -25.259538) (xy 67.714876 -25.261316)
			(xy 67.701232 -25.263308) (xy 67.675703 -25.273709) (xy 67.653892 -25.290567) (xy 67.637392 -25.31265)
			(xy 67.627408 -25.338345) (xy 67.624669 -25.365775) (xy 67.629376 -25.392937) (xy 67.634866 -25.405588)
			(xy 67.646351 -25.431129) (xy 67.662519 -25.484746) (xy 67.670695 -25.540147) (xy 67.671188 -25.568148)
			(xy 67.670702 -25.595399) (xy 67.662946 -25.649347) (xy 67.647591 -25.701642) (xy 67.624949 -25.751219)
			(xy 67.595483 -25.797069) (xy 67.559792 -25.83826) (xy 67.518601 -25.873951) (xy 67.472751 -25.903417)
			(xy 67.423174 -25.926059) (xy 67.370879 -25.941414) (xy 67.316931 -25.94917) (xy 67.262429 -25.94917)
			(xy 67.208481 -25.941414) (xy 67.156186 -25.926059) (xy 67.106609 -25.903417) (xy 67.060759 -25.873951)
			(xy 67.019568 -25.83826) (xy 66.983877 -25.797069) (xy 66.954411 -25.751219) (xy 66.931769 -25.701642)
			(xy 66.916414 -25.649347) (xy 66.908658 -25.595399) (xy 66.908172 -25.568148) (xy 66.908656 -25.539822)
			(xy 66.916999 -25.483787) (xy 66.933537 -25.429603) (xy 66.945256 -25.40381) (xy 66.950791 -25.391201)
			(xy 66.955563 -25.364089) (xy 66.952922 -25.336687) (xy 66.943058 -25.310986) (xy 66.92669 -25.288853)
			(xy 66.905005 -25.271895) (xy 66.879578 -25.261344) (xy 66.852258 -25.257966) (xy 66.838576 -25.259538)
			(xy 66.825876 -25.261316) (xy 66.812232 -25.263308) (xy 66.786703 -25.273709) (xy 66.764892 -25.290567)
			(xy 66.748392 -25.31265) (xy 66.738408 -25.338345) (xy 66.735669 -25.365775) (xy 66.740376 -25.392937)
			(xy 66.745866 -25.405588) (xy 66.757351 -25.431129) (xy 66.773519 -25.484746) (xy 66.781695 -25.540147)
			(xy 66.782188 -25.568148) (xy 66.781702 -25.595399) (xy 66.773946 -25.649347) (xy 66.758591 -25.701642)
			(xy 66.735949 -25.751219) (xy 66.706483 -25.797069) (xy 66.670792 -25.83826) (xy 66.629601 -25.873951)
			(xy 66.583751 -25.903417) (xy 66.534174 -25.926059) (xy 66.481879 -25.941414) (xy 66.427931 -25.94917)
			(xy 66.373429 -25.94917) (xy 66.319481 -25.941414) (xy 66.267186 -25.926059) (xy 66.217609 -25.903417)
			(xy 66.171759 -25.873951) (xy 66.130568 -25.83826) (xy 66.094877 -25.797069) (xy 66.065411 -25.751219)
			(xy 66.042769 -25.701642) (xy 66.027414 -25.649347) (xy 66.019658 -25.595399) (xy 66.019172 -25.568148)
			(xy 64.334711 -25.568148) (xy 64.3374 -25.586852) (xy 64.3374 -25.641348) (xy 64.329645 -25.695289)
			(xy 64.314293 -25.747578) (xy 64.291655 -25.79715) (xy 64.262194 -25.842995) (xy 64.226509 -25.884182)
			(xy 64.185326 -25.919872) (xy 64.139483 -25.949337) (xy 64.089913 -25.971979) (xy 64.037626 -25.987337)
			(xy 63.983686 -25.995097) (xy 63.956438 -25.99563) (xy 63.93069 -25.995223) (xy 63.879657 -25.988326)
			(xy 63.830017 -25.974626) (xy 63.782671 -25.954371) (xy 63.76035 -25.941528) (xy 63.748628 -25.93501)
			(xy 63.722819 -25.927745) (xy 63.696008 -25.92745) (xy 63.670045 -25.934146) (xy 63.646721 -25.947369)
			(xy 63.627644 -25.96621) (xy 63.61413 -25.989367) (xy 63.607111 -26.015245) (xy 63.60668 -26.02865)
			(xy 63.60668 -26.698053) (xy 72.09964 -26.698053) (xy 72.09964 -26.643547) (xy 72.107397 -26.589596)
			(xy 72.122752 -26.537298) (xy 72.145394 -26.487717) (xy 72.174861 -26.441863) (xy 72.210554 -26.400669)
			(xy 72.251745 -26.364974) (xy 72.297598 -26.335504) (xy 72.347177 -26.31286) (xy 72.399474 -26.297501)
			(xy 72.453425 -26.289741) (xy 72.480678 -26.289254) (xy 72.507935 -26.289747) (xy 72.561894 -26.297511)
			(xy 72.6142 -26.312871) (xy 72.66379 -26.335513) (xy 72.709656 -26.364978) (xy 72.750865 -26.400666)
			(xy 72.786579 -26.441853) (xy 72.801734 -26.464514) (xy 72.810015 -26.476441) (xy 72.831951 -26.495445)
			(xy 72.858351 -26.5075) (xy 72.887078 -26.51163) (xy 72.915805 -26.5075) (xy 72.942205 -26.495445)
			(xy 72.964141 -26.476441) (xy 72.972422 -26.464514) (xy 72.987539 -26.441825) (xy 73.023252 -26.400629)
			(xy 73.064464 -26.364935) (xy 73.110336 -26.335469) (xy 73.159935 -26.312831) (xy 73.21225 -26.297482)
			(xy 73.266218 -26.289735) (xy 73.293478 -26.289254) (xy 73.320729 -26.289792) (xy 73.374677 -26.297545)
			(xy 73.426972 -26.312898) (xy 73.47655 -26.335537) (xy 73.522402 -26.365001) (xy 73.563593 -26.400692)
			(xy 73.599285 -26.441881) (xy 73.628752 -26.48773) (xy 73.651394 -26.537307) (xy 73.66675 -26.589601)
			(xy 73.674507 -26.643549) (xy 73.674507 -26.698051) (xy 73.66675 -26.751999) (xy 73.651394 -26.804293)
			(xy 73.628752 -26.85387) (xy 73.599285 -26.899719) (xy 73.563593 -26.940908) (xy 73.522402 -26.976599)
			(xy 73.47655 -27.006063) (xy 73.426972 -27.028702) (xy 73.374677 -27.044055) (xy 73.320729 -27.051808)
			(xy 73.293478 -27.05227) (xy 73.26622 -27.0518) (xy 73.212261 -27.044031) (xy 73.159954 -27.028666)
			(xy 73.110365 -27.00602) (xy 73.064499 -26.976552) (xy 73.023291 -26.940861) (xy 72.987577 -26.899672)
			(xy 72.972422 -26.87701) (xy 72.964141 -26.865083) (xy 72.942205 -26.846079) (xy 72.915805 -26.834024)
			(xy 72.887078 -26.829894) (xy 72.858351 -26.834024) (xy 72.831951 -26.846079) (xy 72.810015 -26.865083)
			(xy 72.801734 -26.87701) (xy 72.786588 -26.899679) (xy 72.750879 -26.940873) (xy 72.709671 -26.976568)
			(xy 72.663804 -27.006036) (xy 72.614211 -27.028677) (xy 72.5619 -27.044031) (xy 72.507937 -27.051786)
			(xy 72.480678 -27.05227) (xy 72.453425 -27.051859) (xy 72.399474 -27.044099) (xy 72.347177 -27.02874)
			(xy 72.297598 -27.006096) (xy 72.251745 -26.976626) (xy 72.210554 -26.940931) (xy 72.174861 -26.899737)
			(xy 72.145394 -26.853883) (xy 72.122752 -26.804302) (xy 72.107397 -26.752004) (xy 72.09964 -26.698053)
			(xy 63.60668 -26.698053) (xy 63.60668 -28.389834) (xy 64.102994 -28.389834) (xy 64.107065 -28.334212)
			(xy 64.119191 -28.279775) (xy 64.139114 -28.227684) (xy 64.16641 -28.179049) (xy 64.200496 -28.134906)
			(xy 64.240645 -28.096197) (xy 64.286003 -28.063746) (xy 64.335603 -28.038245) (xy 64.388387 -28.020238)
			(xy 64.44323 -28.010108) (xy 64.498964 -28.008071) (xy 64.554401 -28.014171) (xy 64.608358 -28.028277)
			(xy 64.659687 -28.050089) (xy 64.707293 -28.079143) (xy 64.750161 -28.114818) (xy 64.787378 -28.156355)
			(xy 64.818151 -28.202868) (xy 64.820305 -28.207462) (xy 66.166238 -28.207462) (xy 66.166725 -28.18014)
			(xy 66.17507 -28.126136) (xy 66.191558 -28.074039) (xy 66.215804 -28.025068) (xy 66.247239 -27.980371)
			(xy 66.265806 -27.96032) (xy 66.276244 -27.94873) (xy 66.290071 -27.920786) (xy 66.294822 -27.889972)
			(xy 66.290054 -27.859161) (xy 66.276212 -27.831225) (xy 66.265806 -27.819604) (xy 66.247204 -27.799581)
			(xy 66.215746 -27.754891) (xy 66.191495 -27.705914) (xy 66.175021 -27.653805) (xy 66.166712 -27.599788)
			(xy 66.166238 -27.572462) (xy 66.166736 -27.545813) (xy 66.174679 -27.493109) (xy 66.190389 -27.442179)
			(xy 66.213515 -27.394158) (xy 66.243539 -27.350121) (xy 66.279791 -27.31105) (xy 66.321462 -27.277819)
			(xy 66.36762 -27.25117) (xy 66.417234 -27.231698) (xy 66.469196 -27.219838) (xy 66.522346 -27.215855)
			(xy 66.575496 -27.219838) (xy 66.627458 -27.231698) (xy 66.677072 -27.25117) (xy 66.72323 -27.277819)
			(xy 66.764901 -27.31105) (xy 66.801153 -27.350121) (xy 66.831177 -27.394158) (xy 66.854303 -27.442179)
			(xy 66.870013 -27.493109) (xy 66.877956 -27.545813) (xy 66.878454 -27.572462) (xy 66.877922 -27.599782)
			(xy 66.869589 -27.653784) (xy 66.853111 -27.705881) (xy 66.828875 -27.754853) (xy 66.797449 -27.799552)
			(xy 66.778886 -27.819604) (xy 66.768524 -27.831256) (xy 66.75469 -27.859178) (xy 66.749926 -27.889972)
			(xy 66.754674 -27.92077) (xy 66.768492 -27.948699) (xy 66.778886 -27.96032) (xy 66.797498 -27.980334)
			(xy 66.828955 -28.025027) (xy 66.853205 -28.074005) (xy 66.869676 -28.126117) (xy 66.877982 -28.180135)
			(xy 66.878454 -28.207462) (xy 67.06616 -28.207462) (xy 67.066669 -28.180141) (xy 67.075011 -28.126139)
			(xy 67.091496 -28.074043) (xy 67.115736 -28.025072) (xy 67.147164 -27.980372) (xy 67.165728 -27.96032)
			(xy 67.176164 -27.948729) (xy 67.189988 -27.920785) (xy 67.194738 -27.889972) (xy 67.189971 -27.859162)
			(xy 67.176132 -27.831226) (xy 67.165728 -27.819604) (xy 67.14713 -27.799577) (xy 67.115671 -27.754889)
			(xy 67.091418 -27.705913) (xy 67.074943 -27.653804) (xy 67.066634 -27.599788) (xy 67.06616 -27.572462)
			(xy 67.066658 -27.545813) (xy 67.074601 -27.493109) (xy 67.090311 -27.442179) (xy 67.113437 -27.394158)
			(xy 67.143461 -27.350121) (xy 67.179713 -27.31105) (xy 67.221384 -27.277819) (xy 67.267542 -27.25117)
			(xy 67.317156 -27.231698) (xy 67.369118 -27.219838) (xy 67.422268 -27.215855) (xy 67.475418 -27.219838)
			(xy 67.52738 -27.231698) (xy 67.576994 -27.25117) (xy 67.623152 -27.277819) (xy 67.664823 -27.31105)
			(xy 67.701075 -27.350121) (xy 67.731099 -27.394158) (xy 67.754225 -27.442179) (xy 67.769935 -27.493109)
			(xy 67.777878 -27.545813) (xy 67.778376 -27.572462) (xy 67.777838 -27.599782) (xy 67.769505 -27.653783)
			(xy 67.753029 -27.70588) (xy 67.728794 -27.754852) (xy 67.69737 -27.799552) (xy 67.678808 -27.819604)
			(xy 67.668452 -27.831259) (xy 67.65463 -27.859181) (xy 67.649869 -27.889972) (xy 67.654613 -27.920766)
			(xy 67.668421 -27.948696) (xy 67.678808 -27.96032) (xy 67.697423 -27.980331) (xy 67.728879 -28.025025)
			(xy 67.753128 -28.074004) (xy 67.769599 -28.126116) (xy 67.777904 -28.180135) (xy 67.778376 -28.207462)
			(xy 67.966082 -28.207462) (xy 67.966585 -28.180141) (xy 67.974928 -28.126139) (xy 67.991414 -28.074042)
			(xy 68.015655 -28.025071) (xy 68.047085 -27.980372) (xy 68.06565 -27.96032) (xy 68.076084 -27.948728)
			(xy 68.089905 -27.920784) (xy 68.094654 -27.889972) (xy 68.089888 -27.859163) (xy 68.076052 -27.831226)
			(xy 68.06565 -27.819604) (xy 68.047056 -27.799574) (xy 68.015595 -27.754887) (xy 67.991341 -27.705912)
			(xy 67.974866 -27.653804) (xy 67.966556 -27.599788) (xy 67.966082 -27.572462) (xy 67.96658 -27.545813)
			(xy 67.974523 -27.493109) (xy 67.990233 -27.442179) (xy 68.013359 -27.394158) (xy 68.043383 -27.350121)
			(xy 68.079635 -27.31105) (xy 68.121306 -27.277819) (xy 68.167464 -27.25117) (xy 68.217078 -27.231698)
			(xy 68.26904 -27.219838) (xy 68.32219 -27.215855) (xy 68.37534 -27.219838) (xy 68.427302 -27.231698)
			(xy 68.476916 -27.25117) (xy 68.523074 -27.277819) (xy 68.564745 -27.31105) (xy 68.600997 -27.350121)
			(xy 68.631021 -27.394158) (xy 68.654147 -27.442179) (xy 68.669857 -27.493109) (xy 68.6778 -27.545813)
			(xy 68.678298 -27.572462) (xy 68.677754 -27.599782) (xy 68.669422 -27.653782) (xy 68.652946 -27.705879)
			(xy 68.628713 -27.754851) (xy 68.597291 -27.799551) (xy 68.57873 -27.819604) (xy 68.568372 -27.831258)
			(xy 68.554547 -27.85918) (xy 68.549785 -27.889972) (xy 68.55453 -27.920767) (xy 68.568341 -27.948697)
			(xy 68.57873 -27.96032) (xy 68.597349 -27.980328) (xy 68.628804 -28.025023) (xy 68.653051 -28.074003)
			(xy 68.669521 -28.126116) (xy 68.677826 -28.180135) (xy 68.678298 -28.207462) (xy 68.866258 -28.207462)
			(xy 68.86674 -28.18014) (xy 68.875085 -28.126136) (xy 68.891574 -28.074038) (xy 68.915821 -28.025067)
			(xy 68.947258 -27.98037) (xy 68.965826 -27.96032) (xy 68.976262 -27.948729) (xy 68.990086 -27.920785)
			(xy 68.994836 -27.889972) (xy 68.99007 -27.859162) (xy 68.976231 -27.831225) (xy 68.965826 -27.819604)
			(xy 68.947228 -27.799578) (xy 68.915768 -27.754889) (xy 68.891516 -27.705913) (xy 68.875041 -27.653804)
			(xy 68.866732 -27.599788) (xy 68.866258 -27.572462) (xy 68.866756 -27.545813) (xy 68.874699 -27.493109)
			(xy 68.890409 -27.442179) (xy 68.913535 -27.394158) (xy 68.943559 -27.350121) (xy 68.979811 -27.31105)
			(xy 69.021482 -27.277819) (xy 69.06764 -27.25117) (xy 69.117254 -27.231698) (xy 69.169216 -27.219838)
			(xy 69.222366 -27.215855) (xy 69.275516 -27.219838) (xy 69.327478 -27.231698) (xy 69.377092 -27.25117)
			(xy 69.42325 -27.277819) (xy 69.464921 -27.31105) (xy 69.501173 -27.350121) (xy 69.531197 -27.394158)
			(xy 69.554323 -27.442179) (xy 69.570033 -27.493109) (xy 69.577976 -27.545813) (xy 69.578474 -27.572462)
			(xy 69.577937 -27.599782) (xy 69.569604 -27.653783) (xy 69.553127 -27.70588) (xy 69.528893 -27.754852)
			(xy 69.497468 -27.799552) (xy 69.478906 -27.819604) (xy 69.468551 -27.831259) (xy 69.454728 -27.859181)
			(xy 69.449967 -27.889972) (xy 69.453879 -27.915362) (xy 70.95617 -27.915362) (xy 70.956679 -27.886623)
			(xy 70.965306 -27.829795) (xy 70.98236 -27.774904) (xy 71.007455 -27.723193) (xy 71.040022 -27.675831)
			(xy 71.059294 -27.654504) (xy 71.069401 -27.642999) (xy 71.082736 -27.615442) (xy 71.087312 -27.585172)
			(xy 71.082719 -27.554905) (xy 71.069369 -27.527355) (xy 71.059294 -27.51582) (xy 71.040015 -27.4945)
			(xy 71.007448 -27.447137) (xy 70.982356 -27.395424) (xy 70.965308 -27.340531) (xy 70.956689 -27.283702)
			(xy 70.95617 -27.254962) (xy 70.956656 -27.227711) (xy 70.964412 -27.173763) (xy 70.979767 -27.121468)
			(xy 71.002409 -27.071891) (xy 71.031875 -27.026041) (xy 71.067566 -26.98485) (xy 71.108757 -26.949159)
			(xy 71.154607 -26.919693) (xy 71.204184 -26.897051) (xy 71.256479 -26.881696) (xy 71.310427 -26.87394)
			(xy 71.364929 -26.87394) (xy 71.418877 -26.881696) (xy 71.471172 -26.897051) (xy 71.520749 -26.919693)
			(xy 71.566599 -26.949159) (xy 71.60779 -26.98485) (xy 71.643481 -27.026041) (xy 71.672947 -27.071891)
			(xy 71.695589 -27.121468) (xy 71.710944 -27.173763) (xy 71.7187 -27.227711) (xy 71.719186 -27.254962)
			(xy 71.718677 -27.283701) (xy 71.710047 -27.340528) (xy 71.692992 -27.395418) (xy 71.667898 -27.44713)
			(xy 71.635332 -27.494492) (xy 71.616062 -27.51582) (xy 71.606025 -27.527383) (xy 71.592674 -27.554918)
			(xy 71.588081 -27.585172) (xy 71.592658 -27.615429) (xy 71.605993 -27.642971) (xy 71.616062 -27.654504)
			(xy 71.635315 -27.675847) (xy 71.667883 -27.723204) (xy 71.692979 -27.774912) (xy 71.710034 -27.829799)
			(xy 71.718662 -27.886624) (xy 71.719186 -27.915362) (xy 71.7187 -27.942613) (xy 71.710944 -27.996561)
			(xy 71.695589 -28.048856) (xy 71.672947 -28.098433) (xy 71.643481 -28.144283) (xy 71.60779 -28.185474)
			(xy 71.566599 -28.221165) (xy 71.520749 -28.250631) (xy 71.471172 -28.273273) (xy 71.418877 -28.288628)
			(xy 71.364929 -28.296384) (xy 71.310427 -28.296384) (xy 71.256479 -28.288628) (xy 71.204184 -28.273273)
			(xy 71.154607 -28.250631) (xy 71.108757 -28.221165) (xy 71.067566 -28.185474) (xy 71.031875 -28.144283)
			(xy 71.002409 -28.098433) (xy 70.979767 -28.048856) (xy 70.964412 -27.996561) (xy 70.956656 -27.942613)
			(xy 70.95617 -27.915362) (xy 69.453879 -27.915362) (xy 69.454712 -27.920766) (xy 69.468519 -27.948696)
			(xy 69.478906 -27.96032) (xy 69.497521 -27.980331) (xy 69.528977 -28.025025) (xy 69.553226 -28.074004)
			(xy 69.569697 -28.126116) (xy 69.578002 -28.180135) (xy 69.578474 -28.207462) (xy 69.577976 -28.234111)
			(xy 69.570033 -28.286815) (xy 69.554323 -28.337745) (xy 69.531197 -28.385766) (xy 69.501173 -28.429803)
			(xy 69.464921 -28.468874) (xy 69.42325 -28.502105) (xy 69.377092 -28.528754) (xy 69.327478 -28.548226)
			(xy 69.275516 -28.560086) (xy 69.222366 -28.56407) (xy 69.169216 -28.560086) (xy 69.117254 -28.548226)
			(xy 69.06764 -28.528754) (xy 69.021482 -28.502105) (xy 68.979811 -28.468874) (xy 68.943559 -28.429803)
			(xy 68.913535 -28.385766) (xy 68.890409 -28.337745) (xy 68.874699 -28.286815) (xy 68.866756 -28.234111)
			(xy 68.866258 -28.207462) (xy 68.678298 -28.207462) (xy 68.6778 -28.234111) (xy 68.669857 -28.286815)
			(xy 68.654147 -28.337745) (xy 68.631021 -28.385766) (xy 68.600997 -28.429803) (xy 68.564745 -28.468874)
			(xy 68.523074 -28.502105) (xy 68.476916 -28.528754) (xy 68.427302 -28.548226) (xy 68.37534 -28.560086)
			(xy 68.32219 -28.56407) (xy 68.26904 -28.560086) (xy 68.217078 -28.548226) (xy 68.167464 -28.528754)
			(xy 68.121306 -28.502105) (xy 68.079635 -28.468874) (xy 68.043383 -28.429803) (xy 68.013359 -28.385766)
			(xy 67.990233 -28.337745) (xy 67.974523 -28.286815) (xy 67.96658 -28.234111) (xy 67.966082 -28.207462)
			(xy 67.778376 -28.207462) (xy 67.777878 -28.234111) (xy 67.769935 -28.286815) (xy 67.754225 -28.337745)
			(xy 67.731099 -28.385766) (xy 67.701075 -28.429803) (xy 67.664823 -28.468874) (xy 67.623152 -28.502105)
			(xy 67.576994 -28.528754) (xy 67.52738 -28.548226) (xy 67.475418 -28.560086) (xy 67.422268 -28.56407)
			(xy 67.369118 -28.560086) (xy 67.317156 -28.548226) (xy 67.267542 -28.528754) (xy 67.221384 -28.502105)
			(xy 67.179713 -28.468874) (xy 67.143461 -28.429803) (xy 67.113437 -28.385766) (xy 67.090311 -28.337745)
			(xy 67.074601 -28.286815) (xy 67.066658 -28.234111) (xy 67.06616 -28.207462) (xy 66.878454 -28.207462)
			(xy 66.877956 -28.234111) (xy 66.870013 -28.286815) (xy 66.854303 -28.337745) (xy 66.831177 -28.385766)
			(xy 66.801153 -28.429803) (xy 66.764901 -28.468874) (xy 66.72323 -28.502105) (xy 66.677072 -28.528754)
			(xy 66.627458 -28.548226) (xy 66.575496 -28.560086) (xy 66.522346 -28.56407) (xy 66.469196 -28.560086)
			(xy 66.417234 -28.548226) (xy 66.36762 -28.528754) (xy 66.321462 -28.502105) (xy 66.279791 -28.468874)
			(xy 66.243539 -28.429803) (xy 66.213515 -28.385766) (xy 66.190389 -28.337745) (xy 66.174679 -28.286815)
			(xy 66.166736 -28.234111) (xy 66.166238 -28.207462) (xy 64.820305 -28.207462) (xy 64.841823 -28.253365)
			(xy 64.857891 -28.306772) (xy 64.866011 -28.361948) (xy 64.86652 -28.389834) (xy 64.866011 -28.41772)
			(xy 64.857891 -28.472896) (xy 64.841823 -28.526303) (xy 64.818151 -28.5768) (xy 64.787378 -28.623313)
			(xy 64.761709 -28.651962) (xy 76.118974 -28.651962) (xy 76.11943 -28.625646) (xy 76.126651 -28.573513)
			(xy 76.140964 -28.522865) (xy 76.162098 -28.474663) (xy 76.189652 -28.429821) (xy 76.223104 -28.389189)
			(xy 76.242164 -28.371038) (xy 76.252225 -28.361264) (xy 76.266926 -28.337381) (xy 76.274562 -28.310397)
			(xy 76.274555 -28.282352) (xy 76.266905 -28.255371) (xy 76.252193 -28.231497) (xy 76.242164 -28.221686)
			(xy 76.22309 -28.203546) (xy 76.189609 -28.162928) (xy 76.162036 -28.118089) (xy 76.140896 -28.069882)
			(xy 76.126591 -28.019225) (xy 76.119394 -27.967081) (xy 76.118974 -27.940762) (xy 76.119492 -27.913189)
			(xy 76.127435 -27.858619) (xy 76.14315 -27.805761) (xy 76.16631 -27.755715) (xy 76.196433 -27.709524)
			(xy 76.232891 -27.66815) (xy 76.253594 -27.649932) (xy 76.264529 -27.640072) (xy 76.280601 -27.615411)
			(xy 76.28898 -27.587193) (xy 76.288973 -27.557758) (xy 76.28058 -27.529544) (xy 76.264497 -27.504891)
			(xy 76.253594 -27.494992) (xy 76.232875 -27.47679) (xy 76.196405 -27.435419) (xy 76.166274 -27.389227)
			(xy 76.14311 -27.339177) (xy 76.127395 -27.286313) (xy 76.119458 -27.231737) (xy 76.118974 -27.204162)
			(xy 76.11946 -27.176911) (xy 76.127216 -27.122963) (xy 76.142571 -27.070668) (xy 76.165213 -27.021091)
			(xy 76.194679 -26.975241) (xy 76.23037 -26.93405) (xy 76.271561 -26.898359) (xy 76.317411 -26.868893)
			(xy 76.366988 -26.846251) (xy 76.419283 -26.830896) (xy 76.473231 -26.82314) (xy 76.527733 -26.82314)
			(xy 76.581681 -26.830896) (xy 76.633976 -26.846251) (xy 76.683553 -26.868893) (xy 76.729403 -26.898359)
			(xy 76.770594 -26.93405) (xy 76.806285 -26.975241) (xy 76.835751 -27.021091) (xy 76.858393 -27.070668)
			(xy 76.873748 -27.122963) (xy 76.881504 -27.176911) (xy 76.88199 -27.204162) (xy 76.881502 -27.231736)
			(xy 76.873554 -27.286308) (xy 76.857834 -27.339167) (xy 76.834668 -27.389213) (xy 76.804539 -27.435404)
			(xy 76.768076 -27.476776) (xy 76.74737 -27.494992) (xy 76.736514 -27.504931) (xy 76.720445 -27.529571)
			(xy 76.71206 -27.557767) (xy 76.712053 -27.587184) (xy 76.720425 -27.615384) (xy 76.736481 -27.640032)
			(xy 76.74737 -27.649932) (xy 76.768094 -27.66813) (xy 76.804564 -27.7095) (xy 76.834696 -27.755693)
			(xy 76.85786 -27.805744) (xy 76.873573 -27.858609) (xy 76.881508 -27.913186) (xy 76.88199 -27.940762)
			(xy 76.881561 -27.967079) (xy 76.874337 -28.019214) (xy 76.860019 -28.069863) (xy 76.83888 -28.118065)
			(xy 76.81132 -28.162906) (xy 76.777862 -28.203537) (xy 76.7588 -28.221686) (xy 76.748818 -28.231534)
			(xy 76.734119 -28.255397) (xy 76.726476 -28.282361) (xy 76.726469 -28.310388) (xy 76.734098 -28.337356)
			(xy 76.748785 -28.361226) (xy 76.7588 -28.371038) (xy 76.777898 -28.389154) (xy 76.811374 -28.429779)
			(xy 76.838942 -28.474623) (xy 76.860078 -28.522834) (xy 76.874378 -28.573495) (xy 76.881572 -28.625641)
			(xy 76.88199 -28.651962) (xy 78.62697 -28.651962) (xy 78.627428 -28.625646) (xy 78.634648 -28.573513)
			(xy 78.648961 -28.522865) (xy 78.670095 -28.474663) (xy 78.697649 -28.429821) (xy 78.731101 -28.389189)
			(xy 78.75016 -28.371038) (xy 78.760222 -28.361264) (xy 78.774923 -28.337381) (xy 78.782559 -28.310397)
			(xy 78.782552 -28.282352) (xy 78.774902 -28.255371) (xy 78.760189 -28.231496) (xy 78.75016 -28.221686)
			(xy 78.731085 -28.203546) (xy 78.697605 -28.162928) (xy 78.670032 -28.118089) (xy 78.648892 -28.069883)
			(xy 78.634587 -28.019225) (xy 78.62739 -27.967081) (xy 78.62697 -27.940762) (xy 78.627489 -27.913189)
			(xy 78.635432 -27.858619) (xy 78.651147 -27.805761) (xy 78.674307 -27.755715) (xy 78.70443 -27.709524)
			(xy 78.740888 -27.66815) (xy 78.76159 -27.649932) (xy 78.772526 -27.640072) (xy 78.788598 -27.615411)
			(xy 78.796978 -27.587193) (xy 78.796971 -27.557758) (xy 78.788577 -27.529544) (xy 78.772493 -27.504891)
			(xy 78.76159 -27.494992) (xy 78.74087 -27.476791) (xy 78.704401 -27.43542) (xy 78.67427 -27.389228)
			(xy 78.651106 -27.339178) (xy 78.635391 -27.286314) (xy 78.627454 -27.231737) (xy 78.62697 -27.204162)
			(xy 78.627456 -27.176911) (xy 78.635212 -27.122963) (xy 78.650567 -27.070668) (xy 78.673209 -27.021091)
			(xy 78.702675 -26.975241) (xy 78.738366 -26.93405) (xy 78.779557 -26.898359) (xy 78.825407 -26.868893)
			(xy 78.874984 -26.846251) (xy 78.927279 -26.830896) (xy 78.981227 -26.82314) (xy 79.035729 -26.82314)
			(xy 79.089677 -26.830896) (xy 79.141972 -26.846251) (xy 79.191549 -26.868893) (xy 79.237399 -26.898359)
			(xy 79.27859 -26.93405) (xy 79.314281 -26.975241) (xy 79.343747 -27.021091) (xy 79.366389 -27.070668)
			(xy 79.381744 -27.122963) (xy 79.3895 -27.176911) (xy 79.389986 -27.204162) (xy 79.389499 -27.231736)
			(xy 79.381552 -27.286308) (xy 79.365831 -27.339168) (xy 79.342665 -27.389214) (xy 79.312536 -27.435404)
			(xy 79.276072 -27.476776) (xy 79.255366 -27.494992) (xy 79.24451 -27.504931) (xy 79.228442 -27.529571)
			(xy 79.220058 -27.557767) (xy 79.22005 -27.587184) (xy 79.228422 -27.615384) (xy 79.244478 -27.640032)
			(xy 79.255366 -27.649932) (xy 79.276089 -27.66813) (xy 79.31256 -27.709501) (xy 79.342691 -27.755693)
			(xy 79.365855 -27.805744) (xy 79.381569 -27.858609) (xy 79.389504 -27.913186) (xy 79.389986 -27.940762)
			(xy 79.389559 -27.967079) (xy 79.382334 -28.019214) (xy 79.368016 -28.069863) (xy 79.346877 -28.118065)
			(xy 79.319317 -28.162906) (xy 79.285858 -28.203537) (xy 79.266796 -28.221686) (xy 79.256814 -28.231534)
			(xy 79.242116 -28.255397) (xy 79.234473 -28.282361) (xy 79.234466 -28.310388) (xy 79.242095 -28.337356)
			(xy 79.256782 -28.361226) (xy 79.266796 -28.371038) (xy 79.285893 -28.389155) (xy 79.31937 -28.429779)
			(xy 79.346938 -28.474623) (xy 79.368073 -28.522834) (xy 79.382374 -28.573495) (xy 79.389568 -28.625641)
			(xy 79.389986 -28.651962) (xy 79.3895 -28.679213) (xy 79.381744 -28.733161) (xy 79.366389 -28.785456)
			(xy 79.343747 -28.835033) (xy 79.314281 -28.880883) (xy 79.27859 -28.922074) (xy 79.237399 -28.957765)
			(xy 79.191549 -28.987231) (xy 79.141972 -29.009873) (xy 79.089677 -29.025228) (xy 79.035729 -29.032984)
			(xy 78.981227 -29.032984) (xy 78.927279 -29.025228) (xy 78.874984 -29.009873) (xy 78.825407 -28.987231)
			(xy 78.779557 -28.957765) (xy 78.738366 -28.922074) (xy 78.702675 -28.880883) (xy 78.673209 -28.835033)
			(xy 78.650567 -28.785456) (xy 78.635212 -28.733161) (xy 78.627456 -28.679213) (xy 78.62697 -28.651962)
			(xy 76.88199 -28.651962) (xy 76.881504 -28.679213) (xy 76.873748 -28.733161) (xy 76.858393 -28.785456)
			(xy 76.835751 -28.835033) (xy 76.806285 -28.880883) (xy 76.770594 -28.922074) (xy 76.729403 -28.957765)
			(xy 76.683553 -28.987231) (xy 76.633976 -29.009873) (xy 76.581681 -29.025228) (xy 76.527733 -29.032984)
			(xy 76.473231 -29.032984) (xy 76.419283 -29.025228) (xy 76.366988 -29.009873) (xy 76.317411 -28.987231)
			(xy 76.271561 -28.957765) (xy 76.23037 -28.922074) (xy 76.194679 -28.880883) (xy 76.165213 -28.835033)
			(xy 76.142571 -28.785456) (xy 76.127216 -28.733161) (xy 76.11946 -28.679213) (xy 76.118974 -28.651962)
			(xy 64.761709 -28.651962) (xy 64.750161 -28.66485) (xy 64.707293 -28.700525) (xy 64.659687 -28.729579)
			(xy 64.608358 -28.751391) (xy 64.554401 -28.765497) (xy 64.498964 -28.771597) (xy 64.44323 -28.76956)
			(xy 64.388387 -28.75943) (xy 64.335603 -28.741423) (xy 64.286003 -28.715922) (xy 64.240645 -28.683471)
			(xy 64.200496 -28.644762) (xy 64.16641 -28.600619) (xy 64.139114 -28.551984) (xy 64.119191 -28.499893)
			(xy 64.107065 -28.445456) (xy 64.102994 -28.389834) (xy 63.60668 -28.389834) (xy 63.60668 -29.393388)
			(xy 64.111122 -29.393388) (xy 64.115193 -29.337766) (xy 64.127319 -29.283329) (xy 64.147242 -29.231238)
			(xy 64.174538 -29.182603) (xy 64.208624 -29.13846) (xy 64.248773 -29.099751) (xy 64.294131 -29.0673)
			(xy 64.343731 -29.041799) (xy 64.396515 -29.023792) (xy 64.451358 -29.013662) (xy 64.507092 -29.011625)
			(xy 64.562529 -29.017725) (xy 64.616486 -29.031831) (xy 64.667815 -29.053643) (xy 64.715421 -29.082697)
			(xy 64.758289 -29.118372) (xy 64.795506 -29.159909) (xy 64.826279 -29.206422) (xy 64.849951 -29.256919)
			(xy 64.866019 -29.310326) (xy 64.874139 -29.365502) (xy 64.874594 -29.390453) (xy 71.46464 -29.390453)
			(xy 71.46464 -29.335947) (xy 71.472397 -29.281996) (xy 71.487752 -29.229698) (xy 71.510394 -29.180117)
			(xy 71.539861 -29.134263) (xy 71.575554 -29.093069) (xy 71.616745 -29.057374) (xy 71.662598 -29.027904)
			(xy 71.712177 -29.00526) (xy 71.764474 -28.989901) (xy 71.818425 -28.982141) (xy 71.845678 -28.981654)
			(xy 71.874595 -28.982168) (xy 71.931768 -28.990895) (xy 71.986967 -29.008152) (xy 72.03893 -29.033545)
			(xy 72.086463 -29.06649) (xy 72.128479 -29.106233) (xy 72.146668 -29.12872) (xy 72.156565 -29.140525)
			(xy 72.181889 -29.158044) (xy 72.211282 -29.16722) (xy 72.242074 -29.16722) (xy 72.271467 -29.158044)
			(xy 72.296791 -29.140525) (xy 72.306688 -29.12872) (xy 72.324891 -29.106246) (xy 72.366908 -29.06651)
			(xy 72.41444 -29.033569) (xy 72.466399 -29.008179) (xy 72.521595 -28.990921) (xy 72.578763 -28.98219)
			(xy 72.607678 -28.981654) (xy 72.634929 -28.982192) (xy 72.688877 -28.989945) (xy 72.741172 -29.005298)
			(xy 72.79075 -29.027937) (xy 72.836602 -29.057401) (xy 72.877793 -29.093092) (xy 72.913485 -29.134281)
			(xy 72.942952 -29.18013) (xy 72.965594 -29.229707) (xy 72.98095 -29.282001) (xy 72.988707 -29.335949)
			(xy 72.988707 -29.390451) (xy 72.98095 -29.444399) (xy 72.965594 -29.496693) (xy 72.942952 -29.54627)
			(xy 72.913485 -29.592119) (xy 72.877793 -29.633308) (xy 72.836602 -29.668999) (xy 72.79075 -29.698463)
			(xy 72.741172 -29.721102) (xy 72.688877 -29.736455) (xy 72.634929 -29.744208) (xy 72.607678 -29.74467)
			(xy 72.578763 -29.744107) (xy 72.521593 -29.735389) (xy 72.466395 -29.71814) (xy 72.414433 -29.692757)
			(xy 72.366898 -29.659821) (xy 72.324879 -29.620086) (xy 72.306688 -29.597604) (xy 72.296791 -29.585799)
			(xy 72.271467 -29.56828) (xy 72.242074 -29.559104) (xy 72.211282 -29.559104) (xy 72.181889 -29.56828)
			(xy 72.156565 -29.585799) (xy 72.146668 -29.597604) (xy 72.128496 -29.620104) (xy 72.086472 -29.659838)
			(xy 72.038933 -29.692775) (xy 71.986968 -29.71816) (xy 71.931767 -29.735413) (xy 71.874595 -29.744137)
			(xy 71.845678 -29.74467) (xy 71.818425 -29.744259) (xy 71.764474 -29.736499) (xy 71.712177 -29.72114)
			(xy 71.662598 -29.698496) (xy 71.616745 -29.669026) (xy 71.575554 -29.633331) (xy 71.539861 -29.592137)
			(xy 71.510394 -29.546283) (xy 71.487752 -29.496702) (xy 71.472397 -29.444404) (xy 71.46464 -29.390453)
			(xy 64.874594 -29.390453) (xy 64.874648 -29.393388) (xy 64.874139 -29.421274) (xy 64.866019 -29.47645)
			(xy 64.849951 -29.529857) (xy 64.826279 -29.580354) (xy 64.795506 -29.626867) (xy 64.758289 -29.668404)
			(xy 64.715421 -29.704079) (xy 64.667815 -29.733133) (xy 64.616486 -29.754945) (xy 64.562529 -29.769051)
			(xy 64.507092 -29.775151) (xy 64.451358 -29.773114) (xy 64.396515 -29.762984) (xy 64.343731 -29.744977)
			(xy 64.294131 -29.719476) (xy 64.248773 -29.687025) (xy 64.208624 -29.648316) (xy 64.174538 -29.604173)
			(xy 64.147242 -29.555538) (xy 64.127319 -29.503447) (xy 64.115193 -29.44901) (xy 64.111122 -29.393388)
			(xy 63.60668 -29.393388) (xy 63.60668 -30.714188) (xy 66.559682 -30.714188) (xy 66.563753 -30.658566)
			(xy 66.575879 -30.604129) (xy 66.595802 -30.552038) (xy 66.623098 -30.503403) (xy 66.657184 -30.45926)
			(xy 66.697333 -30.420551) (xy 66.742691 -30.3881) (xy 66.792291 -30.362599) (xy 66.845075 -30.344592)
			(xy 66.899918 -30.334462) (xy 66.955652 -30.332425) (xy 67.011089 -30.338525) (xy 67.065046 -30.352631)
			(xy 67.116375 -30.374443) (xy 67.163981 -30.403497) (xy 67.206849 -30.439172) (xy 67.244066 -30.480709)
			(xy 67.274839 -30.527222) (xy 67.298511 -30.577719) (xy 67.314579 -30.631126) (xy 67.322699 -30.686302)
			(xy 67.323208 -30.714188) (xy 67.322699 -30.742074) (xy 67.320448 -30.757368) (xy 67.993006 -30.757368)
			(xy 67.993515 -30.730025) (xy 68.001315 -30.675899) (xy 68.016764 -30.623441) (xy 68.039546 -30.573726)
			(xy 68.069194 -30.527775) (xy 68.1051 -30.486529) (xy 68.146528 -30.450832) (xy 68.192629 -30.421418)
			(xy 68.242459 -30.398889) (xy 68.268596 -30.390846) (xy 68.282727 -30.386219) (xy 68.307666 -30.370051)
			(xy 68.326898 -30.347391) (xy 68.338796 -30.320155) (xy 68.342354 -30.290647) (xy 68.33727 -30.261364)
			(xy 68.33108 -30.247844) (xy 68.318428 -30.221234) (xy 68.300553 -30.16509) (xy 68.2915 -30.10687)
			(xy 68.290948 -30.07741) (xy 68.291487 -30.050161) (xy 68.299241 -29.996218) (xy 68.314593 -29.943927)
			(xy 68.33723 -29.894352) (xy 68.366691 -29.848504) (xy 68.402377 -29.807315) (xy 68.443561 -29.771623)
			(xy 68.489405 -29.742156) (xy 68.538976 -29.719512) (xy 68.591265 -29.704153) (xy 68.645207 -29.696391)
			(xy 68.672456 -29.695902) (xy 68.69906 -29.696384) (xy 68.751752 -29.703772) (xy 68.802907 -29.718411)
			(xy 68.85153 -29.740017) (xy 68.896679 -29.768171) (xy 68.937478 -29.802326) (xy 68.973134 -29.84182)
			(xy 69.002955 -29.885885) (xy 69.026364 -29.933667) (xy 69.042905 -29.984238) (xy 69.052257 -30.036618)
			(xy 69.05371 -30.063186) (xy 69.054599 -30.076583) (xy 69.062641 -30.102195) (xy 69.077068 -30.124834)
			(xy 69.096886 -30.142941) (xy 69.120732 -30.155271) (xy 69.146964 -30.160974) (xy 69.16039 -30.160722)
			(xy 69.179694 -30.160214) (xy 69.206949 -30.160632) (xy 69.260903 -30.168389) (xy 69.313205 -30.183746)
			(xy 69.362789 -30.206389) (xy 69.408645 -30.235859) (xy 69.449841 -30.271554) (xy 69.485538 -30.31275)
			(xy 69.515008 -30.358606) (xy 69.537652 -30.408189) (xy 69.55301 -30.460491) (xy 69.560767 -30.514445)
			(xy 69.560767 -30.54223) (xy 69.67042 -30.54223) (xy 69.674491 -30.486608) (xy 69.686617 -30.432171)
			(xy 69.70654 -30.38008) (xy 69.733836 -30.331445) (xy 69.767922 -30.287302) (xy 69.808071 -30.248593)
			(xy 69.853429 -30.216142) (xy 69.903029 -30.190641) (xy 69.955813 -30.172634) (xy 70.010656 -30.162504)
			(xy 70.06639 -30.160467) (xy 70.121827 -30.166567) (xy 70.175784 -30.180673) (xy 70.227113 -30.202485)
			(xy 70.274719 -30.231539) (xy 70.317587 -30.267214) (xy 70.354804 -30.308751) (xy 70.385577 -30.355264)
			(xy 70.409249 -30.405761) (xy 70.425317 -30.459168) (xy 70.433437 -30.514344) (xy 70.433946 -30.54223)
			(xy 70.433437 -30.570116) (xy 70.425317 -30.625292) (xy 70.409249 -30.678699) (xy 70.385577 -30.729196)
			(xy 70.354804 -30.775709) (xy 70.317587 -30.817246) (xy 70.274719 -30.852921) (xy 70.227113 -30.881975)
			(xy 70.175784 -30.903787) (xy 70.121827 -30.917893) (xy 70.06639 -30.923993) (xy 70.010656 -30.921956)
			(xy 69.955813 -30.911826) (xy 69.903029 -30.893819) (xy 69.853429 -30.868318) (xy 69.808071 -30.835867)
			(xy 69.767922 -30.797158) (xy 69.733836 -30.753015) (xy 69.70654 -30.70438) (xy 69.686617 -30.652289)
			(xy 69.674491 -30.597852) (xy 69.67042 -30.54223) (xy 69.560767 -30.54223) (xy 69.560767 -30.568955)
			(xy 69.55301 -30.622909) (xy 69.537652 -30.675211) (xy 69.515008 -30.724794) (xy 69.485538 -30.77065)
			(xy 69.449841 -30.811846) (xy 69.408645 -30.847541) (xy 69.362789 -30.877011) (xy 69.313205 -30.899654)
			(xy 69.260903 -30.915011) (xy 69.206949 -30.922768) (xy 69.179694 -30.92323) (xy 69.149967 -30.922675)
			(xy 69.091233 -30.913439) (xy 69.034643 -30.895206) (xy 68.981564 -30.868419) (xy 68.933282 -30.833725)
			(xy 68.911724 -30.813248) (xy 68.900602 -30.802941) (xy 68.87378 -30.78883) (xy 68.843997 -30.783217)
			(xy 68.813879 -30.786599) (xy 68.786082 -30.798678) (xy 68.763058 -30.818387) (xy 68.746838 -30.843989)
			(xy 68.742306 -30.85846) (xy 68.734516 -30.884963) (xy 68.712369 -30.935568) (xy 68.710877 -30.937962)
			(xy 73.16546 -30.937962) (xy 73.169531 -30.88234) (xy 73.181657 -30.827903) (xy 73.20158 -30.775812)
			(xy 73.228876 -30.727177) (xy 73.262962 -30.683034) (xy 73.303111 -30.644325) (xy 73.348469 -30.611874)
			(xy 73.398069 -30.586373) (xy 73.450853 -30.568366) (xy 73.505696 -30.558236) (xy 73.56143 -30.556199)
			(xy 73.616867 -30.562299) (xy 73.670824 -30.576405) (xy 73.722153 -30.598217) (xy 73.769759 -30.627271)
			(xy 73.812627 -30.662946) (xy 73.849844 -30.704483) (xy 73.880617 -30.750996) (xy 73.904289 -30.801493)
			(xy 73.920357 -30.8549) (xy 73.928477 -30.910076) (xy 73.928986 -30.937962) (xy 73.928477 -30.965848)
			(xy 73.920357 -31.021024) (xy 73.904289 -31.074431) (xy 73.880617 -31.124928) (xy 73.849844 -31.171441)
			(xy 73.812627 -31.212978) (xy 73.769759 -31.248653) (xy 73.722153 -31.277707) (xy 73.670824 -31.299519)
			(xy 73.616867 -31.313625) (xy 73.56143 -31.319725) (xy 73.505696 -31.317688) (xy 73.450853 -31.307558)
			(xy 73.398069 -31.289551) (xy 73.348469 -31.26405) (xy 73.303111 -31.231599) (xy 73.262962 -31.19289)
			(xy 73.228876 -31.148747) (xy 73.20158 -31.100112) (xy 73.181657 -31.048021) (xy 73.169531 -30.993584)
			(xy 73.16546 -30.937962) (xy 68.710877 -30.937962) (xy 68.683152 -30.982448) (xy 68.647475 -31.02462)
			(xy 68.606086 -31.061203) (xy 68.559851 -31.09143) (xy 68.509738 -31.114669) (xy 68.456796 -31.130433)
			(xy 68.402134 -31.138392) (xy 68.374514 -31.138876) (xy 68.34726 -31.138432) (xy 68.293307 -31.130676)
			(xy 68.241007 -31.11532) (xy 68.191424 -31.092677) (xy 68.14557 -31.063207) (xy 68.104376 -31.027511)
			(xy 68.068682 -30.986316) (xy 68.039215 -30.94046) (xy 68.016574 -30.890877) (xy 68.001221 -30.838576)
			(xy 67.993467 -30.784622) (xy 67.993006 -30.757368) (xy 67.320448 -30.757368) (xy 67.314579 -30.79725)
			(xy 67.298511 -30.850657) (xy 67.274839 -30.901154) (xy 67.244066 -30.947667) (xy 67.206849 -30.989204)
			(xy 67.163981 -31.024879) (xy 67.116375 -31.053933) (xy 67.065046 -31.075745) (xy 67.011089 -31.089851)
			(xy 66.955652 -31.095951) (xy 66.899918 -31.093914) (xy 66.845075 -31.083784) (xy 66.792291 -31.065777)
			(xy 66.742691 -31.040276) (xy 66.697333 -31.007825) (xy 66.657184 -30.969116) (xy 66.623098 -30.924973)
			(xy 66.595802 -30.876338) (xy 66.575879 -30.824247) (xy 66.563753 -30.76981) (xy 66.559682 -30.714188)
			(xy 63.60668 -30.714188) (xy 63.60668 -31.874968) (xy 67.159122 -31.874968) (xy 67.163193 -31.819346)
			(xy 67.175319 -31.764909) (xy 67.195242 -31.712818) (xy 67.222538 -31.664183) (xy 67.256624 -31.62004)
			(xy 67.296773 -31.581331) (xy 67.342131 -31.54888) (xy 67.391731 -31.523379) (xy 67.444515 -31.505372)
			(xy 67.499358 -31.495242) (xy 67.555092 -31.493205) (xy 67.610529 -31.499305) (xy 67.664486 -31.513411)
			(xy 67.715815 -31.535223) (xy 67.763421 -31.564277) (xy 67.806289 -31.599952) (xy 67.819215 -31.614378)
			(xy 76.262735 -31.614378) (xy 76.266468 -31.561124) (xy 76.277587 -31.508911) (xy 76.295875 -31.458757)
			(xy 76.320975 -31.411641) (xy 76.352398 -31.368485) (xy 76.389529 -31.330129) (xy 76.410312 -31.313374)
			(xy 76.422151 -31.303515) (xy 76.439663 -31.278179) (xy 76.448833 -31.248777) (xy 76.448826 -31.217979)
			(xy 76.439644 -31.188581) (xy 76.42212 -31.163253) (xy 76.410312 -31.153354) (xy 76.387857 -31.135129)
			(xy 76.348119 -31.093117) (xy 76.315177 -31.045589) (xy 76.289783 -30.993634) (xy 76.272521 -30.938443)
			(xy 76.263785 -30.881278) (xy 76.263246 -30.852364) (xy 76.263732 -30.825113) (xy 76.271488 -30.771165)
			(xy 76.286843 -30.71887) (xy 76.309485 -30.669293) (xy 76.338951 -30.623443) (xy 76.374642 -30.582252)
			(xy 76.415833 -30.546561) (xy 76.461683 -30.517095) (xy 76.51126 -30.494453) (xy 76.563555 -30.479098)
			(xy 76.617503 -30.471342) (xy 76.672005 -30.471342) (xy 76.725953 -30.479098) (xy 76.778248 -30.494453)
			(xy 76.827825 -30.517095) (xy 76.873675 -30.546561) (xy 76.914866 -30.582252) (xy 76.950557 -30.623443)
			(xy 76.980023 -30.669293) (xy 77.002665 -30.71887) (xy 77.01802 -30.771165) (xy 77.025776 -30.825113)
			(xy 77.026262 -30.852364) (xy 77.025732 -30.881281) (xy 77.017008 -30.938452) (xy 76.999753 -30.993651)
			(xy 76.974364 -31.045613) (xy 76.941421 -31.093147) (xy 76.901681 -31.135164) (xy 76.879196 -31.153354)
			(xy 76.867429 -31.163292) (xy 76.849913 -31.188605) (xy 76.840736 -31.217987) (xy 76.840729 -31.248769)
			(xy 76.849894 -31.278155) (xy 76.867398 -31.303476) (xy 76.879196 -31.313374) (xy 76.899945 -31.330169)
			(xy 76.937079 -31.368515) (xy 76.968505 -31.411664) (xy 76.993607 -31.458772) (xy 77.011898 -31.508921)
			(xy 77.023018 -31.561129) (xy 77.026751 -31.614378) (xy 77.026699 -31.615116) (xy 78.804532 -31.615116)
			(xy 78.80826 -31.561866) (xy 78.819375 -31.509656) (xy 78.83766 -31.459505) (xy 78.862758 -31.412393)
			(xy 78.894178 -31.36924) (xy 78.931308 -31.330889) (xy 78.95209 -31.314136) (xy 78.963869 -31.30421)
			(xy 78.981386 -31.278894) (xy 78.990564 -31.249509) (xy 78.990569 -31.218723) (xy 78.9814 -31.189335)
			(xy 78.963891 -31.164014) (xy 78.95209 -31.154116) (xy 78.929612 -31.135918) (xy 78.889877 -31.0939)
			(xy 78.856938 -31.046366) (xy 78.831548 -30.994406) (xy 78.814291 -30.93921) (xy 78.80556 -30.882042)
			(xy 78.805024 -30.853126) (xy 78.80551 -30.825875) (xy 78.813266 -30.771927) (xy 78.828621 -30.719632)
			(xy 78.851263 -30.670055) (xy 78.880729 -30.624205) (xy 78.91642 -30.583014) (xy 78.957611 -30.547323)
			(xy 79.003461 -30.517857) (xy 79.053038 -30.495215) (xy 79.105333 -30.47986) (xy 79.159281 -30.472104)
			(xy 79.213783 -30.472104) (xy 79.267731 -30.47986) (xy 79.320026 -30.495215) (xy 79.369603 -30.517857)
			(xy 79.415453 -30.547323) (xy 79.456644 -30.583014) (xy 79.492335 -30.624205) (xy 79.507254 -30.647419)
			(xy 86.090816 -30.647419) (xy 86.09082 -30.592923) (xy 86.09858 -30.538982) (xy 86.113937 -30.486695)
			(xy 86.136579 -30.437126) (xy 86.166044 -30.391283) (xy 86.201734 -30.3501) (xy 86.242921 -30.314415)
			(xy 86.288768 -30.284956) (xy 86.33834 -30.26232) (xy 86.390629 -30.24697) (xy 86.444571 -30.239217)
			(xy 86.499067 -30.239219) (xy 86.553007 -30.246978) (xy 86.605295 -30.262333) (xy 86.654865 -30.284973)
			(xy 86.700709 -30.314438) (xy 86.741892 -30.350126) (xy 86.777578 -30.391313) (xy 86.807039 -30.437158)
			(xy 86.829676 -30.48673) (xy 86.845028 -30.539019) (xy 86.852782 -30.59296) (xy 86.853268 -30.620208)
			(xy 86.853185 -30.630516) (xy 86.852039 -30.651102) (xy 86.850982 -30.661356) (xy 86.849907 -30.676305)
			(xy 86.855508 -30.705733) (xy 86.869396 -30.732277) (xy 86.890379 -30.753658) (xy 86.916657 -30.768042)
			(xy 86.945975 -30.774196) (xy 86.975819 -30.771592) (xy 86.98992 -30.766512) (xy 87.012608 -30.7578)
			(xy 87.059647 -30.745578) (xy 87.107859 -30.73944) (xy 87.13216 -30.73908) (xy 87.159417 -30.739512)
			(xy 87.213376 -30.747265) (xy 87.265682 -30.762618) (xy 87.315271 -30.785259) (xy 87.361133 -30.814727)
			(xy 87.402334 -30.850422) (xy 87.438036 -30.891617) (xy 87.467511 -30.937474) (xy 87.49016 -30.987059)
			(xy 87.505522 -31.039363) (xy 87.513283 -31.093321) (xy 87.513285 -31.120588) (xy 91.515182 -31.120588)
			(xy 91.519253 -31.064966) (xy 91.531379 -31.010529) (xy 91.551302 -30.958438) (xy 91.578598 -30.909803)
			(xy 91.612684 -30.86566) (xy 91.652833 -30.826951) (xy 91.698191 -30.7945) (xy 91.747791 -30.768999)
			(xy 91.800575 -30.750992) (xy 91.855418 -30.740862) (xy 91.911152 -30.738825) (xy 91.966589 -30.744925)
			(xy 92.020546 -30.759031) (xy 92.071875 -30.780843) (xy 92.119481 -30.809897) (xy 92.162349 -30.845572)
			(xy 92.199566 -30.887109) (xy 92.230339 -30.933622) (xy 92.254011 -30.984119) (xy 92.270079 -31.037526)
			(xy 92.278199 -31.092702) (xy 92.278708 -31.120588) (xy 92.278199 -31.148474) (xy 92.270079 -31.20365)
			(xy 92.260681 -31.234888) (xy 94.241112 -31.234888) (xy 94.241544 -31.207634) (xy 94.249303 -31.153681)
			(xy 94.264661 -31.101381) (xy 94.287307 -31.051799) (xy 94.316778 -31.005945) (xy 94.352475 -30.964752)
			(xy 94.393671 -30.929059) (xy 94.439528 -30.899591) (xy 94.489111 -30.87695) (xy 94.541412 -30.861596)
			(xy 94.595366 -30.853841) (xy 94.62262 -30.85338) (xy 94.654035 -30.854007) (xy 94.716022 -30.864267)
			(xy 94.775492 -30.88454) (xy 94.803468 -30.898846) (xy 94.815592 -30.90483) (xy 94.84191 -30.910962)
			(xy 94.868915 -30.90997) (xy 94.894712 -30.901923) (xy 94.917492 -30.887387) (xy 94.935658 -30.86738)
			(xy 94.947934 -30.843307) (xy 94.95346 -30.816855) (xy 94.953074 -30.803342) (xy 94.952312 -30.780228)
			(xy 94.952725 -30.752973) (xy 94.960479 -30.699017) (xy 94.975832 -30.646714) (xy 94.998473 -30.597128)
			(xy 95.02794 -30.55127) (xy 95.063633 -30.510071) (xy 95.104827 -30.474372) (xy 95.150682 -30.444898)
			(xy 95.200264 -30.422251) (xy 95.252565 -30.40689) (xy 95.30652 -30.399129) (xy 95.36103 -30.399125)
			(xy 95.414985 -30.406879) (xy 95.467288 -30.422233) (xy 95.516874 -30.444874) (xy 95.562733 -30.474341)
			(xy 95.603931 -30.510035) (xy 95.63963 -30.551229) (xy 95.669103 -30.597084) (xy 95.69175 -30.646667)
			(xy 95.707111 -30.698968) (xy 95.714871 -30.752922) (xy 95.714875 -30.807432) (xy 95.70712 -30.861388)
			(xy 95.691766 -30.913691) (xy 95.669125 -30.963276) (xy 95.639657 -31.009135) (xy 95.629511 -31.020845)
			(xy 96.375142 -31.020845) (xy 96.375144 -30.966336) (xy 96.382902 -30.912383) (xy 96.398261 -30.860083)
			(xy 96.420906 -30.810501) (xy 96.450377 -30.764647) (xy 96.486074 -30.723453) (xy 96.52727 -30.687759)
			(xy 96.573127 -30.658292) (xy 96.622711 -30.63565) (xy 96.675012 -30.620296) (xy 96.728966 -30.612541)
			(xy 96.75622 -30.61208) (xy 96.773204 -30.61229) (xy 96.807036 -30.615345) (xy 96.823784 -30.618176)
			(xy 96.837619 -30.620257) (xy 96.865458 -30.61754) (xy 96.891518 -30.60738) (xy 96.913849 -30.590537)
			(xy 96.930781 -30.568273) (xy 96.941044 -30.542253) (xy 96.943872 -30.514426) (xy 96.941894 -30.500574)
			(xy 96.939186 -30.484262) (xy 96.936262 -30.451322) (xy 96.936052 -30.434788) (xy 96.936568 -30.407536)
			(xy 96.944327 -30.353586) (xy 96.959685 -30.301289) (xy 96.982329 -30.251711) (xy 97.011798 -30.20586)
			(xy 97.047493 -30.164669) (xy 97.088686 -30.128978) (xy 97.13454 -30.099513) (xy 97.184121 -30.076873)
			(xy 97.236418 -30.06152) (xy 97.290369 -30.053766) (xy 97.344874 -30.053769) (xy 97.398823 -30.061529)
			(xy 97.451119 -30.076888) (xy 97.500697 -30.099533) (xy 97.546548 -30.129004) (xy 97.587737 -30.164699)
			(xy 97.623428 -30.205894) (xy 97.652892 -30.251748) (xy 97.67553 -30.301329) (xy 97.690882 -30.353628)
			(xy 97.698635 -30.407578) (xy 97.69863 -30.462083) (xy 97.690869 -30.516032) (xy 97.675509 -30.568328)
			(xy 97.652862 -30.617906) (xy 97.623391 -30.663755) (xy 97.587694 -30.704944) (xy 97.546499 -30.740633)
			(xy 97.500643 -30.770096) (xy 97.451062 -30.792734) (xy 97.398763 -30.808084) (xy 97.344812 -30.815836)
			(xy 97.31756 -30.816296) (xy 97.300576 -30.816076) (xy 97.266744 -30.813028) (xy 97.249996 -30.8102)
			(xy 97.236161 -30.808127) (xy 97.208326 -30.810848) (xy 97.182269 -30.82101) (xy 97.159941 -30.837851)
			(xy 97.14301 -30.860112) (xy 97.132744 -30.886127) (xy 97.129911 -30.913951) (xy 97.131886 -30.927802)
			(xy 97.134592 -30.944115) (xy 97.137517 -30.977054) (xy 97.137728 -30.993588) (xy 97.137258 -31.020842)
			(xy 97.129502 -31.074796) (xy 97.114147 -31.127097) (xy 97.091504 -31.17668) (xy 97.062036 -31.222536)
			(xy 97.026341 -31.263732) (xy 96.985147 -31.299428) (xy 96.939292 -31.328898) (xy 96.88971 -31.351542)
			(xy 96.837409 -31.366899) (xy 96.783456 -31.374657) (xy 96.728947 -31.374657) (xy 96.674993 -31.3669)
			(xy 96.622693 -31.351543) (xy 96.57311 -31.328899) (xy 96.527255 -31.299429) (xy 96.486061 -31.263734)
			(xy 96.450366 -31.222538) (xy 96.420897 -31.176683) (xy 96.398254 -31.127099) (xy 96.382898 -31.074799)
			(xy 96.375142 -31.020845) (xy 95.629511 -31.020845) (xy 95.603963 -31.050333) (xy 95.562769 -31.086031)
			(xy 95.516914 -31.115504) (xy 95.467331 -31.138151) (xy 95.41503 -31.153511) (xy 95.361075 -31.161272)
			(xy 95.33382 -31.161736) (xy 95.302405 -31.161091) (xy 95.240419 -31.150838) (xy 95.180949 -31.130573)
			(xy 95.152972 -31.11627) (xy 95.140889 -31.110198) (xy 95.114557 -31.104074) (xy 95.08754 -31.105076)
			(xy 95.061734 -31.113135) (xy 95.038948 -31.127684) (xy 95.020779 -31.147704) (xy 95.008503 -31.171791)
			(xy 95.002979 -31.198255) (xy 95.003366 -31.211774) (xy 95.004128 -31.234888) (xy 95.003572 -31.263983)
			(xy 94.994728 -31.321496) (xy 94.977244 -31.376997) (xy 94.951527 -31.429195) (xy 94.918174 -31.476877)
			(xy 94.898464 -31.498286) (xy 94.888913 -31.508833) (xy 94.875659 -31.534003) (xy 94.869868 -31.561853)
			(xy 94.87199 -31.59022) (xy 94.881859 -31.616899) (xy 94.898709 -31.639818) (xy 94.921231 -31.657195)
			(xy 94.934278 -31.662878) (xy 94.960485 -31.673861) (xy 95.009543 -31.702537) (xy 95.053805 -31.738171)
			(xy 95.092295 -31.779974) (xy 95.12416 -31.827022) (xy 95.148696 -31.878275) (xy 95.165361 -31.932601)
			(xy 95.173786 -31.988796) (xy 95.174308 -32.017208) (xy 95.173822 -32.044459) (xy 95.166066 -32.098407)
			(xy 95.150711 -32.150702) (xy 95.128069 -32.200279) (xy 95.098603 -32.246129) (xy 95.062912 -32.28732)
			(xy 95.021721 -32.323011) (xy 94.975871 -32.352477) (xy 94.926294 -32.375119) (xy 94.873999 -32.390474)
			(xy 94.820051 -32.39823) (xy 94.765549 -32.39823) (xy 94.711601 -32.390474) (xy 94.659306 -32.375119)
			(xy 94.609729 -32.352477) (xy 94.563879 -32.323011) (xy 94.522688 -32.28732) (xy 94.486997 -32.246129)
			(xy 94.457531 -32.200279) (xy 94.434889 -32.150702) (xy 94.419534 -32.098407) (xy 94.411778 -32.044459)
			(xy 94.411292 -32.017208) (xy 94.41184 -31.988113) (xy 94.420685 -31.930599) (xy 94.438171 -31.875098)
			(xy 94.46389 -31.8229) (xy 94.497245 -31.775218) (xy 94.516956 -31.75381) (xy 94.526505 -31.743262)
			(xy 94.539754 -31.718092) (xy 94.545543 -31.690243) (xy 94.543421 -31.661878) (xy 94.533553 -31.6352)
			(xy 94.516706 -31.612281) (xy 94.494187 -31.594903) (xy 94.481142 -31.589218) (xy 94.454938 -31.578228)
			(xy 94.40588 -31.549554) (xy 94.361616 -31.513922) (xy 94.323126 -31.47212) (xy 94.29126 -31.425072)
			(xy 94.266723 -31.37382) (xy 94.250059 -31.319495) (xy 94.241634 -31.2633) (xy 94.241112 -31.234888)
			(xy 92.260681 -31.234888) (xy 92.254011 -31.257057) (xy 92.230339 -31.307554) (xy 92.199566 -31.354067)
			(xy 92.162349 -31.395604) (xy 92.119481 -31.431279) (xy 92.071875 -31.460333) (xy 92.020546 -31.482145)
			(xy 91.966589 -31.496251) (xy 91.911152 -31.502351) (xy 91.855418 -31.500314) (xy 91.800575 -31.490184)
			(xy 91.747791 -31.472177) (xy 91.698191 -31.446676) (xy 91.652833 -31.414225) (xy 91.612684 -31.375516)
			(xy 91.578598 -31.331373) (xy 91.551302 -31.282738) (xy 91.531379 -31.230647) (xy 91.519253 -31.17621)
			(xy 91.515182 -31.120588) (xy 87.513285 -31.120588) (xy 87.513287 -31.147834) (xy 87.505532 -31.201793)
			(xy 87.490176 -31.254098) (xy 87.467533 -31.303686) (xy 87.438063 -31.349547) (xy 87.402366 -31.390746)
			(xy 87.361169 -31.426446) (xy 87.315311 -31.45592) (xy 87.265724 -31.478566) (xy 87.21342 -31.493926)
			(xy 87.159462 -31.501685) (xy 87.104949 -31.501685) (xy 87.050991 -31.493928) (xy 86.998686 -31.47857)
			(xy 86.949099 -31.455925) (xy 86.903239 -31.426453) (xy 86.862041 -31.390754) (xy 86.826343 -31.349555)
			(xy 86.796872 -31.303695) (xy 86.774228 -31.254108) (xy 86.758871 -31.201803) (xy 86.751114 -31.147845)
			(xy 86.750652 -31.120588) (xy 86.750735 -31.11028) (xy 86.751881 -31.089694) (xy 86.752938 -31.07944)
			(xy 86.753989 -31.064491) (xy 86.748388 -31.035067) (xy 86.734503 -31.008528) (xy 86.713524 -30.987149)
			(xy 86.687252 -30.972765) (xy 86.657939 -30.966608) (xy 86.6281 -30.969208) (xy 86.614 -30.974284)
			(xy 86.591309 -30.982989) (xy 86.544272 -30.995214) (xy 86.496061 -31.001354) (xy 86.47176 -31.001716)
			(xy 86.444512 -31.001179) (xy 86.390572 -30.993418) (xy 86.338285 -30.978059) (xy 86.288716 -30.955416)
			(xy 86.242874 -30.925949) (xy 86.201692 -30.890258) (xy 86.166009 -30.84907) (xy 86.13655 -30.803223)
			(xy 86.113916 -30.75365) (xy 86.098567 -30.70136) (xy 86.090816 -30.647419) (xy 79.507254 -30.647419)
			(xy 79.521801 -30.670055) (xy 79.544443 -30.719632) (xy 79.559798 -30.771927) (xy 79.567554 -30.825875)
			(xy 79.56804 -30.853126) (xy 79.567491 -30.882042) (xy 79.558772 -30.939213) (xy 79.541521 -30.994412)
			(xy 79.516135 -31.046374) (xy 79.483196 -31.093909) (xy 79.443458 -31.135926) (xy 79.420974 -31.154116)
			(xy 79.409147 -31.163987) (xy 79.391636 -31.18932) (xy 79.382467 -31.218718) (xy 79.382472 -31.249514)
			(xy 79.39165 -31.278909) (xy 79.409169 -31.304236) (xy 79.420974 -31.314136) (xy 79.441781 -31.33086)
			(xy 79.478909 -31.369218) (xy 79.510327 -31.412377) (xy 79.535423 -31.459494) (xy 79.553707 -31.509649)
			(xy 79.564821 -31.561863) (xy 79.568548 -31.615116) (xy 79.564816 -31.668369) (xy 79.553698 -31.720582)
			(xy 79.53541 -31.770736) (xy 79.51031 -31.81785) (xy 79.478888 -31.861007) (xy 79.441757 -31.899362)
			(xy 79.420974 -31.916116) (xy 79.409147 -31.925987) (xy 79.391636 -31.95132) (xy 79.382467 -31.980718)
			(xy 79.382472 -32.011514) (xy 79.39165 -32.040909) (xy 79.409169 -32.066236) (xy 79.420974 -32.076136)
			(xy 79.443469 -32.094313) (xy 79.483205 -32.136335) (xy 79.516143 -32.183873) (xy 79.54153 -32.235837)
			(xy 79.558783 -32.291037) (xy 79.567508 -32.348209) (xy 79.56804 -32.377126) (xy 79.567554 -32.404377)
			(xy 79.560514 -32.453346) (xy 91.979826 -32.453346) (xy 91.979826 -32.398854) (xy 91.98758 -32.344918)
			(xy 92.002931 -32.292634) (xy 92.025566 -32.243066) (xy 92.055023 -32.197224) (xy 92.090705 -32.15604)
			(xy 92.131884 -32.120353) (xy 92.177722 -32.09089) (xy 92.227287 -32.068248) (xy 92.279569 -32.052891)
			(xy 92.333505 -32.04513) (xy 92.36075 -32.04464) (xy 92.387354 -32.045109) (xy 92.440046 -32.052485)
			(xy 92.491202 -32.067114) (xy 92.539828 -32.088713) (xy 92.584979 -32.116862) (xy 92.625778 -32.151014)
			(xy 92.661433 -32.190506) (xy 92.676726 -32.21228) (xy 92.68506 -32.22376) (xy 92.706804 -32.241964)
			(xy 92.732717 -32.253482) (xy 92.7608 -32.257422) (xy 92.788883 -32.253482) (xy 92.814796 -32.241964)
			(xy 92.83654 -32.22376) (xy 92.844874 -32.21228) (xy 92.860186 -32.190522) (xy 92.895848 -32.151041)
			(xy 92.936648 -32.116895) (xy 92.981795 -32.088748) (xy 93.030414 -32.067143) (xy 93.081562 -32.052501)
			(xy 93.134249 -32.045105) (xy 93.16085 -32.04464) (xy 93.188109 -32.045004) (xy 93.242072 -32.052756)
			(xy 93.294382 -32.068109) (xy 93.343975 -32.090752) (xy 93.38984 -32.120222) (xy 93.431044 -32.15592)
			(xy 93.466748 -32.19712) (xy 93.496224 -32.242981) (xy 93.518873 -32.292571) (xy 93.534234 -32.344879)
			(xy 93.541993 -32.398841) (xy 93.541993 -32.453359) (xy 93.534234 -32.507321) (xy 93.518873 -32.559629)
			(xy 93.496224 -32.609219) (xy 93.466748 -32.65508) (xy 93.431044 -32.69628) (xy 93.38984 -32.731978)
			(xy 93.343975 -32.761448) (xy 93.294382 -32.784091) (xy 93.242072 -32.799444) (xy 93.188109 -32.807196)
			(xy 93.16085 -32.807656) (xy 93.134246 -32.807188) (xy 93.081553 -32.799813) (xy 93.030397 -32.785183)
			(xy 92.981772 -32.763584) (xy 92.936621 -32.735435) (xy 92.895822 -32.701282) (xy 92.860166 -32.66179)
			(xy 92.844874 -32.640016) (xy 92.83654 -32.628536) (xy 92.814796 -32.610332) (xy 92.788883 -32.598814)
			(xy 92.7608 -32.594874) (xy 92.732717 -32.598814) (xy 92.706804 -32.610332) (xy 92.68506 -32.628536)
			(xy 92.676726 -32.640016) (xy 92.661413 -32.661773) (xy 92.625751 -32.701255) (xy 92.584951 -32.7354)
			(xy 92.539805 -32.763548) (xy 92.491186 -32.785153) (xy 92.440038 -32.799795) (xy 92.387351 -32.807191)
			(xy 92.36075 -32.807656) (xy 92.333505 -32.80707) (xy 92.279569 -32.799309) (xy 92.227287 -32.783952)
			(xy 92.177722 -32.761311) (xy 92.131884 -32.731847) (xy 92.090705 -32.69616) (xy 92.055023 -32.654976)
			(xy 92.025566 -32.609134) (xy 92.002931 -32.559566) (xy 91.98758 -32.507282) (xy 91.979826 -32.453346)
			(xy 79.560514 -32.453346) (xy 79.559798 -32.458325) (xy 79.544443 -32.51062) (xy 79.521801 -32.560197)
			(xy 79.492335 -32.606047) (xy 79.456644 -32.647238) (xy 79.415453 -32.682929) (xy 79.369603 -32.712395)
			(xy 79.320026 -32.735037) (xy 79.267731 -32.750392) (xy 79.213783 -32.758148) (xy 79.159281 -32.758148)
			(xy 79.105333 -32.750392) (xy 79.053038 -32.735037) (xy 79.003461 -32.712395) (xy 78.957611 -32.682929)
			(xy 78.91642 -32.647238) (xy 78.880729 -32.606047) (xy 78.851263 -32.560197) (xy 78.828621 -32.51062)
			(xy 78.813266 -32.458325) (xy 78.80551 -32.404377) (xy 78.805024 -32.377126) (xy 78.805552 -32.348209)
			(xy 78.814278 -32.291038) (xy 78.831533 -32.235839) (xy 78.856923 -32.183877) (xy 78.889865 -32.136343)
			(xy 78.929605 -32.094326) (xy 78.95209 -32.076136) (xy 78.963869 -32.06621) (xy 78.981386 -32.040894)
			(xy 78.990564 -32.011509) (xy 78.990569 -31.980723) (xy 78.9814 -31.951335) (xy 78.963891 -31.926014)
			(xy 78.95209 -31.916116) (xy 78.931331 -31.899333) (xy 78.894199 -31.860984) (xy 78.862775 -31.817834)
			(xy 78.837673 -31.770724) (xy 78.819384 -31.720575) (xy 78.808265 -31.668365) (xy 78.804532 -31.615116)
			(xy 77.026699 -31.615116) (xy 77.023024 -31.667627) (xy 77.01191 -31.719837) (xy 76.993626 -31.769987)
			(xy 76.968528 -31.817099) (xy 76.937108 -31.860251) (xy 76.899978 -31.898602) (xy 76.879196 -31.915354)
			(xy 76.867429 -31.925292) (xy 76.849913 -31.950605) (xy 76.840736 -31.979987) (xy 76.840729 -32.010769)
			(xy 76.849894 -32.040155) (xy 76.867398 -32.065476) (xy 76.879196 -32.075374) (xy 76.901666 -32.093581)
			(xy 76.941402 -32.135597) (xy 76.974343 -32.183129) (xy 76.999734 -32.235087) (xy 77.016993 -32.290282)
			(xy 77.025725 -32.347449) (xy 77.026262 -32.376364) (xy 77.025776 -32.403615) (xy 77.01802 -32.457563)
			(xy 77.002665 -32.509858) (xy 76.980023 -32.559435) (xy 76.950557 -32.605285) (xy 76.914866 -32.646476)
			(xy 76.873675 -32.682167) (xy 76.827825 -32.711633) (xy 76.778248 -32.734275) (xy 76.725953 -32.74963)
			(xy 76.672005 -32.757386) (xy 76.617503 -32.757386) (xy 76.563555 -32.74963) (xy 76.51126 -32.734275)
			(xy 76.461683 -32.711633) (xy 76.415833 -32.682167) (xy 76.374642 -32.646476) (xy 76.338951 -32.605285)
			(xy 76.309485 -32.559435) (xy 76.286843 -32.509858) (xy 76.271488 -32.457563) (xy 76.263732 -32.403615)
			(xy 76.263246 -32.376364) (xy 76.263793 -32.347448) (xy 76.272513 -32.290277) (xy 76.289764 -32.235078)
			(xy 76.315151 -32.183116) (xy 76.34809 -32.135581) (xy 76.387828 -32.093564) (xy 76.410312 -32.075374)
			(xy 76.422151 -32.065515) (xy 76.439663 -32.040179) (xy 76.448833 -32.010777) (xy 76.448826 -31.979979)
			(xy 76.439644 -31.950581) (xy 76.42212 -31.925253) (xy 76.410312 -31.915354) (xy 76.389496 -31.898642)
			(xy 76.352369 -31.860282) (xy 76.320952 -31.817121) (xy 76.295857 -31.770003) (xy 76.277575 -31.719847)
			(xy 76.266462 -31.667632) (xy 76.262735 -31.614378) (xy 67.819215 -31.614378) (xy 67.843506 -31.641489)
			(xy 67.874279 -31.688002) (xy 67.897951 -31.738499) (xy 67.914019 -31.791906) (xy 67.922139 -31.847082)
			(xy 67.922648 -31.874968) (xy 67.922139 -31.902854) (xy 67.914019 -31.95803) (xy 67.897951 -32.011437)
			(xy 67.874279 -32.061934) (xy 67.843506 -32.108447) (xy 67.806289 -32.149984) (xy 67.763421 -32.185659)
			(xy 67.715815 -32.214713) (xy 67.664486 -32.236525) (xy 67.610529 -32.250631) (xy 67.555092 -32.256731)
			(xy 67.499358 -32.254694) (xy 67.444515 -32.244564) (xy 67.391731 -32.226557) (xy 67.342131 -32.201056)
			(xy 67.296773 -32.168605) (xy 67.256624 -32.129896) (xy 67.222538 -32.085753) (xy 67.195242 -32.037118)
			(xy 67.175319 -31.985027) (xy 67.163193 -31.93059) (xy 67.159122 -31.874968) (xy 63.60668 -31.874968)
			(xy 63.60668 -32.756348) (xy 63.7667 -32.916368) (xy 69.67042 -32.916368) (xy 69.674491 -32.860746)
			(xy 69.686617 -32.806309) (xy 69.70654 -32.754218) (xy 69.733836 -32.705583) (xy 69.767922 -32.66144)
			(xy 69.808071 -32.622731) (xy 69.853429 -32.59028) (xy 69.903029 -32.564779) (xy 69.955813 -32.546772)
			(xy 70.010656 -32.536642) (xy 70.06639 -32.534605) (xy 70.121827 -32.540705) (xy 70.175784 -32.554811)
			(xy 70.227113 -32.576623) (xy 70.274719 -32.605677) (xy 70.317587 -32.641352) (xy 70.354804 -32.682889)
			(xy 70.385577 -32.729402) (xy 70.409249 -32.779899) (xy 70.425317 -32.833306) (xy 70.433437 -32.888482)
			(xy 70.433946 -32.916368) (xy 70.433437 -32.944254) (xy 70.425317 -32.99943) (xy 70.409249 -33.052837)
			(xy 70.385577 -33.103334) (xy 70.354804 -33.149847) (xy 70.317587 -33.191384) (xy 70.274719 -33.227059)
			(xy 70.227113 -33.256113) (xy 70.175784 -33.277925) (xy 70.121827 -33.292031) (xy 70.06639 -33.298131)
			(xy 70.010656 -33.296094) (xy 69.955813 -33.285964) (xy 69.903029 -33.267957) (xy 69.853429 -33.242456)
			(xy 69.808071 -33.210005) (xy 69.767922 -33.171296) (xy 69.733836 -33.127153) (xy 69.70654 -33.078518)
			(xy 69.686617 -33.026427) (xy 69.674491 -32.97199) (xy 69.67042 -32.916368) (xy 63.7667 -32.916368)
			(xy 64.16675 -33.316418) (xy 86.854282 -33.316418) (xy 86.858353 -33.260796) (xy 86.870479 -33.206359)
			(xy 86.890402 -33.154268) (xy 86.917698 -33.105633) (xy 86.951784 -33.06149) (xy 86.991933 -33.022781)
			(xy 87.037291 -32.99033) (xy 87.086891 -32.964829) (xy 87.139675 -32.946822) (xy 87.194518 -32.936692)
			(xy 87.250252 -32.934655) (xy 87.305689 -32.940755) (xy 87.359646 -32.954861) (xy 87.410975 -32.976673)
			(xy 87.458581 -33.005727) (xy 87.501449 -33.041402) (xy 87.538666 -33.082939) (xy 87.569439 -33.129452)
			(xy 87.593111 -33.179949) (xy 87.609179 -33.233356) (xy 87.617299 -33.288532) (xy 87.617808 -33.316418)
			(xy 87.617299 -33.344304) (xy 87.61146 -33.383982) (xy 94.863156 -33.383982) (xy 94.867227 -33.32836)
			(xy 94.879353 -33.273923) (xy 94.899276 -33.221832) (xy 94.926572 -33.173197) (xy 94.960658 -33.129054)
			(xy 95.000807 -33.090345) (xy 95.046165 -33.057894) (xy 95.095765 -33.032393) (xy 95.148549 -33.014386)
			(xy 95.203392 -33.004256) (xy 95.259126 -33.002219) (xy 95.314563 -33.008319) (xy 95.36852 -33.022425)
			(xy 95.419849 -33.044237) (xy 95.467455 -33.073291) (xy 95.510323 -33.108966) (xy 95.54754 -33.150503)
			(xy 95.578313 -33.197016) (xy 95.601985 -33.247513) (xy 95.610107 -33.274508) (xy 95.958912 -33.274508)
			(xy 95.962983 -33.218886) (xy 95.975109 -33.164449) (xy 95.995032 -33.112358) (xy 96.022328 -33.063723)
			(xy 96.056414 -33.01958) (xy 96.096563 -32.980871) (xy 96.141921 -32.94842) (xy 96.191521 -32.922919)
			(xy 96.244305 -32.904912) (xy 96.299148 -32.894782) (xy 96.354882 -32.892745) (xy 96.410319 -32.898845)
			(xy 96.464276 -32.912951) (xy 96.515605 -32.934763) (xy 96.563211 -32.963817) (xy 96.606079 -32.999492)
			(xy 96.643296 -33.041029) (xy 96.674069 -33.087542) (xy 96.697741 -33.138039) (xy 96.713809 -33.191446)
			(xy 96.721929 -33.246622) (xy 96.722438 -33.274508) (xy 96.721929 -33.302394) (xy 96.713809 -33.35757)
			(xy 96.697741 -33.410977) (xy 96.674069 -33.461474) (xy 96.643296 -33.507987) (xy 96.606079 -33.549524)
			(xy 96.563211 -33.585199) (xy 96.515605 -33.614253) (xy 96.464276 -33.636065) (xy 96.410319 -33.650171)
			(xy 96.354882 -33.656271) (xy 96.299148 -33.654234) (xy 96.244305 -33.644104) (xy 96.191521 -33.626097)
			(xy 96.141921 -33.600596) (xy 96.096563 -33.568145) (xy 96.056414 -33.529436) (xy 96.022328 -33.485293)
			(xy 95.995032 -33.436658) (xy 95.975109 -33.384567) (xy 95.962983 -33.33013) (xy 95.958912 -33.274508)
			(xy 95.610107 -33.274508) (xy 95.618053 -33.30092) (xy 95.626173 -33.356096) (xy 95.626682 -33.383982)
			(xy 95.626173 -33.411868) (xy 95.618053 -33.467044) (xy 95.601985 -33.520451) (xy 95.578313 -33.570948)
			(xy 95.54754 -33.617461) (xy 95.510323 -33.658998) (xy 95.467455 -33.694673) (xy 95.419849 -33.723727)
			(xy 95.36852 -33.745539) (xy 95.314563 -33.759645) (xy 95.259126 -33.765745) (xy 95.203392 -33.763708)
			(xy 95.148549 -33.753578) (xy 95.095765 -33.735571) (xy 95.046165 -33.71007) (xy 95.000807 -33.677619)
			(xy 94.960658 -33.63891) (xy 94.926572 -33.594767) (xy 94.899276 -33.546132) (xy 94.879353 -33.494041)
			(xy 94.867227 -33.439604) (xy 94.863156 -33.383982) (xy 87.61146 -33.383982) (xy 87.609179 -33.39948)
			(xy 87.593111 -33.452887) (xy 87.569439 -33.503384) (xy 87.538666 -33.549897) (xy 87.501449 -33.591434)
			(xy 87.458581 -33.627109) (xy 87.410975 -33.656163) (xy 87.359646 -33.677975) (xy 87.305689 -33.692081)
			(xy 87.250252 -33.698181) (xy 87.194518 -33.696144) (xy 87.139675 -33.686014) (xy 87.086891 -33.668007)
			(xy 87.037291 -33.642506) (xy 86.991933 -33.610055) (xy 86.951784 -33.571346) (xy 86.917698 -33.527203)
			(xy 86.890402 -33.478568) (xy 86.870479 -33.426477) (xy 86.858353 -33.37204) (xy 86.854282 -33.316418)
			(xy 64.16675 -33.316418) (xy 64.858484 -34.008152) (xy 65.21626 -34.008152) (xy 65.21626 -33.953648)
			(xy 65.224016 -33.8997) (xy 65.239371 -33.847405) (xy 65.262011 -33.797827) (xy 65.291477 -33.751975)
			(xy 65.327168 -33.710783) (xy 65.368357 -33.67509) (xy 65.414207 -33.645622) (xy 65.463784 -33.622979)
			(xy 65.516079 -33.607621) (xy 65.570026 -33.599861) (xy 65.597278 -33.599374) (xy 65.62362 -33.59981)
			(xy 65.675802 -33.607063) (xy 65.726491 -33.621422) (xy 65.774725 -33.642613) (xy 65.819588 -33.670233)
			(xy 65.860227 -33.70376) (xy 65.895872 -33.742554) (xy 65.911222 -33.763966) (xy 65.919571 -33.775275)
			(xy 65.941233 -33.793175) (xy 65.966955 -33.804488) (xy 65.994788 -33.808357) (xy 66.022621 -33.804488)
			(xy 66.048343 -33.793175) (xy 66.070005 -33.775275) (xy 66.078354 -33.763966) (xy 66.093727 -33.742571)
			(xy 66.129361 -33.703768) (xy 66.169994 -33.670236) (xy 66.214853 -33.642611) (xy 66.263086 -33.62142)
			(xy 66.313775 -33.607064) (xy 66.365957 -33.599817) (xy 66.392298 -33.599374) (xy 66.41955 -33.599873)
			(xy 66.473498 -33.60763) (xy 66.525794 -33.622985) (xy 66.575372 -33.645626) (xy 66.621223 -33.675093)
			(xy 66.662414 -33.710785) (xy 66.698106 -33.751975) (xy 66.727573 -33.797826) (xy 66.750215 -33.847404)
			(xy 66.76557 -33.8997) (xy 66.773327 -33.953648) (xy 66.773327 -34.008152) (xy 66.772537 -34.013648)
			(xy 92.597222 -34.013648) (xy 92.601293 -33.958026) (xy 92.613419 -33.903589) (xy 92.633342 -33.851498)
			(xy 92.660638 -33.802863) (xy 92.694724 -33.75872) (xy 92.734873 -33.720011) (xy 92.780231 -33.68756)
			(xy 92.829831 -33.662059) (xy 92.882615 -33.644052) (xy 92.937458 -33.633922) (xy 92.993192 -33.631885)
			(xy 93.048629 -33.637985) (xy 93.102586 -33.652091) (xy 93.153915 -33.673903) (xy 93.201521 -33.702957)
			(xy 93.244389 -33.738632) (xy 93.281606 -33.780169) (xy 93.312379 -33.826682) (xy 93.336051 -33.877179)
			(xy 93.352119 -33.930586) (xy 93.360239 -33.985762) (xy 93.360748 -34.013648) (xy 93.360239 -34.041534)
			(xy 93.352119 -34.09671) (xy 93.336051 -34.150117) (xy 93.312379 -34.200614) (xy 93.281606 -34.247127)
			(xy 93.244389 -34.288664) (xy 93.201521 -34.324339) (xy 93.153915 -34.353393) (xy 93.102586 -34.375205)
			(xy 93.048629 -34.389311) (xy 92.993192 -34.395411) (xy 92.937458 -34.393374) (xy 92.882615 -34.383244)
			(xy 92.829831 -34.365237) (xy 92.780231 -34.339736) (xy 92.734873 -34.307285) (xy 92.694724 -34.268576)
			(xy 92.660638 -34.224433) (xy 92.633342 -34.175798) (xy 92.613419 -34.123707) (xy 92.601293 -34.06927)
			(xy 92.597222 -34.013648) (xy 66.772537 -34.013648) (xy 66.76557 -34.0621) (xy 66.750215 -34.114396)
			(xy 66.727573 -34.163974) (xy 66.698106 -34.209825) (xy 66.662414 -34.251015) (xy 66.621223 -34.286707)
			(xy 66.575372 -34.316174) (xy 66.525794 -34.338815) (xy 66.473498 -34.35417) (xy 66.41955 -34.361927)
			(xy 66.392298 -34.36239) (xy 66.365957 -34.361945) (xy 66.313776 -34.35469) (xy 66.263088 -34.340331)
			(xy 66.214855 -34.319141) (xy 66.169993 -34.291522) (xy 66.129352 -34.257999) (xy 66.093706 -34.219208)
			(xy 66.078354 -34.197798) (xy 66.070005 -34.186489) (xy 66.048343 -34.168589) (xy 66.022621 -34.157276)
			(xy 65.994788 -34.153407) (xy 65.966955 -34.157276) (xy 65.941233 -34.168589) (xy 65.919571 -34.186489)
			(xy 65.911222 -34.197798) (xy 65.895883 -34.219219) (xy 65.860241 -34.258018) (xy 65.819601 -34.291546)
			(xy 65.774736 -34.319167) (xy 65.726499 -34.340354) (xy 65.675806 -34.354705) (xy 65.623621 -34.361949)
			(xy 65.597278 -34.36239) (xy 65.570026 -34.361939) (xy 65.516079 -34.354179) (xy 65.463784 -34.338821)
			(xy 65.414207 -34.316178) (xy 65.368357 -34.28671) (xy 65.327168 -34.251017) (xy 65.291477 -34.209825)
			(xy 65.262011 -34.163973) (xy 65.239371 -34.114395) (xy 65.224016 -34.0621) (xy 65.21626 -34.008152)
			(xy 64.858484 -34.008152) (xy 66.43751 -35.587178) (xy 67.429632 -35.587178) (xy 67.433703 -35.531556)
			(xy 67.445829 -35.477119) (xy 67.465752 -35.425028) (xy 67.493048 -35.376393) (xy 67.527134 -35.33225)
			(xy 67.567283 -35.293541) (xy 67.612641 -35.26109) (xy 67.662241 -35.235589) (xy 67.715025 -35.217582)
			(xy 67.769868 -35.207452) (xy 67.825602 -35.205415) (xy 67.881039 -35.211515) (xy 67.934996 -35.225621)
			(xy 67.986325 -35.247433) (xy 68.033931 -35.276487) (xy 68.076799 -35.312162) (xy 68.114016 -35.353699)
			(xy 68.144789 -35.400212) (xy 68.168461 -35.450709) (xy 68.184529 -35.504116) (xy 68.192649 -35.559292)
			(xy 68.193158 -35.587178) (xy 68.192903 -35.601148) (xy 68.909182 -35.601148) (xy 68.913253 -35.545526)
			(xy 68.925379 -35.491089) (xy 68.945302 -35.438998) (xy 68.972598 -35.390363) (xy 69.006684 -35.34622)
			(xy 69.046833 -35.307511) (xy 69.092191 -35.27506) (xy 69.141791 -35.249559) (xy 69.194575 -35.231552)
			(xy 69.249418 -35.221422) (xy 69.305152 -35.219385) (xy 69.360589 -35.225485) (xy 69.414546 -35.239591)
			(xy 69.465875 -35.261403) (xy 69.513481 -35.290457) (xy 69.556349 -35.326132) (xy 69.593566 -35.367669)
			(xy 69.624339 -35.414182) (xy 69.648011 -35.464679) (xy 69.664079 -35.518086) (xy 69.672199 -35.573262)
			(xy 69.672708 -35.601148) (xy 69.672199 -35.629034) (xy 69.665089 -35.677348) (xy 69.931532 -35.677348)
			(xy 69.935603 -35.621726) (xy 69.947729 -35.567289) (xy 69.967652 -35.515198) (xy 69.994948 -35.466563)
			(xy 70.029034 -35.42242) (xy 70.069183 -35.383711) (xy 70.114541 -35.35126) (xy 70.164141 -35.325759)
			(xy 70.216925 -35.307752) (xy 70.271768 -35.297622) (xy 70.327502 -35.295585) (xy 70.382939 -35.301685)
			(xy 70.436896 -35.315791) (xy 70.488225 -35.337603) (xy 70.535831 -35.366657) (xy 70.578699 -35.402332)
			(xy 70.615916 -35.443869) (xy 70.646689 -35.490382) (xy 70.670361 -35.540879) (xy 70.686429 -35.594286)
			(xy 70.694549 -35.649462) (xy 70.695058 -35.677348) (xy 70.694549 -35.705234) (xy 70.686429 -35.76041)
			(xy 70.681512 -35.776752) (xy 70.913462 -35.776752) (xy 70.913462 -35.722248) (xy 70.921219 -35.668298)
			(xy 70.936574 -35.616001) (xy 70.959216 -35.566422) (xy 70.988684 -35.52057) (xy 71.024376 -35.479378)
			(xy 71.065568 -35.443685) (xy 71.11142 -35.414217) (xy 71.160999 -35.391575) (xy 71.213296 -35.376219)
			(xy 71.267246 -35.368462) (xy 71.294498 -35.367976) (xy 71.326687 -35.368681) (xy 71.390145 -35.379527)
			(xy 71.420736 -35.389566) (xy 71.435214 -35.39409) (xy 71.465505 -35.395333) (xy 71.494826 -35.387629)
			(xy 71.520594 -35.371657) (xy 71.540538 -35.348823) (xy 71.547228 -35.33521) (xy 71.558823 -35.310333)
			(xy 71.588167 -35.263951) (xy 71.623857 -35.222254) (xy 71.665156 -35.186104) (xy 71.711209 -35.156247)
			(xy 71.761067 -35.133299) (xy 71.813699 -35.117735) (xy 71.868019 -35.109877) (xy 71.895462 -35.109404)
			(xy 71.922718 -35.10984) (xy 71.976674 -35.117593) (xy 72.028978 -35.132946) (xy 72.078565 -35.155587)
			(xy 72.124424 -35.185055) (xy 72.165623 -35.22075) (xy 72.201322 -35.261945) (xy 72.230794 -35.307802)
			(xy 72.25344 -35.357386) (xy 72.268799 -35.409689) (xy 72.276557 -35.463645) (xy 72.276557 -35.518155)
			(xy 72.27558 -35.524948) (xy 72.515982 -35.524948) (xy 72.520053 -35.469326) (xy 72.532179 -35.414889)
			(xy 72.552102 -35.362798) (xy 72.579398 -35.314163) (xy 72.613484 -35.27002) (xy 72.653633 -35.231311)
			(xy 72.698991 -35.19886) (xy 72.748591 -35.173359) (xy 72.801375 -35.155352) (xy 72.856218 -35.145222)
			(xy 72.911952 -35.143185) (xy 72.967389 -35.149285) (xy 73.021346 -35.163391) (xy 73.072675 -35.185203)
			(xy 73.120281 -35.214257) (xy 73.163149 -35.249932) (xy 73.200366 -35.291469) (xy 73.231139 -35.337982)
			(xy 73.254811 -35.388479) (xy 73.270879 -35.441886) (xy 73.278999 -35.497062) (xy 73.279044 -35.499548)
			(xy 75.005182 -35.499548) (xy 75.009253 -35.443926) (xy 75.021379 -35.389489) (xy 75.041302 -35.337398)
			(xy 75.068598 -35.288763) (xy 75.102684 -35.24462) (xy 75.142833 -35.205911) (xy 75.188191 -35.17346)
			(xy 75.237791 -35.147959) (xy 75.290575 -35.129952) (xy 75.345418 -35.119822) (xy 75.401152 -35.117785)
			(xy 75.456589 -35.123885) (xy 75.510546 -35.137991) (xy 75.561875 -35.159803) (xy 75.609481 -35.188857)
			(xy 75.652349 -35.224532) (xy 75.676869 -35.251898) (xy 82.476846 -35.251898) (xy 82.480917 -35.196276)
			(xy 82.493043 -35.141839) (xy 82.512966 -35.089748) (xy 82.540262 -35.041113) (xy 82.574348 -34.99697)
			(xy 82.614497 -34.958261) (xy 82.659855 -34.92581) (xy 82.709455 -34.900309) (xy 82.762239 -34.882302)
			(xy 82.817082 -34.872172) (xy 82.872816 -34.870135) (xy 82.928253 -34.876235) (xy 82.98221 -34.890341)
			(xy 83.033539 -34.912153) (xy 83.081145 -34.941207) (xy 83.124013 -34.976882) (xy 83.16123 -35.018419)
			(xy 83.192003 -35.064932) (xy 83.215675 -35.115429) (xy 83.231743 -35.168836) (xy 83.239863 -35.224012)
			(xy 83.240372 -35.251898) (xy 83.239863 -35.279784) (xy 83.231743 -35.33496) (xy 83.215675 -35.388367)
			(xy 83.192003 -35.438864) (xy 83.168659 -35.474148) (xy 86.663782 -35.474148) (xy 86.667853 -35.418526)
			(xy 86.679979 -35.364089) (xy 86.699902 -35.311998) (xy 86.727198 -35.263363) (xy 86.761284 -35.21922)
			(xy 86.801433 -35.180511) (xy 86.846791 -35.14806) (xy 86.896391 -35.122559) (xy 86.949175 -35.104552)
			(xy 87.004018 -35.094422) (xy 87.059752 -35.092385) (xy 87.115189 -35.098485) (xy 87.169146 -35.112591)
			(xy 87.220475 -35.134403) (xy 87.268081 -35.163457) (xy 87.310949 -35.199132) (xy 87.348166 -35.240669)
			(xy 87.378939 -35.287182) (xy 87.402611 -35.337679) (xy 87.418679 -35.391086) (xy 87.426799 -35.446262)
			(xy 87.427308 -35.474148) (xy 87.426799 -35.502034) (xy 87.418679 -35.55721) (xy 87.402611 -35.610617)
			(xy 87.378939 -35.661114) (xy 87.348166 -35.707627) (xy 87.310949 -35.749164) (xy 87.268081 -35.784839)
			(xy 87.220475 -35.813893) (xy 87.169146 -35.835705) (xy 87.115189 -35.849811) (xy 87.059752 -35.855911)
			(xy 87.004018 -35.853874) (xy 86.949175 -35.843744) (xy 86.896391 -35.825737) (xy 86.846791 -35.800236)
			(xy 86.801433 -35.767785) (xy 86.761284 -35.729076) (xy 86.727198 -35.684933) (xy 86.699902 -35.636298)
			(xy 86.679979 -35.584207) (xy 86.667853 -35.52977) (xy 86.663782 -35.474148) (xy 83.168659 -35.474148)
			(xy 83.16123 -35.485377) (xy 83.124013 -35.526914) (xy 83.081145 -35.562589) (xy 83.033539 -35.591643)
			(xy 82.98221 -35.613455) (xy 82.928253 -35.627561) (xy 82.872816 -35.633661) (xy 82.817082 -35.631624)
			(xy 82.762239 -35.621494) (xy 82.709455 -35.603487) (xy 82.659855 -35.577986) (xy 82.614497 -35.545535)
			(xy 82.574348 -35.506826) (xy 82.540262 -35.462683) (xy 82.512966 -35.414048) (xy 82.493043 -35.361957)
			(xy 82.480917 -35.30752) (xy 82.476846 -35.251898) (xy 75.676869 -35.251898) (xy 75.689566 -35.266069)
			(xy 75.720339 -35.312582) (xy 75.744011 -35.363079) (xy 75.760079 -35.416486) (xy 75.768199 -35.471662)
			(xy 75.768708 -35.499548) (xy 75.768199 -35.527434) (xy 75.760079 -35.58261) (xy 75.744011 -35.636017)
			(xy 75.720339 -35.686514) (xy 75.689566 -35.733027) (xy 75.652349 -35.774564) (xy 75.609481 -35.810239)
			(xy 75.561875 -35.839293) (xy 75.510546 -35.861105) (xy 75.456589 -35.875211) (xy 75.401152 -35.881311)
			(xy 75.345418 -35.879274) (xy 75.290575 -35.869144) (xy 75.237791 -35.851137) (xy 75.188191 -35.825636)
			(xy 75.142833 -35.793185) (xy 75.102684 -35.754476) (xy 75.068598 -35.710333) (xy 75.041302 -35.661698)
			(xy 75.021379 -35.609607) (xy 75.009253 -35.55517) (xy 75.005182 -35.499548) (xy 73.279044 -35.499548)
			(xy 73.279508 -35.524948) (xy 73.278999 -35.552834) (xy 73.270879 -35.60801) (xy 73.254811 -35.661417)
			(xy 73.231139 -35.711914) (xy 73.200366 -35.758427) (xy 73.163149 -35.799964) (xy 73.120281 -35.835639)
			(xy 73.072675 -35.864693) (xy 73.021346 -35.886505) (xy 72.967389 -35.900611) (xy 72.911952 -35.906711)
			(xy 72.856218 -35.904674) (xy 72.801375 -35.894544) (xy 72.748591 -35.876537) (xy 72.698991 -35.851036)
			(xy 72.653633 -35.818585) (xy 72.613484 -35.779876) (xy 72.579398 -35.735733) (xy 72.552102 -35.687098)
			(xy 72.532179 -35.635007) (xy 72.520053 -35.58057) (xy 72.515982 -35.524948) (xy 72.27558 -35.524948)
			(xy 72.268799 -35.572111) (xy 72.25344 -35.624414) (xy 72.230794 -35.673998) (xy 72.201322 -35.719855)
			(xy 72.165623 -35.76105) (xy 72.124424 -35.796745) (xy 72.078565 -35.826213) (xy 72.028978 -35.848854)
			(xy 71.976674 -35.864207) (xy 71.922718 -35.87196) (xy 71.895462 -35.87242) (xy 71.863273 -35.871725)
			(xy 71.799815 -35.860872) (xy 71.769224 -35.85083) (xy 71.754758 -35.846265) (xy 71.72446 -35.845032)
			(xy 71.695135 -35.852746) (xy 71.669365 -35.868727) (xy 71.649421 -35.891569) (xy 71.642732 -35.905186)
			(xy 71.631088 -35.930038) (xy 71.60175 -35.976419) (xy 71.587768 -35.992757) (xy 76.55324 -35.992757)
			(xy 76.560996 -35.938804) (xy 76.576351 -35.886503) (xy 76.598993 -35.836921) (xy 76.628461 -35.791065)
			(xy 76.664155 -35.749869) (xy 76.705349 -35.714173) (xy 76.751203 -35.684703) (xy 76.800785 -35.662058)
			(xy 76.853084 -35.6467) (xy 76.907037 -35.638942) (xy 76.961545 -35.63894) (xy 77.015499 -35.646696)
			(xy 77.067799 -35.662052) (xy 77.117382 -35.684694) (xy 77.163237 -35.714163) (xy 77.204433 -35.749857)
			(xy 77.240129 -35.791051) (xy 77.269599 -35.836905) (xy 77.292243 -35.886487) (xy 77.307601 -35.938787)
			(xy 77.315359 -35.99274) (xy 77.315822 -36.019994) (xy 77.31535 -36.046046) (xy 77.308212 -36.097661)
			(xy 77.301598 -36.122864) (xy 77.29817 -36.137046) (xy 77.298523 -36.166203) (xy 77.307103 -36.194072)
			(xy 77.323211 -36.218379) (xy 77.345533 -36.237142) (xy 77.372247 -36.248831) (xy 77.401176 -36.252492)
			(xy 77.415644 -36.250626) (xy 77.430718 -36.24836) (xy 77.461107 -36.245941) (xy 77.47635 -36.2458)
			(xy 77.503607 -36.246201) (xy 77.557567 -36.253953) (xy 77.609875 -36.269305) (xy 77.659466 -36.291945)
			(xy 77.70533 -36.321412) (xy 77.746533 -36.357106) (xy 77.782237 -36.398301) (xy 77.811714 -36.444159)
			(xy 77.834365 -36.493744) (xy 77.849729 -36.546048) (xy 77.857492 -36.600007) (xy 77.857497 -36.643818)
			(xy 89.835988 -36.643818) (xy 89.840059 -36.588196) (xy 89.852185 -36.533759) (xy 89.872108 -36.481668)
			(xy 89.899404 -36.433033) (xy 89.93349 -36.38889) (xy 89.973639 -36.350181) (xy 90.018997 -36.31773)
			(xy 90.068597 -36.292229) (xy 90.121381 -36.274222) (xy 90.176224 -36.264092) (xy 90.231958 -36.262055)
			(xy 90.287395 -36.268155) (xy 90.341352 -36.282261) (xy 90.392681 -36.304073) (xy 90.440287 -36.333127)
			(xy 90.483155 -36.368802) (xy 90.520372 -36.410339) (xy 90.551145 -36.456852) (xy 90.574817 -36.507349)
			(xy 90.590885 -36.560756) (xy 90.599005 -36.615932) (xy 90.599514 -36.643818) (xy 90.599005 -36.671704)
			(xy 90.590885 -36.72688) (xy 90.574817 -36.780287) (xy 90.551145 -36.830784) (xy 90.520372 -36.877297)
			(xy 90.483155 -36.918834) (xy 90.440287 -36.954509) (xy 90.392681 -36.983563) (xy 90.341352 -37.005375)
			(xy 90.287395 -37.019481) (xy 90.231958 -37.025581) (xy 90.176224 -37.023544) (xy 90.121381 -37.013414)
			(xy 90.068597 -36.995407) (xy 90.018997 -36.969906) (xy 89.973639 -36.937455) (xy 89.93349 -36.898746)
			(xy 89.899404 -36.854603) (xy 89.872108 -36.805968) (xy 89.852185 -36.753877) (xy 89.840059 -36.69944)
			(xy 89.835988 -36.643818) (xy 77.857497 -36.643818) (xy 77.857498 -36.654521) (xy 77.849744 -36.708481)
			(xy 77.83439 -36.760788) (xy 77.811749 -36.810378) (xy 77.78228 -36.856241) (xy 77.746584 -36.897443)
			(xy 77.705387 -36.933145) (xy 77.659529 -36.962621) (xy 77.609943 -36.98527) (xy 77.557638 -37.000632)
			(xy 77.503679 -37.008393) (xy 77.449165 -37.008397) (xy 77.395205 -37.000641) (xy 77.342898 -36.985286)
			(xy 77.293309 -36.962642) (xy 77.247448 -36.933171) (xy 77.206247 -36.897474) (xy 77.170547 -36.856276)
			(xy 77.141072 -36.810417) (xy 77.118425 -36.76083) (xy 77.103065 -36.708524) (xy 77.095306 -36.654565)
			(xy 77.094842 -36.627308) (xy 77.095315 -36.601256) (xy 77.102452 -36.549641) (xy 77.109066 -36.524438)
			(xy 77.112533 -36.510263) (xy 77.112181 -36.481098) (xy 77.103598 -36.453222) (xy 77.087484 -36.428909)
			(xy 77.065153 -36.410145) (xy 77.038429 -36.398459) (xy 77.009491 -36.394805) (xy 76.99502 -36.396676)
			(xy 76.979947 -36.398947) (xy 76.949557 -36.401363) (xy 76.934314 -36.401502) (xy 76.90706 -36.40106)
			(xy 76.853106 -36.393305) (xy 76.800806 -36.37795) (xy 76.751223 -36.355308) (xy 76.705367 -36.325841)
			(xy 76.664171 -36.290147) (xy 76.628475 -36.248954) (xy 76.599004 -36.203099) (xy 76.576359 -36.153518)
			(xy 76.561001 -36.101218) (xy 76.553242 -36.047265) (xy 76.55324 -35.992757) (xy 71.587768 -35.992757)
			(xy 71.566067 -36.018116) (xy 71.524776 -36.054267) (xy 71.478729 -36.084128) (xy 71.428878 -36.107079)
			(xy 71.376253 -36.122649) (xy 71.321938 -36.130515) (xy 71.294498 -36.130992) (xy 71.267246 -36.130538)
			(xy 71.213296 -36.122781) (xy 71.160999 -36.107425) (xy 71.11142 -36.084783) (xy 71.065568 -36.055315)
			(xy 71.024376 -36.019622) (xy 70.988684 -35.97843) (xy 70.959216 -35.932578) (xy 70.936574 -35.882999)
			(xy 70.921219 -35.830702) (xy 70.913462 -35.776752) (xy 70.681512 -35.776752) (xy 70.670361 -35.813817)
			(xy 70.646689 -35.864314) (xy 70.615916 -35.910827) (xy 70.578699 -35.952364) (xy 70.535831 -35.988039)
			(xy 70.488225 -36.017093) (xy 70.436896 -36.038905) (xy 70.382939 -36.053011) (xy 70.327502 -36.059111)
			(xy 70.271768 -36.057074) (xy 70.216925 -36.046944) (xy 70.164141 -36.028937) (xy 70.114541 -36.003436)
			(xy 70.069183 -35.970985) (xy 70.029034 -35.932276) (xy 69.994948 -35.888133) (xy 69.967652 -35.839498)
			(xy 69.947729 -35.787407) (xy 69.935603 -35.73297) (xy 69.931532 -35.677348) (xy 69.665089 -35.677348)
			(xy 69.664079 -35.68421) (xy 69.648011 -35.737617) (xy 69.624339 -35.788114) (xy 69.593566 -35.834627)
			(xy 69.556349 -35.876164) (xy 69.513481 -35.911839) (xy 69.465875 -35.940893) (xy 69.414546 -35.962705)
			(xy 69.360589 -35.976811) (xy 69.305152 -35.982911) (xy 69.249418 -35.980874) (xy 69.194575 -35.970744)
			(xy 69.141791 -35.952737) (xy 69.092191 -35.927236) (xy 69.046833 -35.894785) (xy 69.006684 -35.856076)
			(xy 68.972598 -35.811933) (xy 68.945302 -35.763298) (xy 68.925379 -35.711207) (xy 68.913253 -35.65677)
			(xy 68.909182 -35.601148) (xy 68.192903 -35.601148) (xy 68.192649 -35.615064) (xy 68.184529 -35.67024)
			(xy 68.168461 -35.723647) (xy 68.144789 -35.774144) (xy 68.114016 -35.820657) (xy 68.076799 -35.862194)
			(xy 68.033931 -35.897869) (xy 67.986325 -35.926923) (xy 67.934996 -35.948735) (xy 67.881039 -35.962841)
			(xy 67.825602 -35.968941) (xy 67.769868 -35.966904) (xy 67.715025 -35.956774) (xy 67.662241 -35.938767)
			(xy 67.612641 -35.913266) (xy 67.567283 -35.880815) (xy 67.527134 -35.842106) (xy 67.493048 -35.797963)
			(xy 67.465752 -35.749328) (xy 67.445829 -35.697237) (xy 67.433703 -35.6428) (xy 67.429632 -35.587178)
			(xy 66.43751 -35.587178) (xy 68.775188 -37.924856) (xy 74.924317 -37.924856) (xy 74.924317 -37.870344)
			(xy 74.932075 -37.816386) (xy 74.947433 -37.764082) (xy 74.970079 -37.714496) (xy 74.999551 -37.668638)
			(xy 75.03525 -37.627441) (xy 75.076448 -37.591744) (xy 75.122307 -37.562273) (xy 75.171894 -37.539629)
			(xy 75.224198 -37.524272) (xy 75.278156 -37.516516) (xy 75.305412 -37.516054) (xy 75.332017 -37.51647)
			(xy 75.384713 -37.523855) (xy 75.43587 -37.538493) (xy 75.484496 -37.5601) (xy 75.529646 -37.588257)
			(xy 75.570444 -37.622417) (xy 75.606097 -37.661917) (xy 75.621388 -37.683694) (xy 75.629722 -37.695174)
			(xy 75.651466 -37.713378) (xy 75.677379 -37.724896) (xy 75.705462 -37.728836) (xy 75.733545 -37.724896)
			(xy 75.759458 -37.713378) (xy 75.781202 -37.695174) (xy 75.789536 -37.683694) (xy 75.804876 -37.661957)
			(xy 75.840533 -37.622474) (xy 75.881328 -37.588327) (xy 75.92647 -37.560177) (xy 75.975085 -37.538569)
			(xy 76.026229 -37.523922) (xy 76.078912 -37.516521) (xy 76.105512 -37.516054) (xy 76.13276 -37.516617)
			(xy 76.186701 -37.524374) (xy 76.238989 -37.539729) (xy 76.28856 -37.562368) (xy 76.334404 -37.591832)
			(xy 76.375589 -37.62752) (xy 76.411275 -37.668706) (xy 76.440737 -37.714551) (xy 76.454136 -37.743892)
			(xy 82.100164 -37.743892) (xy 82.104235 -37.68827) (xy 82.116361 -37.633833) (xy 82.136284 -37.581742)
			(xy 82.16358 -37.533107) (xy 82.197666 -37.488964) (xy 82.237815 -37.450255) (xy 82.283173 -37.417804)
			(xy 82.332773 -37.392303) (xy 82.385557 -37.374296) (xy 82.4404 -37.364166) (xy 82.496134 -37.362129)
			(xy 82.551571 -37.368229) (xy 82.605528 -37.382335) (xy 82.656857 -37.404147) (xy 82.704463 -37.433201)
			(xy 82.747331 -37.468876) (xy 82.784548 -37.510413) (xy 82.815321 -37.556926) (xy 82.838993 -37.607423)
			(xy 82.855061 -37.66083) (xy 82.862201 -37.709348) (xy 87.191086 -37.709348) (xy 87.195157 -37.653726)
			(xy 87.207283 -37.599289) (xy 87.227206 -37.547198) (xy 87.254502 -37.498563) (xy 87.288588 -37.45442)
			(xy 87.328737 -37.415711) (xy 87.374095 -37.38326) (xy 87.423695 -37.357759) (xy 87.476479 -37.339752)
			(xy 87.531322 -37.329622) (xy 87.587056 -37.327585) (xy 87.642493 -37.333685) (xy 87.69645 -37.347791)
			(xy 87.747779 -37.369603) (xy 87.795385 -37.398657) (xy 87.838253 -37.434332) (xy 87.87547 -37.475869)
			(xy 87.906243 -37.522382) (xy 87.929915 -37.572879) (xy 87.945983 -37.626286) (xy 87.954103 -37.681462)
			(xy 87.954612 -37.709348) (xy 87.954103 -37.737234) (xy 87.945983 -37.79241) (xy 87.929915 -37.845817)
			(xy 87.906243 -37.896314) (xy 87.87547 -37.942827) (xy 87.838253 -37.984364) (xy 87.795385 -38.020039)
			(xy 87.747779 -38.049093) (xy 87.69645 -38.070905) (xy 87.642493 -38.085011) (xy 87.587056 -38.091111)
			(xy 87.531322 -38.089074) (xy 87.476479 -38.078944) (xy 87.423695 -38.060937) (xy 87.374095 -38.035436)
			(xy 87.328737 -38.002985) (xy 87.288588 -37.964276) (xy 87.254502 -37.920133) (xy 87.227206 -37.871498)
			(xy 87.207283 -37.819407) (xy 87.195157 -37.76497) (xy 87.191086 -37.709348) (xy 82.862201 -37.709348)
			(xy 82.863181 -37.716006) (xy 82.86369 -37.743892) (xy 82.863181 -37.771778) (xy 82.855061 -37.826954)
			(xy 82.838993 -37.880361) (xy 82.815321 -37.930858) (xy 82.784548 -37.977371) (xy 82.747331 -38.018908)
			(xy 82.704463 -38.054583) (xy 82.656857 -38.083637) (xy 82.605528 -38.105449) (xy 82.551571 -38.119555)
			(xy 82.496134 -38.125655) (xy 82.4404 -38.123618) (xy 82.385557 -38.113488) (xy 82.332773 -38.095481)
			(xy 82.283173 -38.06998) (xy 82.237815 -38.037529) (xy 82.197666 -37.99882) (xy 82.16358 -37.954677)
			(xy 82.136284 -37.906042) (xy 82.116361 -37.853951) (xy 82.104235 -37.799514) (xy 82.100164 -37.743892)
			(xy 76.454136 -37.743892) (xy 76.463375 -37.764122) (xy 76.478728 -37.816411) (xy 76.486484 -37.870352)
			(xy 76.486484 -37.924848) (xy 76.478728 -37.978789) (xy 76.463375 -38.031078) (xy 76.440737 -38.080649)
			(xy 76.411275 -38.126494) (xy 76.375589 -38.16768) (xy 76.334404 -38.203368) (xy 76.28856 -38.232832)
			(xy 76.238989 -38.255471) (xy 76.186701 -38.270826) (xy 76.13276 -38.278583) (xy 76.105512 -38.27907)
			(xy 76.078908 -38.278625) (xy 76.026214 -38.271244) (xy 75.975058 -38.25661) (xy 75.926432 -38.235008)
			(xy 75.881282 -38.206855) (xy 75.840483 -38.1727) (xy 75.804828 -38.133205) (xy 75.789536 -38.11143)
			(xy 75.781202 -38.09995) (xy 75.759458 -38.081746) (xy 75.733545 -38.070228) (xy 75.705462 -38.066288)
			(xy 75.677379 -38.070228) (xy 75.651466 -38.081746) (xy 75.629722 -38.09995) (xy 75.621388 -38.11143)
			(xy 75.606103 -38.133208) (xy 75.570436 -38.172688) (xy 75.529632 -38.206832) (xy 75.48448 -38.234977)
			(xy 75.435857 -38.256578) (xy 75.384704 -38.271216) (xy 75.332015 -38.278608) (xy 75.305412 -38.27907)
			(xy 75.278156 -38.278684) (xy 75.224198 -38.270928) (xy 75.171894 -38.255571) (xy 75.122307 -38.232927)
			(xy 75.076448 -38.203456) (xy 75.03525 -38.167759) (xy 74.999551 -38.126562) (xy 74.970079 -38.080704)
			(xy 74.947433 -38.031118) (xy 74.932075 -37.978814) (xy 74.924317 -37.924856) (xy 68.775188 -37.924856)
			(xy 69.137784 -38.287452) (xy 84.072982 -38.287452) (xy 84.077053 -38.23183) (xy 84.089179 -38.177393)
			(xy 84.109102 -38.125302) (xy 84.136398 -38.076667) (xy 84.170484 -38.032524) (xy 84.210633 -37.993815)
			(xy 84.255991 -37.961364) (xy 84.305591 -37.935863) (xy 84.358375 -37.917856) (xy 84.413218 -37.907726)
			(xy 84.468952 -37.905689) (xy 84.524389 -37.911789) (xy 84.578346 -37.925895) (xy 84.629675 -37.947707)
			(xy 84.677281 -37.976761) (xy 84.720149 -38.012436) (xy 84.757366 -38.053973) (xy 84.788139 -38.100486)
			(xy 84.811811 -38.150983) (xy 84.827879 -38.20439) (xy 84.835999 -38.259566) (xy 84.836508 -38.287452)
			(xy 85.022942 -38.287452) (xy 85.027013 -38.23183) (xy 85.039139 -38.177393) (xy 85.059062 -38.125302)
			(xy 85.086358 -38.076667) (xy 85.120444 -38.032524) (xy 85.160593 -37.993815) (xy 85.205951 -37.961364)
			(xy 85.255551 -37.935863) (xy 85.308335 -37.917856) (xy 85.363178 -37.907726) (xy 85.418912 -37.905689)
			(xy 85.474349 -37.911789) (xy 85.528306 -37.925895) (xy 85.579635 -37.947707) (xy 85.627241 -37.976761)
			(xy 85.670109 -38.012436) (xy 85.707326 -38.053973) (xy 85.738099 -38.100486) (xy 85.761771 -38.150983)
			(xy 85.777839 -38.20439) (xy 85.777877 -38.204648) (xy 88.797382 -38.204648) (xy 88.801453 -38.149026)
			(xy 88.813579 -38.094589) (xy 88.833502 -38.042498) (xy 88.860798 -37.993863) (xy 88.894884 -37.94972)
			(xy 88.935033 -37.911011) (xy 88.980391 -37.87856) (xy 89.029991 -37.853059) (xy 89.082775 -37.835052)
			(xy 89.137618 -37.824922) (xy 89.193352 -37.822885) (xy 89.248789 -37.828985) (xy 89.302746 -37.843091)
			(xy 89.354075 -37.864903) (xy 89.401681 -37.893957) (xy 89.444549 -37.929632) (xy 89.481766 -37.971169)
			(xy 89.512539 -38.017682) (xy 89.536211 -38.068179) (xy 89.552279 -38.121586) (xy 89.560399 -38.176762)
			(xy 89.560908 -38.204648) (xy 89.560399 -38.232534) (xy 89.552279 -38.28771) (xy 89.536211 -38.341117)
			(xy 89.512539 -38.391614) (xy 89.481766 -38.438127) (xy 89.444549 -38.479664) (xy 89.401681 -38.515339)
			(xy 89.354075 -38.544393) (xy 89.302746 -38.566205) (xy 89.248789 -38.580311) (xy 89.193352 -38.586411)
			(xy 89.137618 -38.584374) (xy 89.082775 -38.574244) (xy 89.029991 -38.556237) (xy 88.980391 -38.530736)
			(xy 88.935033 -38.498285) (xy 88.894884 -38.459576) (xy 88.860798 -38.415433) (xy 88.833502 -38.366798)
			(xy 88.813579 -38.314707) (xy 88.801453 -38.26027) (xy 88.797382 -38.204648) (xy 85.777877 -38.204648)
			(xy 85.785959 -38.259566) (xy 85.786468 -38.287452) (xy 85.785959 -38.315338) (xy 85.777839 -38.370514)
			(xy 85.761771 -38.423921) (xy 85.738099 -38.474418) (xy 85.707326 -38.520931) (xy 85.670109 -38.562468)
			(xy 85.627241 -38.598143) (xy 85.579635 -38.627197) (xy 85.528306 -38.649009) (xy 85.474349 -38.663115)
			(xy 85.418912 -38.669215) (xy 85.363178 -38.667178) (xy 85.308335 -38.657048) (xy 85.255551 -38.639041)
			(xy 85.205951 -38.61354) (xy 85.160593 -38.581089) (xy 85.120444 -38.54238) (xy 85.086358 -38.498237)
			(xy 85.059062 -38.449602) (xy 85.039139 -38.397511) (xy 85.027013 -38.343074) (xy 85.022942 -38.287452)
			(xy 84.836508 -38.287452) (xy 84.835999 -38.315338) (xy 84.827879 -38.370514) (xy 84.811811 -38.423921)
			(xy 84.788139 -38.474418) (xy 84.757366 -38.520931) (xy 84.720149 -38.562468) (xy 84.677281 -38.598143)
			(xy 84.629675 -38.627197) (xy 84.578346 -38.649009) (xy 84.524389 -38.663115) (xy 84.468952 -38.669215)
			(xy 84.413218 -38.667178) (xy 84.358375 -38.657048) (xy 84.305591 -38.639041) (xy 84.255991 -38.61354)
			(xy 84.210633 -38.581089) (xy 84.170484 -38.54238) (xy 84.136398 -38.498237) (xy 84.109102 -38.449602)
			(xy 84.089179 -38.397511) (xy 84.077053 -38.343074) (xy 84.072982 -38.287452) (xy 69.137784 -38.287452)
			(xy 69.586094 -38.735762) (xy 71.742044 -38.735762) (xy 71.746115 -38.68014) (xy 71.758241 -38.625703)
			(xy 71.778164 -38.573612) (xy 71.80546 -38.524977) (xy 71.839546 -38.480834) (xy 71.879695 -38.442125)
			(xy 71.925053 -38.409674) (xy 71.974653 -38.384173) (xy 72.027437 -38.366166) (xy 72.08228 -38.356036)
			(xy 72.138014 -38.353999) (xy 72.193451 -38.360099) (xy 72.247408 -38.374205) (xy 72.298737 -38.396017)
			(xy 72.346343 -38.425071) (xy 72.389211 -38.460746) (xy 72.426428 -38.502283) (xy 72.457201 -38.548796)
			(xy 72.480873 -38.599293) (xy 72.496941 -38.6527) (xy 72.505061 -38.707876) (xy 72.50557 -38.735762)
			(xy 72.505061 -38.763648) (xy 72.496941 -38.818824) (xy 72.480873 -38.872231) (xy 72.457201 -38.922728)
			(xy 72.426428 -38.969241) (xy 72.389211 -39.010778) (xy 72.346343 -39.046453) (xy 72.307718 -39.070026)
			(xy 74.434444 -39.070026) (xy 74.438515 -39.014404) (xy 74.450641 -38.959967) (xy 74.470564 -38.907876)
			(xy 74.49786 -38.859241) (xy 74.531946 -38.815098) (xy 74.572095 -38.776389) (xy 74.617453 -38.743938)
			(xy 74.667053 -38.718437) (xy 74.719837 -38.70043) (xy 74.77468 -38.6903) (xy 74.830414 -38.688263)
			(xy 74.885851 -38.694363) (xy 74.939808 -38.708469) (xy 74.991137 -38.730281) (xy 75.038743 -38.759335)
			(xy 75.081611 -38.79501) (xy 75.118828 -38.836547) (xy 75.149601 -38.88306) (xy 75.173273 -38.933557)
			(xy 75.189341 -38.986964) (xy 75.197461 -39.04214) (xy 75.19797 -39.070026) (xy 75.197461 -39.097912)
			(xy 75.189341 -39.153088) (xy 75.173273 -39.206495) (xy 75.149601 -39.256992) (xy 75.118828 -39.303505)
			(xy 75.081611 -39.345042) (xy 75.038743 -39.380717) (xy 74.991137 -39.409771) (xy 74.939808 -39.431583)
			(xy 74.885851 -39.445689) (xy 74.830414 -39.451789) (xy 74.77468 -39.449752) (xy 74.719837 -39.439622)
			(xy 74.667053 -39.421615) (xy 74.617453 -39.396114) (xy 74.572095 -39.363663) (xy 74.531946 -39.324954)
			(xy 74.49786 -39.280811) (xy 74.470564 -39.232176) (xy 74.450641 -39.180085) (xy 74.438515 -39.125648)
			(xy 74.434444 -39.070026) (xy 72.307718 -39.070026) (xy 72.298737 -39.075507) (xy 72.247408 -39.097319)
			(xy 72.193451 -39.111425) (xy 72.138014 -39.117525) (xy 72.08228 -39.115488) (xy 72.027437 -39.105358)
			(xy 71.974653 -39.087351) (xy 71.925053 -39.06185) (xy 71.879695 -39.029399) (xy 71.839546 -38.99069)
			(xy 71.80546 -38.946547) (xy 71.778164 -38.897912) (xy 71.758241 -38.845821) (xy 71.746115 -38.791384)
			(xy 71.742044 -38.735762) (xy 69.586094 -38.735762) (xy 70.74408 -39.893748) (xy 72.902062 -39.893748)
			(xy 72.906133 -39.838126) (xy 72.918259 -39.783689) (xy 72.938182 -39.731598) (xy 72.965478 -39.682963)
			(xy 72.999564 -39.63882) (xy 73.039713 -39.600111) (xy 73.085071 -39.56766) (xy 73.134671 -39.542159)
			(xy 73.187455 -39.524152) (xy 73.242298 -39.514022) (xy 73.298032 -39.511985) (xy 73.353469 -39.518085)
			(xy 73.407426 -39.532191) (xy 73.458755 -39.554003) (xy 73.506361 -39.583057) (xy 73.549229 -39.618732)
			(xy 73.586446 -39.660269) (xy 73.617219 -39.706782) (xy 73.640891 -39.757279) (xy 73.656959 -39.810686)
			(xy 73.665079 -39.865862) (xy 73.665588 -39.893748) (xy 73.665079 -39.921634) (xy 73.656959 -39.97681)
			(xy 73.640891 -40.030217) (xy 73.617219 -40.080714) (xy 73.586446 -40.127227) (xy 73.549229 -40.168764)
			(xy 73.506361 -40.204439) (xy 73.458755 -40.233493) (xy 73.407426 -40.255305) (xy 73.353469 -40.269411)
			(xy 73.298032 -40.275511) (xy 73.242298 -40.273474) (xy 73.187455 -40.263344) (xy 73.134671 -40.245337)
			(xy 73.085071 -40.219836) (xy 73.039713 -40.187385) (xy 72.999564 -40.148676) (xy 72.965478 -40.104533)
			(xy 72.938182 -40.055898) (xy 72.918259 -40.003807) (xy 72.906133 -39.94937) (xy 72.902062 -39.893748)
			(xy 70.74408 -39.893748) (xy 72.87387 -42.023538) (xy 73.451972 -42.023538) (xy 73.456043 -41.967916)
			(xy 73.468169 -41.913479) (xy 73.488092 -41.861388) (xy 73.515388 -41.812753) (xy 73.549474 -41.76861)
			(xy 73.589623 -41.729901) (xy 73.634981 -41.69745) (xy 73.684581 -41.671949) (xy 73.737365 -41.653942)
			(xy 73.792208 -41.643812) (xy 73.847942 -41.641775) (xy 73.903379 -41.647875) (xy 73.957336 -41.661981)
			(xy 74.008665 -41.683793) (xy 74.056271 -41.712847) (xy 74.099139 -41.748522) (xy 74.136356 -41.790059)
			(xy 74.167129 -41.836572) (xy 74.190801 -41.887069) (xy 74.206869 -41.940476) (xy 74.214989 -41.995652)
			(xy 74.215498 -42.023538) (xy 74.214989 -42.051424) (xy 74.206869 -42.1066) (xy 74.190801 -42.160007)
			(xy 74.167129 -42.210504) (xy 74.136356 -42.257017) (xy 74.099139 -42.298554) (xy 74.056271 -42.334229)
			(xy 74.008665 -42.363283) (xy 73.957336 -42.385095) (xy 73.903379 -42.399201) (xy 73.847942 -42.405301)
			(xy 73.792208 -42.403264) (xy 73.737365 -42.393134) (xy 73.684581 -42.375127) (xy 73.634981 -42.349626)
			(xy 73.589623 -42.317175) (xy 73.549474 -42.278466) (xy 73.515388 -42.234323) (xy 73.488092 -42.185688)
			(xy 73.468169 -42.133597) (xy 73.456043 -42.07916) (xy 73.451972 -42.023538) (xy 72.87387 -42.023538)
			(xy 75.216004 -44.365672) (xy 75.226985 -44.375864) (xy 75.253417 -44.389938) (xy 75.282794 -44.395744)
			(xy 75.312592 -44.392783) (xy 75.340252 -44.38131) (xy 75.363397 -44.362309) (xy 75.380038 -44.337413)
			(xy 75.388746 -44.308762) (xy 75.389232 -44.29379) (xy 75.389232 -42.470324) (xy 75.388758 -42.456064)
			(xy 75.38088 -42.428655) (xy 75.365733 -42.404491) (xy 75.344496 -42.385457) (xy 75.318825 -42.373035)
			(xy 75.29072 -42.368193) (xy 75.262372 -42.37131) (xy 75.249024 -42.376344) (xy 75.225934 -42.385424)
			(xy 75.177993 -42.3982) (xy 75.128797 -42.404636) (xy 75.10399 -42.405046) (xy 75.076737 -42.404559)
			(xy 75.022784 -42.396801) (xy 74.970486 -42.381443) (xy 74.920905 -42.3588) (xy 74.875051 -42.32933)
			(xy 74.833858 -42.293635) (xy 74.798164 -42.252441) (xy 74.768696 -42.206586) (xy 74.746053 -42.157005)
			(xy 74.730697 -42.104706) (xy 74.72294 -42.050754) (xy 74.72294 -41.996246) (xy 74.730697 -41.942294)
			(xy 74.746053 -41.889995) (xy 74.768696 -41.840414) (xy 74.798164 -41.794559) (xy 74.833858 -41.753365)
			(xy 74.875051 -41.71767) (xy 74.920905 -41.6882) (xy 74.970486 -41.665557) (xy 75.022784 -41.650199)
			(xy 75.076737 -41.642441) (xy 75.10399 -41.64203) (xy 75.128796 -41.642449) (xy 75.177985 -41.648911)
			(xy 75.225927 -41.661675) (xy 75.249024 -41.670732) (xy 75.262387 -41.675704) (xy 75.290715 -41.678819)
			(xy 75.3188 -41.673981) (xy 75.344453 -41.661566) (xy 75.365674 -41.642543) (xy 75.380807 -41.618394)
			(xy 75.388674 -41.591002) (xy 75.389232 -41.576752) (xy 75.389232 -41.498012) (xy 74.99096 -41.099486)
			(xy 74.970686 -41.078569) (xy 74.93519 -41.032382) (xy 74.906024 -40.981957) (xy 74.883687 -40.928159)
			(xy 74.868561 -40.871905) (xy 74.860903 -40.814159) (xy 74.860404 -40.785034) (xy 74.860404 -40.310562)
			(xy 74.860862 -40.281431) (xy 74.868474 -40.223669) (xy 74.883562 -40.167395) (xy 74.905867 -40.113572)
			(xy 74.935009 -40.063122) (xy 74.970488 -40.016909) (xy 75.011697 -39.975723) (xy 75.05793 -39.94027)
			(xy 75.108396 -39.911157) (xy 75.162232 -39.888881) (xy 75.218514 -39.873825) (xy 75.276281 -39.866246)
			(xy 75.305412 -39.865808) (xy 75.335245 -39.866289) (xy 75.394376 -39.874261) (xy 75.451911 -39.890062)
			(xy 75.50682 -39.913408) (xy 75.558118 -39.94388) (xy 75.604885 -39.980932) (xy 75.646283 -40.0239)
			(xy 75.664314 -40.047672) (xy 75.673646 -40.059526) (xy 75.69777 -40.077616) (xy 75.726131 -40.087858)
			(xy 75.756247 -40.089357) (xy 75.785485 -40.08198) (xy 75.811286 -40.066375) (xy 75.821794 -40.055546)
			(xy 75.839957 -40.036008) (xy 75.880799 -40.001692) (xy 75.926021 -39.973397) (xy 75.974744 -39.951676)
			(xy 76.026016 -39.936951) (xy 76.07884 -39.92951) (xy 76.105512 -39.929054) (xy 76.132765 -39.929541)
			(xy 76.186717 -39.937299) (xy 76.239016 -39.952657) (xy 76.288596 -39.975301) (xy 76.33445 -40.004771)
			(xy 76.375643 -40.040466) (xy 76.411337 -40.08166) (xy 76.440805 -40.127514) (xy 76.463447 -40.177096)
			(xy 76.478803 -40.229395) (xy 76.48656 -40.283347) (xy 76.48656 -40.337853) (xy 76.478803 -40.391805)
			(xy 76.475884 -40.401748) (xy 81.107532 -40.401748) (xy 81.111603 -40.346126) (xy 81.123729 -40.291689)
			(xy 81.143652 -40.239598) (xy 81.170948 -40.190963) (xy 81.205034 -40.14682) (xy 81.245183 -40.108111)
			(xy 81.290541 -40.07566) (xy 81.340141 -40.050159) (xy 81.392925 -40.032152) (xy 81.447768 -40.022022)
			(xy 81.503502 -40.019985) (xy 81.558939 -40.026085) (xy 81.612896 -40.040191) (xy 81.664225 -40.062003)
			(xy 81.711831 -40.091057) (xy 81.754699 -40.126732) (xy 81.791916 -40.168269) (xy 81.822689 -40.214782)
			(xy 81.846361 -40.265279) (xy 81.862429 -40.318686) (xy 81.865205 -40.337548) (xy 91.954386 -40.337548)
			(xy 91.954386 -40.283052) (xy 91.962141 -40.229109) (xy 91.977493 -40.17682) (xy 92.00013 -40.127247)
			(xy 92.029591 -40.0814) (xy 92.065276 -40.040212) (xy 92.10646 -40.004521) (xy 92.152303 -39.975054)
			(xy 92.201873 -39.95241) (xy 92.25416 -39.937051) (xy 92.308102 -39.929289) (xy 92.33535 -39.9288)
			(xy 92.361953 -39.929287) (xy 92.414644 -39.936662) (xy 92.465799 -39.951289) (xy 92.514424 -39.972886)
			(xy 92.559575 -40.001031) (xy 92.600375 -40.03518) (xy 92.636032 -40.074668) (xy 92.651326 -40.09644)
			(xy 92.65966 -40.10792) (xy 92.681404 -40.126124) (xy 92.707317 -40.137642) (xy 92.7354 -40.141582)
			(xy 92.763483 -40.137642) (xy 92.789396 -40.126124) (xy 92.81114 -40.10792) (xy 92.819474 -40.09644)
			(xy 92.834773 -40.074673) (xy 92.870439 -40.035194) (xy 92.911242 -40.00105) (xy 92.956391 -39.972904)
			(xy 93.005011 -39.951301) (xy 93.056161 -39.93666) (xy 93.108848 -39.929264) (xy 93.13545 -39.9288)
			(xy 93.162706 -39.929244) (xy 93.216663 -39.936995) (xy 93.268968 -39.952347) (xy 93.318556 -39.974987)
			(xy 93.364416 -40.004455) (xy 93.405615 -40.040149) (xy 93.441315 -40.081344) (xy 93.470789 -40.1272)
			(xy 93.493435 -40.176785) (xy 93.508794 -40.229088) (xy 93.516552 -40.283044) (xy 93.516552 -40.337556)
			(xy 93.508794 -40.391512) (xy 93.493435 -40.443815) (xy 93.470789 -40.4934) (xy 93.441315 -40.539256)
			(xy 93.405615 -40.580451) (xy 93.364416 -40.616145) (xy 93.318556 -40.645613) (xy 93.268968 -40.668253)
			(xy 93.216663 -40.683605) (xy 93.162706 -40.691356) (xy 93.13545 -40.691816) (xy 93.108848 -40.691322)
			(xy 93.056157 -40.683948) (xy 93.005002 -40.669321) (xy 92.956378 -40.647725) (xy 92.911227 -40.619581)
			(xy 92.870427 -40.585434) (xy 92.834768 -40.545947) (xy 92.819474 -40.524176) (xy 92.81114 -40.512696)
			(xy 92.789396 -40.494492) (xy 92.763483 -40.482974) (xy 92.7354 -40.479034) (xy 92.707317 -40.482974)
			(xy 92.681404 -40.494492) (xy 92.65966 -40.512696) (xy 92.651326 -40.524176) (xy 92.636032 -40.545947)
			(xy 92.600365 -40.585425) (xy 92.559561 -40.619568) (xy 92.514411 -40.647713) (xy 92.46579 -40.669315)
			(xy 92.41464 -40.683956) (xy 92.361952 -40.691352) (xy 92.33535 -40.691816) (xy 92.308102 -40.691311)
			(xy 92.25416 -40.683549) (xy 92.201873 -40.66819) (xy 92.152303 -40.645546) (xy 92.10646 -40.616079)
			(xy 92.065276 -40.580388) (xy 92.029591 -40.5392) (xy 92.00013 -40.493353) (xy 91.977493 -40.44378)
			(xy 91.962141 -40.391491) (xy 91.954386 -40.337548) (xy 81.865205 -40.337548) (xy 81.870549 -40.373862)
			(xy 81.871058 -40.401748) (xy 81.870549 -40.429634) (xy 81.862429 -40.48481) (xy 81.846361 -40.538217)
			(xy 81.822689 -40.588714) (xy 81.791916 -40.635227) (xy 81.754699 -40.676764) (xy 81.711831 -40.712439)
			(xy 81.664225 -40.741493) (xy 81.612896 -40.763305) (xy 81.558939 -40.777411) (xy 81.503502 -40.783511)
			(xy 81.447768 -40.781474) (xy 81.392925 -40.771344) (xy 81.340141 -40.753337) (xy 81.290541 -40.727836)
			(xy 81.245183 -40.695385) (xy 81.205034 -40.656676) (xy 81.170948 -40.612533) (xy 81.143652 -40.563898)
			(xy 81.123729 -40.511807) (xy 81.111603 -40.45737) (xy 81.107532 -40.401748) (xy 76.475884 -40.401748)
			(xy 76.463447 -40.444104) (xy 76.440805 -40.493686) (xy 76.411337 -40.53954) (xy 76.375643 -40.580734)
			(xy 76.33445 -40.616429) (xy 76.288596 -40.645899) (xy 76.239016 -40.668543) (xy 76.186717 -40.683901)
			(xy 76.132765 -40.691659) (xy 76.105512 -40.69207) (xy 76.090526 -40.691816) (xy 76.076975 -40.691691)
			(xy 76.050572 -40.697751) (xy 76.026693 -40.710545) (xy 76.007023 -40.729171) (xy 75.992946 -40.752317)
			(xy 75.985456 -40.778351) (xy 75.985079 -40.805438) (xy 75.991843 -40.83167) (xy 76.005271 -40.855198)
			(xy 76.01458 -40.865044) (xy 76.148692 -40.99941) (xy 76.168964 -41.020328) (xy 76.204456 -41.066517)
			(xy 76.233619 -41.116941) (xy 76.255954 -41.17074) (xy 76.26944 -41.220898) (xy 82.650582 -41.220898)
			(xy 82.654653 -41.165276) (xy 82.666779 -41.110839) (xy 82.686702 -41.058748) (xy 82.713998 -41.010113)
			(xy 82.748084 -40.96597) (xy 82.788233 -40.927261) (xy 82.833591 -40.89481) (xy 82.883191 -40.869309)
			(xy 82.935975 -40.851302) (xy 82.990818 -40.841172) (xy 83.046552 -40.839135) (xy 83.101989 -40.845235)
			(xy 83.155946 -40.859341) (xy 83.207275 -40.881153) (xy 83.254881 -40.910207) (xy 83.297749 -40.945882)
			(xy 83.334966 -40.987419) (xy 83.365739 -41.033932) (xy 83.389411 -41.084429) (xy 83.405479 -41.137836)
			(xy 83.413599 -41.193012) (xy 83.414108 -41.220898) (xy 83.413599 -41.248784) (xy 83.405479 -41.30396)
			(xy 83.389411 -41.357367) (xy 83.365739 -41.407864) (xy 83.334966 -41.454377) (xy 83.297749 -41.495914)
			(xy 83.254881 -41.531589) (xy 83.207275 -41.560643) (xy 83.155946 -41.582455) (xy 83.101989 -41.596561)
			(xy 83.046552 -41.602661) (xy 82.990818 -41.600624) (xy 82.935975 -41.590494) (xy 82.883191 -41.572487)
			(xy 82.833591 -41.546986) (xy 82.788233 -41.514535) (xy 82.748084 -41.475826) (xy 82.713998 -41.431683)
			(xy 82.686702 -41.383048) (xy 82.666779 -41.330957) (xy 82.654653 -41.27652) (xy 82.650582 -41.220898)
			(xy 76.26944 -41.220898) (xy 76.271079 -41.226992) (xy 76.278736 -41.284737) (xy 76.279248 -41.313862)
			(xy 76.279248 -45.266864) (xy 76.655422 -45.643292) (xy 78.678024 -45.643292) (xy 78.707149 -45.643769)
			(xy 78.764899 -45.651372) (xy 78.821164 -45.666445) (xy 78.874982 -45.688731) (xy 78.925432 -45.717848)
			(xy 78.971651 -45.753298) (xy 79.01285 -45.794476) (xy 79.048324 -45.840677) (xy 79.077467 -45.891112)
			(xy 79.099781 -45.944918) (xy 79.114883 -46.001175) (xy 79.122516 -46.058922) (xy 79.123032 -46.088046)
			(xy 79.122869 -46.1043) (xy 79.120452 -46.136717) (xy 79.118206 -46.152816) (xy 79.116551 -46.167302)
			(xy 79.120625 -46.19616) (xy 79.132682 -46.222694) (xy 79.151741 -46.244743) (xy 79.176252 -46.260512)
			(xy 79.204217 -46.268717) (xy 79.21879 -46.269148) (xy 81.53908 -46.269148)
		)
		(stroke
			(width 0)
			(type solid)
		)
		(fill yes)
		(layer "In11.Cu")
		(net "P3V3_OCP_V3_2")
	)
	(gr_poly
		(pts
			(xy 363.156754 -236.259116) (xy 363.180722 -236.249829) (xy 363.230731 -236.237952) (xy 363.281976 -236.233961)
			(xy 363.333221 -236.237952) (xy 363.38323 -236.249829) (xy 363.407198 -236.259116) (xy 363.416596 -236.262926)
			(xy 368.582702 -236.262926) (xy 368.587528 -236.21746) (xy 368.590649 -236.192121) (xy 368.603693 -236.142762)
			(xy 368.624172 -236.095997) (xy 368.6516 -236.052938) (xy 368.685323 -236.014609) (xy 368.72454 -235.981923)
			(xy 368.768318 -235.955657) (xy 368.815614 -235.936435) (xy 368.865303 -235.924717) (xy 368.916204 -235.920779)
			(xy 368.967105 -235.924717) (xy 369.016794 -235.936435) (xy 369.06409 -235.955657) (xy 369.107868 -235.981923)
			(xy 369.147085 -236.014609) (xy 369.180808 -236.052938) (xy 369.208236 -236.095997) (xy 369.228715 -236.142762)
			(xy 369.241759 -236.192121) (xy 369.24488 -236.21746) (xy 369.249706 -236.262926) (xy 369.589304 -236.262926)
			(xy 369.687856 -236.164374) (xy 369.697059 -236.15462) (xy 369.710446 -236.131395) (xy 369.717308 -236.10548)
			(xy 369.717169 -236.078673) (xy 369.710039 -236.052831) (xy 369.696412 -236.029745) (xy 369.687094 -236.020102)
			(xy 369.668643 -236.001313) (xy 369.637339 -235.958971) (xy 369.613135 -235.912206) (xy 369.596641 -235.862199)
			(xy 369.588274 -235.81021) (xy 369.58778 -235.783882) (xy 369.588264 -235.757915) (xy 369.596392 -235.70662)
			(xy 369.612444 -235.657228) (xy 369.636025 -235.610955) (xy 369.666554 -235.568941) (xy 369.703281 -235.532221)
			(xy 369.745299 -235.501697) (xy 369.791576 -235.478124) (xy 369.84097 -235.462079) (xy 369.892267 -235.45396)
			(xy 369.918234 -235.453428) (xy 369.953286 -235.455206) (xy 369.967459 -235.456236) (xy 369.995439 -235.451333)
			(xy 370.020985 -235.438911) (xy 370.042119 -235.419932) (xy 370.057207 -235.395864) (xy 370.065078 -235.36857)
			(xy 370.065554 -235.354368) (xy 370.065554 -235.043218) (xy 370.064538 -235.037884) (xy 370.06124 -235.021123)
			(xy 370.057681 -234.987147) (xy 370.057426 -234.970066) (xy 370.057653 -234.952984) (xy 370.061216 -234.919006)
			(xy 370.064538 -234.902248) (xy 370.065554 -234.896914) (xy 370.065554 -234.585764) (xy 370.065039 -234.571575)
			(xy 370.057142 -234.544314) (xy 370.042051 -234.520277) (xy 370.02093 -234.501319) (xy 369.995408 -234.488902)
			(xy 369.967456 -234.483985) (xy 369.953286 -234.484926) (xy 369.918234 -234.486704) (xy 369.892259 -234.486224)
			(xy 369.840948 -234.478102) (xy 369.791539 -234.462052) (xy 369.74525 -234.438471) (xy 369.70322 -234.407938)
			(xy 369.666484 -234.371206) (xy 369.635947 -234.329179) (xy 369.612361 -234.282892) (xy 369.596306 -234.233485)
			(xy 369.588179 -234.182175) (xy 369.588179 -234.130225) (xy 369.596306 -234.078915) (xy 369.612361 -234.029508)
			(xy 369.635947 -233.983221) (xy 369.666484 -233.941194) (xy 369.70322 -233.904462) (xy 369.74525 -233.873929)
			(xy 369.79154 -233.850348) (xy 369.840948 -233.834298) (xy 369.892259 -233.826176) (xy 369.918234 -233.825796)
			(xy 369.953286 -233.827574) (xy 369.967458 -233.828604) (xy 369.995434 -233.823701) (xy 370.020977 -233.811279)
			(xy 370.042106 -233.792298) (xy 370.057187 -233.768229) (xy 370.065051 -233.740937) (xy 370.065554 -233.726736)
			(xy 370.065554 -233.415332) (xy 370.064538 -233.409998) (xy 370.061239 -233.393237) (xy 370.057678 -233.359261)
			(xy 370.057426 -233.34218) (xy 370.057652 -233.325098) (xy 370.061214 -233.291119) (xy 370.064538 -233.274362)
			(xy 370.065554 -233.269028) (xy 370.065554 -232.957878) (xy 370.065041 -232.943687) (xy 370.057146 -232.916423)
			(xy 370.042056 -232.892383) (xy 370.020934 -232.873422) (xy 369.995411 -232.861003) (xy 369.967456 -232.856085)
			(xy 369.953286 -232.85704) (xy 369.918234 -232.858818) (xy 369.892266 -232.858338) (xy 369.840968 -232.850218)
			(xy 369.791572 -232.834173) (xy 369.745295 -232.810598) (xy 369.703276 -232.780073) (xy 369.666549 -232.74335)
			(xy 369.63602 -232.701334) (xy 369.61244 -232.655059) (xy 369.59639 -232.605665) (xy 369.588265 -232.554368)
			(xy 369.588265 -232.502432) (xy 369.59639 -232.451135) (xy 369.61244 -232.401741) (xy 369.63602 -232.355466)
			(xy 369.666549 -232.31345) (xy 369.703276 -232.276727) (xy 369.745295 -232.246202) (xy 369.791572 -232.222627)
			(xy 369.840968 -232.206582) (xy 369.892266 -232.198462) (xy 369.918234 -232.19791) (xy 369.953286 -232.199688)
			(xy 369.967459 -232.200718) (xy 369.995436 -232.195815) (xy 370.02098 -232.183393) (xy 370.042112 -232.164413)
			(xy 370.057196 -232.140344) (xy 370.065063 -232.113051) (xy 370.065554 -232.09885) (xy 370.065554 -231.78643)
			(xy 370.064538 -231.78135) (xy 370.061326 -231.764837) (xy 370.057885 -231.73137) (xy 370.05768 -231.714548)
			(xy 370.05791 -231.697728) (xy 370.061347 -231.664262) (xy 370.064538 -231.647746) (xy 370.065554 -231.642666)
			(xy 370.065554 -231.329992) (xy 370.065041 -231.315773) (xy 370.057126 -231.288457) (xy 370.041996 -231.264375)
			(xy 370.020819 -231.245391) (xy 369.995234 -231.232973) (xy 369.967218 -231.22808) (xy 369.953032 -231.229154)
			(xy 369.91798 -231.230932) (xy 369.892016 -231.230421) (xy 369.840726 -231.222295) (xy 369.79134 -231.206246)
			(xy 369.745072 -231.182668) (xy 369.703061 -231.152144) (xy 369.666343 -231.115423) (xy 369.635821 -231.073411)
			(xy 369.612247 -231.027142) (xy 369.5962 -230.977754) (xy 369.588077 -230.926464) (xy 369.588077 -230.874536)
			(xy 369.5962 -230.823246) (xy 369.612247 -230.773858) (xy 369.635821 -230.727589) (xy 369.666343 -230.685577)
			(xy 369.703061 -230.648856) (xy 369.745072 -230.618332) (xy 369.79134 -230.594754) (xy 369.840726 -230.578705)
			(xy 369.892016 -230.570579) (xy 369.91798 -230.570024) (xy 369.94493 -230.570555) (xy 369.998116 -230.579298)
			(xy 370.049177 -230.596557) (xy 370.096762 -230.621872) (xy 370.139607 -230.654575) (xy 370.176578 -230.693796)
			(xy 370.206694 -230.738497) (xy 370.229157 -230.787493) (xy 370.23675 -230.813356) (xy 370.241224 -230.827914)
			(xy 370.257498 -230.853643) (xy 370.280634 -230.873432) (xy 370.308574 -230.88552) (xy 370.338837 -230.888835)
			(xy 370.368732 -230.883081) (xy 370.395603 -230.86877) (xy 370.406676 -230.858314) (xy 370.742464 -230.522526)
			(xy 370.742464 -229.58425) (xy 370.713762 -229.57028) (xy 370.690181 -229.558284) (xy 370.646846 -229.527938)
			(xy 370.608899 -229.491077) (xy 370.577307 -229.448642) (xy 370.552878 -229.401717) (xy 370.536236 -229.351499)
			(xy 370.527806 -229.299272) (xy 370.527803 -229.246368) (xy 370.536227 -229.19414) (xy 370.552862 -229.14392)
			(xy 370.577285 -229.096992) (xy 370.608872 -229.054553) (xy 370.646815 -229.017687) (xy 370.690147 -228.987337)
			(xy 370.713762 -228.975412) (xy 370.742464 -228.961442) (xy 370.742464 -228.809296) (xy 370.742037 -228.795315)
			(xy 370.734477 -228.768396) (xy 370.719896 -228.744538) (xy 370.699389 -228.72553) (xy 370.674494 -228.7128)
			(xy 370.64708 -228.707301) (xy 370.619201 -228.709447) (xy 370.592951 -228.719076) (xy 370.581428 -228.727)
			(xy 370.560164 -228.741717) (xy 370.514026 -228.765068) (xy 370.464817 -228.780957) (xy 370.413735 -228.788998)
			(xy 370.38788 -228.789484) (xy 370.361913 -228.788973) (xy 370.310619 -228.780847) (xy 370.261227 -228.764797)
			(xy 370.214953 -228.741218) (xy 370.172938 -228.710692) (xy 370.136214 -228.67397) (xy 370.105687 -228.631955)
			(xy 370.082107 -228.585682) (xy 370.066056 -228.536291) (xy 370.057928 -228.484997) (xy 370.057426 -228.45903)
			(xy 370.057966 -228.431585) (xy 370.067034 -228.377448) (xy 370.084924 -228.325554) (xy 370.111144 -228.277331)
			(xy 370.144975 -228.234105) (xy 370.164868 -228.21519) (xy 370.174682 -228.205609) (xy 370.189255 -228.182388)
			(xy 370.197113 -228.156123) (xy 370.197688 -228.128713) (xy 370.190938 -228.102142) (xy 370.177351 -228.07833)
			(xy 370.167916 -228.068378) (xy 370.049298 -227.94976) (xy 370.019834 -227.959412) (xy 369.995038 -227.966892)
			(xy 369.943875 -227.974925) (xy 369.91798 -227.975414) (xy 369.892013 -227.97493) (xy 369.840719 -227.966802)
			(xy 369.791327 -227.95075) (xy 369.745055 -227.927168) (xy 369.703042 -227.896639) (xy 369.666322 -227.859912)
			(xy 369.6358 -227.817894) (xy 369.612227 -227.771617) (xy 369.596184 -227.722223) (xy 369.588066 -227.670927)
			(xy 369.587526 -227.64496) (xy 369.588035 -227.618249) (xy 369.596621 -227.565522) (xy 369.613578 -227.514863)
			(xy 369.638466 -227.467593) (xy 369.670634 -227.424943) (xy 369.709246 -227.388025) (xy 369.753295 -227.3578)
			(xy 369.777264 -227.346002) (xy 369.777264 -227.198428) (xy 369.776846 -227.184925) (xy 369.769762 -227.158864)
			(xy 369.756083 -227.135577) (xy 369.736769 -227.116701) (xy 369.713176 -227.103558) (xy 369.686959 -227.097072)
			(xy 369.65996 -227.097697) (xy 369.634072 -227.105391) (xy 369.622324 -227.112068) (xy 369.602636 -227.123798)
			(xy 369.560714 -227.14231) (xy 369.516636 -227.154853) (xy 369.471248 -227.161188) (xy 369.448334 -227.161598)
			(xy 369.42236 -227.161118) (xy 369.371049 -227.152996) (xy 369.321642 -227.136947) (xy 369.275353 -227.113366)
			(xy 369.233324 -227.082834) (xy 369.196589 -227.046102) (xy 369.166052 -227.004076) (xy 369.142466 -226.95779)
			(xy 369.126412 -226.908384) (xy 369.118285 -226.857074) (xy 369.118285 -226.805126) (xy 369.126412 -226.753816)
			(xy 369.142466 -226.70441) (xy 369.166052 -226.658124) (xy 369.196589 -226.616098) (xy 369.233324 -226.579366)
			(xy 369.275353 -226.548834) (xy 369.321642 -226.525253) (xy 369.371049 -226.509204) (xy 369.42236 -226.501082)
			(xy 369.448334 -226.50069) (xy 369.47125 -226.501077) (xy 369.516643 -226.507404) (xy 369.560726 -226.519946)
			(xy 369.602651 -226.538463) (xy 369.622324 -226.55022) (xy 369.634034 -226.556959) (xy 369.659932 -226.564627)
			(xy 369.686934 -226.565232) (xy 369.713149 -226.558733) (xy 369.736741 -226.545584) (xy 369.756058 -226.526706)
			(xy 369.769746 -226.503423) (xy 369.776847 -226.477364) (xy 369.777264 -226.46386) (xy 369.777264 -226.316286)
			(xy 369.753344 -226.304422) (xy 369.709357 -226.274162) (xy 369.670798 -226.237232) (xy 369.638669 -226.19459)
			(xy 369.613804 -226.147342) (xy 369.596847 -226.096716) (xy 369.588238 -226.044023) (xy 369.58778 -226.017328)
			(xy 369.588261 -225.991358) (xy 369.596383 -225.940058) (xy 369.61243 -225.89066) (xy 369.636009 -225.844381)
			(xy 369.666538 -225.80236) (xy 369.703265 -225.765634) (xy 369.745286 -225.735106) (xy 369.791565 -225.711528)
			(xy 369.840964 -225.695481) (xy 369.892264 -225.68736) (xy 369.918234 -225.686874) (xy 369.94371 -225.687326)
			(xy 369.994064 -225.695111) (xy 370.042624 -225.710538) (xy 370.088238 -225.733241) (xy 370.129823 -225.762681)
			(xy 370.166394 -225.798159) (xy 370.18214 -225.818192) (xy 370.191292 -225.829433) (xy 370.214561 -225.846692)
			(xy 370.241739 -225.856729) (xy 370.270642 -225.858736) (xy 370.298946 -225.852553) (xy 370.324378 -225.838675)
			(xy 370.335048 -225.82886) (xy 370.39804 -225.765868) (xy 370.643658 -225.765868) (xy 370.663721 -225.749429)
			(xy 370.707963 -225.72236) (xy 370.755891 -225.702536) (xy 370.806328 -225.690443) (xy 370.858034 -225.686379)
			(xy 370.90974 -225.690443) (xy 370.960177 -225.702536) (xy 371.008105 -225.72236) (xy 371.052347 -225.749429)
			(xy 371.07241 -225.765868) (xy 371.583458 -225.765868) (xy 371.603521 -225.749429) (xy 371.647763 -225.72236)
			(xy 371.695691 -225.702536) (xy 371.746128 -225.690443) (xy 371.797834 -225.686379) (xy 371.84954 -225.690443)
			(xy 371.899977 -225.702536) (xy 371.947905 -225.72236) (xy 371.992147 -225.749429) (xy 372.01221 -225.765868)
			(xy 372.41988 -225.765868) (xy 372.73484 -225.450908) (xy 372.73484 -224.779586) (xy 372.699534 -224.718626)
			(xy 372.676674 -224.714308) (xy 372.651742 -224.70916) (xy 372.603736 -224.692222) (xy 372.558896 -224.668121)
			(xy 372.518285 -224.637426) (xy 372.482862 -224.600864) (xy 372.453468 -224.559301) (xy 372.430797 -224.513722)
			(xy 372.415387 -224.465203) (xy 372.407601 -224.414896) (xy 372.40718 -224.389442) (xy 372.407683 -224.363179)
			(xy 372.415986 -224.311314) (xy 372.43239 -224.261416) (xy 372.456482 -224.214742) (xy 372.487655 -224.172466)
			(xy 372.525123 -224.135655) (xy 372.567943 -224.105236) (xy 372.615037 -224.081973) (xy 372.665217 -224.066455)
			(xy 372.691152 -224.06229) (xy 372.73484 -224.056194) (xy 372.73484 -223.761808) (xy 372.70563 -223.732598)
			(xy 372.694484 -223.72216) (xy 372.6675 -223.707896) (xy 372.637505 -223.702242) (xy 372.60718 -223.705705)
			(xy 372.579232 -223.717976) (xy 372.556159 -223.737957) (xy 372.547642 -223.750632) (xy 372.532729 -223.773559)
			(xy 372.496556 -223.814576) (xy 372.454114 -223.849067) (xy 372.406565 -223.876088) (xy 372.355212 -223.894897)
			(xy 372.32844 -223.900492) (xy 372.305326 -223.90481) (xy 372.101872 -224.257616) (xy 372.109492 -224.279714)
			(xy 372.118282 -224.306289) (xy 372.127726 -224.361457) (xy 372.128288 -224.389442) (xy 372.127779 -224.415409)
			(xy 372.119654 -224.466704) (xy 372.103606 -224.516097) (xy 372.080028 -224.562371) (xy 372.049502 -224.604387)
			(xy 372.012779 -224.64111) (xy 371.970763 -224.671636) (xy 371.924489 -224.695214) (xy 371.875096 -224.711262)
			(xy 371.823801 -224.719387) (xy 371.771867 -224.719387) (xy 371.720572 -224.711262) (xy 371.671179 -224.695214)
			(xy 371.624905 -224.671636) (xy 371.582889 -224.64111) (xy 371.546166 -224.604387) (xy 371.51564 -224.562371)
			(xy 371.492062 -224.516097) (xy 371.476014 -224.466704) (xy 371.467889 -224.415409) (xy 371.46738 -224.389442)
			(xy 371.467853 -224.363995) (xy 371.475661 -224.313702) (xy 371.491084 -224.2652) (xy 371.513758 -224.219635)
			(xy 371.543146 -224.178082) (xy 371.578556 -224.141524) (xy 371.619149 -224.110824) (xy 371.663968 -224.086708)
			(xy 371.711952 -224.069745) (xy 371.736874 -224.064576) (xy 371.759734 -224.060258) (xy 371.963442 -223.707198)
			(xy 371.955822 -223.685354) (xy 371.947026 -223.65878) (xy 371.937571 -223.603612) (xy 371.937026 -223.575626)
			(xy 371.937448 -223.55172) (xy 371.944341 -223.504407) (xy 371.957986 -223.458583) (xy 371.978097 -223.415206)
			(xy 372.004255 -223.375184) (xy 372.035912 -223.339353) (xy 372.072407 -223.308463) (xy 372.092474 -223.295464)
			(xy 372.105126 -223.286937) (xy 372.125051 -223.263848) (xy 372.137285 -223.235911) (xy 372.14074 -223.20561)
			(xy 372.13511 -223.175636) (xy 372.120894 -223.148654) (xy 372.110508 -223.137476) (xy 372.07952 -223.106488)
			(xy 365.68888 -223.106488) (xy 365.681768 -223.09963) (xy 350.977962 -223.09963) (xy 350.957625 -223.145545)
			(xy 350.907842 -223.232761) (xy 350.878648 -223.27362) (xy 350.873581 -223.281177) (xy 350.868631 -223.298674)
			(xy 350.870082 -223.316799) (xy 350.87775 -223.333286) (xy 350.883982 -223.339914) (xy 350.902356 -223.358679)
			(xy 350.933519 -223.400949) (xy 350.9576 -223.447619) (xy 350.973992 -223.497511) (xy 350.982283 -223.549368)
			(xy 350.982788 -223.575626) (xy 350.982277 -223.601593) (xy 350.974149 -223.652887) (xy 350.958099 -223.702278)
			(xy 350.93452 -223.748551) (xy 350.903994 -223.790566) (xy 350.867272 -223.827289) (xy 350.825258 -223.857816)
			(xy 350.778985 -223.881396) (xy 350.729595 -223.897448) (xy 350.678301 -223.905576) (xy 350.652334 -223.90608)
			(xy 350.629958 -223.905724) (xy 350.58561 -223.899735) (xy 350.563942 -223.894142) (xy 350.555068 -223.892041)
			(xy 350.53691 -223.893561) (xy 350.520428 -223.901334) (xy 350.507705 -223.914379) (xy 350.503744 -223.92259)
			(xy 350.484048 -223.96595) (xy 350.436441 -224.048437) (xy 350.408748 -224.087182) (xy 350.403692 -224.094738)
			(xy 350.398764 -224.112225) (xy 350.400229 -224.130334) (xy 350.407906 -224.146801) (xy 350.414082 -224.153476)
			(xy 350.432502 -224.172247) (xy 350.463746 -224.214548) (xy 350.487892 -224.261266) (xy 350.504329 -224.31122)
			(xy 350.512641 -224.363147) (xy 350.513142 -224.389442) (xy 350.791526 -224.389442) (xy 350.791938 -224.363966)
			(xy 350.799733 -224.313615) (xy 350.81516 -224.265055) (xy 350.837855 -224.219437) (xy 350.867279 -224.177841)
			(xy 350.902736 -224.141251) (xy 350.943387 -224.110534) (xy 350.988269 -224.086417) (xy 351.03632 -224.069471)
			(xy 351.061274 -224.064322) (xy 351.084388 -224.060004) (xy 351.287842 -223.707452) (xy 351.279968 -223.685608)
			(xy 351.271225 -223.658955) (xy 351.261769 -223.60367) (xy 351.261172 -223.575626) (xy 351.261682 -223.549639)
			(xy 351.269812 -223.498304) (xy 351.285873 -223.448874) (xy 351.309469 -223.402564) (xy 351.340019 -223.360516)
			(xy 351.37677 -223.323765) (xy 351.418818 -223.293215) (xy 351.465128 -223.269619) (xy 351.514558 -223.253558)
			(xy 351.565893 -223.245428) (xy 351.617867 -223.245428) (xy 351.669202 -223.253558) (xy 351.718632 -223.269619)
			(xy 351.764942 -223.293215) (xy 351.80699 -223.323765) (xy 351.843741 -223.360516) (xy 351.874291 -223.402564)
			(xy 351.897887 -223.448874) (xy 351.913948 -223.498304) (xy 351.922078 -223.549639) (xy 351.922588 -223.575626)
			(xy 351.922097 -223.601109) (xy 351.922022 -223.601593) (xy 352.201989 -223.601593) (xy 352.201989 -223.549659)
			(xy 352.210114 -223.498364) (xy 352.226162 -223.448971) (xy 352.24974 -223.402697) (xy 352.280266 -223.360681)
			(xy 352.316989 -223.323958) (xy 352.359005 -223.293432) (xy 352.405279 -223.269854) (xy 352.454672 -223.253806)
			(xy 352.505967 -223.245681) (xy 352.557901 -223.245681) (xy 352.609196 -223.253806) (xy 352.658589 -223.269854)
			(xy 352.704863 -223.293432) (xy 352.746879 -223.323958) (xy 352.783602 -223.360681) (xy 352.814128 -223.402697)
			(xy 352.837706 -223.448971) (xy 352.853754 -223.498364) (xy 352.861879 -223.549659) (xy 352.862388 -223.575626)
			(xy 352.861879 -223.601593) (xy 352.853754 -223.652888) (xy 352.837706 -223.702281) (xy 352.814128 -223.748555)
			(xy 352.783602 -223.790571) (xy 352.746879 -223.827294) (xy 352.704863 -223.85782) (xy 352.658589 -223.881398)
			(xy 352.609196 -223.897446) (xy 352.557901 -223.905571) (xy 352.505967 -223.905571) (xy 352.454672 -223.897446)
			(xy 352.405279 -223.881398) (xy 352.359005 -223.85782) (xy 352.316989 -223.827294) (xy 352.280266 -223.790571)
			(xy 352.24974 -223.748555) (xy 352.226162 -223.702281) (xy 352.210114 -223.652888) (xy 352.201989 -223.601593)
			(xy 351.922022 -223.601593) (xy 351.914288 -223.651474) (xy 351.898844 -223.700045) (xy 351.876129 -223.74567)
			(xy 351.846683 -223.787269) (xy 351.811202 -223.823858) (xy 351.770528 -223.854569) (xy 351.725622 -223.878676)
			(xy 351.67755 -223.895606) (xy 351.652586 -223.900746) (xy 351.629472 -223.905064) (xy 351.426272 -224.257362)
			(xy 351.434146 -224.27946) (xy 351.442906 -224.306108) (xy 351.452351 -224.361397) (xy 351.452942 -224.389442)
			(xy 351.731326 -224.389442) (xy 351.731836 -224.363455) (xy 351.739966 -224.31212) (xy 351.756027 -224.26269)
			(xy 351.779623 -224.21638) (xy 351.810173 -224.174332) (xy 351.846924 -224.137581) (xy 351.888972 -224.107031)
			(xy 351.935282 -224.083435) (xy 351.984712 -224.067374) (xy 352.036047 -224.059244) (xy 352.088021 -224.059244)
			(xy 352.139356 -224.067374) (xy 352.188786 -224.083435) (xy 352.235096 -224.107031) (xy 352.277144 -224.137581)
			(xy 352.313895 -224.174332) (xy 352.344445 -224.21638) (xy 352.368041 -224.26269) (xy 352.384102 -224.31212)
			(xy 352.392232 -224.363455) (xy 352.392742 -224.389442) (xy 352.67138 -224.389442) (xy 352.671787 -224.363988)
			(xy 352.679574 -224.31368) (xy 352.694987 -224.265161) (xy 352.71766 -224.219581) (xy 352.747056 -224.178019)
			(xy 352.78248 -224.141457) (xy 352.823093 -224.110763) (xy 352.867934 -224.086661) (xy 352.915942 -224.069724)
			(xy 352.940874 -224.064576) (xy 352.963734 -224.060258) (xy 353.167442 -223.707198) (xy 353.159822 -223.685354)
			(xy 353.151098 -223.658762) (xy 353.141641 -223.603606) (xy 353.141026 -223.575626) (xy 353.141535 -223.549659)
			(xy 353.14966 -223.498364) (xy 353.165708 -223.448971) (xy 353.189286 -223.402697) (xy 353.219812 -223.360681)
			(xy 353.256535 -223.323958) (xy 353.298551 -223.293432) (xy 353.344825 -223.269854) (xy 353.394218 -223.253806)
			(xy 353.445513 -223.245681) (xy 353.497447 -223.245681) (xy 353.548742 -223.253806) (xy 353.598135 -223.269854)
			(xy 353.644409 -223.293432) (xy 353.686425 -223.323958) (xy 353.723148 -223.360681) (xy 353.753674 -223.402697)
			(xy 353.777252 -223.448971) (xy 353.7933 -223.498364) (xy 353.801425 -223.549659) (xy 353.801934 -223.575626)
			(xy 353.801486 -223.601078) (xy 353.801406 -223.601593) (xy 354.081589 -223.601593) (xy 354.081589 -223.549659)
			(xy 354.089714 -223.498364) (xy 354.105762 -223.448971) (xy 354.12934 -223.402697) (xy 354.159866 -223.360681)
			(xy 354.196589 -223.323958) (xy 354.238605 -223.293432) (xy 354.284879 -223.269854) (xy 354.334272 -223.253806)
			(xy 354.385567 -223.245681) (xy 354.437501 -223.245681) (xy 354.488796 -223.253806) (xy 354.538189 -223.269854)
			(xy 354.584463 -223.293432) (xy 354.626479 -223.323958) (xy 354.663202 -223.360681) (xy 354.693728 -223.402697)
			(xy 354.717306 -223.448971) (xy 354.733354 -223.498364) (xy 354.741479 -223.549659) (xy 354.741988 -223.575626)
			(xy 354.741479 -223.601593) (xy 354.733354 -223.652888) (xy 354.717306 -223.702281) (xy 354.693728 -223.748555)
			(xy 354.663202 -223.790571) (xy 354.626479 -223.827294) (xy 354.584463 -223.85782) (xy 354.538189 -223.881398)
			(xy 354.488796 -223.897446) (xy 354.437501 -223.905571) (xy 354.385567 -223.905571) (xy 354.334272 -223.897446)
			(xy 354.284879 -223.881398) (xy 354.238605 -223.85782) (xy 354.196589 -223.827294) (xy 354.159866 -223.790571)
			(xy 354.12934 -223.748555) (xy 354.105762 -223.702281) (xy 354.089714 -223.652888) (xy 354.081589 -223.601593)
			(xy 353.801406 -223.601593) (xy 353.793704 -223.651385) (xy 353.778297 -223.699901) (xy 353.755629 -223.74548)
			(xy 353.726238 -223.787043) (xy 353.690819 -223.823605) (xy 353.65021 -223.8543) (xy 353.605374 -223.878403)
			(xy 353.55737 -223.895342) (xy 353.53244 -223.900492) (xy 353.509326 -223.90481) (xy 353.305872 -224.257616)
			(xy 353.313492 -224.279714) (xy 353.322233 -224.306301) (xy 353.331678 -224.361461) (xy 353.332288 -224.389442)
			(xy 353.61118 -224.389442) (xy 353.611689 -224.363475) (xy 353.619814 -224.31218) (xy 353.635862 -224.262787)
			(xy 353.65944 -224.216513) (xy 353.689966 -224.174497) (xy 353.726689 -224.137774) (xy 353.768705 -224.107248)
			(xy 353.814979 -224.08367) (xy 353.864372 -224.067622) (xy 353.915667 -224.059497) (xy 353.967601 -224.059497)
			(xy 354.018896 -224.067622) (xy 354.068289 -224.08367) (xy 354.114563 -224.107248) (xy 354.156579 -224.137774)
			(xy 354.193302 -224.174497) (xy 354.223828 -224.216513) (xy 354.247406 -224.262787) (xy 354.263454 -224.31218)
			(xy 354.271579 -224.363475) (xy 354.272088 -224.389442) (xy 354.55098 -224.389442) (xy 354.551387 -224.363988)
			(xy 354.559174 -224.31368) (xy 354.574587 -224.265161) (xy 354.59726 -224.219581) (xy 354.626656 -224.178019)
			(xy 354.66208 -224.141457) (xy 354.702693 -224.110763) (xy 354.747534 -224.086661) (xy 354.795542 -224.069724)
			(xy 354.820474 -224.064576) (xy 354.843334 -224.060258) (xy 355.047042 -223.707198) (xy 355.039422 -223.685354)
			(xy 355.030698 -223.658762) (xy 355.021241 -223.603606) (xy 355.020626 -223.575626) (xy 355.021135 -223.549659)
			(xy 355.02926 -223.498364) (xy 355.045308 -223.448971) (xy 355.068886 -223.402697) (xy 355.099412 -223.360681)
			(xy 355.136135 -223.323958) (xy 355.178151 -223.293432) (xy 355.224425 -223.269854) (xy 355.273818 -223.253806)
			(xy 355.325113 -223.245681) (xy 355.377047 -223.245681) (xy 355.428342 -223.253806) (xy 355.477735 -223.269854)
			(xy 355.524009 -223.293432) (xy 355.566025 -223.323958) (xy 355.602748 -223.360681) (xy 355.633274 -223.402697)
			(xy 355.656852 -223.448971) (xy 355.6729 -223.498364) (xy 355.681025 -223.549659) (xy 355.681534 -223.575626)
			(xy 355.681086 -223.601078) (xy 355.681006 -223.601593) (xy 355.961189 -223.601593) (xy 355.961189 -223.549659)
			(xy 355.969314 -223.498364) (xy 355.985362 -223.448971) (xy 356.00894 -223.402697) (xy 356.039466 -223.360681)
			(xy 356.076189 -223.323958) (xy 356.118205 -223.293432) (xy 356.164479 -223.269854) (xy 356.213872 -223.253806)
			(xy 356.265167 -223.245681) (xy 356.317101 -223.245681) (xy 356.368396 -223.253806) (xy 356.417789 -223.269854)
			(xy 356.464063 -223.293432) (xy 356.506079 -223.323958) (xy 356.542802 -223.360681) (xy 356.573328 -223.402697)
			(xy 356.596906 -223.448971) (xy 356.612954 -223.498364) (xy 356.621079 -223.549659) (xy 356.621588 -223.575626)
			(xy 356.621079 -223.601593) (xy 356.612954 -223.652888) (xy 356.596906 -223.702281) (xy 356.573328 -223.748555)
			(xy 356.542802 -223.790571) (xy 356.506079 -223.827294) (xy 356.464063 -223.85782) (xy 356.417789 -223.881398)
			(xy 356.368396 -223.897446) (xy 356.317101 -223.905571) (xy 356.265167 -223.905571) (xy 356.213872 -223.897446)
			(xy 356.164479 -223.881398) (xy 356.118205 -223.85782) (xy 356.076189 -223.827294) (xy 356.039466 -223.790571)
			(xy 356.00894 -223.748555) (xy 355.985362 -223.702281) (xy 355.969314 -223.652888) (xy 355.961189 -223.601593)
			(xy 355.681006 -223.601593) (xy 355.673304 -223.651385) (xy 355.657897 -223.699901) (xy 355.635229 -223.74548)
			(xy 355.605838 -223.787043) (xy 355.570419 -223.823605) (xy 355.52981 -223.8543) (xy 355.484974 -223.878403)
			(xy 355.43697 -223.895342) (xy 355.41204 -223.900492) (xy 355.388926 -223.90481) (xy 355.185472 -224.257616)
			(xy 355.193092 -224.279714) (xy 355.201833 -224.306301) (xy 355.211278 -224.361461) (xy 355.211888 -224.389442)
			(xy 355.49078 -224.389442) (xy 355.491289 -224.363475) (xy 355.499414 -224.31218) (xy 355.515462 -224.262787)
			(xy 355.53904 -224.216513) (xy 355.569566 -224.174497) (xy 355.606289 -224.137774) (xy 355.648305 -224.107248)
			(xy 355.694579 -224.08367) (xy 355.743972 -224.067622) (xy 355.795267 -224.059497) (xy 355.847201 -224.059497)
			(xy 355.898496 -224.067622) (xy 355.947889 -224.08367) (xy 355.994163 -224.107248) (xy 356.036179 -224.137774)
			(xy 356.072902 -224.174497) (xy 356.103428 -224.216513) (xy 356.127006 -224.262787) (xy 356.143054 -224.31218)
			(xy 356.151179 -224.363475) (xy 356.151688 -224.389442) (xy 356.43058 -224.389442) (xy 356.430987 -224.363988)
			(xy 356.438774 -224.31368) (xy 356.454187 -224.265161) (xy 356.47686 -224.219581) (xy 356.506256 -224.178019)
			(xy 356.54168 -224.141457) (xy 356.582293 -224.110763) (xy 356.627134 -224.086661) (xy 356.675142 -224.069724)
			(xy 356.700074 -224.064576) (xy 356.722934 -224.060258) (xy 356.926642 -223.707198) (xy 356.919022 -223.685354)
			(xy 356.910298 -223.658762) (xy 356.900841 -223.603606) (xy 356.900226 -223.575626) (xy 356.900735 -223.549659)
			(xy 356.90886 -223.498364) (xy 356.924908 -223.448971) (xy 356.948486 -223.402697) (xy 356.979012 -223.360681)
			(xy 357.015735 -223.323958) (xy 357.057751 -223.293432) (xy 357.104025 -223.269854) (xy 357.153418 -223.253806)
			(xy 357.204713 -223.245681) (xy 357.256647 -223.245681) (xy 357.307942 -223.253806) (xy 357.357335 -223.269854)
			(xy 357.403609 -223.293432) (xy 357.445625 -223.323958) (xy 357.482348 -223.360681) (xy 357.512874 -223.402697)
			(xy 357.536452 -223.448971) (xy 357.5525 -223.498364) (xy 357.560625 -223.549659) (xy 357.561134 -223.575626)
			(xy 357.560686 -223.601078) (xy 357.560606 -223.601593) (xy 357.840789 -223.601593) (xy 357.840789 -223.549659)
			(xy 357.848914 -223.498364) (xy 357.864962 -223.448971) (xy 357.88854 -223.402697) (xy 357.919066 -223.360681)
			(xy 357.955789 -223.323958) (xy 357.997805 -223.293432) (xy 358.044079 -223.269854) (xy 358.093472 -223.253806)
			(xy 358.144767 -223.245681) (xy 358.196701 -223.245681) (xy 358.247996 -223.253806) (xy 358.297389 -223.269854)
			(xy 358.343663 -223.293432) (xy 358.385679 -223.323958) (xy 358.422402 -223.360681) (xy 358.452928 -223.402697)
			(xy 358.476506 -223.448971) (xy 358.492554 -223.498364) (xy 358.500679 -223.549659) (xy 358.501188 -223.575626)
			(xy 358.500679 -223.601593) (xy 358.492554 -223.652888) (xy 358.476506 -223.702281) (xy 358.452928 -223.748555)
			(xy 358.422402 -223.790571) (xy 358.385679 -223.827294) (xy 358.343663 -223.85782) (xy 358.297389 -223.881398)
			(xy 358.247996 -223.897446) (xy 358.196701 -223.905571) (xy 358.144767 -223.905571) (xy 358.093472 -223.897446)
			(xy 358.044079 -223.881398) (xy 357.997805 -223.85782) (xy 357.955789 -223.827294) (xy 357.919066 -223.790571)
			(xy 357.88854 -223.748555) (xy 357.864962 -223.702281) (xy 357.848914 -223.652888) (xy 357.840789 -223.601593)
			(xy 357.560606 -223.601593) (xy 357.552904 -223.651385) (xy 357.537497 -223.699901) (xy 357.514829 -223.74548)
			(xy 357.485438 -223.787043) (xy 357.450019 -223.823605) (xy 357.40941 -223.8543) (xy 357.364574 -223.878403)
			(xy 357.31657 -223.895342) (xy 357.29164 -223.900492) (xy 357.268526 -223.90481) (xy 357.065072 -224.257616)
			(xy 357.072692 -224.279714) (xy 357.081433 -224.306301) (xy 357.090878 -224.361461) (xy 357.091488 -224.389442)
			(xy 357.37038 -224.389442) (xy 357.370889 -224.363475) (xy 357.379014 -224.31218) (xy 357.395062 -224.262787)
			(xy 357.41864 -224.216513) (xy 357.449166 -224.174497) (xy 357.485889 -224.137774) (xy 357.527905 -224.107248)
			(xy 357.574179 -224.08367) (xy 357.623572 -224.067622) (xy 357.674867 -224.059497) (xy 357.726801 -224.059497)
			(xy 357.778096 -224.067622) (xy 357.827489 -224.08367) (xy 357.873763 -224.107248) (xy 357.915779 -224.137774)
			(xy 357.952502 -224.174497) (xy 357.983028 -224.216513) (xy 358.006606 -224.262787) (xy 358.022654 -224.31218)
			(xy 358.030779 -224.363475) (xy 358.031288 -224.389442) (xy 358.31018 -224.389442) (xy 358.310587 -224.363988)
			(xy 358.318374 -224.31368) (xy 358.333787 -224.265161) (xy 358.35646 -224.219581) (xy 358.385856 -224.178019)
			(xy 358.42128 -224.141457) (xy 358.461893 -224.110763) (xy 358.506734 -224.086661) (xy 358.554742 -224.069724)
			(xy 358.579674 -224.064576) (xy 358.602534 -224.060258) (xy 358.806242 -223.707198) (xy 358.798622 -223.685354)
			(xy 358.789898 -223.658762) (xy 358.780441 -223.603606) (xy 358.779826 -223.575626) (xy 358.780335 -223.549659)
			(xy 358.78846 -223.498364) (xy 358.804508 -223.448971) (xy 358.828086 -223.402697) (xy 358.858612 -223.360681)
			(xy 358.895335 -223.323958) (xy 358.937351 -223.293432) (xy 358.983625 -223.269854) (xy 359.033018 -223.253806)
			(xy 359.084313 -223.245681) (xy 359.136247 -223.245681) (xy 359.187542 -223.253806) (xy 359.236935 -223.269854)
			(xy 359.283209 -223.293432) (xy 359.325225 -223.323958) (xy 359.361948 -223.360681) (xy 359.392474 -223.402697)
			(xy 359.416052 -223.448971) (xy 359.4321 -223.498364) (xy 359.440225 -223.549659) (xy 359.440734 -223.575626)
			(xy 359.440286 -223.601078) (xy 359.440206 -223.601593) (xy 359.720389 -223.601593) (xy 359.720389 -223.549659)
			(xy 359.728514 -223.498364) (xy 359.744562 -223.448971) (xy 359.76814 -223.402697) (xy 359.798666 -223.360681)
			(xy 359.835389 -223.323958) (xy 359.877405 -223.293432) (xy 359.923679 -223.269854) (xy 359.973072 -223.253806)
			(xy 360.024367 -223.245681) (xy 360.076301 -223.245681) (xy 360.127596 -223.253806) (xy 360.176989 -223.269854)
			(xy 360.223263 -223.293432) (xy 360.265279 -223.323958) (xy 360.302002 -223.360681) (xy 360.332528 -223.402697)
			(xy 360.356106 -223.448971) (xy 360.372154 -223.498364) (xy 360.380279 -223.549659) (xy 360.380788 -223.575626)
			(xy 360.380279 -223.601593) (xy 360.372154 -223.652888) (xy 360.356106 -223.702281) (xy 360.332528 -223.748555)
			(xy 360.302002 -223.790571) (xy 360.265279 -223.827294) (xy 360.223263 -223.85782) (xy 360.176989 -223.881398)
			(xy 360.127596 -223.897446) (xy 360.076301 -223.905571) (xy 360.024367 -223.905571) (xy 359.973072 -223.897446)
			(xy 359.923679 -223.881398) (xy 359.877405 -223.85782) (xy 359.835389 -223.827294) (xy 359.798666 -223.790571)
			(xy 359.76814 -223.748555) (xy 359.744562 -223.702281) (xy 359.728514 -223.652888) (xy 359.720389 -223.601593)
			(xy 359.440206 -223.601593) (xy 359.432504 -223.651385) (xy 359.417097 -223.699901) (xy 359.394429 -223.74548)
			(xy 359.365038 -223.787043) (xy 359.329619 -223.823605) (xy 359.28901 -223.8543) (xy 359.244174 -223.878403)
			(xy 359.19617 -223.895342) (xy 359.17124 -223.900492) (xy 359.148126 -223.90481) (xy 358.944672 -224.257616)
			(xy 358.952292 -224.279714) (xy 358.961033 -224.306301) (xy 358.970478 -224.361461) (xy 358.971088 -224.389442)
			(xy 359.24998 -224.389442) (xy 359.250489 -224.363475) (xy 359.258614 -224.31218) (xy 359.274662 -224.262787)
			(xy 359.29824 -224.216513) (xy 359.328766 -224.174497) (xy 359.365489 -224.137774) (xy 359.407505 -224.107248)
			(xy 359.453779 -224.08367) (xy 359.503172 -224.067622) (xy 359.554467 -224.059497) (xy 359.606401 -224.059497)
			(xy 359.657696 -224.067622) (xy 359.707089 -224.08367) (xy 359.753363 -224.107248) (xy 359.795379 -224.137774)
			(xy 359.832102 -224.174497) (xy 359.862628 -224.216513) (xy 359.886206 -224.262787) (xy 359.902254 -224.31218)
			(xy 359.910379 -224.363475) (xy 359.910888 -224.389442) (xy 360.18978 -224.389442) (xy 360.190187 -224.363988)
			(xy 360.197974 -224.31368) (xy 360.213387 -224.265161) (xy 360.23606 -224.219581) (xy 360.265456 -224.178019)
			(xy 360.30088 -224.141457) (xy 360.341493 -224.110763) (xy 360.386334 -224.086661) (xy 360.434342 -224.069724)
			(xy 360.459274 -224.064576) (xy 360.482134 -224.060258) (xy 360.685842 -223.707198) (xy 360.678222 -223.685354)
			(xy 360.669498 -223.658762) (xy 360.660041 -223.603606) (xy 360.659426 -223.575626) (xy 360.659935 -223.549659)
			(xy 360.66806 -223.498364) (xy 360.684108 -223.448971) (xy 360.707686 -223.402697) (xy 360.738212 -223.360681)
			(xy 360.774935 -223.323958) (xy 360.816951 -223.293432) (xy 360.863225 -223.269854) (xy 360.912618 -223.253806)
			(xy 360.963913 -223.245681) (xy 361.015847 -223.245681) (xy 361.067142 -223.253806) (xy 361.116535 -223.269854)
			(xy 361.162809 -223.293432) (xy 361.204825 -223.323958) (xy 361.241548 -223.360681) (xy 361.272074 -223.402697)
			(xy 361.295652 -223.448971) (xy 361.3117 -223.498364) (xy 361.319825 -223.549659) (xy 361.320334 -223.575626)
			(xy 361.319886 -223.601078) (xy 361.319806 -223.601593) (xy 361.599989 -223.601593) (xy 361.599989 -223.549659)
			(xy 361.608114 -223.498364) (xy 361.624162 -223.448971) (xy 361.64774 -223.402697) (xy 361.678266 -223.360681)
			(xy 361.714989 -223.323958) (xy 361.757005 -223.293432) (xy 361.803279 -223.269854) (xy 361.852672 -223.253806)
			(xy 361.903967 -223.245681) (xy 361.955901 -223.245681) (xy 362.007196 -223.253806) (xy 362.056589 -223.269854)
			(xy 362.102863 -223.293432) (xy 362.144879 -223.323958) (xy 362.181602 -223.360681) (xy 362.212128 -223.402697)
			(xy 362.235706 -223.448971) (xy 362.251754 -223.498364) (xy 362.259879 -223.549659) (xy 362.260388 -223.575626)
			(xy 362.259879 -223.601593) (xy 362.251754 -223.652888) (xy 362.235706 -223.702281) (xy 362.212128 -223.748555)
			(xy 362.181602 -223.790571) (xy 362.144879 -223.827294) (xy 362.102863 -223.85782) (xy 362.056589 -223.881398)
			(xy 362.007196 -223.897446) (xy 361.955901 -223.905571) (xy 361.903967 -223.905571) (xy 361.852672 -223.897446)
			(xy 361.803279 -223.881398) (xy 361.757005 -223.85782) (xy 361.714989 -223.827294) (xy 361.678266 -223.790571)
			(xy 361.64774 -223.748555) (xy 361.624162 -223.702281) (xy 361.608114 -223.652888) (xy 361.599989 -223.601593)
			(xy 361.319806 -223.601593) (xy 361.312104 -223.651385) (xy 361.296697 -223.699901) (xy 361.274029 -223.74548)
			(xy 361.244638 -223.787043) (xy 361.209219 -223.823605) (xy 361.16861 -223.8543) (xy 361.123774 -223.878403)
			(xy 361.07577 -223.895342) (xy 361.05084 -223.900492) (xy 361.027726 -223.90481) (xy 360.824272 -224.257616)
			(xy 360.831892 -224.279714) (xy 360.840633 -224.306301) (xy 360.850078 -224.361461) (xy 360.850688 -224.389442)
			(xy 361.12958 -224.389442) (xy 361.130089 -224.363475) (xy 361.138214 -224.31218) (xy 361.154262 -224.262787)
			(xy 361.17784 -224.216513) (xy 361.208366 -224.174497) (xy 361.245089 -224.137774) (xy 361.287105 -224.107248)
			(xy 361.333379 -224.08367) (xy 361.382772 -224.067622) (xy 361.434067 -224.059497) (xy 361.486001 -224.059497)
			(xy 361.537296 -224.067622) (xy 361.586689 -224.08367) (xy 361.632963 -224.107248) (xy 361.674979 -224.137774)
			(xy 361.711702 -224.174497) (xy 361.742228 -224.216513) (xy 361.765806 -224.262787) (xy 361.781854 -224.31218)
			(xy 361.789979 -224.363475) (xy 361.790488 -224.389442) (xy 362.06938 -224.389442) (xy 362.069787 -224.363988)
			(xy 362.077574 -224.31368) (xy 362.092987 -224.265161) (xy 362.11566 -224.219581) (xy 362.145056 -224.178019)
			(xy 362.18048 -224.141457) (xy 362.221093 -224.110763) (xy 362.265934 -224.086661) (xy 362.313942 -224.069724)
			(xy 362.338874 -224.064576) (xy 362.361734 -224.060258) (xy 362.565696 -223.706944) (xy 362.557822 -223.6851)
			(xy 362.549162 -223.658564) (xy 362.539841 -223.603534) (xy 362.53928 -223.575626) (xy 362.539789 -223.549659)
			(xy 362.547914 -223.498364) (xy 362.563962 -223.448971) (xy 362.58754 -223.402697) (xy 362.618066 -223.360681)
			(xy 362.654789 -223.323958) (xy 362.696805 -223.293432) (xy 362.743079 -223.269854) (xy 362.792472 -223.253806)
			(xy 362.843767 -223.245681) (xy 362.895701 -223.245681) (xy 362.946996 -223.253806) (xy 362.996389 -223.269854)
			(xy 363.042663 -223.293432) (xy 363.084679 -223.323958) (xy 363.121402 -223.360681) (xy 363.151928 -223.402697)
			(xy 363.175506 -223.448971) (xy 363.191554 -223.498364) (xy 363.199679 -223.549659) (xy 363.200188 -223.575626)
			(xy 363.19974 -223.60109) (xy 363.199662 -223.601593) (xy 363.479589 -223.601593) (xy 363.479589 -223.549659)
			(xy 363.487714 -223.498364) (xy 363.503762 -223.448971) (xy 363.52734 -223.402697) (xy 363.557866 -223.360681)
			(xy 363.594589 -223.323958) (xy 363.636605 -223.293432) (xy 363.682879 -223.269854) (xy 363.732272 -223.253806)
			(xy 363.783567 -223.245681) (xy 363.835501 -223.245681) (xy 363.886796 -223.253806) (xy 363.936189 -223.269854)
			(xy 363.982463 -223.293432) (xy 364.024479 -223.323958) (xy 364.061202 -223.360681) (xy 364.091728 -223.402697)
			(xy 364.115306 -223.448971) (xy 364.131354 -223.498364) (xy 364.139479 -223.549659) (xy 364.139988 -223.575626)
			(xy 364.139479 -223.601593) (xy 364.131354 -223.652888) (xy 364.115306 -223.702281) (xy 364.091728 -223.748555)
			(xy 364.061202 -223.790571) (xy 364.024479 -223.827294) (xy 363.982463 -223.85782) (xy 363.936189 -223.881398)
			(xy 363.886796 -223.897446) (xy 363.835501 -223.905571) (xy 363.783567 -223.905571) (xy 363.732272 -223.897446)
			(xy 363.682879 -223.881398) (xy 363.636605 -223.85782) (xy 363.594589 -223.827294) (xy 363.557866 -223.790571)
			(xy 363.52734 -223.748555) (xy 363.503762 -223.702281) (xy 363.487714 -223.652888) (xy 363.479589 -223.601593)
			(xy 363.199662 -223.601593) (xy 363.191937 -223.651415) (xy 363.176504 -223.699947) (xy 363.153808 -223.745537)
			(xy 363.124385 -223.787104) (xy 363.088932 -223.823664) (xy 363.048289 -223.854351) (xy 363.003419 -223.878439)
			(xy 362.955385 -223.895356) (xy 362.93044 -223.900492) (xy 362.907326 -223.90481) (xy 362.703872 -224.257616)
			(xy 362.711492 -224.279714) (xy 362.720233 -224.306301) (xy 362.729678 -224.361461) (xy 362.730288 -224.389442)
			(xy 363.00918 -224.389442) (xy 363.009689 -224.363475) (xy 363.017814 -224.31218) (xy 363.033862 -224.262787)
			(xy 363.05744 -224.216513) (xy 363.087966 -224.174497) (xy 363.124689 -224.137774) (xy 363.166705 -224.107248)
			(xy 363.212979 -224.08367) (xy 363.262372 -224.067622) (xy 363.313667 -224.059497) (xy 363.365601 -224.059497)
			(xy 363.416896 -224.067622) (xy 363.466289 -224.08367) (xy 363.512563 -224.107248) (xy 363.554579 -224.137774)
			(xy 363.591302 -224.174497) (xy 363.621828 -224.216513) (xy 363.645406 -224.262787) (xy 363.661454 -224.31218)
			(xy 363.669579 -224.363475) (xy 363.670088 -224.389442) (xy 363.94898 -224.389442) (xy 363.949387 -224.363988)
			(xy 363.957174 -224.31368) (xy 363.972587 -224.265161) (xy 363.99526 -224.219581) (xy 364.024656 -224.178019)
			(xy 364.06008 -224.141457) (xy 364.100693 -224.110763) (xy 364.145534 -224.086661) (xy 364.193542 -224.069724)
			(xy 364.218474 -224.064576) (xy 364.241334 -224.060258) (xy 364.445042 -223.707198) (xy 364.437422 -223.685354)
			(xy 364.428698 -223.658762) (xy 364.419241 -223.603606) (xy 364.418626 -223.575626) (xy 364.419135 -223.549659)
			(xy 364.42726 -223.498364) (xy 364.443308 -223.448971) (xy 364.466886 -223.402697) (xy 364.497412 -223.360681)
			(xy 364.534135 -223.323958) (xy 364.576151 -223.293432) (xy 364.622425 -223.269854) (xy 364.671818 -223.253806)
			(xy 364.723113 -223.245681) (xy 364.775047 -223.245681) (xy 364.826342 -223.253806) (xy 364.875735 -223.269854)
			(xy 364.922009 -223.293432) (xy 364.964025 -223.323958) (xy 365.000748 -223.360681) (xy 365.031274 -223.402697)
			(xy 365.054852 -223.448971) (xy 365.0709 -223.498364) (xy 365.079025 -223.549659) (xy 365.079534 -223.575626)
			(xy 365.079086 -223.601078) (xy 365.079006 -223.601593) (xy 365.359189 -223.601593) (xy 365.359189 -223.549659)
			(xy 365.367314 -223.498364) (xy 365.383362 -223.448971) (xy 365.40694 -223.402697) (xy 365.437466 -223.360681)
			(xy 365.474189 -223.323958) (xy 365.516205 -223.293432) (xy 365.562479 -223.269854) (xy 365.611872 -223.253806)
			(xy 365.663167 -223.245681) (xy 365.715101 -223.245681) (xy 365.766396 -223.253806) (xy 365.815789 -223.269854)
			(xy 365.862063 -223.293432) (xy 365.904079 -223.323958) (xy 365.940802 -223.360681) (xy 365.971328 -223.402697)
			(xy 365.994906 -223.448971) (xy 366.010954 -223.498364) (xy 366.019079 -223.549659) (xy 366.019588 -223.575626)
			(xy 366.019079 -223.601593) (xy 366.010954 -223.652888) (xy 365.994906 -223.702281) (xy 365.971328 -223.748555)
			(xy 365.940802 -223.790571) (xy 365.904079 -223.827294) (xy 365.862063 -223.85782) (xy 365.815789 -223.881398)
			(xy 365.766396 -223.897446) (xy 365.715101 -223.905571) (xy 365.663167 -223.905571) (xy 365.611872 -223.897446)
			(xy 365.562479 -223.881398) (xy 365.516205 -223.85782) (xy 365.474189 -223.827294) (xy 365.437466 -223.790571)
			(xy 365.40694 -223.748555) (xy 365.383362 -223.702281) (xy 365.367314 -223.652888) (xy 365.359189 -223.601593)
			(xy 365.079006 -223.601593) (xy 365.071304 -223.651385) (xy 365.055897 -223.699901) (xy 365.033229 -223.74548)
			(xy 365.003838 -223.787043) (xy 364.968419 -223.823605) (xy 364.92781 -223.8543) (xy 364.882974 -223.878403)
			(xy 364.83497 -223.895342) (xy 364.81004 -223.900492) (xy 364.786926 -223.90481) (xy 364.583472 -224.257616)
			(xy 364.591092 -224.279714) (xy 364.599833 -224.306301) (xy 364.609278 -224.361461) (xy 364.609888 -224.389442)
			(xy 364.88878 -224.389442) (xy 364.889289 -224.363475) (xy 364.897414 -224.31218) (xy 364.913462 -224.262787)
			(xy 364.93704 -224.216513) (xy 364.967566 -224.174497) (xy 365.004289 -224.137774) (xy 365.046305 -224.107248)
			(xy 365.092579 -224.08367) (xy 365.141972 -224.067622) (xy 365.193267 -224.059497) (xy 365.245201 -224.059497)
			(xy 365.296496 -224.067622) (xy 365.345889 -224.08367) (xy 365.392163 -224.107248) (xy 365.434179 -224.137774)
			(xy 365.470902 -224.174497) (xy 365.501428 -224.216513) (xy 365.525006 -224.262787) (xy 365.541054 -224.31218)
			(xy 365.549179 -224.363475) (xy 365.549688 -224.389442) (xy 365.82858 -224.389442) (xy 365.828987 -224.363988)
			(xy 365.836774 -224.31368) (xy 365.852187 -224.265161) (xy 365.87486 -224.219581) (xy 365.904256 -224.178019)
			(xy 365.93968 -224.141457) (xy 365.980293 -224.110763) (xy 366.025134 -224.086661) (xy 366.073142 -224.069724)
			(xy 366.098074 -224.064576) (xy 366.120934 -224.060258) (xy 366.324642 -223.707198) (xy 366.317022 -223.685354)
			(xy 366.308298 -223.658762) (xy 366.298841 -223.603606) (xy 366.298226 -223.575626) (xy 366.298735 -223.549659)
			(xy 366.30686 -223.498364) (xy 366.322908 -223.448971) (xy 366.346486 -223.402697) (xy 366.377012 -223.360681)
			(xy 366.413735 -223.323958) (xy 366.455751 -223.293432) (xy 366.502025 -223.269854) (xy 366.551418 -223.253806)
			(xy 366.602713 -223.245681) (xy 366.654647 -223.245681) (xy 366.705942 -223.253806) (xy 366.755335 -223.269854)
			(xy 366.801609 -223.293432) (xy 366.843625 -223.323958) (xy 366.880348 -223.360681) (xy 366.910874 -223.402697)
			(xy 366.934452 -223.448971) (xy 366.9505 -223.498364) (xy 366.958625 -223.549659) (xy 366.959134 -223.575626)
			(xy 366.958686 -223.601078) (xy 366.958606 -223.601593) (xy 367.238789 -223.601593) (xy 367.238789 -223.549659)
			(xy 367.246914 -223.498364) (xy 367.262962 -223.448971) (xy 367.28654 -223.402697) (xy 367.317066 -223.360681)
			(xy 367.353789 -223.323958) (xy 367.395805 -223.293432) (xy 367.442079 -223.269854) (xy 367.491472 -223.253806)
			(xy 367.542767 -223.245681) (xy 367.594701 -223.245681) (xy 367.645996 -223.253806) (xy 367.695389 -223.269854)
			(xy 367.741663 -223.293432) (xy 367.783679 -223.323958) (xy 367.820402 -223.360681) (xy 367.850928 -223.402697)
			(xy 367.874506 -223.448971) (xy 367.890554 -223.498364) (xy 367.898679 -223.549659) (xy 367.899188 -223.575626)
			(xy 367.898679 -223.601593) (xy 367.890554 -223.652888) (xy 367.874506 -223.702281) (xy 367.850928 -223.748555)
			(xy 367.820402 -223.790571) (xy 367.783679 -223.827294) (xy 367.741663 -223.85782) (xy 367.695389 -223.881398)
			(xy 367.645996 -223.897446) (xy 367.594701 -223.905571) (xy 367.542767 -223.905571) (xy 367.491472 -223.897446)
			(xy 367.442079 -223.881398) (xy 367.395805 -223.85782) (xy 367.353789 -223.827294) (xy 367.317066 -223.790571)
			(xy 367.28654 -223.748555) (xy 367.262962 -223.702281) (xy 367.246914 -223.652888) (xy 367.238789 -223.601593)
			(xy 366.958606 -223.601593) (xy 366.950904 -223.651385) (xy 366.935497 -223.699901) (xy 366.912829 -223.74548)
			(xy 366.883438 -223.787043) (xy 366.848019 -223.823605) (xy 366.80741 -223.8543) (xy 366.762574 -223.878403)
			(xy 366.71457 -223.895342) (xy 366.68964 -223.900492) (xy 366.666526 -223.90481) (xy 366.463072 -224.257616)
			(xy 366.470692 -224.279714) (xy 366.479433 -224.306301) (xy 366.488878 -224.361461) (xy 366.489488 -224.389442)
			(xy 366.76838 -224.389442) (xy 366.768889 -224.363475) (xy 366.777014 -224.31218) (xy 366.793062 -224.262787)
			(xy 366.81664 -224.216513) (xy 366.847166 -224.174497) (xy 366.883889 -224.137774) (xy 366.925905 -224.107248)
			(xy 366.972179 -224.08367) (xy 367.021572 -224.067622) (xy 367.072867 -224.059497) (xy 367.124801 -224.059497)
			(xy 367.176096 -224.067622) (xy 367.225489 -224.08367) (xy 367.271763 -224.107248) (xy 367.313779 -224.137774)
			(xy 367.350502 -224.174497) (xy 367.381028 -224.216513) (xy 367.404606 -224.262787) (xy 367.420654 -224.31218)
			(xy 367.428779 -224.363475) (xy 367.429288 -224.389442) (xy 367.70818 -224.389442) (xy 367.708587 -224.363988)
			(xy 367.716374 -224.31368) (xy 367.731787 -224.265161) (xy 367.75446 -224.219581) (xy 367.783856 -224.178019)
			(xy 367.81928 -224.141457) (xy 367.859893 -224.110763) (xy 367.904734 -224.086661) (xy 367.952742 -224.069724)
			(xy 367.977674 -224.064576) (xy 368.000534 -224.060258) (xy 368.204242 -223.707198) (xy 368.196622 -223.685354)
			(xy 368.187898 -223.658762) (xy 368.178441 -223.603606) (xy 368.177826 -223.575626) (xy 368.178335 -223.549659)
			(xy 368.18646 -223.498364) (xy 368.202508 -223.448971) (xy 368.226086 -223.402697) (xy 368.256612 -223.360681)
			(xy 368.293335 -223.323958) (xy 368.335351 -223.293432) (xy 368.381625 -223.269854) (xy 368.431018 -223.253806)
			(xy 368.482313 -223.245681) (xy 368.534247 -223.245681) (xy 368.585542 -223.253806) (xy 368.634935 -223.269854)
			(xy 368.681209 -223.293432) (xy 368.723225 -223.323958) (xy 368.759948 -223.360681) (xy 368.790474 -223.402697)
			(xy 368.814052 -223.448971) (xy 368.8301 -223.498364) (xy 368.838225 -223.549659) (xy 368.838734 -223.575626)
			(xy 368.838286 -223.601078) (xy 368.838206 -223.601593) (xy 369.118389 -223.601593) (xy 369.118389 -223.549659)
			(xy 369.126514 -223.498364) (xy 369.142562 -223.448971) (xy 369.16614 -223.402697) (xy 369.196666 -223.360681)
			(xy 369.233389 -223.323958) (xy 369.275405 -223.293432) (xy 369.321679 -223.269854) (xy 369.371072 -223.253806)
			(xy 369.422367 -223.245681) (xy 369.474301 -223.245681) (xy 369.525596 -223.253806) (xy 369.574989 -223.269854)
			(xy 369.621263 -223.293432) (xy 369.663279 -223.323958) (xy 369.700002 -223.360681) (xy 369.730528 -223.402697)
			(xy 369.754106 -223.448971) (xy 369.770154 -223.498364) (xy 369.778279 -223.549659) (xy 369.778788 -223.575626)
			(xy 369.778279 -223.601593) (xy 369.770154 -223.652888) (xy 369.754106 -223.702281) (xy 369.730528 -223.748555)
			(xy 369.700002 -223.790571) (xy 369.663279 -223.827294) (xy 369.621263 -223.85782) (xy 369.574989 -223.881398)
			(xy 369.525596 -223.897446) (xy 369.474301 -223.905571) (xy 369.422367 -223.905571) (xy 369.371072 -223.897446)
			(xy 369.321679 -223.881398) (xy 369.275405 -223.85782) (xy 369.233389 -223.827294) (xy 369.196666 -223.790571)
			(xy 369.16614 -223.748555) (xy 369.142562 -223.702281) (xy 369.126514 -223.652888) (xy 369.118389 -223.601593)
			(xy 368.838206 -223.601593) (xy 368.830504 -223.651385) (xy 368.815097 -223.699901) (xy 368.792429 -223.74548)
			(xy 368.763038 -223.787043) (xy 368.727619 -223.823605) (xy 368.68701 -223.8543) (xy 368.642174 -223.878403)
			(xy 368.59417 -223.895342) (xy 368.56924 -223.900492) (xy 368.546126 -223.90481) (xy 368.342672 -224.257616)
			(xy 368.350292 -224.279714) (xy 368.359033 -224.306301) (xy 368.368478 -224.361461) (xy 368.369088 -224.389442)
			(xy 368.64798 -224.389442) (xy 368.648489 -224.363475) (xy 368.656614 -224.31218) (xy 368.672662 -224.262787)
			(xy 368.69624 -224.216513) (xy 368.726766 -224.174497) (xy 368.763489 -224.137774) (xy 368.805505 -224.107248)
			(xy 368.851779 -224.08367) (xy 368.901172 -224.067622) (xy 368.952467 -224.059497) (xy 369.004401 -224.059497)
			(xy 369.055696 -224.067622) (xy 369.105089 -224.08367) (xy 369.151363 -224.107248) (xy 369.193379 -224.137774)
			(xy 369.230102 -224.174497) (xy 369.260628 -224.216513) (xy 369.284206 -224.262787) (xy 369.300254 -224.31218)
			(xy 369.308379 -224.363475) (xy 369.308888 -224.389442) (xy 369.58778 -224.389442) (xy 369.588187 -224.363988)
			(xy 369.595974 -224.31368) (xy 369.611387 -224.265161) (xy 369.63406 -224.219581) (xy 369.663456 -224.178019)
			(xy 369.69888 -224.141457) (xy 369.739493 -224.110763) (xy 369.784334 -224.086661) (xy 369.832342 -224.069724)
			(xy 369.857274 -224.064576) (xy 369.880134 -224.060258) (xy 370.083842 -223.707198) (xy 370.076222 -223.685354)
			(xy 370.067498 -223.658762) (xy 370.058041 -223.603606) (xy 370.057426 -223.575626) (xy 370.057935 -223.549659)
			(xy 370.06606 -223.498364) (xy 370.082108 -223.448971) (xy 370.105686 -223.402697) (xy 370.136212 -223.360681)
			(xy 370.172935 -223.323958) (xy 370.214951 -223.293432) (xy 370.261225 -223.269854) (xy 370.310618 -223.253806)
			(xy 370.361913 -223.245681) (xy 370.413847 -223.245681) (xy 370.465142 -223.253806) (xy 370.514535 -223.269854)
			(xy 370.560809 -223.293432) (xy 370.602825 -223.323958) (xy 370.639548 -223.360681) (xy 370.670074 -223.402697)
			(xy 370.693652 -223.448971) (xy 370.7097 -223.498364) (xy 370.717825 -223.549659) (xy 370.718334 -223.575626)
			(xy 370.717886 -223.601078) (xy 370.717806 -223.601593) (xy 370.997989 -223.601593) (xy 370.997989 -223.549659)
			(xy 371.006114 -223.498364) (xy 371.022162 -223.448971) (xy 371.04574 -223.402697) (xy 371.076266 -223.360681)
			(xy 371.112989 -223.323958) (xy 371.155005 -223.293432) (xy 371.201279 -223.269854) (xy 371.250672 -223.253806)
			(xy 371.301967 -223.245681) (xy 371.353901 -223.245681) (xy 371.405196 -223.253806) (xy 371.454589 -223.269854)
			(xy 371.500863 -223.293432) (xy 371.542879 -223.323958) (xy 371.579602 -223.360681) (xy 371.610128 -223.402697)
			(xy 371.633706 -223.448971) (xy 371.649754 -223.498364) (xy 371.657879 -223.549659) (xy 371.658388 -223.575626)
			(xy 371.657879 -223.601593) (xy 371.649754 -223.652888) (xy 371.633706 -223.702281) (xy 371.610128 -223.748555)
			(xy 371.579602 -223.790571) (xy 371.542879 -223.827294) (xy 371.500863 -223.85782) (xy 371.454589 -223.881398)
			(xy 371.405196 -223.897446) (xy 371.353901 -223.905571) (xy 371.301967 -223.905571) (xy 371.250672 -223.897446)
			(xy 371.201279 -223.881398) (xy 371.155005 -223.85782) (xy 371.112989 -223.827294) (xy 371.076266 -223.790571)
			(xy 371.04574 -223.748555) (xy 371.022162 -223.702281) (xy 371.006114 -223.652888) (xy 370.997989 -223.601593)
			(xy 370.717806 -223.601593) (xy 370.710104 -223.651385) (xy 370.694697 -223.699901) (xy 370.672029 -223.74548)
			(xy 370.642638 -223.787043) (xy 370.607219 -223.823605) (xy 370.56661 -223.8543) (xy 370.521774 -223.878403)
			(xy 370.47377 -223.895342) (xy 370.44884 -223.900492) (xy 370.425726 -223.90481) (xy 370.222272 -224.257616)
			(xy 370.229892 -224.279714) (xy 370.238633 -224.306301) (xy 370.248078 -224.361461) (xy 370.248688 -224.389442)
			(xy 370.52758 -224.389442) (xy 370.528089 -224.363475) (xy 370.536214 -224.31218) (xy 370.552262 -224.262787)
			(xy 370.57584 -224.216513) (xy 370.606366 -224.174497) (xy 370.643089 -224.137774) (xy 370.685105 -224.107248)
			(xy 370.731379 -224.08367) (xy 370.780772 -224.067622) (xy 370.832067 -224.059497) (xy 370.884001 -224.059497)
			(xy 370.935296 -224.067622) (xy 370.984689 -224.08367) (xy 371.030963 -224.107248) (xy 371.072979 -224.137774)
			(xy 371.109702 -224.174497) (xy 371.140228 -224.216513) (xy 371.163806 -224.262787) (xy 371.179854 -224.31218)
			(xy 371.187979 -224.363475) (xy 371.188488 -224.389442) (xy 371.187946 -224.417428) (xy 371.178489 -224.472596)
			(xy 371.169692 -224.49917) (xy 371.162072 -224.521268) (xy 371.36578 -224.874074) (xy 371.38864 -224.878392)
			(xy 371.413567 -224.883535) (xy 371.461553 -224.900502) (xy 371.506372 -224.924622) (xy 371.546966 -224.955325)
			(xy 371.582375 -224.991886) (xy 371.611762 -225.033442) (xy 371.634435 -225.07901) (xy 371.649856 -225.127515)
			(xy 371.657662 -225.17781) (xy 371.658134 -225.203258) (xy 371.657625 -225.229225) (xy 371.6495 -225.28052)
			(xy 371.633452 -225.329913) (xy 371.609874 -225.376187) (xy 371.579348 -225.418203) (xy 371.542625 -225.454926)
			(xy 371.500609 -225.485452) (xy 371.454335 -225.50903) (xy 371.404942 -225.525078) (xy 371.353647 -225.533203)
			(xy 371.301713 -225.533203) (xy 371.250418 -225.525078) (xy 371.201025 -225.50903) (xy 371.154751 -225.485452)
			(xy 371.112735 -225.454926) (xy 371.076012 -225.418203) (xy 371.045486 -225.376187) (xy 371.021908 -225.329913)
			(xy 371.00586 -225.28052) (xy 370.997735 -225.229225) (xy 370.997226 -225.203258) (xy 370.997767 -225.175272)
			(xy 371.007225 -225.120104) (xy 371.016022 -225.09353) (xy 371.023642 -225.071432) (xy 370.819934 -224.718626)
			(xy 370.797074 -224.714308) (xy 370.772149 -224.709155) (xy 370.724163 -224.69219) (xy 370.679344 -224.668072)
			(xy 370.63875 -224.63737) (xy 370.60334 -224.60081) (xy 370.573952 -224.559256) (xy 370.55128 -224.513688)
			(xy 370.535858 -224.465184) (xy 370.528052 -224.41489) (xy 370.52758 -224.389442) (xy 370.248688 -224.389442)
			(xy 370.248179 -224.415409) (xy 370.240054 -224.466704) (xy 370.224006 -224.516097) (xy 370.200428 -224.562371)
			(xy 370.169902 -224.604387) (xy 370.133179 -224.64111) (xy 370.091163 -224.671636) (xy 370.044889 -224.695214)
			(xy 369.995496 -224.711262) (xy 369.944201 -224.719387) (xy 369.892267 -224.719387) (xy 369.840972 -224.711262)
			(xy 369.791579 -224.695214) (xy 369.745305 -224.671636) (xy 369.703289 -224.64111) (xy 369.666566 -224.604387)
			(xy 369.63604 -224.562371) (xy 369.612462 -224.516097) (xy 369.596414 -224.466704) (xy 369.588289 -224.415409)
			(xy 369.58778 -224.389442) (xy 369.308888 -224.389442) (xy 369.308346 -224.417428) (xy 369.298889 -224.472596)
			(xy 369.290092 -224.49917) (xy 369.282472 -224.521268) (xy 369.48618 -224.874074) (xy 369.50904 -224.878392)
			(xy 369.533967 -224.883535) (xy 369.581953 -224.900502) (xy 369.626772 -224.924622) (xy 369.667366 -224.955325)
			(xy 369.702775 -224.991886) (xy 369.732162 -225.033442) (xy 369.754835 -225.07901) (xy 369.770256 -225.127515)
			(xy 369.778062 -225.17781) (xy 369.778534 -225.203258) (xy 369.778025 -225.229225) (xy 369.7699 -225.28052)
			(xy 369.753852 -225.329913) (xy 369.730274 -225.376187) (xy 369.699748 -225.418203) (xy 369.663025 -225.454926)
			(xy 369.621009 -225.485452) (xy 369.574735 -225.50903) (xy 369.525342 -225.525078) (xy 369.474047 -225.533203)
			(xy 369.422113 -225.533203) (xy 369.370818 -225.525078) (xy 369.321425 -225.50903) (xy 369.275151 -225.485452)
			(xy 369.233135 -225.454926) (xy 369.196412 -225.418203) (xy 369.165886 -225.376187) (xy 369.142308 -225.329913)
			(xy 369.12626 -225.28052) (xy 369.118135 -225.229225) (xy 369.117626 -225.203258) (xy 369.118167 -225.175272)
			(xy 369.127625 -225.120104) (xy 369.136422 -225.09353) (xy 369.144042 -225.071432) (xy 368.940334 -224.718626)
			(xy 368.917474 -224.714308) (xy 368.892549 -224.709155) (xy 368.844563 -224.69219) (xy 368.799744 -224.668072)
			(xy 368.75915 -224.63737) (xy 368.72374 -224.60081) (xy 368.694352 -224.559256) (xy 368.67168 -224.513688)
			(xy 368.656258 -224.465184) (xy 368.648452 -224.41489) (xy 368.64798 -224.389442) (xy 368.369088 -224.389442)
			(xy 368.368579 -224.415409) (xy 368.360454 -224.466704) (xy 368.344406 -224.516097) (xy 368.320828 -224.562371)
			(xy 368.290302 -224.604387) (xy 368.253579 -224.64111) (xy 368.211563 -224.671636) (xy 368.165289 -224.695214)
			(xy 368.115896 -224.711262) (xy 368.064601 -224.719387) (xy 368.012667 -224.719387) (xy 367.961372 -224.711262)
			(xy 367.911979 -224.695214) (xy 367.865705 -224.671636) (xy 367.823689 -224.64111) (xy 367.786966 -224.604387)
			(xy 367.75644 -224.562371) (xy 367.732862 -224.516097) (xy 367.716814 -224.466704) (xy 367.708689 -224.415409)
			(xy 367.70818 -224.389442) (xy 367.429288 -224.389442) (xy 367.428746 -224.417428) (xy 367.419289 -224.472596)
			(xy 367.410492 -224.49917) (xy 367.402872 -224.521268) (xy 367.60658 -224.874074) (xy 367.62944 -224.878392)
			(xy 367.654367 -224.883535) (xy 367.702353 -224.900502) (xy 367.747172 -224.924622) (xy 367.787766 -224.955325)
			(xy 367.823175 -224.991886) (xy 367.852562 -225.033442) (xy 367.875235 -225.07901) (xy 367.890656 -225.127515)
			(xy 367.898462 -225.17781) (xy 367.898934 -225.203258) (xy 367.898425 -225.229225) (xy 367.8903 -225.28052)
			(xy 367.874252 -225.329913) (xy 367.850674 -225.376187) (xy 367.820148 -225.418203) (xy 367.783425 -225.454926)
			(xy 367.741409 -225.485452) (xy 367.695135 -225.50903) (xy 367.645742 -225.525078) (xy 367.594447 -225.533203)
			(xy 367.542513 -225.533203) (xy 367.491218 -225.525078) (xy 367.441825 -225.50903) (xy 367.395551 -225.485452)
			(xy 367.353535 -225.454926) (xy 367.316812 -225.418203) (xy 367.286286 -225.376187) (xy 367.262708 -225.329913)
			(xy 367.24666 -225.28052) (xy 367.238535 -225.229225) (xy 367.238026 -225.203258) (xy 367.238567 -225.175272)
			(xy 367.248025 -225.120104) (xy 367.256822 -225.09353) (xy 367.264442 -225.071432) (xy 367.060734 -224.718626)
			(xy 367.037874 -224.714308) (xy 367.012949 -224.709155) (xy 366.964963 -224.69219) (xy 366.920144 -224.668072)
			(xy 366.87955 -224.63737) (xy 366.84414 -224.60081) (xy 366.814752 -224.559256) (xy 366.79208 -224.513688)
			(xy 366.776658 -224.465184) (xy 366.768852 -224.41489) (xy 366.76838 -224.389442) (xy 366.489488 -224.389442)
			(xy 366.488979 -224.415409) (xy 366.480854 -224.466704) (xy 366.464806 -224.516097) (xy 366.441228 -224.562371)
			(xy 366.410702 -224.604387) (xy 366.373979 -224.64111) (xy 366.331963 -224.671636) (xy 366.285689 -224.695214)
			(xy 366.236296 -224.711262) (xy 366.185001 -224.719387) (xy 366.133067 -224.719387) (xy 366.081772 -224.711262)
			(xy 366.032379 -224.695214) (xy 365.986105 -224.671636) (xy 365.944089 -224.64111) (xy 365.907366 -224.604387)
			(xy 365.87684 -224.562371) (xy 365.853262 -224.516097) (xy 365.837214 -224.466704) (xy 365.829089 -224.415409)
			(xy 365.82858 -224.389442) (xy 365.549688 -224.389442) (xy 365.549146 -224.417428) (xy 365.539689 -224.472596)
			(xy 365.530892 -224.49917) (xy 365.523272 -224.521268) (xy 365.72698 -224.874074) (xy 365.74984 -224.878392)
			(xy 365.774767 -224.883535) (xy 365.822753 -224.900502) (xy 365.867572 -224.924622) (xy 365.908166 -224.955325)
			(xy 365.943575 -224.991886) (xy 365.972962 -225.033442) (xy 365.995635 -225.07901) (xy 366.011056 -225.127515)
			(xy 366.018862 -225.17781) (xy 366.019334 -225.203258) (xy 366.018825 -225.229225) (xy 366.0107 -225.28052)
			(xy 365.994652 -225.329913) (xy 365.971074 -225.376187) (xy 365.940548 -225.418203) (xy 365.903825 -225.454926)
			(xy 365.861809 -225.485452) (xy 365.815535 -225.50903) (xy 365.766142 -225.525078) (xy 365.714847 -225.533203)
			(xy 365.662913 -225.533203) (xy 365.611618 -225.525078) (xy 365.562225 -225.50903) (xy 365.515951 -225.485452)
			(xy 365.473935 -225.454926) (xy 365.437212 -225.418203) (xy 365.406686 -225.376187) (xy 365.383108 -225.329913)
			(xy 365.36706 -225.28052) (xy 365.358935 -225.229225) (xy 365.358426 -225.203258) (xy 365.358967 -225.175272)
			(xy 365.368425 -225.120104) (xy 365.377222 -225.09353) (xy 365.384842 -225.071432) (xy 365.181134 -224.718626)
			(xy 365.158274 -224.714308) (xy 365.133349 -224.709155) (xy 365.085363 -224.69219) (xy 365.040544 -224.668072)
			(xy 364.99995 -224.63737) (xy 364.96454 -224.60081) (xy 364.935152 -224.559256) (xy 364.91248 -224.513688)
			(xy 364.897058 -224.465184) (xy 364.889252 -224.41489) (xy 364.88878 -224.389442) (xy 364.609888 -224.389442)
			(xy 364.609379 -224.415409) (xy 364.601254 -224.466704) (xy 364.585206 -224.516097) (xy 364.561628 -224.562371)
			(xy 364.531102 -224.604387) (xy 364.494379 -224.64111) (xy 364.452363 -224.671636) (xy 364.406089 -224.695214)
			(xy 364.356696 -224.711262) (xy 364.305401 -224.719387) (xy 364.253467 -224.719387) (xy 364.202172 -224.711262)
			(xy 364.152779 -224.695214) (xy 364.106505 -224.671636) (xy 364.064489 -224.64111) (xy 364.027766 -224.604387)
			(xy 363.99724 -224.562371) (xy 363.973662 -224.516097) (xy 363.957614 -224.466704) (xy 363.949489 -224.415409)
			(xy 363.94898 -224.389442) (xy 363.670088 -224.389442) (xy 363.669546 -224.417428) (xy 363.660089 -224.472596)
			(xy 363.651292 -224.49917) (xy 363.643672 -224.521268) (xy 363.84738 -224.874074) (xy 363.87024 -224.878392)
			(xy 363.895167 -224.883535) (xy 363.943153 -224.900502) (xy 363.987972 -224.924622) (xy 364.028566 -224.955325)
			(xy 364.063975 -224.991886) (xy 364.093362 -225.033442) (xy 364.116035 -225.07901) (xy 364.131456 -225.127515)
			(xy 364.139262 -225.17781) (xy 364.139734 -225.203258) (xy 364.139225 -225.229225) (xy 364.1311 -225.28052)
			(xy 364.115052 -225.329913) (xy 364.091474 -225.376187) (xy 364.060948 -225.418203) (xy 364.024225 -225.454926)
			(xy 363.982209 -225.485452) (xy 363.935935 -225.50903) (xy 363.886542 -225.525078) (xy 363.835247 -225.533203)
			(xy 363.783313 -225.533203) (xy 363.732018 -225.525078) (xy 363.682625 -225.50903) (xy 363.636351 -225.485452)
			(xy 363.594335 -225.454926) (xy 363.557612 -225.418203) (xy 363.527086 -225.376187) (xy 363.503508 -225.329913)
			(xy 363.48746 -225.28052) (xy 363.479335 -225.229225) (xy 363.478826 -225.203258) (xy 363.479367 -225.175272)
			(xy 363.488825 -225.120104) (xy 363.497622 -225.09353) (xy 363.505242 -225.071432) (xy 363.301534 -224.718626)
			(xy 363.278674 -224.714308) (xy 363.253749 -224.709155) (xy 363.205763 -224.69219) (xy 363.160944 -224.668072)
			(xy 363.12035 -224.63737) (xy 363.08494 -224.60081) (xy 363.055552 -224.559256) (xy 363.03288 -224.513688)
			(xy 363.017458 -224.465184) (xy 363.009652 -224.41489) (xy 363.00918 -224.389442) (xy 362.730288 -224.389442)
			(xy 362.729779 -224.415409) (xy 362.721654 -224.466704) (xy 362.705606 -224.516097) (xy 362.682028 -224.562371)
			(xy 362.651502 -224.604387) (xy 362.614779 -224.64111) (xy 362.572763 -224.671636) (xy 362.526489 -224.695214)
			(xy 362.477096 -224.711262) (xy 362.425801 -224.719387) (xy 362.373867 -224.719387) (xy 362.322572 -224.711262)
			(xy 362.273179 -224.695214) (xy 362.226905 -224.671636) (xy 362.184889 -224.64111) (xy 362.148166 -224.604387)
			(xy 362.11764 -224.562371) (xy 362.094062 -224.516097) (xy 362.078014 -224.466704) (xy 362.069889 -224.415409)
			(xy 362.06938 -224.389442) (xy 361.790488 -224.389442) (xy 361.789946 -224.417428) (xy 361.780489 -224.472596)
			(xy 361.771692 -224.49917) (xy 361.764072 -224.521268) (xy 361.96778 -224.874074) (xy 361.99064 -224.878392)
			(xy 362.015567 -224.883535) (xy 362.063553 -224.900502) (xy 362.108372 -224.924622) (xy 362.148966 -224.955325)
			(xy 362.184375 -224.991886) (xy 362.213762 -225.033442) (xy 362.236435 -225.07901) (xy 362.251856 -225.127515)
			(xy 362.259662 -225.17781) (xy 362.260134 -225.203258) (xy 362.259625 -225.229225) (xy 362.2515 -225.28052)
			(xy 362.235452 -225.329913) (xy 362.211874 -225.376187) (xy 362.181348 -225.418203) (xy 362.144625 -225.454926)
			(xy 362.102609 -225.485452) (xy 362.056335 -225.50903) (xy 362.006942 -225.525078) (xy 361.955647 -225.533203)
			(xy 361.903713 -225.533203) (xy 361.852418 -225.525078) (xy 361.803025 -225.50903) (xy 361.756751 -225.485452)
			(xy 361.714735 -225.454926) (xy 361.678012 -225.418203) (xy 361.647486 -225.376187) (xy 361.623908 -225.329913)
			(xy 361.60786 -225.28052) (xy 361.599735 -225.229225) (xy 361.599226 -225.203258) (xy 361.599767 -225.175272)
			(xy 361.609225 -225.120104) (xy 361.618022 -225.09353) (xy 361.625642 -225.071432) (xy 361.421934 -224.718626)
			(xy 361.399074 -224.714308) (xy 361.374149 -224.709155) (xy 361.326163 -224.69219) (xy 361.281344 -224.668072)
			(xy 361.24075 -224.63737) (xy 361.20534 -224.60081) (xy 361.175952 -224.559256) (xy 361.15328 -224.513688)
			(xy 361.137858 -224.465184) (xy 361.130052 -224.41489) (xy 361.12958 -224.389442) (xy 360.850688 -224.389442)
			(xy 360.850179 -224.415409) (xy 360.842054 -224.466704) (xy 360.826006 -224.516097) (xy 360.802428 -224.562371)
			(xy 360.771902 -224.604387) (xy 360.735179 -224.64111) (xy 360.693163 -224.671636) (xy 360.646889 -224.695214)
			(xy 360.597496 -224.711262) (xy 360.546201 -224.719387) (xy 360.494267 -224.719387) (xy 360.442972 -224.711262)
			(xy 360.393579 -224.695214) (xy 360.347305 -224.671636) (xy 360.305289 -224.64111) (xy 360.268566 -224.604387)
			(xy 360.23804 -224.562371) (xy 360.214462 -224.516097) (xy 360.198414 -224.466704) (xy 360.190289 -224.415409)
			(xy 360.18978 -224.389442) (xy 359.910888 -224.389442) (xy 359.910346 -224.417428) (xy 359.900889 -224.472596)
			(xy 359.892092 -224.49917) (xy 359.884472 -224.521268) (xy 360.08818 -224.874074) (xy 360.11104 -224.878392)
			(xy 360.135967 -224.883535) (xy 360.183953 -224.900502) (xy 360.228772 -224.924622) (xy 360.269366 -224.955325)
			(xy 360.304775 -224.991886) (xy 360.334162 -225.033442) (xy 360.356835 -225.07901) (xy 360.372256 -225.127515)
			(xy 360.380062 -225.17781) (xy 360.380534 -225.203258) (xy 360.380025 -225.229225) (xy 360.3719 -225.28052)
			(xy 360.355852 -225.329913) (xy 360.332274 -225.376187) (xy 360.301748 -225.418203) (xy 360.265025 -225.454926)
			(xy 360.223009 -225.485452) (xy 360.176735 -225.50903) (xy 360.127342 -225.525078) (xy 360.076047 -225.533203)
			(xy 360.024113 -225.533203) (xy 359.972818 -225.525078) (xy 359.923425 -225.50903) (xy 359.877151 -225.485452)
			(xy 359.835135 -225.454926) (xy 359.798412 -225.418203) (xy 359.767886 -225.376187) (xy 359.744308 -225.329913)
			(xy 359.72826 -225.28052) (xy 359.720135 -225.229225) (xy 359.719626 -225.203258) (xy 359.720167 -225.175272)
			(xy 359.729625 -225.120104) (xy 359.738422 -225.09353) (xy 359.746042 -225.071432) (xy 359.542334 -224.718626)
			(xy 359.519474 -224.714308) (xy 359.494549 -224.709155) (xy 359.446563 -224.69219) (xy 359.401744 -224.668072)
			(xy 359.36115 -224.63737) (xy 359.32574 -224.60081) (xy 359.296352 -224.559256) (xy 359.27368 -224.513688)
			(xy 359.258258 -224.465184) (xy 359.250452 -224.41489) (xy 359.24998 -224.389442) (xy 358.971088 -224.389442)
			(xy 358.970579 -224.415409) (xy 358.962454 -224.466704) (xy 358.946406 -224.516097) (xy 358.922828 -224.562371)
			(xy 358.892302 -224.604387) (xy 358.855579 -224.64111) (xy 358.813563 -224.671636) (xy 358.767289 -224.695214)
			(xy 358.717896 -224.711262) (xy 358.666601 -224.719387) (xy 358.614667 -224.719387) (xy 358.563372 -224.711262)
			(xy 358.513979 -224.695214) (xy 358.467705 -224.671636) (xy 358.425689 -224.64111) (xy 358.388966 -224.604387)
			(xy 358.35844 -224.562371) (xy 358.334862 -224.516097) (xy 358.318814 -224.466704) (xy 358.310689 -224.415409)
			(xy 358.31018 -224.389442) (xy 358.031288 -224.389442) (xy 358.030746 -224.417428) (xy 358.021289 -224.472596)
			(xy 358.012492 -224.49917) (xy 358.004872 -224.521268) (xy 358.20858 -224.874074) (xy 358.23144 -224.878392)
			(xy 358.256367 -224.883535) (xy 358.304353 -224.900502) (xy 358.349172 -224.924622) (xy 358.389766 -224.955325)
			(xy 358.425175 -224.991886) (xy 358.454562 -225.033442) (xy 358.477235 -225.07901) (xy 358.492656 -225.127515)
			(xy 358.500462 -225.17781) (xy 358.500934 -225.203258) (xy 358.500425 -225.229225) (xy 358.780335 -225.229225)
			(xy 358.780335 -225.177291) (xy 358.78846 -225.125996) (xy 358.804508 -225.076603) (xy 358.828086 -225.030329)
			(xy 358.858612 -224.988313) (xy 358.895335 -224.95159) (xy 358.937351 -224.921064) (xy 358.983625 -224.897486)
			(xy 359.033018 -224.881438) (xy 359.084313 -224.873313) (xy 359.136247 -224.873313) (xy 359.187542 -224.881438)
			(xy 359.236935 -224.897486) (xy 359.283209 -224.921064) (xy 359.325225 -224.95159) (xy 359.361948 -224.988313)
			(xy 359.392474 -225.030329) (xy 359.416052 -225.076603) (xy 359.4321 -225.125996) (xy 359.440225 -225.177291)
			(xy 359.440734 -225.203258) (xy 359.440225 -225.229225) (xy 359.4321 -225.28052) (xy 359.416052 -225.329913)
			(xy 359.392474 -225.376187) (xy 359.361948 -225.418203) (xy 359.325225 -225.454926) (xy 359.283209 -225.485452)
			(xy 359.236935 -225.50903) (xy 359.187542 -225.525078) (xy 359.136247 -225.533203) (xy 359.084313 -225.533203)
			(xy 359.033018 -225.525078) (xy 358.983625 -225.50903) (xy 358.937351 -225.485452) (xy 358.895335 -225.454926)
			(xy 358.858612 -225.418203) (xy 358.828086 -225.376187) (xy 358.804508 -225.329913) (xy 358.78846 -225.28052)
			(xy 358.780335 -225.229225) (xy 358.500425 -225.229225) (xy 358.4923 -225.28052) (xy 358.476252 -225.329913)
			(xy 358.452674 -225.376187) (xy 358.422148 -225.418203) (xy 358.385425 -225.454926) (xy 358.343409 -225.485452)
			(xy 358.297135 -225.50903) (xy 358.247742 -225.525078) (xy 358.196447 -225.533203) (xy 358.144513 -225.533203)
			(xy 358.093218 -225.525078) (xy 358.043825 -225.50903) (xy 357.997551 -225.485452) (xy 357.955535 -225.454926)
			(xy 357.918812 -225.418203) (xy 357.888286 -225.376187) (xy 357.864708 -225.329913) (xy 357.84866 -225.28052)
			(xy 357.840535 -225.229225) (xy 357.840026 -225.203258) (xy 357.840567 -225.175272) (xy 357.850025 -225.120104)
			(xy 357.858822 -225.09353) (xy 357.866442 -225.071432) (xy 357.662734 -224.718626) (xy 357.639874 -224.714308)
			(xy 357.614949 -224.709155) (xy 357.566963 -224.69219) (xy 357.522144 -224.668072) (xy 357.48155 -224.63737)
			(xy 357.44614 -224.60081) (xy 357.416752 -224.559256) (xy 357.39408 -224.513688) (xy 357.378658 -224.465184)
			(xy 357.370852 -224.41489) (xy 357.37038 -224.389442) (xy 357.091488 -224.389442) (xy 357.090979 -224.415409)
			(xy 357.082854 -224.466704) (xy 357.066806 -224.516097) (xy 357.043228 -224.562371) (xy 357.012702 -224.604387)
			(xy 356.975979 -224.64111) (xy 356.933963 -224.671636) (xy 356.887689 -224.695214) (xy 356.838296 -224.711262)
			(xy 356.787001 -224.719387) (xy 356.735067 -224.719387) (xy 356.683772 -224.711262) (xy 356.634379 -224.695214)
			(xy 356.588105 -224.671636) (xy 356.546089 -224.64111) (xy 356.509366 -224.604387) (xy 356.47884 -224.562371)
			(xy 356.455262 -224.516097) (xy 356.439214 -224.466704) (xy 356.431089 -224.415409) (xy 356.43058 -224.389442)
			(xy 356.151688 -224.389442) (xy 356.151146 -224.417428) (xy 356.141689 -224.472596) (xy 356.132892 -224.49917)
			(xy 356.125272 -224.521268) (xy 356.32898 -224.874074) (xy 356.35184 -224.878392) (xy 356.376767 -224.883535)
			(xy 356.424753 -224.900502) (xy 356.469572 -224.924622) (xy 356.510166 -224.955325) (xy 356.545575 -224.991886)
			(xy 356.574962 -225.033442) (xy 356.597635 -225.07901) (xy 356.613056 -225.127515) (xy 356.620862 -225.17781)
			(xy 356.621334 -225.203258) (xy 356.620825 -225.229225) (xy 356.6127 -225.28052) (xy 356.596652 -225.329913)
			(xy 356.573074 -225.376187) (xy 356.542548 -225.418203) (xy 356.505825 -225.454926) (xy 356.463809 -225.485452)
			(xy 356.417535 -225.50903) (xy 356.368142 -225.525078) (xy 356.316847 -225.533203) (xy 356.264913 -225.533203)
			(xy 356.213618 -225.525078) (xy 356.164225 -225.50903) (xy 356.117951 -225.485452) (xy 356.075935 -225.454926)
			(xy 356.039212 -225.418203) (xy 356.008686 -225.376187) (xy 355.985108 -225.329913) (xy 355.96906 -225.28052)
			(xy 355.960935 -225.229225) (xy 355.960426 -225.203258) (xy 355.960967 -225.175272) (xy 355.970425 -225.120104)
			(xy 355.979222 -225.09353) (xy 355.986842 -225.071432) (xy 355.783134 -224.718626) (xy 355.760274 -224.714308)
			(xy 355.735349 -224.709155) (xy 355.687363 -224.69219) (xy 355.642544 -224.668072) (xy 355.60195 -224.63737)
			(xy 355.56654 -224.60081) (xy 355.537152 -224.559256) (xy 355.51448 -224.513688) (xy 355.499058 -224.465184)
			(xy 355.491252 -224.41489) (xy 355.49078 -224.389442) (xy 355.211888 -224.389442) (xy 355.211379 -224.415409)
			(xy 355.203254 -224.466704) (xy 355.187206 -224.516097) (xy 355.163628 -224.562371) (xy 355.133102 -224.604387)
			(xy 355.096379 -224.64111) (xy 355.054363 -224.671636) (xy 355.008089 -224.695214) (xy 354.958696 -224.711262)
			(xy 354.907401 -224.719387) (xy 354.855467 -224.719387) (xy 354.804172 -224.711262) (xy 354.754779 -224.695214)
			(xy 354.708505 -224.671636) (xy 354.666489 -224.64111) (xy 354.629766 -224.604387) (xy 354.59924 -224.562371)
			(xy 354.575662 -224.516097) (xy 354.559614 -224.466704) (xy 354.551489 -224.415409) (xy 354.55098 -224.389442)
			(xy 354.272088 -224.389442) (xy 354.271546 -224.417428) (xy 354.262089 -224.472596) (xy 354.253292 -224.49917)
			(xy 354.245672 -224.521268) (xy 354.44938 -224.874074) (xy 354.47224 -224.878392) (xy 354.497167 -224.883535)
			(xy 354.545153 -224.900502) (xy 354.589972 -224.924622) (xy 354.630566 -224.955325) (xy 354.665975 -224.991886)
			(xy 354.695362 -225.033442) (xy 354.718035 -225.07901) (xy 354.733456 -225.127515) (xy 354.741262 -225.17781)
			(xy 354.741734 -225.203258) (xy 354.741225 -225.229225) (xy 354.7331 -225.28052) (xy 354.717052 -225.329913)
			(xy 354.693474 -225.376187) (xy 354.662948 -225.418203) (xy 354.626225 -225.454926) (xy 354.584209 -225.485452)
			(xy 354.537935 -225.50903) (xy 354.488542 -225.525078) (xy 354.437247 -225.533203) (xy 354.385313 -225.533203)
			(xy 354.334018 -225.525078) (xy 354.284625 -225.50903) (xy 354.238351 -225.485452) (xy 354.196335 -225.454926)
			(xy 354.159612 -225.418203) (xy 354.129086 -225.376187) (xy 354.105508 -225.329913) (xy 354.08946 -225.28052)
			(xy 354.081335 -225.229225) (xy 354.080826 -225.203258) (xy 354.081367 -225.175272) (xy 354.090825 -225.120104)
			(xy 354.099622 -225.09353) (xy 354.107242 -225.071432) (xy 353.903534 -224.718626) (xy 353.880674 -224.714308)
			(xy 353.855749 -224.709155) (xy 353.807763 -224.69219) (xy 353.762944 -224.668072) (xy 353.72235 -224.63737)
			(xy 353.68694 -224.60081) (xy 353.657552 -224.559256) (xy 353.63488 -224.513688) (xy 353.619458 -224.465184)
			(xy 353.611652 -224.41489) (xy 353.61118 -224.389442) (xy 353.332288 -224.389442) (xy 353.331779 -224.415409)
			(xy 353.323654 -224.466704) (xy 353.307606 -224.516097) (xy 353.284028 -224.562371) (xy 353.253502 -224.604387)
			(xy 353.216779 -224.64111) (xy 353.174763 -224.671636) (xy 353.128489 -224.695214) (xy 353.079096 -224.711262)
			(xy 353.027801 -224.719387) (xy 352.975867 -224.719387) (xy 352.924572 -224.711262) (xy 352.875179 -224.695214)
			(xy 352.828905 -224.671636) (xy 352.786889 -224.64111) (xy 352.750166 -224.604387) (xy 352.71964 -224.562371)
			(xy 352.696062 -224.516097) (xy 352.680014 -224.466704) (xy 352.671889 -224.415409) (xy 352.67138 -224.389442)
			(xy 352.392742 -224.389442) (xy 352.392191 -224.417491) (xy 352.382746 -224.472786) (xy 352.373946 -224.499424)
			(xy 352.366072 -224.521522) (xy 352.569526 -224.87382) (xy 352.592386 -224.878138) (xy 352.617347 -224.883289)
			(xy 352.665414 -224.900227) (xy 352.710315 -224.924337) (xy 352.750987 -224.955049) (xy 352.786467 -224.991635)
			(xy 352.815916 -225.03323) (xy 352.838637 -225.07885) (xy 352.854092 -225.127415) (xy 352.861915 -225.177776)
			(xy 352.862388 -225.203258) (xy 352.861878 -225.229245) (xy 352.853748 -225.28058) (xy 352.837687 -225.33001)
			(xy 352.814091 -225.37632) (xy 352.783541 -225.418368) (xy 352.74679 -225.455119) (xy 352.704742 -225.485669)
			(xy 352.658432 -225.509265) (xy 352.609002 -225.525326) (xy 352.557667 -225.533456) (xy 352.505693 -225.533456)
			(xy 352.454358 -225.525326) (xy 352.404928 -225.509265) (xy 352.358618 -225.485669) (xy 352.31657 -225.455119)
			(xy 352.279819 -225.418368) (xy 352.249269 -225.37632) (xy 352.225673 -225.33001) (xy 352.209612 -225.28058)
			(xy 352.201482 -225.229245) (xy 352.200972 -225.203258) (xy 352.201522 -225.175209) (xy 352.210967 -225.119914)
			(xy 352.219768 -225.093276) (xy 352.227642 -225.071178) (xy 352.024188 -224.71888) (xy 352.001328 -224.714562)
			(xy 351.976369 -224.709401) (xy 351.928302 -224.692465) (xy 351.8834 -224.668356) (xy 351.842728 -224.637646)
			(xy 351.807248 -224.601061) (xy 351.777799 -224.559467) (xy 351.755078 -224.513848) (xy 351.739623 -224.465284)
			(xy 351.731799 -224.414924) (xy 351.731326 -224.389442) (xy 351.452942 -224.389442) (xy 351.452432 -224.415429)
			(xy 351.444302 -224.466764) (xy 351.428241 -224.516194) (xy 351.404645 -224.562504) (xy 351.374095 -224.604552)
			(xy 351.337344 -224.641303) (xy 351.295296 -224.671853) (xy 351.248986 -224.695449) (xy 351.199556 -224.71151)
			(xy 351.148221 -224.71964) (xy 351.096247 -224.71964) (xy 351.044912 -224.71151) (xy 350.995482 -224.695449)
			(xy 350.949172 -224.671853) (xy 350.907124 -224.641303) (xy 350.870373 -224.604552) (xy 350.839823 -224.562504)
			(xy 350.816227 -224.516194) (xy 350.800166 -224.466764) (xy 350.792036 -224.415429) (xy 350.791526 -224.389442)
			(xy 350.513142 -224.389442) (xy 350.512552 -224.417487) (xy 350.50311 -224.472777) (xy 350.494346 -224.499424)
			(xy 350.486472 -224.521522) (xy 350.689926 -224.87382) (xy 350.712786 -224.878138) (xy 350.737751 -224.883277)
			(xy 350.785824 -224.900208) (xy 350.830731 -224.924314) (xy 350.871407 -224.955025) (xy 350.906889 -224.991613)
			(xy 350.936337 -225.033213) (xy 350.959054 -225.078838) (xy 350.974501 -225.127408) (xy 350.982312 -225.177774)
			(xy 350.982788 -225.203258) (xy 350.982278 -225.229245) (xy 350.974148 -225.28058) (xy 350.958087 -225.33001)
			(xy 350.934491 -225.37632) (xy 350.903941 -225.418368) (xy 350.86719 -225.455119) (xy 350.825142 -225.485669)
			(xy 350.778832 -225.509265) (xy 350.729402 -225.525326) (xy 350.678067 -225.533456) (xy 350.626093 -225.533456)
			(xy 350.574758 -225.525326) (xy 350.525328 -225.509265) (xy 350.479018 -225.485669) (xy 350.43697 -225.455119)
			(xy 350.400219 -225.418368) (xy 350.369669 -225.37632) (xy 350.346073 -225.33001) (xy 350.330012 -225.28058)
			(xy 350.321882 -225.229245) (xy 350.321372 -225.203258) (xy 350.321962 -225.175213) (xy 350.331405 -225.119923)
			(xy 350.340168 -225.093276) (xy 350.348042 -225.071178) (xy 350.31553 -225.015044) (xy 350.307685 -225.002487)
			(xy 350.286146 -224.982191) (xy 350.259692 -224.968921) (xy 350.230545 -224.963791) (xy 350.201151 -224.967232)
			(xy 350.173977 -224.978955) (xy 350.151303 -224.997976) (xy 350.135034 -225.022698) (xy 350.126534 -225.051047)
			(xy 350.126046 -225.065844) (xy 350.126046 -225.636074) (xy 350.126479 -225.646197) (xy 350.134285 -225.664878)
			(xy 350.148697 -225.679098) (xy 350.167481 -225.686652) (xy 350.177608 -225.686874) (xy 350.182434 -225.686874)
			(xy 350.208399 -225.687386) (xy 350.259688 -225.695515) (xy 350.309074 -225.711567) (xy 350.355341 -225.735147)
			(xy 350.39735 -225.765674) (xy 350.434066 -225.802397) (xy 350.464586 -225.844412) (xy 350.488157 -225.890683)
			(xy 350.5042 -225.940072) (xy 350.512319 -225.991363) (xy 350.512888 -226.017328) (xy 350.512404 -226.042864)
			(xy 350.512337 -226.043295) (xy 350.792289 -226.043295) (xy 350.792289 -225.991361) (xy 350.800414 -225.940066)
			(xy 350.816462 -225.890673) (xy 350.84004 -225.844399) (xy 350.870566 -225.802383) (xy 350.907289 -225.76566)
			(xy 350.949305 -225.735134) (xy 350.995579 -225.711556) (xy 351.044972 -225.695508) (xy 351.096267 -225.687383)
			(xy 351.148201 -225.687383) (xy 351.199496 -225.695508) (xy 351.248889 -225.711556) (xy 351.295163 -225.735134)
			(xy 351.337179 -225.76566) (xy 351.373902 -225.802383) (xy 351.404428 -225.844399) (xy 351.428006 -225.890673)
			(xy 351.444054 -225.940066) (xy 351.452179 -225.991361) (xy 351.452688 -226.017328) (xy 351.452179 -226.043295)
			(xy 351.732089 -226.043295) (xy 351.732089 -225.991361) (xy 351.740214 -225.940066) (xy 351.756262 -225.890673)
			(xy 351.77984 -225.844399) (xy 351.810366 -225.802383) (xy 351.847089 -225.76566) (xy 351.889105 -225.735134)
			(xy 351.935379 -225.711556) (xy 351.984772 -225.695508) (xy 352.036067 -225.687383) (xy 352.088001 -225.687383)
			(xy 352.139296 -225.695508) (xy 352.188689 -225.711556) (xy 352.234963 -225.735134) (xy 352.276979 -225.76566)
			(xy 352.313702 -225.802383) (xy 352.344228 -225.844399) (xy 352.367806 -225.890673) (xy 352.383854 -225.940066)
			(xy 352.391979 -225.991361) (xy 352.392488 -226.017328) (xy 352.391979 -226.043295) (xy 352.671889 -226.043295)
			(xy 352.671889 -225.991361) (xy 352.680014 -225.940066) (xy 352.696062 -225.890673) (xy 352.71964 -225.844399)
			(xy 352.750166 -225.802383) (xy 352.786889 -225.76566) (xy 352.828905 -225.735134) (xy 352.875179 -225.711556)
			(xy 352.924572 -225.695508) (xy 352.975867 -225.687383) (xy 353.027801 -225.687383) (xy 353.079096 -225.695508)
			(xy 353.128489 -225.711556) (xy 353.174763 -225.735134) (xy 353.216779 -225.76566) (xy 353.253502 -225.802383)
			(xy 353.284028 -225.844399) (xy 353.307606 -225.890673) (xy 353.323654 -225.940066) (xy 353.331779 -225.991361)
			(xy 353.332288 -226.017328) (xy 353.331779 -226.043295) (xy 353.611689 -226.043295) (xy 353.611689 -225.991361)
			(xy 353.619814 -225.940066) (xy 353.635862 -225.890673) (xy 353.65944 -225.844399) (xy 353.689966 -225.802383)
			(xy 353.726689 -225.76566) (xy 353.768705 -225.735134) (xy 353.814979 -225.711556) (xy 353.864372 -225.695508)
			(xy 353.915667 -225.687383) (xy 353.967601 -225.687383) (xy 354.018896 -225.695508) (xy 354.068289 -225.711556)
			(xy 354.114563 -225.735134) (xy 354.156579 -225.76566) (xy 354.193302 -225.802383) (xy 354.223828 -225.844399)
			(xy 354.247406 -225.890673) (xy 354.263454 -225.940066) (xy 354.271579 -225.991361) (xy 354.272088 -226.017328)
			(xy 354.271579 -226.043295) (xy 354.551489 -226.043295) (xy 354.551489 -225.991361) (xy 354.559614 -225.940066)
			(xy 354.575662 -225.890673) (xy 354.59924 -225.844399) (xy 354.629766 -225.802383) (xy 354.666489 -225.76566)
			(xy 354.708505 -225.735134) (xy 354.754779 -225.711556) (xy 354.804172 -225.695508) (xy 354.855467 -225.687383)
			(xy 354.907401 -225.687383) (xy 354.958696 -225.695508) (xy 355.008089 -225.711556) (xy 355.054363 -225.735134)
			(xy 355.096379 -225.76566) (xy 355.133102 -225.802383) (xy 355.163628 -225.844399) (xy 355.187206 -225.890673)
			(xy 355.203254 -225.940066) (xy 355.211379 -225.991361) (xy 355.211888 -226.017328) (xy 355.211379 -226.043295)
			(xy 355.491289 -226.043295) (xy 355.491289 -225.991361) (xy 355.499414 -225.940066) (xy 355.515462 -225.890673)
			(xy 355.53904 -225.844399) (xy 355.569566 -225.802383) (xy 355.606289 -225.76566) (xy 355.648305 -225.735134)
			(xy 355.694579 -225.711556) (xy 355.743972 -225.695508) (xy 355.795267 -225.687383) (xy 355.847201 -225.687383)
			(xy 355.898496 -225.695508) (xy 355.947889 -225.711556) (xy 355.994163 -225.735134) (xy 356.036179 -225.76566)
			(xy 356.072902 -225.802383) (xy 356.103428 -225.844399) (xy 356.127006 -225.890673) (xy 356.143054 -225.940066)
			(xy 356.151179 -225.991361) (xy 356.151688 -226.017328) (xy 356.151179 -226.043295) (xy 356.431089 -226.043295)
			(xy 356.431089 -225.991361) (xy 356.439214 -225.940066) (xy 356.455262 -225.890673) (xy 356.47884 -225.844399)
			(xy 356.509366 -225.802383) (xy 356.546089 -225.76566) (xy 356.588105 -225.735134) (xy 356.634379 -225.711556)
			(xy 356.683772 -225.695508) (xy 356.735067 -225.687383) (xy 356.787001 -225.687383) (xy 356.838296 -225.695508)
			(xy 356.887689 -225.711556) (xy 356.933963 -225.735134) (xy 356.975979 -225.76566) (xy 357.012702 -225.802383)
			(xy 357.043228 -225.844399) (xy 357.066806 -225.890673) (xy 357.082854 -225.940066) (xy 357.090979 -225.991361)
			(xy 357.091488 -226.017328) (xy 357.090979 -226.043295) (xy 357.370889 -226.043295) (xy 357.370889 -225.991361)
			(xy 357.379014 -225.940066) (xy 357.395062 -225.890673) (xy 357.41864 -225.844399) (xy 357.449166 -225.802383)
			(xy 357.485889 -225.76566) (xy 357.527905 -225.735134) (xy 357.574179 -225.711556) (xy 357.623572 -225.695508)
			(xy 357.674867 -225.687383) (xy 357.726801 -225.687383) (xy 357.778096 -225.695508) (xy 357.827489 -225.711556)
			(xy 357.873763 -225.735134) (xy 357.915779 -225.76566) (xy 357.952502 -225.802383) (xy 357.983028 -225.844399)
			(xy 358.006606 -225.890673) (xy 358.022654 -225.940066) (xy 358.030779 -225.991361) (xy 358.031288 -226.017328)
			(xy 358.030779 -226.043295) (xy 358.310689 -226.043295) (xy 358.310689 -225.991361) (xy 358.318814 -225.940066)
			(xy 358.334862 -225.890673) (xy 358.35844 -225.844399) (xy 358.388966 -225.802383) (xy 358.425689 -225.76566)
			(xy 358.467705 -225.735134) (xy 358.513979 -225.711556) (xy 358.563372 -225.695508) (xy 358.614667 -225.687383)
			(xy 358.666601 -225.687383) (xy 358.717896 -225.695508) (xy 358.767289 -225.711556) (xy 358.813563 -225.735134)
			(xy 358.855579 -225.76566) (xy 358.892302 -225.802383) (xy 358.922828 -225.844399) (xy 358.946406 -225.890673)
			(xy 358.962454 -225.940066) (xy 358.970579 -225.991361) (xy 358.971088 -226.017328) (xy 358.970579 -226.043295)
			(xy 359.250489 -226.043295) (xy 359.250489 -225.991361) (xy 359.258614 -225.940066) (xy 359.274662 -225.890673)
			(xy 359.29824 -225.844399) (xy 359.328766 -225.802383) (xy 359.365489 -225.76566) (xy 359.407505 -225.735134)
			(xy 359.453779 -225.711556) (xy 359.503172 -225.695508) (xy 359.554467 -225.687383) (xy 359.606401 -225.687383)
			(xy 359.657696 -225.695508) (xy 359.707089 -225.711556) (xy 359.753363 -225.735134) (xy 359.795379 -225.76566)
			(xy 359.832102 -225.802383) (xy 359.862628 -225.844399) (xy 359.886206 -225.890673) (xy 359.902254 -225.940066)
			(xy 359.910379 -225.991361) (xy 359.910888 -226.017328) (xy 359.910379 -226.043295) (xy 360.190289 -226.043295)
			(xy 360.190289 -225.991361) (xy 360.198414 -225.940066) (xy 360.214462 -225.890673) (xy 360.23804 -225.844399)
			(xy 360.268566 -225.802383) (xy 360.305289 -225.76566) (xy 360.347305 -225.735134) (xy 360.393579 -225.711556)
			(xy 360.442972 -225.695508) (xy 360.494267 -225.687383) (xy 360.546201 -225.687383) (xy 360.597496 -225.695508)
			(xy 360.646889 -225.711556) (xy 360.693163 -225.735134) (xy 360.735179 -225.76566) (xy 360.771902 -225.802383)
			(xy 360.802428 -225.844399) (xy 360.826006 -225.890673) (xy 360.842054 -225.940066) (xy 360.850179 -225.991361)
			(xy 360.850688 -226.017328) (xy 360.850179 -226.043295) (xy 361.130089 -226.043295) (xy 361.130089 -225.991361)
			(xy 361.138214 -225.940066) (xy 361.154262 -225.890673) (xy 361.17784 -225.844399) (xy 361.208366 -225.802383)
			(xy 361.245089 -225.76566) (xy 361.287105 -225.735134) (xy 361.333379 -225.711556) (xy 361.382772 -225.695508)
			(xy 361.434067 -225.687383) (xy 361.486001 -225.687383) (xy 361.537296 -225.695508) (xy 361.586689 -225.711556)
			(xy 361.632963 -225.735134) (xy 361.674979 -225.76566) (xy 361.711702 -225.802383) (xy 361.742228 -225.844399)
			(xy 361.765806 -225.890673) (xy 361.781854 -225.940066) (xy 361.789979 -225.991361) (xy 361.790488 -226.017328)
			(xy 361.789979 -226.043295) (xy 362.069889 -226.043295) (xy 362.069889 -225.991361) (xy 362.078014 -225.940066)
			(xy 362.094062 -225.890673) (xy 362.11764 -225.844399) (xy 362.148166 -225.802383) (xy 362.184889 -225.76566)
			(xy 362.226905 -225.735134) (xy 362.273179 -225.711556) (xy 362.322572 -225.695508) (xy 362.373867 -225.687383)
			(xy 362.425801 -225.687383) (xy 362.477096 -225.695508) (xy 362.526489 -225.711556) (xy 362.572763 -225.735134)
			(xy 362.614779 -225.76566) (xy 362.651502 -225.802383) (xy 362.682028 -225.844399) (xy 362.705606 -225.890673)
			(xy 362.721654 -225.940066) (xy 362.729779 -225.991361) (xy 362.730288 -226.017328) (xy 362.729779 -226.043295)
			(xy 363.009689 -226.043295) (xy 363.009689 -225.991361) (xy 363.017814 -225.940066) (xy 363.033862 -225.890673)
			(xy 363.05744 -225.844399) (xy 363.087966 -225.802383) (xy 363.124689 -225.76566) (xy 363.166705 -225.735134)
			(xy 363.212979 -225.711556) (xy 363.262372 -225.695508) (xy 363.313667 -225.687383) (xy 363.365601 -225.687383)
			(xy 363.416896 -225.695508) (xy 363.466289 -225.711556) (xy 363.512563 -225.735134) (xy 363.554579 -225.76566)
			(xy 363.591302 -225.802383) (xy 363.621828 -225.844399) (xy 363.645406 -225.890673) (xy 363.661454 -225.940066)
			(xy 363.669579 -225.991361) (xy 363.670088 -226.017328) (xy 363.669579 -226.043295) (xy 363.949489 -226.043295)
			(xy 363.949489 -225.991361) (xy 363.957614 -225.940066) (xy 363.973662 -225.890673) (xy 363.99724 -225.844399)
			(xy 364.027766 -225.802383) (xy 364.064489 -225.76566) (xy 364.106505 -225.735134) (xy 364.152779 -225.711556)
			(xy 364.202172 -225.695508) (xy 364.253467 -225.687383) (xy 364.305401 -225.687383) (xy 364.356696 -225.695508)
			(xy 364.406089 -225.711556) (xy 364.452363 -225.735134) (xy 364.494379 -225.76566) (xy 364.531102 -225.802383)
			(xy 364.561628 -225.844399) (xy 364.585206 -225.890673) (xy 364.601254 -225.940066) (xy 364.609379 -225.991361)
			(xy 364.609888 -226.017328) (xy 364.609379 -226.043295) (xy 364.889289 -226.043295) (xy 364.889289 -225.991361)
			(xy 364.897414 -225.940066) (xy 364.913462 -225.890673) (xy 364.93704 -225.844399) (xy 364.967566 -225.802383)
			(xy 365.004289 -225.76566) (xy 365.046305 -225.735134) (xy 365.092579 -225.711556) (xy 365.141972 -225.695508)
			(xy 365.193267 -225.687383) (xy 365.245201 -225.687383) (xy 365.296496 -225.695508) (xy 365.345889 -225.711556)
			(xy 365.392163 -225.735134) (xy 365.434179 -225.76566) (xy 365.470902 -225.802383) (xy 365.501428 -225.844399)
			(xy 365.525006 -225.890673) (xy 365.541054 -225.940066) (xy 365.549179 -225.991361) (xy 365.549688 -226.017328)
			(xy 365.549179 -226.043295) (xy 365.829089 -226.043295) (xy 365.829089 -225.991361) (xy 365.837214 -225.940066)
			(xy 365.853262 -225.890673) (xy 365.87684 -225.844399) (xy 365.907366 -225.802383) (xy 365.944089 -225.76566)
			(xy 365.986105 -225.735134) (xy 366.032379 -225.711556) (xy 366.081772 -225.695508) (xy 366.133067 -225.687383)
			(xy 366.185001 -225.687383) (xy 366.236296 -225.695508) (xy 366.285689 -225.711556) (xy 366.331963 -225.735134)
			(xy 366.373979 -225.76566) (xy 366.410702 -225.802383) (xy 366.441228 -225.844399) (xy 366.464806 -225.890673)
			(xy 366.480854 -225.940066) (xy 366.488979 -225.991361) (xy 366.489488 -226.017328) (xy 366.488979 -226.043295)
			(xy 366.768889 -226.043295) (xy 366.768889 -225.991361) (xy 366.777014 -225.940066) (xy 366.793062 -225.890673)
			(xy 366.81664 -225.844399) (xy 366.847166 -225.802383) (xy 366.883889 -225.76566) (xy 366.925905 -225.735134)
			(xy 366.972179 -225.711556) (xy 367.021572 -225.695508) (xy 367.072867 -225.687383) (xy 367.124801 -225.687383)
			(xy 367.176096 -225.695508) (xy 367.225489 -225.711556) (xy 367.271763 -225.735134) (xy 367.313779 -225.76566)
			(xy 367.350502 -225.802383) (xy 367.381028 -225.844399) (xy 367.404606 -225.890673) (xy 367.420654 -225.940066)
			(xy 367.428779 -225.991361) (xy 367.429288 -226.017328) (xy 367.428779 -226.043295) (xy 367.708689 -226.043295)
			(xy 367.708689 -225.991361) (xy 367.716814 -225.940066) (xy 367.732862 -225.890673) (xy 367.75644 -225.844399)
			(xy 367.786966 -225.802383) (xy 367.823689 -225.76566) (xy 367.865705 -225.735134) (xy 367.911979 -225.711556)
			(xy 367.961372 -225.695508) (xy 368.012667 -225.687383) (xy 368.064601 -225.687383) (xy 368.115896 -225.695508)
			(xy 368.165289 -225.711556) (xy 368.211563 -225.735134) (xy 368.253579 -225.76566) (xy 368.290302 -225.802383)
			(xy 368.320828 -225.844399) (xy 368.344406 -225.890673) (xy 368.360454 -225.940066) (xy 368.368579 -225.991361)
			(xy 368.369088 -226.017328) (xy 368.368579 -226.043295) (xy 368.648489 -226.043295) (xy 368.648489 -225.991361)
			(xy 368.656614 -225.940066) (xy 368.672662 -225.890673) (xy 368.69624 -225.844399) (xy 368.726766 -225.802383)
			(xy 368.763489 -225.76566) (xy 368.805505 -225.735134) (xy 368.851779 -225.711556) (xy 368.901172 -225.695508)
			(xy 368.952467 -225.687383) (xy 369.004401 -225.687383) (xy 369.055696 -225.695508) (xy 369.105089 -225.711556)
			(xy 369.151363 -225.735134) (xy 369.193379 -225.76566) (xy 369.230102 -225.802383) (xy 369.260628 -225.844399)
			(xy 369.284206 -225.890673) (xy 369.300254 -225.940066) (xy 369.308379 -225.991361) (xy 369.308888 -226.017328)
			(xy 369.308379 -226.043295) (xy 369.300254 -226.09459) (xy 369.284206 -226.143983) (xy 369.260628 -226.190257)
			(xy 369.230102 -226.232273) (xy 369.193379 -226.268996) (xy 369.151363 -226.299522) (xy 369.105089 -226.3231)
			(xy 369.055696 -226.339148) (xy 369.004401 -226.347273) (xy 368.952467 -226.347273) (xy 368.901172 -226.339148)
			(xy 368.851779 -226.3231) (xy 368.805505 -226.299522) (xy 368.763489 -226.268996) (xy 368.726766 -226.232273)
			(xy 368.69624 -226.190257) (xy 368.672662 -226.143983) (xy 368.656614 -226.09459) (xy 368.648489 -226.043295)
			(xy 368.368579 -226.043295) (xy 368.360454 -226.09459) (xy 368.344406 -226.143983) (xy 368.320828 -226.190257)
			(xy 368.290302 -226.232273) (xy 368.253579 -226.268996) (xy 368.211563 -226.299522) (xy 368.165289 -226.3231)
			(xy 368.115896 -226.339148) (xy 368.064601 -226.347273) (xy 368.012667 -226.347273) (xy 367.961372 -226.339148)
			(xy 367.911979 -226.3231) (xy 367.865705 -226.299522) (xy 367.823689 -226.268996) (xy 367.786966 -226.232273)
			(xy 367.75644 -226.190257) (xy 367.732862 -226.143983) (xy 367.716814 -226.09459) (xy 367.708689 -226.043295)
			(xy 367.428779 -226.043295) (xy 367.420654 -226.09459) (xy 367.404606 -226.143983) (xy 367.381028 -226.190257)
			(xy 367.350502 -226.232273) (xy 367.313779 -226.268996) (xy 367.271763 -226.299522) (xy 367.225489 -226.3231)
			(xy 367.176096 -226.339148) (xy 367.124801 -226.347273) (xy 367.072867 -226.347273) (xy 367.021572 -226.339148)
			(xy 366.972179 -226.3231) (xy 366.925905 -226.299522) (xy 366.883889 -226.268996) (xy 366.847166 -226.232273)
			(xy 366.81664 -226.190257) (xy 366.793062 -226.143983) (xy 366.777014 -226.09459) (xy 366.768889 -226.043295)
			(xy 366.488979 -226.043295) (xy 366.480854 -226.09459) (xy 366.464806 -226.143983) (xy 366.441228 -226.190257)
			(xy 366.410702 -226.232273) (xy 366.373979 -226.268996) (xy 366.331963 -226.299522) (xy 366.285689 -226.3231)
			(xy 366.236296 -226.339148) (xy 366.185001 -226.347273) (xy 366.133067 -226.347273) (xy 366.081772 -226.339148)
			(xy 366.032379 -226.3231) (xy 365.986105 -226.299522) (xy 365.944089 -226.268996) (xy 365.907366 -226.232273)
			(xy 365.87684 -226.190257) (xy 365.853262 -226.143983) (xy 365.837214 -226.09459) (xy 365.829089 -226.043295)
			(xy 365.549179 -226.043295) (xy 365.541054 -226.09459) (xy 365.525006 -226.143983) (xy 365.501428 -226.190257)
			(xy 365.470902 -226.232273) (xy 365.434179 -226.268996) (xy 365.392163 -226.299522) (xy 365.345889 -226.3231)
			(xy 365.296496 -226.339148) (xy 365.245201 -226.347273) (xy 365.193267 -226.347273) (xy 365.141972 -226.339148)
			(xy 365.092579 -226.3231) (xy 365.046305 -226.299522) (xy 365.004289 -226.268996) (xy 364.967566 -226.232273)
			(xy 364.93704 -226.190257) (xy 364.913462 -226.143983) (xy 364.897414 -226.09459) (xy 364.889289 -226.043295)
			(xy 364.609379 -226.043295) (xy 364.601254 -226.09459) (xy 364.585206 -226.143983) (xy 364.561628 -226.190257)
			(xy 364.531102 -226.232273) (xy 364.494379 -226.268996) (xy 364.452363 -226.299522) (xy 364.406089 -226.3231)
			(xy 364.356696 -226.339148) (xy 364.305401 -226.347273) (xy 364.253467 -226.347273) (xy 364.202172 -226.339148)
			(xy 364.152779 -226.3231) (xy 364.106505 -226.299522) (xy 364.064489 -226.268996) (xy 364.027766 -226.232273)
			(xy 363.99724 -226.190257) (xy 363.973662 -226.143983) (xy 363.957614 -226.09459) (xy 363.949489 -226.043295)
			(xy 363.669579 -226.043295) (xy 363.661454 -226.09459) (xy 363.645406 -226.143983) (xy 363.621828 -226.190257)
			(xy 363.591302 -226.232273) (xy 363.554579 -226.268996) (xy 363.512563 -226.299522) (xy 363.466289 -226.3231)
			(xy 363.416896 -226.339148) (xy 363.365601 -226.347273) (xy 363.313667 -226.347273) (xy 363.262372 -226.339148)
			(xy 363.212979 -226.3231) (xy 363.166705 -226.299522) (xy 363.124689 -226.268996) (xy 363.087966 -226.232273)
			(xy 363.05744 -226.190257) (xy 363.033862 -226.143983) (xy 363.017814 -226.09459) (xy 363.009689 -226.043295)
			(xy 362.729779 -226.043295) (xy 362.721654 -226.09459) (xy 362.705606 -226.143983) (xy 362.682028 -226.190257)
			(xy 362.651502 -226.232273) (xy 362.614779 -226.268996) (xy 362.572763 -226.299522) (xy 362.526489 -226.3231)
			(xy 362.477096 -226.339148) (xy 362.425801 -226.347273) (xy 362.373867 -226.347273) (xy 362.322572 -226.339148)
			(xy 362.273179 -226.3231) (xy 362.226905 -226.299522) (xy 362.184889 -226.268996) (xy 362.148166 -226.232273)
			(xy 362.11764 -226.190257) (xy 362.094062 -226.143983) (xy 362.078014 -226.09459) (xy 362.069889 -226.043295)
			(xy 361.789979 -226.043295) (xy 361.781854 -226.09459) (xy 361.765806 -226.143983) (xy 361.742228 -226.190257)
			(xy 361.711702 -226.232273) (xy 361.674979 -226.268996) (xy 361.632963 -226.299522) (xy 361.586689 -226.3231)
			(xy 361.537296 -226.339148) (xy 361.486001 -226.347273) (xy 361.434067 -226.347273) (xy 361.382772 -226.339148)
			(xy 361.333379 -226.3231) (xy 361.287105 -226.299522) (xy 361.245089 -226.268996) (xy 361.208366 -226.232273)
			(xy 361.17784 -226.190257) (xy 361.154262 -226.143983) (xy 361.138214 -226.09459) (xy 361.130089 -226.043295)
			(xy 360.850179 -226.043295) (xy 360.842054 -226.09459) (xy 360.826006 -226.143983) (xy 360.802428 -226.190257)
			(xy 360.771902 -226.232273) (xy 360.735179 -226.268996) (xy 360.693163 -226.299522) (xy 360.646889 -226.3231)
			(xy 360.597496 -226.339148) (xy 360.546201 -226.347273) (xy 360.494267 -226.347273) (xy 360.442972 -226.339148)
			(xy 360.393579 -226.3231) (xy 360.347305 -226.299522) (xy 360.305289 -226.268996) (xy 360.268566 -226.232273)
			(xy 360.23804 -226.190257) (xy 360.214462 -226.143983) (xy 360.198414 -226.09459) (xy 360.190289 -226.043295)
			(xy 359.910379 -226.043295) (xy 359.902254 -226.09459) (xy 359.886206 -226.143983) (xy 359.862628 -226.190257)
			(xy 359.832102 -226.232273) (xy 359.795379 -226.268996) (xy 359.753363 -226.299522) (xy 359.707089 -226.3231)
			(xy 359.657696 -226.339148) (xy 359.606401 -226.347273) (xy 359.554467 -226.347273) (xy 359.503172 -226.339148)
			(xy 359.453779 -226.3231) (xy 359.407505 -226.299522) (xy 359.365489 -226.268996) (xy 359.328766 -226.232273)
			(xy 359.29824 -226.190257) (xy 359.274662 -226.143983) (xy 359.258614 -226.09459) (xy 359.250489 -226.043295)
			(xy 358.970579 -226.043295) (xy 358.962454 -226.09459) (xy 358.946406 -226.143983) (xy 358.922828 -226.190257)
			(xy 358.892302 -226.232273) (xy 358.855579 -226.268996) (xy 358.813563 -226.299522) (xy 358.767289 -226.3231)
			(xy 358.717896 -226.339148) (xy 358.666601 -226.347273) (xy 358.614667 -226.347273) (xy 358.563372 -226.339148)
			(xy 358.513979 -226.3231) (xy 358.467705 -226.299522) (xy 358.425689 -226.268996) (xy 358.388966 -226.232273)
			(xy 358.35844 -226.190257) (xy 358.334862 -226.143983) (xy 358.318814 -226.09459) (xy 358.310689 -226.043295)
			(xy 358.030779 -226.043295) (xy 358.022654 -226.09459) (xy 358.006606 -226.143983) (xy 357.983028 -226.190257)
			(xy 357.952502 -226.232273) (xy 357.915779 -226.268996) (xy 357.873763 -226.299522) (xy 357.827489 -226.3231)
			(xy 357.778096 -226.339148) (xy 357.726801 -226.347273) (xy 357.674867 -226.347273) (xy 357.623572 -226.339148)
			(xy 357.574179 -226.3231) (xy 357.527905 -226.299522) (xy 357.485889 -226.268996) (xy 357.449166 -226.232273)
			(xy 357.41864 -226.190257) (xy 357.395062 -226.143983) (xy 357.379014 -226.09459) (xy 357.370889 -226.043295)
			(xy 357.090979 -226.043295) (xy 357.082854 -226.09459) (xy 357.066806 -226.143983) (xy 357.043228 -226.190257)
			(xy 357.012702 -226.232273) (xy 356.975979 -226.268996) (xy 356.933963 -226.299522) (xy 356.887689 -226.3231)
			(xy 356.838296 -226.339148) (xy 356.787001 -226.347273) (xy 356.735067 -226.347273) (xy 356.683772 -226.339148)
			(xy 356.634379 -226.3231) (xy 356.588105 -226.299522) (xy 356.546089 -226.268996) (xy 356.509366 -226.232273)
			(xy 356.47884 -226.190257) (xy 356.455262 -226.143983) (xy 356.439214 -226.09459) (xy 356.431089 -226.043295)
			(xy 356.151179 -226.043295) (xy 356.143054 -226.09459) (xy 356.127006 -226.143983) (xy 356.103428 -226.190257)
			(xy 356.072902 -226.232273) (xy 356.036179 -226.268996) (xy 355.994163 -226.299522) (xy 355.947889 -226.3231)
			(xy 355.898496 -226.339148) (xy 355.847201 -226.347273) (xy 355.795267 -226.347273) (xy 355.743972 -226.339148)
			(xy 355.694579 -226.3231) (xy 355.648305 -226.299522) (xy 355.606289 -226.268996) (xy 355.569566 -226.232273)
			(xy 355.53904 -226.190257) (xy 355.515462 -226.143983) (xy 355.499414 -226.09459) (xy 355.491289 -226.043295)
			(xy 355.211379 -226.043295) (xy 355.203254 -226.09459) (xy 355.187206 -226.143983) (xy 355.163628 -226.190257)
			(xy 355.133102 -226.232273) (xy 355.096379 -226.268996) (xy 355.054363 -226.299522) (xy 355.008089 -226.3231)
			(xy 354.958696 -226.339148) (xy 354.907401 -226.347273) (xy 354.855467 -226.347273) (xy 354.804172 -226.339148)
			(xy 354.754779 -226.3231) (xy 354.708505 -226.299522) (xy 354.666489 -226.268996) (xy 354.629766 -226.232273)
			(xy 354.59924 -226.190257) (xy 354.575662 -226.143983) (xy 354.559614 -226.09459) (xy 354.551489 -226.043295)
			(xy 354.271579 -226.043295) (xy 354.263454 -226.09459) (xy 354.247406 -226.143983) (xy 354.223828 -226.190257)
			(xy 354.193302 -226.232273) (xy 354.156579 -226.268996) (xy 354.114563 -226.299522) (xy 354.068289 -226.3231)
			(xy 354.018896 -226.339148) (xy 353.967601 -226.347273) (xy 353.915667 -226.347273) (xy 353.864372 -226.339148)
			(xy 353.814979 -226.3231) (xy 353.768705 -226.299522) (xy 353.726689 -226.268996) (xy 353.689966 -226.232273)
			(xy 353.65944 -226.190257) (xy 353.635862 -226.143983) (xy 353.619814 -226.09459) (xy 353.611689 -226.043295)
			(xy 353.331779 -226.043295) (xy 353.323654 -226.09459) (xy 353.307606 -226.143983) (xy 353.284028 -226.190257)
			(xy 353.253502 -226.232273) (xy 353.216779 -226.268996) (xy 353.174763 -226.299522) (xy 353.128489 -226.3231)
			(xy 353.079096 -226.339148) (xy 353.027801 -226.347273) (xy 352.975867 -226.347273) (xy 352.924572 -226.339148)
			(xy 352.875179 -226.3231) (xy 352.828905 -226.299522) (xy 352.786889 -226.268996) (xy 352.750166 -226.232273)
			(xy 352.71964 -226.190257) (xy 352.696062 -226.143983) (xy 352.680014 -226.09459) (xy 352.671889 -226.043295)
			(xy 352.391979 -226.043295) (xy 352.383854 -226.09459) (xy 352.367806 -226.143983) (xy 352.344228 -226.190257)
			(xy 352.313702 -226.232273) (xy 352.276979 -226.268996) (xy 352.234963 -226.299522) (xy 352.188689 -226.3231)
			(xy 352.139296 -226.339148) (xy 352.088001 -226.347273) (xy 352.036067 -226.347273) (xy 351.984772 -226.339148)
			(xy 351.935379 -226.3231) (xy 351.889105 -226.299522) (xy 351.847089 -226.268996) (xy 351.810366 -226.232273)
			(xy 351.77984 -226.190257) (xy 351.756262 -226.143983) (xy 351.740214 -226.09459) (xy 351.732089 -226.043295)
			(xy 351.452179 -226.043295) (xy 351.444054 -226.09459) (xy 351.428006 -226.143983) (xy 351.404428 -226.190257)
			(xy 351.373902 -226.232273) (xy 351.337179 -226.268996) (xy 351.295163 -226.299522) (xy 351.248889 -226.3231)
			(xy 351.199496 -226.339148) (xy 351.148201 -226.347273) (xy 351.096267 -226.347273) (xy 351.044972 -226.339148)
			(xy 350.995579 -226.3231) (xy 350.949305 -226.299522) (xy 350.907289 -226.268996) (xy 350.870566 -226.232273)
			(xy 350.84004 -226.190257) (xy 350.816462 -226.143983) (xy 350.800414 -226.09459) (xy 350.792289 -226.043295)
			(xy 350.512337 -226.043295) (xy 350.504532 -226.093327) (xy 350.488995 -226.141979) (xy 350.466163 -226.187664)
			(xy 350.436579 -226.229295) (xy 350.400946 -226.265883) (xy 350.360111 -226.296558) (xy 350.315045 -226.32059)
			(xy 350.266821 -226.337407) (xy 350.216584 -226.34661) (xy 350.19107 -226.347782) (xy 350.175394 -226.348784)
			(xy 350.145748 -226.359115) (xy 350.120638 -226.377958) (xy 350.102433 -226.403535) (xy 350.092852 -226.433432)
			(xy 350.092264 -226.449128) (xy 350.092264 -226.857111) (xy 350.322135 -226.857111) (xy 350.322135 -226.805177)
			(xy 350.33026 -226.753882) (xy 350.346308 -226.704489) (xy 350.369886 -226.658215) (xy 350.400412 -226.616199)
			(xy 350.437135 -226.579476) (xy 350.479151 -226.54895) (xy 350.525425 -226.525372) (xy 350.574818 -226.509324)
			(xy 350.626113 -226.501199) (xy 350.678047 -226.501199) (xy 350.729342 -226.509324) (xy 350.778735 -226.525372)
			(xy 350.825009 -226.54895) (xy 350.867025 -226.579476) (xy 350.903748 -226.616199) (xy 350.934274 -226.658215)
			(xy 350.957852 -226.704489) (xy 350.9739 -226.753882) (xy 350.982025 -226.805177) (xy 350.982534 -226.831144)
			(xy 350.982025 -226.857111) (xy 351.262189 -226.857111) (xy 351.262189 -226.805177) (xy 351.270314 -226.753882)
			(xy 351.286362 -226.704489) (xy 351.30994 -226.658215) (xy 351.340466 -226.616199) (xy 351.377189 -226.579476)
			(xy 351.419205 -226.54895) (xy 351.465479 -226.525372) (xy 351.514872 -226.509324) (xy 351.566167 -226.501199)
			(xy 351.618101 -226.501199) (xy 351.669396 -226.509324) (xy 351.718789 -226.525372) (xy 351.765063 -226.54895)
			(xy 351.807079 -226.579476) (xy 351.843802 -226.616199) (xy 351.874328 -226.658215) (xy 351.897906 -226.704489)
			(xy 351.913954 -226.753882) (xy 351.922079 -226.805177) (xy 351.922588 -226.831144) (xy 351.922079 -226.857111)
			(xy 352.201989 -226.857111) (xy 352.201989 -226.805177) (xy 352.210114 -226.753882) (xy 352.226162 -226.704489)
			(xy 352.24974 -226.658215) (xy 352.280266 -226.616199) (xy 352.316989 -226.579476) (xy 352.359005 -226.54895)
			(xy 352.405279 -226.525372) (xy 352.454672 -226.509324) (xy 352.505967 -226.501199) (xy 352.557901 -226.501199)
			(xy 352.609196 -226.509324) (xy 352.658589 -226.525372) (xy 352.704863 -226.54895) (xy 352.746879 -226.579476)
			(xy 352.783602 -226.616199) (xy 352.814128 -226.658215) (xy 352.837706 -226.704489) (xy 352.853754 -226.753882)
			(xy 352.861879 -226.805177) (xy 352.862388 -226.831144) (xy 352.861879 -226.857111) (xy 353.141535 -226.857111)
			(xy 353.141535 -226.805177) (xy 353.14966 -226.753882) (xy 353.165708 -226.704489) (xy 353.189286 -226.658215)
			(xy 353.219812 -226.616199) (xy 353.256535 -226.579476) (xy 353.298551 -226.54895) (xy 353.344825 -226.525372)
			(xy 353.394218 -226.509324) (xy 353.445513 -226.501199) (xy 353.497447 -226.501199) (xy 353.548742 -226.509324)
			(xy 353.598135 -226.525372) (xy 353.644409 -226.54895) (xy 353.686425 -226.579476) (xy 353.723148 -226.616199)
			(xy 353.753674 -226.658215) (xy 353.777252 -226.704489) (xy 353.7933 -226.753882) (xy 353.801425 -226.805177)
			(xy 353.801934 -226.831144) (xy 353.801425 -226.857111) (xy 354.081589 -226.857111) (xy 354.081589 -226.805177)
			(xy 354.089714 -226.753882) (xy 354.105762 -226.704489) (xy 354.12934 -226.658215) (xy 354.159866 -226.616199)
			(xy 354.196589 -226.579476) (xy 354.238605 -226.54895) (xy 354.284879 -226.525372) (xy 354.334272 -226.509324)
			(xy 354.385567 -226.501199) (xy 354.437501 -226.501199) (xy 354.488796 -226.509324) (xy 354.538189 -226.525372)
			(xy 354.584463 -226.54895) (xy 354.626479 -226.579476) (xy 354.663202 -226.616199) (xy 354.693728 -226.658215)
			(xy 354.717306 -226.704489) (xy 354.733354 -226.753882) (xy 354.741479 -226.805177) (xy 354.741988 -226.831144)
			(xy 354.741479 -226.857111) (xy 355.021135 -226.857111) (xy 355.021135 -226.805177) (xy 355.02926 -226.753882)
			(xy 355.045308 -226.704489) (xy 355.068886 -226.658215) (xy 355.099412 -226.616199) (xy 355.136135 -226.579476)
			(xy 355.178151 -226.54895) (xy 355.224425 -226.525372) (xy 355.273818 -226.509324) (xy 355.325113 -226.501199)
			(xy 355.377047 -226.501199) (xy 355.428342 -226.509324) (xy 355.477735 -226.525372) (xy 355.524009 -226.54895)
			(xy 355.566025 -226.579476) (xy 355.602748 -226.616199) (xy 355.633274 -226.658215) (xy 355.656852 -226.704489)
			(xy 355.6729 -226.753882) (xy 355.681025 -226.805177) (xy 355.681534 -226.831144) (xy 355.681025 -226.857111)
			(xy 355.961189 -226.857111) (xy 355.961189 -226.805177) (xy 355.969314 -226.753882) (xy 355.985362 -226.704489)
			(xy 356.00894 -226.658215) (xy 356.039466 -226.616199) (xy 356.076189 -226.579476) (xy 356.118205 -226.54895)
			(xy 356.164479 -226.525372) (xy 356.213872 -226.509324) (xy 356.265167 -226.501199) (xy 356.317101 -226.501199)
			(xy 356.368396 -226.509324) (xy 356.417789 -226.525372) (xy 356.464063 -226.54895) (xy 356.506079 -226.579476)
			(xy 356.542802 -226.616199) (xy 356.573328 -226.658215) (xy 356.596906 -226.704489) (xy 356.612954 -226.753882)
			(xy 356.621079 -226.805177) (xy 356.621588 -226.831144) (xy 356.621079 -226.857111) (xy 356.900735 -226.857111)
			(xy 356.900735 -226.805177) (xy 356.90886 -226.753882) (xy 356.924908 -226.704489) (xy 356.948486 -226.658215)
			(xy 356.979012 -226.616199) (xy 357.015735 -226.579476) (xy 357.057751 -226.54895) (xy 357.104025 -226.525372)
			(xy 357.153418 -226.509324) (xy 357.204713 -226.501199) (xy 357.256647 -226.501199) (xy 357.307942 -226.509324)
			(xy 357.357335 -226.525372) (xy 357.403609 -226.54895) (xy 357.445625 -226.579476) (xy 357.482348 -226.616199)
			(xy 357.512874 -226.658215) (xy 357.536452 -226.704489) (xy 357.5525 -226.753882) (xy 357.560625 -226.805177)
			(xy 357.561134 -226.831144) (xy 357.560625 -226.857111) (xy 357.840789 -226.857111) (xy 357.840789 -226.805177)
			(xy 357.848914 -226.753882) (xy 357.864962 -226.704489) (xy 357.88854 -226.658215) (xy 357.919066 -226.616199)
			(xy 357.955789 -226.579476) (xy 357.997805 -226.54895) (xy 358.044079 -226.525372) (xy 358.093472 -226.509324)
			(xy 358.144767 -226.501199) (xy 358.196701 -226.501199) (xy 358.247996 -226.509324) (xy 358.297389 -226.525372)
			(xy 358.343663 -226.54895) (xy 358.385679 -226.579476) (xy 358.422402 -226.616199) (xy 358.452928 -226.658215)
			(xy 358.476506 -226.704489) (xy 358.492554 -226.753882) (xy 358.500679 -226.805177) (xy 358.501188 -226.831144)
			(xy 358.500679 -226.857111) (xy 358.780335 -226.857111) (xy 358.780335 -226.805177) (xy 358.78846 -226.753882)
			(xy 358.804508 -226.704489) (xy 358.828086 -226.658215) (xy 358.858612 -226.616199) (xy 358.895335 -226.579476)
			(xy 358.937351 -226.54895) (xy 358.983625 -226.525372) (xy 359.033018 -226.509324) (xy 359.084313 -226.501199)
			(xy 359.136247 -226.501199) (xy 359.187542 -226.509324) (xy 359.236935 -226.525372) (xy 359.283209 -226.54895)
			(xy 359.325225 -226.579476) (xy 359.361948 -226.616199) (xy 359.392474 -226.658215) (xy 359.416052 -226.704489)
			(xy 359.4321 -226.753882) (xy 359.440225 -226.805177) (xy 359.440734 -226.831144) (xy 359.440225 -226.857111)
			(xy 359.720389 -226.857111) (xy 359.720389 -226.805177) (xy 359.728514 -226.753882) (xy 359.744562 -226.704489)
			(xy 359.76814 -226.658215) (xy 359.798666 -226.616199) (xy 359.835389 -226.579476) (xy 359.877405 -226.54895)
			(xy 359.923679 -226.525372) (xy 359.973072 -226.509324) (xy 360.024367 -226.501199) (xy 360.076301 -226.501199)
			(xy 360.127596 -226.509324) (xy 360.176989 -226.525372) (xy 360.223263 -226.54895) (xy 360.265279 -226.579476)
			(xy 360.302002 -226.616199) (xy 360.332528 -226.658215) (xy 360.356106 -226.704489) (xy 360.372154 -226.753882)
			(xy 360.380279 -226.805177) (xy 360.380788 -226.831144) (xy 360.380279 -226.857111) (xy 360.659935 -226.857111)
			(xy 360.659935 -226.805177) (xy 360.66806 -226.753882) (xy 360.684108 -226.704489) (xy 360.707686 -226.658215)
			(xy 360.738212 -226.616199) (xy 360.774935 -226.579476) (xy 360.816951 -226.54895) (xy 360.863225 -226.525372)
			(xy 360.912618 -226.509324) (xy 360.963913 -226.501199) (xy 361.015847 -226.501199) (xy 361.067142 -226.509324)
			(xy 361.116535 -226.525372) (xy 361.162809 -226.54895) (xy 361.204825 -226.579476) (xy 361.241548 -226.616199)
			(xy 361.272074 -226.658215) (xy 361.295652 -226.704489) (xy 361.3117 -226.753882) (xy 361.319825 -226.805177)
			(xy 361.320334 -226.831144) (xy 361.319825 -226.857111) (xy 361.599989 -226.857111) (xy 361.599989 -226.805177)
			(xy 361.608114 -226.753882) (xy 361.624162 -226.704489) (xy 361.64774 -226.658215) (xy 361.678266 -226.616199)
			(xy 361.714989 -226.579476) (xy 361.757005 -226.54895) (xy 361.803279 -226.525372) (xy 361.852672 -226.509324)
			(xy 361.903967 -226.501199) (xy 361.955901 -226.501199) (xy 362.007196 -226.509324) (xy 362.056589 -226.525372)
			(xy 362.102863 -226.54895) (xy 362.144879 -226.579476) (xy 362.181602 -226.616199) (xy 362.212128 -226.658215)
			(xy 362.235706 -226.704489) (xy 362.251754 -226.753882) (xy 362.259879 -226.805177) (xy 362.260388 -226.831144)
			(xy 362.259879 -226.857111) (xy 362.539789 -226.857111) (xy 362.539789 -226.805177) (xy 362.547914 -226.753882)
			(xy 362.563962 -226.704489) (xy 362.58754 -226.658215) (xy 362.618066 -226.616199) (xy 362.654789 -226.579476)
			(xy 362.696805 -226.54895) (xy 362.743079 -226.525372) (xy 362.792472 -226.509324) (xy 362.843767 -226.501199)
			(xy 362.895701 -226.501199) (xy 362.946996 -226.509324) (xy 362.996389 -226.525372) (xy 363.042663 -226.54895)
			(xy 363.084679 -226.579476) (xy 363.121402 -226.616199) (xy 363.151928 -226.658215) (xy 363.175506 -226.704489)
			(xy 363.191554 -226.753882) (xy 363.199679 -226.805177) (xy 363.200188 -226.831144) (xy 363.199679 -226.857111)
			(xy 363.479589 -226.857111) (xy 363.479589 -226.805177) (xy 363.487714 -226.753882) (xy 363.503762 -226.704489)
			(xy 363.52734 -226.658215) (xy 363.557866 -226.616199) (xy 363.594589 -226.579476) (xy 363.636605 -226.54895)
			(xy 363.682879 -226.525372) (xy 363.732272 -226.509324) (xy 363.783567 -226.501199) (xy 363.835501 -226.501199)
			(xy 363.886796 -226.509324) (xy 363.936189 -226.525372) (xy 363.982463 -226.54895) (xy 364.024479 -226.579476)
			(xy 364.061202 -226.616199) (xy 364.091728 -226.658215) (xy 364.115306 -226.704489) (xy 364.131354 -226.753882)
			(xy 364.139479 -226.805177) (xy 364.139988 -226.831144) (xy 364.139479 -226.857111) (xy 364.419135 -226.857111)
			(xy 364.419135 -226.805177) (xy 364.42726 -226.753882) (xy 364.443308 -226.704489) (xy 364.466886 -226.658215)
			(xy 364.497412 -226.616199) (xy 364.534135 -226.579476) (xy 364.576151 -226.54895) (xy 364.622425 -226.525372)
			(xy 364.671818 -226.509324) (xy 364.723113 -226.501199) (xy 364.775047 -226.501199) (xy 364.826342 -226.509324)
			(xy 364.875735 -226.525372) (xy 364.922009 -226.54895) (xy 364.964025 -226.579476) (xy 365.000748 -226.616199)
			(xy 365.031274 -226.658215) (xy 365.054852 -226.704489) (xy 365.0709 -226.753882) (xy 365.079025 -226.805177)
			(xy 365.079534 -226.831144) (xy 365.079025 -226.857111) (xy 365.359189 -226.857111) (xy 365.359189 -226.805177)
			(xy 365.367314 -226.753882) (xy 365.383362 -226.704489) (xy 365.40694 -226.658215) (xy 365.437466 -226.616199)
			(xy 365.474189 -226.579476) (xy 365.516205 -226.54895) (xy 365.562479 -226.525372) (xy 365.611872 -226.509324)
			(xy 365.663167 -226.501199) (xy 365.715101 -226.501199) (xy 365.766396 -226.509324) (xy 365.815789 -226.525372)
			(xy 365.862063 -226.54895) (xy 365.904079 -226.579476) (xy 365.940802 -226.616199) (xy 365.971328 -226.658215)
			(xy 365.994906 -226.704489) (xy 366.010954 -226.753882) (xy 366.019079 -226.805177) (xy 366.019588 -226.831144)
			(xy 366.019079 -226.857111) (xy 366.298735 -226.857111) (xy 366.298735 -226.805177) (xy 366.30686 -226.753882)
			(xy 366.322908 -226.704489) (xy 366.346486 -226.658215) (xy 366.377012 -226.616199) (xy 366.413735 -226.579476)
			(xy 366.455751 -226.54895) (xy 366.502025 -226.525372) (xy 366.551418 -226.509324) (xy 366.602713 -226.501199)
			(xy 366.654647 -226.501199) (xy 366.705942 -226.509324) (xy 366.755335 -226.525372) (xy 366.801609 -226.54895)
			(xy 366.843625 -226.579476) (xy 366.880348 -226.616199) (xy 366.910874 -226.658215) (xy 366.934452 -226.704489)
			(xy 366.9505 -226.753882) (xy 366.958625 -226.805177) (xy 366.959134 -226.831144) (xy 366.958625 -226.857111)
			(xy 367.238789 -226.857111) (xy 367.238789 -226.805177) (xy 367.246914 -226.753882) (xy 367.262962 -226.704489)
			(xy 367.28654 -226.658215) (xy 367.317066 -226.616199) (xy 367.353789 -226.579476) (xy 367.395805 -226.54895)
			(xy 367.442079 -226.525372) (xy 367.491472 -226.509324) (xy 367.542767 -226.501199) (xy 367.594701 -226.501199)
			(xy 367.645996 -226.509324) (xy 367.695389 -226.525372) (xy 367.741663 -226.54895) (xy 367.783679 -226.579476)
			(xy 367.820402 -226.616199) (xy 367.850928 -226.658215) (xy 367.874506 -226.704489) (xy 367.890554 -226.753882)
			(xy 367.898679 -226.805177) (xy 367.899188 -226.831144) (xy 367.898679 -226.857111) (xy 368.178335 -226.857111)
			(xy 368.178335 -226.805177) (xy 368.18646 -226.753882) (xy 368.202508 -226.704489) (xy 368.226086 -226.658215)
			(xy 368.256612 -226.616199) (xy 368.293335 -226.579476) (xy 368.335351 -226.54895) (xy 368.381625 -226.525372)
			(xy 368.431018 -226.509324) (xy 368.482313 -226.501199) (xy 368.534247 -226.501199) (xy 368.585542 -226.509324)
			(xy 368.634935 -226.525372) (xy 368.681209 -226.54895) (xy 368.723225 -226.579476) (xy 368.759948 -226.616199)
			(xy 368.790474 -226.658215) (xy 368.814052 -226.704489) (xy 368.8301 -226.753882) (xy 368.838225 -226.805177)
			(xy 368.838734 -226.831144) (xy 368.838225 -226.857111) (xy 368.8301 -226.908406) (xy 368.814052 -226.957799)
			(xy 368.790474 -227.004073) (xy 368.759948 -227.046089) (xy 368.723225 -227.082812) (xy 368.681209 -227.113338)
			(xy 368.634935 -227.136916) (xy 368.585542 -227.152964) (xy 368.534247 -227.161089) (xy 368.482313 -227.161089)
			(xy 368.431018 -227.152964) (xy 368.381625 -227.136916) (xy 368.335351 -227.113338) (xy 368.293335 -227.082812)
			(xy 368.256612 -227.046089) (xy 368.226086 -227.004073) (xy 368.202508 -226.957799) (xy 368.18646 -226.908406)
			(xy 368.178335 -226.857111) (xy 367.898679 -226.857111) (xy 367.890554 -226.908406) (xy 367.874506 -226.957799)
			(xy 367.850928 -227.004073) (xy 367.820402 -227.046089) (xy 367.783679 -227.082812) (xy 367.741663 -227.113338)
			(xy 367.695389 -227.136916) (xy 367.645996 -227.152964) (xy 367.594701 -227.161089) (xy 367.542767 -227.161089)
			(xy 367.491472 -227.152964) (xy 367.442079 -227.136916) (xy 367.395805 -227.113338) (xy 367.353789 -227.082812)
			(xy 367.317066 -227.046089) (xy 367.28654 -227.004073) (xy 367.262962 -226.957799) (xy 367.246914 -226.908406)
			(xy 367.238789 -226.857111) (xy 366.958625 -226.857111) (xy 366.9505 -226.908406) (xy 366.934452 -226.957799)
			(xy 366.910874 -227.004073) (xy 366.880348 -227.046089) (xy 366.843625 -227.082812) (xy 366.801609 -227.113338)
			(xy 366.755335 -227.136916) (xy 366.705942 -227.152964) (xy 366.654647 -227.161089) (xy 366.602713 -227.161089)
			(xy 366.551418 -227.152964) (xy 366.502025 -227.136916) (xy 366.455751 -227.113338) (xy 366.413735 -227.082812)
			(xy 366.377012 -227.046089) (xy 366.346486 -227.004073) (xy 366.322908 -226.957799) (xy 366.30686 -226.908406)
			(xy 366.298735 -226.857111) (xy 366.019079 -226.857111) (xy 366.010954 -226.908406) (xy 365.994906 -226.957799)
			(xy 365.971328 -227.004073) (xy 365.940802 -227.046089) (xy 365.904079 -227.082812) (xy 365.862063 -227.113338)
			(xy 365.815789 -227.136916) (xy 365.766396 -227.152964) (xy 365.715101 -227.161089) (xy 365.663167 -227.161089)
			(xy 365.611872 -227.152964) (xy 365.562479 -227.136916) (xy 365.516205 -227.113338) (xy 365.474189 -227.082812)
			(xy 365.437466 -227.046089) (xy 365.40694 -227.004073) (xy 365.383362 -226.957799) (xy 365.367314 -226.908406)
			(xy 365.359189 -226.857111) (xy 365.079025 -226.857111) (xy 365.0709 -226.908406) (xy 365.054852 -226.957799)
			(xy 365.031274 -227.004073) (xy 365.000748 -227.046089) (xy 364.964025 -227.082812) (xy 364.922009 -227.113338)
			(xy 364.875735 -227.136916) (xy 364.826342 -227.152964) (xy 364.775047 -227.161089) (xy 364.723113 -227.161089)
			(xy 364.671818 -227.152964) (xy 364.622425 -227.136916) (xy 364.576151 -227.113338) (xy 364.534135 -227.082812)
			(xy 364.497412 -227.046089) (xy 364.466886 -227.004073) (xy 364.443308 -226.957799) (xy 364.42726 -226.908406)
			(xy 364.419135 -226.857111) (xy 364.139479 -226.857111) (xy 364.131354 -226.908406) (xy 364.115306 -226.957799)
			(xy 364.091728 -227.004073) (xy 364.061202 -227.046089) (xy 364.024479 -227.082812) (xy 363.982463 -227.113338)
			(xy 363.936189 -227.136916) (xy 363.886796 -227.152964) (xy 363.835501 -227.161089) (xy 363.783567 -227.161089)
			(xy 363.732272 -227.152964) (xy 363.682879 -227.136916) (xy 363.636605 -227.113338) (xy 363.594589 -227.082812)
			(xy 363.557866 -227.046089) (xy 363.52734 -227.004073) (xy 363.503762 -226.957799) (xy 363.487714 -226.908406)
			(xy 363.479589 -226.857111) (xy 363.199679 -226.857111) (xy 363.191554 -226.908406) (xy 363.175506 -226.957799)
			(xy 363.151928 -227.004073) (xy 363.121402 -227.046089) (xy 363.084679 -227.082812) (xy 363.042663 -227.113338)
			(xy 362.996389 -227.136916) (xy 362.946996 -227.152964) (xy 362.895701 -227.161089) (xy 362.843767 -227.161089)
			(xy 362.792472 -227.152964) (xy 362.743079 -227.136916) (xy 362.696805 -227.113338) (xy 362.654789 -227.082812)
			(xy 362.618066 -227.046089) (xy 362.58754 -227.004073) (xy 362.563962 -226.957799) (xy 362.547914 -226.908406)
			(xy 362.539789 -226.857111) (xy 362.259879 -226.857111) (xy 362.251754 -226.908406) (xy 362.235706 -226.957799)
			(xy 362.212128 -227.004073) (xy 362.181602 -227.046089) (xy 362.144879 -227.082812) (xy 362.102863 -227.113338)
			(xy 362.056589 -227.136916) (xy 362.007196 -227.152964) (xy 361.955901 -227.161089) (xy 361.903967 -227.161089)
			(xy 361.852672 -227.152964) (xy 361.803279 -227.136916) (xy 361.757005 -227.113338) (xy 361.714989 -227.082812)
			(xy 361.678266 -227.046089) (xy 361.64774 -227.004073) (xy 361.624162 -226.957799) (xy 361.608114 -226.908406)
			(xy 361.599989 -226.857111) (xy 361.319825 -226.857111) (xy 361.3117 -226.908406) (xy 361.295652 -226.957799)
			(xy 361.272074 -227.004073) (xy 361.241548 -227.046089) (xy 361.204825 -227.082812) (xy 361.162809 -227.113338)
			(xy 361.116535 -227.136916) (xy 361.067142 -227.152964) (xy 361.015847 -227.161089) (xy 360.963913 -227.161089)
			(xy 360.912618 -227.152964) (xy 360.863225 -227.136916) (xy 360.816951 -227.113338) (xy 360.774935 -227.082812)
			(xy 360.738212 -227.046089) (xy 360.707686 -227.004073) (xy 360.684108 -226.957799) (xy 360.66806 -226.908406)
			(xy 360.659935 -226.857111) (xy 360.380279 -226.857111) (xy 360.372154 -226.908406) (xy 360.356106 -226.957799)
			(xy 360.332528 -227.004073) (xy 360.302002 -227.046089) (xy 360.265279 -227.082812) (xy 360.223263 -227.113338)
			(xy 360.176989 -227.136916) (xy 360.127596 -227.152964) (xy 360.076301 -227.161089) (xy 360.024367 -227.161089)
			(xy 359.973072 -227.152964) (xy 359.923679 -227.136916) (xy 359.877405 -227.113338) (xy 359.835389 -227.082812)
			(xy 359.798666 -227.046089) (xy 359.76814 -227.004073) (xy 359.744562 -226.957799) (xy 359.728514 -226.908406)
			(xy 359.720389 -226.857111) (xy 359.440225 -226.857111) (xy 359.4321 -226.908406) (xy 359.416052 -226.957799)
			(xy 359.392474 -227.004073) (xy 359.361948 -227.046089) (xy 359.325225 -227.082812) (xy 359.283209 -227.113338)
			(xy 359.236935 -227.136916) (xy 359.187542 -227.152964) (xy 359.136247 -227.161089) (xy 359.084313 -227.161089)
			(xy 359.033018 -227.152964) (xy 358.983625 -227.136916) (xy 358.937351 -227.113338) (xy 358.895335 -227.082812)
			(xy 358.858612 -227.046089) (xy 358.828086 -227.004073) (xy 358.804508 -226.957799) (xy 358.78846 -226.908406)
			(xy 358.780335 -226.857111) (xy 358.500679 -226.857111) (xy 358.492554 -226.908406) (xy 358.476506 -226.957799)
			(xy 358.452928 -227.004073) (xy 358.422402 -227.046089) (xy 358.385679 -227.082812) (xy 358.343663 -227.113338)
			(xy 358.297389 -227.136916) (xy 358.247996 -227.152964) (xy 358.196701 -227.161089) (xy 358.144767 -227.161089)
			(xy 358.093472 -227.152964) (xy 358.044079 -227.136916) (xy 357.997805 -227.113338) (xy 357.955789 -227.082812)
			(xy 357.919066 -227.046089) (xy 357.88854 -227.004073) (xy 357.864962 -226.957799) (xy 357.848914 -226.908406)
			(xy 357.840789 -226.857111) (xy 357.560625 -226.857111) (xy 357.5525 -226.908406) (xy 357.536452 -226.957799)
			(xy 357.512874 -227.004073) (xy 357.482348 -227.046089) (xy 357.445625 -227.082812) (xy 357.403609 -227.113338)
			(xy 357.357335 -227.136916) (xy 357.307942 -227.152964) (xy 357.256647 -227.161089) (xy 357.204713 -227.161089)
			(xy 357.153418 -227.152964) (xy 357.104025 -227.136916) (xy 357.057751 -227.113338) (xy 357.015735 -227.082812)
			(xy 356.979012 -227.046089) (xy 356.948486 -227.004073) (xy 356.924908 -226.957799) (xy 356.90886 -226.908406)
			(xy 356.900735 -226.857111) (xy 356.621079 -226.857111) (xy 356.612954 -226.908406) (xy 356.596906 -226.957799)
			(xy 356.573328 -227.004073) (xy 356.542802 -227.046089) (xy 356.506079 -227.082812) (xy 356.464063 -227.113338)
			(xy 356.417789 -227.136916) (xy 356.368396 -227.152964) (xy 356.317101 -227.161089) (xy 356.265167 -227.161089)
			(xy 356.213872 -227.152964) (xy 356.164479 -227.136916) (xy 356.118205 -227.113338) (xy 356.076189 -227.082812)
			(xy 356.039466 -227.046089) (xy 356.00894 -227.004073) (xy 355.985362 -226.957799) (xy 355.969314 -226.908406)
			(xy 355.961189 -226.857111) (xy 355.681025 -226.857111) (xy 355.6729 -226.908406) (xy 355.656852 -226.957799)
			(xy 355.633274 -227.004073) (xy 355.602748 -227.046089) (xy 355.566025 -227.082812) (xy 355.524009 -227.113338)
			(xy 355.477735 -227.136916) (xy 355.428342 -227.152964) (xy 355.377047 -227.161089) (xy 355.325113 -227.161089)
			(xy 355.273818 -227.152964) (xy 355.224425 -227.136916) (xy 355.178151 -227.113338) (xy 355.136135 -227.082812)
			(xy 355.099412 -227.046089) (xy 355.068886 -227.004073) (xy 355.045308 -226.957799) (xy 355.02926 -226.908406)
			(xy 355.021135 -226.857111) (xy 354.741479 -226.857111) (xy 354.733354 -226.908406) (xy 354.717306 -226.957799)
			(xy 354.693728 -227.004073) (xy 354.663202 -227.046089) (xy 354.626479 -227.082812) (xy 354.584463 -227.113338)
			(xy 354.538189 -227.136916) (xy 354.488796 -227.152964) (xy 354.437501 -227.161089) (xy 354.385567 -227.161089)
			(xy 354.334272 -227.152964) (xy 354.284879 -227.136916) (xy 354.238605 -227.113338) (xy 354.196589 -227.082812)
			(xy 354.159866 -227.046089) (xy 354.12934 -227.004073) (xy 354.105762 -226.957799) (xy 354.089714 -226.908406)
			(xy 354.081589 -226.857111) (xy 353.801425 -226.857111) (xy 353.7933 -226.908406) (xy 353.777252 -226.957799)
			(xy 353.753674 -227.004073) (xy 353.723148 -227.046089) (xy 353.686425 -227.082812) (xy 353.644409 -227.113338)
			(xy 353.598135 -227.136916) (xy 353.548742 -227.152964) (xy 353.497447 -227.161089) (xy 353.445513 -227.161089)
			(xy 353.394218 -227.152964) (xy 353.344825 -227.136916) (xy 353.298551 -227.113338) (xy 353.256535 -227.082812)
			(xy 353.219812 -227.046089) (xy 353.189286 -227.004073) (xy 353.165708 -226.957799) (xy 353.14966 -226.908406)
			(xy 353.141535 -226.857111) (xy 352.861879 -226.857111) (xy 352.853754 -226.908406) (xy 352.837706 -226.957799)
			(xy 352.814128 -227.004073) (xy 352.783602 -227.046089) (xy 352.746879 -227.082812) (xy 352.704863 -227.113338)
			(xy 352.658589 -227.136916) (xy 352.609196 -227.152964) (xy 352.557901 -227.161089) (xy 352.505967 -227.161089)
			(xy 352.454672 -227.152964) (xy 352.405279 -227.136916) (xy 352.359005 -227.113338) (xy 352.316989 -227.082812)
			(xy 352.280266 -227.046089) (xy 352.24974 -227.004073) (xy 352.226162 -226.957799) (xy 352.210114 -226.908406)
			(xy 352.201989 -226.857111) (xy 351.922079 -226.857111) (xy 351.913954 -226.908406) (xy 351.897906 -226.957799)
			(xy 351.874328 -227.004073) (xy 351.843802 -227.046089) (xy 351.807079 -227.082812) (xy 351.765063 -227.113338)
			(xy 351.718789 -227.136916) (xy 351.669396 -227.152964) (xy 351.618101 -227.161089) (xy 351.566167 -227.161089)
			(xy 351.514872 -227.152964) (xy 351.465479 -227.136916) (xy 351.419205 -227.113338) (xy 351.377189 -227.082812)
			(xy 351.340466 -227.046089) (xy 351.30994 -227.004073) (xy 351.286362 -226.957799) (xy 351.270314 -226.908406)
			(xy 351.262189 -226.857111) (xy 350.982025 -226.857111) (xy 350.9739 -226.908406) (xy 350.957852 -226.957799)
			(xy 350.934274 -227.004073) (xy 350.903748 -227.046089) (xy 350.867025 -227.082812) (xy 350.825009 -227.113338)
			(xy 350.778735 -227.136916) (xy 350.729342 -227.152964) (xy 350.678047 -227.161089) (xy 350.626113 -227.161089)
			(xy 350.574818 -227.152964) (xy 350.525425 -227.136916) (xy 350.479151 -227.113338) (xy 350.437135 -227.082812)
			(xy 350.400412 -227.046089) (xy 350.369886 -227.004073) (xy 350.346308 -226.957799) (xy 350.33026 -226.908406)
			(xy 350.322135 -226.857111) (xy 350.092264 -226.857111) (xy 350.092264 -227.21316) (xy 350.092882 -227.22885)
			(xy 350.102474 -227.258731) (xy 350.120676 -227.284296) (xy 350.145772 -227.303138) (xy 350.175401 -227.313483)
			(xy 350.19107 -227.314506) (xy 350.216593 -227.315645) (xy 350.26685 -227.324815) (xy 350.315097 -227.341611)
			(xy 350.360183 -227.365633) (xy 350.401035 -227.396309) (xy 350.436679 -227.432907) (xy 350.466264 -227.474555)
			(xy 350.489087 -227.520261) (xy 350.504602 -227.568934) (xy 350.512441 -227.619416) (xy 350.512888 -227.64496)
			(xy 350.512379 -227.671216) (xy 350.50407 -227.723068) (xy 350.487671 -227.772954) (xy 350.463595 -227.819622)
			(xy 350.432445 -227.861898) (xy 350.414082 -227.880672) (xy 350.407829 -227.8873) (xy 350.400083 -227.903779)
			(xy 350.398616 -227.921929) (xy 350.403614 -227.939439) (xy 350.408748 -227.946966) (xy 350.429763 -227.976167)
			(xy 350.467415 -228.037477) (xy 350.499831 -228.101709) (xy 350.51365 -228.134926) (xy 350.587564 -228.134926)
			(xy 350.592136 -228.134164) (xy 350.606988 -228.131576) (xy 350.637006 -228.128777) (xy 350.65208 -228.128576)
			(xy 350.667154 -228.128768) (xy 350.697173 -228.13157) (xy 350.712024 -228.134164) (xy 350.716596 -228.134926)
			(xy 351.184464 -228.134926) (xy 351.737422 -227.581968) (xy 351.740724 -227.568252) (xy 351.746839 -227.544474)
			(xy 351.765142 -227.498917) (xy 351.78999 -227.456574) (xy 351.820835 -227.418378) (xy 351.856997 -227.385171)
			(xy 351.897678 -227.357685) (xy 351.941981 -227.336528) (xy 351.988929 -227.322165) (xy 352.037486 -227.314914)
			(xy 352.062034 -227.314506) (xy 352.087897 -227.31501) (xy 352.138991 -227.323076) (xy 352.188203 -227.339006)
			(xy 352.234332 -227.362411) (xy 352.276249 -227.392719) (xy 352.312932 -227.429188) (xy 352.343482 -227.470929)
			(xy 352.367155 -227.516921) (xy 352.375724 -227.541328) (xy 352.387408 -227.576126) (xy 352.67646 -227.576126)
			(xy 352.688144 -227.541328) (xy 352.696718 -227.516917) (xy 352.720374 -227.470907) (xy 352.750914 -227.429148)
			(xy 352.787592 -227.392662) (xy 352.829511 -227.362341) (xy 352.875644 -227.338926) (xy 352.924864 -227.32299)
			(xy 352.975966 -227.314924) (xy 353.027702 -227.314924) (xy 353.078804 -227.32299) (xy 353.128024 -227.338926)
			(xy 353.174157 -227.362341) (xy 353.216076 -227.392662) (xy 353.252754 -227.429148) (xy 353.283294 -227.470907)
			(xy 353.30695 -227.516917) (xy 353.315524 -227.541328) (xy 353.327208 -227.576126) (xy 353.61626 -227.576126)
			(xy 353.627944 -227.541328) (xy 353.636518 -227.516917) (xy 353.660174 -227.470907) (xy 353.690714 -227.429148)
			(xy 353.727392 -227.392662) (xy 353.769311 -227.362341) (xy 353.815444 -227.338926) (xy 353.864664 -227.32299)
			(xy 353.915766 -227.314924) (xy 353.967502 -227.314924) (xy 354.018604 -227.32299) (xy 354.067824 -227.338926)
			(xy 354.113957 -227.362341) (xy 354.155876 -227.392662) (xy 354.192554 -227.429148) (xy 354.223094 -227.470907)
			(xy 354.24675 -227.516917) (xy 354.255324 -227.541328) (xy 354.267008 -227.576126) (xy 354.55606 -227.576126)
			(xy 354.567744 -227.541328) (xy 354.576318 -227.516917) (xy 354.599974 -227.470907) (xy 354.630514 -227.429148)
			(xy 354.667192 -227.392662) (xy 354.709111 -227.362341) (xy 354.755244 -227.338926) (xy 354.804464 -227.32299)
			(xy 354.855566 -227.314924) (xy 354.907302 -227.314924) (xy 354.958404 -227.32299) (xy 355.007624 -227.338926)
			(xy 355.053757 -227.362341) (xy 355.095676 -227.392662) (xy 355.132354 -227.429148) (xy 355.162894 -227.470907)
			(xy 355.18655 -227.516917) (xy 355.195124 -227.541328) (xy 355.206808 -227.576126) (xy 355.49586 -227.576126)
			(xy 355.507544 -227.541328) (xy 355.516118 -227.516917) (xy 355.539774 -227.470907) (xy 355.570314 -227.429148)
			(xy 355.606992 -227.392662) (xy 355.648911 -227.362341) (xy 355.695044 -227.338926) (xy 355.744264 -227.32299)
			(xy 355.795366 -227.314924) (xy 355.847102 -227.314924) (xy 355.898204 -227.32299) (xy 355.947424 -227.338926)
			(xy 355.993557 -227.362341) (xy 356.035476 -227.392662) (xy 356.072154 -227.429148) (xy 356.102694 -227.470907)
			(xy 356.12635 -227.516917) (xy 356.134924 -227.541328) (xy 356.146608 -227.576126) (xy 356.43566 -227.576126)
			(xy 356.447344 -227.541328) (xy 356.455918 -227.516917) (xy 356.479574 -227.470907) (xy 356.510114 -227.429148)
			(xy 356.546792 -227.392662) (xy 356.588711 -227.362341) (xy 356.634844 -227.338926) (xy 356.684064 -227.32299)
			(xy 356.735166 -227.314924) (xy 356.786902 -227.314924) (xy 356.838004 -227.32299) (xy 356.887224 -227.338926)
			(xy 356.933357 -227.362341) (xy 356.975276 -227.392662) (xy 357.011954 -227.429148) (xy 357.042494 -227.470907)
			(xy 357.06615 -227.516917) (xy 357.074724 -227.541328) (xy 357.086408 -227.576126) (xy 357.37546 -227.576126)
			(xy 357.387144 -227.541328) (xy 357.395718 -227.516917) (xy 357.419374 -227.470907) (xy 357.449914 -227.429148)
			(xy 357.486592 -227.392662) (xy 357.528511 -227.362341) (xy 357.574644 -227.338926) (xy 357.623864 -227.32299)
			(xy 357.674966 -227.314924) (xy 357.726702 -227.314924) (xy 357.777804 -227.32299) (xy 357.827024 -227.338926)
			(xy 357.873157 -227.362341) (xy 357.915076 -227.392662) (xy 357.951754 -227.429148) (xy 357.982294 -227.470907)
			(xy 358.00595 -227.516917) (xy 358.014524 -227.541328) (xy 358.026208 -227.576126) (xy 358.31526 -227.576126)
			(xy 358.326944 -227.541328) (xy 358.335518 -227.516917) (xy 358.359174 -227.470907) (xy 358.389714 -227.429148)
			(xy 358.426392 -227.392662) (xy 358.468311 -227.362341) (xy 358.514444 -227.338926) (xy 358.563664 -227.32299)
			(xy 358.614766 -227.314924) (xy 358.666502 -227.314924) (xy 358.717604 -227.32299) (xy 358.766824 -227.338926)
			(xy 358.812957 -227.362341) (xy 358.854876 -227.392662) (xy 358.891554 -227.429148) (xy 358.922094 -227.470907)
			(xy 358.94575 -227.516917) (xy 358.954324 -227.541328) (xy 358.966008 -227.576126) (xy 359.25506 -227.576126)
			(xy 359.266744 -227.541328) (xy 359.275315 -227.51692) (xy 359.298968 -227.470917) (xy 359.329509 -227.429167)
			(xy 359.36619 -227.392694) (xy 359.408112 -227.36239) (xy 359.454248 -227.338997) (xy 359.503469 -227.323089)
			(xy 359.55457 -227.315055) (xy 359.580434 -227.314506) (xy 359.606401 -227.315018) (xy 359.657694 -227.323146)
			(xy 359.707084 -227.339197) (xy 359.753357 -227.362776) (xy 359.795371 -227.393302) (xy 359.832094 -227.430024)
			(xy 359.862621 -227.472038) (xy 359.886201 -227.51831) (xy 359.902253 -227.5677) (xy 359.910382 -227.618993)
			(xy 359.910888 -227.64496) (xy 359.910342 -227.670927) (xy 360.190289 -227.670927) (xy 360.190289 -227.618993)
			(xy 360.198414 -227.567698) (xy 360.214462 -227.518305) (xy 360.23804 -227.472031) (xy 360.268566 -227.430015)
			(xy 360.305289 -227.393292) (xy 360.347305 -227.362766) (xy 360.393579 -227.339188) (xy 360.442972 -227.32314)
			(xy 360.494267 -227.315015) (xy 360.546201 -227.315015) (xy 360.597496 -227.32314) (xy 360.646889 -227.339188)
			(xy 360.693163 -227.362766) (xy 360.735179 -227.393292) (xy 360.771902 -227.430015) (xy 360.802428 -227.472031)
			(xy 360.826006 -227.518305) (xy 360.842054 -227.567698) (xy 360.850179 -227.618993) (xy 360.850688 -227.64496)
			(xy 360.850179 -227.670927) (xy 361.130089 -227.670927) (xy 361.130089 -227.618993) (xy 361.138214 -227.567698)
			(xy 361.154262 -227.518305) (xy 361.17784 -227.472031) (xy 361.208366 -227.430015) (xy 361.245089 -227.393292)
			(xy 361.287105 -227.362766) (xy 361.333379 -227.339188) (xy 361.382772 -227.32314) (xy 361.434067 -227.315015)
			(xy 361.486001 -227.315015) (xy 361.537296 -227.32314) (xy 361.586689 -227.339188) (xy 361.632963 -227.362766)
			(xy 361.674979 -227.393292) (xy 361.711702 -227.430015) (xy 361.742228 -227.472031) (xy 361.765806 -227.518305)
			(xy 361.781854 -227.567698) (xy 361.789979 -227.618993) (xy 361.790488 -227.64496) (xy 361.789979 -227.670927)
			(xy 362.070143 -227.670927) (xy 362.070143 -227.618993) (xy 362.078268 -227.567698) (xy 362.094316 -227.518305)
			(xy 362.117894 -227.472031) (xy 362.14842 -227.430015) (xy 362.185143 -227.393292) (xy 362.227159 -227.362766)
			(xy 362.273433 -227.339188) (xy 362.322826 -227.32314) (xy 362.374121 -227.315015) (xy 362.426055 -227.315015)
			(xy 362.47735 -227.32314) (xy 362.526743 -227.339188) (xy 362.573017 -227.362766) (xy 362.615033 -227.393292)
			(xy 362.651756 -227.430015) (xy 362.682282 -227.472031) (xy 362.70586 -227.518305) (xy 362.721908 -227.567698)
			(xy 362.730033 -227.618993) (xy 362.730542 -227.64496) (xy 362.730033 -227.670927) (xy 363.009689 -227.670927)
			(xy 363.009689 -227.618993) (xy 363.017814 -227.567698) (xy 363.033862 -227.518305) (xy 363.05744 -227.472031)
			(xy 363.087966 -227.430015) (xy 363.124689 -227.393292) (xy 363.166705 -227.362766) (xy 363.212979 -227.339188)
			(xy 363.262372 -227.32314) (xy 363.313667 -227.315015) (xy 363.365601 -227.315015) (xy 363.416896 -227.32314)
			(xy 363.466289 -227.339188) (xy 363.512563 -227.362766) (xy 363.554579 -227.393292) (xy 363.591302 -227.430015)
			(xy 363.621828 -227.472031) (xy 363.645406 -227.518305) (xy 363.661454 -227.567698) (xy 363.669579 -227.618993)
			(xy 363.670088 -227.64496) (xy 363.669579 -227.670927) (xy 363.949489 -227.670927) (xy 363.949489 -227.618993)
			(xy 363.957614 -227.567698) (xy 363.973662 -227.518305) (xy 363.99724 -227.472031) (xy 364.027766 -227.430015)
			(xy 364.064489 -227.393292) (xy 364.106505 -227.362766) (xy 364.152779 -227.339188) (xy 364.202172 -227.32314)
			(xy 364.253467 -227.315015) (xy 364.305401 -227.315015) (xy 364.356696 -227.32314) (xy 364.406089 -227.339188)
			(xy 364.452363 -227.362766) (xy 364.494379 -227.393292) (xy 364.531102 -227.430015) (xy 364.561628 -227.472031)
			(xy 364.585206 -227.518305) (xy 364.601254 -227.567698) (xy 364.609379 -227.618993) (xy 364.609888 -227.64496)
			(xy 364.609379 -227.670927) (xy 364.889289 -227.670927) (xy 364.889289 -227.618993) (xy 364.897414 -227.567698)
			(xy 364.913462 -227.518305) (xy 364.93704 -227.472031) (xy 364.967566 -227.430015) (xy 365.004289 -227.393292)
			(xy 365.046305 -227.362766) (xy 365.092579 -227.339188) (xy 365.141972 -227.32314) (xy 365.193267 -227.315015)
			(xy 365.245201 -227.315015) (xy 365.296496 -227.32314) (xy 365.345889 -227.339188) (xy 365.392163 -227.362766)
			(xy 365.434179 -227.393292) (xy 365.470902 -227.430015) (xy 365.501428 -227.472031) (xy 365.525006 -227.518305)
			(xy 365.541054 -227.567698) (xy 365.549179 -227.618993) (xy 365.549688 -227.64496) (xy 365.549179 -227.670927)
			(xy 365.829089 -227.670927) (xy 365.829089 -227.618993) (xy 365.837214 -227.567698) (xy 365.853262 -227.518305)
			(xy 365.87684 -227.472031) (xy 365.907366 -227.430015) (xy 365.944089 -227.393292) (xy 365.986105 -227.362766)
			(xy 366.032379 -227.339188) (xy 366.081772 -227.32314) (xy 366.133067 -227.315015) (xy 366.185001 -227.315015)
			(xy 366.236296 -227.32314) (xy 366.285689 -227.339188) (xy 366.331963 -227.362766) (xy 366.373979 -227.393292)
			(xy 366.410702 -227.430015) (xy 366.441228 -227.472031) (xy 366.464806 -227.518305) (xy 366.480854 -227.567698)
			(xy 366.488979 -227.618993) (xy 366.489488 -227.64496) (xy 366.488979 -227.670927) (xy 366.768889 -227.670927)
			(xy 366.768889 -227.618993) (xy 366.777014 -227.567698) (xy 366.793062 -227.518305) (xy 366.81664 -227.472031)
			(xy 366.847166 -227.430015) (xy 366.883889 -227.393292) (xy 366.925905 -227.362766) (xy 366.972179 -227.339188)
			(xy 367.021572 -227.32314) (xy 367.072867 -227.315015) (xy 367.124801 -227.315015) (xy 367.176096 -227.32314)
			(xy 367.225489 -227.339188) (xy 367.271763 -227.362766) (xy 367.313779 -227.393292) (xy 367.350502 -227.430015)
			(xy 367.381028 -227.472031) (xy 367.404606 -227.518305) (xy 367.420654 -227.567698) (xy 367.428779 -227.618993)
			(xy 367.429288 -227.64496) (xy 367.428779 -227.670927) (xy 367.708689 -227.670927) (xy 367.708689 -227.618993)
			(xy 367.716814 -227.567698) (xy 367.732862 -227.518305) (xy 367.75644 -227.472031) (xy 367.786966 -227.430015)
			(xy 367.823689 -227.393292) (xy 367.865705 -227.362766) (xy 367.911979 -227.339188) (xy 367.961372 -227.32314)
			(xy 368.012667 -227.315015) (xy 368.064601 -227.315015) (xy 368.115896 -227.32314) (xy 368.165289 -227.339188)
			(xy 368.211563 -227.362766) (xy 368.253579 -227.393292) (xy 368.290302 -227.430015) (xy 368.320828 -227.472031)
			(xy 368.344406 -227.518305) (xy 368.360454 -227.567698) (xy 368.368579 -227.618993) (xy 368.369088 -227.64496)
			(xy 368.368579 -227.670927) (xy 368.648489 -227.670927) (xy 368.648489 -227.618993) (xy 368.656614 -227.567698)
			(xy 368.672662 -227.518305) (xy 368.69624 -227.472031) (xy 368.726766 -227.430015) (xy 368.763489 -227.393292)
			(xy 368.805505 -227.362766) (xy 368.851779 -227.339188) (xy 368.901172 -227.32314) (xy 368.952467 -227.315015)
			(xy 369.004401 -227.315015) (xy 369.055696 -227.32314) (xy 369.105089 -227.339188) (xy 369.151363 -227.362766)
			(xy 369.193379 -227.393292) (xy 369.230102 -227.430015) (xy 369.260628 -227.472031) (xy 369.284206 -227.518305)
			(xy 369.300254 -227.567698) (xy 369.308379 -227.618993) (xy 369.308888 -227.64496) (xy 369.308379 -227.670927)
			(xy 369.300254 -227.722222) (xy 369.284206 -227.771615) (xy 369.260628 -227.817889) (xy 369.230102 -227.859905)
			(xy 369.193379 -227.896628) (xy 369.151363 -227.927154) (xy 369.105089 -227.950732) (xy 369.055696 -227.96678)
			(xy 369.004401 -227.974905) (xy 368.952467 -227.974905) (xy 368.901172 -227.96678) (xy 368.851779 -227.950732)
			(xy 368.805505 -227.927154) (xy 368.763489 -227.896628) (xy 368.726766 -227.859905) (xy 368.69624 -227.817889)
			(xy 368.672662 -227.771615) (xy 368.656614 -227.722222) (xy 368.648489 -227.670927) (xy 368.368579 -227.670927)
			(xy 368.360454 -227.722222) (xy 368.344406 -227.771615) (xy 368.320828 -227.817889) (xy 368.290302 -227.859905)
			(xy 368.253579 -227.896628) (xy 368.211563 -227.927154) (xy 368.165289 -227.950732) (xy 368.115896 -227.96678)
			(xy 368.064601 -227.974905) (xy 368.012667 -227.974905) (xy 367.961372 -227.96678) (xy 367.911979 -227.950732)
			(xy 367.865705 -227.927154) (xy 367.823689 -227.896628) (xy 367.786966 -227.859905) (xy 367.75644 -227.817889)
			(xy 367.732862 -227.771615) (xy 367.716814 -227.722222) (xy 367.708689 -227.670927) (xy 367.428779 -227.670927)
			(xy 367.420654 -227.722222) (xy 367.404606 -227.771615) (xy 367.381028 -227.817889) (xy 367.350502 -227.859905)
			(xy 367.313779 -227.896628) (xy 367.271763 -227.927154) (xy 367.225489 -227.950732) (xy 367.176096 -227.96678)
			(xy 367.124801 -227.974905) (xy 367.072867 -227.974905) (xy 367.021572 -227.96678) (xy 366.972179 -227.950732)
			(xy 366.925905 -227.927154) (xy 366.883889 -227.896628) (xy 366.847166 -227.859905) (xy 366.81664 -227.817889)
			(xy 366.793062 -227.771615) (xy 366.777014 -227.722222) (xy 366.768889 -227.670927) (xy 366.488979 -227.670927)
			(xy 366.480854 -227.722222) (xy 366.464806 -227.771615) (xy 366.441228 -227.817889) (xy 366.410702 -227.859905)
			(xy 366.373979 -227.896628) (xy 366.331963 -227.927154) (xy 366.285689 -227.950732) (xy 366.236296 -227.96678)
			(xy 366.185001 -227.974905) (xy 366.133067 -227.974905) (xy 366.081772 -227.96678) (xy 366.032379 -227.950732)
			(xy 365.986105 -227.927154) (xy 365.944089 -227.896628) (xy 365.907366 -227.859905) (xy 365.87684 -227.817889)
			(xy 365.853262 -227.771615) (xy 365.837214 -227.722222) (xy 365.829089 -227.670927) (xy 365.549179 -227.670927)
			(xy 365.541054 -227.722222) (xy 365.525006 -227.771615) (xy 365.501428 -227.817889) (xy 365.470902 -227.859905)
			(xy 365.434179 -227.896628) (xy 365.392163 -227.927154) (xy 365.345889 -227.950732) (xy 365.296496 -227.96678)
			(xy 365.245201 -227.974905) (xy 365.193267 -227.974905) (xy 365.141972 -227.96678) (xy 365.092579 -227.950732)
			(xy 365.046305 -227.927154) (xy 365.004289 -227.896628) (xy 364.967566 -227.859905) (xy 364.93704 -227.817889)
			(xy 364.913462 -227.771615) (xy 364.897414 -227.722222) (xy 364.889289 -227.670927) (xy 364.609379 -227.670927)
			(xy 364.601254 -227.722222) (xy 364.585206 -227.771615) (xy 364.561628 -227.817889) (xy 364.531102 -227.859905)
			(xy 364.494379 -227.896628) (xy 364.452363 -227.927154) (xy 364.406089 -227.950732) (xy 364.356696 -227.96678)
			(xy 364.305401 -227.974905) (xy 364.253467 -227.974905) (xy 364.202172 -227.96678) (xy 364.152779 -227.950732)
			(xy 364.106505 -227.927154) (xy 364.064489 -227.896628) (xy 364.027766 -227.859905) (xy 363.99724 -227.817889)
			(xy 363.973662 -227.771615) (xy 363.957614 -227.722222) (xy 363.949489 -227.670927) (xy 363.669579 -227.670927)
			(xy 363.661454 -227.722222) (xy 363.645406 -227.771615) (xy 363.621828 -227.817889) (xy 363.591302 -227.859905)
			(xy 363.554579 -227.896628) (xy 363.512563 -227.927154) (xy 363.466289 -227.950732) (xy 363.416896 -227.96678)
			(xy 363.365601 -227.974905) (xy 363.313667 -227.974905) (xy 363.262372 -227.96678) (xy 363.212979 -227.950732)
			(xy 363.166705 -227.927154) (xy 363.124689 -227.896628) (xy 363.087966 -227.859905) (xy 363.05744 -227.817889)
			(xy 363.033862 -227.771615) (xy 363.017814 -227.722222) (xy 363.009689 -227.670927) (xy 362.730033 -227.670927)
			(xy 362.721908 -227.722222) (xy 362.70586 -227.771615) (xy 362.682282 -227.817889) (xy 362.651756 -227.859905)
			(xy 362.615033 -227.896628) (xy 362.573017 -227.927154) (xy 362.526743 -227.950732) (xy 362.47735 -227.96678)
			(xy 362.426055 -227.974905) (xy 362.374121 -227.974905) (xy 362.322826 -227.96678) (xy 362.273433 -227.950732)
			(xy 362.227159 -227.927154) (xy 362.185143 -227.896628) (xy 362.14842 -227.859905) (xy 362.117894 -227.817889)
			(xy 362.094316 -227.771615) (xy 362.078268 -227.722222) (xy 362.070143 -227.670927) (xy 361.789979 -227.670927)
			(xy 361.781854 -227.722222) (xy 361.765806 -227.771615) (xy 361.742228 -227.817889) (xy 361.711702 -227.859905)
			(xy 361.674979 -227.896628) (xy 361.632963 -227.927154) (xy 361.586689 -227.950732) (xy 361.537296 -227.96678)
			(xy 361.486001 -227.974905) (xy 361.434067 -227.974905) (xy 361.382772 -227.96678) (xy 361.333379 -227.950732)
			(xy 361.287105 -227.927154) (xy 361.245089 -227.896628) (xy 361.208366 -227.859905) (xy 361.17784 -227.817889)
			(xy 361.154262 -227.771615) (xy 361.138214 -227.722222) (xy 361.130089 -227.670927) (xy 360.850179 -227.670927)
			(xy 360.842054 -227.722222) (xy 360.826006 -227.771615) (xy 360.802428 -227.817889) (xy 360.771902 -227.859905)
			(xy 360.735179 -227.896628) (xy 360.693163 -227.927154) (xy 360.646889 -227.950732) (xy 360.597496 -227.96678)
			(xy 360.546201 -227.974905) (xy 360.494267 -227.974905) (xy 360.442972 -227.96678) (xy 360.393579 -227.950732)
			(xy 360.347305 -227.927154) (xy 360.305289 -227.896628) (xy 360.268566 -227.859905) (xy 360.23804 -227.817889)
			(xy 360.214462 -227.771615) (xy 360.198414 -227.722222) (xy 360.190289 -227.670927) (xy 359.910342 -227.670927)
			(xy 359.910328 -227.671574) (xy 359.901751 -227.724109) (xy 359.884878 -227.774593) (xy 359.860143 -227.821727)
			(xy 359.844594 -227.843334) (xy 359.818178 -227.87864) (xy 360.068114 -228.128576) (xy 360.085894 -228.130608)
			(xy 360.110555 -228.133748) (xy 360.15861 -228.146479) (xy 360.204214 -228.166267) (xy 360.246338 -228.192665)
			(xy 360.284031 -228.225077) (xy 360.316442 -228.262771) (xy 360.342838 -228.304896) (xy 360.362625 -228.350501)
			(xy 360.375354 -228.398556) (xy 360.378502 -228.423216) (xy 360.380534 -228.440996) (xy 360.486198 -228.54666)
			(xy 360.496062 -228.555932) (xy 360.519547 -228.569377) (xy 360.545739 -228.576182) (xy 360.572798 -228.57587)
			(xy 360.598826 -228.568462) (xy 360.621995 -228.554478) (xy 360.640677 -228.534901) (xy 360.653563 -228.511104)
			(xy 360.659746 -228.484759) (xy 360.65968 -228.471222) (xy 360.659426 -228.45903) (xy 360.659907 -228.433058)
			(xy 360.668028 -228.381754) (xy 360.684075 -228.332351) (xy 360.707654 -228.286068) (xy 360.738182 -228.244042)
			(xy 360.774909 -228.20731) (xy 360.816931 -228.176776) (xy 360.863211 -228.153192) (xy 360.912611 -228.137138)
			(xy 360.963915 -228.12901) (xy 361.015858 -228.129008) (xy 361.067163 -228.137132) (xy 361.116564 -228.153182)
			(xy 361.162847 -228.176762) (xy 361.20487 -228.207293) (xy 361.2416 -228.244022) (xy 361.272132 -228.286045)
			(xy 361.295714 -228.332327) (xy 361.311766 -228.381728) (xy 361.319891 -228.433032) (xy 361.319891 -228.484975)
			(xy 361.319888 -228.484997) (xy 361.599735 -228.484997) (xy 361.599735 -228.433063) (xy 361.60786 -228.381768)
			(xy 361.623908 -228.332375) (xy 361.647486 -228.286101) (xy 361.678012 -228.244085) (xy 361.714735 -228.207362)
			(xy 361.756751 -228.176836) (xy 361.803025 -228.153258) (xy 361.852418 -228.13721) (xy 361.903713 -228.129085)
			(xy 361.955647 -228.129085) (xy 362.006942 -228.13721) (xy 362.056335 -228.153258) (xy 362.102609 -228.176836)
			(xy 362.144625 -228.207362) (xy 362.181348 -228.244085) (xy 362.211874 -228.286101) (xy 362.235452 -228.332375)
			(xy 362.2515 -228.381768) (xy 362.259625 -228.433063) (xy 362.260134 -228.45903) (xy 362.259625 -228.484997)
			(xy 363.479335 -228.484997) (xy 363.479335 -228.433063) (xy 363.48746 -228.381768) (xy 363.503508 -228.332375)
			(xy 363.527086 -228.286101) (xy 363.557612 -228.244085) (xy 363.594335 -228.207362) (xy 363.636351 -228.176836)
			(xy 363.682625 -228.153258) (xy 363.732018 -228.13721) (xy 363.783313 -228.129085) (xy 363.835247 -228.129085)
			(xy 363.886542 -228.13721) (xy 363.935935 -228.153258) (xy 363.982209 -228.176836) (xy 364.024225 -228.207362)
			(xy 364.060948 -228.244085) (xy 364.091474 -228.286101) (xy 364.115052 -228.332375) (xy 364.1311 -228.381768)
			(xy 364.139225 -228.433063) (xy 364.139734 -228.45903) (xy 364.139225 -228.484997) (xy 365.358935 -228.484997)
			(xy 365.358935 -228.433063) (xy 365.36706 -228.381768) (xy 365.383108 -228.332375) (xy 365.406686 -228.286101)
			(xy 365.437212 -228.244085) (xy 365.473935 -228.207362) (xy 365.515951 -228.176836) (xy 365.562225 -228.153258)
			(xy 365.611618 -228.13721) (xy 365.662913 -228.129085) (xy 365.714847 -228.129085) (xy 365.766142 -228.13721)
			(xy 365.815535 -228.153258) (xy 365.861809 -228.176836) (xy 365.903825 -228.207362) (xy 365.940548 -228.244085)
			(xy 365.971074 -228.286101) (xy 365.994652 -228.332375) (xy 366.0107 -228.381768) (xy 366.018825 -228.433063)
			(xy 366.019334 -228.45903) (xy 366.018825 -228.484997) (xy 367.238535 -228.484997) (xy 367.238535 -228.433063)
			(xy 367.24666 -228.381768) (xy 367.262708 -228.332375) (xy 367.286286 -228.286101) (xy 367.316812 -228.244085)
			(xy 367.353535 -228.207362) (xy 367.395551 -228.176836) (xy 367.441825 -228.153258) (xy 367.491218 -228.13721)
			(xy 367.542513 -228.129085) (xy 367.594447 -228.129085) (xy 367.645742 -228.13721) (xy 367.695135 -228.153258)
			(xy 367.741409 -228.176836) (xy 367.783425 -228.207362) (xy 367.820148 -228.244085) (xy 367.850674 -228.286101)
			(xy 367.874252 -228.332375) (xy 367.8903 -228.381768) (xy 367.898425 -228.433063) (xy 367.898934 -228.45903)
			(xy 367.898425 -228.484997) (xy 368.178335 -228.484997) (xy 368.178335 -228.433063) (xy 368.18646 -228.381768)
			(xy 368.202508 -228.332375) (xy 368.226086 -228.286101) (xy 368.256612 -228.244085) (xy 368.293335 -228.207362)
			(xy 368.335351 -228.176836) (xy 368.381625 -228.153258) (xy 368.431018 -228.13721) (xy 368.482313 -228.129085)
			(xy 368.534247 -228.129085) (xy 368.585542 -228.13721) (xy 368.634935 -228.153258) (xy 368.681209 -228.176836)
			(xy 368.723225 -228.207362) (xy 368.759948 -228.244085) (xy 368.790474 -228.286101) (xy 368.814052 -228.332375)
			(xy 368.8301 -228.381768) (xy 368.838225 -228.433063) (xy 368.838734 -228.45903) (xy 368.838225 -228.484997)
			(xy 369.118135 -228.484997) (xy 369.118135 -228.433063) (xy 369.12626 -228.381768) (xy 369.142308 -228.332375)
			(xy 369.165886 -228.286101) (xy 369.196412 -228.244085) (xy 369.233135 -228.207362) (xy 369.275151 -228.176836)
			(xy 369.321425 -228.153258) (xy 369.370818 -228.13721) (xy 369.422113 -228.129085) (xy 369.474047 -228.129085)
			(xy 369.525342 -228.13721) (xy 369.574735 -228.153258) (xy 369.621009 -228.176836) (xy 369.663025 -228.207362)
			(xy 369.699748 -228.244085) (xy 369.730274 -228.286101) (xy 369.753852 -228.332375) (xy 369.7699 -228.381768)
			(xy 369.778025 -228.433063) (xy 369.778534 -228.45903) (xy 369.778025 -228.484997) (xy 369.7699 -228.536292)
			(xy 369.753852 -228.585685) (xy 369.730274 -228.631959) (xy 369.699748 -228.673975) (xy 369.663025 -228.710698)
			(xy 369.621009 -228.741224) (xy 369.574735 -228.764802) (xy 369.525342 -228.78085) (xy 369.474047 -228.788975)
			(xy 369.422113 -228.788975) (xy 369.370818 -228.78085) (xy 369.321425 -228.764802) (xy 369.275151 -228.741224)
			(xy 369.233135 -228.710698) (xy 369.196412 -228.673975) (xy 369.165886 -228.631959) (xy 369.142308 -228.585685)
			(xy 369.12626 -228.536292) (xy 369.118135 -228.484997) (xy 368.838225 -228.484997) (xy 368.8301 -228.536292)
			(xy 368.814052 -228.585685) (xy 368.790474 -228.631959) (xy 368.759948 -228.673975) (xy 368.723225 -228.710698)
			(xy 368.681209 -228.741224) (xy 368.634935 -228.764802) (xy 368.585542 -228.78085) (xy 368.534247 -228.788975)
			(xy 368.482313 -228.788975) (xy 368.431018 -228.78085) (xy 368.381625 -228.764802) (xy 368.335351 -228.741224)
			(xy 368.293335 -228.710698) (xy 368.256612 -228.673975) (xy 368.226086 -228.631959) (xy 368.202508 -228.585685)
			(xy 368.18646 -228.536292) (xy 368.178335 -228.484997) (xy 367.898425 -228.484997) (xy 367.8903 -228.536292)
			(xy 367.874252 -228.585685) (xy 367.850674 -228.631959) (xy 367.820148 -228.673975) (xy 367.783425 -228.710698)
			(xy 367.741409 -228.741224) (xy 367.695135 -228.764802) (xy 367.645742 -228.78085) (xy 367.594447 -228.788975)
			(xy 367.542513 -228.788975) (xy 367.491218 -228.78085) (xy 367.441825 -228.764802) (xy 367.395551 -228.741224)
			(xy 367.353535 -228.710698) (xy 367.316812 -228.673975) (xy 367.286286 -228.631959) (xy 367.262708 -228.585685)
			(xy 367.24666 -228.536292) (xy 367.238535 -228.484997) (xy 366.018825 -228.484997) (xy 366.0107 -228.536292)
			(xy 365.994652 -228.585685) (xy 365.971074 -228.631959) (xy 365.940548 -228.673975) (xy 365.903825 -228.710698)
			(xy 365.861809 -228.741224) (xy 365.815535 -228.764802) (xy 365.766142 -228.78085) (xy 365.714847 -228.788975)
			(xy 365.662913 -228.788975) (xy 365.611618 -228.78085) (xy 365.562225 -228.764802) (xy 365.515951 -228.741224)
			(xy 365.473935 -228.710698) (xy 365.437212 -228.673975) (xy 365.406686 -228.631959) (xy 365.383108 -228.585685)
			(xy 365.36706 -228.536292) (xy 365.358935 -228.484997) (xy 364.139225 -228.484997) (xy 364.1311 -228.536292)
			(xy 364.115052 -228.585685) (xy 364.091474 -228.631959) (xy 364.060948 -228.673975) (xy 364.024225 -228.710698)
			(xy 363.982209 -228.741224) (xy 363.935935 -228.764802) (xy 363.886542 -228.78085) (xy 363.835247 -228.788975)
			(xy 363.783313 -228.788975) (xy 363.732018 -228.78085) (xy 363.682625 -228.764802) (xy 363.636351 -228.741224)
			(xy 363.594335 -228.710698) (xy 363.557612 -228.673975) (xy 363.527086 -228.631959) (xy 363.503508 -228.585685)
			(xy 363.48746 -228.536292) (xy 363.479335 -228.484997) (xy 362.259625 -228.484997) (xy 362.2515 -228.536292)
			(xy 362.235452 -228.585685) (xy 362.211874 -228.631959) (xy 362.181348 -228.673975) (xy 362.144625 -228.710698)
			(xy 362.102609 -228.741224) (xy 362.056335 -228.764802) (xy 362.006942 -228.78085) (xy 361.955647 -228.788975)
			(xy 361.903713 -228.788975) (xy 361.852418 -228.78085) (xy 361.803025 -228.764802) (xy 361.756751 -228.741224)
			(xy 361.714735 -228.710698) (xy 361.678012 -228.673975) (xy 361.647486 -228.631959) (xy 361.623908 -228.585685)
			(xy 361.60786 -228.536292) (xy 361.599735 -228.484997) (xy 361.319888 -228.484997) (xy 361.311764 -228.536279)
			(xy 361.295712 -228.58568) (xy 361.272129 -228.631961) (xy 361.241596 -228.673983) (xy 361.204865 -228.710711)
			(xy 361.162841 -228.741241) (xy 361.116558 -228.764821) (xy 361.067156 -228.78087) (xy 361.015852 -228.788993)
			(xy 360.98988 -228.789484) (xy 360.977688 -228.78923) (xy 360.964132 -228.789137) (xy 360.937734 -228.795266)
			(xy 360.913881 -228.808127) (xy 360.894256 -228.826815) (xy 360.880243 -228.850011) (xy 360.872831 -228.876077)
			(xy 360.872544 -228.903175) (xy 360.8794 -228.929393) (xy 360.892917 -228.952881) (xy 360.90225 -228.962712)
			(xy 361.035092 -229.095554) (xy 361.045901 -229.10565) (xy 361.071917 -229.119696) (xy 361.100863 -229.125716)
			(xy 361.130322 -229.123206) (xy 361.157832 -229.112377) (xy 361.181097 -229.094133) (xy 361.190032 -229.082346)
			(xy 361.205643 -229.061111) (xy 361.242474 -229.023416) (xy 361.28482 -228.992044) (xy 361.331608 -228.967789)
			(xy 361.381652 -228.951265) (xy 361.433683 -228.942892) (xy 361.460034 -228.942392) (xy 361.486 -228.942877)
			(xy 361.537293 -228.951007) (xy 361.586682 -228.96706) (xy 361.632951 -228.990643) (xy 361.674962 -229.021173)
			(xy 361.711679 -229.057899) (xy 361.742199 -229.099917) (xy 361.76577 -229.146192) (xy 361.781812 -229.195585)
			(xy 361.789929 -229.24688) (xy 361.790488 -229.272846) (xy 361.789986 -229.298813) (xy 362.069889 -229.298813)
			(xy 362.069889 -229.246879) (xy 362.078014 -229.195584) (xy 362.094062 -229.146191) (xy 362.11764 -229.099917)
			(xy 362.148166 -229.057901) (xy 362.184889 -229.021178) (xy 362.226905 -228.990652) (xy 362.273179 -228.967074)
			(xy 362.322572 -228.951026) (xy 362.373867 -228.942901) (xy 362.425801 -228.942901) (xy 362.477096 -228.951026)
			(xy 362.526489 -228.967074) (xy 362.572763 -228.990652) (xy 362.614779 -229.021178) (xy 362.651502 -229.057901)
			(xy 362.682028 -229.099917) (xy 362.705606 -229.146191) (xy 362.721654 -229.195584) (xy 362.729779 -229.246879)
			(xy 362.730288 -229.272846) (xy 362.729779 -229.298813) (xy 363.009689 -229.298813) (xy 363.009689 -229.246879)
			(xy 363.017814 -229.195584) (xy 363.033862 -229.146191) (xy 363.05744 -229.099917) (xy 363.087966 -229.057901)
			(xy 363.124689 -229.021178) (xy 363.166705 -228.990652) (xy 363.212979 -228.967074) (xy 363.262372 -228.951026)
			(xy 363.313667 -228.942901) (xy 363.365601 -228.942901) (xy 363.416896 -228.951026) (xy 363.466289 -228.967074)
			(xy 363.512563 -228.990652) (xy 363.554579 -229.021178) (xy 363.591302 -229.057901) (xy 363.621828 -229.099917)
			(xy 363.645406 -229.146191) (xy 363.661454 -229.195584) (xy 363.669579 -229.246879) (xy 363.670088 -229.272846)
			(xy 363.669579 -229.298813) (xy 363.949489 -229.298813) (xy 363.949489 -229.246879) (xy 363.957614 -229.195584)
			(xy 363.973662 -229.146191) (xy 363.99724 -229.099917) (xy 364.027766 -229.057901) (xy 364.064489 -229.021178)
			(xy 364.106505 -228.990652) (xy 364.152779 -228.967074) (xy 364.202172 -228.951026) (xy 364.253467 -228.942901)
			(xy 364.305401 -228.942901) (xy 364.356696 -228.951026) (xy 364.406089 -228.967074) (xy 364.452363 -228.990652)
			(xy 364.494379 -229.021178) (xy 364.531102 -229.057901) (xy 364.561628 -229.099917) (xy 364.585206 -229.146191)
			(xy 364.601254 -229.195584) (xy 364.609379 -229.246879) (xy 364.609888 -229.272846) (xy 364.609379 -229.298813)
			(xy 364.889289 -229.298813) (xy 364.889289 -229.246879) (xy 364.897414 -229.195584) (xy 364.913462 -229.146191)
			(xy 364.93704 -229.099917) (xy 364.967566 -229.057901) (xy 365.004289 -229.021178) (xy 365.046305 -228.990652)
			(xy 365.092579 -228.967074) (xy 365.141972 -228.951026) (xy 365.193267 -228.942901) (xy 365.245201 -228.942901)
			(xy 365.296496 -228.951026) (xy 365.345889 -228.967074) (xy 365.392163 -228.990652) (xy 365.434179 -229.021178)
			(xy 365.470902 -229.057901) (xy 365.501428 -229.099917) (xy 365.525006 -229.146191) (xy 365.541054 -229.195584)
			(xy 365.549179 -229.246879) (xy 365.549688 -229.272846) (xy 365.549179 -229.298813) (xy 365.829089 -229.298813)
			(xy 365.829089 -229.246879) (xy 365.837214 -229.195584) (xy 365.853262 -229.146191) (xy 365.87684 -229.099917)
			(xy 365.907366 -229.057901) (xy 365.944089 -229.021178) (xy 365.986105 -228.990652) (xy 366.032379 -228.967074)
			(xy 366.081772 -228.951026) (xy 366.133067 -228.942901) (xy 366.185001 -228.942901) (xy 366.236296 -228.951026)
			(xy 366.285689 -228.967074) (xy 366.331963 -228.990652) (xy 366.373979 -229.021178) (xy 366.410702 -229.057901)
			(xy 366.441228 -229.099917) (xy 366.464806 -229.146191) (xy 366.480854 -229.195584) (xy 366.488979 -229.246879)
			(xy 366.489488 -229.272846) (xy 366.488979 -229.298813) (xy 366.768889 -229.298813) (xy 366.768889 -229.246879)
			(xy 366.777014 -229.195584) (xy 366.793062 -229.146191) (xy 366.81664 -229.099917) (xy 366.847166 -229.057901)
			(xy 366.883889 -229.021178) (xy 366.925905 -228.990652) (xy 366.972179 -228.967074) (xy 367.021572 -228.951026)
			(xy 367.072867 -228.942901) (xy 367.124801 -228.942901) (xy 367.176096 -228.951026) (xy 367.225489 -228.967074)
			(xy 367.271763 -228.990652) (xy 367.313779 -229.021178) (xy 367.350502 -229.057901) (xy 367.381028 -229.099917)
			(xy 367.404606 -229.146191) (xy 367.420654 -229.195584) (xy 367.428779 -229.246879) (xy 367.429288 -229.272846)
			(xy 367.428779 -229.298813) (xy 367.708689 -229.298813) (xy 367.708689 -229.246879) (xy 367.716814 -229.195584)
			(xy 367.732862 -229.146191) (xy 367.75644 -229.099917) (xy 367.786966 -229.057901) (xy 367.823689 -229.021178)
			(xy 367.865705 -228.990652) (xy 367.911979 -228.967074) (xy 367.961372 -228.951026) (xy 368.012667 -228.942901)
			(xy 368.064601 -228.942901) (xy 368.115896 -228.951026) (xy 368.165289 -228.967074) (xy 368.211563 -228.990652)
			(xy 368.253579 -229.021178) (xy 368.290302 -229.057901) (xy 368.320828 -229.099917) (xy 368.344406 -229.146191)
			(xy 368.360454 -229.195584) (xy 368.368579 -229.246879) (xy 368.369088 -229.272846) (xy 368.368579 -229.298813)
			(xy 368.648489 -229.298813) (xy 368.648489 -229.246879) (xy 368.656614 -229.195584) (xy 368.672662 -229.146191)
			(xy 368.69624 -229.099917) (xy 368.726766 -229.057901) (xy 368.763489 -229.021178) (xy 368.805505 -228.990652)
			(xy 368.851779 -228.967074) (xy 368.901172 -228.951026) (xy 368.952467 -228.942901) (xy 369.004401 -228.942901)
			(xy 369.055696 -228.951026) (xy 369.105089 -228.967074) (xy 369.151363 -228.990652) (xy 369.193379 -229.021178)
			(xy 369.230102 -229.057901) (xy 369.260628 -229.099917) (xy 369.284206 -229.146191) (xy 369.300254 -229.195584)
			(xy 369.308379 -229.246879) (xy 369.308888 -229.272846) (xy 369.308379 -229.298813) (xy 369.588289 -229.298813)
			(xy 369.588289 -229.246879) (xy 369.596414 -229.195584) (xy 369.612462 -229.146191) (xy 369.63604 -229.099917)
			(xy 369.666566 -229.057901) (xy 369.703289 -229.021178) (xy 369.745305 -228.990652) (xy 369.791579 -228.967074)
			(xy 369.840972 -228.951026) (xy 369.892267 -228.942901) (xy 369.944201 -228.942901) (xy 369.995496 -228.951026)
			(xy 370.044889 -228.967074) (xy 370.091163 -228.990652) (xy 370.133179 -229.021178) (xy 370.169902 -229.057901)
			(xy 370.200428 -229.099917) (xy 370.224006 -229.146191) (xy 370.240054 -229.195584) (xy 370.248179 -229.246879)
			(xy 370.248688 -229.272846) (xy 370.248179 -229.298813) (xy 370.240054 -229.350108) (xy 370.224006 -229.399501)
			(xy 370.200428 -229.445775) (xy 370.169902 -229.487791) (xy 370.133179 -229.524514) (xy 370.091163 -229.55504)
			(xy 370.044889 -229.578618) (xy 369.995496 -229.594666) (xy 369.944201 -229.602791) (xy 369.892267 -229.602791)
			(xy 369.840972 -229.594666) (xy 369.791579 -229.578618) (xy 369.745305 -229.55504) (xy 369.703289 -229.524514)
			(xy 369.666566 -229.487791) (xy 369.63604 -229.445775) (xy 369.612462 -229.399501) (xy 369.596414 -229.350108)
			(xy 369.588289 -229.298813) (xy 369.308379 -229.298813) (xy 369.300254 -229.350108) (xy 369.284206 -229.399501)
			(xy 369.260628 -229.445775) (xy 369.230102 -229.487791) (xy 369.193379 -229.524514) (xy 369.151363 -229.55504)
			(xy 369.105089 -229.578618) (xy 369.055696 -229.594666) (xy 369.004401 -229.602791) (xy 368.952467 -229.602791)
			(xy 368.901172 -229.594666) (xy 368.851779 -229.578618) (xy 368.805505 -229.55504) (xy 368.763489 -229.524514)
			(xy 368.726766 -229.487791) (xy 368.69624 -229.445775) (xy 368.672662 -229.399501) (xy 368.656614 -229.350108)
			(xy 368.648489 -229.298813) (xy 368.368579 -229.298813) (xy 368.360454 -229.350108) (xy 368.344406 -229.399501)
			(xy 368.320828 -229.445775) (xy 368.290302 -229.487791) (xy 368.253579 -229.524514) (xy 368.211563 -229.55504)
			(xy 368.165289 -229.578618) (xy 368.115896 -229.594666) (xy 368.064601 -229.602791) (xy 368.012667 -229.602791)
			(xy 367.961372 -229.594666) (xy 367.911979 -229.578618) (xy 367.865705 -229.55504) (xy 367.823689 -229.524514)
			(xy 367.786966 -229.487791) (xy 367.75644 -229.445775) (xy 367.732862 -229.399501) (xy 367.716814 -229.350108)
			(xy 367.708689 -229.298813) (xy 367.428779 -229.298813) (xy 367.420654 -229.350108) (xy 367.404606 -229.399501)
			(xy 367.381028 -229.445775) (xy 367.350502 -229.487791) (xy 367.313779 -229.524514) (xy 367.271763 -229.55504)
			(xy 367.225489 -229.578618) (xy 367.176096 -229.594666) (xy 367.124801 -229.602791) (xy 367.072867 -229.602791)
			(xy 367.021572 -229.594666) (xy 366.972179 -229.578618) (xy 366.925905 -229.55504) (xy 366.883889 -229.524514)
			(xy 366.847166 -229.487791) (xy 366.81664 -229.445775) (xy 366.793062 -229.399501) (xy 366.777014 -229.350108)
			(xy 366.768889 -229.298813) (xy 366.488979 -229.298813) (xy 366.480854 -229.350108) (xy 366.464806 -229.399501)
			(xy 366.441228 -229.445775) (xy 366.410702 -229.487791) (xy 366.373979 -229.524514) (xy 366.331963 -229.55504)
			(xy 366.285689 -229.578618) (xy 366.236296 -229.594666) (xy 366.185001 -229.602791) (xy 366.133067 -229.602791)
			(xy 366.081772 -229.594666) (xy 366.032379 -229.578618) (xy 365.986105 -229.55504) (xy 365.944089 -229.524514)
			(xy 365.907366 -229.487791) (xy 365.87684 -229.445775) (xy 365.853262 -229.399501) (xy 365.837214 -229.350108)
			(xy 365.829089 -229.298813) (xy 365.549179 -229.298813) (xy 365.541054 -229.350108) (xy 365.525006 -229.399501)
			(xy 365.501428 -229.445775) (xy 365.470902 -229.487791) (xy 365.434179 -229.524514) (xy 365.392163 -229.55504)
			(xy 365.345889 -229.578618) (xy 365.296496 -229.594666) (xy 365.245201 -229.602791) (xy 365.193267 -229.602791)
			(xy 365.141972 -229.594666) (xy 365.092579 -229.578618) (xy 365.046305 -229.55504) (xy 365.004289 -229.524514)
			(xy 364.967566 -229.487791) (xy 364.93704 -229.445775) (xy 364.913462 -229.399501) (xy 364.897414 -229.350108)
			(xy 364.889289 -229.298813) (xy 364.609379 -229.298813) (xy 364.601254 -229.350108) (xy 364.585206 -229.399501)
			(xy 364.561628 -229.445775) (xy 364.531102 -229.487791) (xy 364.494379 -229.524514) (xy 364.452363 -229.55504)
			(xy 364.406089 -229.578618) (xy 364.356696 -229.594666) (xy 364.305401 -229.602791) (xy 364.253467 -229.602791)
			(xy 364.202172 -229.594666) (xy 364.152779 -229.578618) (xy 364.106505 -229.55504) (xy 364.064489 -229.524514)
			(xy 364.027766 -229.487791) (xy 363.99724 -229.445775) (xy 363.973662 -229.399501) (xy 363.957614 -229.350108)
			(xy 363.949489 -229.298813) (xy 363.669579 -229.298813) (xy 363.661454 -229.350108) (xy 363.645406 -229.399501)
			(xy 363.621828 -229.445775) (xy 363.591302 -229.487791) (xy 363.554579 -229.524514) (xy 363.512563 -229.55504)
			(xy 363.466289 -229.578618) (xy 363.416896 -229.594666) (xy 363.365601 -229.602791) (xy 363.313667 -229.602791)
			(xy 363.262372 -229.594666) (xy 363.212979 -229.578618) (xy 363.166705 -229.55504) (xy 363.124689 -229.524514)
			(xy 363.087966 -229.487791) (xy 363.05744 -229.445775) (xy 363.033862 -229.399501) (xy 363.017814 -229.350108)
			(xy 363.009689 -229.298813) (xy 362.729779 -229.298813) (xy 362.721654 -229.350108) (xy 362.705606 -229.399501)
			(xy 362.682028 -229.445775) (xy 362.651502 -229.487791) (xy 362.614779 -229.524514) (xy 362.572763 -229.55504)
			(xy 362.526489 -229.578618) (xy 362.477096 -229.594666) (xy 362.425801 -229.602791) (xy 362.373867 -229.602791)
			(xy 362.322572 -229.594666) (xy 362.273179 -229.578618) (xy 362.226905 -229.55504) (xy 362.184889 -229.524514)
			(xy 362.148166 -229.487791) (xy 362.11764 -229.445775) (xy 362.094062 -229.399501) (xy 362.078014 -229.350108)
			(xy 362.069889 -229.298813) (xy 361.789986 -229.298813) (xy 361.789979 -229.299198) (xy 361.78162 -229.351235)
			(xy 361.765106 -229.401285) (xy 361.740856 -229.448079) (xy 361.709485 -229.490429) (xy 361.671788 -229.527262)
			(xy 361.650534 -229.542848) (xy 361.638745 -229.551788) (xy 361.620484 -229.575048) (xy 361.609642 -229.602562)
			(xy 361.607127 -229.632027) (xy 361.613149 -229.66098) (xy 361.627204 -229.686999) (xy 361.637326 -229.697788)
			(xy 361.747816 -229.808278) (xy 361.780836 -229.791768) (xy 361.80408 -229.780571) (xy 361.853177 -229.764728)
			(xy 361.904139 -229.756704) (xy 361.929934 -229.756208) (xy 361.955901 -229.75672) (xy 362.007194 -229.764848)
			(xy 362.056584 -229.780899) (xy 362.102856 -229.804478) (xy 362.14487 -229.835004) (xy 362.181593 -229.871726)
			(xy 362.21212 -229.91374) (xy 362.235699 -229.960012) (xy 362.251751 -230.009402) (xy 362.25988 -230.060695)
			(xy 362.260388 -230.086662) (xy 362.259894 -230.112458) (xy 362.259867 -230.112629) (xy 362.539789 -230.112629)
			(xy 362.539789 -230.060695) (xy 362.547914 -230.0094) (xy 362.563962 -229.960007) (xy 362.58754 -229.913733)
			(xy 362.618066 -229.871717) (xy 362.654789 -229.834994) (xy 362.696805 -229.804468) (xy 362.743079 -229.78089)
			(xy 362.792472 -229.764842) (xy 362.843767 -229.756717) (xy 362.895701 -229.756717) (xy 362.946996 -229.764842)
			(xy 362.996389 -229.78089) (xy 363.042663 -229.804468) (xy 363.084679 -229.834994) (xy 363.121402 -229.871717)
			(xy 363.151928 -229.913733) (xy 363.175506 -229.960007) (xy 363.191554 -230.0094) (xy 363.199679 -230.060695)
			(xy 363.200188 -230.086662) (xy 363.199679 -230.112629) (xy 363.479335 -230.112629) (xy 363.479335 -230.060695)
			(xy 363.48746 -230.0094) (xy 363.503508 -229.960007) (xy 363.527086 -229.913733) (xy 363.557612 -229.871717)
			(xy 363.594335 -229.834994) (xy 363.636351 -229.804468) (xy 363.682625 -229.78089) (xy 363.732018 -229.764842)
			(xy 363.783313 -229.756717) (xy 363.835247 -229.756717) (xy 363.886542 -229.764842) (xy 363.935935 -229.78089)
			(xy 363.982209 -229.804468) (xy 364.024225 -229.834994) (xy 364.060948 -229.871717) (xy 364.091474 -229.913733)
			(xy 364.115052 -229.960007) (xy 364.1311 -230.0094) (xy 364.139225 -230.060695) (xy 364.139734 -230.086662)
			(xy 364.139225 -230.112629) (xy 364.419135 -230.112629) (xy 364.419135 -230.060695) (xy 364.42726 -230.0094)
			(xy 364.443308 -229.960007) (xy 364.466886 -229.913733) (xy 364.497412 -229.871717) (xy 364.534135 -229.834994)
			(xy 364.576151 -229.804468) (xy 364.622425 -229.78089) (xy 364.671818 -229.764842) (xy 364.723113 -229.756717)
			(xy 364.775047 -229.756717) (xy 364.826342 -229.764842) (xy 364.875735 -229.78089) (xy 364.922009 -229.804468)
			(xy 364.964025 -229.834994) (xy 365.000748 -229.871717) (xy 365.031274 -229.913733) (xy 365.054852 -229.960007)
			(xy 365.0709 -230.0094) (xy 365.079025 -230.060695) (xy 365.079534 -230.086662) (xy 365.079025 -230.112629)
			(xy 365.358935 -230.112629) (xy 365.358935 -230.060695) (xy 365.36706 -230.0094) (xy 365.383108 -229.960007)
			(xy 365.406686 -229.913733) (xy 365.437212 -229.871717) (xy 365.473935 -229.834994) (xy 365.515951 -229.804468)
			(xy 365.562225 -229.78089) (xy 365.611618 -229.764842) (xy 365.662913 -229.756717) (xy 365.714847 -229.756717)
			(xy 365.766142 -229.764842) (xy 365.815535 -229.78089) (xy 365.861809 -229.804468) (xy 365.903825 -229.834994)
			(xy 365.940548 -229.871717) (xy 365.971074 -229.913733) (xy 365.994652 -229.960007) (xy 366.0107 -230.0094)
			(xy 366.018825 -230.060695) (xy 366.019334 -230.086662) (xy 366.018825 -230.112629) (xy 366.298735 -230.112629)
			(xy 366.298735 -230.060695) (xy 366.30686 -230.0094) (xy 366.322908 -229.960007) (xy 366.346486 -229.913733)
			(xy 366.377012 -229.871717) (xy 366.413735 -229.834994) (xy 366.455751 -229.804468) (xy 366.502025 -229.78089)
			(xy 366.551418 -229.764842) (xy 366.602713 -229.756717) (xy 366.654647 -229.756717) (xy 366.705942 -229.764842)
			(xy 366.755335 -229.78089) (xy 366.801609 -229.804468) (xy 366.843625 -229.834994) (xy 366.880348 -229.871717)
			(xy 366.910874 -229.913733) (xy 366.934452 -229.960007) (xy 366.9505 -230.0094) (xy 366.958625 -230.060695)
			(xy 366.959134 -230.086662) (xy 366.958625 -230.112629) (xy 367.238535 -230.112629) (xy 367.238535 -230.060695)
			(xy 367.24666 -230.0094) (xy 367.262708 -229.960007) (xy 367.286286 -229.913733) (xy 367.316812 -229.871717)
			(xy 367.353535 -229.834994) (xy 367.395551 -229.804468) (xy 367.441825 -229.78089) (xy 367.491218 -229.764842)
			(xy 367.542513 -229.756717) (xy 367.594447 -229.756717) (xy 367.645742 -229.764842) (xy 367.695135 -229.78089)
			(xy 367.741409 -229.804468) (xy 367.783425 -229.834994) (xy 367.820148 -229.871717) (xy 367.850674 -229.913733)
			(xy 367.874252 -229.960007) (xy 367.8903 -230.0094) (xy 367.898425 -230.060695) (xy 367.898934 -230.086662)
			(xy 367.898425 -230.112629) (xy 368.178335 -230.112629) (xy 368.178335 -230.060695) (xy 368.18646 -230.0094)
			(xy 368.202508 -229.960007) (xy 368.226086 -229.913733) (xy 368.256612 -229.871717) (xy 368.293335 -229.834994)
			(xy 368.335351 -229.804468) (xy 368.381625 -229.78089) (xy 368.431018 -229.764842) (xy 368.482313 -229.756717)
			(xy 368.534247 -229.756717) (xy 368.585542 -229.764842) (xy 368.634935 -229.78089) (xy 368.681209 -229.804468)
			(xy 368.723225 -229.834994) (xy 368.759948 -229.871717) (xy 368.790474 -229.913733) (xy 368.814052 -229.960007)
			(xy 368.8301 -230.0094) (xy 368.838225 -230.060695) (xy 368.838734 -230.086662) (xy 368.838225 -230.112629)
			(xy 369.118135 -230.112629) (xy 369.118135 -230.060695) (xy 369.12626 -230.0094) (xy 369.142308 -229.960007)
			(xy 369.165886 -229.913733) (xy 369.196412 -229.871717) (xy 369.233135 -229.834994) (xy 369.275151 -229.804468)
			(xy 369.321425 -229.78089) (xy 369.370818 -229.764842) (xy 369.422113 -229.756717) (xy 369.474047 -229.756717)
			(xy 369.525342 -229.764842) (xy 369.574735 -229.78089) (xy 369.621009 -229.804468) (xy 369.663025 -229.834994)
			(xy 369.699748 -229.871717) (xy 369.730274 -229.913733) (xy 369.753852 -229.960007) (xy 369.7699 -230.0094)
			(xy 369.778025 -230.060695) (xy 369.778534 -230.086662) (xy 369.778025 -230.112629) (xy 369.7699 -230.163924)
			(xy 369.753852 -230.213317) (xy 369.730274 -230.259591) (xy 369.699748 -230.301607) (xy 369.663025 -230.33833)
			(xy 369.621009 -230.368856) (xy 369.574735 -230.392434) (xy 369.525342 -230.408482) (xy 369.474047 -230.416607)
			(xy 369.422113 -230.416607) (xy 369.370818 -230.408482) (xy 369.321425 -230.392434) (xy 369.275151 -230.368856)
			(xy 369.233135 -230.33833) (xy 369.196412 -230.301607) (xy 369.165886 -230.259591) (xy 369.142308 -230.213317)
			(xy 369.12626 -230.163924) (xy 369.118135 -230.112629) (xy 368.838225 -230.112629) (xy 368.8301 -230.163924)
			(xy 368.814052 -230.213317) (xy 368.790474 -230.259591) (xy 368.759948 -230.301607) (xy 368.723225 -230.33833)
			(xy 368.681209 -230.368856) (xy 368.634935 -230.392434) (xy 368.585542 -230.408482) (xy 368.534247 -230.416607)
			(xy 368.482313 -230.416607) (xy 368.431018 -230.408482) (xy 368.381625 -230.392434) (xy 368.335351 -230.368856)
			(xy 368.293335 -230.33833) (xy 368.256612 -230.301607) (xy 368.226086 -230.259591) (xy 368.202508 -230.213317)
			(xy 368.18646 -230.163924) (xy 368.178335 -230.112629) (xy 367.898425 -230.112629) (xy 367.8903 -230.163924)
			(xy 367.874252 -230.213317) (xy 367.850674 -230.259591) (xy 367.820148 -230.301607) (xy 367.783425 -230.33833)
			(xy 367.741409 -230.368856) (xy 367.695135 -230.392434) (xy 367.645742 -230.408482) (xy 367.594447 -230.416607)
			(xy 367.542513 -230.416607) (xy 367.491218 -230.408482) (xy 367.441825 -230.392434) (xy 367.395551 -230.368856)
			(xy 367.353535 -230.33833) (xy 367.316812 -230.301607) (xy 367.286286 -230.259591) (xy 367.262708 -230.213317)
			(xy 367.24666 -230.163924) (xy 367.238535 -230.112629) (xy 366.958625 -230.112629) (xy 366.9505 -230.163924)
			(xy 366.934452 -230.213317) (xy 366.910874 -230.259591) (xy 366.880348 -230.301607) (xy 366.843625 -230.33833)
			(xy 366.801609 -230.368856) (xy 366.755335 -230.392434) (xy 366.705942 -230.408482) (xy 366.654647 -230.416607)
			(xy 366.602713 -230.416607) (xy 366.551418 -230.408482) (xy 366.502025 -230.392434) (xy 366.455751 -230.368856)
			(xy 366.413735 -230.33833) (xy 366.377012 -230.301607) (xy 366.346486 -230.259591) (xy 366.322908 -230.213317)
			(xy 366.30686 -230.163924) (xy 366.298735 -230.112629) (xy 366.018825 -230.112629) (xy 366.0107 -230.163924)
			(xy 365.994652 -230.213317) (xy 365.971074 -230.259591) (xy 365.940548 -230.301607) (xy 365.903825 -230.33833)
			(xy 365.861809 -230.368856) (xy 365.815535 -230.392434) (xy 365.766142 -230.408482) (xy 365.714847 -230.416607)
			(xy 365.662913 -230.416607) (xy 365.611618 -230.408482) (xy 365.562225 -230.392434) (xy 365.515951 -230.368856)
			(xy 365.473935 -230.33833) (xy 365.437212 -230.301607) (xy 365.406686 -230.259591) (xy 365.383108 -230.213317)
			(xy 365.36706 -230.163924) (xy 365.358935 -230.112629) (xy 365.079025 -230.112629) (xy 365.0709 -230.163924)
			(xy 365.054852 -230.213317) (xy 365.031274 -230.259591) (xy 365.000748 -230.301607) (xy 364.964025 -230.33833)
			(xy 364.922009 -230.368856) (xy 364.875735 -230.392434) (xy 364.826342 -230.408482) (xy 364.775047 -230.416607)
			(xy 364.723113 -230.416607) (xy 364.671818 -230.408482) (xy 364.622425 -230.392434) (xy 364.576151 -230.368856)
			(xy 364.534135 -230.33833) (xy 364.497412 -230.301607) (xy 364.466886 -230.259591) (xy 364.443308 -230.213317)
			(xy 364.42726 -230.163924) (xy 364.419135 -230.112629) (xy 364.139225 -230.112629) (xy 364.1311 -230.163924)
			(xy 364.115052 -230.213317) (xy 364.091474 -230.259591) (xy 364.060948 -230.301607) (xy 364.024225 -230.33833)
			(xy 363.982209 -230.368856) (xy 363.935935 -230.392434) (xy 363.886542 -230.408482) (xy 363.835247 -230.416607)
			(xy 363.783313 -230.416607) (xy 363.732018 -230.408482) (xy 363.682625 -230.392434) (xy 363.636351 -230.368856)
			(xy 363.594335 -230.33833) (xy 363.557612 -230.301607) (xy 363.527086 -230.259591) (xy 363.503508 -230.213317)
			(xy 363.48746 -230.163924) (xy 363.479335 -230.112629) (xy 363.199679 -230.112629) (xy 363.191554 -230.163924)
			(xy 363.175506 -230.213317) (xy 363.151928 -230.259591) (xy 363.121402 -230.301607) (xy 363.084679 -230.33833)
			(xy 363.042663 -230.368856) (xy 362.996389 -230.392434) (xy 362.946996 -230.408482) (xy 362.895701 -230.416607)
			(xy 362.843767 -230.416607) (xy 362.792472 -230.408482) (xy 362.743079 -230.392434) (xy 362.696805 -230.368856)
			(xy 362.654789 -230.33833) (xy 362.618066 -230.301607) (xy 362.58754 -230.259591) (xy 362.563962 -230.213317)
			(xy 362.547914 -230.163924) (xy 362.539789 -230.112629) (xy 362.259867 -230.112629) (xy 362.251878 -230.163423)
			(xy 362.236036 -230.212521) (xy 362.224828 -230.23576) (xy 362.208318 -230.26878) (xy 362.482384 -230.542846)
			(xy 362.482384 -230.578406) (xy 362.515404 -230.590852) (xy 362.538754 -230.600045) (xy 362.58259 -230.624464)
			(xy 362.62223 -230.655232) (xy 362.656762 -230.69164) (xy 362.685392 -230.73285) (xy 362.707462 -230.777916)
			(xy 362.722464 -230.8258) (xy 362.730052 -230.875403) (xy 362.730053 -230.925582) (xy 362.729921 -230.926445)
			(xy 363.009689 -230.926445) (xy 363.009689 -230.874511) (xy 363.017814 -230.823216) (xy 363.033862 -230.773823)
			(xy 363.05744 -230.727549) (xy 363.087966 -230.685533) (xy 363.124689 -230.64881) (xy 363.166705 -230.618284)
			(xy 363.212979 -230.594706) (xy 363.262372 -230.578658) (xy 363.313667 -230.570533) (xy 363.365601 -230.570533)
			(xy 363.416896 -230.578658) (xy 363.466289 -230.594706) (xy 363.512563 -230.618284) (xy 363.554579 -230.64881)
			(xy 363.591302 -230.685533) (xy 363.621828 -230.727549) (xy 363.645406 -230.773823) (xy 363.661454 -230.823216)
			(xy 363.669579 -230.874511) (xy 363.670088 -230.900478) (xy 363.669579 -230.926445) (xy 363.949489 -230.926445)
			(xy 363.949489 -230.874511) (xy 363.957614 -230.823216) (xy 363.973662 -230.773823) (xy 363.99724 -230.727549)
			(xy 364.027766 -230.685533) (xy 364.064489 -230.64881) (xy 364.106505 -230.618284) (xy 364.152779 -230.594706)
			(xy 364.202172 -230.578658) (xy 364.253467 -230.570533) (xy 364.305401 -230.570533) (xy 364.356696 -230.578658)
			(xy 364.406089 -230.594706) (xy 364.452363 -230.618284) (xy 364.494379 -230.64881) (xy 364.531102 -230.685533)
			(xy 364.561628 -230.727549) (xy 364.585206 -230.773823) (xy 364.601254 -230.823216) (xy 364.609379 -230.874511)
			(xy 364.609888 -230.900478) (xy 364.609379 -230.926445) (xy 364.889289 -230.926445) (xy 364.889289 -230.874511)
			(xy 364.897414 -230.823216) (xy 364.913462 -230.773823) (xy 364.93704 -230.727549) (xy 364.967566 -230.685533)
			(xy 365.004289 -230.64881) (xy 365.046305 -230.618284) (xy 365.092579 -230.594706) (xy 365.141972 -230.578658)
			(xy 365.193267 -230.570533) (xy 365.245201 -230.570533) (xy 365.296496 -230.578658) (xy 365.345889 -230.594706)
			(xy 365.392163 -230.618284) (xy 365.434179 -230.64881) (xy 365.470902 -230.685533) (xy 365.501428 -230.727549)
			(xy 365.525006 -230.773823) (xy 365.541054 -230.823216) (xy 365.549179 -230.874511) (xy 365.549688 -230.900478)
			(xy 365.549179 -230.926445) (xy 365.829089 -230.926445) (xy 365.829089 -230.874511) (xy 365.837214 -230.823216)
			(xy 365.853262 -230.773823) (xy 365.87684 -230.727549) (xy 365.907366 -230.685533) (xy 365.944089 -230.64881)
			(xy 365.986105 -230.618284) (xy 366.032379 -230.594706) (xy 366.081772 -230.578658) (xy 366.133067 -230.570533)
			(xy 366.185001 -230.570533) (xy 366.236296 -230.578658) (xy 366.285689 -230.594706) (xy 366.331963 -230.618284)
			(xy 366.373979 -230.64881) (xy 366.410702 -230.685533) (xy 366.441228 -230.727549) (xy 366.464806 -230.773823)
			(xy 366.480854 -230.823216) (xy 366.488979 -230.874511) (xy 366.489488 -230.900478) (xy 366.488979 -230.926445)
			(xy 366.768889 -230.926445) (xy 366.768889 -230.874511) (xy 366.777014 -230.823216) (xy 366.793062 -230.773823)
			(xy 366.81664 -230.727549) (xy 366.847166 -230.685533) (xy 366.883889 -230.64881) (xy 366.925905 -230.618284)
			(xy 366.972179 -230.594706) (xy 367.021572 -230.578658) (xy 367.072867 -230.570533) (xy 367.124801 -230.570533)
			(xy 367.176096 -230.578658) (xy 367.225489 -230.594706) (xy 367.271763 -230.618284) (xy 367.313779 -230.64881)
			(xy 367.350502 -230.685533) (xy 367.381028 -230.727549) (xy 367.404606 -230.773823) (xy 367.420654 -230.823216)
			(xy 367.428779 -230.874511) (xy 367.429288 -230.900478) (xy 367.428779 -230.926445) (xy 367.708689 -230.926445)
			(xy 367.708689 -230.874511) (xy 367.716814 -230.823216) (xy 367.732862 -230.773823) (xy 367.75644 -230.727549)
			(xy 367.786966 -230.685533) (xy 367.823689 -230.64881) (xy 367.865705 -230.618284) (xy 367.911979 -230.594706)
			(xy 367.961372 -230.578658) (xy 368.012667 -230.570533) (xy 368.064601 -230.570533) (xy 368.115896 -230.578658)
			(xy 368.165289 -230.594706) (xy 368.211563 -230.618284) (xy 368.253579 -230.64881) (xy 368.290302 -230.685533)
			(xy 368.320828 -230.727549) (xy 368.344406 -230.773823) (xy 368.360454 -230.823216) (xy 368.368579 -230.874511)
			(xy 368.369088 -230.900478) (xy 368.368579 -230.926445) (xy 368.648489 -230.926445) (xy 368.648489 -230.874511)
			(xy 368.656614 -230.823216) (xy 368.672662 -230.773823) (xy 368.69624 -230.727549) (xy 368.726766 -230.685533)
			(xy 368.763489 -230.64881) (xy 368.805505 -230.618284) (xy 368.851779 -230.594706) (xy 368.901172 -230.578658)
			(xy 368.952467 -230.570533) (xy 369.004401 -230.570533) (xy 369.055696 -230.578658) (xy 369.105089 -230.594706)
			(xy 369.151363 -230.618284) (xy 369.193379 -230.64881) (xy 369.230102 -230.685533) (xy 369.260628 -230.727549)
			(xy 369.284206 -230.773823) (xy 369.300254 -230.823216) (xy 369.308379 -230.874511) (xy 369.308888 -230.900478)
			(xy 369.308379 -230.926445) (xy 369.300254 -230.97774) (xy 369.284206 -231.027133) (xy 369.260628 -231.073407)
			(xy 369.230102 -231.115423) (xy 369.193379 -231.152146) (xy 369.151363 -231.182672) (xy 369.105089 -231.20625)
			(xy 369.055696 -231.222298) (xy 369.004401 -231.230423) (xy 368.952467 -231.230423) (xy 368.901172 -231.222298)
			(xy 368.851779 -231.20625) (xy 368.805505 -231.182672) (xy 368.763489 -231.152146) (xy 368.726766 -231.115423)
			(xy 368.69624 -231.073407) (xy 368.672662 -231.027133) (xy 368.656614 -230.97774) (xy 368.648489 -230.926445)
			(xy 368.368579 -230.926445) (xy 368.360454 -230.97774) (xy 368.344406 -231.027133) (xy 368.320828 -231.073407)
			(xy 368.290302 -231.115423) (xy 368.253579 -231.152146) (xy 368.211563 -231.182672) (xy 368.165289 -231.20625)
			(xy 368.115896 -231.222298) (xy 368.064601 -231.230423) (xy 368.012667 -231.230423) (xy 367.961372 -231.222298)
			(xy 367.911979 -231.20625) (xy 367.865705 -231.182672) (xy 367.823689 -231.152146) (xy 367.786966 -231.115423)
			(xy 367.75644 -231.073407) (xy 367.732862 -231.027133) (xy 367.716814 -230.97774) (xy 367.708689 -230.926445)
			(xy 367.428779 -230.926445) (xy 367.420654 -230.97774) (xy 367.404606 -231.027133) (xy 367.381028 -231.073407)
			(xy 367.350502 -231.115423) (xy 367.313779 -231.152146) (xy 367.271763 -231.182672) (xy 367.225489 -231.20625)
			(xy 367.176096 -231.222298) (xy 367.124801 -231.230423) (xy 367.072867 -231.230423) (xy 367.021572 -231.222298)
			(xy 366.972179 -231.20625) (xy 366.925905 -231.182672) (xy 366.883889 -231.152146) (xy 366.847166 -231.115423)
			(xy 366.81664 -231.073407) (xy 366.793062 -231.027133) (xy 366.777014 -230.97774) (xy 366.768889 -230.926445)
			(xy 366.488979 -230.926445) (xy 366.480854 -230.97774) (xy 366.464806 -231.027133) (xy 366.441228 -231.073407)
			(xy 366.410702 -231.115423) (xy 366.373979 -231.152146) (xy 366.331963 -231.182672) (xy 366.285689 -231.20625)
			(xy 366.236296 -231.222298) (xy 366.185001 -231.230423) (xy 366.133067 -231.230423) (xy 366.081772 -231.222298)
			(xy 366.032379 -231.20625) (xy 365.986105 -231.182672) (xy 365.944089 -231.152146) (xy 365.907366 -231.115423)
			(xy 365.87684 -231.073407) (xy 365.853262 -231.027133) (xy 365.837214 -230.97774) (xy 365.829089 -230.926445)
			(xy 365.549179 -230.926445) (xy 365.541054 -230.97774) (xy 365.525006 -231.027133) (xy 365.501428 -231.073407)
			(xy 365.470902 -231.115423) (xy 365.434179 -231.152146) (xy 365.392163 -231.182672) (xy 365.345889 -231.20625)
			(xy 365.296496 -231.222298) (xy 365.245201 -231.230423) (xy 365.193267 -231.230423) (xy 365.141972 -231.222298)
			(xy 365.092579 -231.20625) (xy 365.046305 -231.182672) (xy 365.004289 -231.152146) (xy 364.967566 -231.115423)
			(xy 364.93704 -231.073407) (xy 364.913462 -231.027133) (xy 364.897414 -230.97774) (xy 364.889289 -230.926445)
			(xy 364.609379 -230.926445) (xy 364.601254 -230.97774) (xy 364.585206 -231.027133) (xy 364.561628 -231.073407)
			(xy 364.531102 -231.115423) (xy 364.494379 -231.152146) (xy 364.452363 -231.182672) (xy 364.406089 -231.20625)
			(xy 364.356696 -231.222298) (xy 364.305401 -231.230423) (xy 364.253467 -231.230423) (xy 364.202172 -231.222298)
			(xy 364.152779 -231.20625) (xy 364.106505 -231.182672) (xy 364.064489 -231.152146) (xy 364.027766 -231.115423)
			(xy 363.99724 -231.073407) (xy 363.973662 -231.027133) (xy 363.957614 -230.97774) (xy 363.949489 -230.926445)
			(xy 363.669579 -230.926445) (xy 363.661454 -230.97774) (xy 363.645406 -231.027133) (xy 363.621828 -231.073407)
			(xy 363.591302 -231.115423) (xy 363.554579 -231.152146) (xy 363.512563 -231.182672) (xy 363.466289 -231.20625)
			(xy 363.416896 -231.222298) (xy 363.365601 -231.230423) (xy 363.313667 -231.230423) (xy 363.262372 -231.222298)
			(xy 363.212979 -231.20625) (xy 363.166705 -231.182672) (xy 363.124689 -231.152146) (xy 363.087966 -231.115423)
			(xy 363.05744 -231.073407) (xy 363.033862 -231.027133) (xy 363.017814 -230.97774) (xy 363.009689 -230.926445)
			(xy 362.729921 -230.926445) (xy 362.722467 -230.975185) (xy 362.707468 -231.02307) (xy 362.6854 -231.068137)
			(xy 362.656772 -231.109348) (xy 362.622242 -231.145758) (xy 362.582603 -231.176527) (xy 362.538768 -231.200949)
			(xy 362.515404 -231.210104) (xy 362.482384 -231.22255) (xy 362.482384 -231.39019) (xy 362.482867 -231.40477)
			(xy 362.49112 -231.43274) (xy 362.50693 -231.457243) (xy 362.529012 -231.47629) (xy 362.555572 -231.488332)
			(xy 362.584449 -231.49239) (xy 362.613299 -231.488135) (xy 362.639775 -231.475912) (xy 362.65104 -231.466644)
			(xy 362.669225 -231.45116) (xy 362.709218 -231.425052) (xy 362.752557 -231.404981) (xy 362.798336 -231.391366)
			(xy 362.8456 -231.384493) (xy 362.86948 -231.384094) (xy 362.895447 -231.384575) (xy 362.946741 -231.392697)
			(xy 362.996133 -231.408742) (xy 363.042406 -231.432317) (xy 363.084422 -231.462841) (xy 363.121146 -231.499563)
			(xy 363.151672 -231.541577) (xy 363.17525 -231.587849) (xy 363.191299 -231.63724) (xy 363.199423 -231.688533)
			(xy 363.199423 -231.740467) (xy 363.199415 -231.740515) (xy 363.479335 -231.740515) (xy 363.479335 -231.688581)
			(xy 363.48746 -231.637286) (xy 363.503508 -231.587893) (xy 363.527086 -231.541619) (xy 363.557612 -231.499603)
			(xy 363.594335 -231.46288) (xy 363.636351 -231.432354) (xy 363.682625 -231.408776) (xy 363.732018 -231.392728)
			(xy 363.783313 -231.384603) (xy 363.835247 -231.384603) (xy 363.886542 -231.392728) (xy 363.935935 -231.408776)
			(xy 363.982209 -231.432354) (xy 364.024225 -231.46288) (xy 364.060948 -231.499603) (xy 364.091474 -231.541619)
			(xy 364.115052 -231.587893) (xy 364.1311 -231.637286) (xy 364.139225 -231.688581) (xy 364.139734 -231.714548)
			(xy 364.139225 -231.740515) (xy 364.419135 -231.740515) (xy 364.419135 -231.688581) (xy 364.42726 -231.637286)
			(xy 364.443308 -231.587893) (xy 364.466886 -231.541619) (xy 364.497412 -231.499603) (xy 364.534135 -231.46288)
			(xy 364.576151 -231.432354) (xy 364.622425 -231.408776) (xy 364.671818 -231.392728) (xy 364.723113 -231.384603)
			(xy 364.775047 -231.384603) (xy 364.826342 -231.392728) (xy 364.875735 -231.408776) (xy 364.922009 -231.432354)
			(xy 364.964025 -231.46288) (xy 365.000748 -231.499603) (xy 365.031274 -231.541619) (xy 365.054852 -231.587893)
			(xy 365.0709 -231.637286) (xy 365.079025 -231.688581) (xy 365.079534 -231.714548) (xy 365.079025 -231.740515)
			(xy 365.358935 -231.740515) (xy 365.358935 -231.688581) (xy 365.36706 -231.637286) (xy 365.383108 -231.587893)
			(xy 365.406686 -231.541619) (xy 365.437212 -231.499603) (xy 365.473935 -231.46288) (xy 365.515951 -231.432354)
			(xy 365.562225 -231.408776) (xy 365.611618 -231.392728) (xy 365.662913 -231.384603) (xy 365.714847 -231.384603)
			(xy 365.766142 -231.392728) (xy 365.815535 -231.408776) (xy 365.861809 -231.432354) (xy 365.903825 -231.46288)
			(xy 365.940548 -231.499603) (xy 365.971074 -231.541619) (xy 365.994652 -231.587893) (xy 366.0107 -231.637286)
			(xy 366.018825 -231.688581) (xy 366.019334 -231.714548) (xy 366.018825 -231.740515) (xy 366.298735 -231.740515)
			(xy 366.298735 -231.688581) (xy 366.30686 -231.637286) (xy 366.322908 -231.587893) (xy 366.346486 -231.541619)
			(xy 366.377012 -231.499603) (xy 366.413735 -231.46288) (xy 366.455751 -231.432354) (xy 366.502025 -231.408776)
			(xy 366.551418 -231.392728) (xy 366.602713 -231.384603) (xy 366.654647 -231.384603) (xy 366.705942 -231.392728)
			(xy 366.755335 -231.408776) (xy 366.801609 -231.432354) (xy 366.843625 -231.46288) (xy 366.880348 -231.499603)
			(xy 366.910874 -231.541619) (xy 366.934452 -231.587893) (xy 366.9505 -231.637286) (xy 366.958625 -231.688581)
			(xy 366.959134 -231.714548) (xy 366.958625 -231.740515) (xy 367.239043 -231.740515) (xy 367.239043 -231.688581)
			(xy 367.247168 -231.637286) (xy 367.263216 -231.587893) (xy 367.286794 -231.541619) (xy 367.31732 -231.499603)
			(xy 367.354043 -231.46288) (xy 367.396059 -231.432354) (xy 367.442333 -231.408776) (xy 367.491726 -231.392728)
			(xy 367.543021 -231.384603) (xy 367.594955 -231.384603) (xy 367.64625 -231.392728) (xy 367.695643 -231.408776)
			(xy 367.741917 -231.432354) (xy 367.783933 -231.46288) (xy 367.820656 -231.499603) (xy 367.851182 -231.541619)
			(xy 367.87476 -231.587893) (xy 367.890808 -231.637286) (xy 367.898933 -231.688581) (xy 367.899442 -231.714548)
			(xy 367.898933 -231.740515) (xy 368.178335 -231.740515) (xy 368.178335 -231.688581) (xy 368.18646 -231.637286)
			(xy 368.202508 -231.587893) (xy 368.226086 -231.541619) (xy 368.256612 -231.499603) (xy 368.293335 -231.46288)
			(xy 368.335351 -231.432354) (xy 368.381625 -231.408776) (xy 368.431018 -231.392728) (xy 368.482313 -231.384603)
			(xy 368.534247 -231.384603) (xy 368.585542 -231.392728) (xy 368.634935 -231.408776) (xy 368.681209 -231.432354)
			(xy 368.723225 -231.46288) (xy 368.759948 -231.499603) (xy 368.790474 -231.541619) (xy 368.814052 -231.587893)
			(xy 368.8301 -231.637286) (xy 368.838225 -231.688581) (xy 368.838734 -231.714548) (xy 368.838225 -231.740515)
			(xy 369.118643 -231.740515) (xy 369.118643 -231.688581) (xy 369.126768 -231.637286) (xy 369.142816 -231.587893)
			(xy 369.166394 -231.541619) (xy 369.19692 -231.499603) (xy 369.233643 -231.46288) (xy 369.275659 -231.432354)
			(xy 369.321933 -231.408776) (xy 369.371326 -231.392728) (xy 369.422621 -231.384603) (xy 369.474555 -231.384603)
			(xy 369.52585 -231.392728) (xy 369.575243 -231.408776) (xy 369.621517 -231.432354) (xy 369.663533 -231.46288)
			(xy 369.700256 -231.499603) (xy 369.730782 -231.541619) (xy 369.75436 -231.587893) (xy 369.770408 -231.637286)
			(xy 369.778533 -231.688581) (xy 369.779042 -231.714548) (xy 369.778533 -231.740515) (xy 369.770408 -231.79181)
			(xy 369.75436 -231.841203) (xy 369.730782 -231.887477) (xy 369.700256 -231.929493) (xy 369.663533 -231.966216)
			(xy 369.621517 -231.996742) (xy 369.575243 -232.02032) (xy 369.52585 -232.036368) (xy 369.474555 -232.044493)
			(xy 369.422621 -232.044493) (xy 369.371326 -232.036368) (xy 369.321933 -232.02032) (xy 369.275659 -231.996742)
			(xy 369.233643 -231.966216) (xy 369.19692 -231.929493) (xy 369.166394 -231.887477) (xy 369.142816 -231.841203)
			(xy 369.126768 -231.79181) (xy 369.118643 -231.740515) (xy 368.838225 -231.740515) (xy 368.8301 -231.79181)
			(xy 368.814052 -231.841203) (xy 368.790474 -231.887477) (xy 368.759948 -231.929493) (xy 368.723225 -231.966216)
			(xy 368.681209 -231.996742) (xy 368.634935 -232.02032) (xy 368.585542 -232.036368) (xy 368.534247 -232.044493)
			(xy 368.482313 -232.044493) (xy 368.431018 -232.036368) (xy 368.381625 -232.02032) (xy 368.335351 -231.996742)
			(xy 368.293335 -231.966216) (xy 368.256612 -231.929493) (xy 368.226086 -231.887477) (xy 368.202508 -231.841203)
			(xy 368.18646 -231.79181) (xy 368.178335 -231.740515) (xy 367.898933 -231.740515) (xy 367.890808 -231.79181)
			(xy 367.87476 -231.841203) (xy 367.851182 -231.887477) (xy 367.820656 -231.929493) (xy 367.783933 -231.966216)
			(xy 367.741917 -231.996742) (xy 367.695643 -232.02032) (xy 367.64625 -232.036368) (xy 367.594955 -232.044493)
			(xy 367.543021 -232.044493) (xy 367.491726 -232.036368) (xy 367.442333 -232.02032) (xy 367.396059 -231.996742)
			(xy 367.354043 -231.966216) (xy 367.31732 -231.929493) (xy 367.286794 -231.887477) (xy 367.263216 -231.841203)
			(xy 367.247168 -231.79181) (xy 367.239043 -231.740515) (xy 366.958625 -231.740515) (xy 366.9505 -231.79181)
			(xy 366.934452 -231.841203) (xy 366.910874 -231.887477) (xy 366.880348 -231.929493) (xy 366.843625 -231.966216)
			(xy 366.801609 -231.996742) (xy 366.755335 -232.02032) (xy 366.705942 -232.036368) (xy 366.654647 -232.044493)
			(xy 366.602713 -232.044493) (xy 366.551418 -232.036368) (xy 366.502025 -232.02032) (xy 366.455751 -231.996742)
			(xy 366.413735 -231.966216) (xy 366.377012 -231.929493) (xy 366.346486 -231.887477) (xy 366.322908 -231.841203)
			(xy 366.30686 -231.79181) (xy 366.298735 -231.740515) (xy 366.018825 -231.740515) (xy 366.0107 -231.79181)
			(xy 365.994652 -231.841203) (xy 365.971074 -231.887477) (xy 365.940548 -231.929493) (xy 365.903825 -231.966216)
			(xy 365.861809 -231.996742) (xy 365.815535 -232.02032) (xy 365.766142 -232.036368) (xy 365.714847 -232.044493)
			(xy 365.662913 -232.044493) (xy 365.611618 -232.036368) (xy 365.562225 -232.02032) (xy 365.515951 -231.996742)
			(xy 365.473935 -231.966216) (xy 365.437212 -231.929493) (xy 365.406686 -231.887477) (xy 365.383108 -231.841203)
			(xy 365.36706 -231.79181) (xy 365.358935 -231.740515) (xy 365.079025 -231.740515) (xy 365.0709 -231.79181)
			(xy 365.054852 -231.841203) (xy 365.031274 -231.887477) (xy 365.000748 -231.929493) (xy 364.964025 -231.966216)
			(xy 364.922009 -231.996742) (xy 364.875735 -232.02032) (xy 364.826342 -232.036368) (xy 364.775047 -232.044493)
			(xy 364.723113 -232.044493) (xy 364.671818 -232.036368) (xy 364.622425 -232.02032) (xy 364.576151 -231.996742)
			(xy 364.534135 -231.966216) (xy 364.497412 -231.929493) (xy 364.466886 -231.887477) (xy 364.443308 -231.841203)
			(xy 364.42726 -231.79181) (xy 364.419135 -231.740515) (xy 364.139225 -231.740515) (xy 364.1311 -231.79181)
			(xy 364.115052 -231.841203) (xy 364.091474 -231.887477) (xy 364.060948 -231.929493) (xy 364.024225 -231.966216)
			(xy 363.982209 -231.996742) (xy 363.935935 -232.02032) (xy 363.886542 -232.036368) (xy 363.835247 -232.044493)
			(xy 363.783313 -232.044493) (xy 363.732018 -232.036368) (xy 363.682625 -232.02032) (xy 363.636351 -231.996742)
			(xy 363.594335 -231.966216) (xy 363.557612 -231.929493) (xy 363.527086 -231.887477) (xy 363.503508 -231.841203)
			(xy 363.48746 -231.79181) (xy 363.479335 -231.740515) (xy 363.199415 -231.740515) (xy 363.191299 -231.79176)
			(xy 363.17525 -231.841151) (xy 363.151672 -231.887423) (xy 363.121146 -231.929437) (xy 363.084422 -231.966159)
			(xy 363.042406 -231.996683) (xy 362.996133 -232.020258) (xy 362.946741 -232.036303) (xy 362.895447 -232.044425)
			(xy 362.86948 -232.045002) (xy 362.845601 -232.04458) (xy 362.798341 -232.037701) (xy 362.752563 -232.024089)
			(xy 362.709223 -232.004029) (xy 362.669222 -231.977937) (xy 362.65104 -231.962452) (xy 362.639765 -231.953181)
			(xy 362.613291 -231.94091) (xy 362.584429 -231.936623) (xy 362.555531 -231.940668) (xy 362.528955 -231.952716)
			(xy 362.506869 -231.971784) (xy 362.491072 -231.996318) (xy 362.482854 -232.024316) (xy 362.482384 -232.038906)
			(xy 362.482384 -232.206546) (xy 362.515404 -232.218738) (xy 362.538739 -232.227946) (xy 362.582542 -232.252389)
			(xy 362.62215 -232.283171) (xy 362.656651 -232.319584) (xy 362.685254 -232.360792) (xy 362.707303 -232.405849)
			(xy 362.72229 -232.45372) (xy 362.729871 -232.503306) (xy 362.729873 -232.553469) (xy 362.729741 -232.554331)
			(xy 363.009689 -232.554331) (xy 363.009689 -232.502397) (xy 363.017814 -232.451102) (xy 363.033862 -232.401709)
			(xy 363.05744 -232.355435) (xy 363.087966 -232.313419) (xy 363.124689 -232.276696) (xy 363.166705 -232.24617)
			(xy 363.212979 -232.222592) (xy 363.262372 -232.206544) (xy 363.313667 -232.198419) (xy 363.365601 -232.198419)
			(xy 363.416896 -232.206544) (xy 363.466289 -232.222592) (xy 363.512563 -232.24617) (xy 363.554579 -232.276696)
			(xy 363.591302 -232.313419) (xy 363.621828 -232.355435) (xy 363.645406 -232.401709) (xy 363.661454 -232.451102)
			(xy 363.669579 -232.502397) (xy 363.670088 -232.528364) (xy 363.669579 -232.554331) (xy 363.949489 -232.554331)
			(xy 363.949489 -232.502397) (xy 363.957614 -232.451102) (xy 363.973662 -232.401709) (xy 363.99724 -232.355435)
			(xy 364.027766 -232.313419) (xy 364.064489 -232.276696) (xy 364.106505 -232.24617) (xy 364.152779 -232.222592)
			(xy 364.202172 -232.206544) (xy 364.253467 -232.198419) (xy 364.305401 -232.198419) (xy 364.356696 -232.206544)
			(xy 364.406089 -232.222592) (xy 364.452363 -232.24617) (xy 364.494379 -232.276696) (xy 364.531102 -232.313419)
			(xy 364.561628 -232.355435) (xy 364.585206 -232.401709) (xy 364.601254 -232.451102) (xy 364.609379 -232.502397)
			(xy 364.609888 -232.528364) (xy 364.609379 -232.554331) (xy 364.889289 -232.554331) (xy 364.889289 -232.502397)
			(xy 364.897414 -232.451102) (xy 364.913462 -232.401709) (xy 364.93704 -232.355435) (xy 364.967566 -232.313419)
			(xy 365.004289 -232.276696) (xy 365.046305 -232.24617) (xy 365.092579 -232.222592) (xy 365.141972 -232.206544)
			(xy 365.193267 -232.198419) (xy 365.245201 -232.198419) (xy 365.296496 -232.206544) (xy 365.345889 -232.222592)
			(xy 365.392163 -232.24617) (xy 365.434179 -232.276696) (xy 365.470902 -232.313419) (xy 365.501428 -232.355435)
			(xy 365.525006 -232.401709) (xy 365.541054 -232.451102) (xy 365.549179 -232.502397) (xy 365.549688 -232.528364)
			(xy 365.549179 -232.554331) (xy 365.829089 -232.554331) (xy 365.829089 -232.502397) (xy 365.837214 -232.451102)
			(xy 365.853262 -232.401709) (xy 365.87684 -232.355435) (xy 365.907366 -232.313419) (xy 365.944089 -232.276696)
			(xy 365.986105 -232.24617) (xy 366.032379 -232.222592) (xy 366.081772 -232.206544) (xy 366.133067 -232.198419)
			(xy 366.185001 -232.198419) (xy 366.236296 -232.206544) (xy 366.285689 -232.222592) (xy 366.331963 -232.24617)
			(xy 366.373979 -232.276696) (xy 366.410702 -232.313419) (xy 366.441228 -232.355435) (xy 366.464806 -232.401709)
			(xy 366.480854 -232.451102) (xy 366.488979 -232.502397) (xy 366.489488 -232.528364) (xy 366.488979 -232.554331)
			(xy 366.768889 -232.554331) (xy 366.768889 -232.502397) (xy 366.777014 -232.451102) (xy 366.793062 -232.401709)
			(xy 366.81664 -232.355435) (xy 366.847166 -232.313419) (xy 366.883889 -232.276696) (xy 366.925905 -232.24617)
			(xy 366.972179 -232.222592) (xy 367.021572 -232.206544) (xy 367.072867 -232.198419) (xy 367.124801 -232.198419)
			(xy 367.176096 -232.206544) (xy 367.225489 -232.222592) (xy 367.271763 -232.24617) (xy 367.313779 -232.276696)
			(xy 367.350502 -232.313419) (xy 367.381028 -232.355435) (xy 367.404606 -232.401709) (xy 367.420654 -232.451102)
			(xy 367.428779 -232.502397) (xy 367.429288 -232.528364) (xy 367.428779 -232.554331) (xy 367.708435 -232.554331)
			(xy 367.708435 -232.502397) (xy 367.71656 -232.451102) (xy 367.732608 -232.401709) (xy 367.756186 -232.355435)
			(xy 367.786712 -232.313419) (xy 367.823435 -232.276696) (xy 367.865451 -232.24617) (xy 367.911725 -232.222592)
			(xy 367.961118 -232.206544) (xy 368.012413 -232.198419) (xy 368.064347 -232.198419) (xy 368.115642 -232.206544)
			(xy 368.165035 -232.222592) (xy 368.211309 -232.24617) (xy 368.253325 -232.276696) (xy 368.290048 -232.313419)
			(xy 368.320574 -232.355435) (xy 368.344152 -232.401709) (xy 368.3602 -232.451102) (xy 368.368325 -232.502397)
			(xy 368.368834 -232.528364) (xy 368.368325 -232.554331) (xy 368.648489 -232.554331) (xy 368.648489 -232.502397)
			(xy 368.656614 -232.451102) (xy 368.672662 -232.401709) (xy 368.69624 -232.355435) (xy 368.726766 -232.313419)
			(xy 368.763489 -232.276696) (xy 368.805505 -232.24617) (xy 368.851779 -232.222592) (xy 368.901172 -232.206544)
			(xy 368.952467 -232.198419) (xy 369.004401 -232.198419) (xy 369.055696 -232.206544) (xy 369.105089 -232.222592)
			(xy 369.151363 -232.24617) (xy 369.193379 -232.276696) (xy 369.230102 -232.313419) (xy 369.260628 -232.355435)
			(xy 369.284206 -232.401709) (xy 369.300254 -232.451102) (xy 369.308379 -232.502397) (xy 369.308888 -232.528364)
			(xy 369.308379 -232.554331) (xy 369.300254 -232.605626) (xy 369.284206 -232.655019) (xy 369.260628 -232.701293)
			(xy 369.230102 -232.743309) (xy 369.193379 -232.780032) (xy 369.151363 -232.810558) (xy 369.105089 -232.834136)
			(xy 369.055696 -232.850184) (xy 369.004401 -232.858309) (xy 368.952467 -232.858309) (xy 368.901172 -232.850184)
			(xy 368.851779 -232.834136) (xy 368.805505 -232.810558) (xy 368.763489 -232.780032) (xy 368.726766 -232.743309)
			(xy 368.69624 -232.701293) (xy 368.672662 -232.655019) (xy 368.656614 -232.605626) (xy 368.648489 -232.554331)
			(xy 368.368325 -232.554331) (xy 368.3602 -232.605626) (xy 368.344152 -232.655019) (xy 368.320574 -232.701293)
			(xy 368.290048 -232.743309) (xy 368.253325 -232.780032) (xy 368.211309 -232.810558) (xy 368.165035 -232.834136)
			(xy 368.115642 -232.850184) (xy 368.064347 -232.858309) (xy 368.012413 -232.858309) (xy 367.961118 -232.850184)
			(xy 367.911725 -232.834136) (xy 367.865451 -232.810558) (xy 367.823435 -232.780032) (xy 367.786712 -232.743309)
			(xy 367.756186 -232.701293) (xy 367.732608 -232.655019) (xy 367.71656 -232.605626) (xy 367.708435 -232.554331)
			(xy 367.428779 -232.554331) (xy 367.420654 -232.605626) (xy 367.404606 -232.655019) (xy 367.381028 -232.701293)
			(xy 367.350502 -232.743309) (xy 367.313779 -232.780032) (xy 367.271763 -232.810558) (xy 367.225489 -232.834136)
			(xy 367.176096 -232.850184) (xy 367.124801 -232.858309) (xy 367.072867 -232.858309) (xy 367.021572 -232.850184)
			(xy 366.972179 -232.834136) (xy 366.925905 -232.810558) (xy 366.883889 -232.780032) (xy 366.847166 -232.743309)
			(xy 366.81664 -232.701293) (xy 366.793062 -232.655019) (xy 366.777014 -232.605626) (xy 366.768889 -232.554331)
			(xy 366.488979 -232.554331) (xy 366.480854 -232.605626) (xy 366.464806 -232.655019) (xy 366.441228 -232.701293)
			(xy 366.410702 -232.743309) (xy 366.373979 -232.780032) (xy 366.331963 -232.810558) (xy 366.285689 -232.834136)
			(xy 366.236296 -232.850184) (xy 366.185001 -232.858309) (xy 366.133067 -232.858309) (xy 366.081772 -232.850184)
			(xy 366.032379 -232.834136) (xy 365.986105 -232.810558) (xy 365.944089 -232.780032) (xy 365.907366 -232.743309)
			(xy 365.87684 -232.701293) (xy 365.853262 -232.655019) (xy 365.837214 -232.605626) (xy 365.829089 -232.554331)
			(xy 365.549179 -232.554331) (xy 365.541054 -232.605626) (xy 365.525006 -232.655019) (xy 365.501428 -232.701293)
			(xy 365.470902 -232.743309) (xy 365.434179 -232.780032) (xy 365.392163 -232.810558) (xy 365.345889 -232.834136)
			(xy 365.296496 -232.850184) (xy 365.245201 -232.858309) (xy 365.193267 -232.858309) (xy 365.141972 -232.850184)
			(xy 365.092579 -232.834136) (xy 365.046305 -232.810558) (xy 365.004289 -232.780032) (xy 364.967566 -232.743309)
			(xy 364.93704 -232.701293) (xy 364.913462 -232.655019) (xy 364.897414 -232.605626) (xy 364.889289 -232.554331)
			(xy 364.609379 -232.554331) (xy 364.601254 -232.605626) (xy 364.585206 -232.655019) (xy 364.561628 -232.701293)
			(xy 364.531102 -232.743309) (xy 364.494379 -232.780032) (xy 364.452363 -232.810558) (xy 364.406089 -232.834136)
			(xy 364.356696 -232.850184) (xy 364.305401 -232.858309) (xy 364.253467 -232.858309) (xy 364.202172 -232.850184)
			(xy 364.152779 -232.834136) (xy 364.106505 -232.810558) (xy 364.064489 -232.780032) (xy 364.027766 -232.743309)
			(xy 363.99724 -232.701293) (xy 363.973662 -232.655019) (xy 363.957614 -232.605626) (xy 363.949489 -232.554331)
			(xy 363.669579 -232.554331) (xy 363.661454 -232.605626) (xy 363.645406 -232.655019) (xy 363.621828 -232.701293)
			(xy 363.591302 -232.743309) (xy 363.554579 -232.780032) (xy 363.512563 -232.810558) (xy 363.466289 -232.834136)
			(xy 363.416896 -232.850184) (xy 363.365601 -232.858309) (xy 363.313667 -232.858309) (xy 363.262372 -232.850184)
			(xy 363.212979 -232.834136) (xy 363.166705 -232.810558) (xy 363.124689 -232.780032) (xy 363.087966 -232.743309)
			(xy 363.05744 -232.701293) (xy 363.033862 -232.655019) (xy 363.017814 -232.605626) (xy 363.009689 -232.554331)
			(xy 362.729741 -232.554331) (xy 362.722295 -232.603055) (xy 362.707312 -232.650928) (xy 362.685267 -232.695986)
			(xy 362.656667 -232.737197) (xy 362.622168 -232.773612) (xy 362.582563 -232.804397) (xy 362.538761 -232.828844)
			(xy 362.515404 -232.83799) (xy 362.482384 -232.850182) (xy 362.482384 -233.017822) (xy 362.482858 -233.03241)
			(xy 362.491101 -233.060397) (xy 362.506909 -233.084918) (xy 362.528997 -233.10398) (xy 362.555567 -233.11603)
			(xy 362.584459 -233.12009) (xy 362.613321 -233.115828) (xy 362.639807 -233.103591) (xy 362.65104 -233.094276)
			(xy 362.669227 -233.078795) (xy 362.709221 -233.052692) (xy 362.75256 -233.032625) (xy 362.798338 -233.019014)
			(xy 362.8456 -233.012142) (xy 362.86948 -233.011726) (xy 362.895452 -233.012207) (xy 362.946757 -233.02033)
			(xy 362.996159 -233.03638) (xy 363.042442 -233.059959) (xy 363.084466 -233.09049) (xy 363.121197 -233.127218)
			(xy 363.15173 -233.169241) (xy 363.175313 -233.215523) (xy 363.191365 -233.264924) (xy 363.199491 -233.316228)
			(xy 363.199491 -233.368147) (xy 363.479335 -233.368147) (xy 363.479335 -233.316213) (xy 363.48746 -233.264918)
			(xy 363.503508 -233.215525) (xy 363.527086 -233.169251) (xy 363.557612 -233.127235) (xy 363.594335 -233.090512)
			(xy 363.636351 -233.059986) (xy 363.682625 -233.036408) (xy 363.732018 -233.02036) (xy 363.783313 -233.012235)
			(xy 363.835247 -233.012235) (xy 363.886542 -233.02036) (xy 363.935935 -233.036408) (xy 363.982209 -233.059986)
			(xy 364.024225 -233.090512) (xy 364.060948 -233.127235) (xy 364.091474 -233.169251) (xy 364.115052 -233.215525)
			(xy 364.1311 -233.264918) (xy 364.139225 -233.316213) (xy 364.139734 -233.34218) (xy 364.139225 -233.368147)
			(xy 364.419135 -233.368147) (xy 364.419135 -233.316213) (xy 364.42726 -233.264918) (xy 364.443308 -233.215525)
			(xy 364.466886 -233.169251) (xy 364.497412 -233.127235) (xy 364.534135 -233.090512) (xy 364.576151 -233.059986)
			(xy 364.622425 -233.036408) (xy 364.671818 -233.02036) (xy 364.723113 -233.012235) (xy 364.775047 -233.012235)
			(xy 364.826342 -233.02036) (xy 364.875735 -233.036408) (xy 364.922009 -233.059986) (xy 364.964025 -233.090512)
			(xy 365.000748 -233.127235) (xy 365.031274 -233.169251) (xy 365.054852 -233.215525) (xy 365.0709 -233.264918)
			(xy 365.079025 -233.316213) (xy 365.079534 -233.34218) (xy 365.079025 -233.368147) (xy 365.358935 -233.368147)
			(xy 365.358935 -233.316213) (xy 365.36706 -233.264918) (xy 365.383108 -233.215525) (xy 365.406686 -233.169251)
			(xy 365.437212 -233.127235) (xy 365.473935 -233.090512) (xy 365.515951 -233.059986) (xy 365.562225 -233.036408)
			(xy 365.611618 -233.02036) (xy 365.662913 -233.012235) (xy 365.714847 -233.012235) (xy 365.766142 -233.02036)
			(xy 365.815535 -233.036408) (xy 365.861809 -233.059986) (xy 365.903825 -233.090512) (xy 365.940548 -233.127235)
			(xy 365.971074 -233.169251) (xy 365.994652 -233.215525) (xy 366.0107 -233.264918) (xy 366.018825 -233.316213)
			(xy 366.019334 -233.34218) (xy 366.018825 -233.368147) (xy 366.298735 -233.368147) (xy 366.298735 -233.316213)
			(xy 366.30686 -233.264918) (xy 366.322908 -233.215525) (xy 366.346486 -233.169251) (xy 366.377012 -233.127235)
			(xy 366.413735 -233.090512) (xy 366.455751 -233.059986) (xy 366.502025 -233.036408) (xy 366.551418 -233.02036)
			(xy 366.602713 -233.012235) (xy 366.654647 -233.012235) (xy 366.705942 -233.02036) (xy 366.755335 -233.036408)
			(xy 366.801609 -233.059986) (xy 366.843625 -233.090512) (xy 366.880348 -233.127235) (xy 366.910874 -233.169251)
			(xy 366.934452 -233.215525) (xy 366.9505 -233.264918) (xy 366.958625 -233.316213) (xy 366.959134 -233.34218)
			(xy 366.958625 -233.368147) (xy 367.238535 -233.368147) (xy 367.238535 -233.316213) (xy 367.24666 -233.264918)
			(xy 367.262708 -233.215525) (xy 367.286286 -233.169251) (xy 367.316812 -233.127235) (xy 367.353535 -233.090512)
			(xy 367.395551 -233.059986) (xy 367.441825 -233.036408) (xy 367.491218 -233.02036) (xy 367.542513 -233.012235)
			(xy 367.594447 -233.012235) (xy 367.645742 -233.02036) (xy 367.695135 -233.036408) (xy 367.741409 -233.059986)
			(xy 367.783425 -233.090512) (xy 367.820148 -233.127235) (xy 367.850674 -233.169251) (xy 367.874252 -233.215525)
			(xy 367.8903 -233.264918) (xy 367.898425 -233.316213) (xy 367.898934 -233.34218) (xy 367.898425 -233.368147)
			(xy 368.178335 -233.368147) (xy 368.178335 -233.316213) (xy 368.18646 -233.264918) (xy 368.202508 -233.215525)
			(xy 368.226086 -233.169251) (xy 368.256612 -233.127235) (xy 368.293335 -233.090512) (xy 368.335351 -233.059986)
			(xy 368.381625 -233.036408) (xy 368.431018 -233.02036) (xy 368.482313 -233.012235) (xy 368.534247 -233.012235)
			(xy 368.585542 -233.02036) (xy 368.634935 -233.036408) (xy 368.681209 -233.059986) (xy 368.723225 -233.090512)
			(xy 368.759948 -233.127235) (xy 368.790474 -233.169251) (xy 368.814052 -233.215525) (xy 368.8301 -233.264918)
			(xy 368.838225 -233.316213) (xy 368.838734 -233.34218) (xy 368.838225 -233.368147) (xy 369.118389 -233.368147)
			(xy 369.118389 -233.316213) (xy 369.126514 -233.264918) (xy 369.142562 -233.215525) (xy 369.16614 -233.169251)
			(xy 369.196666 -233.127235) (xy 369.233389 -233.090512) (xy 369.275405 -233.059986) (xy 369.321679 -233.036408)
			(xy 369.371072 -233.02036) (xy 369.422367 -233.012235) (xy 369.474301 -233.012235) (xy 369.525596 -233.02036)
			(xy 369.574989 -233.036408) (xy 369.621263 -233.059986) (xy 369.663279 -233.090512) (xy 369.700002 -233.127235)
			(xy 369.730528 -233.169251) (xy 369.754106 -233.215525) (xy 369.770154 -233.264918) (xy 369.778279 -233.316213)
			(xy 369.778788 -233.34218) (xy 369.778279 -233.368147) (xy 369.770154 -233.419442) (xy 369.754106 -233.468835)
			(xy 369.730528 -233.515109) (xy 369.700002 -233.557125) (xy 369.663279 -233.593848) (xy 369.621263 -233.624374)
			(xy 369.574989 -233.647952) (xy 369.525596 -233.664) (xy 369.474301 -233.672125) (xy 369.422367 -233.672125)
			(xy 369.371072 -233.664) (xy 369.321679 -233.647952) (xy 369.275405 -233.624374) (xy 369.233389 -233.593848)
			(xy 369.196666 -233.557125) (xy 369.16614 -233.515109) (xy 369.142562 -233.468835) (xy 369.126514 -233.419442)
			(xy 369.118389 -233.368147) (xy 368.838225 -233.368147) (xy 368.8301 -233.419442) (xy 368.814052 -233.468835)
			(xy 368.790474 -233.515109) (xy 368.759948 -233.557125) (xy 368.723225 -233.593848) (xy 368.681209 -233.624374)
			(xy 368.634935 -233.647952) (xy 368.585542 -233.664) (xy 368.534247 -233.672125) (xy 368.482313 -233.672125)
			(xy 368.431018 -233.664) (xy 368.381625 -233.647952) (xy 368.335351 -233.624374) (xy 368.293335 -233.593848)
			(xy 368.256612 -233.557125) (xy 368.226086 -233.515109) (xy 368.202508 -233.468835) (xy 368.18646 -233.419442)
			(xy 368.178335 -233.368147) (xy 367.898425 -233.368147) (xy 367.8903 -233.419442) (xy 367.874252 -233.468835)
			(xy 367.850674 -233.515109) (xy 367.820148 -233.557125) (xy 367.783425 -233.593848) (xy 367.741409 -233.624374)
			(xy 367.695135 -233.647952) (xy 367.645742 -233.664) (xy 367.594447 -233.672125) (xy 367.542513 -233.672125)
			(xy 367.491218 -233.664) (xy 367.441825 -233.647952) (xy 367.395551 -233.624374) (xy 367.353535 -233.593848)
			(xy 367.316812 -233.557125) (xy 367.286286 -233.515109) (xy 367.262708 -233.468835) (xy 367.24666 -233.419442)
			(xy 367.238535 -233.368147) (xy 366.958625 -233.368147) (xy 366.9505 -233.419442) (xy 366.934452 -233.468835)
			(xy 366.910874 -233.515109) (xy 366.880348 -233.557125) (xy 366.843625 -233.593848) (xy 366.801609 -233.624374)
			(xy 366.755335 -233.647952) (xy 366.705942 -233.664) (xy 366.654647 -233.672125) (xy 366.602713 -233.672125)
			(xy 366.551418 -233.664) (xy 366.502025 -233.647952) (xy 366.455751 -233.624374) (xy 366.413735 -233.593848)
			(xy 366.377012 -233.557125) (xy 366.346486 -233.515109) (xy 366.322908 -233.468835) (xy 366.30686 -233.419442)
			(xy 366.298735 -233.368147) (xy 366.018825 -233.368147) (xy 366.0107 -233.419442) (xy 365.994652 -233.468835)
			(xy 365.971074 -233.515109) (xy 365.940548 -233.557125) (xy 365.903825 -233.593848) (xy 365.861809 -233.624374)
			(xy 365.815535 -233.647952) (xy 365.766142 -233.664) (xy 365.714847 -233.672125) (xy 365.662913 -233.672125)
			(xy 365.611618 -233.664) (xy 365.562225 -233.647952) (xy 365.515951 -233.624374) (xy 365.473935 -233.593848)
			(xy 365.437212 -233.557125) (xy 365.406686 -233.515109) (xy 365.383108 -233.468835) (xy 365.36706 -233.419442)
			(xy 365.358935 -233.368147) (xy 365.079025 -233.368147) (xy 365.0709 -233.419442) (xy 365.054852 -233.468835)
			(xy 365.031274 -233.515109) (xy 365.000748 -233.557125) (xy 364.964025 -233.593848) (xy 364.922009 -233.624374)
			(xy 364.875735 -233.647952) (xy 364.826342 -233.664) (xy 364.775047 -233.672125) (xy 364.723113 -233.672125)
			(xy 364.671818 -233.664) (xy 364.622425 -233.647952) (xy 364.576151 -233.624374) (xy 364.534135 -233.593848)
			(xy 364.497412 -233.557125) (xy 364.466886 -233.515109) (xy 364.443308 -233.468835) (xy 364.42726 -233.419442)
			(xy 364.419135 -233.368147) (xy 364.139225 -233.368147) (xy 364.1311 -233.419442) (xy 364.115052 -233.468835)
			(xy 364.091474 -233.515109) (xy 364.060948 -233.557125) (xy 364.024225 -233.593848) (xy 363.982209 -233.624374)
			(xy 363.935935 -233.647952) (xy 363.886542 -233.664) (xy 363.835247 -233.672125) (xy 363.783313 -233.672125)
			(xy 363.732018 -233.664) (xy 363.682625 -233.647952) (xy 363.636351 -233.624374) (xy 363.594335 -233.593848)
			(xy 363.557612 -233.557125) (xy 363.527086 -233.515109) (xy 363.503508 -233.468835) (xy 363.48746 -233.419442)
			(xy 363.479335 -233.368147) (xy 363.199491 -233.368147) (xy 363.199491 -233.368172) (xy 363.191365 -233.419476)
			(xy 363.175313 -233.468877) (xy 363.15173 -233.515159) (xy 363.121197 -233.557182) (xy 363.084466 -233.59391)
			(xy 363.042442 -233.624441) (xy 362.996159 -233.648021) (xy 362.946757 -233.66407) (xy 362.895452 -233.672193)
			(xy 362.86948 -233.672634) (xy 362.845601 -233.672212) (xy 362.798342 -233.665331) (xy 362.752566 -233.651718)
			(xy 362.709228 -233.631654) (xy 362.669231 -233.605559) (xy 362.65104 -233.590084) (xy 362.639767 -233.580811)
			(xy 362.613295 -233.568537) (xy 362.584433 -233.564247) (xy 362.555536 -233.568292) (xy 362.528961 -233.580342)
			(xy 362.506877 -233.599412) (xy 362.491085 -233.623948) (xy 362.482874 -233.651948) (xy 362.482384 -233.666538)
			(xy 362.482384 -233.834432) (xy 362.515404 -233.846624) (xy 362.53874 -233.855832) (xy 362.582545 -233.880276)
			(xy 362.622155 -233.911058) (xy 362.656658 -233.947472) (xy 362.685263 -233.988681) (xy 362.707313 -234.03374)
			(xy 362.722301 -234.081612) (xy 362.729884 -234.1312) (xy 362.729887 -234.181365) (xy 362.729757 -234.182217)
			(xy 363.009689 -234.182217) (xy 363.009689 -234.130283) (xy 363.017814 -234.078988) (xy 363.033862 -234.029595)
			(xy 363.05744 -233.983321) (xy 363.087966 -233.941305) (xy 363.124689 -233.904582) (xy 363.166705 -233.874056)
			(xy 363.212979 -233.850478) (xy 363.262372 -233.83443) (xy 363.313667 -233.826305) (xy 363.365601 -233.826305)
			(xy 363.416896 -233.83443) (xy 363.466289 -233.850478) (xy 363.512563 -233.874056) (xy 363.554579 -233.904582)
			(xy 363.591302 -233.941305) (xy 363.621828 -233.983321) (xy 363.645406 -234.029595) (xy 363.661454 -234.078988)
			(xy 363.669579 -234.130283) (xy 363.670088 -234.15625) (xy 363.669579 -234.182217) (xy 363.949489 -234.182217)
			(xy 363.949489 -234.130283) (xy 363.957614 -234.078988) (xy 363.973662 -234.029595) (xy 363.99724 -233.983321)
			(xy 364.027766 -233.941305) (xy 364.064489 -233.904582) (xy 364.106505 -233.874056) (xy 364.152779 -233.850478)
			(xy 364.202172 -233.83443) (xy 364.253467 -233.826305) (xy 364.305401 -233.826305) (xy 364.356696 -233.83443)
			(xy 364.406089 -233.850478) (xy 364.452363 -233.874056) (xy 364.494379 -233.904582) (xy 364.531102 -233.941305)
			(xy 364.561628 -233.983321) (xy 364.585206 -234.029595) (xy 364.601254 -234.078988) (xy 364.609379 -234.130283)
			(xy 364.609888 -234.15625) (xy 364.609379 -234.182217) (xy 364.889289 -234.182217) (xy 364.889289 -234.130283)
			(xy 364.897414 -234.078988) (xy 364.913462 -234.029595) (xy 364.93704 -233.983321) (xy 364.967566 -233.941305)
			(xy 365.004289 -233.904582) (xy 365.046305 -233.874056) (xy 365.092579 -233.850478) (xy 365.141972 -233.83443)
			(xy 365.193267 -233.826305) (xy 365.245201 -233.826305) (xy 365.296496 -233.83443) (xy 365.345889 -233.850478)
			(xy 365.392163 -233.874056) (xy 365.434179 -233.904582) (xy 365.470902 -233.941305) (xy 365.501428 -233.983321)
			(xy 365.525006 -234.029595) (xy 365.541054 -234.078988) (xy 365.549179 -234.130283) (xy 365.549688 -234.15625)
			(xy 365.549179 -234.182217) (xy 365.829089 -234.182217) (xy 365.829089 -234.130283) (xy 365.837214 -234.078988)
			(xy 365.853262 -234.029595) (xy 365.87684 -233.983321) (xy 365.907366 -233.941305) (xy 365.944089 -233.904582)
			(xy 365.986105 -233.874056) (xy 366.032379 -233.850478) (xy 366.081772 -233.83443) (xy 366.133067 -233.826305)
			(xy 366.185001 -233.826305) (xy 366.236296 -233.83443) (xy 366.285689 -233.850478) (xy 366.331963 -233.874056)
			(xy 366.373979 -233.904582) (xy 366.410702 -233.941305) (xy 366.441228 -233.983321) (xy 366.464806 -234.029595)
			(xy 366.480854 -234.078988) (xy 366.488979 -234.130283) (xy 366.489488 -234.15625) (xy 366.488979 -234.182217)
			(xy 366.768889 -234.182217) (xy 366.768889 -234.130283) (xy 366.777014 -234.078988) (xy 366.793062 -234.029595)
			(xy 366.81664 -233.983321) (xy 366.847166 -233.941305) (xy 366.883889 -233.904582) (xy 366.925905 -233.874056)
			(xy 366.972179 -233.850478) (xy 367.021572 -233.83443) (xy 367.072867 -233.826305) (xy 367.124801 -233.826305)
			(xy 367.176096 -233.83443) (xy 367.225489 -233.850478) (xy 367.271763 -233.874056) (xy 367.313779 -233.904582)
			(xy 367.350502 -233.941305) (xy 367.381028 -233.983321) (xy 367.404606 -234.029595) (xy 367.420654 -234.078988)
			(xy 367.428779 -234.130283) (xy 367.429288 -234.15625) (xy 367.428779 -234.182217) (xy 367.708689 -234.182217)
			(xy 367.708689 -234.130283) (xy 367.716814 -234.078988) (xy 367.732862 -234.029595) (xy 367.75644 -233.983321)
			(xy 367.786966 -233.941305) (xy 367.823689 -233.904582) (xy 367.865705 -233.874056) (xy 367.911979 -233.850478)
			(xy 367.961372 -233.83443) (xy 368.012667 -233.826305) (xy 368.064601 -233.826305) (xy 368.115896 -233.83443)
			(xy 368.165289 -233.850478) (xy 368.211563 -233.874056) (xy 368.253579 -233.904582) (xy 368.290302 -233.941305)
			(xy 368.320828 -233.983321) (xy 368.344406 -234.029595) (xy 368.360454 -234.078988) (xy 368.368579 -234.130283)
			(xy 368.369088 -234.15625) (xy 368.368579 -234.182217) (xy 368.648235 -234.182217) (xy 368.648235 -234.130283)
			(xy 368.65636 -234.078988) (xy 368.672408 -234.029595) (xy 368.695986 -233.983321) (xy 368.726512 -233.941305)
			(xy 368.763235 -233.904582) (xy 368.805251 -233.874056) (xy 368.851525 -233.850478) (xy 368.900918 -233.83443)
			(xy 368.952213 -233.826305) (xy 369.004147 -233.826305) (xy 369.055442 -233.83443) (xy 369.104835 -233.850478)
			(xy 369.151109 -233.874056) (xy 369.193125 -233.904582) (xy 369.229848 -233.941305) (xy 369.260374 -233.983321)
			(xy 369.283952 -234.029595) (xy 369.3 -234.078988) (xy 369.308125 -234.130283) (xy 369.308634 -234.15625)
			(xy 369.308125 -234.182217) (xy 369.3 -234.233512) (xy 369.283952 -234.282905) (xy 369.260374 -234.329179)
			(xy 369.229848 -234.371195) (xy 369.193125 -234.407918) (xy 369.151109 -234.438444) (xy 369.104835 -234.462022)
			(xy 369.055442 -234.47807) (xy 369.004147 -234.486195) (xy 368.952213 -234.486195) (xy 368.900918 -234.47807)
			(xy 368.851525 -234.462022) (xy 368.805251 -234.438444) (xy 368.763235 -234.407918) (xy 368.726512 -234.371195)
			(xy 368.695986 -234.329179) (xy 368.672408 -234.282905) (xy 368.65636 -234.233512) (xy 368.648235 -234.182217)
			(xy 368.368579 -234.182217) (xy 368.360454 -234.233512) (xy 368.344406 -234.282905) (xy 368.320828 -234.329179)
			(xy 368.290302 -234.371195) (xy 368.253579 -234.407918) (xy 368.211563 -234.438444) (xy 368.165289 -234.462022)
			(xy 368.115896 -234.47807) (xy 368.064601 -234.486195) (xy 368.012667 -234.486195) (xy 367.961372 -234.47807)
			(xy 367.911979 -234.462022) (xy 367.865705 -234.438444) (xy 367.823689 -234.407918) (xy 367.786966 -234.371195)
			(xy 367.75644 -234.329179) (xy 367.732862 -234.282905) (xy 367.716814 -234.233512) (xy 367.708689 -234.182217)
			(xy 367.428779 -234.182217) (xy 367.420654 -234.233512) (xy 367.404606 -234.282905) (xy 367.381028 -234.329179)
			(xy 367.350502 -234.371195) (xy 367.313779 -234.407918) (xy 367.271763 -234.438444) (xy 367.225489 -234.462022)
			(xy 367.176096 -234.47807) (xy 367.124801 -234.486195) (xy 367.072867 -234.486195) (xy 367.021572 -234.47807)
			(xy 366.972179 -234.462022) (xy 366.925905 -234.438444) (xy 366.883889 -234.407918) (xy 366.847166 -234.371195)
			(xy 366.81664 -234.329179) (xy 366.793062 -234.282905) (xy 366.777014 -234.233512) (xy 366.768889 -234.182217)
			(xy 366.488979 -234.182217) (xy 366.480854 -234.233512) (xy 366.464806 -234.282905) (xy 366.441228 -234.329179)
			(xy 366.410702 -234.371195) (xy 366.373979 -234.407918) (xy 366.331963 -234.438444) (xy 366.285689 -234.462022)
			(xy 366.236296 -234.47807) (xy 366.185001 -234.486195) (xy 366.133067 -234.486195) (xy 366.081772 -234.47807)
			(xy 366.032379 -234.462022) (xy 365.986105 -234.438444) (xy 365.944089 -234.407918) (xy 365.907366 -234.371195)
			(xy 365.87684 -234.329179) (xy 365.853262 -234.282905) (xy 365.837214 -234.233512) (xy 365.829089 -234.182217)
			(xy 365.549179 -234.182217) (xy 365.541054 -234.233512) (xy 365.525006 -234.282905) (xy 365.501428 -234.329179)
			(xy 365.470902 -234.371195) (xy 365.434179 -234.407918) (xy 365.392163 -234.438444) (xy 365.345889 -234.462022)
			(xy 365.296496 -234.47807) (xy 365.245201 -234.486195) (xy 365.193267 -234.486195) (xy 365.141972 -234.47807)
			(xy 365.092579 -234.462022) (xy 365.046305 -234.438444) (xy 365.004289 -234.407918) (xy 364.967566 -234.371195)
			(xy 364.93704 -234.329179) (xy 364.913462 -234.282905) (xy 364.897414 -234.233512) (xy 364.889289 -234.182217)
			(xy 364.609379 -234.182217) (xy 364.601254 -234.233512) (xy 364.585206 -234.282905) (xy 364.561628 -234.329179)
			(xy 364.531102 -234.371195) (xy 364.494379 -234.407918) (xy 364.452363 -234.438444) (xy 364.406089 -234.462022)
			(xy 364.356696 -234.47807) (xy 364.305401 -234.486195) (xy 364.253467 -234.486195) (xy 364.202172 -234.47807)
			(xy 364.152779 -234.462022) (xy 364.106505 -234.438444) (xy 364.064489 -234.407918) (xy 364.027766 -234.371195)
			(xy 363.99724 -234.329179) (xy 363.973662 -234.282905) (xy 363.957614 -234.233512) (xy 363.949489 -234.182217)
			(xy 363.669579 -234.182217) (xy 363.661454 -234.233512) (xy 363.645406 -234.282905) (xy 363.621828 -234.329179)
			(xy 363.591302 -234.371195) (xy 363.554579 -234.407918) (xy 363.512563 -234.438444) (xy 363.466289 -234.462022)
			(xy 363.416896 -234.47807) (xy 363.365601 -234.486195) (xy 363.313667 -234.486195) (xy 363.262372 -234.47807)
			(xy 363.212979 -234.462022) (xy 363.166705 -234.438444) (xy 363.124689 -234.407918) (xy 363.087966 -234.371195)
			(xy 363.05744 -234.329179) (xy 363.033862 -234.282905) (xy 363.017814 -234.233512) (xy 363.009689 -234.182217)
			(xy 362.729757 -234.182217) (xy 362.722309 -234.230953) (xy 362.707326 -234.278828) (xy 362.685281 -234.323889)
			(xy 362.65668 -234.365101) (xy 362.622181 -234.401519) (xy 362.582575 -234.432305) (xy 362.538771 -234.456754)
			(xy 362.515404 -234.465876) (xy 362.482384 -234.478068) (xy 362.482384 -234.996033) (xy 369.118135 -234.996033)
			(xy 369.118135 -234.944099) (xy 369.12626 -234.892804) (xy 369.142308 -234.843411) (xy 369.165886 -234.797137)
			(xy 369.196412 -234.755121) (xy 369.233135 -234.718398) (xy 369.275151 -234.687872) (xy 369.321425 -234.664294)
			(xy 369.370818 -234.648246) (xy 369.422113 -234.640121) (xy 369.474047 -234.640121) (xy 369.525342 -234.648246)
			(xy 369.574735 -234.664294) (xy 369.621009 -234.687872) (xy 369.663025 -234.718398) (xy 369.699748 -234.755121)
			(xy 369.730274 -234.797137) (xy 369.753852 -234.843411) (xy 369.7699 -234.892804) (xy 369.778025 -234.944099)
			(xy 369.778534 -234.970066) (xy 369.778025 -234.996033) (xy 369.7699 -235.047328) (xy 369.753852 -235.096721)
			(xy 369.730274 -235.142995) (xy 369.699748 -235.185011) (xy 369.663025 -235.221734) (xy 369.621009 -235.25226)
			(xy 369.574735 -235.275838) (xy 369.525342 -235.291886) (xy 369.474047 -235.300011) (xy 369.422113 -235.300011)
			(xy 369.370818 -235.291886) (xy 369.321425 -235.275838) (xy 369.275151 -235.25226) (xy 369.233135 -235.221734)
			(xy 369.196412 -235.185011) (xy 369.165886 -235.142995) (xy 369.142308 -235.096721) (xy 369.12626 -235.047328)
			(xy 369.118135 -234.996033) (xy 362.482384 -234.996033) (xy 362.482384 -235.462064) (xy 362.515404 -235.474256)
			(xy 362.538738 -235.48346) (xy 362.582541 -235.507897) (xy 362.622147 -235.538675) (xy 362.656645 -235.575085)
			(xy 362.685244 -235.616292) (xy 362.707285 -235.661348) (xy 362.722263 -235.709219) (xy 362.729832 -235.758803)
			(xy 362.730288 -235.783882) (xy 362.729733 -235.810399) (xy 362.721213 -235.862745) (xy 362.704452 -235.913062)
			(xy 362.679881 -235.960061) (xy 362.648127 -236.00254) (xy 362.62945 -236.021372) (xy 362.871004 -236.262926)
			(xy 363.147356 -236.262926)
		)
		(stroke
			(width 0)
			(type solid)
		)
		(fill yes)
		(layer "In11.Cu")
		(net "PVCCINFAON_CPU0")
	)
	(gr_poly
		(pts
			(xy 21.131022 -183.535066) (xy 21.144405 -183.534659) (xy 21.17025 -183.527693) (xy 21.193394 -183.514246)
			(xy 21.212245 -183.495242) (xy 21.225506 -183.471991) (xy 21.232264 -183.446091) (xy 21.232622 -183.432704)
			(xy 21.232622 -183.429656) (xy 21.233108 -183.402405) (xy 21.240864 -183.348457) (xy 21.256219 -183.296162)
			(xy 21.278861 -183.246585) (xy 21.308327 -183.200735) (xy 21.344018 -183.159544) (xy 21.385209 -183.123853)
			(xy 21.431059 -183.094387) (xy 21.480636 -183.071745) (xy 21.532931 -183.05639) (xy 21.586879 -183.048634)
			(xy 21.641381 -183.048634) (xy 21.695329 -183.05639) (xy 21.747624 -183.071745) (xy 21.797201 -183.094387)
			(xy 21.843051 -183.123853) (xy 21.884242 -183.159544) (xy 21.919933 -183.200735) (xy 21.949399 -183.246585)
			(xy 21.972041 -183.296162) (xy 21.987396 -183.348457) (xy 21.995152 -183.402405) (xy 21.995638 -183.429656)
			(xy 21.995638 -183.432704) (xy 21.995938 -183.446095) (xy 22.002701 -183.472004) (xy 22.015971 -183.495262)
			(xy 22.034834 -183.514266) (xy 22.057992 -183.527709) (xy 22.083849 -183.534665) (xy 22.097238 -183.535066)
			(xy 22.826726 -183.535066) (xy 22.84104 -183.534577) (xy 22.868543 -183.526629) (xy 22.892761 -183.511364)
			(xy 22.911795 -183.48998) (xy 22.92415 -183.464156) (xy 22.928857 -183.435917) (xy 22.925547 -183.407481)
			(xy 22.920452 -183.394096) (xy 22.910051 -183.369602) (xy 22.895363 -183.318454) (xy 22.887916 -183.265763)
			(xy 22.887432 -183.239156) (xy 22.887432 -183.23433) (xy 22.888244 -183.207304) (xy 22.896554 -183.153877)
			(xy 22.912323 -183.102159) (xy 22.935235 -183.053186) (xy 22.964832 -183.007937) (xy 23.000521 -182.96732)
			(xy 23.041586 -182.932148) (xy 23.087205 -182.903126) (xy 23.136465 -182.880835) (xy 23.188379 -182.865721)
			(xy 23.241906 -182.858088) (xy 23.295974 -182.858088) (xy 23.349501 -182.865721) (xy 23.401415 -182.880835)
			(xy 23.450675 -182.903126) (xy 23.496294 -182.932148) (xy 23.537359 -182.96732) (xy 23.573048 -183.007937)
			(xy 23.602645 -183.053186) (xy 23.625557 -183.102159) (xy 23.641326 -183.153877) (xy 23.649636 -183.207304)
			(xy 23.650448 -183.23433) (xy 23.650448 -183.239156) (xy 23.649975 -183.26567) (xy 23.642597 -183.318182)
			(xy 23.628017 -183.369167) (xy 23.617682 -183.393588) (xy 23.617174 -183.395112) (xy 23.612238 -183.40847)
			(xy 23.609177 -183.436772) (xy 23.614043 -183.46482) (xy 23.626458 -183.490436) (xy 23.645459 -183.511633)
			(xy 23.669571 -183.526766) (xy 23.696921 -183.534659) (xy 23.711154 -183.535066) (xy 35.177984 -183.535066)
			(xy 35.191415 -183.534659) (xy 35.21735 -183.52766) (xy 35.240564 -183.514142) (xy 35.25945 -183.495039)
			(xy 35.272703 -183.471673) (xy 35.279406 -183.44566) (xy 35.279095 -183.418799) (xy 35.275774 -183.40578)
			(xy 35.269009 -183.380278) (xy 35.261751 -183.32802) (xy 35.261296 -183.30164) (xy 35.261757 -183.274385)
			(xy 35.269509 -183.22043) (xy 35.284862 -183.168128) (xy 35.307502 -183.118543) (xy 35.336969 -183.072685)
			(xy 35.372663 -183.031488) (xy 35.413856 -182.99579) (xy 35.459711 -182.966319) (xy 35.509294 -182.943674)
			(xy 35.561595 -182.928317) (xy 35.615549 -182.920559) (xy 35.642804 -182.920132) (xy 35.670442 -182.920624)
			(xy 35.725139 -182.928607) (xy 35.77811 -182.944405) (xy 35.828244 -182.967686) (xy 35.874491 -182.997964)
			(xy 35.895534 -183.01589) (xy 35.906671 -183.024499) (xy 35.932433 -183.035817) (xy 35.960304 -183.039688)
			(xy 35.988175 -183.035817) (xy 36.013937 -183.024499) (xy 36.025074 -183.01589) (xy 36.046103 -182.997949)
			(xy 36.09236 -182.967689) (xy 36.142499 -182.944418) (xy 36.19547 -182.928623) (xy 36.250166 -182.920636)
			(xy 36.277804 -182.920132) (xy 36.305539 -182.920637) (xy 36.360424 -182.928682) (xy 36.413566 -182.944587)
			(xy 36.463845 -182.968018) (xy 36.510203 -182.998481) (xy 36.551663 -183.035333) (xy 36.587352 -183.077799)
			(xy 36.616517 -183.124984) (xy 36.638544 -183.175894) (xy 36.652969 -183.229457) (xy 36.656772 -183.256936)
			(xy 36.658296 -183.27116) (xy 36.659566 -183.30164) (xy 36.659566 -183.302148) (xy 36.65904 -183.330054)
			(xy 36.650883 -183.385267) (xy 36.64331 -183.41213) (xy 36.640669 -183.427033) (xy 36.643243 -183.457173)
			(xy 36.654524 -183.48524) (xy 36.673524 -183.508778) (xy 36.698581 -183.525726) (xy 36.7275 -183.534599)
			(xy 36.742624 -183.535066) (xy 40.461184 -183.535066) (xy 40.474615 -183.534659) (xy 40.50055 -183.52766)
			(xy 40.523764 -183.514142) (xy 40.54265 -183.495039) (xy 40.555903 -183.471673) (xy 40.562606 -183.44566)
			(xy 40.562295 -183.418799) (xy 40.558974 -183.40578) (xy 40.552209 -183.380278) (xy 40.544951 -183.32802)
			(xy 40.544496 -183.30164) (xy 40.544957 -183.274385) (xy 40.552709 -183.22043) (xy 40.568062 -183.168128)
			(xy 40.590702 -183.118543) (xy 40.620169 -183.072685) (xy 40.655863 -183.031488) (xy 40.697056 -182.99579)
			(xy 40.742911 -182.966319) (xy 40.792494 -182.943674) (xy 40.844795 -182.928317) (xy 40.898749 -182.920559)
			(xy 40.926004 -182.920132) (xy 40.953642 -182.920624) (xy 41.008339 -182.928607) (xy 41.06131 -182.944405)
			(xy 41.111444 -182.967686) (xy 41.157691 -182.997964) (xy 41.178734 -183.01589) (xy 41.189871 -183.024499)
			(xy 41.215633 -183.035817) (xy 41.243504 -183.039688) (xy 41.271375 -183.035817) (xy 41.297137 -183.024499)
			(xy 41.308274 -183.01589) (xy 41.329303 -182.997949) (xy 41.37556 -182.967689) (xy 41.425699 -182.944418)
			(xy 41.47867 -182.928623) (xy 41.533366 -182.920636) (xy 41.561004 -182.920132) (xy 41.588739 -182.920637)
			(xy 41.643624 -182.928682) (xy 41.696766 -182.944587) (xy 41.747045 -182.968018) (xy 41.793403 -182.998481)
			(xy 41.834863 -183.035333) (xy 41.870552 -183.077799) (xy 41.899717 -183.124984) (xy 41.921744 -183.175894)
			(xy 41.936169 -183.229457) (xy 41.939972 -183.256936) (xy 41.941496 -183.27116) (xy 41.942766 -183.30164)
			(xy 41.942766 -183.302148) (xy 41.94224 -183.330054) (xy 41.934083 -183.385267) (xy 41.92651 -183.41213)
			(xy 41.923869 -183.427033) (xy 41.926443 -183.457173) (xy 41.937724 -183.48524) (xy 41.956724 -183.508778)
			(xy 41.981781 -183.525726) (xy 42.0107 -183.534599) (xy 42.025824 -183.535066) (xy 56.632348 -183.535066)
			(xy 57.387744 -182.77967) (xy 57.390284 -182.763414) (xy 57.394846 -182.737046) (xy 57.410388 -182.685841)
			(xy 57.432934 -182.63731) (xy 57.46204 -182.592406) (xy 57.497137 -182.552012) (xy 57.537536 -182.516918)
			(xy 57.582442 -182.487816) (xy 57.630975 -182.465275) (xy 57.682182 -182.449738) (xy 57.708546 -182.445152)
			(xy 57.724802 -182.442612) (xy 59.459368 -180.708046) (xy 59.459368 -143.211296) (xy 58.66384 -142.415768)
			(xy 33.685734 -142.415768) (xy 31.612867 -144.48872) (xy 51.012924 -144.48872) (xy 51.012928 -144.434227)
			(xy 51.020687 -144.380288) (xy 51.036042 -144.328003) (xy 51.058683 -144.278435) (xy 51.088146 -144.232593)
			(xy 51.123834 -144.191411) (xy 51.165019 -144.155727) (xy 51.210863 -144.126267) (xy 51.260433 -144.103631)
			(xy 51.312719 -144.08828) (xy 51.366659 -144.080526) (xy 51.421152 -144.080526) (xy 51.475091 -144.088282)
			(xy 51.527377 -144.103635) (xy 51.576946 -144.126272) (xy 51.62279 -144.155734) (xy 51.663974 -144.191419)
			(xy 51.69966 -144.232602) (xy 51.729122 -144.278444) (xy 51.736434 -144.294455) (xy 53.058229 -144.294455)
			(xy 53.058229 -144.239945) (xy 53.065987 -144.185989) (xy 53.081345 -144.133686) (xy 53.10399 -144.084102)
			(xy 53.133461 -144.038245) (xy 53.169159 -143.997049) (xy 53.210356 -143.961353) (xy 53.256214 -143.931883)
			(xy 53.305799 -143.90924) (xy 53.358102 -143.893884) (xy 53.412059 -143.886128) (xy 53.439314 -143.885666)
			(xy 53.439822 -143.885666) (xy 53.472957 -143.886408) (xy 53.538223 -143.8979) (xy 53.569616 -143.908526)
			(xy 53.583198 -143.913028) (xy 53.611739 -143.914958) (xy 53.639697 -143.908906) (xy 53.664884 -143.895343)
			(xy 53.685327 -143.875334) (xy 53.699426 -143.850443) (xy 53.70322 -143.836644) (xy 53.710286 -143.809161)
			(xy 53.73138 -143.756484) (xy 53.760045 -143.707514) (xy 53.795649 -143.663332) (xy 53.837407 -143.624912)
			(xy 53.884396 -143.593104) (xy 53.93558 -143.568608) (xy 53.989828 -143.551967) (xy 54.045943 -143.543547)
			(xy 54.074314 -143.54302) (xy 54.101567 -143.543451) (xy 54.155517 -143.55121) (xy 54.207814 -143.566567)
			(xy 54.257393 -143.589211) (xy 54.303245 -143.618679) (xy 54.344436 -143.654374) (xy 54.380129 -143.695566)
			(xy 54.409596 -143.74142) (xy 54.432238 -143.790999) (xy 54.447593 -143.843297) (xy 54.45535 -143.897247)
			(xy 54.45535 -143.951753) (xy 54.447593 -144.005703) (xy 54.432238 -144.058001) (xy 54.409596 -144.10758)
			(xy 54.380129 -144.153434) (xy 54.344436 -144.194626) (xy 54.303245 -144.230321) (xy 54.257393 -144.259789)
			(xy 54.207814 -144.282433) (xy 54.155517 -144.29779) (xy 54.101567 -144.305549) (xy 54.074314 -144.306036)
			(xy 54.073806 -144.306036) (xy 54.040672 -144.305286) (xy 53.975406 -144.293799) (xy 53.944012 -144.283176)
			(xy 53.930421 -144.278704) (xy 53.901885 -144.276768) (xy 53.873929 -144.282814) (xy 53.848744 -144.296371)
			(xy 53.828301 -144.316375) (xy 53.814203 -144.341261) (xy 53.810408 -144.355058) (xy 53.803409 -144.38256)
			(xy 53.78231 -144.435241) (xy 53.753638 -144.484215) (xy 53.718025 -144.528399) (xy 53.676259 -144.566818)
			(xy 53.62926 -144.598624) (xy 53.578068 -144.623114) (xy 53.523811 -144.639749) (xy 53.467689 -144.64816)
			(xy 53.439314 -144.648682) (xy 53.412059 -144.648272) (xy 53.358102 -144.640516) (xy 53.305799 -144.62516)
			(xy 53.256214 -144.602517) (xy 53.210356 -144.573047) (xy 53.169159 -144.537351) (xy 53.133461 -144.496155)
			(xy 53.10399 -144.450298) (xy 53.081345 -144.400714) (xy 53.065987 -144.348411) (xy 53.058229 -144.294455)
			(xy 51.736434 -144.294455) (xy 51.751761 -144.328013) (xy 51.767116 -144.380299) (xy 51.774873 -144.434237)
			(xy 51.77536 -144.461484) (xy 51.77493 -144.486875) (xy 51.768173 -144.537207) (xy 51.761898 -144.561814)
			(xy 51.758525 -144.576472) (xy 51.759445 -144.606518) (xy 51.769069 -144.634996) (xy 51.786564 -144.65944)
			(xy 51.810415 -144.677736) (xy 51.838559 -144.688299) (xy 51.868558 -144.690215) (xy 51.88331 -144.68729)
			(xy 51.90484 -144.682535) (xy 51.948639 -144.677442) (xy 51.970686 -144.67713) (xy 51.97094 -144.67713)
			(xy 51.998187 -144.677621) (xy 52.052126 -144.685382) (xy 52.104412 -144.700739) (xy 52.153979 -144.723381)
			(xy 52.199821 -144.752847) (xy 52.241002 -144.788536) (xy 52.276686 -144.829723) (xy 52.306145 -144.875568)
			(xy 52.32878 -144.925139) (xy 52.34413 -144.977427) (xy 52.351883 -145.031367) (xy 52.351881 -145.085861)
			(xy 52.344124 -145.139801) (xy 52.32877 -145.192087) (xy 52.306131 -145.241657) (xy 52.276669 -145.2875)
			(xy 52.240982 -145.328684) (xy 52.199798 -145.36437) (xy 52.153955 -145.393832) (xy 52.104385 -145.416471)
			(xy 52.052099 -145.431824) (xy 51.998159 -145.439581) (xy 51.943665 -145.439583) (xy 51.889725 -145.431829)
			(xy 51.837437 -145.416479) (xy 51.787866 -145.393844) (xy 51.742021 -145.364384) (xy 51.700835 -145.328701)
			(xy 51.665146 -145.287519) (xy 51.63568 -145.241678) (xy 51.613039 -145.19211) (xy 51.597681 -145.139824)
			(xy 51.589921 -145.085885) (xy 51.589432 -145.058638) (xy 51.589867 -145.033247) (xy 51.596621 -144.982916)
			(xy 51.602894 -144.958308) (xy 51.606253 -144.943646) (xy 51.605338 -144.913601) (xy 51.595718 -144.885123)
			(xy 51.578225 -144.860677) (xy 51.554375 -144.842382) (xy 51.526232 -144.83182) (xy 51.496234 -144.829906)
			(xy 51.481482 -144.832832) (xy 51.459952 -144.837589) (xy 51.416153 -144.84268) (xy 51.394106 -144.842992)
			(xy 51.393852 -144.842992) (xy 51.366605 -144.84247) (xy 51.312667 -144.834709) (xy 51.260383 -144.81935)
			(xy 51.210816 -144.796707) (xy 51.164976 -144.767241) (xy 51.123796 -144.731551) (xy 51.088114 -144.690364)
			(xy 51.058657 -144.644518) (xy 51.036024 -144.594947) (xy 51.020675 -144.54266) (xy 51.012924 -144.48872)
			(xy 31.612867 -144.48872) (xy 29.34302 -146.75866) (xy 43.126914 -146.75866) (xy 43.127436 -146.729921)
			(xy 43.136063 -146.673095) (xy 43.153114 -146.618205) (xy 43.178206 -146.566493) (xy 43.210769 -146.51913)
			(xy 43.230038 -146.497802) (xy 43.240134 -146.486238) (xy 43.253567 -146.458655) (xy 43.258189 -146.428324)
			(xy 43.253582 -146.397991) (xy 43.240162 -146.370401) (xy 43.230038 -146.358864) (xy 43.21077 -146.337534)
			(xy 43.178203 -146.290173) (xy 43.15311 -146.238462) (xy 43.136059 -146.183572) (xy 43.127435 -146.126745)
			(xy 43.126914 -146.098006) (xy 43.12738 -146.070636) (xy 43.135197 -146.016457) (xy 43.150686 -145.963953)
			(xy 43.173528 -145.914206) (xy 43.203253 -145.86824) (xy 43.220894 -145.847308) (xy 43.230126 -145.835977)
			(xy 43.242304 -145.80942) (xy 43.246478 -145.780505) (xy 43.242307 -145.751588) (xy 43.23013 -145.725031)
			(xy 43.220894 -145.713704) (xy 43.203242 -145.692782) (xy 43.173533 -145.646806) (xy 43.150699 -145.597056)
			(xy 43.135211 -145.544553) (xy 43.127386 -145.490376) (xy 43.126914 -145.463006) (xy 43.127361 -145.435752)
			(xy 43.135118 -145.3818) (xy 43.150474 -145.3295) (xy 43.173117 -145.279919) (xy 43.202587 -145.234064)
			(xy 43.238282 -145.192871) (xy 43.279477 -145.157177) (xy 43.325333 -145.12771) (xy 43.374915 -145.105068)
			(xy 43.427215 -145.089714) (xy 43.481168 -145.08196) (xy 43.508422 -145.081498) (xy 43.535793 -145.081952)
			(xy 43.589972 -145.089773) (xy 43.642476 -145.105265) (xy 43.692222 -145.128109) (xy 43.738189 -145.157836)
			(xy 43.75912 -145.175478) (xy 43.770448 -145.184714) (xy 43.797005 -145.19689) (xy 43.825922 -145.201063)
			(xy 43.854839 -145.19689) (xy 43.881396 -145.184714) (xy 43.892724 -145.175478) (xy 43.913671 -145.157858)
			(xy 43.95964 -145.128144) (xy 44.009384 -145.105305) (xy 44.061881 -145.089809) (xy 44.116054 -145.081975)
			(xy 44.143422 -145.081498) (xy 44.172161 -145.082009) (xy 44.228989 -145.090635) (xy 44.28388 -145.107688)
			(xy 44.335592 -145.132782) (xy 44.382954 -145.16535) (xy 44.40428 -145.184622) (xy 44.415814 -145.194694)
			(xy 44.44336 -145.208036) (xy 44.473622 -145.212621) (xy 44.503884 -145.208036) (xy 44.53143 -145.194694)
			(xy 44.542964 -145.184622) (xy 44.564291 -145.165352) (xy 44.611654 -145.132787) (xy 44.663365 -145.107696)
			(xy 44.718256 -145.090646) (xy 44.775083 -145.082024) (xy 44.832561 -145.082024) (xy 44.889388 -145.090646)
			(xy 44.944279 -145.107696) (xy 44.99599 -145.132787) (xy 45.043353 -145.165352) (xy 45.06468 -145.184622)
			(xy 45.076214 -145.194694) (xy 45.10376 -145.208036) (xy 45.134022 -145.212621) (xy 45.164284 -145.208036)
			(xy 45.19183 -145.194694) (xy 45.203364 -145.184622) (xy 45.224691 -145.165352) (xy 45.272054 -145.132787)
			(xy 45.323765 -145.107696) (xy 45.378656 -145.090646) (xy 45.435483 -145.082024) (xy 45.492961 -145.082024)
			(xy 45.549788 -145.090646) (xy 45.604679 -145.107696) (xy 45.65639 -145.132787) (xy 45.703753 -145.165352)
			(xy 45.72508 -145.184622) (xy 45.736614 -145.194694) (xy 45.76416 -145.208036) (xy 45.794422 -145.212621)
			(xy 45.824684 -145.208036) (xy 45.85223 -145.194694) (xy 45.863764 -145.184622) (xy 45.885091 -145.165352)
			(xy 45.932454 -145.132787) (xy 45.984165 -145.107696) (xy 46.039056 -145.090646) (xy 46.095883 -145.082024)
			(xy 46.153361 -145.082024) (xy 46.210188 -145.090646) (xy 46.265079 -145.107696) (xy 46.31679 -145.132787)
			(xy 46.364153 -145.165352) (xy 46.38548 -145.184622) (xy 46.397014 -145.194694) (xy 46.42456 -145.208036)
			(xy 46.454822 -145.212621) (xy 46.485084 -145.208036) (xy 46.51263 -145.194694) (xy 46.524164 -145.184622)
			(xy 46.545491 -145.165352) (xy 46.592854 -145.132787) (xy 46.644565 -145.107696) (xy 46.699456 -145.090646)
			(xy 46.756283 -145.082024) (xy 46.813761 -145.082024) (xy 46.870588 -145.090646) (xy 46.925479 -145.107696)
			(xy 46.97719 -145.132787) (xy 47.024553 -145.165352) (xy 47.04588 -145.184622) (xy 47.057414 -145.194694)
			(xy 47.08496 -145.208036) (xy 47.115222 -145.212621) (xy 47.145484 -145.208036) (xy 47.17303 -145.194694)
			(xy 47.184564 -145.184622) (xy 47.20588 -145.165338) (xy 47.253245 -145.132774) (xy 47.30496 -145.107685)
			(xy 47.359853 -145.090637) (xy 47.416682 -145.082017) (xy 47.445422 -145.081498) (xy 47.472674 -145.081957)
			(xy 47.526623 -145.089717) (xy 47.578919 -145.105075) (xy 47.628496 -145.127719) (xy 47.674347 -145.157189)
			(xy 47.715537 -145.192883) (xy 47.751228 -145.234076) (xy 47.780694 -145.279928) (xy 47.803335 -145.329508)
			(xy 47.818689 -145.381804) (xy 47.826445 -145.435754) (xy 47.82693 -145.463006) (xy 47.826467 -145.489242)
			(xy 47.819271 -145.541217) (xy 47.805017 -145.591715) (xy 47.783973 -145.639781) (xy 47.756538 -145.684508)
			(xy 47.723228 -145.725051) (xy 47.704248 -145.743168) (xy 47.696871 -145.750692) (xy 47.688442 -145.769979)
			(xy 47.688444 -145.791029) (xy 47.696876 -145.810315) (xy 47.704248 -145.817844) (xy 47.725584 -145.83918)
			(xy 47.733113 -145.846552) (xy 47.752398 -145.854983) (xy 47.773446 -145.854983) (xy 47.792731 -145.846552)
			(xy 47.80026 -145.83918) (xy 47.818371 -145.820192) (xy 47.858911 -145.786874) (xy 47.903638 -145.759432)
			(xy 47.951706 -145.738384) (xy 48.002206 -145.724128) (xy 48.054185 -145.716934) (xy 48.080422 -145.716498)
			(xy 48.107674 -145.716957) (xy 48.161623 -145.724717) (xy 48.213919 -145.740075) (xy 48.263496 -145.762719)
			(xy 48.309347 -145.792189) (xy 48.350537 -145.827883) (xy 48.386228 -145.869076) (xy 48.400993 -145.892052)
			(xy 49.996289 -145.892052) (xy 49.996289 -145.837548) (xy 50.004047 -145.783598) (xy 50.019404 -145.731301)
			(xy 50.042047 -145.681722) (xy 50.071517 -145.635871) (xy 50.107212 -145.594681) (xy 50.148406 -145.55899)
			(xy 50.194261 -145.529526) (xy 50.243842 -145.506888) (xy 50.296141 -145.491537) (xy 50.350092 -145.483786)
			(xy 50.377344 -145.483326) (xy 50.407031 -145.483911) (xy 50.465689 -145.493102) (xy 50.522215 -145.511271)
			(xy 50.575243 -145.537978) (xy 50.623492 -145.57258) (xy 50.665798 -145.614239) (xy 50.683922 -145.637758)
			(xy 50.692348 -145.648365) (xy 50.713661 -145.665072) (xy 50.738615 -145.675591) (xy 50.765456 -145.679181)
			(xy 50.792297 -145.675591) (xy 50.817251 -145.665072) (xy 50.838564 -145.648365) (xy 50.84699 -145.637758)
			(xy 50.86512 -145.614243) (xy 50.907427 -145.572585) (xy 50.955675 -145.537982) (xy 51.008701 -145.511271)
			(xy 51.065225 -145.493095) (xy 51.123881 -145.483893) (xy 51.153568 -145.483326) (xy 51.180825 -145.483719)
			(xy 51.234784 -145.491473) (xy 51.28709 -145.506827) (xy 51.336679 -145.52947) (xy 51.38254 -145.55894)
			(xy 51.423741 -145.594637) (xy 51.459441 -145.635834) (xy 51.488915 -145.681693) (xy 51.511561 -145.73128)
			(xy 51.52692 -145.783585) (xy 51.534679 -145.837543) (xy 51.534679 -145.892057) (xy 51.52692 -145.946015)
			(xy 51.511561 -145.99832) (xy 51.488915 -146.047907) (xy 51.459441 -146.093766) (xy 51.423741 -146.134963)
			(xy 51.38254 -146.17066) (xy 51.336679 -146.20013) (xy 51.28709 -146.222773) (xy 51.234784 -146.238127)
			(xy 51.180825 -146.245881) (xy 51.153568 -146.246342) (xy 51.123881 -146.24576) (xy 51.065222 -146.23657)
			(xy 51.008695 -146.218402) (xy 50.955667 -146.191694) (xy 50.907418 -146.157091) (xy 50.865114 -146.11543)
			(xy 50.84699 -146.09191) (xy 50.838564 -146.081303) (xy 50.817251 -146.064596) (xy 50.792297 -146.054077)
			(xy 50.765456 -146.050487) (xy 50.738615 -146.054077) (xy 50.713661 -146.064596) (xy 50.692348 -146.081303)
			(xy 50.683922 -146.09191) (xy 50.665776 -146.115412) (xy 50.623474 -146.157073) (xy 50.575229 -146.191678)
			(xy 50.522206 -146.218392) (xy 50.465685 -146.23657) (xy 50.40703 -146.245774) (xy 50.377344 -146.246342)
			(xy 50.350092 -146.245814) (xy 50.296141 -146.238063) (xy 50.243842 -146.222712) (xy 50.194261 -146.200074)
			(xy 50.148406 -146.17061) (xy 50.107212 -146.134919) (xy 50.071517 -146.093729) (xy 50.042047 -146.047878)
			(xy 50.019404 -145.998299) (xy 50.004047 -145.946002) (xy 49.996289 -145.892052) (xy 48.400993 -145.892052)
			(xy 48.415694 -145.914928) (xy 48.438335 -145.964508) (xy 48.453689 -146.016804) (xy 48.461445 -146.070754)
			(xy 48.46193 -146.098006) (xy 48.461402 -146.126745) (xy 48.452779 -146.183571) (xy 48.43573 -146.238462)
			(xy 48.410639 -146.290174) (xy 48.378076 -146.337537) (xy 48.358806 -146.358864) (xy 48.348699 -146.3704)
			(xy 48.335361 -146.398008) (xy 48.330783 -146.428324) (xy 48.335375 -146.458639) (xy 48.348727 -146.48624)
			(xy 48.358806 -146.497802) (xy 48.378048 -146.519154) (xy 48.41062 -146.566508) (xy 48.435719 -146.618213)
			(xy 48.452776 -146.673099) (xy 48.461405 -146.729923) (xy 48.46193 -146.75866) (xy 48.461408 -146.785911)
			(xy 48.453657 -146.839859) (xy 48.438307 -146.892154) (xy 48.415671 -146.941732) (xy 48.386209 -146.987585)
			(xy 48.350521 -147.028777) (xy 48.309334 -147.064472) (xy 48.263487 -147.093941) (xy 48.213912 -147.116585)
			(xy 48.161619 -147.131943) (xy 48.107673 -147.139703) (xy 48.080422 -147.140168) (xy 48.053052 -147.139697)
			(xy 47.998873 -147.131881) (xy 47.946369 -147.116394) (xy 47.896622 -147.093553) (xy 47.850656 -147.063829)
			(xy 47.829724 -147.046188) (xy 47.818396 -147.036952) (xy 47.791839 -147.024776) (xy 47.762922 -147.020603)
			(xy 47.734005 -147.024776) (xy 47.707448 -147.036952) (xy 47.69612 -147.046188) (xy 47.67519 -147.063829)
			(xy 47.629217 -147.093541) (xy 47.579469 -147.116377) (xy 47.526968 -147.131867) (xy 47.472791 -147.139695)
			(xy 47.445422 -147.140168) (xy 47.416685 -147.139613) (xy 47.359859 -147.130995) (xy 47.30497 -147.113951)
			(xy 47.253257 -147.088867) (xy 47.205893 -147.05631) (xy 47.184564 -147.037044) (xy 47.17303 -147.026972)
			(xy 47.145484 -147.01363) (xy 47.115222 -147.009045) (xy 47.08496 -147.01363) (xy 47.057414 -147.026972)
			(xy 47.04588 -147.037044) (xy 47.024553 -147.056314) (xy 46.97719 -147.088879) (xy 46.925479 -147.11397)
			(xy 46.870588 -147.13102) (xy 46.813761 -147.139642) (xy 46.756283 -147.139642) (xy 46.699456 -147.13102)
			(xy 46.644565 -147.11397) (xy 46.592854 -147.088879) (xy 46.545491 -147.056314) (xy 46.524164 -147.037044)
			(xy 46.51263 -147.026972) (xy 46.485084 -147.01363) (xy 46.454822 -147.009045) (xy 46.42456 -147.01363)
			(xy 46.397014 -147.026972) (xy 46.38548 -147.037044) (xy 46.364153 -147.056314) (xy 46.31679 -147.088879)
			(xy 46.265079 -147.11397) (xy 46.210188 -147.13102) (xy 46.153361 -147.139642) (xy 46.095883 -147.139642)
			(xy 46.039056 -147.13102) (xy 45.984165 -147.11397) (xy 45.932454 -147.088879) (xy 45.885091 -147.056314)
			(xy 45.863764 -147.037044) (xy 45.85223 -147.026972) (xy 45.824684 -147.01363) (xy 45.794422 -147.009045)
			(xy 45.76416 -147.01363) (xy 45.736614 -147.026972) (xy 45.72508 -147.037044) (xy 45.703753 -147.056314)
			(xy 45.65639 -147.088879) (xy 45.604679 -147.11397) (xy 45.549788 -147.13102) (xy 45.492961 -147.139642)
			(xy 45.435483 -147.139642) (xy 45.378656 -147.13102) (xy 45.323765 -147.11397) (xy 45.272054 -147.088879)
			(xy 45.224691 -147.056314) (xy 45.203364 -147.037044) (xy 45.19183 -147.026972) (xy 45.164284 -147.01363)
			(xy 45.134022 -147.009045) (xy 45.10376 -147.01363) (xy 45.076214 -147.026972) (xy 45.06468 -147.037044)
			(xy 45.043353 -147.056314) (xy 44.99599 -147.088879) (xy 44.944279 -147.11397) (xy 44.889388 -147.13102)
			(xy 44.832561 -147.139642) (xy 44.775083 -147.139642) (xy 44.718256 -147.13102) (xy 44.663365 -147.11397)
			(xy 44.611654 -147.088879) (xy 44.564291 -147.056314) (xy 44.542964 -147.037044) (xy 44.53143 -147.026972)
			(xy 44.503884 -147.01363) (xy 44.473622 -147.009045) (xy 44.44336 -147.01363) (xy 44.415814 -147.026972)
			(xy 44.40428 -147.037044) (xy 44.382941 -147.056301) (xy 44.335583 -147.08887) (xy 44.283874 -147.113965)
			(xy 44.228986 -147.131019) (xy 44.17216 -147.139645) (xy 44.143422 -147.140168) (xy 44.116052 -147.139697)
			(xy 44.061873 -147.131881) (xy 44.009369 -147.116394) (xy 43.959622 -147.093553) (xy 43.913656 -147.063829)
			(xy 43.892724 -147.046188) (xy 43.881396 -147.036952) (xy 43.854839 -147.024776) (xy 43.825922 -147.020603)
			(xy 43.797005 -147.024776) (xy 43.770448 -147.036952) (xy 43.75912 -147.046188) (xy 43.73819 -147.063829)
			(xy 43.692217 -147.093541) (xy 43.642469 -147.116377) (xy 43.589968 -147.131867) (xy 43.535791 -147.139695)
			(xy 43.508422 -147.140168) (xy 43.481168 -147.139724) (xy 43.427214 -147.131969) (xy 43.374914 -147.116614)
			(xy 43.325331 -147.093971) (xy 43.279476 -147.064502) (xy 43.238282 -147.028806) (xy 43.202588 -146.98761)
			(xy 43.17312 -146.941753) (xy 43.15048 -146.89217) (xy 43.135127 -146.839868) (xy 43.127375 -146.785914)
			(xy 43.126914 -146.75866) (xy 29.34302 -146.75866) (xy 28.124279 -147.977451) (xy 50.206652 -147.977451)
			(xy 50.206652 -147.922949) (xy 50.214408 -147.869001) (xy 50.229762 -147.816707) (xy 50.252401 -147.767129)
			(xy 50.281865 -147.721277) (xy 50.317554 -147.680086) (xy 50.358742 -147.644392) (xy 50.40459 -147.614922)
			(xy 50.454165 -147.592277) (xy 50.506458 -147.576917) (xy 50.560405 -147.569155) (xy 50.587656 -147.568666)
			(xy 50.58791 -147.568666) (xy 50.617749 -147.569247) (xy 50.676695 -147.578559) (xy 50.705258 -147.587208)
			(xy 50.719167 -147.591239) (xy 50.748099 -147.592148) (xy 50.776118 -147.584883) (xy 50.800963 -147.570032)
			(xy 50.820629 -147.548792) (xy 50.833527 -147.522879) (xy 50.836576 -147.508722) (xy 50.843165 -147.475884)
			(xy 50.866284 -147.413031) (xy 50.88255 -147.383754) (xy 50.889618 -147.370804) (xy 50.896647 -147.342161)
			(xy 50.895197 -147.312704) (xy 50.885389 -147.28489) (xy 50.868042 -147.261039) (xy 50.844601 -147.243141)
			(xy 50.830988 -147.23745) (xy 50.80422 -147.226735) (xy 50.753979 -147.19845) (xy 50.70857 -147.162922)
			(xy 50.669027 -147.120963) (xy 50.636253 -147.073528) (xy 50.610993 -147.0217) (xy 50.593825 -146.96666)
			(xy 50.585139 -146.909662) (xy 50.584608 -146.880834) (xy 50.585094 -146.853583) (xy 50.59285 -146.799635)
			(xy 50.608205 -146.74734) (xy 50.630847 -146.697763) (xy 50.660313 -146.651913) (xy 50.696004 -146.610722)
			(xy 50.737195 -146.575031) (xy 50.783045 -146.545565) (xy 50.832622 -146.522923) (xy 50.884917 -146.507568)
			(xy 50.938865 -146.499812) (xy 50.993367 -146.499812) (xy 51.047315 -146.507568) (xy 51.09961 -146.522923)
			(xy 51.149187 -146.545565) (xy 51.195037 -146.575031) (xy 51.236228 -146.610722) (xy 51.271919 -146.651913)
			(xy 51.301385 -146.697763) (xy 51.324027 -146.74734) (xy 51.339382 -146.799635) (xy 51.347138 -146.853583)
			(xy 51.347624 -146.880834) (xy 51.347624 -146.881088) (xy 51.347224 -146.906292) (xy 51.340585 -146.95626)
			(xy 51.327409 -147.004914) (xy 51.307926 -147.051404) (xy 51.295554 -147.073366) (xy 51.28846 -147.086303)
			(xy 51.281434 -147.114951) (xy 51.282888 -147.144412) (xy 51.292701 -147.172229) (xy 51.310054 -147.196081)
			(xy 51.3335 -147.21398) (xy 51.347116 -147.21967) (xy 51.373892 -147.230366) (xy 51.424134 -147.258654)
			(xy 51.469543 -147.294184) (xy 51.509085 -147.336146) (xy 51.541859 -147.383583) (xy 51.567117 -147.435414)
			(xy 51.584283 -147.490457) (xy 51.592966 -147.547457) (xy 51.593496 -147.576286) (xy 51.593032 -147.603539)
			(xy 51.585276 -147.657491) (xy 51.569921 -147.709789) (xy 51.54728 -147.75937) (xy 51.517812 -147.805224)
			(xy 51.482118 -147.846417) (xy 51.440925 -147.882111) (xy 51.395072 -147.911579) (xy 51.345491 -147.934221)
			(xy 51.293193 -147.949576) (xy 51.239241 -147.957331) (xy 51.211988 -147.957794) (xy 51.211734 -147.957794)
			(xy 51.181895 -147.957227) (xy 51.122949 -147.947906) (xy 51.094386 -147.939252) (xy 51.080457 -147.935302)
			(xy 51.051539 -147.934385) (xy 51.02353 -147.941636) (xy 50.998691 -147.956471) (xy 50.979026 -147.977693)
			(xy 50.966122 -148.003589) (xy 50.963068 -148.017738) (xy 50.957919 -148.043816) (xy 50.941346 -148.09432)
			(xy 50.917921 -148.142034) (xy 50.888096 -148.186032) (xy 50.852451 -148.225463) (xy 50.811676 -148.259561)
			(xy 50.76656 -148.287667) (xy 50.717979 -148.309236) (xy 50.666873 -148.323849) (xy 50.614233 -148.331225)
			(xy 50.587656 -148.331682) (xy 50.560405 -148.331245) (xy 50.506458 -148.323483) (xy 50.454165 -148.308123)
			(xy 50.40459 -148.285478) (xy 50.358742 -148.256008) (xy 50.317554 -148.220314) (xy 50.281865 -148.179123)
			(xy 50.252401 -148.133271) (xy 50.229762 -148.083693) (xy 50.214408 -148.031399) (xy 50.206652 -147.977451)
			(xy 28.124279 -147.977451) (xy 27.474164 -148.627592) (xy 27.464539 -148.637909) (xy 27.450875 -148.662582)
			(xy 27.444488 -148.690053) (xy 27.445866 -148.718223) (xy 27.454905 -148.74494) (xy 27.470912 -148.768161)
			(xy 27.492666 -148.786111) (xy 27.518504 -148.79742) (xy 27.54645 -148.801223) (xy 27.57437 -148.797228)
			(xy 27.587448 -148.79193) (xy 27.679723 -148.74853) (xy 27.866989 -148.66776) (xy 28.057116 -148.593977)
			(xy 28.249843 -148.527281) (xy 28.444907 -148.467764) (xy 28.64204 -148.415508) (xy 28.840972 -148.370583)
			(xy 29.04143 -148.333052) (xy 29.243141 -148.302965) (xy 29.445826 -148.280365) (xy 29.649209 -148.265282)
			(xy 29.853011 -148.257737) (xy 29.954982 -148.25726) (xy 30.059654 -148.257755) (xy 30.268848 -148.265709)
			(xy 30.477588 -148.281605) (xy 30.685574 -148.30542) (xy 30.892504 -148.337121) (xy 31.098081 -148.37666)
			(xy 31.302007 -148.423982) (xy 31.503988 -148.479017) (xy 31.703732 -148.541687) (xy 31.900951 -148.6119)
			(xy 32.095359 -148.689556) (xy 32.286677 -148.774541) (xy 32.474628 -148.866735) (xy 32.658941 -148.966003)
			(xy 32.839349 -149.072201) (xy 33.015591 -149.185178) (xy 33.187414 -149.304769) (xy 33.35457 -149.430802)
			(xy 33.516816 -149.563094) (xy 33.673919 -149.701456) (xy 33.825651 -149.845686) (xy 33.971794 -149.995577)
			(xy 34.112137 -150.150913) (xy 34.246477 -150.311468) (xy 34.350203 -150.44547) (xy 50.99304 -150.44547)
			(xy 50.993427 -150.418214) (xy 51.001189 -150.364258) (xy 51.016552 -150.311956) (xy 51.039201 -150.262372)
			(xy 51.068677 -150.216517) (xy 51.104379 -150.175323) (xy 51.145579 -150.13963) (xy 51.191441 -150.110164)
			(xy 51.241029 -150.087524) (xy 51.293334 -150.072173) (xy 51.347292 -150.064422) (xy 51.374548 -150.063962)
			(xy 51.402122 -150.064442) (xy 51.456695 -150.072388) (xy 51.509556 -150.088109) (xy 51.559603 -150.111276)
			(xy 51.605792 -150.141408) (xy 51.647163 -150.177875) (xy 51.665378 -150.198582) (xy 51.675276 -150.20948)
			(xy 51.699926 -150.225555) (xy 51.728134 -150.233939) (xy 51.757562 -150.233939) (xy 51.78577 -150.225555)
			(xy 51.81042 -150.20948) (xy 51.820318 -150.198582) (xy 51.838512 -150.177855) (xy 51.879885 -150.141387)
			(xy 51.926079 -150.111257) (xy 51.97613 -150.088094) (xy 52.028995 -150.072381) (xy 52.083572 -150.064445)
			(xy 52.111148 -150.063962) (xy 52.137649 -150.064415) (xy 52.19014 -150.071762) (xy 52.241107 -150.086307)
			(xy 52.289569 -150.10777) (xy 52.334592 -150.135737) (xy 52.355242 -150.152354) (xy 52.367396 -150.161784)
			(xy 52.395794 -150.173573) (xy 52.426411 -150.176397) (xy 52.456486 -150.170003) (xy 52.483306 -150.154967)
			(xy 52.504451 -150.132645) (xy 52.511706 -150.11908) (xy 52.523817 -150.095395) (xy 52.553737 -150.051413)
			(xy 52.589605 -150.01213) (xy 52.630693 -149.978345) (xy 52.653184 -149.96414) (xy 52.665431 -149.956248)
			(xy 52.685104 -149.934769) (xy 52.697907 -149.908607) (xy 52.702796 -149.879894) (xy 52.699373 -149.850969)
			(xy 52.694078 -149.837394) (xy 52.684593 -149.814182) (xy 52.671241 -149.76585) (xy 52.664511 -149.716161)
			(xy 52.664106 -149.69109) (xy 52.66454 -149.666021) (xy 52.671286 -149.616338) (xy 52.684614 -149.568004)
			(xy 52.694078 -149.544786) (xy 52.699333 -149.531207) (xy 52.702713 -149.502299) (xy 52.697811 -149.47361)
			(xy 52.685024 -149.447464) (xy 52.665389 -149.42598) (xy 52.653184 -149.41804) (xy 52.630024 -149.403514)
			(xy 52.587899 -149.368668) (xy 52.551317 -149.328041) (xy 52.521063 -149.282506) (xy 52.497786 -149.233039)
			(xy 52.481986 -149.180703) (xy 52.474001 -149.126619) (xy 52.474003 -149.07195) (xy 52.481993 -149.017867)
			(xy 52.497797 -148.965532) (xy 52.521079 -148.916067) (xy 52.551336 -148.870534) (xy 52.587922 -148.829911)
			(xy 52.630049 -148.795068) (xy 52.653184 -148.7805) (xy 52.66539 -148.772551) (xy 52.685063 -148.751088)
			(xy 52.697871 -148.724941) (xy 52.702771 -148.696241) (xy 52.699363 -148.667326) (xy 52.694078 -148.653754)
			(xy 52.684581 -148.630547) (xy 52.671233 -148.582213) (xy 52.664508 -148.532522) (xy 52.664106 -148.50745)
			(xy 52.664627 -148.479565) (xy 52.672939 -148.424418) (xy 52.689377 -148.371126) (xy 52.713575 -148.32088)
			(xy 52.744991 -148.274801) (xy 52.782924 -148.233919) (xy 52.826526 -148.199147) (xy 52.874824 -148.171262)
			(xy 52.926739 -148.150887) (xy 52.98111 -148.138477) (xy 53.036724 -148.13431) (xy 53.092338 -148.138477)
			(xy 53.146709 -148.150887) (xy 53.198624 -148.171262) (xy 53.246922 -148.199147) (xy 53.290524 -148.233919)
			(xy 53.328457 -148.274801) (xy 53.359873 -148.32088) (xy 53.384071 -148.371126) (xy 53.400509 -148.424418)
			(xy 53.408821 -148.479565) (xy 53.409342 -148.50745) (xy 53.408875 -148.534782) (xy 53.400906 -148.588863)
			(xy 53.385118 -148.641198) (xy 53.36185 -148.690662) (xy 53.331601 -148.736195) (xy 53.295022 -148.776817)
			(xy 53.252897 -148.811655) (xy 53.229764 -148.82622) (xy 53.217537 -148.834138) (xy 53.19787 -148.855612)
			(xy 53.185068 -148.881767) (xy 53.180173 -148.910472) (xy 53.183584 -148.939392) (xy 53.18887 -148.952966)
			(xy 53.198345 -148.976181) (xy 53.211701 -149.024512) (xy 53.218435 -149.074199) (xy 53.218842 -149.09927)
			(xy 53.218431 -149.12434) (xy 53.211677 -149.174023) (xy 53.198339 -149.222357) (xy 53.18887 -149.245574)
			(xy 53.183624 -149.259151) (xy 53.180262 -149.288051) (xy 53.185173 -149.316729) (xy 53.197961 -149.342863)
			(xy 53.217591 -149.364338) (xy 53.229764 -149.37232) (xy 53.252885 -149.386903) (xy 53.295003 -149.421747)
			(xy 53.331579 -149.462369) (xy 53.361829 -149.507898) (xy 53.385103 -149.557358) (xy 53.400902 -149.609688)
			(xy 53.408888 -149.663764) (xy 53.408889 -149.718426) (xy 53.400905 -149.772502) (xy 53.385107 -149.824832)
			(xy 53.361834 -149.874292) (xy 53.331585 -149.919823) (xy 53.29501 -149.960446) (xy 53.252893 -149.995291)
			(xy 53.229764 -150.00986) (xy 53.217509 -150.017739) (xy 53.197842 -150.039225) (xy 53.185043 -150.06539)
			(xy 53.180156 -150.094104) (xy 53.183577 -150.12303) (xy 53.18887 -150.136606) (xy 53.198357 -150.159817)
			(xy 53.211708 -150.208149) (xy 53.218438 -150.257838) (xy 53.218842 -150.28291) (xy 53.21837 -150.309752)
			(xy 53.210665 -150.362881) (xy 53.195416 -150.414354) (xy 53.172938 -150.463106) (xy 53.143697 -150.508127)
			(xy 53.108298 -150.548487) (xy 53.067473 -150.583349) (xy 53.022069 -150.611993) (xy 52.973024 -150.633824)
			(xy 52.947316 -150.641558) (xy 52.932841 -150.646276) (xy 52.907286 -150.662788) (xy 52.887726 -150.686092)
			(xy 52.875894 -150.714122) (xy 52.87284 -150.744393) (xy 52.878835 -150.774222) (xy 52.885594 -150.787862)
			(xy 52.900228 -150.816008) (xy 52.920955 -150.875959) (xy 52.931453 -150.938517) (xy 52.932076 -150.970234)
			(xy 52.931855 -150.988253) (xy 52.928421 -151.024128) (xy 52.925218 -151.041862) (xy 52.922936 -151.057077)
			(xy 52.926453 -151.087622) (xy 52.938901 -151.115736) (xy 52.959153 -151.138871) (xy 52.985373 -151.154931)
			(xy 53.000148 -151.15921) (xy 53.027191 -151.166611) (xy 53.078917 -151.188241) (xy 53.126922 -151.217205)
			(xy 53.170174 -151.25288) (xy 53.207741 -151.294499) (xy 53.238815 -151.341165) (xy 53.262728 -151.391876)
			(xy 53.278965 -151.44554) (xy 53.287177 -151.501001) (xy 53.287676 -151.529034) (xy 53.287254 -151.556288)
			(xy 53.279492 -151.610239) (xy 53.264131 -151.662537) (xy 53.241483 -151.712117) (xy 53.21201 -151.757968)
			(xy 53.176312 -151.799159) (xy 53.135115 -151.83485) (xy 53.089259 -151.864315) (xy 53.039675 -151.886954)
			(xy 52.987375 -151.902306) (xy 52.933422 -151.910058) (xy 52.906168 -151.910542) (xy 52.878594 -151.91005)
			(xy 52.824022 -151.902105) (xy 52.771161 -151.886387) (xy 52.721115 -151.863222) (xy 52.674925 -151.833093)
			(xy 52.633554 -151.796628) (xy 52.615338 -151.775922) (xy 52.60544 -151.765024) (xy 52.58079 -151.748949)
			(xy 52.552582 -151.740565) (xy 52.523154 -151.740565) (xy 52.494946 -151.748949) (xy 52.470296 -151.765024)
			(xy 52.460398 -151.775922) (xy 52.442183 -151.796628) (xy 52.400812 -151.833093) (xy 52.354622 -151.86322)
			(xy 52.304575 -151.886383) (xy 52.251714 -151.902099) (xy 52.197142 -151.910039) (xy 52.141994 -151.910039)
			(xy 52.087422 -151.902099) (xy 52.034561 -151.886383) (xy 51.984514 -151.86322) (xy 51.938324 -151.833093)
			(xy 51.896953 -151.796628) (xy 51.878738 -151.775922) (xy 51.86884 -151.765024) (xy 51.84419 -151.748949)
			(xy 51.815982 -151.740565) (xy 51.786554 -151.740565) (xy 51.758346 -151.748949) (xy 51.733696 -151.765024)
			(xy 51.723798 -151.775922) (xy 51.705596 -151.796642) (xy 51.664225 -151.83311) (xy 51.618033 -151.863241)
			(xy 51.567983 -151.886405) (xy 51.515119 -151.90212) (xy 51.460543 -151.910058) (xy 51.432968 -151.910542)
			(xy 51.405718 -151.910052) (xy 51.351772 -151.902292) (xy 51.299479 -151.886935) (xy 51.249904 -151.864292)
			(xy 51.204055 -151.834826) (xy 51.162866 -151.799135) (xy 51.127175 -151.757946) (xy 51.097709 -151.712098)
			(xy 51.075066 -151.662523) (xy 51.059708 -151.61023) (xy 51.051948 -151.556284) (xy 51.05146 -151.529034)
			(xy 51.052043 -151.501181) (xy 51.060161 -151.44607) (xy 51.0762 -151.392722) (xy 51.09982 -151.342272)
			(xy 51.130519 -151.295788) (xy 51.167647 -151.254258) (xy 51.210414 -151.218563) (xy 51.257914 -151.189461)
			(xy 51.309138 -151.167569) (xy 51.33594 -151.159972) (xy 51.350063 -151.155719) (xy 51.375204 -151.14032)
			(xy 51.394916 -151.118396) (xy 51.407566 -151.091764) (xy 51.412104 -151.062632) (xy 51.410616 -151.047958)
			(xy 51.408945 -151.034942) (xy 51.407166 -151.008757) (xy 51.40706 -150.995634) (xy 51.407158 -150.981485)
			(xy 51.409189 -150.953262) (xy 51.411124 -150.939246) (xy 51.412683 -150.925896) (xy 51.409585 -150.899209)
			(xy 51.39962 -150.874259) (xy 51.38348 -150.852781) (xy 51.362288 -150.836267) (xy 51.337516 -150.825867)
			(xy 51.324256 -150.823676) (xy 51.297113 -150.81953) (xy 51.244287 -150.804561) (xy 51.194152 -150.782174)
			(xy 51.147744 -150.752832) (xy 51.106021 -150.717141) (xy 51.069844 -150.675838) (xy 51.039961 -150.629777)
			(xy 51.016989 -150.579907) (xy 51.001402 -150.52726) (xy 50.993522 -150.472923) (xy 50.99304 -150.44547)
			(xy 34.350203 -150.44547) (xy 34.374619 -150.477012) (xy 34.49638 -150.647304) (xy 34.611582 -150.8221)
			(xy 34.72006 -151.001147) (xy 34.821657 -151.184185) (xy 34.916227 -151.370952) (xy 35.003632 -151.561177)
			(xy 35.0383 -151.644871) (xy 43.782962 -151.644871) (xy 43.786968 -151.589723) (xy 43.798892 -151.535731)
			(xy 43.818485 -151.484026) (xy 43.845337 -151.435691) (xy 43.878885 -151.391738) (xy 43.898312 -151.372062)
			(xy 43.907656 -151.362295) (xy 43.921334 -151.338994) (xy 43.928423 -151.312922) (xy 43.928426 -151.285903)
			(xy 43.921344 -151.259829) (xy 43.907671 -151.236525) (xy 43.898312 -151.226774) (xy 43.880473 -151.208774)
			(xy 43.849246 -151.16886) (xy 43.823579 -151.125162) (xy 43.803922 -151.078452) (xy 43.790624 -151.029549)
			(xy 43.783917 -150.979317) (xy 43.783504 -150.953978) (xy 43.783957 -150.926726) (xy 43.791717 -150.872776)
			(xy 43.807076 -150.82048) (xy 43.82972 -150.770902) (xy 43.85919 -150.725051) (xy 43.894885 -150.683861)
			(xy 43.936078 -150.64817) (xy 43.981932 -150.618704) (xy 44.031512 -150.596064) (xy 44.083809 -150.58071)
			(xy 44.13776 -150.572955) (xy 44.165012 -150.57247) (xy 44.194271 -150.573037) (xy 44.252103 -150.581981)
			(xy 44.307894 -150.599642) (xy 44.360337 -150.625607) (xy 44.408206 -150.659268) (xy 44.42968 -150.67915)
			(xy 44.439987 -150.688465) (xy 44.464413 -150.701673) (xy 44.491499 -150.707794) (xy 44.519231 -150.706373)
			(xy 44.545549 -150.697515) (xy 44.568497 -150.681879) (xy 44.577762 -150.67153) (xy 44.596006 -150.650711)
			(xy 44.637408 -150.613972) (xy 44.683688 -150.583606) (xy 44.733873 -150.560253) (xy 44.786908 -150.544404)
			(xy 44.841678 -150.536392) (xy 44.869354 -150.535894) (xy 44.896723 -150.536388) (xy 44.950901 -150.5442)
			(xy 45.003404 -150.559682) (xy 45.053151 -150.582518) (xy 45.099119 -150.612236) (xy 45.120052 -150.629874)
			(xy 45.13138 -150.63911) (xy 45.157937 -150.651286) (xy 45.186854 -150.655459) (xy 45.215771 -150.651286)
			(xy 45.242328 -150.63911) (xy 45.253656 -150.629874) (xy 45.274589 -150.612233) (xy 45.320557 -150.582509)
			(xy 45.370303 -150.559663) (xy 45.422805 -150.544167) (xy 45.476983 -150.536338) (xy 45.531725 -150.536338)
			(xy 45.585903 -150.544167) (xy 45.638405 -150.559663) (xy 45.688151 -150.582509) (xy 45.734119 -150.612233)
			(xy 45.755052 -150.629874) (xy 45.76638 -150.63911) (xy 45.792937 -150.651286) (xy 45.821854 -150.655459)
			(xy 45.850771 -150.651286) (xy 45.877328 -150.63911) (xy 45.888656 -150.629874) (xy 45.909589 -150.612233)
			(xy 45.955557 -150.582509) (xy 46.005303 -150.559663) (xy 46.057805 -150.544167) (xy 46.111983 -150.536338)
			(xy 46.166725 -150.536338) (xy 46.220903 -150.544167) (xy 46.273405 -150.559663) (xy 46.323151 -150.582509)
			(xy 46.369119 -150.612233) (xy 46.390052 -150.629874) (xy 46.40138 -150.63911) (xy 46.427937 -150.651286)
			(xy 46.456854 -150.655459) (xy 46.485771 -150.651286) (xy 46.512328 -150.63911) (xy 46.523656 -150.629874)
			(xy 46.54459 -150.612238) (xy 46.590563 -150.582527) (xy 46.64031 -150.55969) (xy 46.69281 -150.544199)
			(xy 46.746985 -150.536369) (xy 46.774354 -150.535894) (xy 46.804152 -150.536484) (xy 46.863022 -150.545758)
			(xy 46.919734 -150.56407) (xy 46.972911 -150.590976) (xy 47.021258 -150.625822) (xy 47.042832 -150.646384)
			(xy 47.054372 -150.657021) (xy 47.082273 -150.671355) (xy 47.113206 -150.676557) (xy 47.144261 -150.672139)
			(xy 47.172516 -150.658516) (xy 47.18431 -150.648162) (xy 47.205669 -150.628715) (xy 47.25316 -150.595835)
			(xy 47.305067 -150.570493) (xy 47.360201 -150.553269) (xy 47.417303 -150.544556) (xy 47.446184 -150.544022)
			(xy 47.473438 -150.54447) (xy 47.527391 -150.552226) (xy 47.579691 -150.567581) (xy 47.629273 -150.590224)
			(xy 47.675128 -150.619693) (xy 47.716321 -150.655389) (xy 47.752015 -150.696584) (xy 47.781483 -150.742439)
			(xy 47.804124 -150.792022) (xy 47.819477 -150.844323) (xy 47.827231 -150.898276) (xy 47.827692 -150.92553)
			(xy 47.827299 -150.950869) (xy 47.820586 -151.001101) (xy 47.807281 -151.050002) (xy 47.787619 -151.096711)
			(xy 47.761946 -151.140406) (xy 47.730715 -151.180317) (xy 47.712884 -151.198326) (xy 47.703553 -151.208104)
			(xy 47.689874 -151.231402) (xy 47.682784 -151.257471) (xy 47.682779 -151.284487) (xy 47.689858 -151.310559)
			(xy 47.703527 -151.333863) (xy 47.712884 -151.343614) (xy 47.732318 -151.363281) (xy 47.76586 -151.407234)
			(xy 47.792706 -151.455569) (xy 47.812293 -151.507273) (xy 47.824211 -151.561262) (xy 47.828212 -151.616407)
			(xy 47.824209 -151.671552) (xy 47.812289 -151.725541) (xy 47.7927 -151.777244) (xy 47.765852 -151.825578)
			(xy 47.732309 -151.86953) (xy 47.712884 -151.889206) (xy 47.703473 -151.898913) (xy 47.6898 -151.922231)
			(xy 47.68272 -151.948319) (xy 47.682729 -151.975351) (xy 47.689827 -152.001433) (xy 47.703516 -152.024742)
			(xy 47.712884 -152.034494) (xy 47.730707 -152.05251) (xy 47.761935 -152.09242) (xy 47.787605 -152.136114)
			(xy 47.807264 -152.182822) (xy 47.820566 -152.231722) (xy 47.827277 -152.281952) (xy 47.827692 -152.30729)
			(xy 47.827235 -152.334543) (xy 47.819479 -152.388495) (xy 47.804124 -152.440794) (xy 47.781481 -152.490375)
			(xy 47.752013 -152.536229) (xy 47.716318 -152.577423) (xy 47.675125 -152.613116) (xy 47.62927 -152.642584)
			(xy 47.579689 -152.665226) (xy 47.527389 -152.680581) (xy 47.473437 -152.688336) (xy 47.446184 -152.688798)
			(xy 47.416385 -152.688249) (xy 47.357513 -152.678966) (xy 47.300799 -152.660644) (xy 47.247624 -152.633728)
			(xy 47.199279 -152.598874) (xy 47.177706 -152.578308) (xy 47.166217 -152.567611) (xy 47.138297 -152.553284)
			(xy 47.107349 -152.548094) (xy 47.076284 -152.552527) (xy 47.048023 -152.566167) (xy 47.036228 -152.57653)
			(xy 47.014852 -152.595958) (xy 46.967366 -152.628841) (xy 46.915463 -152.654186) (xy 46.860333 -152.671415)
			(xy 46.803234 -152.680133) (xy 46.774354 -152.68067) (xy 46.746985 -152.68018) (xy 46.692806 -152.672369)
			(xy 46.640303 -152.656886) (xy 46.590556 -152.634049) (xy 46.544588 -152.604329) (xy 46.523656 -152.58669)
			(xy 46.512328 -152.577454) (xy 46.485771 -152.565278) (xy 46.456854 -152.561105) (xy 46.427937 -152.565278)
			(xy 46.40138 -152.577454) (xy 46.390052 -152.58669) (xy 46.369119 -152.604331) (xy 46.323151 -152.634055)
			(xy 46.273405 -152.656901) (xy 46.220903 -152.672397) (xy 46.166725 -152.680226) (xy 46.111983 -152.680226)
			(xy 46.057805 -152.672397) (xy 46.005303 -152.656901) (xy 45.955557 -152.634055) (xy 45.909589 -152.604331)
			(xy 45.888656 -152.58669) (xy 45.877328 -152.577454) (xy 45.850771 -152.565278) (xy 45.821854 -152.561105)
			(xy 45.792937 -152.565278) (xy 45.76638 -152.577454) (xy 45.755052 -152.58669) (xy 45.734119 -152.604331)
			(xy 45.688151 -152.634055) (xy 45.638405 -152.656901) (xy 45.585903 -152.672397) (xy 45.531725 -152.680226)
			(xy 45.476983 -152.680226) (xy 45.422805 -152.672397) (xy 45.370303 -152.656901) (xy 45.320557 -152.634055)
			(xy 45.274589 -152.604331) (xy 45.253656 -152.58669) (xy 45.242328 -152.577454) (xy 45.215771 -152.565278)
			(xy 45.186854 -152.561105) (xy 45.157937 -152.565278) (xy 45.13138 -152.577454) (xy 45.120052 -152.58669)
			(xy 45.09911 -152.604317) (xy 45.05314 -152.634031) (xy 45.003395 -152.656869) (xy 44.950897 -152.672363)
			(xy 44.896723 -152.680194) (xy 44.869354 -152.68067) (xy 44.840094 -152.680113) (xy 44.782263 -152.671165)
			(xy 44.726473 -152.653501) (xy 44.674029 -152.627534) (xy 44.62616 -152.593872) (xy 44.604686 -152.57399)
			(xy 44.594404 -152.564648) (xy 44.569969 -152.551451) (xy 44.542878 -152.545339) (xy 44.515144 -152.546766)
			(xy 44.488824 -152.555626) (xy 44.465872 -152.571261) (xy 44.456604 -152.58161) (xy 44.438387 -152.602453)
			(xy 44.396978 -152.639189) (xy 44.350692 -152.669551) (xy 44.300502 -152.692899) (xy 44.247463 -152.708743)
			(xy 44.19269 -152.71675) (xy 44.165012 -152.717246) (xy 44.137763 -152.716711) (xy 44.083819 -152.708957)
			(xy 44.031527 -152.693605) (xy 43.981953 -152.670968) (xy 43.936104 -152.641507) (xy 43.894915 -152.60582)
			(xy 43.859223 -152.564636) (xy 43.829756 -152.518791) (xy 43.807112 -152.469219) (xy 43.791754 -152.41693)
			(xy 43.783993 -152.362987) (xy 43.783504 -152.335738) (xy 43.783942 -152.3104) (xy 43.790646 -152.26017)
			(xy 43.803942 -152.21127) (xy 43.823596 -152.164561) (xy 43.849261 -152.120865) (xy 43.880485 -152.080952)
			(xy 43.898312 -152.062942) (xy 43.907675 -152.053192) (xy 43.921352 -152.029887) (xy 43.928439 -152.00381)
			(xy 43.928438 -151.976787) (xy 43.921351 -151.950711) (xy 43.907674 -151.927405) (xy 43.898312 -151.917654)
			(xy 43.878846 -151.898018) (xy 43.845305 -151.85406) (xy 43.818461 -151.805721) (xy 43.798875 -151.754012)
			(xy 43.786959 -151.700019) (xy 43.782962 -151.644871) (xy 35.0383 -151.644871) (xy 35.083747 -151.754585)
			(xy 35.156456 -151.950898) (xy 35.221653 -152.149831) (xy 35.279246 -152.351098) (xy 35.32915 -152.554407)
			(xy 35.371293 -152.759466) (xy 35.405615 -152.965978) (xy 35.425834 -153.12472) (xy 51.012924 -153.12472)
			(xy 51.012928 -153.070227) (xy 51.020687 -153.016288) (xy 51.036042 -152.964003) (xy 51.058683 -152.914435)
			(xy 51.088146 -152.868593) (xy 51.123834 -152.827411) (xy 51.165019 -152.791727) (xy 51.210863 -152.762267)
			(xy 51.260433 -152.739631) (xy 51.312719 -152.72428) (xy 51.366659 -152.716526) (xy 51.421152 -152.716526)
			(xy 51.475091 -152.724282) (xy 51.527377 -152.739635) (xy 51.576946 -152.762272) (xy 51.62279 -152.791734)
			(xy 51.663974 -152.827419) (xy 51.69966 -152.868602) (xy 51.729122 -152.914444) (xy 51.736434 -152.930455)
			(xy 53.058229 -152.930455) (xy 53.058229 -152.875945) (xy 53.065987 -152.821989) (xy 53.081345 -152.769686)
			(xy 53.10399 -152.720102) (xy 53.133461 -152.674245) (xy 53.169159 -152.633049) (xy 53.210356 -152.597353)
			(xy 53.256214 -152.567883) (xy 53.305799 -152.54524) (xy 53.358102 -152.529884) (xy 53.412059 -152.522128)
			(xy 53.439314 -152.521666) (xy 53.466685 -152.522108) (xy 53.520866 -152.529929) (xy 53.57337 -152.545423)
			(xy 53.623117 -152.56827) (xy 53.669082 -152.598001) (xy 53.690012 -152.615646) (xy 53.70134 -152.624882)
			(xy 53.727897 -152.637058) (xy 53.756814 -152.641231) (xy 53.785731 -152.637058) (xy 53.812288 -152.624882)
			(xy 53.823616 -152.615646) (xy 53.844575 -152.59804) (xy 53.89054 -152.568322) (xy 53.94028 -152.545479)
			(xy 53.992775 -152.52998) (xy 54.046947 -152.522144) (xy 54.074314 -152.521666) (xy 54.101563 -152.522205)
			(xy 54.155505 -152.529963) (xy 54.207795 -152.545318) (xy 54.257367 -152.567958) (xy 54.303212 -152.597423)
			(xy 54.344398 -152.633112) (xy 54.380085 -152.674299) (xy 54.409548 -152.720146) (xy 54.432187 -152.769719)
			(xy 54.44754 -152.822009) (xy 54.455296 -152.875951) (xy 54.455296 -152.930449) (xy 54.44754 -152.984391)
			(xy 54.432187 -153.036681) (xy 54.409548 -153.086254) (xy 54.380085 -153.132101) (xy 54.344398 -153.173288)
			(xy 54.303212 -153.208977) (xy 54.257367 -153.238442) (xy 54.207795 -153.261082) (xy 54.155505 -153.276437)
			(xy 54.101563 -153.284195) (xy 54.074314 -153.284682) (xy 54.046944 -153.284212) (xy 53.992765 -153.276396)
			(xy 53.940262 -153.260908) (xy 53.890515 -153.238067) (xy 53.844548 -153.208343) (xy 53.823616 -153.190702)
			(xy 53.812288 -153.181466) (xy 53.785731 -153.16929) (xy 53.756814 -153.165117) (xy 53.727897 -153.16929)
			(xy 53.70134 -153.181466) (xy 53.690012 -153.190702) (xy 53.669086 -153.208349) (xy 53.623112 -153.23806)
			(xy 53.573363 -153.260894) (xy 53.520861 -153.276383) (xy 53.466684 -153.284209) (xy 53.439314 -153.284682)
			(xy 53.412059 -153.284272) (xy 53.358102 -153.276516) (xy 53.305799 -153.26116) (xy 53.256214 -153.238517)
			(xy 53.210356 -153.209047) (xy 53.169159 -153.173351) (xy 53.133461 -153.132155) (xy 53.10399 -153.086298)
			(xy 53.081345 -153.036714) (xy 53.065987 -152.984411) (xy 53.058229 -152.930455) (xy 51.736434 -152.930455)
			(xy 51.751761 -152.964013) (xy 51.767116 -153.016299) (xy 51.774873 -153.070237) (xy 51.77536 -153.097484)
			(xy 51.77493 -153.122875) (xy 51.768173 -153.173207) (xy 51.761898 -153.197814) (xy 51.758525 -153.212472)
			(xy 51.759445 -153.242518) (xy 51.769069 -153.270996) (xy 51.786564 -153.29544) (xy 51.810415 -153.313736)
			(xy 51.838559 -153.324299) (xy 51.868558 -153.326215) (xy 51.88331 -153.32329) (xy 51.90484 -153.318535)
			(xy 51.948639 -153.313442) (xy 51.970686 -153.31313) (xy 51.97094 -153.31313) (xy 51.998187 -153.313621)
			(xy 52.052126 -153.321382) (xy 52.104412 -153.336739) (xy 52.153979 -153.359381) (xy 52.199821 -153.388847)
			(xy 52.241002 -153.424536) (xy 52.276686 -153.465723) (xy 52.306145 -153.511568) (xy 52.32878 -153.561139)
			(xy 52.34413 -153.613427) (xy 52.351883 -153.667367) (xy 52.351881 -153.721861) (xy 52.344124 -153.775801)
			(xy 52.32877 -153.828087) (xy 52.306131 -153.877657) (xy 52.276669 -153.9235) (xy 52.240982 -153.964684)
			(xy 52.199798 -154.00037) (xy 52.153955 -154.029832) (xy 52.104385 -154.052471) (xy 52.052099 -154.067824)
			(xy 51.998159 -154.075581) (xy 51.943665 -154.075583) (xy 51.889725 -154.067829) (xy 51.837437 -154.052479)
			(xy 51.787866 -154.029844) (xy 51.742021 -154.000384) (xy 51.700835 -153.964701) (xy 51.665146 -153.923519)
			(xy 51.63568 -153.877678) (xy 51.613039 -153.82811) (xy 51.597681 -153.775824) (xy 51.589921 -153.721885)
			(xy 51.589432 -153.694638) (xy 51.589867 -153.669247) (xy 51.596621 -153.618916) (xy 51.602894 -153.594308)
			(xy 51.606253 -153.579646) (xy 51.605338 -153.549601) (xy 51.595718 -153.521123) (xy 51.578225 -153.496677)
			(xy 51.554375 -153.478382) (xy 51.526232 -153.46782) (xy 51.496234 -153.465906) (xy 51.481482 -153.468832)
			(xy 51.459952 -153.473589) (xy 51.416153 -153.47868) (xy 51.394106 -153.478992) (xy 51.393852 -153.478992)
			(xy 51.366605 -153.47847) (xy 51.312667 -153.470709) (xy 51.260383 -153.45535) (xy 51.210816 -153.432707)
			(xy 51.164976 -153.403241) (xy 51.123796 -153.367551) (xy 51.088114 -153.326364) (xy 51.058657 -153.280518)
			(xy 51.036024 -153.230947) (xy 51.020675 -153.17866) (xy 51.012924 -153.12472) (xy 35.425834 -153.12472)
			(xy 35.432066 -153.173645) (xy 35.450608 -153.382166) (xy 35.461215 -153.591242) (xy 35.46387 -153.80057)
			(xy 35.458569 -154.009847) (xy 35.445322 -154.218773) (xy 35.424146 -154.427043) (xy 35.409981 -154.528052)
			(xy 49.996289 -154.528052) (xy 49.996289 -154.473548) (xy 50.004047 -154.419598) (xy 50.019404 -154.367301)
			(xy 50.042047 -154.317722) (xy 50.071517 -154.271871) (xy 50.107212 -154.230681) (xy 50.148406 -154.19499)
			(xy 50.194261 -154.165526) (xy 50.243842 -154.142888) (xy 50.296141 -154.127537) (xy 50.350092 -154.119786)
			(xy 50.377344 -154.119326) (xy 50.407031 -154.119911) (xy 50.465689 -154.129102) (xy 50.522215 -154.147271)
			(xy 50.575243 -154.173978) (xy 50.623492 -154.20858) (xy 50.665798 -154.250239) (xy 50.683922 -154.273758)
			(xy 50.692348 -154.284365) (xy 50.713661 -154.301072) (xy 50.738615 -154.311591) (xy 50.765456 -154.315181)
			(xy 50.792297 -154.311591) (xy 50.817251 -154.301072) (xy 50.838564 -154.284365) (xy 50.84699 -154.273758)
			(xy 50.86512 -154.250243) (xy 50.907427 -154.208585) (xy 50.955675 -154.173982) (xy 51.008701 -154.147271)
			(xy 51.065225 -154.129095) (xy 51.123881 -154.119893) (xy 51.153568 -154.119326) (xy 51.180825 -154.119719)
			(xy 51.234784 -154.127473) (xy 51.28709 -154.142827) (xy 51.336679 -154.16547) (xy 51.38254 -154.19494)
			(xy 51.423741 -154.230637) (xy 51.459441 -154.271834) (xy 51.488915 -154.317693) (xy 51.511561 -154.36728)
			(xy 51.52692 -154.419585) (xy 51.534679 -154.473543) (xy 51.534679 -154.528057) (xy 51.52692 -154.582015)
			(xy 51.511561 -154.63432) (xy 51.488915 -154.683907) (xy 51.459441 -154.729766) (xy 51.423741 -154.770963)
			(xy 51.38254 -154.80666) (xy 51.336679 -154.83613) (xy 51.28709 -154.858773) (xy 51.234784 -154.874127)
			(xy 51.180825 -154.881881) (xy 51.153568 -154.882342) (xy 51.123881 -154.88176) (xy 51.065222 -154.87257)
			(xy 51.008695 -154.854402) (xy 50.955667 -154.827694) (xy 50.907418 -154.793091) (xy 50.865114 -154.75143)
			(xy 50.84699 -154.72791) (xy 50.838564 -154.717303) (xy 50.817251 -154.700596) (xy 50.792297 -154.690077)
			(xy 50.765456 -154.686487) (xy 50.738615 -154.690077) (xy 50.713661 -154.700596) (xy 50.692348 -154.717303)
			(xy 50.683922 -154.72791) (xy 50.665776 -154.751412) (xy 50.623474 -154.793073) (xy 50.575229 -154.827678)
			(xy 50.522206 -154.854392) (xy 50.465685 -154.87257) (xy 50.40703 -154.881774) (xy 50.377344 -154.882342)
			(xy 50.350092 -154.881814) (xy 50.296141 -154.874063) (xy 50.243842 -154.858712) (xy 50.194261 -154.836074)
			(xy 50.148406 -154.80661) (xy 50.107212 -154.770919) (xy 50.071517 -154.729729) (xy 50.042047 -154.683878)
			(xy 50.019404 -154.634299) (xy 50.004047 -154.582002) (xy 49.996289 -154.528052) (xy 35.409981 -154.528052)
			(xy 35.395073 -154.634359) (xy 35.358144 -154.840421) (xy 35.313412 -155.044931) (xy 35.260943 -155.247593)
			(xy 35.200812 -155.448116) (xy 35.133106 -155.64621) (xy 35.057922 -155.841588) (xy 34.975369 -156.033968)
			(xy 34.885567 -156.223073) (xy 34.788645 -156.40863) (xy 34.684743 -156.59037) (xy 34.670357 -156.613451)
			(xy 50.206652 -156.613451) (xy 50.206652 -156.558949) (xy 50.214408 -156.505001) (xy 50.229762 -156.452707)
			(xy 50.252401 -156.403129) (xy 50.281865 -156.357277) (xy 50.317554 -156.316086) (xy 50.358742 -156.280392)
			(xy 50.40459 -156.250922) (xy 50.454165 -156.228277) (xy 50.506458 -156.212917) (xy 50.560405 -156.205155)
			(xy 50.587656 -156.204666) (xy 50.58791 -156.204666) (xy 50.617749 -156.205247) (xy 50.676695 -156.214559)
			(xy 50.705258 -156.223208) (xy 50.719167 -156.227239) (xy 50.748099 -156.228148) (xy 50.776118 -156.220883)
			(xy 50.800963 -156.206032) (xy 50.820629 -156.184792) (xy 50.833527 -156.158879) (xy 50.836576 -156.144722)
			(xy 50.843165 -156.111884) (xy 50.866284 -156.049031) (xy 50.88255 -156.019754) (xy 50.889618 -156.006804)
			(xy 50.896647 -155.978161) (xy 50.895197 -155.948704) (xy 50.885389 -155.92089) (xy 50.868042 -155.897039)
			(xy 50.844601 -155.879141) (xy 50.830988 -155.87345) (xy 50.80422 -155.862735) (xy 50.753979 -155.83445)
			(xy 50.70857 -155.798922) (xy 50.669027 -155.756963) (xy 50.636253 -155.709528) (xy 50.610993 -155.6577)
			(xy 50.593825 -155.60266) (xy 50.585139 -155.545662) (xy 50.584608 -155.516834) (xy 50.585094 -155.489583)
			(xy 50.59285 -155.435635) (xy 50.608205 -155.38334) (xy 50.630847 -155.333763) (xy 50.660313 -155.287913)
			(xy 50.696004 -155.246722) (xy 50.737195 -155.211031) (xy 50.783045 -155.181565) (xy 50.832622 -155.158923)
			(xy 50.884917 -155.143568) (xy 50.938865 -155.135812) (xy 50.993367 -155.135812) (xy 51.047315 -155.143568)
			(xy 51.09961 -155.158923) (xy 51.149187 -155.181565) (xy 51.195037 -155.211031) (xy 51.236228 -155.246722)
			(xy 51.271919 -155.287913) (xy 51.301385 -155.333763) (xy 51.324027 -155.38334) (xy 51.339382 -155.435635)
			(xy 51.347138 -155.489583) (xy 51.347624 -155.516834) (xy 51.347624 -155.517088) (xy 51.347224 -155.542292)
			(xy 51.340585 -155.59226) (xy 51.327409 -155.640914) (xy 51.307926 -155.687404) (xy 51.295554 -155.709366)
			(xy 51.28846 -155.722303) (xy 51.281434 -155.750951) (xy 51.282888 -155.780412) (xy 51.292701 -155.808229)
			(xy 51.310054 -155.832081) (xy 51.3335 -155.84998) (xy 51.347116 -155.85567) (xy 51.373892 -155.866366)
			(xy 51.424134 -155.894654) (xy 51.469543 -155.930184) (xy 51.509085 -155.972146) (xy 51.541859 -156.019583)
			(xy 51.567117 -156.071414) (xy 51.584283 -156.126457) (xy 51.592966 -156.183457) (xy 51.593496 -156.212286)
			(xy 51.593032 -156.239539) (xy 51.585276 -156.293491) (xy 51.569921 -156.345789) (xy 51.54728 -156.39537)
			(xy 51.517812 -156.441224) (xy 51.482118 -156.482417) (xy 51.440925 -156.518111) (xy 51.395072 -156.547579)
			(xy 51.345491 -156.570221) (xy 51.293193 -156.585576) (xy 51.239241 -156.593331) (xy 51.211988 -156.593794)
			(xy 51.211734 -156.593794) (xy 51.181895 -156.593227) (xy 51.122949 -156.583906) (xy 51.094386 -156.575252)
			(xy 51.080457 -156.571302) (xy 51.051539 -156.570385) (xy 51.02353 -156.577636) (xy 50.998691 -156.592471)
			(xy 50.979026 -156.613693) (xy 50.966122 -156.639589) (xy 50.963068 -156.653738) (xy 50.957919 -156.679816)
			(xy 50.941346 -156.73032) (xy 50.917921 -156.778034) (xy 50.888096 -156.822032) (xy 50.852451 -156.861463)
			(xy 50.811676 -156.895561) (xy 50.76656 -156.923667) (xy 50.717979 -156.945236) (xy 50.666873 -156.959849)
			(xy 50.614233 -156.967225) (xy 50.587656 -156.967682) (xy 50.560405 -156.967245) (xy 50.506458 -156.959483)
			(xy 50.454165 -156.944123) (xy 50.40459 -156.921478) (xy 50.358742 -156.892008) (xy 50.317554 -156.856314)
			(xy 50.281865 -156.815123) (xy 50.252401 -156.769271) (xy 50.229762 -156.719693) (xy 50.214408 -156.667399)
			(xy 50.206652 -156.613451) (xy 34.670357 -156.613451) (xy 34.57401 -156.768031) (xy 34.456608 -156.941357)
			(xy 34.332705 -157.110098) (xy 34.202481 -157.274009) (xy 34.066123 -157.432854) (xy 33.923829 -157.586403)
			(xy 33.775803 -157.734435) (xy 33.62226 -157.876737) (xy 33.463421 -158.013102) (xy 33.299516 -158.143334)
			(xy 33.130782 -158.267244) (xy 32.957461 -158.384654) (xy 32.779805 -158.495394) (xy 32.598069 -158.599305)
			(xy 32.412517 -158.696235) (xy 32.223416 -158.786046) (xy 32.031039 -158.868608) (xy 31.835665 -158.9438)
			(xy 31.637574 -159.011516) (xy 31.437054 -159.071656) (xy 31.399154 -159.08147) (xy 50.99304 -159.08147)
			(xy 50.993427 -159.054214) (xy 51.001189 -159.000258) (xy 51.016552 -158.947956) (xy 51.039201 -158.898372)
			(xy 51.068677 -158.852517) (xy 51.104379 -158.811323) (xy 51.145579 -158.77563) (xy 51.191441 -158.746164)
			(xy 51.241029 -158.723524) (xy 51.293334 -158.708173) (xy 51.347292 -158.700422) (xy 51.374548 -158.699962)
			(xy 51.402122 -158.700442) (xy 51.456695 -158.708388) (xy 51.509556 -158.724109) (xy 51.559603 -158.747276)
			(xy 51.605792 -158.777408) (xy 51.647163 -158.813875) (xy 51.665378 -158.834582) (xy 51.675276 -158.84548)
			(xy 51.699926 -158.861555) (xy 51.728134 -158.869939) (xy 51.757562 -158.869939) (xy 51.78577 -158.861555)
			(xy 51.81042 -158.84548) (xy 51.820318 -158.834582) (xy 51.838512 -158.813855) (xy 51.879885 -158.777387)
			(xy 51.926079 -158.747257) (xy 51.97613 -158.724094) (xy 52.028995 -158.708381) (xy 52.083572 -158.700445)
			(xy 52.111148 -158.699962) (xy 52.137649 -158.700415) (xy 52.19014 -158.707762) (xy 52.241107 -158.722307)
			(xy 52.289569 -158.74377) (xy 52.334592 -158.771737) (xy 52.355242 -158.788354) (xy 52.367396 -158.797784)
			(xy 52.395794 -158.809573) (xy 52.426411 -158.812397) (xy 52.456486 -158.806003) (xy 52.483306 -158.790967)
			(xy 52.504451 -158.768645) (xy 52.511706 -158.75508) (xy 52.523817 -158.731395) (xy 52.553737 -158.687413)
			(xy 52.589605 -158.64813) (xy 52.630693 -158.614345) (xy 52.653184 -158.60014) (xy 52.665431 -158.592248)
			(xy 52.685104 -158.570769) (xy 52.697907 -158.544607) (xy 52.702796 -158.515894) (xy 52.699373 -158.486969)
			(xy 52.694078 -158.473394) (xy 52.684593 -158.450182) (xy 52.671241 -158.40185) (xy 52.664511 -158.352161)
			(xy 52.664106 -158.32709) (xy 52.66454 -158.302021) (xy 52.671286 -158.252338) (xy 52.684614 -158.204004)
			(xy 52.694078 -158.180786) (xy 52.699333 -158.167207) (xy 52.702713 -158.138299) (xy 52.697811 -158.10961)
			(xy 52.685024 -158.083464) (xy 52.665389 -158.06198) (xy 52.653184 -158.05404) (xy 52.630024 -158.039514)
			(xy 52.587899 -158.004668) (xy 52.551317 -157.964041) (xy 52.521063 -157.918506) (xy 52.497786 -157.869039)
			(xy 52.481986 -157.816703) (xy 52.474001 -157.762619) (xy 52.474003 -157.70795) (xy 52.481993 -157.653867)
			(xy 52.497797 -157.601532) (xy 52.521079 -157.552067) (xy 52.551336 -157.506534) (xy 52.587922 -157.465911)
			(xy 52.630049 -157.431068) (xy 52.653184 -157.4165) (xy 52.66539 -157.408551) (xy 52.685063 -157.387088)
			(xy 52.697871 -157.360941) (xy 52.702771 -157.332241) (xy 52.699363 -157.303326) (xy 52.694078 -157.289754)
			(xy 52.684581 -157.266547) (xy 52.671233 -157.218213) (xy 52.664508 -157.168522) (xy 52.664106 -157.14345)
			(xy 52.664627 -157.115565) (xy 52.672939 -157.060418) (xy 52.689377 -157.007126) (xy 52.713575 -156.95688)
			(xy 52.744991 -156.910801) (xy 52.782924 -156.869919) (xy 52.826526 -156.835147) (xy 52.874824 -156.807262)
			(xy 52.926739 -156.786887) (xy 52.98111 -156.774477) (xy 53.036724 -156.77031) (xy 53.092338 -156.774477)
			(xy 53.146709 -156.786887) (xy 53.198624 -156.807262) (xy 53.246922 -156.835147) (xy 53.290524 -156.869919)
			(xy 53.328457 -156.910801) (xy 53.359873 -156.95688) (xy 53.384071 -157.007126) (xy 53.400509 -157.060418)
			(xy 53.408821 -157.115565) (xy 53.409342 -157.14345) (xy 53.408875 -157.170782) (xy 53.400906 -157.224863)
			(xy 53.385118 -157.277198) (xy 53.36185 -157.326662) (xy 53.331601 -157.372195) (xy 53.295022 -157.412817)
			(xy 53.252897 -157.447655) (xy 53.229764 -157.46222) (xy 53.217537 -157.470138) (xy 53.19787 -157.491612)
			(xy 53.185068 -157.517767) (xy 53.180173 -157.546472) (xy 53.183584 -157.575392) (xy 53.18887 -157.588966)
			(xy 53.198345 -157.612181) (xy 53.211701 -157.660512) (xy 53.218435 -157.710199) (xy 53.218842 -157.73527)
			(xy 53.218431 -157.76034) (xy 53.211677 -157.810023) (xy 53.198339 -157.858357) (xy 53.18887 -157.881574)
			(xy 53.183624 -157.895151) (xy 53.180262 -157.924051) (xy 53.185173 -157.952729) (xy 53.197961 -157.978863)
			(xy 53.217591 -158.000338) (xy 53.229764 -158.00832) (xy 53.252885 -158.022903) (xy 53.295003 -158.057747)
			(xy 53.331579 -158.098369) (xy 53.361829 -158.143898) (xy 53.385103 -158.193358) (xy 53.400902 -158.245688)
			(xy 53.408888 -158.299764) (xy 53.408889 -158.354426) (xy 53.400905 -158.408502) (xy 53.385107 -158.460832)
			(xy 53.361834 -158.510292) (xy 53.331585 -158.555823) (xy 53.29501 -158.596446) (xy 53.252893 -158.631291)
			(xy 53.229764 -158.64586) (xy 53.217509 -158.653739) (xy 53.197842 -158.675225) (xy 53.185043 -158.70139)
			(xy 53.180156 -158.730104) (xy 53.183577 -158.75903) (xy 53.18887 -158.772606) (xy 53.198357 -158.795817)
			(xy 53.211708 -158.844149) (xy 53.218438 -158.893838) (xy 53.218842 -158.91891) (xy 53.21837 -158.945752)
			(xy 53.210665 -158.998881) (xy 53.195416 -159.050354) (xy 53.172938 -159.099106) (xy 53.143697 -159.144127)
			(xy 53.108298 -159.184487) (xy 53.067473 -159.219349) (xy 53.022069 -159.247993) (xy 52.973024 -159.269824)
			(xy 52.947316 -159.277558) (xy 52.932841 -159.282276) (xy 52.907286 -159.298788) (xy 52.887726 -159.322092)
			(xy 52.875894 -159.350122) (xy 52.87284 -159.380393) (xy 52.878835 -159.410222) (xy 52.885594 -159.423862)
			(xy 52.900228 -159.452008) (xy 52.920955 -159.511959) (xy 52.931453 -159.574517) (xy 52.932076 -159.606234)
			(xy 52.931855 -159.624253) (xy 52.928421 -159.660128) (xy 52.925218 -159.677862) (xy 52.922936 -159.693077)
			(xy 52.926453 -159.723622) (xy 52.938901 -159.751736) (xy 52.959153 -159.774871) (xy 52.985373 -159.790931)
			(xy 53.000148 -159.79521) (xy 53.027191 -159.802611) (xy 53.078917 -159.824241) (xy 53.126922 -159.853205)
			(xy 53.170174 -159.88888) (xy 53.207741 -159.930499) (xy 53.238815 -159.977165) (xy 53.262728 -160.027876)
			(xy 53.278965 -160.08154) (xy 53.287177 -160.137001) (xy 53.287676 -160.165034) (xy 53.287254 -160.192288)
			(xy 53.279492 -160.246239) (xy 53.264131 -160.298537) (xy 53.241483 -160.348117) (xy 53.21201 -160.393968)
			(xy 53.176312 -160.435159) (xy 53.135115 -160.47085) (xy 53.089259 -160.500315) (xy 53.039675 -160.522954)
			(xy 52.987375 -160.538306) (xy 52.933422 -160.546058) (xy 52.906168 -160.546542) (xy 52.878594 -160.54605)
			(xy 52.824022 -160.538105) (xy 52.771161 -160.522387) (xy 52.721115 -160.499222) (xy 52.674925 -160.469093)
			(xy 52.633554 -160.432628) (xy 52.615338 -160.411922) (xy 52.60544 -160.401024) (xy 52.58079 -160.384949)
			(xy 52.552582 -160.376565) (xy 52.523154 -160.376565) (xy 52.494946 -160.384949) (xy 52.470296 -160.401024)
			(xy 52.460398 -160.411922) (xy 52.442183 -160.432628) (xy 52.400812 -160.469093) (xy 52.354622 -160.49922)
			(xy 52.304575 -160.522383) (xy 52.251714 -160.538099) (xy 52.197142 -160.546039) (xy 52.141994 -160.546039)
			(xy 52.087422 -160.538099) (xy 52.034561 -160.522383) (xy 51.984514 -160.49922) (xy 51.938324 -160.469093)
			(xy 51.896953 -160.432628) (xy 51.878738 -160.411922) (xy 51.86884 -160.401024) (xy 51.84419 -160.384949)
			(xy 51.815982 -160.376565) (xy 51.786554 -160.376565) (xy 51.758346 -160.384949) (xy 51.733696 -160.401024)
			(xy 51.723798 -160.411922) (xy 51.705596 -160.432642) (xy 51.664225 -160.46911) (xy 51.618033 -160.499241)
			(xy 51.567983 -160.522405) (xy 51.515119 -160.53812) (xy 51.460543 -160.546058) (xy 51.432968 -160.546542)
			(xy 51.405718 -160.546052) (xy 51.351772 -160.538292) (xy 51.299479 -160.522935) (xy 51.249904 -160.500292)
			(xy 51.204055 -160.470826) (xy 51.162866 -160.435135) (xy 51.127175 -160.393946) (xy 51.097709 -160.348098)
			(xy 51.075066 -160.298523) (xy 51.059708 -160.24623) (xy 51.051948 -160.192284) (xy 51.05146 -160.165034)
			(xy 51.052043 -160.137181) (xy 51.060161 -160.08207) (xy 51.0762 -160.028722) (xy 51.09982 -159.978272)
			(xy 51.130519 -159.931788) (xy 51.167647 -159.890258) (xy 51.210414 -159.854563) (xy 51.257914 -159.825461)
			(xy 51.309138 -159.803569) (xy 51.33594 -159.795972) (xy 51.350063 -159.791719) (xy 51.375204 -159.77632)
			(xy 51.394916 -159.754396) (xy 51.407566 -159.727764) (xy 51.412104 -159.698632) (xy 51.410616 -159.683958)
			(xy 51.408945 -159.670942) (xy 51.407166 -159.644757) (xy 51.40706 -159.631634) (xy 51.407158 -159.617485)
			(xy 51.409189 -159.589262) (xy 51.411124 -159.575246) (xy 51.412683 -159.561896) (xy 51.409585 -159.535209)
			(xy 51.39962 -159.510259) (xy 51.38348 -159.488781) (xy 51.362288 -159.472267) (xy 51.337516 -159.461867)
			(xy 51.324256 -159.459676) (xy 51.297113 -159.45553) (xy 51.244287 -159.440561) (xy 51.194152 -159.418174)
			(xy 51.147744 -159.388832) (xy 51.106021 -159.353141) (xy 51.069844 -159.311838) (xy 51.039961 -159.265777)
			(xy 51.016989 -159.215907) (xy 51.001402 -159.16326) (xy 50.993522 -159.108923) (xy 50.99304 -159.08147)
			(xy 31.399154 -159.08147) (xy 31.234394 -159.124134) (xy 31.029886 -159.168875) (xy 30.823826 -159.205813)
			(xy 30.616512 -159.234896) (xy 30.408242 -159.256081) (xy 30.199317 -159.269338) (xy 29.99004 -159.274648)
			(xy 29.780712 -159.272002) (xy 29.571636 -159.261406) (xy 29.363113 -159.242873) (xy 29.155445 -159.216431)
			(xy 28.948932 -159.182119) (xy 28.743871 -159.139985) (xy 28.540559 -159.09009) (xy 28.33929 -159.032507)
			(xy 28.140354 -158.967318) (xy 27.944038 -158.894618) (xy 27.750626 -158.814512) (xy 27.560397 -158.727115)
			(xy 27.373626 -158.632554) (xy 27.190583 -158.530966) (xy 27.011531 -158.422496) (xy 26.83673 -158.307301)
			(xy 26.666432 -158.185548) (xy 26.500883 -158.057413) (xy 26.340321 -157.923081) (xy 26.18498 -157.782745)
			(xy 26.035082 -157.636609) (xy 25.890844 -157.484883) (xy 25.752476 -157.327787) (xy 25.620176 -157.165547)
			(xy 25.494135 -156.998397) (xy 25.374537 -156.826579) (xy 25.261552 -156.650342) (xy 25.155345 -156.469939)
			(xy 25.056069 -156.285631) (xy 24.963867 -156.097684) (xy 24.878873 -155.90637) (xy 24.801208 -155.711965)
			(xy 24.730986 -155.514749) (xy 24.668307 -155.315008) (xy 24.613263 -155.113029) (xy 24.565932 -154.909105)
			(xy 24.526383 -154.70353) (xy 24.494674 -154.496601) (xy 24.470849 -154.288617) (xy 24.454943 -154.079877)
			(xy 24.44698 -153.870684) (xy 24.446484 -153.766012) (xy 24.446484 -153.764742) (xy 24.447021 -153.656343)
			(xy 24.455568 -153.439713) (xy 24.472635 -153.223587) (xy 24.498196 -153.008301) (xy 24.532211 -152.794188)
			(xy 24.55291 -152.687782) (xy 24.575685 -152.576589) (xy 24.629227 -152.355994) (xy 24.691808 -152.137791)
			(xy 24.763323 -151.922351) (xy 24.84365 -151.710038) (xy 24.932652 -151.501214) (xy 24.9809 -151.398478)
			(xy 24.986232 -151.385408) (xy 24.990237 -151.357478) (xy 24.986439 -151.329519) (xy 24.975129 -151.303668)
			(xy 24.957172 -151.281904) (xy 24.933941 -151.265889) (xy 24.907212 -151.256849) (xy 24.87903 -151.255475)
			(xy 24.851548 -151.261872) (xy 24.82687 -151.275551) (xy 24.816562 -151.285194) (xy 21.119592 -154.982164)
			(xy 21.119592 -160.088834) (xy 21.421598 -160.39084) (xy 21.77923 -160.39084) (xy 21.853652 -160.316418)
			(xy 21.947632 -160.222692) (xy 21.947632 -159.958532) (xy 21.904198 -159.951928) (xy 21.877422 -159.947425)
			(xy 21.82541 -159.931838) (xy 21.776132 -159.909041) (xy 21.730579 -159.879493) (xy 21.689671 -159.843791)
			(xy 21.654232 -159.802654) (xy 21.624978 -159.756912) (xy 21.602499 -159.707488) (xy 21.587246 -159.655377)
			(xy 21.579529 -159.601632) (xy 21.579078 -159.574484) (xy 21.579565 -159.547233) (xy 21.587323 -159.493286)
			(xy 21.60268 -159.440993) (xy 21.625321 -159.391417) (xy 21.654788 -159.345567) (xy 21.690479 -159.304378)
			(xy 21.731669 -159.268687) (xy 21.777518 -159.23922) (xy 21.827095 -159.216579) (xy 21.879388 -159.201223)
			(xy 21.933335 -159.193465) (xy 21.960586 -159.192976) (xy 21.986966 -159.19342) (xy 22.039222 -159.200682)
			(xy 22.089982 -159.21507) (xy 22.138277 -159.236308) (xy 22.183188 -159.263994) (xy 22.22386 -159.2976)
			(xy 22.259517 -159.336485) (xy 22.289482 -159.379909) (xy 22.301708 -159.403288) (xy 22.30841 -159.415647)
			(xy 22.327385 -159.436375) (xy 22.351299 -159.451137) (xy 22.378335 -159.458809) (xy 22.406437 -159.458809)
			(xy 22.433473 -159.451137) (xy 22.457387 -159.436375) (xy 22.476362 -159.415647) (xy 22.483064 -159.403288)
			(xy 22.495308 -159.379919) (xy 22.525267 -159.336494) (xy 22.56092 -159.297608) (xy 22.601589 -159.264003)
			(xy 22.646499 -159.236319) (xy 22.694793 -159.215084) (xy 22.745552 -159.200703) (xy 22.797808 -159.193449)
			(xy 22.824186 -159.192976) (xy 22.851923 -159.193479) (xy 22.906813 -159.201522) (xy 22.959959 -159.217425)
			(xy 23.010245 -159.240854) (xy 23.056609 -159.271314) (xy 23.098075 -159.308165) (xy 23.133771 -159.350631)
			(xy 23.162944 -159.397816) (xy 23.18498 -159.448727) (xy 23.199414 -159.502292) (xy 23.203154 -159.52978)
			(xy 23.204678 -159.543496) (xy 23.206494 -159.572147) (xy 23.202535 -159.629419) (xy 23.190042 -159.685451)
			(xy 23.169298 -159.738981) (xy 23.14077 -159.788799) (xy 23.105103 -159.833783) (xy 23.0631 -159.872916)
			(xy 23.015709 -159.905317) (xy 22.964 -159.930255) (xy 22.909139 -159.947166) (xy 22.880828 -159.951928)
			(xy 22.83714 -159.958278) (xy 22.83714 -160.368742) (xy 22.837394 -160.48609) (xy 22.836784 -160.511074)
			(xy 22.827046 -160.560085) (xy 22.80794 -160.606257) (xy 22.780201 -160.647819) (xy 22.762972 -160.665922)
			(xy 22.27453 -161.154364) (xy 25.594308 -161.154364) (xy 25.598379 -161.098742) (xy 25.610505 -161.044305)
			(xy 25.630428 -160.992214) (xy 25.657724 -160.943579) (xy 25.69181 -160.899436) (xy 25.731959 -160.860727)
			(xy 25.777317 -160.828276) (xy 25.826917 -160.802775) (xy 25.879701 -160.784768) (xy 25.934544 -160.774638)
			(xy 25.990278 -160.772601) (xy 26.045715 -160.778701) (xy 26.099672 -160.792807) (xy 26.151001 -160.814619)
			(xy 26.198607 -160.843673) (xy 26.241475 -160.879348) (xy 26.278692 -160.920885) (xy 26.309465 -160.967398)
			(xy 26.309713 -160.967928) (xy 26.570432 -160.967928) (xy 26.570946 -160.940755) (xy 26.578642 -160.886956)
			(xy 26.593896 -160.834795) (xy 26.6164 -160.785326) (xy 26.645697 -160.739553) (xy 26.681194 -160.698402)
			(xy 26.722173 -160.662705) (xy 26.767804 -160.633187) (xy 26.817163 -160.610444) (xy 26.86925 -160.594938)
			(xy 26.89606 -160.590484) (xy 26.90991 -160.587923) (xy 26.935569 -160.576339) (xy 26.957091 -160.558192)
			(xy 26.972845 -160.53486) (xy 26.981632 -160.508114) (xy 26.982786 -160.479985) (xy 26.97622 -160.45261)
			(xy 26.96972 -160.440116) (xy 26.958096 -160.418623) (xy 26.939779 -160.373325) (xy 26.927382 -160.326061)
			(xy 26.921109 -160.277603) (xy 26.920698 -160.253172) (xy 26.920698 -160.252918) (xy 26.921172 -160.225665)
			(xy 26.928927 -160.171714) (xy 26.944281 -160.119416) (xy 26.966922 -160.069836) (xy 26.996388 -160.023982)
			(xy 27.032081 -159.982789) (xy 27.073273 -159.947096) (xy 27.119125 -159.917627) (xy 27.168705 -159.894985)
			(xy 27.221003 -159.879629) (xy 27.274953 -159.871873) (xy 27.302206 -159.87141) (xy 27.329163 -159.871906)
			(xy 27.38254 -159.879496) (xy 27.434317 -159.894525) (xy 27.483463 -159.916692) (xy 27.528999 -159.945556)
			(xy 27.570019 -159.980543) (xy 27.58821 -160.000442) (xy 27.5982 -160.011136) (xy 27.622961 -160.026717)
			(xy 27.651124 -160.034637) (xy 27.680377 -160.034246) (xy 27.708318 -160.025576) (xy 27.732653 -160.009339)
			(xy 27.742388 -159.99841) (xy 27.760611 -159.977409) (xy 27.802113 -159.940408) (xy 27.848545 -159.909821)
			(xy 27.898924 -159.886295) (xy 27.952183 -159.870329) (xy 28.007195 -159.86226) (xy 28.034996 -159.861758)
			(xy 28.062246 -159.862281) (xy 28.11619 -159.870036) (xy 28.168482 -159.885389) (xy 28.218057 -159.908028)
			(xy 28.263906 -159.93749) (xy 28.305095 -159.973178) (xy 28.340787 -160.014364) (xy 28.370254 -160.060209)
			(xy 28.392897 -160.109782) (xy 28.408255 -160.162073) (xy 28.416016 -160.216016) (xy 28.416504 -160.243266)
			(xy 28.41498 -160.278064) (xy 28.414165 -160.293081) (xy 28.420272 -160.322513) (xy 28.434692 -160.348886)
			(xy 28.456174 -160.369911) (xy 28.482851 -160.383762) (xy 28.49753 -160.38703) (xy 28.526432 -160.392984)
			(xy 28.582076 -160.412623) (xy 28.634041 -160.440578) (xy 28.681095 -160.476185) (xy 28.702 -160.497012)
			(xy 28.713208 -160.507706) (xy 28.740419 -160.522471) (xy 28.770798 -160.528431) (xy 28.801571 -160.525042)
			(xy 28.829926 -160.512612) (xy 28.841954 -160.502854) (xy 28.862882 -160.485154) (xy 28.908886 -160.455355)
			(xy 28.958685 -160.432455) (xy 29.011251 -160.416926) (xy 29.0655 -160.409088) (xy 29.092906 -160.40862)
			(xy 29.09316 -160.40862) (xy 29.122313 -160.409181) (xy 29.179938 -160.41806) (xy 29.235541 -160.435603)
			(xy 29.287829 -160.4614) (xy 29.335584 -160.494852) (xy 29.377693 -160.535179) (xy 29.413177 -160.581443)
			(xy 29.427678 -160.60674) (xy 29.435187 -160.619327) (xy 29.455948 -160.639992) (xy 29.481718 -160.653918)
			(xy 29.510381 -160.659958) (xy 29.53958 -160.657617) (xy 29.566914 -160.647087) (xy 29.590137 -160.629234)
			(xy 29.599128 -160.617662) (xy 29.61455 -160.596998) (xy 29.650085 -160.559636) (xy 29.690329 -160.5274)
			(xy 29.734547 -160.500876) (xy 29.781933 -160.480549) (xy 29.831626 -160.466789) (xy 29.882719 -160.459845)
			(xy 29.9085 -160.45942) (xy 29.934856 -160.459881) (xy 29.987065 -160.467149) (xy 30.037778 -160.481532)
			(xy 30.086028 -160.502757) (xy 30.130899 -160.53042) (xy 30.171536 -160.563994) (xy 30.189678 -160.583118)
			(xy 30.198948 -160.592739) (xy 30.221445 -160.607141) (xy 30.246909 -160.615206) (xy 30.273594 -160.616381)
			(xy 30.299669 -160.610586) (xy 30.323344 -160.598219) (xy 30.333442 -160.589468) (xy 30.354685 -160.570621)
			(xy 30.4017 -160.53877) (xy 30.452918 -160.514243) (xy 30.507207 -160.497582) (xy 30.563366 -160.489155)
			(xy 30.59176 -160.48863) (xy 30.619017 -160.489014) (xy 30.672978 -160.496767) (xy 30.725286 -160.512121)
			(xy 30.774876 -160.534764) (xy 30.820739 -160.564234) (xy 30.861941 -160.599931) (xy 30.897642 -160.641129)
			(xy 30.927117 -160.686989) (xy 30.949765 -160.736576) (xy 30.965124 -160.788883) (xy 30.972883 -160.842843)
			(xy 30.972883 -160.897357) (xy 30.965124 -160.951317) (xy 30.949765 -161.003624) (xy 30.927117 -161.053211)
			(xy 30.897642 -161.099071) (xy 30.861941 -161.140269) (xy 30.820739 -161.175966) (xy 30.774876 -161.205436)
			(xy 30.725286 -161.228079) (xy 30.672978 -161.243433) (xy 30.619017 -161.251186) (xy 30.59176 -161.251646)
			(xy 30.565402 -161.251223) (xy 30.513191 -161.243949) (xy 30.462478 -161.229559) (xy 30.414227 -161.208327)
			(xy 30.369357 -161.180657) (xy 30.328723 -161.147075) (xy 30.310582 -161.127948) (xy 30.301256 -161.118382)
			(xy 30.278778 -161.103969) (xy 30.253326 -161.095892) (xy 30.22665 -161.094705) (xy 30.200582 -161.100491)
			(xy 30.176913 -161.112851) (xy 30.166818 -161.121598) (xy 30.145586 -161.140458) (xy 30.098569 -161.172308)
			(xy 30.047348 -161.196834) (xy 29.993056 -161.213491) (xy 29.936895 -161.221913) (xy 29.9085 -161.222436)
			(xy 29.879345 -161.22193) (xy 29.821716 -161.213043) (xy 29.76611 -161.195493) (xy 29.713822 -161.169687)
			(xy 29.666068 -161.136226) (xy 29.62396 -161.09589) (xy 29.58848 -161.049617) (xy 29.573982 -161.024316)
			(xy 29.566526 -161.011692) (xy 29.545759 -160.991013) (xy 29.519977 -160.977081) (xy 29.491299 -160.971041)
			(xy 29.462087 -160.973391) (xy 29.434744 -160.983937) (xy 29.41152 -161.001811) (xy 29.402532 -161.013394)
			(xy 29.387061 -161.03402) (xy 29.351535 -161.071385) (xy 29.311301 -161.103626) (xy 29.267092 -161.130155)
			(xy 29.219712 -161.150488) (xy 29.170026 -161.164256) (xy 29.118939 -161.171207) (xy 29.09316 -161.171636)
			(xy 29.067638 -161.171269) (xy 29.017049 -161.164468) (xy 28.967819 -161.15098) (xy 28.920828 -161.131046)
			(xy 28.876916 -161.105023) (xy 28.836868 -161.073374) (xy 28.81884 -161.055304) (xy 28.807683 -161.044552)
			(xy 28.780455 -161.02979) (xy 28.750059 -161.02384) (xy 28.719275 -161.027244) (xy 28.690915 -161.039693)
			(xy 28.678886 -161.049462) (xy 28.657945 -161.067146) (xy 28.611944 -161.096946) (xy 28.562148 -161.119849)
			(xy 28.509585 -161.135382) (xy 28.455339 -161.143225) (xy 28.427934 -161.143696) (xy 28.42768 -161.143696)
			(xy 28.400428 -161.143241) (xy 28.346478 -161.135481) (xy 28.294182 -161.120123) (xy 28.244604 -161.097479)
			(xy 28.198753 -161.068009) (xy 28.157563 -161.032314) (xy 28.121872 -160.991121) (xy 28.092406 -160.945268)
			(xy 28.069766 -160.895688) (xy 28.054412 -160.84339) (xy 28.046657 -160.78944) (xy 28.046172 -160.762188)
			(xy 28.047696 -160.72739) (xy 28.048492 -160.712374) (xy 28.042378 -160.682951) (xy 28.027959 -160.656584)
			(xy 28.006486 -160.635559) (xy 27.97982 -160.6217) (xy 27.965146 -160.618424) (xy 27.94033 -160.613351)
			(xy 27.892202 -160.597564) (xy 27.846588 -160.575544) (xy 27.804291 -160.54768) (xy 27.766054 -160.514462)
			(xy 27.748992 -160.495742) (xy 27.738999 -160.485052) (xy 27.714238 -160.469473) (xy 27.686077 -160.461554)
			(xy 27.656825 -160.461945) (xy 27.628885 -160.470613) (xy 27.604549 -160.486847) (xy 27.594814 -160.497774)
			(xy 27.576613 -160.51873) (xy 27.535206 -160.555693) (xy 27.48888 -160.586264) (xy 27.438613 -160.6098)
			(xy 27.385466 -160.625802) (xy 27.358086 -160.630362) (xy 27.344215 -160.632826) (xy 27.318551 -160.644429)
			(xy 27.297027 -160.662594) (xy 27.281276 -160.685943) (xy 27.272494 -160.712704) (xy 27.271346 -160.740845)
			(xy 27.277921 -160.768232) (xy 27.284426 -160.78073) (xy 27.296071 -160.802211) (xy 27.314383 -160.847515)
			(xy 27.326773 -160.894782) (xy 27.33304 -160.943242) (xy 27.333448 -160.967674) (xy 27.333448 -160.967928)
			(xy 27.332962 -160.995179) (xy 27.325206 -161.049127) (xy 27.309851 -161.101422) (xy 27.287209 -161.150999)
			(xy 27.257743 -161.196849) (xy 27.222052 -161.23804) (xy 27.180861 -161.273731) (xy 27.135011 -161.303197)
			(xy 27.085434 -161.325839) (xy 27.033139 -161.341194) (xy 26.979191 -161.34895) (xy 26.924689 -161.34895)
			(xy 26.870741 -161.341194) (xy 26.818446 -161.325839) (xy 26.768869 -161.303197) (xy 26.723019 -161.273731)
			(xy 26.681828 -161.23804) (xy 26.646137 -161.196849) (xy 26.616671 -161.150999) (xy 26.594029 -161.101422)
			(xy 26.578674 -161.049127) (xy 26.570918 -160.995179) (xy 26.570432 -160.967928) (xy 26.309713 -160.967928)
			(xy 26.333137 -161.017895) (xy 26.349205 -161.071302) (xy 26.357325 -161.126478) (xy 26.357834 -161.154364)
			(xy 26.357325 -161.18225) (xy 26.349205 -161.237426) (xy 26.333137 -161.290833) (xy 26.309465 -161.34133)
			(xy 26.278692 -161.387843) (xy 26.241475 -161.42938) (xy 26.198607 -161.465055) (xy 26.151001 -161.494109)
			(xy 26.099672 -161.515921) (xy 26.045715 -161.530027) (xy 25.990278 -161.536127) (xy 25.934544 -161.53409)
			(xy 25.879701 -161.52396) (xy 25.826917 -161.505953) (xy 25.777317 -161.480452) (xy 25.731959 -161.448001)
			(xy 25.69181 -161.409292) (xy 25.657724 -161.365149) (xy 25.630428 -161.316514) (xy 25.610505 -161.264423)
			(xy 25.598379 -161.209986) (xy 25.594308 -161.154364) (xy 22.27453 -161.154364) (xy 22.222714 -161.20618)
			(xy 22.204618 -161.223435) (xy 22.163071 -161.251241) (xy 22.116901 -161.270413) (xy 22.067878 -161.280215)
			(xy 22.042882 -161.280856) (xy 21.157946 -161.280856) (xy 21.13295 -161.280219) (xy 21.083927 -161.270418)
			(xy 21.037756 -161.251244) (xy 20.996213 -161.223432) (xy 20.978114 -161.20618) (xy 20.304252 -160.532318)
			(xy 20.286995 -160.514223) (xy 20.259185 -160.472677) (xy 20.240009 -160.426506) (xy 20.230205 -160.377483)
			(xy 20.229576 -160.352486) (xy 20.229576 -154.718512) (xy 20.230217 -154.693518) (xy 20.240023 -154.644499)
			(xy 20.259204 -154.598334) (xy 20.287021 -154.556798) (xy 20.304252 -154.53868) (xy 33.23844 -141.604746)
			(xy 33.23844 -135.56234) (xy 33.237942 -135.548591) (xy 33.230523 -135.522108) (xy 33.216318 -135.498558)
			(xy 33.196354 -135.479642) (xy 33.172073 -135.466727) (xy 33.145229 -135.460745) (xy 33.117762 -135.46213)
			(xy 33.104582 -135.466074) (xy 33.081493 -135.475159) (xy 33.033553 -135.487945) (xy 32.984356 -135.49439)
			(xy 32.959548 -135.494776) (xy 32.932295 -135.494316) (xy 32.878344 -135.486565) (xy 32.826044 -135.471215)
			(xy 32.776462 -135.448577) (xy 32.730607 -135.419113) (xy 32.689412 -135.383422) (xy 32.653716 -135.342231)
			(xy 32.624246 -135.29638) (xy 32.601602 -135.246801) (xy 32.586245 -135.194503) (xy 32.578487 -135.140553)
			(xy 32.578487 -135.086047) (xy 32.586245 -135.032097) (xy 32.601602 -134.979799) (xy 32.624246 -134.93022)
			(xy 32.653716 -134.884369) (xy 32.689412 -134.843178) (xy 32.730607 -134.807487) (xy 32.776462 -134.778023)
			(xy 32.826044 -134.755385) (xy 32.878344 -134.740035) (xy 32.932295 -134.732284) (xy 32.959548 -134.73176)
			(xy 32.984354 -134.732176) (xy 33.033545 -134.738633) (xy 33.081489 -134.751394) (xy 33.104582 -134.760462)
			(xy 33.117776 -134.764411) (xy 33.145267 -134.765876) (xy 33.172149 -134.759937) (xy 33.196464 -134.747026)
			(xy 33.216442 -134.728084) (xy 33.230627 -134.704489) (xy 33.237987 -134.677961) (xy 33.23844 -134.664196)
			(xy 33.23844 -134.066788) (xy 35.86099 -131.444238) (xy 35.86099 -130.421888) (xy 36.737798 -129.54508)
			(xy 37.760148 -129.54508) (xy 38.020752 -129.284476) (xy 38.030653 -129.273867) (xy 38.044588 -129.248428)
			(xy 38.050807 -129.220098) (xy 38.048806 -129.191161) (xy 38.038747 -129.163956) (xy 38.021443 -129.140678)
			(xy 37.998291 -129.123206) (xy 37.971159 -129.112952) (xy 37.956744 -129.111248) (xy 37.929919 -129.110153)
			(xy 37.876956 -129.101366) (xy 37.825748 -129.085239) (xy 37.777308 -129.062091) (xy 37.732591 -129.032379)
			(xy 37.692483 -128.996692) (xy 37.657775 -128.955733) (xy 37.629152 -128.910312) (xy 37.607181 -128.861326)
			(xy 37.592296 -128.809744) (xy 37.584791 -128.756584) (xy 37.58438 -128.72974) (xy 37.58484 -128.702485)
			(xy 37.592592 -128.648529) (xy 37.607945 -128.596226) (xy 37.630585 -128.54664) (xy 37.660052 -128.500781)
			(xy 37.695745 -128.459582) (xy 37.736939 -128.423883) (xy 37.782794 -128.39441) (xy 37.832377 -128.371763)
			(xy 37.884678 -128.356403) (xy 37.938633 -128.348644) (xy 37.965888 -128.348232) (xy 37.992724 -128.348694)
			(xy 38.045866 -128.356226) (xy 38.097428 -128.371129) (xy 38.146394 -128.393108) (xy 38.191797 -128.421731)
			(xy 38.232743 -128.456433) (xy 38.268423 -128.496528) (xy 38.298133 -128.541228) (xy 38.321289 -128.589648)
			(xy 38.337432 -128.640836) (xy 38.346245 -128.69378) (xy 38.347396 -128.720596) (xy 38.348935 -128.735053)
			(xy 38.359163 -128.762254) (xy 38.376644 -128.78547) (xy 38.39996 -128.802818) (xy 38.427221 -128.81289)
			(xy 38.456215 -128.81487) (xy 38.484591 -128.808597) (xy 38.510049 -128.794581) (xy 38.520624 -128.784604)
			(xy 39.1922 -128.113028) (xy 39.1922 -126.145544) (xy 39.191609 -126.130403) (xy 39.182667 -126.101467)
			(xy 39.165643 -126.076419) (xy 39.142029 -126.057455) (xy 39.113897 -126.046237) (xy 39.083714 -126.043751)
			(xy 39.054126 -126.050212) (xy 39.027727 -126.065056) (xy 39.01694 -126.075694) (xy 38.998733 -126.096188)
			(xy 38.95745 -126.132258) (xy 38.91143 -126.162047) (xy 38.86162 -126.184941) (xy 38.809046 -126.200471)
			(xy 38.75479 -126.208315) (xy 38.72738 -126.20879) (xy 38.699774 -126.2083) (xy 38.64514 -126.200338)
			(xy 38.592224 -126.184584) (xy 38.542132 -126.161366) (xy 38.49591 -126.131169) (xy 38.454524 -126.094625)
			(xy 38.418838 -126.052497) (xy 38.389598 -126.005664) (xy 38.367414 -125.955106) (xy 38.359588 -125.928628)
			(xy 38.354782 -125.916098) (xy 38.339644 -125.893949) (xy 38.319257 -125.876511) (xy 38.295029 -125.864989)
			(xy 38.268635 -125.86018) (xy 38.241901 -125.862416) (xy 38.216673 -125.871543) (xy 38.20541 -125.878844)
			(xy 38.181285 -125.894961) (xy 38.12919 -125.920495) (xy 38.073833 -125.937855) (xy 38.016486 -125.946642)
			(xy 37.987478 -125.94717) (xy 37.960231 -125.946682) (xy 37.906291 -125.938924) (xy 37.854004 -125.923569)
			(xy 37.804434 -125.900928) (xy 37.758591 -125.871465) (xy 37.717408 -125.835777) (xy 37.681722 -125.794591)
			(xy 37.652261 -125.748746) (xy 37.629624 -125.699176) (xy 37.614271 -125.646888) (xy 37.606516 -125.592947)
			(xy 37.606516 -125.538452) (xy 37.614271 -125.484512) (xy 37.629624 -125.432224) (xy 37.652261 -125.382654)
			(xy 37.681722 -125.336809) (xy 37.717408 -125.295623) (xy 37.758591 -125.259935) (xy 37.804434 -125.230472)
			(xy 37.854004 -125.207831) (xy 37.906291 -125.192476) (xy 37.960231 -125.184718) (xy 37.987478 -125.184154)
			(xy 38.015085 -125.184641) (xy 38.069721 -125.192599) (xy 38.12264 -125.20835) (xy 38.172734 -125.231566)
			(xy 38.218959 -125.261762) (xy 38.260346 -125.298307) (xy 38.296033 -125.340438) (xy 38.325272 -125.387273)
			(xy 38.347453 -125.437834) (xy 38.35527 -125.464316) (xy 38.360071 -125.476856) (xy 38.375205 -125.499026)
			(xy 38.395595 -125.516483) (xy 38.419832 -125.528021) (xy 38.446238 -125.53284) (xy 38.472988 -125.530608)
			(xy 38.49823 -125.521479) (xy 38.509448 -125.5141) (xy 38.533573 -125.497985) (xy 38.585669 -125.472456)
			(xy 38.641027 -125.455102) (xy 38.698373 -125.446323) (xy 38.72738 -125.445774) (xy 38.754819 -125.446255)
			(xy 38.80913 -125.454125) (xy 38.861754 -125.469692) (xy 38.911607 -125.492633) (xy 38.95766 -125.522477)
			(xy 38.998966 -125.558609) (xy 39.017194 -125.579124) (xy 39.028053 -125.589663) (xy 39.05445 -125.604425)
			(xy 39.08401 -125.610817) (xy 39.114148 -125.608281) (xy 39.142224 -125.597037) (xy 39.165783 -125.578071)
			(xy 39.182761 -125.553042) (xy 39.191672 -125.524141) (xy 39.1922 -125.50902) (xy 39.1922 -124.424948)
			(xy 36.3474 -121.580148) (xy 35.442144 -121.580148) (xy 35.428091 -121.580632) (xy 35.401065 -121.58836)
			(xy 35.377167 -121.603159) (xy 35.358207 -121.623911) (xy 35.345618 -121.649043) (xy 35.340355 -121.676655)
			(xy 35.342814 -121.704656) (xy 35.352811 -121.730928) (xy 35.360864 -121.742454) (xy 35.376575 -121.76281)
			(xy 35.402966 -121.806942) (xy 35.423187 -121.85422) (xy 35.436873 -121.903786) (xy 35.443775 -121.954742)
			(xy 35.444176 -121.980452) (xy 35.44369 -122.007703) (xy 35.435934 -122.061651) (xy 35.420579 -122.113946)
			(xy 35.397937 -122.163523) (xy 35.368471 -122.209373) (xy 35.33278 -122.250564) (xy 35.291589 -122.286255)
			(xy 35.245739 -122.315721) (xy 35.196162 -122.338363) (xy 35.143867 -122.353718) (xy 35.089919 -122.361474)
			(xy 35.035417 -122.361474) (xy 34.981469 -122.353718) (xy 34.929174 -122.338363) (xy 34.879597 -122.315721)
			(xy 34.833747 -122.286255) (xy 34.792556 -122.250564) (xy 34.756865 -122.209373) (xy 34.727399 -122.163523)
			(xy 34.704757 -122.113946) (xy 34.689402 -122.061651) (xy 34.681646 -122.007703) (xy 34.68116 -121.980452)
			(xy 34.681594 -121.954581) (xy 34.68859 -121.903313) (xy 34.702446 -121.85346) (xy 34.72291 -121.805935)
			(xy 34.749605 -121.761611) (xy 34.765488 -121.741184) (xy 34.773295 -121.729607) (xy 34.782872 -121.703388)
			(xy 34.78499 -121.675554) (xy 34.779489 -121.648188) (xy 34.766781 -121.623335) (xy 34.747815 -121.602854)
			(xy 34.724011 -121.588276) (xy 34.697148 -121.58069) (xy 34.683192 -121.580148) (xy 34.119058 -121.580148)
			(xy 34.105003 -121.58063) (xy 34.077974 -121.588356) (xy 34.054073 -121.603155) (xy 34.035109 -121.623907)
			(xy 34.022519 -121.649042) (xy 34.017255 -121.676656) (xy 34.019715 -121.70466) (xy 34.029715 -121.730934)
			(xy 34.037778 -121.742454) (xy 34.053489 -121.76281) (xy 34.079878 -121.806942) (xy 34.100099 -121.85422)
			(xy 34.113784 -121.903786) (xy 34.120686 -121.954742) (xy 34.12109 -121.980452) (xy 34.120604 -122.007703)
			(xy 34.112848 -122.061651) (xy 34.097493 -122.113946) (xy 34.074851 -122.163523) (xy 34.045385 -122.209373)
			(xy 34.009694 -122.250564) (xy 33.968503 -122.286255) (xy 33.922653 -122.315721) (xy 33.873076 -122.338363)
			(xy 33.820781 -122.353718) (xy 33.766833 -122.361474) (xy 33.712331 -122.361474) (xy 33.658383 -122.353718)
			(xy 33.606088 -122.338363) (xy 33.556511 -122.315721) (xy 33.510661 -122.286255) (xy 33.46947 -122.250564)
			(xy 33.433779 -122.209373) (xy 33.404313 -122.163523) (xy 33.381671 -122.113946) (xy 33.366316 -122.061651)
			(xy 33.35856 -122.007703) (xy 33.358074 -121.980452) (xy 33.358508 -121.954581) (xy 33.365504 -121.903313)
			(xy 33.379361 -121.85346) (xy 33.399825 -121.805936) (xy 33.426521 -121.761612) (xy 33.442402 -121.741184)
			(xy 33.450208 -121.729606) (xy 33.459784 -121.703386) (xy 33.461901 -121.675553) (xy 33.4564 -121.648186)
			(xy 33.443692 -121.623333) (xy 33.424728 -121.60285) (xy 33.400925 -121.588269) (xy 33.374062 -121.580681)
			(xy 33.360106 -121.580148) (xy 29.464 -121.580148) (xy 27.843734 -123.200414) (xy 29.125416 -123.200414)
			(xy 29.129487 -123.144792) (xy 29.141613 -123.090355) (xy 29.161536 -123.038264) (xy 29.188832 -122.989629)
			(xy 29.222918 -122.945486) (xy 29.263067 -122.906777) (xy 29.308425 -122.874326) (xy 29.358025 -122.848825)
			(xy 29.410809 -122.830818) (xy 29.465652 -122.820688) (xy 29.521386 -122.818651) (xy 29.576823 -122.824751)
			(xy 29.63078 -122.838857) (xy 29.682109 -122.860669) (xy 29.729715 -122.889723) (xy 29.772583 -122.925398)
			(xy 29.8098 -122.966935) (xy 29.840573 -123.013448) (xy 29.864245 -123.063945) (xy 29.880313 -123.117352)
			(xy 29.888433 -123.172528) (xy 29.888942 -123.200414) (xy 29.888433 -123.2283) (xy 29.880313 -123.283476)
			(xy 29.864245 -123.336883) (xy 29.840573 -123.38738) (xy 29.8098 -123.433893) (xy 29.772583 -123.47543)
			(xy 29.729715 -123.511105) (xy 29.682109 -123.540159) (xy 29.63078 -123.561971) (xy 29.576823 -123.576077)
			(xy 29.521386 -123.582177) (xy 29.465652 -123.58014) (xy 29.410809 -123.57001) (xy 29.358025 -123.552003)
			(xy 29.308425 -123.526502) (xy 29.263067 -123.494051) (xy 29.222918 -123.455342) (xy 29.188832 -123.411199)
			(xy 29.161536 -123.362564) (xy 29.141613 -123.310473) (xy 29.129487 -123.256036) (xy 29.125416 -123.200414)
			(xy 27.843734 -123.200414) (xy 27.554428 -123.48972) (xy 27.543734 -123.501247) (xy 27.52932 -123.529173)
			(xy 27.524057 -123.560156) (xy 27.528444 -123.591275) (xy 27.542064 -123.619596) (xy 27.551953 -123.630944)
			(xy 31.385762 -123.630944) (xy 31.389833 -123.575322) (xy 31.401959 -123.520885) (xy 31.421882 -123.468794)
			(xy 31.449178 -123.420159) (xy 31.483264 -123.376016) (xy 31.523413 -123.337307) (xy 31.568771 -123.304856)
			(xy 31.618371 -123.279355) (xy 31.671155 -123.261348) (xy 31.725998 -123.251218) (xy 31.781732 -123.249181)
			(xy 31.837169 -123.255281) (xy 31.891126 -123.269387) (xy 31.942455 -123.291199) (xy 31.990061 -123.320253)
			(xy 32.032929 -123.355928) (xy 32.070146 -123.397465) (xy 32.100919 -123.443978) (xy 32.124591 -123.494475)
			(xy 32.140659 -123.547882) (xy 32.148779 -123.603058) (xy 32.149288 -123.630944) (xy 32.148779 -123.65883)
			(xy 32.140659 -123.714006) (xy 32.124591 -123.767413) (xy 32.100919 -123.81791) (xy 32.070146 -123.864423)
			(xy 32.032929 -123.90596) (xy 32.031934 -123.906788) (xy 32.966912 -123.906788) (xy 32.970983 -123.851166)
			(xy 32.983109 -123.796729) (xy 33.003032 -123.744638) (xy 33.030328 -123.696003) (xy 33.064414 -123.65186)
			(xy 33.104563 -123.613151) (xy 33.149921 -123.5807) (xy 33.199521 -123.555199) (xy 33.252305 -123.537192)
			(xy 33.307148 -123.527062) (xy 33.362882 -123.525025) (xy 33.418319 -123.531125) (xy 33.472276 -123.545231)
			(xy 33.523605 -123.567043) (xy 33.571211 -123.596097) (xy 33.614079 -123.631772) (xy 33.651296 -123.673309)
			(xy 33.682069 -123.719822) (xy 33.705741 -123.770319) (xy 33.721809 -123.823726) (xy 33.729929 -123.878902)
			(xy 33.730118 -123.889262) (xy 33.909506 -123.889262) (xy 33.913577 -123.83364) (xy 33.925703 -123.779203)
			(xy 33.945626 -123.727112) (xy 33.972922 -123.678477) (xy 34.007008 -123.634334) (xy 34.047157 -123.595625)
			(xy 34.092515 -123.563174) (xy 34.142115 -123.537673) (xy 34.194899 -123.519666) (xy 34.249742 -123.509536)
			(xy 34.305476 -123.507499) (xy 34.360913 -123.513599) (xy 34.41487 -123.527705) (xy 34.466199 -123.549517)
			(xy 34.513805 -123.578571) (xy 34.556673 -123.614246) (xy 34.59389 -123.655783) (xy 34.624663 -123.702296)
			(xy 34.648335 -123.752793) (xy 34.664403 -123.8062) (xy 34.672523 -123.861376) (xy 34.673032 -123.889262)
			(xy 34.672523 -123.917148) (xy 34.664403 -123.972324) (xy 34.648335 -124.025731) (xy 34.624911 -124.075698)
			(xy 37.74643 -124.075698) (xy 37.750503 -124.020039) (xy 37.762638 -123.965566) (xy 37.782574 -123.91344)
			(xy 37.809888 -123.864772) (xy 37.843996 -123.8206) (xy 37.884173 -123.781865) (xy 37.929561 -123.749393)
			(xy 37.979193 -123.723875) (xy 38.032013 -123.705856) (xy 38.086892 -123.695719) (xy 38.142663 -123.693681)
			(xy 38.198137 -123.699784) (xy 38.25213 -123.7139) (xy 38.303493 -123.735727) (xy 38.351131 -123.7648)
			(xy 38.394027 -123.800499) (xy 38.431269 -123.842063) (xy 38.462063 -123.888607) (xy 38.485751 -123.939138)
			(xy 38.501829 -123.99258) (xy 38.509955 -124.047794) (xy 38.510464 -124.075698) (xy 38.509955 -124.103602)
			(xy 38.501829 -124.158816) (xy 38.485751 -124.212258) (xy 38.462063 -124.262789) (xy 38.431269 -124.309333)
			(xy 38.394027 -124.350897) (xy 38.351131 -124.386596) (xy 38.303493 -124.415669) (xy 38.25213 -124.437496)
			(xy 38.198137 -124.451612) (xy 38.142663 -124.457715) (xy 38.086892 -124.455677) (xy 38.032013 -124.44554)
			(xy 37.979193 -124.427521) (xy 37.929561 -124.402003) (xy 37.884173 -124.369531) (xy 37.843996 -124.330796)
			(xy 37.809888 -124.286624) (xy 37.782574 -124.237956) (xy 37.762638 -124.18583) (xy 37.750503 -124.131357)
			(xy 37.74643 -124.075698) (xy 34.624911 -124.075698) (xy 34.624663 -124.076228) (xy 34.59389 -124.122741)
			(xy 34.556673 -124.164278) (xy 34.513805 -124.199953) (xy 34.466199 -124.229007) (xy 34.41487 -124.250819)
			(xy 34.360913 -124.264925) (xy 34.305476 -124.271025) (xy 34.249742 -124.268988) (xy 34.194899 -124.258858)
			(xy 34.142115 -124.240851) (xy 34.092515 -124.21535) (xy 34.047157 -124.182899) (xy 34.007008 -124.14419)
			(xy 33.972922 -124.100047) (xy 33.945626 -124.051412) (xy 33.925703 -123.999321) (xy 33.913577 -123.944884)
			(xy 33.909506 -123.889262) (xy 33.730118 -123.889262) (xy 33.730438 -123.906788) (xy 33.729929 -123.934674)
			(xy 33.721809 -123.98985) (xy 33.705741 -124.043257) (xy 33.682069 -124.093754) (xy 33.651296 -124.140267)
			(xy 33.614079 -124.181804) (xy 33.571211 -124.217479) (xy 33.523605 -124.246533) (xy 33.472276 -124.268345)
			(xy 33.418319 -124.282451) (xy 33.362882 -124.288551) (xy 33.307148 -124.286514) (xy 33.252305 -124.276384)
			(xy 33.199521 -124.258377) (xy 33.149921 -124.232876) (xy 33.104563 -124.200425) (xy 33.064414 -124.161716)
			(xy 33.030328 -124.117573) (xy 33.003032 -124.068938) (xy 32.983109 -124.016847) (xy 32.970983 -123.96241)
			(xy 32.966912 -123.906788) (xy 32.031934 -123.906788) (xy 31.990061 -123.941635) (xy 31.942455 -123.970689)
			(xy 31.891126 -123.992501) (xy 31.837169 -124.006607) (xy 31.781732 -124.012707) (xy 31.725998 -124.01067)
			(xy 31.671155 -124.00054) (xy 31.618371 -123.982533) (xy 31.568771 -123.957032) (xy 31.523413 -123.924581)
			(xy 31.483264 -123.885872) (xy 31.449178 -123.841729) (xy 31.421882 -123.793094) (xy 31.401959 -123.741003)
			(xy 31.389833 -123.686566) (xy 31.385762 -123.630944) (xy 27.551953 -123.630944) (xy 27.552396 -123.631452)
			(xy 27.573503 -123.653101) (xy 27.60929 -123.701831) (xy 27.636946 -123.755594) (xy 27.655778 -123.813046)
			(xy 27.665315 -123.872748) (xy 27.665934 -123.902978) (xy 27.66545 -123.930231) (xy 27.657696 -123.984182)
			(xy 27.642343 -124.036481) (xy 27.619703 -124.086063) (xy 27.590238 -124.131918) (xy 27.554547 -124.173113)
			(xy 27.513356 -124.208809) (xy 27.467505 -124.23828) (xy 27.417926 -124.260926) (xy 27.365629 -124.276286)
			(xy 27.311679 -124.284046) (xy 27.284426 -124.284486) (xy 27.254194 -124.28391) (xy 27.194486 -124.274374)
			(xy 27.13703 -124.255536) (xy 27.083267 -124.227869) (xy 27.034543 -124.192064) (xy 27.0129 -124.170948)
			(xy 27.001077 -124.160574) (xy 26.972749 -124.146942) (xy 26.941618 -124.14256) (xy 26.910628 -124.147842)
			(xy 26.882707 -124.162289) (xy 26.871168 -124.17298) (xy 26.801572 -124.242576) (xy 26.816812 -124.370592)
			(xy 26.837894 -124.383546) (xy 26.861358 -124.398535) (xy 26.904082 -124.434236) (xy 26.941167 -124.475764)
			(xy 26.971829 -124.522238) (xy 26.995415 -124.572672) (xy 27.011427 -124.625997) (xy 27.019525 -124.681082)
			(xy 27.020012 -124.70892) (xy 27.019524 -124.73619) (xy 27.011761 -124.790174) (xy 26.996394 -124.842504)
			(xy 26.973737 -124.892115) (xy 26.952883 -124.924566) (xy 31.371284 -124.924566) (xy 31.375355 -124.868944)
			(xy 31.387481 -124.814507) (xy 31.407404 -124.762416) (xy 31.4347 -124.713781) (xy 31.468786 -124.669638)
			(xy 31.508935 -124.630929) (xy 31.554293 -124.598478) (xy 31.603893 -124.572977) (xy 31.656677 -124.55497)
			(xy 31.71152 -124.54484) (xy 31.767254 -124.542803) (xy 31.822691 -124.548903) (xy 31.876648 -124.563009)
			(xy 31.927977 -124.584821) (xy 31.975583 -124.613875) (xy 32.018451 -124.64955) (xy 32.055668 -124.691087)
			(xy 32.086441 -124.7376) (xy 32.110113 -124.788097) (xy 32.126181 -124.841504) (xy 32.134301 -124.89668)
			(xy 32.13481 -124.924566) (xy 32.134301 -124.952452) (xy 32.126181 -125.007628) (xy 32.110113 -125.061035)
			(xy 32.086441 -125.111532) (xy 32.055668 -125.158045) (xy 32.018451 -125.199582) (xy 31.975583 -125.235257)
			(xy 31.927977 -125.264311) (xy 31.876648 -125.286123) (xy 31.822691 -125.300229) (xy 31.767254 -125.306329)
			(xy 31.71152 -125.304292) (xy 31.656677 -125.294162) (xy 31.603893 -125.276155) (xy 31.554293 -125.250654)
			(xy 31.508935 -125.218203) (xy 31.468786 -125.179494) (xy 31.4347 -125.135351) (xy 31.407404 -125.086716)
			(xy 31.387481 -125.034625) (xy 31.375355 -124.980188) (xy 31.371284 -124.924566) (xy 26.952883 -124.924566)
			(xy 26.944252 -124.937997) (xy 26.908537 -124.979216) (xy 26.867321 -125.014934) (xy 26.821441 -125.044423)
			(xy 26.771832 -125.067083) (xy 26.719503 -125.082454) (xy 26.66552 -125.090222) (xy 26.63825 -125.090682)
			(xy 26.61041 -125.090181) (xy 26.555321 -125.082098) (xy 26.50199 -125.066097) (xy 26.451551 -125.042516)
			(xy 26.405073 -125.011858) (xy 26.363542 -124.974771) (xy 26.327841 -124.932044) (xy 26.312876 -124.908564)
			(xy 26.299922 -124.887482) (xy 26.171906 -124.872242) (xy 25.089866 -125.954282) (xy 31.145478 -125.954282)
			(xy 31.149549 -125.89866) (xy 31.161675 -125.844223) (xy 31.181598 -125.792132) (xy 31.208894 -125.743497)
			(xy 31.24298 -125.699354) (xy 31.283129 -125.660645) (xy 31.328487 -125.628194) (xy 31.378087 -125.602693)
			(xy 31.430871 -125.584686) (xy 31.485714 -125.574556) (xy 31.541448 -125.572519) (xy 31.596885 -125.578619)
			(xy 31.650842 -125.592725) (xy 31.702171 -125.614537) (xy 31.749777 -125.643591) (xy 31.792645 -125.679266)
			(xy 31.829862 -125.720803) (xy 31.860635 -125.767316) (xy 31.884307 -125.817813) (xy 31.900375 -125.87122)
			(xy 31.908495 -125.926396) (xy 31.909004 -125.954282) (xy 31.908495 -125.982168) (xy 31.900375 -126.037344)
			(xy 31.893881 -126.05893) (xy 33.07918 -126.05893) (xy 33.083251 -126.003308) (xy 33.095377 -125.948871)
			(xy 33.1153 -125.89678) (xy 33.142596 -125.848145) (xy 33.176682 -125.804002) (xy 33.216831 -125.765293)
			(xy 33.262189 -125.732842) (xy 33.311789 -125.707341) (xy 33.364573 -125.689334) (xy 33.419416 -125.679204)
			(xy 33.47515 -125.677167) (xy 33.530587 -125.683267) (xy 33.584544 -125.697373) (xy 33.635873 -125.719185)
			(xy 33.683479 -125.748239) (xy 33.726347 -125.783914) (xy 33.763564 -125.825451) (xy 33.794337 -125.871964)
			(xy 33.818009 -125.922461) (xy 33.834077 -125.975868) (xy 33.842197 -126.031044) (xy 33.842706 -126.05893)
			(xy 33.842197 -126.086816) (xy 33.834077 -126.141992) (xy 33.818009 -126.195399) (xy 33.794337 -126.245896)
			(xy 33.784437 -126.26086) (xy 34.41141 -126.26086) (xy 34.415481 -126.205238) (xy 34.427607 -126.150801)
			(xy 34.44753 -126.09871) (xy 34.474826 -126.050075) (xy 34.508912 -126.005932) (xy 34.549061 -125.967223)
			(xy 34.594419 -125.934772) (xy 34.644019 -125.909271) (xy 34.696803 -125.891264) (xy 34.751646 -125.881134)
			(xy 34.80738 -125.879097) (xy 34.862817 -125.885197) (xy 34.916774 -125.899303) (xy 34.968103 -125.921115)
			(xy 35.015709 -125.950169) (xy 35.058577 -125.985844) (xy 35.095794 -126.027381) (xy 35.126567 -126.073894)
			(xy 35.150239 -126.124391) (xy 35.166307 -126.177798) (xy 35.174427 -126.232974) (xy 35.174936 -126.26086)
			(xy 35.174427 -126.288746) (xy 35.166307 -126.343922) (xy 35.150239 -126.397329) (xy 35.126567 -126.447826)
			(xy 35.095794 -126.494339) (xy 35.058577 -126.535876) (xy 35.015709 -126.571551) (xy 34.968103 -126.600605)
			(xy 34.916774 -126.622417) (xy 34.862817 -126.636523) (xy 34.80738 -126.642623) (xy 34.751646 -126.640586)
			(xy 34.696803 -126.630456) (xy 34.644019 -126.612449) (xy 34.594419 -126.586948) (xy 34.549061 -126.554497)
			(xy 34.508912 -126.515788) (xy 34.474826 -126.471645) (xy 34.44753 -126.42301) (xy 34.427607 -126.370919)
			(xy 34.415481 -126.316482) (xy 34.41141 -126.26086) (xy 33.784437 -126.26086) (xy 33.763564 -126.292409)
			(xy 33.726347 -126.333946) (xy 33.683479 -126.369621) (xy 33.635873 -126.398675) (xy 33.584544 -126.420487)
			(xy 33.530587 -126.434593) (xy 33.47515 -126.440693) (xy 33.419416 -126.438656) (xy 33.364573 -126.428526)
			(xy 33.311789 -126.410519) (xy 33.262189 -126.385018) (xy 33.216831 -126.352567) (xy 33.176682 -126.313858)
			(xy 33.142596 -126.269715) (xy 33.1153 -126.22108) (xy 33.095377 -126.168989) (xy 33.083251 -126.114552)
			(xy 33.07918 -126.05893) (xy 31.893881 -126.05893) (xy 31.884307 -126.090751) (xy 31.860635 -126.141248)
			(xy 31.829862 -126.187761) (xy 31.792645 -126.229298) (xy 31.749777 -126.264973) (xy 31.702171 -126.294027)
			(xy 31.650842 -126.315839) (xy 31.596885 -126.329945) (xy 31.541448 -126.336045) (xy 31.485714 -126.334008)
			(xy 31.430871 -126.323878) (xy 31.378087 -126.305871) (xy 31.328487 -126.28037) (xy 31.283129 -126.247919)
			(xy 31.24298 -126.20921) (xy 31.208894 -126.165067) (xy 31.181598 -126.116432) (xy 31.161675 -126.064341)
			(xy 31.149549 -126.009904) (xy 31.145478 -125.954282) (xy 25.089866 -125.954282) (xy 24.483314 -126.560834)
			(xy 27.732988 -126.560834) (xy 27.737059 -126.505212) (xy 27.749185 -126.450775) (xy 27.769108 -126.398684)
			(xy 27.796404 -126.350049) (xy 27.83049 -126.305906) (xy 27.870639 -126.267197) (xy 27.915997 -126.234746)
			(xy 27.965597 -126.209245) (xy 28.018381 -126.191238) (xy 28.073224 -126.181108) (xy 28.128958 -126.179071)
			(xy 28.184395 -126.185171) (xy 28.238352 -126.199277) (xy 28.289681 -126.221089) (xy 28.337287 -126.250143)
			(xy 28.380155 -126.285818) (xy 28.417372 -126.327355) (xy 28.448145 -126.373868) (xy 28.468635 -126.417578)
			(xy 29.186376 -126.417578) (xy 29.190447 -126.361956) (xy 29.202573 -126.307519) (xy 29.222496 -126.255428)
			(xy 29.249792 -126.206793) (xy 29.283878 -126.16265) (xy 29.324027 -126.123941) (xy 29.369385 -126.09149)
			(xy 29.418985 -126.065989) (xy 29.471769 -126.047982) (xy 29.526612 -126.037852) (xy 29.582346 -126.035815)
			(xy 29.637783 -126.041915) (xy 29.69174 -126.056021) (xy 29.743069 -126.077833) (xy 29.790675 -126.106887)
			(xy 29.833543 -126.142562) (xy 29.87076 -126.184099) (xy 29.901533 -126.230612) (xy 29.925205 -126.281109)
			(xy 29.941273 -126.334516) (xy 29.949393 -126.389692) (xy 29.949902 -126.417578) (xy 29.949393 -126.445464)
			(xy 29.941273 -126.50064) (xy 29.925205 -126.554047) (xy 29.901533 -126.604544) (xy 29.87076 -126.651057)
			(xy 29.833543 -126.692594) (xy 29.827359 -126.69774) (xy 35.487862 -126.69774) (xy 35.491933 -126.642118)
			(xy 35.504059 -126.587681) (xy 35.523982 -126.53559) (xy 35.551278 -126.486955) (xy 35.585364 -126.442812)
			(xy 35.625513 -126.404103) (xy 35.670871 -126.371652) (xy 35.720471 -126.346151) (xy 35.773255 -126.328144)
			(xy 35.828098 -126.318014) (xy 35.883832 -126.315977) (xy 35.939269 -126.322077) (xy 35.993226 -126.336183)
			(xy 36.044555 -126.357995) (xy 36.092161 -126.387049) (xy 36.135029 -126.422724) (xy 36.172246 -126.464261)
			(xy 36.203019 -126.510774) (xy 36.226691 -126.561271) (xy 36.242759 -126.614678) (xy 36.250879 -126.669854)
			(xy 36.251388 -126.69774) (xy 36.250879 -126.725626) (xy 36.242759 -126.780802) (xy 36.226691 -126.834209)
			(xy 36.203019 -126.884706) (xy 36.172246 -126.931219) (xy 36.135029 -126.972756) (xy 36.092161 -127.008431)
			(xy 36.044555 -127.037485) (xy 35.993226 -127.059297) (xy 35.939269 -127.073403) (xy 35.883832 -127.079503)
			(xy 35.828098 -127.077466) (xy 35.773255 -127.067336) (xy 35.720471 -127.049329) (xy 35.670871 -127.023828)
			(xy 35.625513 -126.991377) (xy 35.585364 -126.952668) (xy 35.551278 -126.908525) (xy 35.523982 -126.85989)
			(xy 35.504059 -126.807799) (xy 35.491933 -126.753362) (xy 35.487862 -126.69774) (xy 29.827359 -126.69774)
			(xy 29.790675 -126.728269) (xy 29.743069 -126.757323) (xy 29.69174 -126.779135) (xy 29.637783 -126.793241)
			(xy 29.582346 -126.799341) (xy 29.526612 -126.797304) (xy 29.471769 -126.787174) (xy 29.418985 -126.769167)
			(xy 29.369385 -126.743666) (xy 29.324027 -126.711215) (xy 29.283878 -126.672506) (xy 29.249792 -126.628363)
			(xy 29.222496 -126.579728) (xy 29.202573 -126.527637) (xy 29.190447 -126.4732) (xy 29.186376 -126.417578)
			(xy 28.468635 -126.417578) (xy 28.471817 -126.424365) (xy 28.487885 -126.477772) (xy 28.496005 -126.532948)
			(xy 28.496514 -126.560834) (xy 28.496005 -126.58872) (xy 28.487885 -126.643896) (xy 28.471817 -126.697303)
			(xy 28.448145 -126.7478) (xy 28.417372 -126.794313) (xy 28.380155 -126.83585) (xy 28.337287 -126.871525)
			(xy 28.289681 -126.900579) (xy 28.238352 -126.922391) (xy 28.184395 -126.936497) (xy 28.128958 -126.942597)
			(xy 28.073224 -126.94056) (xy 28.018381 -126.93043) (xy 27.965597 -126.912423) (xy 27.915997 -126.886922)
			(xy 27.870639 -126.854471) (xy 27.83049 -126.815762) (xy 27.796404 -126.771619) (xy 27.769108 -126.722984)
			(xy 27.749185 -126.670893) (xy 27.737059 -126.616456) (xy 27.732988 -126.560834) (xy 24.483314 -126.560834)
			(xy 23.3172 -127.726948) (xy 23.3172 -127.966724) (xy 35.514532 -127.966724) (xy 35.518603 -127.911102)
			(xy 35.530729 -127.856665) (xy 35.550652 -127.804574) (xy 35.577948 -127.755939) (xy 35.612034 -127.711796)
			(xy 35.652183 -127.673087) (xy 35.697541 -127.640636) (xy 35.747141 -127.615135) (xy 35.799925 -127.597128)
			(xy 35.854768 -127.586998) (xy 35.910502 -127.584961) (xy 35.965939 -127.591061) (xy 36.019896 -127.605167)
			(xy 36.071225 -127.626979) (xy 36.118831 -127.656033) (xy 36.161699 -127.691708) (xy 36.198916 -127.733245)
			(xy 36.229689 -127.779758) (xy 36.253361 -127.830255) (xy 36.269429 -127.883662) (xy 36.277549 -127.938838)
			(xy 36.278058 -127.966724) (xy 36.277549 -127.99461) (xy 36.269429 -128.049786) (xy 36.253361 -128.103193)
			(xy 36.229689 -128.15369) (xy 36.198916 -128.200203) (xy 36.161699 -128.24174) (xy 36.118831 -128.277415)
			(xy 36.071225 -128.306469) (xy 36.019896 -128.328281) (xy 35.965939 -128.342387) (xy 35.910502 -128.348487)
			(xy 35.854768 -128.34645) (xy 35.799925 -128.33632) (xy 35.747141 -128.318313) (xy 35.697541 -128.292812)
			(xy 35.652183 -128.260361) (xy 35.612034 -128.221652) (xy 35.577948 -128.177509) (xy 35.550652 -128.128874)
			(xy 35.530729 -128.076783) (xy 35.518603 -128.022346) (xy 35.514532 -127.966724) (xy 23.3172 -127.966724)
			(xy 23.3172 -128.364996) (xy 25.623518 -128.364996) (xy 25.627589 -128.309374) (xy 25.639715 -128.254937)
			(xy 25.659638 -128.202846) (xy 25.686934 -128.154211) (xy 25.72102 -128.110068) (xy 25.761169 -128.071359)
			(xy 25.806527 -128.038908) (xy 25.856127 -128.013407) (xy 25.908911 -127.9954) (xy 25.963754 -127.98527)
			(xy 26.019488 -127.983233) (xy 26.074925 -127.989333) (xy 26.128882 -128.003439) (xy 26.180211 -128.025251)
			(xy 26.227817 -128.054305) (xy 26.270685 -128.08998) (xy 26.307902 -128.131517) (xy 26.338675 -128.17803)
			(xy 26.362347 -128.228527) (xy 26.378415 -128.281934) (xy 26.386535 -128.33711) (xy 26.387044 -128.364996)
			(xy 26.386547 -128.392219) (xy 27.67692 -128.392219) (xy 27.676924 -128.337725) (xy 27.684683 -128.283785)
			(xy 27.70004 -128.231499) (xy 27.722681 -128.18193) (xy 27.752145 -128.136088) (xy 27.787834 -128.094906)
			(xy 27.82902 -128.059221) (xy 27.874865 -128.029761) (xy 27.924436 -128.007126) (xy 27.976724 -127.991775)
			(xy 28.030665 -127.984021) (xy 28.085159 -127.984023) (xy 28.139099 -127.99178) (xy 28.191386 -128.007134)
			(xy 28.240956 -128.029773) (xy 28.286799 -128.059236) (xy 28.327983 -128.094923) (xy 28.363669 -128.136107)
			(xy 28.393131 -128.181951) (xy 28.415769 -128.231521) (xy 28.431122 -128.283809) (xy 28.438878 -128.337749)
			(xy 28.439364 -128.364996) (xy 28.439364 -128.365758) (xy 28.43888 -128.392273) (xy 28.431485 -128.444787)
			(xy 28.424632 -128.470406) (xy 28.421138 -128.484151) (xy 28.421089 -128.512502) (xy 28.428848 -128.539771)
			(xy 28.443814 -128.563849) (xy 28.464831 -128.582877) (xy 28.490274 -128.595383) (xy 28.518178 -128.600401)
			(xy 28.532328 -128.599438) (xy 28.56992 -128.59766) (xy 28.59717 -128.598159) (xy 28.651116 -128.605917)
			(xy 28.703408 -128.621274) (xy 28.752984 -128.643915) (xy 28.798832 -128.67338) (xy 28.840022 -128.70907)
			(xy 28.875713 -128.750258) (xy 28.90518 -128.796106) (xy 28.927822 -128.84568) (xy 28.94318 -128.897972)
			(xy 28.943221 -128.898257) (xy 34.774519 -128.898257) (xy 34.774519 -128.843743) (xy 34.782278 -128.789784)
			(xy 34.797637 -128.737479) (xy 34.820284 -128.687892) (xy 34.849757 -128.642033) (xy 34.885458 -128.600835)
			(xy 34.926658 -128.565138) (xy 34.97252 -128.535668) (xy 35.022109 -128.513025) (xy 35.074416 -128.497671)
			(xy 35.128375 -128.489917) (xy 35.155632 -128.489456) (xy 35.183235 -128.48994) (xy 35.237867 -128.497876)
			(xy 35.290784 -128.513608) (xy 35.340879 -128.536805) (xy 35.387106 -128.566983) (xy 35.428498 -128.603512)
			(xy 35.46419 -128.645628) (xy 35.479228 -128.66878) (xy 35.486745 -128.680134) (xy 35.506723 -128.698627)
			(xy 35.530881 -128.711177) (xy 35.557498 -128.716889) (xy 35.584678 -128.715357) (xy 35.610485 -128.70669)
			(xy 35.633079 -128.691506) (xy 35.642296 -128.68148) (xy 35.660491 -128.661057) (xy 35.701733 -128.625128)
			(xy 35.747683 -128.595458) (xy 35.7974 -128.572655) (xy 35.849864 -128.557185) (xy 35.904 -128.549366)
			(xy 35.931348 -128.548892) (xy 35.9586 -128.549333) (xy 36.01255 -128.557096) (xy 36.064845 -128.572457)
			(xy 36.114423 -128.595104) (xy 36.160273 -128.624575) (xy 36.201463 -128.660271) (xy 36.237153 -128.701466)
			(xy 36.266619 -128.747319) (xy 36.289259 -128.7969) (xy 36.304614 -128.849197) (xy 36.31237 -128.903148)
			(xy 36.312856 -128.9304) (xy 36.312354 -128.959318) (xy 36.303624 -129.01649) (xy 36.286364 -129.07169)
			(xy 36.260969 -129.123652) (xy 36.228022 -129.171186) (xy 36.188277 -129.213201) (xy 36.16579 -129.23139)
			(xy 36.154505 -129.240742) (xy 36.137427 -129.264546) (xy 36.127817 -129.292223) (xy 36.12647 -129.321489)
			(xy 36.133495 -129.349931) (xy 36.148314 -129.375205) (xy 36.158678 -129.385568) (xy 36.177306 -129.403687)
			(xy 36.210021 -129.444059) (xy 36.236951 -129.4885) (xy 36.257598 -129.536186) (xy 36.271578 -129.586234)
			(xy 36.278634 -129.637716) (xy 36.279074 -129.663698) (xy 36.278643 -129.690952) (xy 36.270885 -129.744906)
			(xy 36.255528 -129.797207) (xy 36.232883 -129.846789) (xy 36.203412 -129.892644) (xy 36.167715 -129.933837)
			(xy 36.126518 -129.969531) (xy 36.080661 -129.998998) (xy 36.031077 -130.021639) (xy 35.978775 -130.036992)
			(xy 35.92482 -130.044745) (xy 35.897566 -130.045206) (xy 35.868794 -130.044675) (xy 35.811906 -130.035999)
			(xy 35.784282 -130.027934) (xy 35.770239 -130.023972) (xy 35.741071 -130.023495) (xy 35.712955 -130.031276)
			(xy 35.688183 -130.046681) (xy 35.66877 -130.068456) (xy 35.656298 -130.094827) (xy 35.651782 -130.123647)
			(xy 35.653218 -130.13817) (xy 35.654756 -130.150495) (xy 35.656405 -130.17528) (xy 35.65652 -130.1877)
			(xy 35.656045 -130.214953) (xy 35.648288 -130.268904) (xy 35.632931 -130.321202) (xy 35.610289 -130.370783)
			(xy 35.58082 -130.416636) (xy 35.545126 -130.457829) (xy 35.503933 -130.493523) (xy 35.458079 -130.52299)
			(xy 35.408499 -130.545633) (xy 35.3562 -130.560988) (xy 35.302249 -130.568745) (xy 35.247743 -130.568744)
			(xy 35.193792 -130.560987) (xy 35.141494 -130.54563) (xy 35.091914 -130.522987) (xy 35.046061 -130.493518)
			(xy 35.004868 -130.457823) (xy 34.969175 -130.41663) (xy 34.939708 -130.370776) (xy 34.917066 -130.321195)
			(xy 34.901711 -130.268896) (xy 34.893955 -130.214945) (xy 34.893956 -130.160439) (xy 34.901714 -130.106488)
			(xy 34.917071 -130.05419) (xy 34.939715 -130.00461) (xy 34.969185 -129.958757) (xy 35.00488 -129.917565)
			(xy 35.046073 -129.881873) (xy 35.091928 -129.852406) (xy 35.141509 -129.829764) (xy 35.193807 -129.81441)
			(xy 35.247759 -129.806654) (xy 35.275012 -129.806192) (xy 35.303784 -129.806728) (xy 35.360672 -129.815401)
			(xy 35.388296 -129.823464) (xy 35.402345 -129.827403) (xy 35.431511 -129.827886) (xy 35.459625 -129.820109)
			(xy 35.484397 -129.804708) (xy 35.50381 -129.782936) (xy 35.516281 -129.756567) (xy 35.520797 -129.72775)
			(xy 35.51936 -129.713228) (xy 35.517822 -129.700903) (xy 35.516173 -129.676118) (xy 35.516058 -129.663698)
			(xy 35.516553 -129.63478) (xy 35.525284 -129.577607) (xy 35.542545 -129.522406) (xy 35.567941 -129.470444)
			(xy 35.600889 -129.422911) (xy 35.640636 -129.380897) (xy 35.663124 -129.362708) (xy 35.67441 -129.353358)
			(xy 35.691486 -129.329553) (xy 35.701094 -129.301876) (xy 35.702441 -129.27261) (xy 35.695417 -129.244168)
			(xy 35.680599 -129.218894) (xy 35.670236 -129.20853) (xy 35.65251 -129.191376) (xy 35.62117 -129.153283)
			(xy 35.607752 -129.132584) (xy 35.600137 -129.121302) (xy 35.580177 -129.102818) (xy 35.556041 -129.09027)
			(xy 35.529445 -129.084551) (xy 35.502284 -129.086069) (xy 35.47649 -129.094714) (xy 35.453901 -129.109872)
			(xy 35.444684 -129.119884) (xy 35.426492 -129.14031) (xy 35.38525 -129.176239) (xy 35.339299 -129.20591)
			(xy 35.289582 -129.228714) (xy 35.237117 -129.244183) (xy 35.182981 -129.251999) (xy 35.155632 -129.252472)
			(xy 35.128375 -129.252083) (xy 35.074416 -129.244329) (xy 35.022109 -129.228975) (xy 34.97252 -129.206332)
			(xy 34.926658 -129.176862) (xy 34.885458 -129.141165) (xy 34.849757 -129.099967) (xy 34.820284 -129.054108)
			(xy 34.797637 -129.004521) (xy 34.782278 -128.952216) (xy 34.774519 -128.898257) (xy 28.943221 -128.898257)
			(xy 28.95094 -128.951918) (xy 28.951428 -128.979168) (xy 28.950983 -129.006005) (xy 28.943447 -129.059147)
			(xy 28.928534 -129.110708) (xy 28.906538 -129.159668) (xy 28.877895 -129.20506) (xy 28.843169 -129.245987)
			(xy 28.823412 -129.264156) (xy 28.812991 -129.274041) (xy 28.797685 -129.298332) (xy 28.789743 -129.325924)
			(xy 28.789794 -129.354636) (xy 28.797834 -129.382199) (xy 28.813226 -129.406436) (xy 28.823666 -129.416302)
			(xy 28.843522 -129.434453) (xy 28.878376 -129.475433) (xy 28.907127 -129.520903) (xy 28.929204 -129.569962)
			(xy 28.94417 -129.621636) (xy 28.951729 -129.674899) (xy 28.95219 -129.701798) (xy 28.951704 -129.729049)
			(xy 28.943948 -129.782997) (xy 28.928593 -129.835292) (xy 28.905951 -129.884869) (xy 28.876485 -129.930719)
			(xy 28.840794 -129.97191) (xy 28.799603 -130.007601) (xy 28.753753 -130.037067) (xy 28.704176 -130.059709)
			(xy 28.651881 -130.075064) (xy 28.597933 -130.08282) (xy 28.543431 -130.08282) (xy 28.489483 -130.075064)
			(xy 28.437188 -130.059709) (xy 28.387611 -130.037067) (xy 28.341761 -130.007601) (xy 28.30057 -129.97191)
			(xy 28.264879 -129.930719) (xy 28.235413 -129.884869) (xy 28.212771 -129.835292) (xy 28.197416 -129.782997)
			(xy 28.18966 -129.729049) (xy 28.189174 -129.701798) (xy 28.189663 -129.674963) (xy 28.19719 -129.621822)
			(xy 28.212094 -129.570262) (xy 28.234082 -129.521302) (xy 28.262718 -129.475909) (xy 28.297436 -129.43498)
			(xy 28.31719 -129.41681) (xy 28.327545 -129.406861) (xy 28.342854 -129.382587) (xy 28.350803 -129.355013)
			(xy 28.350764 -129.326315) (xy 28.342741 -129.298762) (xy 28.327366 -129.27453) (xy 28.316936 -129.264664)
			(xy 28.297112 -129.246479) (xy 28.262256 -129.205507) (xy 28.233501 -129.160043) (xy 28.211418 -129.110991)
			(xy 28.196444 -129.059324) (xy 28.188878 -129.006065) (xy 28.188412 -128.979168) (xy 28.188412 -128.978406)
			(xy 28.18891 -128.951891) (xy 28.196296 -128.899378) (xy 28.203144 -128.873758) (xy 28.206593 -128.860001)
			(xy 28.206656 -128.831653) (xy 28.198909 -128.804385) (xy 28.183951 -128.780305) (xy 28.162938 -128.761277)
			(xy 28.137498 -128.748772) (xy 28.109597 -128.743759) (xy 28.095448 -128.744726) (xy 28.057856 -128.746504)
			(xy 28.030609 -128.745975) (xy 27.97667 -128.738213) (xy 27.924384 -128.722855) (xy 27.874816 -128.700212)
			(xy 27.828975 -128.670745) (xy 27.787794 -128.635055) (xy 27.752112 -128.593867) (xy 27.722654 -128.548021)
			(xy 27.70002 -128.498449) (xy 27.684671 -128.44616) (xy 27.67692 -128.392219) (xy 26.386547 -128.392219)
			(xy 26.386535 -128.392882) (xy 26.378415 -128.448058) (xy 26.362347 -128.501465) (xy 26.338675 -128.551962)
			(xy 26.307902 -128.598475) (xy 26.270685 -128.640012) (xy 26.227817 -128.675687) (xy 26.180211 -128.704741)
			(xy 26.128882 -128.726553) (xy 26.074925 -128.740659) (xy 26.019488 -128.746759) (xy 25.963754 -128.744722)
			(xy 25.908911 -128.734592) (xy 25.856127 -128.716585) (xy 25.806527 -128.691084) (xy 25.761169 -128.658633)
			(xy 25.72102 -128.619924) (xy 25.686934 -128.575781) (xy 25.659638 -128.527146) (xy 25.639715 -128.475055)
			(xy 25.627589 -128.420618) (xy 25.623518 -128.364996) (xy 23.3172 -128.364996) (xy 23.3172 -130.936663)
			(xy 24.961212 -130.936663) (xy 24.968967 -130.882704) (xy 24.984323 -130.830398) (xy 25.006967 -130.780809)
			(xy 25.036438 -130.734948) (xy 25.072136 -130.693749) (xy 25.113334 -130.658049) (xy 25.159193 -130.628576)
			(xy 25.208781 -130.60593) (xy 25.261086 -130.590571) (xy 25.315045 -130.582813) (xy 25.369559 -130.582813)
			(xy 25.423518 -130.590572) (xy 25.475823 -130.605931) (xy 25.52541 -130.628578) (xy 25.571269 -130.658051)
			(xy 25.612467 -130.693752) (xy 25.648164 -130.734952) (xy 25.677635 -130.780813) (xy 25.700278 -130.830401)
			(xy 25.715093 -130.880866) (xy 27.573222 -130.880866) (xy 27.577293 -130.825244) (xy 27.589419 -130.770807)
			(xy 27.609342 -130.718716) (xy 27.636638 -130.670081) (xy 27.670724 -130.625938) (xy 27.710873 -130.587229)
			(xy 27.756231 -130.554778) (xy 27.805831 -130.529277) (xy 27.858615 -130.51127) (xy 27.913458 -130.50114)
			(xy 27.969192 -130.499103) (xy 28.024629 -130.505203) (xy 28.078586 -130.519309) (xy 28.129915 -130.541121)
			(xy 28.177521 -130.570175) (xy 28.220389 -130.60585) (xy 28.257606 -130.647387) (xy 28.288379 -130.6939)
			(xy 28.312051 -130.744397) (xy 28.328119 -130.797804) (xy 28.336239 -130.85298) (xy 28.336748 -130.880866)
			(xy 28.336239 -130.908752) (xy 28.328119 -130.963928) (xy 28.312051 -131.017335) (xy 28.288379 -131.067832)
			(xy 28.257606 -131.114345) (xy 28.220389 -131.155882) (xy 28.192535 -131.179062) (xy 34.962844 -131.179062)
			(xy 34.966915 -131.12344) (xy 34.979041 -131.069003) (xy 34.998964 -131.016912) (xy 35.02626 -130.968277)
			(xy 35.060346 -130.924134) (xy 35.100495 -130.885425) (xy 35.145853 -130.852974) (xy 35.195453 -130.827473)
			(xy 35.248237 -130.809466) (xy 35.30308 -130.799336) (xy 35.358814 -130.797299) (xy 35.414251 -130.803399)
			(xy 35.468208 -130.817505) (xy 35.519537 -130.839317) (xy 35.567143 -130.868371) (xy 35.610011 -130.904046)
			(xy 35.647228 -130.945583) (xy 35.678001 -130.992096) (xy 35.701673 -131.042593) (xy 35.717741 -131.096)
			(xy 35.725861 -131.151176) (xy 35.72637 -131.179062) (xy 35.725861 -131.206948) (xy 35.717741 -131.262124)
			(xy 35.701673 -131.315531) (xy 35.678001 -131.366028) (xy 35.647228 -131.412541) (xy 35.610011 -131.454078)
			(xy 35.567143 -131.489753) (xy 35.519537 -131.518807) (xy 35.468208 -131.540619) (xy 35.414251 -131.554725)
			(xy 35.358814 -131.560825) (xy 35.30308 -131.558788) (xy 35.248237 -131.548658) (xy 35.195453 -131.530651)
			(xy 35.145853 -131.50515) (xy 35.100495 -131.472699) (xy 35.060346 -131.43399) (xy 35.02626 -131.389847)
			(xy 34.998964 -131.341212) (xy 34.979041 -131.289121) (xy 34.966915 -131.234684) (xy 34.962844 -131.179062)
			(xy 28.192535 -131.179062) (xy 28.177521 -131.191557) (xy 28.129915 -131.220611) (xy 28.078586 -131.242423)
			(xy 28.024629 -131.256529) (xy 27.969192 -131.262629) (xy 27.913458 -131.260592) (xy 27.858615 -131.250462)
			(xy 27.805831 -131.232455) (xy 27.756231 -131.206954) (xy 27.710873 -131.174503) (xy 27.670724 -131.135794)
			(xy 27.636638 -131.091651) (xy 27.609342 -131.043016) (xy 27.589419 -130.990925) (xy 27.577293 -130.936488)
			(xy 27.573222 -130.880866) (xy 25.715093 -130.880866) (xy 25.715634 -130.882708) (xy 25.723389 -130.936667)
			(xy 25.72385 -130.963924) (xy 25.72318 -130.996583) (xy 25.712073 -131.060948) (xy 25.701752 -131.09194)
			(xy 25.697687 -131.10491) (xy 25.695635 -131.131995) (xy 25.700795 -131.158664) (xy 25.712802 -131.183029)
			(xy 25.730807 -131.203368) (xy 25.753536 -131.218241) (xy 25.779382 -131.226598) (xy 25.806516 -131.227846)
			(xy 25.819862 -131.22529) (xy 25.840537 -131.220891) (xy 25.882546 -131.216187) (xy 25.903682 -131.215892)
			(xy 25.930936 -131.216336) (xy 25.984891 -131.224091) (xy 26.037192 -131.239445) (xy 26.086776 -131.262087)
			(xy 26.132633 -131.291555) (xy 26.17383 -131.327249) (xy 26.209527 -131.368442) (xy 26.238999 -131.414297)
			(xy 26.261644 -131.463879) (xy 26.277003 -131.51618) (xy 26.284762 -131.570134) (xy 26.284764 -131.624642)
			(xy 26.277008 -131.678597) (xy 26.261653 -131.730898) (xy 26.23901 -131.780482) (xy 26.209542 -131.826338)
			(xy 26.173847 -131.867534) (xy 26.132653 -131.903231) (xy 26.086798 -131.932702) (xy 26.037215 -131.955346)
			(xy 25.984914 -131.970704) (xy 25.93096 -131.978463) (xy 25.876452 -131.978464) (xy 25.822497 -131.970707)
			(xy 25.770196 -131.955351) (xy 25.720613 -131.932707) (xy 25.674757 -131.903238) (xy 25.633562 -131.867543)
			(xy 25.597865 -131.826348) (xy 25.568396 -131.780492) (xy 25.545751 -131.730909) (xy 25.530394 -131.678608)
			(xy 25.522637 -131.624654) (xy 25.522174 -131.5974) (xy 25.522829 -131.564741) (xy 25.533946 -131.500375)
			(xy 25.544272 -131.469384) (xy 25.548512 -131.456463) (xy 25.550554 -131.429351) (xy 25.545376 -131.40266)
			(xy 25.533345 -131.378277) (xy 25.515313 -131.357929) (xy 25.492555 -131.343053) (xy 25.46668 -131.334703)
			(xy 25.439519 -131.333468) (xy 25.426162 -131.336034) (xy 25.405486 -131.340428) (xy 25.363478 -131.345136)
			(xy 25.342342 -131.345432) (xy 25.315085 -131.34499) (xy 25.261125 -131.337238) (xy 25.208818 -131.321884)
			(xy 25.159229 -131.299243) (xy 25.113366 -131.269775) (xy 25.072164 -131.23408) (xy 25.036462 -131.192884)
			(xy 25.006986 -131.147026) (xy 24.984337 -131.09744) (xy 24.968976 -131.045135) (xy 24.961214 -130.991177)
			(xy 24.961212 -130.936663) (xy 23.3172 -130.936663) (xy 23.3172 -132.264658) (xy 26.43708 -132.264658)
			(xy 26.441151 -132.209036) (xy 26.453277 -132.154599) (xy 26.4732 -132.102508) (xy 26.500496 -132.053873)
			(xy 26.534582 -132.00973) (xy 26.574731 -131.971021) (xy 26.620089 -131.93857) (xy 26.669689 -131.913069)
			(xy 26.722473 -131.895062) (xy 26.777316 -131.884932) (xy 26.83305 -131.882895) (xy 26.888487 -131.888995)
			(xy 26.942444 -131.903101) (xy 26.993773 -131.924913) (xy 27.041379 -131.953967) (xy 27.084247 -131.989642)
			(xy 27.121464 -132.031179) (xy 27.152237 -132.077692) (xy 27.175909 -132.128189) (xy 27.191977 -132.181596)
			(xy 27.200097 -132.236772) (xy 27.200606 -132.264658) (xy 27.200097 -132.292544) (xy 27.191977 -132.34772)
			(xy 27.175909 -132.401127) (xy 27.152237 -132.451624) (xy 27.121464 -132.498137) (xy 27.084247 -132.539674)
			(xy 27.041379 -132.575349) (xy 26.993773 -132.604403) (xy 26.942444 -132.626215) (xy 26.888487 -132.640321)
			(xy 26.83305 -132.646421) (xy 26.777316 -132.644384) (xy 26.722473 -132.634254) (xy 26.669689 -132.616247)
			(xy 26.620089 -132.590746) (xy 26.574731 -132.558295) (xy 26.534582 -132.519586) (xy 26.500496 -132.475443)
			(xy 26.4732 -132.426808) (xy 26.453277 -132.374717) (xy 26.441151 -132.32028) (xy 26.43708 -132.264658)
			(xy 23.3172 -132.264658) (xy 23.3172 -133.6802) (xy 24.987502 -133.6802) (xy 24.991573 -133.624578)
			(xy 25.003699 -133.570141) (xy 25.023622 -133.51805) (xy 25.050918 -133.469415) (xy 25.085004 -133.425272)
			(xy 25.125153 -133.386563) (xy 25.170511 -133.354112) (xy 25.220111 -133.328611) (xy 25.272895 -133.310604)
			(xy 25.327738 -133.300474) (xy 25.383472 -133.298437) (xy 25.438909 -133.304537) (xy 25.492866 -133.318643)
			(xy 25.544195 -133.340455) (xy 25.591801 -133.369509) (xy 25.634669 -133.405184) (xy 25.671886 -133.446721)
			(xy 25.702659 -133.493234) (xy 25.726331 -133.543731) (xy 25.742399 -133.597138) (xy 25.750519 -133.652314)
			(xy 25.751028 -133.6802) (xy 25.750519 -133.708086) (xy 25.742399 -133.763262) (xy 25.726331 -133.816669)
			(xy 25.702659 -133.867166) (xy 25.671886 -133.913679) (xy 25.634669 -133.955216) (xy 25.591801 -133.990891)
			(xy 25.544195 -134.019945) (xy 25.492866 -134.041757) (xy 25.438909 -134.055863) (xy 25.383472 -134.061963)
			(xy 25.327738 -134.059926) (xy 25.272895 -134.049796) (xy 25.220111 -134.031789) (xy 25.170511 -134.006288)
			(xy 25.125153 -133.973837) (xy 25.085004 -133.935128) (xy 25.050918 -133.890985) (xy 25.023622 -133.84235)
			(xy 25.003699 -133.790259) (xy 24.991573 -133.735822) (xy 24.987502 -133.6802) (xy 23.3172 -133.6802)
			(xy 23.3172 -147.538948) (xy 23.0632 -147.792948) (xy 22.953726 -147.792948) (xy 22.78761 -147.959064)
			(xy 22.7838 -147.97151) (xy 22.781768 -147.978114) (xy 22.773355 -148.003512) (xy 22.75128 -148.052249)
			(xy 22.723512 -148.097982) (xy 22.690454 -148.140051) (xy 22.671786 -148.159216) (xy 18.940526 -151.89073)
			(xy 18.940526 -152.743408) (xy 18.941053 -152.758082) (xy 18.949468 -152.786201) (xy 18.965518 -152.810775)
			(xy 18.987882 -152.829784) (xy 19.014721 -152.841664) (xy 19.043828 -152.845438) (xy 19.07281 -152.840796)
			(xy 19.099283 -152.82812) (xy 19.110452 -152.818592) (xy 27.305508 -144.623536) (xy 27.305508 -135.987536)
			(xy 27.305254 -133.522974) (xy 27.305867 -133.497992) (xy 27.315613 -133.448986) (xy 27.334726 -133.402821)
			(xy 27.362472 -133.361268) (xy 27.379676 -133.343142) (xy 28.118054 -132.604764) (xy 28.136165 -132.587544)
			(xy 28.177726 -132.559809) (xy 28.223896 -132.540706) (xy 28.272903 -132.530966) (xy 28.297886 -132.530342)
			(xy 28.94203 -132.530342) (xy 28.967012 -132.530956) (xy 29.016018 -132.540702) (xy 29.062183 -132.559814)
			(xy 29.103736 -132.587559) (xy 29.121862 -132.604764) (xy 29.350208 -132.83311) (xy 29.367433 -132.851219)
			(xy 29.395178 -132.892778) (xy 29.414292 -132.938948) (xy 29.424041 -132.987957) (xy 29.42463 -133.012942)
			(xy 29.424376 -133.18236) (xy 29.424376 -133.775958) (xy 29.468064 -133.782308) (xy 29.494003 -133.786646)
			(xy 29.544449 -133.801519) (xy 29.592375 -133.823177) (xy 29.636873 -133.851208) (xy 29.677103 -133.885084)
			(xy 29.712301 -133.924161) (xy 29.741801 -133.9677) (xy 29.753814 -133.991096) (xy 29.755338 -133.994652)
			(xy 29.762752 -134.007312) (xy 29.783474 -134.028063) (xy 29.809234 -134.042077) (xy 29.837914 -134.048201)
			(xy 29.867151 -134.04593) (xy 29.894541 -134.035453) (xy 29.906468 -134.02691) (xy 29.931544 -134.008575)
			(xy 29.986401 -133.979436) (xy 30.045255 -133.959573) (xy 30.10655 -133.949508) (xy 30.137608 -133.948932)
			(xy 30.164856 -133.949419) (xy 30.218797 -133.957175) (xy 30.271085 -133.97253) (xy 30.320656 -133.995169)
			(xy 30.366501 -134.024632) (xy 30.407686 -134.06032) (xy 30.443373 -134.101506) (xy 30.472835 -134.147351)
			(xy 30.495473 -134.196922) (xy 30.510826 -134.249211) (xy 30.518582 -134.303152) (xy 30.518582 -134.357648)
			(xy 30.510826 -134.411589) (xy 30.495473 -134.463878) (xy 30.472835 -134.513449) (xy 30.443373 -134.559294)
			(xy 30.407686 -134.60048) (xy 30.366501 -134.636168) (xy 30.320656 -134.665631) (xy 30.271085 -134.68827)
			(xy 30.218797 -134.703625) (xy 30.164856 -134.711381) (xy 30.137608 -134.711948) (xy 30.137608 -134.712202)
			(xy 30.110754 -134.711745) (xy 30.057575 -134.704218) (xy 30.005977 -134.689309) (xy 29.956978 -134.667315)
			(xy 29.911547 -134.63867) (xy 29.870579 -134.603938) (xy 29.834885 -134.563807) (xy 29.805168 -134.519068)
			(xy 29.793184 -134.495032) (xy 29.785721 -134.4825) (xy 29.76499 -134.461997) (xy 29.739314 -134.448181)
			(xy 29.710783 -134.442174) (xy 29.681716 -134.444465) (xy 29.654478 -134.454867) (xy 29.642562 -134.463282)
			(xy 29.617483 -134.481609) (xy 29.562623 -134.51073) (xy 29.503769 -134.530578) (xy 29.442477 -134.540628)
			(xy 29.411422 -134.54126) (xy 29.385042 -134.540816) (xy 29.332783 -134.533556) (xy 29.282022 -134.51917)
			(xy 29.233724 -134.497933) (xy 29.18881 -134.470249) (xy 29.148135 -134.436645) (xy 29.112474 -134.397761)
			(xy 29.082505 -134.354339) (xy 29.0703 -134.330948) (xy 29.063598 -134.318589) (xy 29.044623 -134.297861)
			(xy 29.020709 -134.283099) (xy 28.993673 -134.275427) (xy 28.965571 -134.275427) (xy 28.938535 -134.283099)
			(xy 28.914621 -134.297861) (xy 28.895646 -134.318589) (xy 28.888944 -134.330948) (xy 28.876703 -134.35432)
			(xy 28.846748 -134.397753) (xy 28.811097 -134.436646) (xy 28.770429 -134.470257) (xy 28.725519 -134.497947)
			(xy 28.677223 -134.519187) (xy 28.626461 -134.533572) (xy 28.574202 -134.540829) (xy 28.547822 -134.54126)
			(xy 28.521733 -134.540836) (xy 28.470042 -134.533729) (xy 28.419801 -134.519645) (xy 28.371948 -134.498846)
			(xy 28.349448 -134.485634) (xy 28.336447 -134.478288) (xy 28.307572 -134.470726) (xy 28.277744 -134.471831)
			(xy 28.249508 -134.481508) (xy 28.225273 -134.498931) (xy 28.207106 -134.522614) (xy 28.196558 -134.550536)
			(xy 28.195016 -134.56539) (xy 28.195016 -142.597124) (xy 28.19527 -144.886934) (xy 28.194656 -144.911916)
			(xy 28.184909 -144.960922) (xy 28.165797 -145.007087) (xy 28.138053 -145.048641) (xy 28.120848 -145.066766)
			(xy 18.940526 -154.246834) (xy 18.940526 -162.067748) (xy 30.453582 -162.067748) (xy 30.457653 -162.012126)
			(xy 30.469779 -161.957689) (xy 30.489702 -161.905598) (xy 30.516998 -161.856963) (xy 30.551084 -161.81282)
			(xy 30.591233 -161.774111) (xy 30.636591 -161.74166) (xy 30.686191 -161.716159) (xy 30.738975 -161.698152)
			(xy 30.793818 -161.688022) (xy 30.849552 -161.685985) (xy 30.904989 -161.692085) (xy 30.958946 -161.706191)
			(xy 31.010275 -161.728003) (xy 31.057881 -161.757057) (xy 31.100749 -161.792732) (xy 31.137966 -161.834269)
			(xy 31.168739 -161.880782) (xy 31.192411 -161.931279) (xy 31.208479 -161.984686) (xy 31.216599 -162.039862)
			(xy 31.217108 -162.067748) (xy 31.216599 -162.095634) (xy 31.208479 -162.15081) (xy 31.192411 -162.204217)
			(xy 31.168739 -162.254714) (xy 31.137966 -162.301227) (xy 31.100749 -162.342764) (xy 31.057881 -162.378439)
			(xy 31.010275 -162.407493) (xy 30.958946 -162.429305) (xy 30.904989 -162.443411) (xy 30.849552 -162.449511)
			(xy 30.793818 -162.447474) (xy 30.738975 -162.437344) (xy 30.686191 -162.419337) (xy 30.636591 -162.393836)
			(xy 30.591233 -162.361385) (xy 30.551084 -162.322676) (xy 30.516998 -162.278533) (xy 30.489702 -162.229898)
			(xy 30.469779 -162.177807) (xy 30.457653 -162.12337) (xy 30.453582 -162.067748) (xy 18.940526 -162.067748)
			(xy 18.940526 -163.032948) (xy 20.014182 -163.032948) (xy 20.018253 -162.977326) (xy 20.030379 -162.922889)
			(xy 20.050302 -162.870798) (xy 20.077598 -162.822163) (xy 20.111684 -162.77802) (xy 20.151833 -162.739311)
			(xy 20.197191 -162.70686) (xy 20.246791 -162.681359) (xy 20.299575 -162.663352) (xy 20.354418 -162.653222)
			(xy 20.410152 -162.651185) (xy 20.465589 -162.657285) (xy 20.519546 -162.671391) (xy 20.570875 -162.693203)
			(xy 20.618481 -162.722257) (xy 20.661349 -162.757932) (xy 20.698566 -162.799469) (xy 20.729339 -162.845982)
			(xy 20.753011 -162.896479) (xy 20.769079 -162.949886) (xy 20.777199 -163.005062) (xy 20.777708 -163.032948)
			(xy 20.777199 -163.060834) (xy 20.769079 -163.11601) (xy 20.753011 -163.169417) (xy 20.729339 -163.219914)
			(xy 20.698566 -163.266427) (xy 20.661349 -163.307964) (xy 20.618481 -163.343639) (xy 20.570875 -163.372693)
			(xy 20.525196 -163.392104) (xy 22.73884 -163.392104) (xy 22.742911 -163.336482) (xy 22.755037 -163.282045)
			(xy 22.77496 -163.229954) (xy 22.802256 -163.181319) (xy 22.836342 -163.137176) (xy 22.876491 -163.098467)
			(xy 22.921849 -163.066016) (xy 22.971449 -163.040515) (xy 23.024233 -163.022508) (xy 23.079076 -163.012378)
			(xy 23.13481 -163.010341) (xy 23.190247 -163.016441) (xy 23.244204 -163.030547) (xy 23.295533 -163.052359)
			(xy 23.343139 -163.081413) (xy 23.386007 -163.117088) (xy 23.423224 -163.158625) (xy 23.453997 -163.205138)
			(xy 23.477669 -163.255635) (xy 23.493737 -163.309042) (xy 23.501857 -163.364218) (xy 23.502366 -163.392104)
			(xy 23.501857 -163.41999) (xy 23.493737 -163.475166) (xy 23.477669 -163.528573) (xy 23.453997 -163.57907)
			(xy 23.428637 -163.617402) (xy 31.594552 -163.617402) (xy 31.59497 -163.590666) (xy 31.602436 -163.537719)
			(xy 31.617224 -163.486333) (xy 31.639042 -163.437516) (xy 31.667464 -163.392223) (xy 31.701932 -163.351344)
			(xy 31.721552 -163.333176) (xy 31.721552 -160.269428) (xy 31.722197 -160.244432) (xy 31.731997 -160.19541)
			(xy 31.751168 -160.149239) (xy 31.778974 -160.107692) (xy 31.796228 -160.089596) (xy 32.727138 -159.158686)
			(xy 32.745267 -159.141485) (xy 32.786819 -159.113738) (xy 32.832983 -159.094625) (xy 32.881988 -159.084878)
			(xy 32.90697 -159.084264) (xy 34.381186 -159.084264) (xy 34.406168 -159.084899) (xy 34.455175 -159.094634)
			(xy 34.501345 -159.113735) (xy 34.542907 -159.141467) (xy 34.561018 -159.158686) (xy 35.348672 -159.94634)
			(xy 35.365935 -159.964429) (xy 35.393745 -160.005976) (xy 35.412917 -160.052149) (xy 35.422713 -160.101175)
			(xy 35.423348 -160.126172) (xy 35.423348 -161.891218) (xy 43.505377 -161.891218) (xy 43.509413 -161.807771)
			(xy 43.521485 -161.725103) (xy 43.541478 -161.643986) (xy 43.569207 -161.565177) (xy 43.604413 -161.489412)
			(xy 43.646767 -161.417399) (xy 43.695873 -161.34981) (xy 43.751274 -161.287276) (xy 43.812451 -161.230381)
			(xy 43.878834 -161.179655) (xy 43.949802 -161.135574) (xy 44.024694 -161.098548) (xy 44.10281 -161.068922)
			(xy 44.18342 -161.046974) (xy 44.265772 -161.032909) (xy 44.349098 -161.026857) (xy 44.432618 -161.028876)
			(xy 44.515554 -161.038946) (xy 44.59713 -161.056974) (xy 44.676586 -161.082791) (xy 44.753179 -161.116156)
			(xy 44.826195 -161.156757) (xy 44.894951 -161.204216) (xy 44.958805 -161.258089) (xy 45.017162 -161.317874)
			(xy 45.069477 -161.383011) (xy 45.11526 -161.452894) (xy 45.154085 -161.526869) (xy 45.18559 -161.604246)
			(xy 45.209479 -161.684303) (xy 45.224439 -161.76072) (xy 51.012924 -161.76072) (xy 51.012928 -161.706227)
			(xy 51.020687 -161.652288) (xy 51.036042 -161.600003) (xy 51.058683 -161.550435) (xy 51.088146 -161.504593)
			(xy 51.123834 -161.463411) (xy 51.165019 -161.427727) (xy 51.210863 -161.398267) (xy 51.260433 -161.375631)
			(xy 51.312719 -161.36028) (xy 51.366659 -161.352526) (xy 51.421152 -161.352526) (xy 51.475091 -161.360282)
			(xy 51.527377 -161.375635) (xy 51.576946 -161.398272) (xy 51.62279 -161.427734) (xy 51.663974 -161.463419)
			(xy 51.69966 -161.504602) (xy 51.729122 -161.550444) (xy 51.736434 -161.566455) (xy 53.058229 -161.566455)
			(xy 53.058229 -161.511945) (xy 53.065987 -161.457989) (xy 53.081345 -161.405686) (xy 53.10399 -161.356102)
			(xy 53.133461 -161.310245) (xy 53.169159 -161.269049) (xy 53.210356 -161.233353) (xy 53.256214 -161.203883)
			(xy 53.305799 -161.18124) (xy 53.358102 -161.165884) (xy 53.412059 -161.158128) (xy 53.439314 -161.157666)
			(xy 53.466685 -161.158108) (xy 53.520866 -161.165929) (xy 53.57337 -161.181423) (xy 53.623117 -161.20427)
			(xy 53.669082 -161.234001) (xy 53.690012 -161.251646) (xy 53.70134 -161.260882) (xy 53.727897 -161.273058)
			(xy 53.756814 -161.277231) (xy 53.785731 -161.273058) (xy 53.812288 -161.260882) (xy 53.823616 -161.251646)
			(xy 53.844575 -161.23404) (xy 53.89054 -161.204322) (xy 53.94028 -161.181479) (xy 53.992775 -161.16598)
			(xy 54.046947 -161.158144) (xy 54.074314 -161.157666) (xy 54.101563 -161.158205) (xy 54.155505 -161.165963)
			(xy 54.207795 -161.181318) (xy 54.257367 -161.203958) (xy 54.303212 -161.233423) (xy 54.344398 -161.269112)
			(xy 54.380085 -161.310299) (xy 54.409548 -161.356146) (xy 54.432187 -161.405719) (xy 54.44754 -161.458009)
			(xy 54.455296 -161.511951) (xy 54.455296 -161.566449) (xy 54.44754 -161.620391) (xy 54.432187 -161.672681)
			(xy 54.409548 -161.722254) (xy 54.380085 -161.768101) (xy 54.344398 -161.809288) (xy 54.303212 -161.844977)
			(xy 54.257367 -161.874442) (xy 54.207795 -161.897082) (xy 54.155505 -161.912437) (xy 54.101563 -161.920195)
			(xy 54.074314 -161.920682) (xy 54.046944 -161.920212) (xy 53.992765 -161.912396) (xy 53.940262 -161.896908)
			(xy 53.890515 -161.874067) (xy 53.844548 -161.844343) (xy 53.823616 -161.826702) (xy 53.812288 -161.817466)
			(xy 53.785731 -161.80529) (xy 53.756814 -161.801117) (xy 53.727897 -161.80529) (xy 53.70134 -161.817466)
			(xy 53.690012 -161.826702) (xy 53.669086 -161.844349) (xy 53.623112 -161.87406) (xy 53.573363 -161.896894)
			(xy 53.520861 -161.912383) (xy 53.466684 -161.920209) (xy 53.439314 -161.920682) (xy 53.412059 -161.920272)
			(xy 53.358102 -161.912516) (xy 53.305799 -161.89716) (xy 53.256214 -161.874517) (xy 53.210356 -161.845047)
			(xy 53.169159 -161.809351) (xy 53.133461 -161.768155) (xy 53.10399 -161.722298) (xy 53.081345 -161.672714)
			(xy 53.065987 -161.620411) (xy 53.058229 -161.566455) (xy 51.736434 -161.566455) (xy 51.751761 -161.600013)
			(xy 51.767116 -161.652299) (xy 51.774873 -161.706237) (xy 51.77536 -161.733484) (xy 51.77493 -161.758875)
			(xy 51.768173 -161.809207) (xy 51.761898 -161.833814) (xy 51.758525 -161.848472) (xy 51.759445 -161.878518)
			(xy 51.769069 -161.906996) (xy 51.786564 -161.93144) (xy 51.810415 -161.949736) (xy 51.838559 -161.960299)
			(xy 51.868558 -161.962215) (xy 51.88331 -161.95929) (xy 51.90484 -161.954535) (xy 51.948639 -161.949442)
			(xy 51.970686 -161.94913) (xy 51.97094 -161.94913) (xy 51.998187 -161.949621) (xy 52.052126 -161.957382)
			(xy 52.104412 -161.972739) (xy 52.153979 -161.995381) (xy 52.199821 -162.024847) (xy 52.241002 -162.060536)
			(xy 52.276686 -162.101723) (xy 52.306145 -162.147568) (xy 52.32878 -162.197139) (xy 52.34413 -162.249427)
			(xy 52.351883 -162.303367) (xy 52.351881 -162.357861) (xy 52.344124 -162.411801) (xy 52.32877 -162.464087)
			(xy 52.306131 -162.513657) (xy 52.276669 -162.5595) (xy 52.240982 -162.600684) (xy 52.199798 -162.63637)
			(xy 52.153955 -162.665832) (xy 52.104385 -162.688471) (xy 52.052099 -162.703824) (xy 51.998159 -162.711581)
			(xy 51.943665 -162.711583) (xy 51.889725 -162.703829) (xy 51.837437 -162.688479) (xy 51.787866 -162.665844)
			(xy 51.742021 -162.636384) (xy 51.700835 -162.600701) (xy 51.665146 -162.559519) (xy 51.63568 -162.513678)
			(xy 51.613039 -162.46411) (xy 51.597681 -162.411824) (xy 51.589921 -162.357885) (xy 51.589432 -162.330638)
			(xy 51.589867 -162.305247) (xy 51.596621 -162.254916) (xy 51.602894 -162.230308) (xy 51.606253 -162.215646)
			(xy 51.605338 -162.185601) (xy 51.595718 -162.157123) (xy 51.578225 -162.132677) (xy 51.554375 -162.114382)
			(xy 51.526232 -162.10382) (xy 51.496234 -162.101906) (xy 51.481482 -162.104832) (xy 51.459952 -162.109589)
			(xy 51.416153 -162.11468) (xy 51.394106 -162.114992) (xy 51.393852 -162.114992) (xy 51.366605 -162.11447)
			(xy 51.312667 -162.106709) (xy 51.260383 -162.09135) (xy 51.210816 -162.068707) (xy 51.164976 -162.039241)
			(xy 51.123796 -162.003551) (xy 51.088114 -161.962364) (xy 51.058657 -161.916518) (xy 51.036024 -161.866947)
			(xy 51.020675 -161.81466) (xy 51.012924 -161.76072) (xy 45.224439 -161.76072) (xy 45.22553 -161.766291)
			(xy 45.233593 -161.849446) (xy 45.234098 -161.891218) (xy 45.233593 -161.93299) (xy 45.22553 -162.016145)
			(xy 45.209479 -162.098133) (xy 45.18559 -162.17819) (xy 45.154085 -162.255567) (xy 45.11526 -162.329542)
			(xy 45.069477 -162.399425) (xy 45.017162 -162.464562) (xy 44.958805 -162.524347) (xy 44.894951 -162.57822)
			(xy 44.826195 -162.625679) (xy 44.753179 -162.66628) (xy 44.676586 -162.699645) (xy 44.59713 -162.725462)
			(xy 44.515554 -162.74349) (xy 44.432618 -162.75356) (xy 44.349098 -162.755579) (xy 44.265772 -162.749527)
			(xy 44.18342 -162.735462) (xy 44.10281 -162.713514) (xy 44.024694 -162.683888) (xy 43.949802 -162.646862)
			(xy 43.878834 -162.602781) (xy 43.812451 -162.552055) (xy 43.751274 -162.49516) (xy 43.695873 -162.432626)
			(xy 43.646767 -162.365037) (xy 43.604413 -162.293024) (xy 43.569207 -162.217259) (xy 43.541478 -162.13845)
			(xy 43.521485 -162.057333) (xy 43.509413 -161.974665) (xy 43.505377 -161.891218) (xy 35.423348 -161.891218)
			(xy 35.423348 -163.164052) (xy 49.996289 -163.164052) (xy 49.996289 -163.109548) (xy 50.004047 -163.055598)
			(xy 50.019404 -163.003301) (xy 50.042047 -162.953722) (xy 50.071517 -162.907871) (xy 50.107212 -162.866681)
			(xy 50.148406 -162.83099) (xy 50.194261 -162.801526) (xy 50.243842 -162.778888) (xy 50.296141 -162.763537)
			(xy 50.350092 -162.755786) (xy 50.377344 -162.755326) (xy 50.407031 -162.755911) (xy 50.465689 -162.765102)
			(xy 50.522215 -162.783271) (xy 50.575243 -162.809978) (xy 50.623492 -162.84458) (xy 50.665798 -162.886239)
			(xy 50.683922 -162.909758) (xy 50.692348 -162.920365) (xy 50.713661 -162.937072) (xy 50.738615 -162.947591)
			(xy 50.765456 -162.951181) (xy 50.792297 -162.947591) (xy 50.817251 -162.937072) (xy 50.838564 -162.920365)
			(xy 50.84699 -162.909758) (xy 50.86512 -162.886243) (xy 50.907427 -162.844585) (xy 50.955675 -162.809982)
			(xy 51.008701 -162.783271) (xy 51.065225 -162.765095) (xy 51.123881 -162.755893) (xy 51.153568 -162.755326)
			(xy 51.180825 -162.755719) (xy 51.234784 -162.763473) (xy 51.28709 -162.778827) (xy 51.336679 -162.80147)
			(xy 51.38254 -162.83094) (xy 51.423741 -162.866637) (xy 51.459441 -162.907834) (xy 51.488915 -162.953693)
			(xy 51.511561 -163.00328) (xy 51.52692 -163.055585) (xy 51.534679 -163.109543) (xy 51.534679 -163.164057)
			(xy 51.52692 -163.218015) (xy 51.511561 -163.27032) (xy 51.488915 -163.319907) (xy 51.459441 -163.365766)
			(xy 51.423741 -163.406963) (xy 51.38254 -163.44266) (xy 51.336679 -163.47213) (xy 51.28709 -163.494773)
			(xy 51.234784 -163.510127) (xy 51.180825 -163.517881) (xy 51.153568 -163.518342) (xy 51.123881 -163.51776)
			(xy 51.065222 -163.50857) (xy 51.008695 -163.490402) (xy 50.955667 -163.463694) (xy 50.907418 -163.429091)
			(xy 50.865114 -163.38743) (xy 50.84699 -163.36391) (xy 50.838564 -163.353303) (xy 50.817251 -163.336596)
			(xy 50.792297 -163.326077) (xy 50.765456 -163.322487) (xy 50.738615 -163.326077) (xy 50.713661 -163.336596)
			(xy 50.692348 -163.353303) (xy 50.683922 -163.36391) (xy 50.665776 -163.387412) (xy 50.623474 -163.429073)
			(xy 50.575229 -163.463678) (xy 50.522206 -163.490392) (xy 50.465685 -163.50857) (xy 50.40703 -163.517774)
			(xy 50.377344 -163.518342) (xy 50.350092 -163.517814) (xy 50.296141 -163.510063) (xy 50.243842 -163.494712)
			(xy 50.194261 -163.472074) (xy 50.148406 -163.44261) (xy 50.107212 -163.406919) (xy 50.071517 -163.365729)
			(xy 50.042047 -163.319878) (xy 50.019404 -163.270299) (xy 50.004047 -163.218002) (xy 49.996289 -163.164052)
			(xy 35.423348 -163.164052) (xy 35.423348 -164.433688) (xy 43.480986 -164.433688) (xy 43.480986 -164.348992)
			(xy 43.489037 -164.264678) (xy 43.505066 -164.181512) (xy 43.528927 -164.100245) (xy 43.560406 -164.021615)
			(xy 43.599217 -163.946334) (xy 43.645007 -163.875082) (xy 43.697363 -163.808506) (xy 43.755811 -163.747208)
			(xy 43.819821 -163.691743) (xy 43.888813 -163.642614) (xy 43.962163 -163.600265) (xy 44.039206 -163.565081)
			(xy 44.119245 -163.537379) (xy 44.201554 -163.517411) (xy 44.285389 -163.505358) (xy 44.36999 -163.501328)
			(xy 44.454591 -163.505358) (xy 44.538426 -163.517411) (xy 44.620735 -163.537379) (xy 44.700774 -163.565081)
			(xy 44.777817 -163.600265) (xy 44.851167 -163.642614) (xy 44.920159 -163.691743) (xy 44.984169 -163.747208)
			(xy 45.042617 -163.808506) (xy 45.094973 -163.875082) (xy 45.140763 -163.946334) (xy 45.179574 -164.021615)
			(xy 45.211053 -164.100245) (xy 45.234914 -164.181512) (xy 45.250943 -164.264678) (xy 45.258994 -164.348992)
			(xy 45.259498 -164.39134) (xy 45.258994 -164.433688) (xy 45.250943 -164.518002) (xy 45.234914 -164.601168)
			(xy 45.211053 -164.682435) (xy 45.179574 -164.761065) (xy 45.140763 -164.836346) (xy 45.094973 -164.907598)
			(xy 45.042617 -164.974174) (xy 44.984169 -165.035472) (xy 44.920159 -165.090937) (xy 44.851167 -165.140066)
			(xy 44.777817 -165.182415) (xy 44.700774 -165.217599) (xy 44.620735 -165.245301) (xy 44.538426 -165.265269)
			(xy 44.454591 -165.277322) (xy 44.36999 -165.281353) (xy 44.285389 -165.277322) (xy 44.201554 -165.265269)
			(xy 44.119245 -165.245301) (xy 44.039206 -165.217599) (xy 43.962163 -165.182415) (xy 43.888813 -165.140066)
			(xy 43.819821 -165.090937) (xy 43.755811 -165.035472) (xy 43.697363 -164.974174) (xy 43.645007 -164.907598)
			(xy 43.599217 -164.836346) (xy 43.560406 -164.761065) (xy 43.528927 -164.682435) (xy 43.505066 -164.601168)
			(xy 43.489037 -164.518002) (xy 43.480986 -164.433688) (xy 35.423348 -164.433688) (xy 35.423348 -165.365938)
			(xy 36.20897 -166.15156) (xy 45.67047 -166.15156) (xy 47.849282 -163.973002) (xy 47.867395 -163.955783)
			(xy 47.908952 -163.928039) (xy 47.955121 -163.90893) (xy 48.00413 -163.89919) (xy 48.029114 -163.89858)
			(xy 50.68189 -163.89858) (xy 50.700052 -163.878945) (xy 50.740922 -163.844443) (xy 50.78621 -163.815985)
			(xy 50.835026 -163.794129) (xy 50.886416 -163.779302) (xy 50.939373 -163.771795) (xy 50.966116 -163.771326)
			(xy 50.993371 -163.77174) (xy 51.047325 -163.7795) (xy 51.099626 -163.79486) (xy 51.149209 -163.817507)
			(xy 51.195063 -163.84698) (xy 51.236257 -163.882679) (xy 51.27195 -163.923877) (xy 51.301417 -163.969735)
			(xy 51.324058 -164.019321) (xy 51.339411 -164.071624) (xy 51.347163 -164.125579) (xy 51.347624 -164.152834)
			(xy 51.347624 -164.153088) (xy 51.347224 -164.178292) (xy 51.340585 -164.22826) (xy 51.327409 -164.276914)
			(xy 51.307926 -164.323404) (xy 51.295554 -164.345366) (xy 51.28846 -164.358303) (xy 51.281434 -164.386951)
			(xy 51.282888 -164.416412) (xy 51.292701 -164.444229) (xy 51.310054 -164.468081) (xy 51.3335 -164.48598)
			(xy 51.347116 -164.49167) (xy 51.373892 -164.502366) (xy 51.424134 -164.530654) (xy 51.469543 -164.566184)
			(xy 51.509085 -164.608146) (xy 51.541859 -164.655583) (xy 51.567117 -164.707414) (xy 51.584283 -164.762457)
			(xy 51.592966 -164.819457) (xy 51.593496 -164.848286) (xy 51.593032 -164.875539) (xy 51.585276 -164.929491)
			(xy 51.569921 -164.981789) (xy 51.54728 -165.03137) (xy 51.517812 -165.077224) (xy 51.482118 -165.118417)
			(xy 51.440925 -165.154111) (xy 51.395072 -165.183579) (xy 51.345491 -165.206221) (xy 51.293193 -165.221576)
			(xy 51.239241 -165.229331) (xy 51.211988 -165.229794) (xy 51.211734 -165.229794) (xy 51.181895 -165.229227)
			(xy 51.122949 -165.219906) (xy 51.094386 -165.211252) (xy 51.080457 -165.207302) (xy 51.051539 -165.206385)
			(xy 51.02353 -165.213636) (xy 50.998691 -165.228471) (xy 50.979026 -165.249693) (xy 50.966122 -165.275589)
			(xy 50.963068 -165.289738) (xy 50.957919 -165.315816) (xy 50.941346 -165.36632) (xy 50.917921 -165.414034)
			(xy 50.888096 -165.458032) (xy 50.852451 -165.497463) (xy 50.811676 -165.531561) (xy 50.76656 -165.559667)
			(xy 50.717979 -165.581236) (xy 50.666873 -165.595849) (xy 50.614233 -165.603225) (xy 50.587656 -165.603682)
			(xy 50.560405 -165.603245) (xy 50.506458 -165.595483) (xy 50.454165 -165.580123) (xy 50.40459 -165.557478)
			(xy 50.358742 -165.528008) (xy 50.317554 -165.492314) (xy 50.281865 -165.451123) (xy 50.252401 -165.405271)
			(xy 50.229762 -165.355693) (xy 50.214408 -165.303399) (xy 50.206652 -165.249451) (xy 50.206652 -165.194949)
			(xy 50.214408 -165.141001) (xy 50.229762 -165.088707) (xy 50.252401 -165.039129) (xy 50.281865 -164.993277)
			(xy 50.317554 -164.952086) (xy 50.358742 -164.916392) (xy 50.40459 -164.886922) (xy 50.454165 -164.864277)
			(xy 50.506458 -164.848917) (xy 50.560405 -164.841155) (xy 50.587656 -164.840666) (xy 50.58791 -164.840666)
			(xy 50.617749 -164.841247) (xy 50.676695 -164.850559) (xy 50.705258 -164.859208) (xy 50.719167 -164.863239)
			(xy 50.748099 -164.864148) (xy 50.776118 -164.856883) (xy 50.800963 -164.842032) (xy 50.820629 -164.820792)
			(xy 50.833527 -164.794879) (xy 50.836576 -164.780722) (xy 50.843165 -164.747884) (xy 50.866284 -164.685031)
			(xy 50.88255 -164.655754) (xy 50.889618 -164.642804) (xy 50.896647 -164.614161) (xy 50.895197 -164.584704)
			(xy 50.885389 -164.55689) (xy 50.868042 -164.533039) (xy 50.844601 -164.515141) (xy 50.830988 -164.50945)
			(xy 50.80273 -164.498094) (xy 50.749937 -164.467739) (xy 50.702636 -164.429383) (xy 50.68189 -164.407088)
			(xy 48.134524 -164.407088) (xy 45.955712 -166.5859) (xy 45.937605 -166.603143) (xy 45.896064 -166.630956)
			(xy 45.849896 -166.650132) (xy 45.800875 -166.659936) (xy 45.77588 -166.660576) (xy 36.10356 -166.660576)
			(xy 36.078566 -166.659904) (xy 36.029545 -166.650111) (xy 35.983374 -166.630948) (xy 35.941826 -166.60315)
			(xy 35.923728 -166.5859) (xy 34.989008 -165.65118) (xy 34.971751 -165.633085) (xy 34.943941 -165.59154)
			(xy 34.924768 -165.545369) (xy 34.914969 -165.496344) (xy 34.914332 -165.471348) (xy 34.914332 -160.231582)
			(xy 34.275776 -159.592772) (xy 33.01238 -159.592772) (xy 32.230568 -160.374838) (xy 32.230568 -161.170874)
			(xy 33.5186 -161.170874) (xy 33.522671 -161.115252) (xy 33.534797 -161.060815) (xy 33.55472 -161.008724)
			(xy 33.582016 -160.960089) (xy 33.616102 -160.915946) (xy 33.656251 -160.877237) (xy 33.701609 -160.844786)
			(xy 33.751209 -160.819285) (xy 33.803993 -160.801278) (xy 33.858836 -160.791148) (xy 33.91457 -160.789111)
			(xy 33.970007 -160.795211) (xy 34.023964 -160.809317) (xy 34.075293 -160.831129) (xy 34.122899 -160.860183)
			(xy 34.165767 -160.895858) (xy 34.202984 -160.937395) (xy 34.233757 -160.983908) (xy 34.257429 -161.034405)
			(xy 34.273497 -161.087812) (xy 34.281617 -161.142988) (xy 34.282126 -161.170874) (xy 34.281617 -161.19876)
			(xy 34.273497 -161.253936) (xy 34.257429 -161.307343) (xy 34.233757 -161.35784) (xy 34.202984 -161.404353)
			(xy 34.165767 -161.44589) (xy 34.122899 -161.481565) (xy 34.075293 -161.510619) (xy 34.023964 -161.532431)
			(xy 33.970007 -161.546537) (xy 33.91457 -161.552637) (xy 33.858836 -161.5506) (xy 33.803993 -161.54047)
			(xy 33.751209 -161.522463) (xy 33.701609 -161.496962) (xy 33.656251 -161.464511) (xy 33.616102 -161.425802)
			(xy 33.582016 -161.381659) (xy 33.55472 -161.333024) (xy 33.534797 -161.280933) (xy 33.522671 -161.226496)
			(xy 33.5186 -161.170874) (xy 32.230568 -161.170874) (xy 32.230568 -162.586162) (xy 33.079942 -162.586162)
			(xy 33.084013 -162.53054) (xy 33.096139 -162.476103) (xy 33.116062 -162.424012) (xy 33.143358 -162.375377)
			(xy 33.177444 -162.331234) (xy 33.217593 -162.292525) (xy 33.262951 -162.260074) (xy 33.312551 -162.234573)
			(xy 33.365335 -162.216566) (xy 33.420178 -162.206436) (xy 33.475912 -162.204399) (xy 33.531349 -162.210499)
			(xy 33.585306 -162.224605) (xy 33.636635 -162.246417) (xy 33.684241 -162.275471) (xy 33.727109 -162.311146)
			(xy 33.764326 -162.352683) (xy 33.795099 -162.399196) (xy 33.818771 -162.449693) (xy 33.834839 -162.5031)
			(xy 33.842959 -162.558276) (xy 33.843468 -162.586162) (xy 33.842959 -162.614048) (xy 33.834839 -162.669224)
			(xy 33.818771 -162.722631) (xy 33.795099 -162.773128) (xy 33.764326 -162.819641) (xy 33.727109 -162.861178)
			(xy 33.684241 -162.896853) (xy 33.636635 -162.925907) (xy 33.585306 -162.947719) (xy 33.531349 -162.961825)
			(xy 33.475912 -162.967925) (xy 33.420178 -162.965888) (xy 33.365335 -162.955758) (xy 33.312551 -162.937751)
			(xy 33.262951 -162.91225) (xy 33.217593 -162.879799) (xy 33.177444 -162.84109) (xy 33.143358 -162.796947)
			(xy 33.116062 -162.748312) (xy 33.096139 -162.696221) (xy 33.084013 -162.641784) (xy 33.079942 -162.586162)
			(xy 32.230568 -162.586162) (xy 32.230568 -163.333176) (xy 32.250188 -163.351341) (xy 32.284647 -163.392225)
			(xy 32.31306 -163.43752) (xy 32.334872 -163.486338) (xy 32.349655 -163.537722) (xy 32.357119 -163.590668)
			(xy 32.357568 -163.617402) (xy 32.357082 -163.644653) (xy 32.349326 -163.698601) (xy 32.333971 -163.750896)
			(xy 32.311329 -163.800473) (xy 32.281863 -163.846323) (xy 32.246172 -163.887514) (xy 32.204981 -163.923205)
			(xy 32.159131 -163.952671) (xy 32.109554 -163.975313) (xy 32.057259 -163.990668) (xy 32.003311 -163.998424)
			(xy 31.948809 -163.998424) (xy 31.894861 -163.990668) (xy 31.842566 -163.975313) (xy 31.792989 -163.952671)
			(xy 31.747139 -163.923205) (xy 31.705948 -163.887514) (xy 31.670257 -163.846323) (xy 31.640791 -163.800473)
			(xy 31.618149 -163.750896) (xy 31.602794 -163.698601) (xy 31.595038 -163.644653) (xy 31.594552 -163.617402)
			(xy 23.428637 -163.617402) (xy 23.423224 -163.625583) (xy 23.386007 -163.66712) (xy 23.343139 -163.702795)
			(xy 23.295533 -163.731849) (xy 23.244204 -163.753661) (xy 23.190247 -163.767767) (xy 23.13481 -163.773867)
			(xy 23.079076 -163.77183) (xy 23.024233 -163.7617) (xy 22.971449 -163.743693) (xy 22.921849 -163.718192)
			(xy 22.876491 -163.685741) (xy 22.836342 -163.647032) (xy 22.802256 -163.602889) (xy 22.77496 -163.554254)
			(xy 22.755037 -163.502163) (xy 22.742911 -163.447726) (xy 22.73884 -163.392104) (xy 20.525196 -163.392104)
			(xy 20.519546 -163.394505) (xy 20.465589 -163.408611) (xy 20.410152 -163.414711) (xy 20.354418 -163.412674)
			(xy 20.299575 -163.402544) (xy 20.246791 -163.384537) (xy 20.197191 -163.359036) (xy 20.151833 -163.326585)
			(xy 20.111684 -163.287876) (xy 20.077598 -163.243733) (xy 20.050302 -163.195098) (xy 20.030379 -163.143007)
			(xy 20.018253 -163.08857) (xy 20.014182 -163.032948) (xy 18.940526 -163.032948) (xy 18.940526 -164.194744)
			(xy 20.752814 -164.194744) (xy 20.756885 -164.139122) (xy 20.769011 -164.084685) (xy 20.788934 -164.032594)
			(xy 20.81623 -163.983959) (xy 20.850316 -163.939816) (xy 20.890465 -163.901107) (xy 20.935823 -163.868656)
			(xy 20.985423 -163.843155) (xy 21.038207 -163.825148) (xy 21.09305 -163.815018) (xy 21.148784 -163.812981)
			(xy 21.204221 -163.819081) (xy 21.258178 -163.833187) (xy 21.309507 -163.854999) (xy 21.357113 -163.884053)
			(xy 21.399981 -163.919728) (xy 21.437198 -163.961265) (xy 21.467971 -164.007778) (xy 21.491643 -164.058275)
			(xy 21.507711 -164.111682) (xy 21.515831 -164.166858) (xy 21.51634 -164.194744) (xy 21.515831 -164.22263)
			(xy 21.507711 -164.277806) (xy 21.500223 -164.302694) (xy 33.044382 -164.302694) (xy 33.048453 -164.247072)
			(xy 33.060579 -164.192635) (xy 33.080502 -164.140544) (xy 33.107798 -164.091909) (xy 33.141884 -164.047766)
			(xy 33.182033 -164.009057) (xy 33.227391 -163.976606) (xy 33.276991 -163.951105) (xy 33.329775 -163.933098)
			(xy 33.384618 -163.922968) (xy 33.440352 -163.920931) (xy 33.495789 -163.927031) (xy 33.549746 -163.941137)
			(xy 33.601075 -163.962949) (xy 33.648681 -163.992003) (xy 33.691549 -164.027678) (xy 33.728766 -164.069215)
			(xy 33.759539 -164.115728) (xy 33.783211 -164.166225) (xy 33.799279 -164.219632) (xy 33.807399 -164.274808)
			(xy 33.807908 -164.302694) (xy 33.807399 -164.33058) (xy 33.799279 -164.385756) (xy 33.783211 -164.439163)
			(xy 33.759539 -164.48966) (xy 33.728766 -164.536173) (xy 33.691549 -164.57771) (xy 33.648681 -164.613385)
			(xy 33.601075 -164.642439) (xy 33.549746 -164.664251) (xy 33.495789 -164.678357) (xy 33.440352 -164.684457)
			(xy 33.384618 -164.68242) (xy 33.329775 -164.67229) (xy 33.276991 -164.654283) (xy 33.227391 -164.628782)
			(xy 33.182033 -164.596331) (xy 33.141884 -164.557622) (xy 33.107798 -164.513479) (xy 33.080502 -164.464844)
			(xy 33.060579 -164.412753) (xy 33.048453 -164.358316) (xy 33.044382 -164.302694) (xy 21.500223 -164.302694)
			(xy 21.491643 -164.331213) (xy 21.467971 -164.38171) (xy 21.437198 -164.428223) (xy 21.399981 -164.46976)
			(xy 21.357113 -164.505435) (xy 21.309507 -164.534489) (xy 21.258178 -164.556301) (xy 21.204221 -164.570407)
			(xy 21.148784 -164.576507) (xy 21.09305 -164.57447) (xy 21.038207 -164.56434) (xy 20.985423 -164.546333)
			(xy 20.935823 -164.520832) (xy 20.890465 -164.488381) (xy 20.850316 -164.449672) (xy 20.81623 -164.405529)
			(xy 20.788934 -164.356894) (xy 20.769011 -164.304803) (xy 20.756885 -164.250366) (xy 20.752814 -164.194744)
			(xy 18.940526 -164.194744) (xy 18.940526 -164.994336) (xy 22.751794 -164.994336) (xy 22.755865 -164.938714)
			(xy 22.767991 -164.884277) (xy 22.787914 -164.832186) (xy 22.81521 -164.783551) (xy 22.849296 -164.739408)
			(xy 22.889445 -164.700699) (xy 22.934803 -164.668248) (xy 22.984403 -164.642747) (xy 23.037187 -164.62474)
			(xy 23.09203 -164.61461) (xy 23.147764 -164.612573) (xy 23.203201 -164.618673) (xy 23.257158 -164.632779)
			(xy 23.308487 -164.654591) (xy 23.356093 -164.683645) (xy 23.398961 -164.71932) (xy 23.436178 -164.760857)
			(xy 23.466951 -164.80737) (xy 23.490623 -164.857867) (xy 23.506691 -164.911274) (xy 23.514811 -164.96645)
			(xy 23.51532 -164.994336) (xy 23.514811 -165.022222) (xy 23.506691 -165.077398) (xy 23.490623 -165.130805)
			(xy 23.466951 -165.181302) (xy 23.436178 -165.227815) (xy 23.398961 -165.269352) (xy 23.356093 -165.305027)
			(xy 23.308487 -165.334081) (xy 23.257158 -165.355893) (xy 23.203201 -165.369999) (xy 23.147764 -165.376099)
			(xy 23.09203 -165.374062) (xy 23.037187 -165.363932) (xy 22.984403 -165.345925) (xy 22.934803 -165.320424)
			(xy 22.889445 -165.287973) (xy 22.849296 -165.249264) (xy 22.81521 -165.205121) (xy 22.787914 -165.156486)
			(xy 22.767991 -165.104395) (xy 22.755865 -165.049958) (xy 22.751794 -164.994336) (xy 18.940526 -164.994336)
			(xy 18.940526 -165.751256) (xy 20.741892 -165.751256) (xy 20.745963 -165.695634) (xy 20.758089 -165.641197)
			(xy 20.778012 -165.589106) (xy 20.805308 -165.540471) (xy 20.839394 -165.496328) (xy 20.879543 -165.457619)
			(xy 20.924901 -165.425168) (xy 20.974501 -165.399667) (xy 21.027285 -165.38166) (xy 21.082128 -165.37153)
			(xy 21.137862 -165.369493) (xy 21.193299 -165.375593) (xy 21.247256 -165.389699) (xy 21.298585 -165.411511)
			(xy 21.346191 -165.440565) (xy 21.389059 -165.47624) (xy 21.426276 -165.517777) (xy 21.457049 -165.56429)
			(xy 21.469681 -165.591236) (xy 30.677612 -165.591236) (xy 30.678089 -165.563983) (xy 30.685841 -165.510032)
			(xy 30.701194 -165.457733) (xy 30.723834 -165.408151) (xy 30.7533 -165.362297) (xy 30.788992 -165.321104)
			(xy 30.830184 -165.285409) (xy 30.876037 -165.255941) (xy 30.925618 -165.2333) (xy 30.977916 -165.217945)
			(xy 31.031867 -165.21019) (xy 31.05912 -165.209728) (xy 31.074876 -165.20987) (xy 31.106285 -165.21241)
			(xy 31.121858 -165.214808) (xy 31.136247 -165.216682) (xy 31.165042 -165.213223) (xy 31.191699 -165.2018)
			(xy 31.214065 -165.183337) (xy 31.230331 -165.159326) (xy 31.239182 -165.131707) (xy 31.239903 -165.102714)
			(xy 31.236666 -165.08857) (xy 31.230726 -165.064625) (xy 31.224354 -165.015702) (xy 31.223966 -164.991034)
			(xy 31.223966 -164.99078) (xy 31.224477 -164.963529) (xy 31.232236 -164.909581) (xy 31.247594 -164.857286)
			(xy 31.270238 -164.80771) (xy 31.299707 -164.76186) (xy 31.335401 -164.720672) (xy 31.376594 -164.684982)
			(xy 31.422447 -164.655518) (xy 31.472026 -164.63288) (xy 31.524322 -164.617527) (xy 31.57827 -164.609774)
			(xy 31.632773 -164.609777) (xy 31.686721 -164.617537) (xy 31.739016 -164.632895) (xy 31.788592 -164.655539)
			(xy 31.834441 -164.685009) (xy 31.87563 -164.720703) (xy 31.911319 -164.761896) (xy 31.940783 -164.807748)
			(xy 31.963421 -164.857327) (xy 31.978773 -164.909624) (xy 31.986526 -164.963572) (xy 31.986523 -165.018075)
			(xy 31.978763 -165.072023) (xy 31.963404 -165.124318) (xy 31.94076 -165.173894) (xy 31.91129 -165.219743)
			(xy 31.875596 -165.260931) (xy 31.834403 -165.29662) (xy 31.78855 -165.326084) (xy 31.738971 -165.348722)
			(xy 31.686674 -165.364074) (xy 31.632726 -165.371827) (xy 31.605474 -165.372288) (xy 31.589718 -165.372146)
			(xy 31.558309 -165.369606) (xy 31.542736 -165.367208) (xy 31.528349 -165.365308) (xy 31.49955 -165.368769)
			(xy 31.472889 -165.380195) (xy 31.450522 -165.398663) (xy 31.434256 -165.422679) (xy 31.425406 -165.450303)
			(xy 31.424689 -165.4793) (xy 31.427928 -165.493446) (xy 31.433885 -165.517453) (xy 31.440254 -165.566504)
			(xy 31.440628 -165.591236) (xy 31.440072 -165.62106) (xy 31.430817 -165.679986) (xy 31.412508 -165.736754)
			(xy 31.385589 -165.789982) (xy 31.350717 -165.838374) (xy 31.330138 -165.859968) (xy 31.320921 -165.869896)
			(xy 31.307608 -165.893478) (xy 31.300954 -165.919729) (xy 31.301426 -165.946805) (xy 31.308991 -165.972808)
			(xy 31.323119 -165.995911) (xy 31.332678 -166.00551) (xy 31.351326 -166.023609) (xy 31.384039 -166.063986)
			(xy 31.410967 -166.108431) (xy 31.43161 -166.15612) (xy 31.445586 -166.206172) (xy 31.452637 -166.257657)
			(xy 31.453074 -166.28364) (xy 31.452588 -166.310891) (xy 31.444832 -166.364839) (xy 31.429477 -166.417134)
			(xy 31.406835 -166.466711) (xy 31.377369 -166.512561) (xy 31.341678 -166.553752) (xy 31.300487 -166.589443)
			(xy 31.254637 -166.618909) (xy 31.20506 -166.641551) (xy 31.152765 -166.656906) (xy 31.098817 -166.664662)
			(xy 31.044315 -166.664662) (xy 30.990367 -166.656906) (xy 30.938072 -166.641551) (xy 30.888495 -166.618909)
			(xy 30.842645 -166.589443) (xy 30.801454 -166.553752) (xy 30.765763 -166.512561) (xy 30.736297 -166.466711)
			(xy 30.713655 -166.417134) (xy 30.6983 -166.364839) (xy 30.690544 -166.310891) (xy 30.690058 -166.28364)
			(xy 30.690058 -166.283386) (xy 30.690621 -166.253587) (xy 30.699903 -166.194717) (xy 30.718222 -166.138004)
			(xy 30.745134 -166.084828) (xy 30.779984 -166.036482) (xy 30.800548 -166.014908) (xy 30.809791 -166.005002)
			(xy 30.823104 -165.981413) (xy 30.829756 -165.955157) (xy 30.829279 -165.928075) (xy 30.821707 -165.902069)
			(xy 30.807572 -165.878964) (xy 30.798008 -165.869366) (xy 30.779346 -165.851282) (xy 30.746635 -165.810901)
			(xy 30.719709 -165.766453) (xy 30.699069 -165.71876) (xy 30.685095 -165.668707) (xy 30.678047 -165.61722)
			(xy 30.677612 -165.591236) (xy 21.469681 -165.591236) (xy 21.480721 -165.614787) (xy 21.496789 -165.668194)
			(xy 21.504909 -165.72337) (xy 21.505418 -165.751256) (xy 21.504909 -165.779142) (xy 21.496789 -165.834318)
			(xy 21.480721 -165.887725) (xy 21.457049 -165.938222) (xy 21.426276 -165.984735) (xy 21.389059 -166.026272)
			(xy 21.346191 -166.061947) (xy 21.298585 -166.091001) (xy 21.247256 -166.112813) (xy 21.193299 -166.126919)
			(xy 21.137862 -166.133019) (xy 21.082128 -166.130982) (xy 21.027285 -166.120852) (xy 20.974501 -166.102845)
			(xy 20.924901 -166.077344) (xy 20.879543 -166.044893) (xy 20.839394 -166.006184) (xy 20.805308 -165.962041)
			(xy 20.778012 -165.913406) (xy 20.758089 -165.861315) (xy 20.745963 -165.806878) (xy 20.741892 -165.751256)
			(xy 18.940526 -165.751256) (xy 18.940526 -166.25316) (xy 23.932132 -166.25316) (xy 23.936203 -166.197538)
			(xy 23.948329 -166.143101) (xy 23.968252 -166.09101) (xy 23.995548 -166.042375) (xy 24.029634 -165.998232)
			(xy 24.069783 -165.959523) (xy 24.115141 -165.927072) (xy 24.164741 -165.901571) (xy 24.217525 -165.883564)
			(xy 24.272368 -165.873434) (xy 24.328102 -165.871397) (xy 24.383539 -165.877497) (xy 24.437496 -165.891603)
			(xy 24.488825 -165.913415) (xy 24.536431 -165.942469) (xy 24.579299 -165.978144) (xy 24.616516 -166.019681)
			(xy 24.647289 -166.066194) (xy 24.670961 -166.116691) (xy 24.687029 -166.170098) (xy 24.695149 -166.225274)
			(xy 24.695658 -166.25316) (xy 24.695149 -166.281046) (xy 24.687029 -166.336222) (xy 24.670961 -166.389629)
			(xy 24.647289 -166.440126) (xy 24.616516 -166.486639) (xy 24.579299 -166.528176) (xy 24.536431 -166.563851)
			(xy 24.488825 -166.592905) (xy 24.437496 -166.614717) (xy 24.383539 -166.628823) (xy 24.328102 -166.634923)
			(xy 24.272368 -166.632886) (xy 24.217525 -166.622756) (xy 24.164741 -166.604749) (xy 24.115141 -166.579248)
			(xy 24.069783 -166.546797) (xy 24.029634 -166.508088) (xy 23.995548 -166.463945) (xy 23.968252 -166.41531)
			(xy 23.948329 -166.363219) (xy 23.936203 -166.308782) (xy 23.932132 -166.25316) (xy 18.940526 -166.25316)
			(xy 18.940526 -167.416046) (xy 20.000149 -167.416046) (xy 20.00015 -167.361539) (xy 20.007908 -167.307587)
			(xy 20.023266 -167.255288) (xy 20.04591 -167.205707) (xy 20.07538 -167.159853) (xy 20.111076 -167.118661)
			(xy 20.152271 -167.082967) (xy 20.198126 -167.0535) (xy 20.247708 -167.030858) (xy 20.300008 -167.015504)
			(xy 20.35396 -167.007748) (xy 20.381214 -167.007286) (xy 20.409833 -167.007814) (xy 20.46642 -167.016427)
			(xy 20.52109 -167.033384) (xy 20.547076 -167.045386) (xy 20.559384 -167.050937) (xy 20.585915 -167.055914)
			(xy 20.612823 -167.053761) (xy 20.638225 -167.044628) (xy 20.660345 -167.029155) (xy 20.677633 -167.008425)
			(xy 20.688882 -166.983886) (xy 20.693304 -166.957257) (xy 20.692364 -166.943786) (xy 20.690586 -166.906194)
			(xy 20.691062 -166.878942) (xy 20.698819 -166.824992) (xy 20.714176 -166.772695) (xy 20.736819 -166.723116)
			(xy 20.766287 -166.677264) (xy 20.801981 -166.636072) (xy 20.843174 -166.60038) (xy 20.889026 -166.570913)
			(xy 20.938606 -166.548272) (xy 20.990903 -166.532917) (xy 21.044854 -166.525161) (xy 21.099358 -166.525162)
			(xy 21.153308 -166.532919) (xy 21.205605 -166.548276) (xy 21.255184 -166.570919) (xy 21.301036 -166.600387)
			(xy 21.342228 -166.636081) (xy 21.37792 -166.677274) (xy 21.407387 -166.723126) (xy 21.430028 -166.772706)
			(xy 21.445383 -166.825003) (xy 21.453139 -166.878954) (xy 21.453138 -166.933458) (xy 21.445381 -166.987408)
			(xy 21.430024 -167.039705) (xy 21.407381 -167.089284) (xy 21.377913 -167.135136) (xy 21.342219 -167.176328)
			(xy 21.301026 -167.21202) (xy 21.255174 -167.241487) (xy 21.205594 -167.264128) (xy 21.153297 -167.279483)
			(xy 21.099346 -167.287239) (xy 21.072094 -167.287702) (xy 21.043475 -167.287173) (xy 20.986888 -167.27856)
			(xy 20.932218 -167.261604) (xy 20.906232 -167.249602) (xy 20.893916 -167.244072) (xy 20.867388 -167.239095)
			(xy 20.840484 -167.241247) (xy 20.815084 -167.250377) (xy 20.792967 -167.265846) (xy 20.775679 -167.286573)
			(xy 20.764429 -167.311108) (xy 20.760005 -167.337733) (xy 20.760944 -167.351202) (xy 20.762722 -167.388794)
			(xy 20.762251 -167.416048) (xy 20.754495 -167.47) (xy 20.739139 -167.522299) (xy 20.729234 -167.543988)
			(xy 23.966422 -167.543988) (xy 23.970493 -167.488366) (xy 23.982619 -167.433929) (xy 24.002542 -167.381838)
			(xy 24.029838 -167.333203) (xy 24.063924 -167.28906) (xy 24.104073 -167.250351) (xy 24.149431 -167.2179)
			(xy 24.199031 -167.192399) (xy 24.251815 -167.174392) (xy 24.306658 -167.164262) (xy 24.362392 -167.162225)
			(xy 24.417829 -167.168325) (xy 24.471786 -167.182431) (xy 24.523115 -167.204243) (xy 24.570721 -167.233297)
			(xy 24.613589 -167.268972) (xy 24.650806 -167.310509) (xy 24.681579 -167.357022) (xy 24.705251 -167.407519)
			(xy 24.721319 -167.460926) (xy 24.729439 -167.516102) (xy 24.729948 -167.543988) (xy 24.729439 -167.571874)
			(xy 24.721319 -167.62705) (xy 24.705251 -167.680457) (xy 24.681579 -167.730954) (xy 24.650806 -167.777467)
			(xy 24.613589 -167.819004) (xy 24.570721 -167.854679) (xy 24.523115 -167.883733) (xy 24.471786 -167.905545)
			(xy 24.417829 -167.919651) (xy 24.362392 -167.925751) (xy 24.306658 -167.923714) (xy 24.251815 -167.913584)
			(xy 24.199031 -167.895577) (xy 24.149431 -167.870076) (xy 24.104073 -167.837625) (xy 24.063924 -167.798916)
			(xy 24.029838 -167.754773) (xy 24.002542 -167.706138) (xy 23.982619 -167.654047) (xy 23.970493 -167.59961)
			(xy 23.966422 -167.543988) (xy 20.729234 -167.543988) (xy 20.716496 -167.571881) (xy 20.687028 -167.617736)
			(xy 20.651334 -167.65893) (xy 20.61014 -167.694625) (xy 20.564286 -167.724094) (xy 20.514704 -167.746737)
			(xy 20.462405 -167.762094) (xy 20.408453 -167.769851) (xy 20.353946 -167.769851) (xy 20.299993 -167.762093)
			(xy 20.247694 -167.746737) (xy 20.198113 -167.724093) (xy 20.152259 -167.694624) (xy 20.111065 -167.658929)
			(xy 20.075371 -167.617735) (xy 20.045903 -167.57188) (xy 20.023261 -167.522298) (xy 20.007905 -167.469999)
			(xy 20.000149 -167.416046) (xy 18.940526 -167.416046) (xy 18.940526 -168.126918) (xy 26.807412 -168.126918)
			(xy 26.811483 -168.071296) (xy 26.823609 -168.016859) (xy 26.843532 -167.964768) (xy 26.870828 -167.916133)
			(xy 26.904914 -167.87199) (xy 26.945063 -167.833281) (xy 26.990421 -167.80083) (xy 27.040021 -167.775329)
			(xy 27.092805 -167.757322) (xy 27.147648 -167.747192) (xy 27.203382 -167.745155) (xy 27.258819 -167.751255)
			(xy 27.312776 -167.765361) (xy 27.364105 -167.787173) (xy 27.411711 -167.816227) (xy 27.454579 -167.851902)
			(xy 27.491796 -167.893439) (xy 27.522569 -167.939952) (xy 27.545203 -167.988234) (xy 29.594808 -167.988234)
			(xy 29.598879 -167.932612) (xy 29.611005 -167.878175) (xy 29.630928 -167.826084) (xy 29.658224 -167.777449)
			(xy 29.69231 -167.733306) (xy 29.732459 -167.694597) (xy 29.777817 -167.662146) (xy 29.827417 -167.636645)
			(xy 29.880201 -167.618638) (xy 29.935044 -167.608508) (xy 29.990778 -167.606471) (xy 30.046215 -167.612571)
			(xy 30.100172 -167.626677) (xy 30.151501 -167.648489) (xy 30.199107 -167.677543) (xy 30.241975 -167.713218)
			(xy 30.245785 -167.71747) (xy 50.99304 -167.71747) (xy 50.993427 -167.690214) (xy 51.001189 -167.636258)
			(xy 51.016552 -167.583956) (xy 51.039201 -167.534372) (xy 51.068677 -167.488517) (xy 51.104379 -167.447323)
			(xy 51.145579 -167.41163) (xy 51.191441 -167.382164) (xy 51.241029 -167.359524) (xy 51.293334 -167.344173)
			(xy 51.347292 -167.336422) (xy 51.374548 -167.335962) (xy 51.402122 -167.336442) (xy 51.456695 -167.344388)
			(xy 51.509556 -167.360109) (xy 51.559603 -167.383276) (xy 51.605792 -167.413408) (xy 51.647163 -167.449875)
			(xy 51.665378 -167.470582) (xy 51.675276 -167.48148) (xy 51.699926 -167.497555) (xy 51.728134 -167.505939)
			(xy 51.757562 -167.505939) (xy 51.78577 -167.497555) (xy 51.81042 -167.48148) (xy 51.820318 -167.470582)
			(xy 51.838512 -167.449855) (xy 51.879885 -167.413387) (xy 51.926079 -167.383257) (xy 51.97613 -167.360094)
			(xy 52.028995 -167.344381) (xy 52.083572 -167.336445) (xy 52.111148 -167.335962) (xy 52.137649 -167.336415)
			(xy 52.19014 -167.343762) (xy 52.241107 -167.358307) (xy 52.289569 -167.37977) (xy 52.334592 -167.407737)
			(xy 52.355242 -167.424354) (xy 52.367396 -167.433784) (xy 52.395794 -167.445573) (xy 52.426411 -167.448397)
			(xy 52.456486 -167.442003) (xy 52.483306 -167.426967) (xy 52.504451 -167.404645) (xy 52.511706 -167.39108)
			(xy 52.523817 -167.367395) (xy 52.553737 -167.323413) (xy 52.589605 -167.28413) (xy 52.630693 -167.250345)
			(xy 52.653184 -167.23614) (xy 52.665431 -167.228248) (xy 52.685104 -167.206769) (xy 52.697907 -167.180607)
			(xy 52.702796 -167.151894) (xy 52.699373 -167.122969) (xy 52.694078 -167.109394) (xy 52.684593 -167.086182)
			(xy 52.671241 -167.03785) (xy 52.664511 -166.988161) (xy 52.664106 -166.96309) (xy 52.66454 -166.938021)
			(xy 52.671286 -166.888338) (xy 52.684614 -166.840004) (xy 52.694078 -166.816786) (xy 52.699333 -166.803207)
			(xy 52.702713 -166.774299) (xy 52.697811 -166.74561) (xy 52.685024 -166.719464) (xy 52.665389 -166.69798)
			(xy 52.653184 -166.69004) (xy 52.630024 -166.675514) (xy 52.587899 -166.640668) (xy 52.551317 -166.600041)
			(xy 52.521063 -166.554506) (xy 52.497786 -166.505039) (xy 52.481986 -166.452703) (xy 52.474001 -166.398619)
			(xy 52.474003 -166.34395) (xy 52.481993 -166.289867) (xy 52.497797 -166.237532) (xy 52.521079 -166.188067)
			(xy 52.551336 -166.142534) (xy 52.587922 -166.101911) (xy 52.630049 -166.067068) (xy 52.653184 -166.0525)
			(xy 52.66539 -166.044551) (xy 52.685063 -166.023088) (xy 52.697871 -165.996941) (xy 52.702771 -165.968241)
			(xy 52.699363 -165.939326) (xy 52.694078 -165.925754) (xy 52.684581 -165.902547) (xy 52.671233 -165.854213)
			(xy 52.664508 -165.804522) (xy 52.664106 -165.77945) (xy 52.664627 -165.751565) (xy 52.672939 -165.696418)
			(xy 52.689377 -165.643126) (xy 52.713575 -165.59288) (xy 52.744991 -165.546801) (xy 52.782924 -165.505919)
			(xy 52.826526 -165.471147) (xy 52.874824 -165.443262) (xy 52.926739 -165.422887) (xy 52.98111 -165.410477)
			(xy 53.036724 -165.40631) (xy 53.092338 -165.410477) (xy 53.146709 -165.422887) (xy 53.198624 -165.443262)
			(xy 53.246922 -165.471147) (xy 53.290524 -165.505919) (xy 53.328457 -165.546801) (xy 53.359873 -165.59288)
			(xy 53.384071 -165.643126) (xy 53.400509 -165.696418) (xy 53.408821 -165.751565) (xy 53.409342 -165.77945)
			(xy 53.408875 -165.806782) (xy 53.400906 -165.860863) (xy 53.385118 -165.913198) (xy 53.36185 -165.962662)
			(xy 53.331601 -166.008195) (xy 53.295022 -166.048817) (xy 53.252897 -166.083655) (xy 53.229764 -166.09822)
			(xy 53.217537 -166.106138) (xy 53.19787 -166.127612) (xy 53.185068 -166.153767) (xy 53.180173 -166.182472)
			(xy 53.183584 -166.211392) (xy 53.18887 -166.224966) (xy 53.198345 -166.248181) (xy 53.211701 -166.296512)
			(xy 53.218435 -166.346199) (xy 53.218842 -166.37127) (xy 53.218431 -166.39634) (xy 53.211677 -166.446023)
			(xy 53.198339 -166.494357) (xy 53.18887 -166.517574) (xy 53.183624 -166.531151) (xy 53.180262 -166.560051)
			(xy 53.185173 -166.588729) (xy 53.197961 -166.614863) (xy 53.217591 -166.636338) (xy 53.229764 -166.64432)
			(xy 53.252885 -166.658903) (xy 53.295003 -166.693747) (xy 53.331579 -166.734369) (xy 53.361829 -166.779898)
			(xy 53.385103 -166.829358) (xy 53.400902 -166.881688) (xy 53.408888 -166.935764) (xy 53.408889 -166.990426)
			(xy 53.400905 -167.044502) (xy 53.385107 -167.096832) (xy 53.361834 -167.146292) (xy 53.331585 -167.191823)
			(xy 53.29501 -167.232446) (xy 53.252893 -167.267291) (xy 53.229764 -167.28186) (xy 53.217509 -167.289739)
			(xy 53.197842 -167.311225) (xy 53.185043 -167.33739) (xy 53.180156 -167.366104) (xy 53.183577 -167.39503)
			(xy 53.18887 -167.408606) (xy 53.198357 -167.431817) (xy 53.211708 -167.480149) (xy 53.218438 -167.529838)
			(xy 53.218842 -167.55491) (xy 53.21837 -167.581752) (xy 53.210665 -167.634881) (xy 53.195416 -167.686354)
			(xy 53.172938 -167.735106) (xy 53.143697 -167.780127) (xy 53.108298 -167.820487) (xy 53.067473 -167.855349)
			(xy 53.022069 -167.883993) (xy 52.973024 -167.905824) (xy 52.947316 -167.913558) (xy 52.932841 -167.918276)
			(xy 52.907286 -167.934788) (xy 52.887726 -167.958092) (xy 52.875894 -167.986122) (xy 52.87284 -168.016393)
			(xy 52.878835 -168.046222) (xy 52.885594 -168.059862) (xy 52.900228 -168.088008) (xy 52.920955 -168.147959)
			(xy 52.931453 -168.210517) (xy 52.932076 -168.242234) (xy 52.931855 -168.260253) (xy 52.928421 -168.296128)
			(xy 52.925218 -168.313862) (xy 52.922936 -168.329077) (xy 52.926453 -168.359622) (xy 52.938901 -168.387736)
			(xy 52.959153 -168.410871) (xy 52.985373 -168.426931) (xy 53.000148 -168.43121) (xy 53.027191 -168.438611)
			(xy 53.078917 -168.460241) (xy 53.126922 -168.489205) (xy 53.170174 -168.52488) (xy 53.207741 -168.566499)
			(xy 53.238815 -168.613165) (xy 53.262728 -168.663876) (xy 53.278965 -168.71754) (xy 53.287177 -168.773001)
			(xy 53.287676 -168.801034) (xy 53.287254 -168.828288) (xy 53.279492 -168.882239) (xy 53.264131 -168.934537)
			(xy 53.241483 -168.984117) (xy 53.21201 -169.029968) (xy 53.176312 -169.071159) (xy 53.135115 -169.10685)
			(xy 53.089259 -169.136315) (xy 53.039675 -169.158954) (xy 52.987375 -169.174306) (xy 52.933422 -169.182058)
			(xy 52.906168 -169.182542) (xy 52.878594 -169.18205) (xy 52.824022 -169.174105) (xy 52.771161 -169.158387)
			(xy 52.721115 -169.135222) (xy 52.674925 -169.105093) (xy 52.633554 -169.068628) (xy 52.615338 -169.047922)
			(xy 52.60544 -169.037024) (xy 52.58079 -169.020949) (xy 52.552582 -169.012565) (xy 52.523154 -169.012565)
			(xy 52.494946 -169.020949) (xy 52.470296 -169.037024) (xy 52.460398 -169.047922) (xy 52.442183 -169.068628)
			(xy 52.400812 -169.105093) (xy 52.354622 -169.13522) (xy 52.304575 -169.158383) (xy 52.251714 -169.174099)
			(xy 52.197142 -169.182039) (xy 52.141994 -169.182039) (xy 52.087422 -169.174099) (xy 52.034561 -169.158383)
			(xy 51.984514 -169.13522) (xy 51.938324 -169.105093) (xy 51.896953 -169.068628) (xy 51.878738 -169.047922)
			(xy 51.86884 -169.037024) (xy 51.84419 -169.020949) (xy 51.815982 -169.012565) (xy 51.786554 -169.012565)
			(xy 51.758346 -169.020949) (xy 51.733696 -169.037024) (xy 51.723798 -169.047922) (xy 51.705596 -169.068642)
			(xy 51.664225 -169.10511) (xy 51.618033 -169.135241) (xy 51.567983 -169.158405) (xy 51.515119 -169.17412)
			(xy 51.460543 -169.182058) (xy 51.432968 -169.182542) (xy 51.405718 -169.182052) (xy 51.351772 -169.174292)
			(xy 51.299479 -169.158935) (xy 51.249904 -169.136292) (xy 51.204055 -169.106826) (xy 51.162866 -169.071135)
			(xy 51.127175 -169.029946) (xy 51.097709 -168.984098) (xy 51.075066 -168.934523) (xy 51.059708 -168.88223)
			(xy 51.051948 -168.828284) (xy 51.05146 -168.801034) (xy 51.052043 -168.773181) (xy 51.060161 -168.71807)
			(xy 51.0762 -168.664722) (xy 51.09982 -168.614272) (xy 51.130519 -168.567788) (xy 51.167647 -168.526258)
			(xy 51.210414 -168.490563) (xy 51.257914 -168.461461) (xy 51.309138 -168.439569) (xy 51.33594 -168.431972)
			(xy 51.350063 -168.427719) (xy 51.375204 -168.41232) (xy 51.394916 -168.390396) (xy 51.407566 -168.363764)
			(xy 51.412104 -168.334632) (xy 51.410616 -168.319958) (xy 51.408945 -168.306942) (xy 51.407166 -168.280757)
			(xy 51.40706 -168.267634) (xy 51.407158 -168.253485) (xy 51.409189 -168.225262) (xy 51.411124 -168.211246)
			(xy 51.412683 -168.197896) (xy 51.409585 -168.171209) (xy 51.39962 -168.146259) (xy 51.38348 -168.124781)
			(xy 51.362288 -168.108267) (xy 51.337516 -168.097867) (xy 51.324256 -168.095676) (xy 51.297113 -168.09153)
			(xy 51.244287 -168.076561) (xy 51.194152 -168.054174) (xy 51.147744 -168.024832) (xy 51.106021 -167.989141)
			(xy 51.069844 -167.947838) (xy 51.039961 -167.901777) (xy 51.016989 -167.851907) (xy 51.001402 -167.79926)
			(xy 50.993522 -167.744923) (xy 50.99304 -167.71747) (xy 30.245785 -167.71747) (xy 30.279192 -167.754755)
			(xy 30.309965 -167.801268) (xy 30.333637 -167.851765) (xy 30.349705 -167.905172) (xy 30.357825 -167.960348)
			(xy 30.358334 -167.988234) (xy 30.357825 -168.01612) (xy 30.349705 -168.071296) (xy 30.333637 -168.124703)
			(xy 30.309965 -168.1752) (xy 30.279192 -168.221713) (xy 30.241975 -168.26325) (xy 30.199107 -168.298925)
			(xy 30.151501 -168.327979) (xy 30.100172 -168.349791) (xy 30.046215 -168.363897) (xy 29.990778 -168.369997)
			(xy 29.935044 -168.36796) (xy 29.880201 -168.35783) (xy 29.827417 -168.339823) (xy 29.777817 -168.314322)
			(xy 29.732459 -168.281871) (xy 29.69231 -168.243162) (xy 29.658224 -168.199019) (xy 29.630928 -168.150384)
			(xy 29.611005 -168.098293) (xy 29.598879 -168.043856) (xy 29.594808 -167.988234) (xy 27.545203 -167.988234)
			(xy 27.546241 -167.990449) (xy 27.562309 -168.043856) (xy 27.570429 -168.099032) (xy 27.570938 -168.126918)
			(xy 27.570429 -168.154804) (xy 27.562309 -168.20998) (xy 27.546241 -168.263387) (xy 27.522569 -168.313884)
			(xy 27.491796 -168.360397) (xy 27.454579 -168.401934) (xy 27.411711 -168.437609) (xy 27.364105 -168.466663)
			(xy 27.312776 -168.488475) (xy 27.258819 -168.502581) (xy 27.203382 -168.508681) (xy 27.147648 -168.506644)
			(xy 27.092805 -168.496514) (xy 27.040021 -168.478507) (xy 26.990421 -168.453006) (xy 26.945063 -168.420555)
			(xy 26.904914 -168.381846) (xy 26.870828 -168.337703) (xy 26.843532 -168.289068) (xy 26.823609 -168.236977)
			(xy 26.811483 -168.18254) (xy 26.807412 -168.126918) (xy 18.940526 -168.126918) (xy 18.940526 -168.15562)
			(xy 18.97761 -168.166034) (xy 19.003729 -168.173819) (xy 19.053413 -168.196221) (xy 19.099102 -168.225931)
			(xy 19.139732 -168.262255) (xy 19.174353 -168.304347) (xy 19.202156 -168.351221) (xy 19.222493 -168.401784)
			(xy 19.234888 -168.454856) (xy 19.239053 -168.509197) (xy 19.234889 -168.563538) (xy 19.222495 -168.616609)
			(xy 19.203486 -168.663874) (xy 19.969224 -168.663874) (xy 19.973295 -168.608252) (xy 19.985421 -168.553815)
			(xy 20.005344 -168.501724) (xy 20.03264 -168.453089) (xy 20.066726 -168.408946) (xy 20.106875 -168.370237)
			(xy 20.152233 -168.337786) (xy 20.201833 -168.312285) (xy 20.254617 -168.294278) (xy 20.30946 -168.284148)
			(xy 20.365194 -168.282111) (xy 20.420631 -168.288211) (xy 20.474588 -168.302317) (xy 20.525917 -168.324129)
			(xy 20.573523 -168.353183) (xy 20.616391 -168.388858) (xy 20.653608 -168.430395) (xy 20.684381 -168.476908)
			(xy 20.708053 -168.527405) (xy 20.724121 -168.580812) (xy 20.725168 -168.587928) (xy 24.769316 -168.587928)
			(xy 24.773387 -168.532306) (xy 24.785513 -168.477869) (xy 24.805436 -168.425778) (xy 24.832732 -168.377143)
			(xy 24.866818 -168.333) (xy 24.906967 -168.294291) (xy 24.952325 -168.26184) (xy 25.001925 -168.236339)
			(xy 25.054709 -168.218332) (xy 25.109552 -168.208202) (xy 25.165286 -168.206165) (xy 25.220723 -168.212265)
			(xy 25.27468 -168.226371) (xy 25.326009 -168.248183) (xy 25.373615 -168.277237) (xy 25.416483 -168.312912)
			(xy 25.4537 -168.354449) (xy 25.484473 -168.400962) (xy 25.508145 -168.451459) (xy 25.524213 -168.504866)
			(xy 25.532333 -168.560042) (xy 25.532842 -168.587928) (xy 25.532333 -168.615814) (xy 25.524213 -168.67099)
			(xy 25.508145 -168.724397) (xy 25.484473 -168.774894) (xy 25.4537 -168.821407) (xy 25.416483 -168.862944)
			(xy 25.373615 -168.898619) (xy 25.326009 -168.927673) (xy 25.27468 -168.949485) (xy 25.220723 -168.963591)
			(xy 25.165286 -168.969691) (xy 25.109552 -168.967654) (xy 25.054709 -168.957524) (xy 25.001925 -168.939517)
			(xy 24.952325 -168.914016) (xy 24.906967 -168.881565) (xy 24.866818 -168.842856) (xy 24.832732 -168.798713)
			(xy 24.805436 -168.750078) (xy 24.785513 -168.697987) (xy 24.773387 -168.64355) (xy 24.769316 -168.587928)
			(xy 20.725168 -168.587928) (xy 20.732241 -168.635988) (xy 20.73275 -168.663874) (xy 20.732241 -168.69176)
			(xy 20.724121 -168.746936) (xy 20.708053 -168.800343) (xy 20.684381 -168.85084) (xy 20.653608 -168.897353)
			(xy 20.616391 -168.93889) (xy 20.573523 -168.974565) (xy 20.525917 -169.003619) (xy 20.490399 -169.018712)
			(xy 20.763482 -169.018712) (xy 20.767553 -168.96309) (xy 20.779679 -168.908653) (xy 20.799602 -168.856562)
			(xy 20.826898 -168.807927) (xy 20.860984 -168.763784) (xy 20.901133 -168.725075) (xy 20.946491 -168.692624)
			(xy 20.996091 -168.667123) (xy 21.048875 -168.649116) (xy 21.103718 -168.638986) (xy 21.159452 -168.636949)
			(xy 21.214889 -168.643049) (xy 21.268846 -168.657155) (xy 21.320175 -168.678967) (xy 21.367781 -168.708021)
			(xy 21.410649 -168.743696) (xy 21.447866 -168.785233) (xy 21.478639 -168.831746) (xy 21.502311 -168.882243)
			(xy 21.518379 -168.93565) (xy 21.526499 -168.990826) (xy 21.527008 -169.018712) (xy 21.526499 -169.046598)
			(xy 21.51894 -169.09796) (xy 32.975802 -169.09796) (xy 32.979873 -169.042338) (xy 32.991999 -168.987901)
			(xy 33.011922 -168.93581) (xy 33.039218 -168.887175) (xy 33.073304 -168.843032) (xy 33.113453 -168.804323)
			(xy 33.158811 -168.771872) (xy 33.208411 -168.746371) (xy 33.261195 -168.728364) (xy 33.316038 -168.718234)
			(xy 33.371772 -168.716197) (xy 33.427209 -168.722297) (xy 33.481166 -168.736403) (xy 33.532495 -168.758215)
			(xy 33.580101 -168.787269) (xy 33.622969 -168.822944) (xy 33.660186 -168.864481) (xy 33.690959 -168.910994)
			(xy 33.714631 -168.961491) (xy 33.730699 -169.014898) (xy 33.738819 -169.070074) (xy 33.739328 -169.09796)
			(xy 33.738819 -169.125846) (xy 33.730699 -169.181022) (xy 33.714631 -169.234429) (xy 33.690959 -169.284926)
			(xy 33.660186 -169.331439) (xy 33.622969 -169.372976) (xy 33.580101 -169.408651) (xy 33.532495 -169.437705)
			(xy 33.481166 -169.459517) (xy 33.427209 -169.473623) (xy 33.371772 -169.479723) (xy 33.316038 -169.477686)
			(xy 33.261195 -169.467556) (xy 33.208411 -169.449549) (xy 33.158811 -169.424048) (xy 33.113453 -169.391597)
			(xy 33.073304 -169.352888) (xy 33.039218 -169.308745) (xy 33.011922 -169.26011) (xy 32.991999 -169.208019)
			(xy 32.979873 -169.153582) (xy 32.975802 -169.09796) (xy 21.51894 -169.09796) (xy 21.518379 -169.101774)
			(xy 21.502311 -169.155181) (xy 21.478639 -169.205678) (xy 21.447866 -169.252191) (xy 21.410649 -169.293728)
			(xy 21.367781 -169.329403) (xy 21.320175 -169.358457) (xy 21.268846 -169.380269) (xy 21.214889 -169.394375)
			(xy 21.159452 -169.400475) (xy 21.103718 -169.398438) (xy 21.048875 -169.388308) (xy 20.996091 -169.370301)
			(xy 20.946491 -169.3448) (xy 20.901133 -169.312349) (xy 20.860984 -169.27364) (xy 20.826898 -169.229497)
			(xy 20.799602 -169.180862) (xy 20.779679 -169.128771) (xy 20.767553 -169.074334) (xy 20.763482 -169.018712)
			(xy 20.490399 -169.018712) (xy 20.474588 -169.025431) (xy 20.420631 -169.039537) (xy 20.365194 -169.045637)
			(xy 20.30946 -169.0436) (xy 20.254617 -169.03347) (xy 20.201833 -169.015463) (xy 20.152233 -168.989962)
			(xy 20.106875 -168.957511) (xy 20.066726 -168.918802) (xy 20.03264 -168.874659) (xy 20.005344 -168.826024)
			(xy 19.985421 -168.773933) (xy 19.973295 -168.719496) (xy 19.969224 -168.663874) (xy 19.203486 -168.663874)
			(xy 19.202159 -168.667173) (xy 19.174356 -168.714048) (xy 19.139736 -168.75614) (xy 19.099107 -168.792465)
			(xy 19.053418 -168.822176) (xy 19.003736 -168.844579) (xy 18.97761 -168.852342) (xy 18.940526 -168.862756)
			(xy 18.940526 -169.240454) (xy 18.984976 -169.246042) (xy 19.012335 -169.24993) (xy 19.06562 -169.264572)
			(xy 19.116236 -169.286746) (xy 19.163125 -169.315989) (xy 19.205305 -169.351689) (xy 19.241895 -169.3931)
			(xy 19.27213 -169.439354) (xy 19.295378 -169.489486) (xy 19.311152 -169.542447) (xy 19.319122 -169.59713)
			(xy 19.319122 -169.65239) (xy 19.318744 -169.654982) (xy 19.972272 -169.654982) (xy 19.976343 -169.59936)
			(xy 19.988469 -169.544923) (xy 20.008392 -169.492832) (xy 20.035688 -169.444197) (xy 20.069774 -169.400054)
			(xy 20.109923 -169.361345) (xy 20.155281 -169.328894) (xy 20.204881 -169.303393) (xy 20.257665 -169.285386)
			(xy 20.312508 -169.275256) (xy 20.368242 -169.273219) (xy 20.423679 -169.279319) (xy 20.477636 -169.293425)
			(xy 20.528965 -169.315237) (xy 20.576571 -169.344291) (xy 20.619439 -169.379966) (xy 20.656656 -169.421503)
			(xy 20.687429 -169.468016) (xy 20.711101 -169.518513) (xy 20.727169 -169.57192) (xy 20.735289 -169.627096)
			(xy 20.735798 -169.654982) (xy 20.735289 -169.682868) (xy 20.727169 -169.738044) (xy 20.711101 -169.791451)
			(xy 20.687429 -169.841948) (xy 20.681898 -169.850308) (xy 21.073362 -169.850308) (xy 21.077433 -169.794686)
			(xy 21.089559 -169.740249) (xy 21.109482 -169.688158) (xy 21.136778 -169.639523) (xy 21.170864 -169.59538)
			(xy 21.211013 -169.556671) (xy 21.256371 -169.52422) (xy 21.305971 -169.498719) (xy 21.358755 -169.480712)
			(xy 21.413598 -169.470582) (xy 21.469332 -169.468545) (xy 21.524769 -169.474645) (xy 21.572365 -169.487088)
			(xy 25.88082 -169.487088) (xy 25.884891 -169.431466) (xy 25.897017 -169.377029) (xy 25.91694 -169.324938)
			(xy 25.944236 -169.276303) (xy 25.978322 -169.23216) (xy 26.018471 -169.193451) (xy 26.063829 -169.161)
			(xy 26.113429 -169.135499) (xy 26.166213 -169.117492) (xy 26.221056 -169.107362) (xy 26.27679 -169.105325)
			(xy 26.332227 -169.111425) (xy 26.386184 -169.125531) (xy 26.437513 -169.147343) (xy 26.485119 -169.176397)
			(xy 26.527987 -169.212072) (xy 26.565204 -169.253609) (xy 26.595977 -169.300122) (xy 26.619649 -169.350619)
			(xy 26.635717 -169.404026) (xy 26.643837 -169.459202) (xy 26.644346 -169.487088) (xy 26.643837 -169.514974)
			(xy 26.635717 -169.57015) (xy 26.619649 -169.623557) (xy 26.595977 -169.674054) (xy 26.565204 -169.720567)
			(xy 26.527987 -169.762104) (xy 26.485119 -169.797779) (xy 26.47854 -169.801794) (xy 43.431209 -169.801794)
			(xy 43.435245 -169.718347) (xy 43.447317 -169.635679) (xy 43.46731 -169.554562) (xy 43.495039 -169.475753)
			(xy 43.530245 -169.399988) (xy 43.572599 -169.327975) (xy 43.621705 -169.260386) (xy 43.677106 -169.197852)
			(xy 43.738283 -169.140957) (xy 43.804666 -169.090231) (xy 43.875634 -169.04615) (xy 43.950526 -169.009124)
			(xy 44.028642 -168.979498) (xy 44.109252 -168.95755) (xy 44.191604 -168.943485) (xy 44.27493 -168.937433)
			(xy 44.35845 -168.939452) (xy 44.441386 -168.949522) (xy 44.522962 -168.96755) (xy 44.602418 -168.993367)
			(xy 44.679011 -169.026732) (xy 44.752027 -169.067333) (xy 44.820783 -169.114792) (xy 44.884637 -169.168665)
			(xy 44.942994 -169.22845) (xy 44.995309 -169.293587) (xy 45.041092 -169.36347) (xy 45.079917 -169.437445)
			(xy 45.111422 -169.514822) (xy 45.135311 -169.594879) (xy 45.151362 -169.676867) (xy 45.159425 -169.760022)
			(xy 45.15993 -169.801794) (xy 45.159425 -169.843566) (xy 45.151362 -169.926721) (xy 45.135311 -170.008709)
			(xy 45.111422 -170.088766) (xy 45.079917 -170.166143) (xy 45.041092 -170.240118) (xy 44.995309 -170.310001)
			(xy 44.942994 -170.375138) (xy 44.884637 -170.434923) (xy 44.820783 -170.488796) (xy 44.752027 -170.536255)
			(xy 44.679011 -170.576856) (xy 44.602418 -170.610221) (xy 44.522962 -170.636038) (xy 44.441386 -170.654066)
			(xy 44.35845 -170.664136) (xy 44.27493 -170.666155) (xy 44.191604 -170.660103) (xy 44.109252 -170.646038)
			(xy 44.028642 -170.62409) (xy 43.950526 -170.594464) (xy 43.875634 -170.557438) (xy 43.804666 -170.513357)
			(xy 43.738283 -170.462631) (xy 43.677106 -170.405736) (xy 43.621705 -170.343202) (xy 43.572599 -170.275613)
			(xy 43.530245 -170.2036) (xy 43.495039 -170.127835) (xy 43.46731 -170.049026) (xy 43.447317 -169.967909)
			(xy 43.435245 -169.885241) (xy 43.431209 -169.801794) (xy 26.47854 -169.801794) (xy 26.437513 -169.826833)
			(xy 26.386184 -169.848645) (xy 26.332227 -169.862751) (xy 26.27679 -169.868851) (xy 26.221056 -169.866814)
			(xy 26.166213 -169.856684) (xy 26.113429 -169.838677) (xy 26.063829 -169.813176) (xy 26.018471 -169.780725)
			(xy 25.978322 -169.742016) (xy 25.944236 -169.697873) (xy 25.91694 -169.649238) (xy 25.897017 -169.597147)
			(xy 25.884891 -169.54271) (xy 25.88082 -169.487088) (xy 21.572365 -169.487088) (xy 21.578726 -169.488751)
			(xy 21.630055 -169.510563) (xy 21.677661 -169.539617) (xy 21.720529 -169.575292) (xy 21.757746 -169.616829)
			(xy 21.788519 -169.663342) (xy 21.812191 -169.713839) (xy 21.828259 -169.767246) (xy 21.836379 -169.822422)
			(xy 21.836888 -169.850308) (xy 21.836379 -169.878194) (xy 21.828259 -169.93337) (xy 21.812191 -169.986777)
			(xy 21.788519 -170.037274) (xy 21.757746 -170.083787) (xy 21.720529 -170.125324) (xy 21.677661 -170.160999)
			(xy 21.630055 -170.190053) (xy 21.578726 -170.211865) (xy 21.524769 -170.225971) (xy 21.469332 -170.232071)
			(xy 21.413598 -170.230034) (xy 21.358755 -170.219904) (xy 21.305971 -170.201897) (xy 21.256371 -170.176396)
			(xy 21.211013 -170.143945) (xy 21.170864 -170.105236) (xy 21.136778 -170.061093) (xy 21.109482 -170.012458)
			(xy 21.089559 -169.960367) (xy 21.077433 -169.90593) (xy 21.073362 -169.850308) (xy 20.681898 -169.850308)
			(xy 20.656656 -169.888461) (xy 20.619439 -169.929998) (xy 20.576571 -169.965673) (xy 20.528965 -169.994727)
			(xy 20.477636 -170.016539) (xy 20.423679 -170.030645) (xy 20.368242 -170.036745) (xy 20.312508 -170.034708)
			(xy 20.257665 -170.024578) (xy 20.204881 -170.006571) (xy 20.155281 -169.98107) (xy 20.109923 -169.948619)
			(xy 20.069774 -169.90991) (xy 20.035688 -169.865767) (xy 20.008392 -169.817132) (xy 19.988469 -169.765041)
			(xy 19.976343 -169.710604) (xy 19.972272 -169.654982) (xy 19.318744 -169.654982) (xy 19.311152 -169.707072)
			(xy 19.295378 -169.760033) (xy 19.272131 -169.810165) (xy 19.241896 -169.85642) (xy 19.205306 -169.89783)
			(xy 19.163125 -169.93353) (xy 19.116237 -169.962773) (xy 19.065621 -169.984948) (xy 19.012336 -169.99959)
			(xy 18.984976 -170.00347) (xy 18.940526 -170.009058) (xy 18.940526 -170.67022) (xy 30.752032 -170.67022)
			(xy 30.756103 -170.614598) (xy 30.768229 -170.560161) (xy 30.788152 -170.50807) (xy 30.815448 -170.459435)
			(xy 30.849534 -170.415292) (xy 30.889683 -170.376583) (xy 30.935041 -170.344132) (xy 30.984641 -170.318631)
			(xy 31.037425 -170.300624) (xy 31.092268 -170.290494) (xy 31.148002 -170.288457) (xy 31.203439 -170.294557)
			(xy 31.257396 -170.308663) (xy 31.308725 -170.330475) (xy 31.356331 -170.359529) (xy 31.399199 -170.395204)
			(xy 31.436416 -170.436741) (xy 31.467189 -170.483254) (xy 31.490861 -170.533751) (xy 31.506929 -170.587158)
			(xy 31.515049 -170.642334) (xy 31.515558 -170.67022) (xy 31.515049 -170.698106) (xy 31.506929 -170.753282)
			(xy 31.490861 -170.806689) (xy 31.467676 -170.856148) (xy 50.017172 -170.856148) (xy 50.017649 -170.828574)
			(xy 50.025597 -170.774002) (xy 50.041318 -170.721142) (xy 50.064486 -170.671096) (xy 50.094617 -170.624907)
			(xy 50.131084 -170.583538) (xy 50.173128 -170.54785) (xy 50.196242 -170.532806) (xy 50.208147 -170.524733)
			(xy 50.227333 -170.503326) (xy 50.239787 -170.477417) (xy 50.244521 -170.449062) (xy 50.24116 -170.420513)
			(xy 50.229971 -170.394033) (xy 50.21184 -170.371725) (xy 50.200306 -170.363134) (xy 50.178981 -170.347755)
			(xy 50.140292 -170.312157) (xy 50.10686 -170.27158) (xy 50.079321 -170.226795) (xy 50.058196 -170.178651)
			(xy 50.043886 -170.128062) (xy 50.036663 -170.075985) (xy 50.036222 -170.049698) (xy 50.036708 -170.022447)
			(xy 50.044464 -169.968499) (xy 50.059819 -169.916204) (xy 50.082461 -169.866627) (xy 50.111927 -169.820777)
			(xy 50.147618 -169.779586) (xy 50.188809 -169.743895) (xy 50.234659 -169.714429) (xy 50.284236 -169.691787)
			(xy 50.336531 -169.676432) (xy 50.390479 -169.668676) (xy 50.444981 -169.668676) (xy 50.498929 -169.676432)
			(xy 50.551224 -169.691787) (xy 50.600801 -169.714429) (xy 50.646651 -169.743895) (xy 50.687842 -169.779586)
			(xy 50.723533 -169.820777) (xy 50.752999 -169.866627) (xy 50.775641 -169.916204) (xy 50.790996 -169.968499)
			(xy 50.798752 -170.022447) (xy 50.799238 -170.049698) (xy 50.798792 -170.077273) (xy 50.790838 -170.131847)
			(xy 50.775111 -170.184707) (xy 50.751938 -170.234752) (xy 50.721802 -170.280941) (xy 50.685331 -170.32231)
			(xy 50.643284 -170.357997) (xy 50.620168 -170.37304) (xy 50.608219 -170.381053) (xy 50.58903 -170.402473)
			(xy 50.576576 -170.428395) (xy 50.571846 -170.456762) (xy 50.575216 -170.485322) (xy 50.586418 -170.51181)
			(xy 50.599378 -170.527747) (xy 52.354526 -170.527747) (xy 52.354526 -170.473253) (xy 52.362281 -170.419314)
			(xy 52.377633 -170.367027) (xy 52.40027 -170.317458) (xy 52.429731 -170.271614) (xy 52.465416 -170.23043)
			(xy 52.506598 -170.194743) (xy 52.55244 -170.16528) (xy 52.602009 -170.14264) (xy 52.654294 -170.127285)
			(xy 52.708233 -170.119528) (xy 52.73548 -170.11904) (xy 52.765603 -170.119626) (xy 52.825098 -170.129104)
			(xy 52.882366 -170.147811) (xy 52.935983 -170.175284) (xy 52.984619 -170.210839) (xy 53.006244 -170.231816)
			(xy 53.015966 -170.241034) (xy 53.039128 -170.254479) (xy 53.064989 -170.261441) (xy 53.091771 -170.261441)
			(xy 53.117632 -170.254479) (xy 53.140794 -170.241034) (xy 53.150516 -170.231816) (xy 53.172113 -170.210806)
			(xy 53.220749 -170.175241) (xy 53.274373 -170.147766) (xy 53.331649 -170.129065) (xy 53.391154 -170.119603)
			(xy 53.42128 -170.11904) (xy 53.448537 -170.119406) (xy 53.502497 -170.127161) (xy 53.554804 -170.142517)
			(xy 53.604393 -170.165162) (xy 53.650254 -170.194633) (xy 53.691455 -170.230331) (xy 53.727155 -170.27153)
			(xy 53.756629 -170.317389) (xy 53.779276 -170.366977) (xy 53.794635 -170.419283) (xy 53.802393 -170.473243)
			(xy 53.802393 -170.527757) (xy 53.794635 -170.581717) (xy 53.779276 -170.634023) (xy 53.756629 -170.683611)
			(xy 53.727155 -170.72947) (xy 53.691455 -170.770669) (xy 53.650254 -170.806367) (xy 53.604393 -170.835838)
			(xy 53.554804 -170.858483) (xy 53.502497 -170.873839) (xy 53.448537 -170.881594) (xy 53.42128 -170.882056)
			(xy 53.391156 -170.881496) (xy 53.331659 -170.872012) (xy 53.274391 -170.853299) (xy 53.220775 -170.82582)
			(xy 53.172141 -170.79026) (xy 53.150516 -170.76928) (xy 53.140794 -170.760062) (xy 53.117632 -170.746617)
			(xy 53.091771 -170.739655) (xy 53.064989 -170.739655) (xy 53.039128 -170.746617) (xy 53.015966 -170.760062)
			(xy 53.006244 -170.76928) (xy 52.98462 -170.790261) (xy 52.935991 -170.82583) (xy 52.882375 -170.85331)
			(xy 52.825104 -170.872018) (xy 52.765604 -170.881488) (xy 52.73548 -170.882056) (xy 52.708233 -170.881472)
			(xy 52.654294 -170.873715) (xy 52.602009 -170.85836) (xy 52.55244 -170.83572) (xy 52.506598 -170.806257)
			(xy 52.465416 -170.77057) (xy 52.429731 -170.729386) (xy 52.40027 -170.683542) (xy 52.377633 -170.633973)
			(xy 52.362281 -170.581686) (xy 52.354526 -170.527747) (xy 50.599378 -170.527747) (xy 50.604562 -170.534121)
			(xy 50.616104 -170.542712) (xy 50.637453 -170.558059) (xy 50.676141 -170.593663) (xy 50.709571 -170.634245)
			(xy 50.737107 -170.679036) (xy 50.758228 -170.727185) (xy 50.772533 -170.777779) (xy 50.779751 -170.829859)
			(xy 50.780188 -170.856148) (xy 50.779702 -170.883399) (xy 50.771946 -170.937347) (xy 50.756591 -170.989642)
			(xy 50.733949 -171.039219) (xy 50.704483 -171.085069) (xy 50.668792 -171.12626) (xy 50.627601 -171.161951)
			(xy 50.581751 -171.191417) (xy 50.532174 -171.214059) (xy 50.479879 -171.229414) (xy 50.425931 -171.23717)
			(xy 50.371429 -171.23717) (xy 50.317481 -171.229414) (xy 50.265186 -171.214059) (xy 50.215609 -171.191417)
			(xy 50.169759 -171.161951) (xy 50.128568 -171.12626) (xy 50.092877 -171.085069) (xy 50.063411 -171.039219)
			(xy 50.040769 -170.989642) (xy 50.025414 -170.937347) (xy 50.017658 -170.883399) (xy 50.017172 -170.856148)
			(xy 31.467676 -170.856148) (xy 31.467189 -170.857186) (xy 31.436416 -170.903699) (xy 31.399199 -170.945236)
			(xy 31.356331 -170.980911) (xy 31.308725 -171.009965) (xy 31.257396 -171.031777) (xy 31.203439 -171.045883)
			(xy 31.148002 -171.051983) (xy 31.092268 -171.049946) (xy 31.037425 -171.039816) (xy 30.984641 -171.021809)
			(xy 30.935041 -170.996308) (xy 30.889683 -170.963857) (xy 30.849534 -170.925148) (xy 30.815448 -170.881005)
			(xy 30.788152 -170.83237) (xy 30.768229 -170.780279) (xy 30.756103 -170.725842) (xy 30.752032 -170.67022)
			(xy 18.940526 -170.67022) (xy 18.940526 -170.71975) (xy 17.316012 -172.344264) (xy 43.406818 -172.344264)
			(xy 43.406818 -172.259568) (xy 43.414869 -172.175254) (xy 43.430898 -172.092088) (xy 43.454759 -172.010821)
			(xy 43.486238 -171.932191) (xy 43.525049 -171.85691) (xy 43.570839 -171.785658) (xy 43.623195 -171.719082)
			(xy 43.681643 -171.657784) (xy 43.745653 -171.602319) (xy 43.814645 -171.55319) (xy 43.887995 -171.510841)
			(xy 43.965038 -171.475657) (xy 44.045077 -171.447955) (xy 44.127386 -171.427987) (xy 44.211221 -171.415934)
			(xy 44.295822 -171.411904) (xy 44.380423 -171.415934) (xy 44.464258 -171.427987) (xy 44.546567 -171.447955)
			(xy 44.626606 -171.475657) (xy 44.703649 -171.510841) (xy 44.776999 -171.55319) (xy 44.845991 -171.602319)
			(xy 44.910001 -171.657784) (xy 44.968449 -171.719082) (xy 45.020805 -171.785658) (xy 45.066595 -171.85691)
			(xy 45.105406 -171.932191) (xy 45.136885 -172.010821) (xy 45.160746 -172.092088) (xy 45.176775 -172.175254)
			(xy 45.184826 -172.259568) (xy 45.185173 -172.288752) (xy 48.725285 -172.288752) (xy 48.725285 -172.234248)
			(xy 48.733042 -172.180299) (xy 48.748399 -172.128003) (xy 48.771041 -172.078425) (xy 48.80051 -172.032574)
			(xy 48.836204 -171.991384) (xy 48.877396 -171.955693) (xy 48.923249 -171.926228) (xy 48.972829 -171.903589)
			(xy 49.025126 -171.888236) (xy 49.079076 -171.880483) (xy 49.106328 -171.880022) (xy 49.136703 -171.88062)
			(xy 49.196685 -171.89025) (xy 49.254384 -171.909263) (xy 49.308341 -171.937178) (xy 49.357193 -171.97329)
			(xy 49.37887 -171.994576) (xy 49.388621 -172.003887) (xy 49.411894 -172.017482) (xy 49.437911 -172.024524)
			(xy 49.464863 -172.024524) (xy 49.49088 -172.017482) (xy 49.514153 -172.003887) (xy 49.523904 -171.994576)
			(xy 49.54556 -171.973266) (xy 49.594415 -171.937152) (xy 49.648377 -171.909238) (xy 49.706081 -171.890229)
			(xy 49.766069 -171.880607) (xy 49.796446 -171.880022) (xy 49.823697 -171.880451) (xy 49.877644 -171.888213)
			(xy 49.929938 -171.903574) (xy 49.979513 -171.926219) (xy 50.025361 -171.955689) (xy 50.066549 -171.991383)
			(xy 50.102238 -172.032576) (xy 50.131703 -172.078428) (xy 50.133776 -172.082968) (xy 50.422554 -172.082968)
			(xy 50.426625 -172.027346) (xy 50.438751 -171.972909) (xy 50.458674 -171.920818) (xy 50.48597 -171.872183)
			(xy 50.520056 -171.82804) (xy 50.560205 -171.789331) (xy 50.605563 -171.75688) (xy 50.655163 -171.731379)
			(xy 50.707947 -171.713372) (xy 50.76279 -171.703242) (xy 50.818524 -171.701205) (xy 50.873961 -171.707305)
			(xy 50.927918 -171.721411) (xy 50.979247 -171.743223) (xy 51.026853 -171.772277) (xy 51.069721 -171.807952)
			(xy 51.106938 -171.849489) (xy 51.137711 -171.896002) (xy 51.161383 -171.946499) (xy 51.177451 -171.999906)
			(xy 51.185571 -172.055082) (xy 51.18608 -172.082968) (xy 51.185571 -172.110854) (xy 51.177451 -172.16603)
			(xy 51.161383 -172.219437) (xy 51.137711 -172.269934) (xy 51.106938 -172.316447) (xy 51.069721 -172.357984)
			(xy 51.026853 -172.393659) (xy 50.979247 -172.422713) (xy 50.927918 -172.444525) (xy 50.873961 -172.458631)
			(xy 50.818524 -172.464731) (xy 50.76279 -172.462694) (xy 50.707947 -172.452564) (xy 50.655163 -172.434557)
			(xy 50.605563 -172.409056) (xy 50.560205 -172.376605) (xy 50.520056 -172.337896) (xy 50.48597 -172.293753)
			(xy 50.458674 -172.245118) (xy 50.438751 -172.193027) (xy 50.426625 -172.13859) (xy 50.422554 -172.082968)
			(xy 50.133776 -172.082968) (xy 50.154342 -172.128006) (xy 50.169696 -172.180301) (xy 50.177452 -172.234249)
			(xy 50.177452 -172.288751) (xy 50.169696 -172.342699) (xy 50.154342 -172.394994) (xy 50.131703 -172.444572)
			(xy 50.102238 -172.490424) (xy 50.066549 -172.531617) (xy 50.025361 -172.567311) (xy 49.979513 -172.596781)
			(xy 49.929938 -172.619426) (xy 49.877644 -172.634787) (xy 49.823697 -172.642549) (xy 49.796446 -172.643038)
			(xy 49.76607 -172.642468) (xy 49.706086 -172.632833) (xy 49.648386 -172.613814) (xy 49.59443 -172.585893)
			(xy 49.545579 -172.549774) (xy 49.523904 -172.528484) (xy 49.514176 -172.519126) (xy 49.490915 -172.50545)
			(xy 49.464879 -172.498363) (xy 49.437895 -172.498363) (xy 49.411859 -172.50545) (xy 49.388598 -172.519126)
			(xy 49.37887 -172.528484) (xy 49.357174 -172.549751) (xy 49.30833 -172.585872) (xy 49.254379 -172.613795)
			(xy 49.196683 -172.632814) (xy 49.136703 -172.642447) (xy 49.106328 -172.643038) (xy 49.079076 -172.642517)
			(xy 49.025126 -172.634764) (xy 48.972829 -172.619411) (xy 48.923249 -172.596772) (xy 48.877396 -172.567307)
			(xy 48.836204 -172.531616) (xy 48.80051 -172.490426) (xy 48.771041 -172.444575) (xy 48.748399 -172.394997)
			(xy 48.733042 -172.342701) (xy 48.725285 -172.288752) (xy 45.185173 -172.288752) (xy 45.18533 -172.301916)
			(xy 45.184826 -172.344264) (xy 45.176775 -172.428578) (xy 45.160746 -172.511744) (xy 45.136885 -172.593011)
			(xy 45.105406 -172.671641) (xy 45.066595 -172.746922) (xy 45.020805 -172.818174) (xy 44.968449 -172.88475)
			(xy 44.910001 -172.946048) (xy 44.845991 -173.001513) (xy 44.776999 -173.050642) (xy 44.703649 -173.092991)
			(xy 44.626606 -173.128175) (xy 44.546567 -173.155877) (xy 44.464258 -173.175845) (xy 44.380423 -173.187898)
			(xy 44.295822 -173.191929) (xy 44.211221 -173.187898) (xy 44.127386 -173.175845) (xy 44.045077 -173.155877)
			(xy 43.965038 -173.128175) (xy 43.887995 -173.092991) (xy 43.814645 -173.050642) (xy 43.745653 -173.001513)
			(xy 43.681643 -172.946048) (xy 43.623195 -172.88475) (xy 43.570839 -172.818174) (xy 43.525049 -172.746922)
			(xy 43.486238 -172.671641) (xy 43.454759 -172.593011) (xy 43.430898 -172.511744) (xy 43.414869 -172.428578)
			(xy 43.406818 -172.344264) (xy 17.316012 -172.344264) (xy 14.867636 -174.79264) (xy 21.571964 -174.79264)
			(xy 21.576035 -174.737018) (xy 21.588161 -174.682581) (xy 21.608084 -174.63049) (xy 21.63538 -174.581855)
			(xy 21.669466 -174.537712) (xy 21.709615 -174.499003) (xy 21.754973 -174.466552) (xy 21.804573 -174.441051)
			(xy 21.857357 -174.423044) (xy 21.9122 -174.412914) (xy 21.967934 -174.410877) (xy 22.023371 -174.416977)
			(xy 22.077328 -174.431083) (xy 22.128657 -174.452895) (xy 22.176263 -174.481949) (xy 22.219131 -174.517624)
			(xy 22.256348 -174.559161) (xy 22.287121 -174.605674) (xy 22.310793 -174.656171) (xy 22.326861 -174.709578)
			(xy 22.334981 -174.764754) (xy 22.33549 -174.79264) (xy 22.334981 -174.820526) (xy 22.326861 -174.875702)
			(xy 22.314406 -174.9171) (xy 25.556462 -174.9171) (xy 25.560533 -174.861478) (xy 25.572659 -174.807041)
			(xy 25.592582 -174.75495) (xy 25.619878 -174.706315) (xy 25.653964 -174.662172) (xy 25.694113 -174.623463)
			(xy 25.739471 -174.591012) (xy 25.789071 -174.565511) (xy 25.841855 -174.547504) (xy 25.896698 -174.537374)
			(xy 25.952432 -174.535337) (xy 26.001635 -174.540751) (xy 48.944772 -174.540751) (xy 48.944772 -174.486249)
			(xy 48.952528 -174.432302) (xy 48.967883 -174.380008) (xy 48.990523 -174.330431) (xy 49.019988 -174.28458)
			(xy 49.055678 -174.24339) (xy 49.096867 -174.207698) (xy 49.142717 -174.178231) (xy 49.192293 -174.155588)
			(xy 49.244586 -174.140231) (xy 49.298533 -174.132473) (xy 49.325784 -174.131986) (xy 49.350659 -174.132354)
			(xy 49.399986 -174.138825) (xy 49.448052 -174.151659) (xy 49.494039 -174.170637) (xy 49.537167 -174.195438)
			(xy 49.557178 -174.210218) (xy 49.569675 -174.219055) (xy 49.598406 -174.229566) (xy 49.62896 -174.231114)
			(xy 49.658606 -174.223559) (xy 49.684693 -174.207578) (xy 49.704889 -174.184599) (xy 49.71161 -174.170848)
			(xy 49.723254 -174.14601) (xy 49.752631 -174.099682) (xy 49.788337 -174.058036) (xy 49.829637 -174.021931)
			(xy 49.875681 -173.99211) (xy 49.925519 -173.969188) (xy 49.978125 -173.953636) (xy 50.032416 -173.945775)
			(xy 50.059844 -173.945296) (xy 50.087093 -173.945777) (xy 50.141037 -173.953538) (xy 50.193327 -173.968898)
			(xy 50.242899 -173.991541) (xy 50.288745 -174.021009) (xy 50.32993 -174.056701) (xy 50.365617 -174.097891)
			(xy 50.39508 -174.143739) (xy 50.417718 -174.193314) (xy 50.433071 -174.245606) (xy 50.440826 -174.29955)
			(xy 50.440826 -174.35405) (xy 50.433071 -174.407994) (xy 50.417718 -174.460286) (xy 50.39508 -174.509861)
			(xy 50.365617 -174.555709) (xy 50.32993 -174.596899) (xy 50.288745 -174.632591) (xy 50.242899 -174.662059)
			(xy 50.193327 -174.684702) (xy 50.141037 -174.700062) (xy 50.087093 -174.707823) (xy 50.059844 -174.708312)
			(xy 50.03497 -174.707929) (xy 49.985643 -174.701462) (xy 49.937577 -174.688631) (xy 49.89159 -174.669656)
			(xy 49.848462 -174.644859) (xy 49.82845 -174.63008) (xy 49.815931 -174.621277) (xy 49.787208 -174.610762)
			(xy 49.75666 -174.60921) (xy 49.72702 -174.616758) (xy 49.700935 -174.632732) (xy 49.68074 -174.655703)
			(xy 49.674018 -174.66945) (xy 49.662351 -174.694277) (xy 49.632977 -174.740604) (xy 49.597274 -174.78225)
			(xy 49.555977 -174.818355) (xy 49.509937 -174.848178) (xy 49.460103 -174.871102) (xy 49.407499 -174.886657)
			(xy 49.353211 -174.894521) (xy 49.325784 -174.895002) (xy 49.298533 -174.894527) (xy 49.244586 -174.886769)
			(xy 49.192293 -174.871412) (xy 49.142717 -174.848769) (xy 49.096867 -174.819302) (xy 49.055678 -174.78361)
			(xy 49.019988 -174.74242) (xy 48.990523 -174.696569) (xy 48.967883 -174.646992) (xy 48.952528 -174.594698)
			(xy 48.944772 -174.540751) (xy 26.001635 -174.540751) (xy 26.007869 -174.541437) (xy 26.061826 -174.555543)
			(xy 26.113155 -174.577355) (xy 26.160761 -174.606409) (xy 26.203629 -174.642084) (xy 26.240846 -174.683621)
			(xy 26.271619 -174.730134) (xy 26.295291 -174.780631) (xy 26.311359 -174.834038) (xy 26.319479 -174.889214)
			(xy 26.319988 -174.9171) (xy 26.319479 -174.944986) (xy 26.311359 -175.000162) (xy 26.295291 -175.053569)
			(xy 26.271619 -175.104066) (xy 26.240846 -175.150579) (xy 26.203629 -175.192116) (xy 26.160761 -175.227791)
			(xy 26.113155 -175.256845) (xy 26.061826 -175.278657) (xy 26.007869 -175.292763) (xy 25.952432 -175.298863)
			(xy 25.896698 -175.296826) (xy 25.841855 -175.286696) (xy 25.789071 -175.268689) (xy 25.739471 -175.243188)
			(xy 25.694113 -175.210737) (xy 25.653964 -175.172028) (xy 25.619878 -175.127885) (xy 25.592582 -175.07925)
			(xy 25.572659 -175.027159) (xy 25.560533 -174.972722) (xy 25.556462 -174.9171) (xy 22.314406 -174.9171)
			(xy 22.310793 -174.929109) (xy 22.287121 -174.979606) (xy 22.256348 -175.026119) (xy 22.219131 -175.067656)
			(xy 22.176263 -175.103331) (xy 22.128657 -175.132385) (xy 22.077328 -175.154197) (xy 22.023371 -175.168303)
			(xy 21.967934 -175.174403) (xy 21.9122 -175.172366) (xy 21.857357 -175.162236) (xy 21.804573 -175.144229)
			(xy 21.754973 -175.118728) (xy 21.709615 -175.086277) (xy 21.669466 -175.047568) (xy 21.63538 -175.003425)
			(xy 21.608084 -174.95479) (xy 21.588161 -174.902699) (xy 21.576035 -174.848262) (xy 21.571964 -174.79264)
			(xy 14.867636 -174.79264) (xy 14.45006 -175.210216) (xy 20.264372 -175.210216) (xy 20.268443 -175.154594)
			(xy 20.280569 -175.100157) (xy 20.300492 -175.048066) (xy 20.327788 -174.999431) (xy 20.361874 -174.955288)
			(xy 20.402023 -174.916579) (xy 20.447381 -174.884128) (xy 20.496981 -174.858627) (xy 20.549765 -174.84062)
			(xy 20.604608 -174.83049) (xy 20.660342 -174.828453) (xy 20.715779 -174.834553) (xy 20.769736 -174.848659)
			(xy 20.821065 -174.870471) (xy 20.868671 -174.899525) (xy 20.911539 -174.9352) (xy 20.948756 -174.976737)
			(xy 20.979529 -175.02325) (xy 21.003201 -175.073747) (xy 21.019269 -175.127154) (xy 21.027389 -175.18233)
			(xy 21.027898 -175.210216) (xy 21.027389 -175.238102) (xy 21.019269 -175.293278) (xy 21.003201 -175.346685)
			(xy 20.979529 -175.397182) (xy 20.948756 -175.443695) (xy 20.911539 -175.485232) (xy 20.868671 -175.520907)
			(xy 20.821065 -175.549961) (xy 20.769736 -175.571773) (xy 20.715779 -175.585879) (xy 20.660342 -175.591979)
			(xy 20.604608 -175.589942) (xy 20.549765 -175.579812) (xy 20.496981 -175.561805) (xy 20.447381 -175.536304)
			(xy 20.402023 -175.503853) (xy 20.361874 -175.465144) (xy 20.327788 -175.421001) (xy 20.300492 -175.372366)
			(xy 20.280569 -175.320275) (xy 20.268443 -175.265838) (xy 20.264372 -175.210216) (xy 14.45006 -175.210216)
			(xy 14.291818 -175.368458) (xy 14.291818 -175.83404) (xy 23.37714 -175.83404) (xy 23.381229 -175.778158)
			(xy 23.393412 -175.723468) (xy 23.413428 -175.671134) (xy 23.440851 -175.622272) (xy 23.475096 -175.577924)
			(xy 23.515432 -175.539034) (xy 23.561002 -175.506432) (xy 23.610833 -175.480813) (xy 23.663863 -175.462721)
			(xy 23.718961 -175.452544) (xy 23.774955 -175.450498) (xy 23.83065 -175.456626) (xy 23.884859 -175.470798)
			(xy 23.936427 -175.492712) (xy 23.984255 -175.521901) (xy 24.027323 -175.557742) (xy 24.064713 -175.599472)
			(xy 24.095629 -175.646202) (xy 24.119412 -175.696935) (xy 24.135554 -175.750591) (xy 24.141855 -175.7934)
			(xy 25.541222 -175.7934) (xy 25.545293 -175.737778) (xy 25.557419 -175.683341) (xy 25.577342 -175.63125)
			(xy 25.604638 -175.582615) (xy 25.638724 -175.538472) (xy 25.678873 -175.499763) (xy 25.724231 -175.467312)
			(xy 25.773831 -175.441811) (xy 25.826615 -175.423804) (xy 25.881458 -175.413674) (xy 25.937192 -175.411637)
			(xy 25.992629 -175.417737) (xy 26.046586 -175.431843) (xy 26.097915 -175.453655) (xy 26.145521 -175.482709)
			(xy 26.156993 -175.492256) (xy 35.295733 -175.492256) (xy 35.295733 -175.437744) (xy 35.303491 -175.383786)
			(xy 35.31885 -175.331482) (xy 35.341497 -175.281896) (xy 35.370971 -175.236039) (xy 35.406671 -175.194842)
			(xy 35.447871 -175.159147) (xy 35.493731 -175.129678) (xy 35.54332 -175.107036) (xy 35.595625 -175.091683)
			(xy 35.649584 -175.08393) (xy 35.67684 -175.08347) (xy 35.70421 -175.083954) (xy 35.758389 -175.091765)
			(xy 35.810892 -175.107249) (xy 35.86064 -175.130087) (xy 35.906607 -175.159809) (xy 35.927538 -175.17745)
			(xy 35.938866 -175.186686) (xy 35.965423 -175.198862) (xy 35.99434 -175.203035) (xy 36.023257 -175.198862)
			(xy 36.049814 -175.186686) (xy 36.061142 -175.17745) (xy 36.082092 -175.159832) (xy 36.128059 -175.130116)
			(xy 36.177802 -175.107275) (xy 36.230299 -175.091779) (xy 36.284472 -175.083946) (xy 36.31184 -175.08347)
			(xy 36.339088 -175.084003) (xy 36.393028 -175.091764) (xy 36.445315 -175.107121) (xy 36.494884 -175.129763)
			(xy 36.540727 -175.159229) (xy 36.58191 -175.194918) (xy 36.617595 -175.236105) (xy 36.633929 -175.261524)
			(xy 51.230528 -175.261524) (xy 51.234599 -175.205902) (xy 51.246725 -175.151465) (xy 51.266648 -175.099374)
			(xy 51.293944 -175.050739) (xy 51.32803 -175.006596) (xy 51.368179 -174.967887) (xy 51.413537 -174.935436)
			(xy 51.463137 -174.909935) (xy 51.515921 -174.891928) (xy 51.570764 -174.881798) (xy 51.626498 -174.879761)
			(xy 51.681935 -174.885861) (xy 51.735892 -174.899967) (xy 51.787221 -174.921779) (xy 51.834827 -174.950833)
			(xy 51.877695 -174.986508) (xy 51.914912 -175.028045) (xy 51.945685 -175.074558) (xy 51.969357 -175.125055)
			(xy 51.985425 -175.178462) (xy 51.993545 -175.233638) (xy 51.994054 -175.261524) (xy 51.993957 -175.266858)
			(xy 52.228748 -175.266858) (xy 52.232819 -175.211236) (xy 52.244945 -175.156799) (xy 52.264868 -175.104708)
			(xy 52.292164 -175.056073) (xy 52.32625 -175.01193) (xy 52.366399 -174.973221) (xy 52.411757 -174.94077)
			(xy 52.461357 -174.915269) (xy 52.514141 -174.897262) (xy 52.568984 -174.887132) (xy 52.624718 -174.885095)
			(xy 52.680155 -174.891195) (xy 52.734112 -174.905301) (xy 52.785441 -174.927113) (xy 52.833047 -174.956167)
			(xy 52.875915 -174.991842) (xy 52.913132 -175.033379) (xy 52.943905 -175.079892) (xy 52.967577 -175.130389)
			(xy 52.983645 -175.183796) (xy 52.991765 -175.238972) (xy 52.992274 -175.266858) (xy 52.991765 -175.294744)
			(xy 52.983645 -175.34992) (xy 52.967577 -175.403327) (xy 52.943905 -175.453824) (xy 52.913132 -175.500337)
			(xy 52.875915 -175.541874) (xy 52.833047 -175.577549) (xy 52.785441 -175.606603) (xy 52.734112 -175.628415)
			(xy 52.680155 -175.642521) (xy 52.624718 -175.648621) (xy 52.568984 -175.646584) (xy 52.514141 -175.636454)
			(xy 52.461357 -175.618447) (xy 52.411757 -175.592946) (xy 52.366399 -175.560495) (xy 52.32625 -175.521786)
			(xy 52.292164 -175.477643) (xy 52.264868 -175.429008) (xy 52.244945 -175.376917) (xy 52.232819 -175.32248)
			(xy 52.228748 -175.266858) (xy 51.993957 -175.266858) (xy 51.993545 -175.28941) (xy 51.985425 -175.344586)
			(xy 51.969357 -175.397993) (xy 51.945685 -175.44849) (xy 51.914912 -175.495003) (xy 51.877695 -175.53654)
			(xy 51.834827 -175.572215) (xy 51.787221 -175.601269) (xy 51.735892 -175.623081) (xy 51.681935 -175.637187)
			(xy 51.626498 -175.643287) (xy 51.570764 -175.64125) (xy 51.515921 -175.63112) (xy 51.463137 -175.613113)
			(xy 51.413537 -175.587612) (xy 51.368179 -175.555161) (xy 51.32803 -175.516452) (xy 51.293944 -175.472309)
			(xy 51.266648 -175.423674) (xy 51.246725 -175.371583) (xy 51.234599 -175.317146) (xy 51.230528 -175.261524)
			(xy 36.633929 -175.261524) (xy 36.647056 -175.281951) (xy 36.669693 -175.331523) (xy 36.685045 -175.383811)
			(xy 36.6928 -175.437752) (xy 36.6928 -175.492248) (xy 36.685045 -175.546189) (xy 36.669693 -175.598477)
			(xy 36.647056 -175.648049) (xy 36.617595 -175.693895) (xy 36.58191 -175.735082) (xy 36.540727 -175.770771)
			(xy 36.494884 -175.800237) (xy 36.445315 -175.822879) (xy 36.393028 -175.838236) (xy 36.339088 -175.845997)
			(xy 36.31184 -175.846486) (xy 36.28447 -175.846) (xy 36.230292 -175.838187) (xy 36.177789 -175.822703)
			(xy 36.128042 -175.799866) (xy 36.082074 -175.770145) (xy 36.061142 -175.752506) (xy 36.049814 -175.74327)
			(xy 36.023257 -175.731094) (xy 35.99434 -175.726921) (xy 35.965423 -175.731094) (xy 35.938866 -175.74327)
			(xy 35.927538 -175.752506) (xy 35.906603 -175.770142) (xy 35.860631 -175.799854) (xy 35.810884 -175.82269)
			(xy 35.758384 -175.838182) (xy 35.704209 -175.846011) (xy 35.67684 -175.846486) (xy 35.649584 -175.84607)
			(xy 35.595625 -175.838317) (xy 35.54332 -175.822964) (xy 35.493731 -175.800322) (xy 35.447871 -175.770853)
			(xy 35.406671 -175.735158) (xy 35.370971 -175.693961) (xy 35.341497 -175.648104) (xy 35.31885 -175.598518)
			(xy 35.303491 -175.546214) (xy 35.295733 -175.492256) (xy 26.156993 -175.492256) (xy 26.188389 -175.518384)
			(xy 26.225606 -175.559921) (xy 26.256379 -175.606434) (xy 26.280051 -175.656931) (xy 26.296119 -175.710338)
			(xy 26.304239 -175.765514) (xy 26.304748 -175.7934) (xy 26.304239 -175.821286) (xy 26.296119 -175.876462)
			(xy 26.280051 -175.929869) (xy 26.256379 -175.980366) (xy 26.225606 -176.026879) (xy 26.188389 -176.068416)
			(xy 26.145521 -176.104091) (xy 26.097915 -176.133145) (xy 26.046586 -176.154957) (xy 25.992629 -176.169063)
			(xy 25.937192 -176.175163) (xy 25.881458 -176.173126) (xy 25.826615 -176.162996) (xy 25.773831 -176.144989)
			(xy 25.724231 -176.119488) (xy 25.678873 -176.087037) (xy 25.638724 -176.048328) (xy 25.604638 -176.004185)
			(xy 25.577342 -175.95555) (xy 25.557419 -175.903459) (xy 25.545293 -175.849022) (xy 25.541222 -175.7934)
			(xy 24.141855 -175.7934) (xy 24.143713 -175.806025) (xy 24.144224 -175.83404) (xy 24.143713 -175.862055)
			(xy 24.135554 -175.917489) (xy 24.119412 -175.971145) (xy 24.095629 -176.021878) (xy 24.064713 -176.068608)
			(xy 24.027323 -176.110338) (xy 23.984255 -176.146179) (xy 23.936427 -176.175368) (xy 23.923164 -176.181004)
			(xy 51.225448 -176.181004) (xy 51.229519 -176.125382) (xy 51.241645 -176.070945) (xy 51.261568 -176.018854)
			(xy 51.288864 -175.970219) (xy 51.32295 -175.926076) (xy 51.363099 -175.887367) (xy 51.408457 -175.854916)
			(xy 51.458057 -175.829415) (xy 51.510841 -175.811408) (xy 51.565684 -175.801278) (xy 51.621418 -175.799241)
			(xy 51.676855 -175.805341) (xy 51.730812 -175.819447) (xy 51.782141 -175.841259) (xy 51.829747 -175.870313)
			(xy 51.872615 -175.905988) (xy 51.909832 -175.947525) (xy 51.940605 -175.994038) (xy 51.964277 -176.044535)
			(xy 51.980345 -176.097942) (xy 51.988465 -176.153118) (xy 51.988974 -176.181004) (xy 51.988928 -176.183544)
			(xy 52.231542 -176.183544) (xy 52.235613 -176.127922) (xy 52.247739 -176.073485) (xy 52.267662 -176.021394)
			(xy 52.294958 -175.972759) (xy 52.329044 -175.928616) (xy 52.369193 -175.889907) (xy 52.414551 -175.857456)
			(xy 52.464151 -175.831955) (xy 52.516935 -175.813948) (xy 52.571778 -175.803818) (xy 52.627512 -175.801781)
			(xy 52.682949 -175.807881) (xy 52.736906 -175.821987) (xy 52.788235 -175.843799) (xy 52.835841 -175.872853)
			(xy 52.878709 -175.908528) (xy 52.915926 -175.950065) (xy 52.946699 -175.996578) (xy 52.970371 -176.047075)
			(xy 52.986439 -176.100482) (xy 52.994559 -176.155658) (xy 52.995068 -176.183544) (xy 52.994559 -176.21143)
			(xy 52.986439 -176.266606) (xy 52.970371 -176.320013) (xy 52.946699 -176.37051) (xy 52.915926 -176.417023)
			(xy 52.878709 -176.45856) (xy 52.835841 -176.494235) (xy 52.788235 -176.523289) (xy 52.736906 -176.545101)
			(xy 52.682949 -176.559207) (xy 52.627512 -176.565307) (xy 52.571778 -176.56327) (xy 52.516935 -176.55314)
			(xy 52.464151 -176.535133) (xy 52.414551 -176.509632) (xy 52.369193 -176.477181) (xy 52.329044 -176.438472)
			(xy 52.294958 -176.394329) (xy 52.267662 -176.345694) (xy 52.247739 -176.293603) (xy 52.235613 -176.239166)
			(xy 52.231542 -176.183544) (xy 51.988928 -176.183544) (xy 51.988465 -176.20889) (xy 51.980345 -176.264066)
			(xy 51.964277 -176.317473) (xy 51.940605 -176.36797) (xy 51.909832 -176.414483) (xy 51.872615 -176.45602)
			(xy 51.829747 -176.491695) (xy 51.782141 -176.520749) (xy 51.730812 -176.542561) (xy 51.676855 -176.556667)
			(xy 51.621418 -176.562767) (xy 51.565684 -176.56073) (xy 51.510841 -176.5506) (xy 51.458057 -176.532593)
			(xy 51.408457 -176.507092) (xy 51.363099 -176.474641) (xy 51.32295 -176.435932) (xy 51.288864 -176.391789)
			(xy 51.261568 -176.343154) (xy 51.241645 -176.291063) (xy 51.229519 -176.236626) (xy 51.225448 -176.181004)
			(xy 23.923164 -176.181004) (xy 23.884859 -176.197282) (xy 23.83065 -176.211454) (xy 23.774955 -176.217582)
			(xy 23.718961 -176.215536) (xy 23.663863 -176.205359) (xy 23.610833 -176.187267) (xy 23.561002 -176.161648)
			(xy 23.515432 -176.129046) (xy 23.475096 -176.090156) (xy 23.440851 -176.045808) (xy 23.413428 -175.996946)
			(xy 23.393412 -175.944612) (xy 23.381229 -175.889922) (xy 23.37714 -175.83404) (xy 14.291818 -175.83404)
			(xy 14.291818 -177.191416) (xy 20.962872 -177.191416) (xy 20.966943 -177.135794) (xy 20.979069 -177.081357)
			(xy 20.998992 -177.029266) (xy 21.026288 -176.980631) (xy 21.060374 -176.936488) (xy 21.100523 -176.897779)
			(xy 21.145881 -176.865328) (xy 21.195481 -176.839827) (xy 21.248265 -176.82182) (xy 21.303108 -176.81169)
			(xy 21.358842 -176.809653) (xy 21.414279 -176.815753) (xy 21.468236 -176.829859) (xy 21.519565 -176.851671)
			(xy 21.567171 -176.880725) (xy 21.610039 -176.9164) (xy 21.647256 -176.957937) (xy 21.678029 -177.00445)
			(xy 21.701701 -177.054947) (xy 21.716624 -177.104548) (xy 25.632662 -177.104548) (xy 25.636733 -177.048926)
			(xy 25.648859 -176.994489) (xy 25.668782 -176.942398) (xy 25.696078 -176.893763) (xy 25.730164 -176.84962)
			(xy 25.770313 -176.810911) (xy 25.815671 -176.77846) (xy 25.865271 -176.752959) (xy 25.918055 -176.734952)
			(xy 25.972898 -176.724822) (xy 26.028632 -176.722785) (xy 26.084069 -176.728885) (xy 26.138026 -176.742991)
			(xy 26.189355 -176.764803) (xy 26.236961 -176.793857) (xy 26.279829 -176.829532) (xy 26.317046 -176.871069)
			(xy 26.347819 -176.917582) (xy 26.353804 -176.930349) (xy 49.335704 -176.930349) (xy 49.335704 -176.875851)
			(xy 49.34346 -176.821908) (xy 49.358813 -176.769618) (xy 49.381452 -176.720045) (xy 49.410916 -176.674198)
			(xy 49.446604 -176.633011) (xy 49.48779 -176.597322) (xy 49.533636 -176.567857) (xy 49.583208 -176.545217)
			(xy 49.635498 -176.529862) (xy 49.689441 -176.522105) (xy 49.71669 -176.521618) (xy 49.74406 -176.522086)
			(xy 49.798239 -176.529902) (xy 49.850743 -176.545391) (xy 49.90049 -176.568232) (xy 49.946456 -176.597957)
			(xy 49.967388 -176.615598) (xy 49.978716 -176.624834) (xy 50.005273 -176.63701) (xy 50.03419 -176.641183)
			(xy 50.063107 -176.63701) (xy 50.089664 -176.624834) (xy 50.100992 -176.615598) (xy 50.121925 -176.597957)
			(xy 50.167893 -176.568233) (xy 50.217639 -176.545387) (xy 50.270141 -176.529891) (xy 50.324319 -176.522062)
			(xy 50.379061 -176.522062) (xy 50.433239 -176.529891) (xy 50.485741 -176.545387) (xy 50.535487 -176.568233)
			(xy 50.581455 -176.597957) (xy 50.602388 -176.615598) (xy 50.613716 -176.624834) (xy 50.640273 -176.63701)
			(xy 50.66919 -176.641183) (xy 50.698107 -176.63701) (xy 50.724664 -176.624834) (xy 50.735992 -176.615598)
			(xy 50.756916 -176.597949) (xy 50.802891 -176.568239) (xy 50.852641 -176.545405) (xy 50.905143 -176.529916)
			(xy 50.95932 -176.52209) (xy 50.98669 -176.521618) (xy 51.013944 -176.522065) (xy 51.067897 -176.529821)
			(xy 51.120196 -176.545177) (xy 51.169778 -176.56782) (xy 51.215633 -176.59729) (xy 51.256826 -176.632985)
			(xy 51.29252 -176.67418) (xy 51.321987 -176.720036) (xy 51.344629 -176.769619) (xy 51.359982 -176.821919)
			(xy 51.367736 -176.875872) (xy 51.368198 -176.903126) (xy 51.367748 -176.930497) (xy 51.359926 -176.984677)
			(xy 51.344433 -177.03718) (xy 51.321588 -177.086926) (xy 51.291861 -177.132893) (xy 51.274218 -177.153824)
			(xy 51.264955 -177.165132) (xy 51.252778 -177.191696) (xy 51.24861 -177.22062) (xy 51.252789 -177.249541)
			(xy 51.264976 -177.276101) (xy 51.274218 -177.287428) (xy 51.29184 -177.308374) (xy 51.321553 -177.354343)
			(xy 51.344392 -177.404087) (xy 51.359888 -177.456585) (xy 51.367721 -177.510758) (xy 51.368198 -177.538126)
			(xy 51.367746 -177.565378) (xy 51.359986 -177.619328) (xy 51.344627 -177.671624) (xy 51.321982 -177.721202)
			(xy 51.292512 -177.767053) (xy 51.256817 -177.808243) (xy 51.215624 -177.843934) (xy 51.16977 -177.873399)
			(xy 51.12019 -177.89604) (xy 51.067893 -177.911394) (xy 51.013942 -177.919149) (xy 50.98669 -177.919634)
			(xy 50.959319 -177.91919) (xy 50.905138 -177.911369) (xy 50.852634 -177.895876) (xy 50.802888 -177.873029)
			(xy 50.756922 -177.843298) (xy 50.735992 -177.825654) (xy 50.724664 -177.816418) (xy 50.698107 -177.804242)
			(xy 50.66919 -177.800069) (xy 50.640273 -177.804242) (xy 50.613716 -177.816418) (xy 50.602388 -177.825654)
			(xy 50.581428 -177.843258) (xy 50.535463 -177.872977) (xy 50.485723 -177.89582) (xy 50.433228 -177.911319)
			(xy 50.379057 -177.919156) (xy 50.35169 -177.919634) (xy 50.32444 -177.919132) (xy 50.270494 -177.911374)
			(xy 50.218201 -177.896019) (xy 50.168626 -177.873379) (xy 50.122776 -177.843914) (xy 50.081587 -177.808224)
			(xy 50.045896 -177.767036) (xy 50.016429 -177.721189) (xy 49.993786 -177.671614) (xy 49.978429 -177.619322)
			(xy 49.97067 -177.565376) (xy 49.970182 -177.538126) (xy 49.970663 -177.511891) (xy 49.977854 -177.459916)
			(xy 49.992105 -177.409419) (xy 50.013145 -177.361352) (xy 50.040578 -177.316625) (xy 50.073885 -177.276082)
			(xy 50.092864 -177.257964) (xy 50.100207 -177.250412) (xy 50.108638 -177.231137) (xy 50.108646 -177.210098)
			(xy 50.100228 -177.190817) (xy 50.092864 -177.183288) (xy 50.071528 -177.161952) (xy 50.063999 -177.15458)
			(xy 50.044714 -177.146149) (xy 50.023666 -177.146149) (xy 50.004381 -177.15458) (xy 49.996852 -177.161952)
			(xy 49.978741 -177.180941) (xy 49.938201 -177.214257) (xy 49.893474 -177.241698) (xy 49.845406 -177.262746)
			(xy 49.794905 -177.277002) (xy 49.742927 -177.284197) (xy 49.71669 -177.284634) (xy 49.689441 -177.284095)
			(xy 49.635498 -177.276338) (xy 49.583208 -177.260983) (xy 49.533636 -177.238343) (xy 49.48779 -177.208878)
			(xy 49.446604 -177.173189) (xy 49.410916 -177.132002) (xy 49.381452 -177.086155) (xy 49.358813 -177.036582)
			(xy 49.34346 -176.984292) (xy 49.335704 -176.930349) (xy 26.353804 -176.930349) (xy 26.371491 -176.968079)
			(xy 26.387559 -177.021486) (xy 26.395679 -177.076662) (xy 26.396188 -177.104548) (xy 26.395679 -177.132434)
			(xy 26.387559 -177.18761) (xy 26.371491 -177.241017) (xy 26.347819 -177.291514) (xy 26.317046 -177.338027)
			(xy 26.279829 -177.379564) (xy 26.236961 -177.415239) (xy 26.189355 -177.444293) (xy 26.138026 -177.466105)
			(xy 26.084069 -177.480211) (xy 26.028632 -177.486311) (xy 25.972898 -177.484274) (xy 25.918055 -177.474144)
			(xy 25.865271 -177.456137) (xy 25.815671 -177.430636) (xy 25.770313 -177.398185) (xy 25.730164 -177.359476)
			(xy 25.696078 -177.315333) (xy 25.668782 -177.266698) (xy 25.648859 -177.214607) (xy 25.636733 -177.16017)
			(xy 25.632662 -177.104548) (xy 21.716624 -177.104548) (xy 21.717769 -177.108354) (xy 21.725889 -177.16353)
			(xy 21.726398 -177.191416) (xy 21.725889 -177.219302) (xy 21.717769 -177.274478) (xy 21.701701 -177.327885)
			(xy 21.678029 -177.378382) (xy 21.647256 -177.424895) (xy 21.610039 -177.466432) (xy 21.567171 -177.502107)
			(xy 21.519565 -177.531161) (xy 21.468236 -177.552973) (xy 21.414279 -177.567079) (xy 21.358842 -177.573179)
			(xy 21.303108 -177.571142) (xy 21.248265 -177.561012) (xy 21.195481 -177.543005) (xy 21.145881 -177.517504)
			(xy 21.100523 -177.485053) (xy 21.060374 -177.446344) (xy 21.026288 -177.402201) (xy 20.998992 -177.353566)
			(xy 20.979069 -177.301475) (xy 20.966943 -177.247038) (xy 20.962872 -177.191416) (xy 14.291818 -177.191416)
			(xy 14.291818 -177.745644) (xy 24.330912 -177.745644) (xy 24.334983 -177.690022) (xy 24.347109 -177.635585)
			(xy 24.367032 -177.583494) (xy 24.394328 -177.534859) (xy 24.428414 -177.490716) (xy 24.468563 -177.452007)
			(xy 24.513921 -177.419556) (xy 24.563521 -177.394055) (xy 24.616305 -177.376048) (xy 24.671148 -177.365918)
			(xy 24.726882 -177.363881) (xy 24.782319 -177.369981) (xy 24.836276 -177.384087) (xy 24.887605 -177.405899)
			(xy 24.935211 -177.434953) (xy 24.978079 -177.470628) (xy 25.015296 -177.512165) (xy 25.023956 -177.525254)
			(xy 35.243449 -177.525254) (xy 35.243449 -177.470746) (xy 35.251207 -177.416793) (xy 35.266564 -177.364493)
			(xy 35.289208 -177.314911) (xy 35.318678 -177.269056) (xy 35.354374 -177.227863) (xy 35.395569 -177.192168)
			(xy 35.441425 -177.1627) (xy 35.491008 -177.140058) (xy 35.543308 -177.124704) (xy 35.597262 -177.116948)
			(xy 35.624516 -177.116486) (xy 35.651886 -177.116946) (xy 35.706066 -177.124766) (xy 35.758569 -177.140257)
			(xy 35.808315 -177.163099) (xy 35.854282 -177.192825) (xy 35.875214 -177.210466) (xy 35.886542 -177.219702)
			(xy 35.913099 -177.231878) (xy 35.942016 -177.236051) (xy 35.970933 -177.231878) (xy 35.99749 -177.219702)
			(xy 36.008818 -177.210466) (xy 36.029766 -177.192847) (xy 36.075735 -177.163133) (xy 36.125478 -177.140294)
			(xy 36.177975 -177.124798) (xy 36.232148 -177.116964) (xy 36.259516 -177.116486) (xy 36.286766 -177.116985)
			(xy 36.340711 -177.124743) (xy 36.393003 -177.140099) (xy 36.442578 -177.162741) (xy 36.488425 -177.192207)
			(xy 36.529613 -177.227898) (xy 36.565302 -177.269087) (xy 36.594767 -177.314936) (xy 36.617406 -177.364512)
			(xy 36.63276 -177.416804) (xy 36.640516 -177.47075) (xy 36.640516 -177.52525) (xy 36.63276 -177.579196)
			(xy 36.617406 -177.631488) (xy 36.594767 -177.681064) (xy 36.565302 -177.726913) (xy 36.529613 -177.768102)
			(xy 36.488425 -177.803793) (xy 36.442578 -177.833259) (xy 36.393003 -177.855901) (xy 36.340711 -177.871257)
			(xy 36.286766 -177.879015) (xy 36.259516 -177.879502) (xy 36.232146 -177.879026) (xy 36.177967 -177.871211)
			(xy 36.125464 -177.855724) (xy 36.075717 -177.832884) (xy 36.02975 -177.803162) (xy 36.008818 -177.785522)
			(xy 35.99749 -177.776286) (xy 35.970933 -177.76411) (xy 35.942016 -177.759937) (xy 35.913099 -177.76411)
			(xy 35.886542 -177.776286) (xy 35.875214 -177.785522) (xy 35.85429 -177.803171) (xy 35.808315 -177.832881)
			(xy 35.758565 -177.855715) (xy 35.706063 -177.871203) (xy 35.651886 -177.879029) (xy 35.624516 -177.879502)
			(xy 35.597262 -177.879052) (xy 35.543308 -177.871296) (xy 35.491008 -177.855942) (xy 35.441425 -177.8333)
			(xy 35.395569 -177.803832) (xy 35.354374 -177.768137) (xy 35.318678 -177.726944) (xy 35.289208 -177.681089)
			(xy 35.266564 -177.631507) (xy 35.251207 -177.579207) (xy 35.243449 -177.525254) (xy 25.023956 -177.525254)
			(xy 25.046069 -177.558678) (xy 25.069741 -177.609175) (xy 25.085809 -177.662582) (xy 25.093929 -177.717758)
			(xy 25.094438 -177.745644) (xy 25.093929 -177.77353) (xy 25.085809 -177.828706) (xy 25.069741 -177.882113)
			(xy 25.046069 -177.93261) (xy 25.015296 -177.979123) (xy 24.978079 -178.02066) (xy 24.935211 -178.056335)
			(xy 24.887605 -178.085389) (xy 24.836276 -178.107201) (xy 24.782319 -178.121307) (xy 24.726882 -178.127407)
			(xy 24.671148 -178.12537) (xy 24.616305 -178.11524) (xy 24.563521 -178.097233) (xy 24.513921 -178.071732)
			(xy 24.468563 -178.039281) (xy 24.428414 -178.000572) (xy 24.394328 -177.956429) (xy 24.367032 -177.907794)
			(xy 24.347109 -177.855703) (xy 24.334983 -177.801266) (xy 24.330912 -177.745644) (xy 14.291818 -177.745644)
			(xy 14.291818 -178.265328) (xy 19.450302 -178.265328) (xy 19.454373 -178.209706) (xy 19.466499 -178.155269)
			(xy 19.486422 -178.103178) (xy 19.513718 -178.054543) (xy 19.547804 -178.0104) (xy 19.587953 -177.971691)
			(xy 19.633311 -177.93924) (xy 19.682911 -177.913739) (xy 19.735695 -177.895732) (xy 19.790538 -177.885602)
			(xy 19.846272 -177.883565) (xy 19.901709 -177.889665) (xy 19.955666 -177.903771) (xy 20.006995 -177.925583)
			(xy 20.054601 -177.954637) (xy 20.097469 -177.990312) (xy 20.134686 -178.031849) (xy 20.165459 -178.078362)
			(xy 20.189131 -178.128859) (xy 20.205199 -178.182266) (xy 20.213319 -178.237442) (xy 20.213828 -178.265328)
			(xy 20.213319 -178.293214) (xy 20.205199 -178.34839) (xy 20.189131 -178.401797) (xy 20.165459 -178.452294)
			(xy 20.134686 -178.498807) (xy 20.097469 -178.540344) (xy 20.054601 -178.576019) (xy 20.006995 -178.605073)
			(xy 19.955666 -178.626885) (xy 19.901709 -178.640991) (xy 19.846272 -178.647091) (xy 19.790538 -178.645054)
			(xy 19.735695 -178.634924) (xy 19.682911 -178.616917) (xy 19.633311 -178.591416) (xy 19.587953 -178.558965)
			(xy 19.547804 -178.520256) (xy 19.513718 -178.476113) (xy 19.486422 -178.427478) (xy 19.466499 -178.375387)
			(xy 19.454373 -178.32095) (xy 19.450302 -178.265328) (xy 14.291818 -178.265328) (xy 14.291818 -179.105814)
			(xy 20.700998 -179.105814) (xy 20.705069 -179.050192) (xy 20.717195 -178.995755) (xy 20.737118 -178.943664)
			(xy 20.764414 -178.895029) (xy 20.7985 -178.850886) (xy 20.838649 -178.812177) (xy 20.884007 -178.779726)
			(xy 20.933607 -178.754225) (xy 20.986391 -178.736218) (xy 21.041234 -178.726088) (xy 21.096968 -178.724051)
			(xy 21.152405 -178.730151) (xy 21.206362 -178.744257) (xy 21.257691 -178.766069) (xy 21.305297 -178.795123)
			(xy 21.348165 -178.830798) (xy 21.385382 -178.872335) (xy 21.416155 -178.918848) (xy 21.439827 -178.969345)
			(xy 21.455895 -179.022752) (xy 21.464015 -179.077928) (xy 21.464524 -179.105814) (xy 21.464015 -179.1337)
			(xy 21.455895 -179.188876) (xy 21.439827 -179.242283) (xy 21.416155 -179.29278) (xy 21.385382 -179.339293)
			(xy 21.348165 -179.38083) (xy 21.305297 -179.416505) (xy 21.257691 -179.445559) (xy 21.206362 -179.467371)
			(xy 21.152405 -179.481477) (xy 21.096968 -179.487577) (xy 21.041234 -179.48554) (xy 20.986391 -179.47541)
			(xy 20.933607 -179.457403) (xy 20.884007 -179.431902) (xy 20.838649 -179.399451) (xy 20.7985 -179.360742)
			(xy 20.764414 -179.316599) (xy 20.737118 -179.267964) (xy 20.717195 -179.215873) (xy 20.705069 -179.161436)
			(xy 20.700998 -179.105814) (xy 14.291818 -179.105814) (xy 14.291818 -179.563354) (xy 35.249545 -179.563354)
			(xy 35.249545 -179.508846) (xy 35.257302 -179.454892) (xy 35.272659 -179.402592) (xy 35.295303 -179.35301)
			(xy 35.324773 -179.307155) (xy 35.360469 -179.265961) (xy 35.401665 -179.230266) (xy 35.44752 -179.200798)
			(xy 35.497103 -179.178155) (xy 35.549404 -179.1628) (xy 35.603358 -179.155044) (xy 35.630612 -179.154582)
			(xy 35.657983 -179.155021) (xy 35.712164 -179.162842) (xy 35.764669 -179.178337) (xy 35.814415 -179.201185)
			(xy 35.86038 -179.230917) (xy 35.88131 -179.248562) (xy 35.892638 -179.257798) (xy 35.919195 -179.269974)
			(xy 35.948112 -179.274147) (xy 35.977029 -179.269974) (xy 36.003586 -179.257798) (xy 36.014914 -179.248562)
			(xy 36.035863 -179.230943) (xy 36.081831 -179.20123) (xy 36.131575 -179.17839) (xy 36.184072 -179.162894)
			(xy 36.238244 -179.155059) (xy 36.265612 -179.154582) (xy 36.292862 -179.155089) (xy 36.346807 -179.162847)
			(xy 36.399099 -179.178203) (xy 36.448673 -179.200844) (xy 36.494521 -179.23031) (xy 36.535708 -179.266)
			(xy 36.571398 -179.307189) (xy 36.600862 -179.353037) (xy 36.623502 -179.402612) (xy 36.638856 -179.454905)
			(xy 36.646612 -179.50885) (xy 36.646612 -179.56335) (xy 36.646611 -179.563354) (xy 40.532745 -179.563354)
			(xy 40.532745 -179.508846) (xy 40.540502 -179.454892) (xy 40.555859 -179.402592) (xy 40.578503 -179.35301)
			(xy 40.607973 -179.307155) (xy 40.643669 -179.265961) (xy 40.684865 -179.230266) (xy 40.73072 -179.200798)
			(xy 40.780303 -179.178155) (xy 40.832604 -179.1628) (xy 40.886558 -179.155044) (xy 40.913812 -179.154582)
			(xy 40.941183 -179.155021) (xy 40.995364 -179.162842) (xy 41.047869 -179.178337) (xy 41.097615 -179.201185)
			(xy 41.14358 -179.230917) (xy 41.16451 -179.248562) (xy 41.175838 -179.257798) (xy 41.202395 -179.269974)
			(xy 41.231312 -179.274147) (xy 41.260229 -179.269974) (xy 41.286786 -179.257798) (xy 41.298114 -179.248562)
			(xy 41.319063 -179.230943) (xy 41.365031 -179.20123) (xy 41.414775 -179.17839) (xy 41.467272 -179.162894)
			(xy 41.521444 -179.155059) (xy 41.548812 -179.154582) (xy 41.576062 -179.155089) (xy 41.630007 -179.162847)
			(xy 41.682299 -179.178203) (xy 41.731873 -179.200844) (xy 41.777721 -179.23031) (xy 41.818908 -179.266)
			(xy 41.854598 -179.307189) (xy 41.884062 -179.353037) (xy 41.906702 -179.402612) (xy 41.922056 -179.454905)
			(xy 41.929812 -179.50885) (xy 41.929812 -179.56335) (xy 41.922056 -179.617295) (xy 41.906702 -179.669588)
			(xy 41.884062 -179.719163) (xy 41.854598 -179.765011) (xy 41.818908 -179.8062) (xy 41.777721 -179.84189)
			(xy 41.731873 -179.871356) (xy 41.682299 -179.893997) (xy 41.630007 -179.909353) (xy 41.576062 -179.917111)
			(xy 41.548812 -179.917598) (xy 41.521442 -179.917125) (xy 41.467263 -179.909309) (xy 41.41476 -179.893822)
			(xy 41.365013 -179.870981) (xy 41.319046 -179.841258) (xy 41.298114 -179.823618) (xy 41.286786 -179.814382)
			(xy 41.260229 -179.802206) (xy 41.231312 -179.798033) (xy 41.202395 -179.802206) (xy 41.175838 -179.814382)
			(xy 41.16451 -179.823618) (xy 41.143587 -179.841269) (xy 41.097612 -179.870978) (xy 41.047862 -179.893812)
			(xy 40.995359 -179.9093) (xy 40.941182 -179.917125) (xy 40.913812 -179.917598) (xy 40.886558 -179.917156)
			(xy 40.832604 -179.9094) (xy 40.780303 -179.894045) (xy 40.73072 -179.871402) (xy 40.684865 -179.841934)
			(xy 40.643669 -179.806239) (xy 40.607973 -179.765045) (xy 40.578503 -179.71919) (xy 40.555859 -179.669608)
			(xy 40.540502 -179.617308) (xy 40.532745 -179.563354) (xy 36.646611 -179.563354) (xy 36.638856 -179.617295)
			(xy 36.623502 -179.669588) (xy 36.600862 -179.719163) (xy 36.571398 -179.765011) (xy 36.535708 -179.8062)
			(xy 36.494521 -179.84189) (xy 36.448673 -179.871356) (xy 36.399099 -179.893997) (xy 36.346807 -179.909353)
			(xy 36.292862 -179.917111) (xy 36.265612 -179.917598) (xy 36.238242 -179.917125) (xy 36.184063 -179.909309)
			(xy 36.13156 -179.893822) (xy 36.081813 -179.870981) (xy 36.035846 -179.841258) (xy 36.014914 -179.823618)
			(xy 36.003586 -179.814382) (xy 35.977029 -179.802206) (xy 35.948112 -179.798033) (xy 35.919195 -179.802206)
			(xy 35.892638 -179.814382) (xy 35.88131 -179.823618) (xy 35.860387 -179.841269) (xy 35.814412 -179.870978)
			(xy 35.764662 -179.893812) (xy 35.712159 -179.9093) (xy 35.657982 -179.917125) (xy 35.630612 -179.917598)
			(xy 35.603358 -179.917156) (xy 35.549404 -179.9094) (xy 35.497103 -179.894045) (xy 35.44752 -179.871402)
			(xy 35.401665 -179.841934) (xy 35.360469 -179.806239) (xy 35.324773 -179.765045) (xy 35.295303 -179.71919)
			(xy 35.272659 -179.669608) (xy 35.257302 -179.617308) (xy 35.249545 -179.563354) (xy 14.291818 -179.563354)
			(xy 14.291818 -181.176422) (xy 56.742582 -181.176422) (xy 56.746653 -181.1208) (xy 56.758779 -181.066363)
			(xy 56.778702 -181.014272) (xy 56.805998 -180.965637) (xy 56.840084 -180.921494) (xy 56.880233 -180.882785)
			(xy 56.925591 -180.850334) (xy 56.975191 -180.824833) (xy 57.027975 -180.806826) (xy 57.082818 -180.796696)
			(xy 57.138552 -180.794659) (xy 57.193989 -180.800759) (xy 57.247946 -180.814865) (xy 57.299275 -180.836677)
			(xy 57.346881 -180.865731) (xy 57.389749 -180.901406) (xy 57.426966 -180.942943) (xy 57.457739 -180.989456)
			(xy 57.481411 -181.039953) (xy 57.497479 -181.09336) (xy 57.505599 -181.148536) (xy 57.506108 -181.176422)
			(xy 57.505599 -181.204308) (xy 57.497479 -181.259484) (xy 57.481411 -181.312891) (xy 57.457739 -181.363388)
			(xy 57.426966 -181.409901) (xy 57.389749 -181.451438) (xy 57.346881 -181.487113) (xy 57.299275 -181.516167)
			(xy 57.247946 -181.537979) (xy 57.193989 -181.552085) (xy 57.138552 -181.558185) (xy 57.082818 -181.556148)
			(xy 57.027975 -181.546018) (xy 56.975191 -181.528011) (xy 56.925591 -181.50251) (xy 56.880233 -181.470059)
			(xy 56.840084 -181.43135) (xy 56.805998 -181.387207) (xy 56.778702 -181.338572) (xy 56.758779 -181.286481)
			(xy 56.746653 -181.232044) (xy 56.742582 -181.176422) (xy 14.291818 -181.176422) (xy 14.291818 -181.713378)
			(xy 14.533372 -181.954932) (xy 23.963628 -181.954932) (xy 23.967699 -181.89931) (xy 23.979825 -181.844873)
			(xy 23.999748 -181.792782) (xy 24.027044 -181.744147) (xy 24.06113 -181.700004) (xy 24.101279 -181.661295)
			(xy 24.146637 -181.628844) (xy 24.196237 -181.603343) (xy 24.249021 -181.585336) (xy 24.303864 -181.575206)
			(xy 24.359598 -181.573169) (xy 24.415035 -181.579269) (xy 24.468992 -181.593375) (xy 24.520321 -181.615187)
			(xy 24.567927 -181.644241) (xy 24.610795 -181.679916) (xy 24.648012 -181.721453) (xy 24.678785 -181.767966)
			(xy 24.702457 -181.818463) (xy 24.718525 -181.87187) (xy 24.726645 -181.927046) (xy 24.727154 -181.954932)
			(xy 24.726645 -181.982818) (xy 24.718525 -182.037994) (xy 24.702457 -182.091401) (xy 24.678785 -182.141898)
			(xy 24.648012 -182.188411) (xy 24.610795 -182.229948) (xy 24.567927 -182.265623) (xy 24.520321 -182.294677)
			(xy 24.468992 -182.316489) (xy 24.415035 -182.330595) (xy 24.359598 -182.336695) (xy 24.303864 -182.334658)
			(xy 24.249021 -182.324528) (xy 24.196237 -182.306521) (xy 24.146637 -182.28102) (xy 24.101279 -182.248569)
			(xy 24.06113 -182.20986) (xy 24.027044 -182.165717) (xy 23.999748 -182.117082) (xy 23.979825 -182.064991)
			(xy 23.967699 -182.010554) (xy 23.963628 -181.954932) (xy 14.533372 -181.954932) (xy 16.113506 -183.535066)
		)
		(stroke
			(width 0)
			(type solid)
		)
		(fill yes)
		(layer "In11.Cu")
		(net "GND")
	)
	(gr_poly
		(pts
			(xy 364.277148 -82.443828) (xy 364.291585 -82.443318) (xy 364.319303 -82.435225) (xy 364.343648 -82.419699)
			(xy 364.362676 -82.397981) (xy 364.374866 -82.371805) (xy 364.379245 -82.343264) (xy 364.375462 -82.314638)
			(xy 364.36382 -82.288215) (xy 364.345248 -82.266104) (xy 364.333536 -82.257646) (xy 364.302615 -82.236491)
			(xy 364.244656 -82.189009) (xy 364.191637 -82.136067) (xy 364.14407 -82.078178) (xy 364.102414 -82.0159)
			(xy 364.06707 -81.949834) (xy 364.038381 -81.880619) (xy 364.016623 -81.808922) (xy 364.002006 -81.735436)
			(xy 363.994672 -81.660871) (xy 363.994192 -81.623408) (xy 363.994776 -81.580567) (xy 364.004381 -81.495424)
			(xy 364.023461 -81.411893) (xy 364.051774 -81.331024) (xy 364.088966 -81.253834) (xy 364.111286 -81.217262)
			(xy 364.092305 -81.18279) (xy 364.060742 -81.110698) (xy 364.036763 -81.035741) (xy 364.020625 -80.958715)
			(xy 364.012498 -80.880437) (xy 364.011972 -80.841088) (xy 364.012479 -80.801124) (xy 364.020841 -80.721634)
			(xy 364.037472 -80.643454) (xy 364.062189 -80.567444) (xy 364.094722 -80.494435) (xy 364.134713 -80.425231)
			(xy 364.181724 -80.360589) (xy 364.235239 -80.301219) (xy 364.29467 -80.247773) (xy 364.359366 -80.200836)
			(xy 364.393734 -80.180434) (xy 364.396571 -80.148027) (xy 364.41189 -80.084809) (xy 364.424214 -80.054704)
			(xy 364.390456 -80.034134) (xy 364.326961 -79.987037) (xy 364.268678 -79.933623) (xy 364.216233 -79.874468)
			(xy 364.170188 -79.810205) (xy 364.131038 -79.741523) (xy 364.099202 -79.669161) (xy 364.075023 -79.593893)
			(xy 364.058759 -79.516528) (xy 364.050584 -79.437896) (xy 364.050072 -79.398368) (xy 364.050517 -79.361538)
			(xy 364.057621 -79.28822) (xy 364.071761 -79.215929) (xy 364.092804 -79.145338) (xy 364.120554 -79.077105)
			(xy 364.154754 -79.011865) (xy 364.174532 -78.980792) (xy 364.153915 -78.945223) (xy 364.119581 -78.870518)
			(xy 364.093486 -78.792553) (xy 364.075935 -78.712231) (xy 364.067131 -78.630487) (xy 364.066582 -78.589378)
			(xy 364.067108 -78.548706) (xy 364.075773 -78.467824) (xy 364.093002 -78.388325) (xy 364.118598 -78.311113)
			(xy 364.152271 -78.237066) (xy 364.193639 -78.167025) (xy 364.242229 -78.101788) (xy 364.297491 -78.042097)
			(xy 364.358794 -77.98863) (xy 364.425443 -77.941995) (xy 364.46079 -77.921866) (xy 364.469054 -77.916788)
			(xy 364.48131 -77.901772) (xy 364.487147 -77.88329) (xy 364.485738 -77.863959) (xy 364.481872 -77.855064)
			(xy 364.469847 -77.829041) (xy 364.452873 -77.774288) (xy 364.444285 -77.71761) (xy 364.443772 -77.688948)
			(xy 364.444248 -77.66158) (xy 364.452079 -77.607406) (xy 364.467574 -77.554908) (xy 364.490415 -77.505165)
			(xy 364.520131 -77.459197) (xy 364.537752 -77.43825) (xy 364.546992 -77.426921) (xy 364.559176 -77.400359)
			(xy 364.563358 -77.371436) (xy 364.559197 -77.342511) (xy 364.547031 -77.31594) (xy 364.537752 -77.304646)
			(xy 364.520111 -77.283715) (xy 364.490387 -77.237748) (xy 364.467548 -77.188001) (xy 364.452063 -77.135497)
			(xy 364.444251 -77.081318) (xy 364.443772 -77.053948) (xy 364.444212 -77.027605) (xy 364.451453 -76.975419)
			(xy 364.465803 -76.924726) (xy 364.486991 -76.876488) (xy 364.514612 -76.831623) (xy 364.548143 -76.790985)
			(xy 364.586945 -76.755345) (xy 364.608364 -76.740004) (xy 364.619228 -76.731988) (xy 364.636639 -76.711366)
			(xy 364.648047 -76.686907) (xy 364.652657 -76.660314) (xy 364.650148 -76.633442) (xy 364.640694 -76.608163)
			(xy 364.624955 -76.586238) (xy 364.614714 -76.577444) (xy 364.593027 -76.559238) (xy 364.554754 -76.517509)
			(xy 364.523073 -76.47058) (xy 364.498681 -76.419481) (xy 364.482114 -76.365336) (xy 364.473736 -76.309337)
			(xy 364.473236 -76.281026) (xy 364.473722 -76.253775) (xy 364.481478 -76.199827) (xy 364.496833 -76.147532)
			(xy 364.519475 -76.097955) (xy 364.548941 -76.052105) (xy 364.584632 -76.010914) (xy 364.625823 -75.975223)
			(xy 364.671673 -75.945757) (xy 364.72125 -75.923115) (xy 364.773545 -75.90776) (xy 364.827493 -75.900004)
			(xy 364.881995 -75.900004) (xy 364.935943 -75.90776) (xy 364.988238 -75.923115) (xy 365.037815 -75.945757)
			(xy 365.083665 -75.975223) (xy 365.124856 -76.010914) (xy 365.160547 -76.052105) (xy 365.190013 -76.097955)
			(xy 365.212655 -76.147532) (xy 365.22801 -76.199827) (xy 365.235766 -76.253775) (xy 365.236252 -76.281026)
			(xy 365.235814 -76.30737) (xy 365.228577 -76.359558) (xy 365.214229 -76.410255) (xy 365.193045 -76.458496)
			(xy 365.165426 -76.503365) (xy 365.131897 -76.544008) (xy 365.093097 -76.579652) (xy 365.07166 -76.59497)
			(xy 365.060804 -76.602985) (xy 365.043407 -76.623601) (xy 365.032013 -76.648052) (xy 365.027416 -76.674632)
			(xy 365.029936 -76.70149) (xy 365.039398 -76.726751) (xy 365.055142 -76.748656) (xy 365.06531 -76.75753)
			(xy 365.086992 -76.775738) (xy 365.125254 -76.81747) (xy 365.156924 -76.864401) (xy 365.181305 -76.9155)
			(xy 365.197861 -76.969643) (xy 365.206227 -77.025639) (xy 365.206788 -77.053948) (xy 365.206313 -77.081317)
			(xy 365.198483 -77.135491) (xy 365.18299 -77.187991) (xy 365.160153 -77.237737) (xy 365.13044 -77.283708)
			(xy 365.112808 -77.304646) (xy 365.103578 -77.315973) (xy 365.091413 -77.342527) (xy 365.087251 -77.371436)
			(xy 365.091433 -77.400343) (xy 365.103617 -77.426888) (xy 365.112808 -77.43825) (xy 365.130447 -77.459182)
			(xy 365.160166 -77.50515) (xy 365.183002 -77.554898) (xy 365.198485 -77.607401) (xy 365.206297 -77.661579)
			(xy 365.206788 -77.688948) (xy 365.206268 -77.717095) (xy 365.197965 -77.772773) (xy 365.181577 -77.826628)
			(xy 365.169958 -77.85227) (xy 365.166229 -77.861191) (xy 365.165054 -77.880476) (xy 365.171087 -77.89883)
			(xy 365.183473 -77.913658) (xy 365.191802 -77.918564) (xy 365.227602 -77.938555) (xy 365.295116 -77.985092)
			(xy 365.35725 -78.038602) (xy 365.413286 -78.098468) (xy 365.462578 -78.163998) (xy 365.504557 -78.234437)
			(xy 365.53874 -78.308972) (xy 365.564732 -78.386743) (xy 365.582232 -78.466853) (xy 365.59104 -78.548378)
			(xy 365.591598 -78.589378) (xy 365.591156 -78.626209) (xy 365.584056 -78.699528) (xy 365.56992 -78.771821)
			(xy 365.548881 -78.842415) (xy 365.521133 -78.910651) (xy 365.486936 -78.975894) (xy 365.467138 -79.006954)
			(xy 365.487758 -79.042522) (xy 365.522099 -79.117226) (xy 365.5482 -79.195191) (xy 365.565758 -79.275513)
			(xy 365.574568 -79.357258) (xy 365.575088 -79.398368) (xy 365.574583 -79.437565) (xy 365.566533 -79.515544)
			(xy 365.550526 -79.592286) (xy 365.526729 -79.666981) (xy 365.495395 -79.73884) (xy 365.456853 -79.807105)
			(xy 365.411512 -79.871055) (xy 365.359848 -79.930017) (xy 365.302408 -79.983366) (xy 365.239798 -80.030541)
			(xy 365.172677 -80.071044) (xy 365.137446 -80.088232) (xy 365.144385 -80.110732) (xy 365.153301 -80.156967)
			(xy 365.155226 -80.180434) (xy 365.1896 -80.200828) (xy 365.2543 -80.247763) (xy 365.313735 -80.301208)
			(xy 365.367253 -80.360578) (xy 365.414267 -80.425221) (xy 365.454261 -80.494427) (xy 365.486796 -80.567436)
			(xy 365.511515 -80.643449) (xy 365.528147 -80.72163) (xy 365.53651 -80.801123) (xy 365.536988 -80.841088)
			(xy 365.536404 -80.883929) (xy 365.526799 -80.969072) (xy 365.50772 -81.052603) (xy 365.479406 -81.133472)
			(xy 365.442214 -81.210662) (xy 365.419894 -81.247234) (xy 365.438875 -81.281706) (xy 365.47044 -81.353798)
			(xy 365.49442 -81.428754) (xy 365.510559 -81.505781) (xy 365.518687 -81.584059) (xy 365.519208 -81.623408)
			(xy 365.518762 -81.660871) (xy 365.511412 -81.735437) (xy 365.496784 -81.808922) (xy 365.475018 -81.880617)
			(xy 365.446326 -81.949833) (xy 365.410983 -82.0159) (xy 365.36933 -82.078182) (xy 365.321769 -82.136078)
			(xy 365.268759 -82.189031) (xy 365.210811 -82.236528) (xy 365.179864 -82.257646) (xy 365.168123 -82.266074)
			(xy 365.14953 -82.288183) (xy 365.137871 -82.314614) (xy 365.13408 -82.343252) (xy 365.13846 -82.371806)
			(xy 365.150661 -82.397991) (xy 365.169706 -82.419712) (xy 365.194071 -82.435231) (xy 365.221808 -82.443306)
			(xy 365.236252 -82.443828) (xy 374.90654 -82.443828) (xy 376.37466 -80.975708) (xy 376.37466 -68.712588)
			(xy 373.999506 -66.337434) (xy 373.967502 -66.352166) (xy 373.94254 -66.362988) (xy 373.89032 -66.378255)
			(xy 373.836463 -66.385964) (xy 373.80926 -66.386456) (xy 373.78104 -66.385945) (xy 373.725217 -66.377625)
			(xy 373.671229 -66.361172) (xy 373.620253 -66.336947) (xy 373.573402 -66.305476) (xy 373.531698 -66.267447)
			(xy 373.496051 -66.22369) (xy 373.467239 -66.175158) (xy 373.44589 -66.122912) (xy 373.438674 -66.095626)
			(xy 373.434669 -66.081408) (xy 373.419725 -66.055942) (xy 373.39813 -66.035805) (xy 373.371683 -66.022676)
			(xy 373.342587 -66.017648) (xy 373.313268 -66.02114) (xy 373.286168 -66.032862) (xy 373.27459 -66.042032)
			(xy 373.253886 -66.058786) (xy 373.20871 -66.086993) (xy 373.16005 -66.108642) (xy 373.108851 -66.123312)
			(xy 373.05611 -66.130718) (xy 373.02948 -66.131186) (xy 373.002229 -66.130721) (xy 372.948281 -66.122962)
			(xy 372.895987 -66.107604) (xy 372.846411 -66.08496) (xy 372.800562 -66.055491) (xy 372.759373 -66.019797)
			(xy 372.723684 -65.978605) (xy 372.69422 -65.932752) (xy 372.671581 -65.883174) (xy 372.656229 -65.830878)
			(xy 372.648476 -65.776929) (xy 372.647972 -65.749678) (xy 372.64843 -65.722427) (xy 372.656178 -65.66848)
			(xy 372.671528 -65.616185) (xy 372.694167 -65.566608) (xy 372.723634 -65.520759) (xy 372.759327 -65.479572)
			(xy 372.800521 -65.443887) (xy 372.846376 -65.41443) (xy 372.870984 -65.402714) (xy 372.883571 -65.396496)
			(xy 372.904981 -65.378352) (xy 372.920632 -65.355056) (xy 372.929337 -65.328376) (xy 372.930436 -65.300333)
			(xy 372.923846 -65.273053) (xy 372.910067 -65.248604) (xy 372.900448 -65.238376) (xy 369.417092 -61.75502)
			(xy 369.46078 -61.711332) (xy 369.46078 -59.77636) (xy 369.828064 -59.409076) (xy 381.797306 -59.409076)
			(xy 381.810323 -59.384014) (xy 381.842625 -59.337692) (xy 381.881404 -59.296639) (xy 381.925812 -59.261752)
			(xy 381.974879 -59.233794) (xy 382.027531 -59.213376) (xy 382.082618 -59.200943) (xy 382.138936 -59.196769)
			(xy 382.195254 -59.200943) (xy 382.250341 -59.213376) (xy 382.302993 -59.233794) (xy 382.35206 -59.261752)
			(xy 382.396468 -59.296639) (xy 382.435247 -59.337692) (xy 382.467549 -59.384014) (xy 382.480566 -59.409076)
			(xy 384.48488 -59.409076) (xy 384.506536 -59.394136) (xy 384.553134 -59.369712) (xy 384.602647 -59.351927)
			(xy 384.654136 -59.341119) (xy 384.706622 -59.337493) (xy 384.759108 -59.341119) (xy 384.810597 -59.351927)
			(xy 384.86011 -59.369712) (xy 384.906708 -59.394136) (xy 384.928364 -59.409076) (xy 388.993888 -59.409076)
			(xy 392.816842 -63.23203) (xy 394.517624 -63.23203) (xy 394.521695 -63.176408) (xy 394.533821 -63.121971)
			(xy 394.553744 -63.06988) (xy 394.58104 -63.021245) (xy 394.615126 -62.977102) (xy 394.655275 -62.938393)
			(xy 394.700633 -62.905942) (xy 394.750233 -62.880441) (xy 394.803017 -62.862434) (xy 394.85786 -62.852304)
			(xy 394.913594 -62.850267) (xy 394.969031 -62.856367) (xy 395.022988 -62.870473) (xy 395.074317 -62.892285)
			(xy 395.121923 -62.921339) (xy 395.164791 -62.957014) (xy 395.202008 -62.998551) (xy 395.232781 -63.045064)
			(xy 395.256453 -63.095561) (xy 395.272521 -63.148968) (xy 395.280641 -63.204144) (xy 395.28115 -63.23203)
			(xy 395.280641 -63.259916) (xy 395.272521 -63.315092) (xy 395.256453 -63.368499) (xy 395.232781 -63.418996)
			(xy 395.202008 -63.465509) (xy 395.164791 -63.507046) (xy 395.121923 -63.542721) (xy 395.074317 -63.571775)
			(xy 395.022988 -63.593587) (xy 394.969031 -63.607693) (xy 394.913594 -63.613793) (xy 394.85786 -63.611756)
			(xy 394.803017 -63.601626) (xy 394.750233 -63.583619) (xy 394.700633 -63.558118) (xy 394.655275 -63.525667)
			(xy 394.615126 -63.486958) (xy 394.58104 -63.442815) (xy 394.553744 -63.39418) (xy 394.533821 -63.342089)
			(xy 394.521695 -63.287652) (xy 394.517624 -63.23203) (xy 392.816842 -63.23203) (xy 393.414758 -63.829946)
			(xy 396.301468 -63.829946) (xy 396.639288 -63.492126) (xy 396.639288 -61.310266) (xy 396.638775 -61.295425)
			(xy 396.630241 -61.266996) (xy 396.613903 -61.242215) (xy 396.591136 -61.22317) (xy 396.563858 -61.211466)
			(xy 396.534369 -61.208089) (xy 396.505152 -61.213322) (xy 396.478668 -61.226726) (xy 396.467584 -61.236606)
			(xy 396.446181 -61.256269) (xy 396.398528 -61.289541) (xy 396.346379 -61.315198) (xy 396.290942 -61.332648)
			(xy 396.233499 -61.341486) (xy 396.20444 -61.342016) (xy 396.177185 -61.341555) (xy 396.123228 -61.333803)
			(xy 396.070925 -61.31845) (xy 396.021338 -61.295809) (xy 395.975479 -61.266342) (xy 395.934281 -61.230647)
			(xy 395.898582 -61.189453) (xy 395.86911 -61.143597) (xy 395.846464 -61.094013) (xy 395.831106 -61.041711)
			(xy 395.823347 -60.987755) (xy 395.823347 -60.933245) (xy 395.831106 -60.879289) (xy 395.846464 -60.826987)
			(xy 395.86911 -60.777403) (xy 395.898582 -60.731547) (xy 395.934281 -60.690353) (xy 395.975479 -60.654658)
			(xy 396.021338 -60.625191) (xy 396.070925 -60.60255) (xy 396.123228 -60.587197) (xy 396.177185 -60.579445)
			(xy 396.20444 -60.579) (xy 396.233501 -60.579542) (xy 396.290949 -60.588359) (xy 396.346393 -60.605796)
			(xy 396.398546 -60.63145) (xy 396.4462 -60.664725) (xy 396.467584 -60.68441) (xy 396.478689 -60.694283)
			(xy 396.505175 -60.707722) (xy 396.534406 -60.712981) (xy 396.563915 -60.709615) (xy 396.591212 -60.69791)
			(xy 396.613992 -60.678853) (xy 396.630334 -60.654052) (xy 396.638857 -60.6256) (xy 396.639288 -60.61075)
			(xy 396.639288 -58.332878) (xy 396.506954 -58.200544) (xy 396.45082 -58.256932) (xy 396.457678 -58.284618)
			(xy 396.463023 -58.307422) (xy 396.46876 -58.353909) (xy 396.469108 -58.377328) (xy 396.468622 -58.404579)
			(xy 396.460866 -58.458527) (xy 396.445511 -58.510822) (xy 396.422869 -58.560399) (xy 396.393403 -58.606249)
			(xy 396.357712 -58.64744) (xy 396.316521 -58.683131) (xy 396.270671 -58.712597) (xy 396.221094 -58.735239)
			(xy 396.168799 -58.750594) (xy 396.114851 -58.75835) (xy 396.060349 -58.75835) (xy 396.006401 -58.750594)
			(xy 395.954106 -58.735239) (xy 395.904529 -58.712597) (xy 395.858679 -58.683131) (xy 395.817488 -58.64744)
			(xy 395.781797 -58.606249) (xy 395.752331 -58.560399) (xy 395.729689 -58.510822) (xy 395.714334 -58.458527)
			(xy 395.706578 -58.404579) (xy 395.706092 -58.377328) (xy 395.706617 -58.34852) (xy 395.715279 -58.291559)
			(xy 395.732409 -58.236548) (xy 395.75762 -58.18474) (xy 395.790335 -58.137314) (xy 395.829812 -58.095347)
			(xy 395.875152 -58.059796) (xy 395.925324 -58.031469) (xy 395.979185 -58.01101) (xy 396.035511 -57.998886)
			(xy 396.064232 -57.996582) (xy 396.078768 -57.995187) (xy 396.10619 -57.985186) (xy 396.12967 -57.967845)
			(xy 396.147294 -57.944576) (xy 396.157627 -57.917276) (xy 396.159825 -57.88817) (xy 396.153711 -57.859628)
			(xy 396.139781 -57.833976) (xy 396.129764 -57.823354) (xy 395.426692 -57.120282) (xy 395.415987 -57.11025)
			(xy 395.390222 -57.096243) (xy 395.36154 -57.09013) (xy 395.332303 -57.092415) (xy 395.304918 -57.102909)
			(xy 395.281642 -57.120748) (xy 395.26439 -57.144463) (xy 395.259052 -57.158128) (xy 395.248723 -57.185578)
			(xy 395.220854 -57.237182) (xy 395.185417 -57.283914) (xy 395.143247 -57.324673) (xy 395.095338 -57.358501)
			(xy 395.042817 -57.3846) (xy 394.986921 -57.402356) (xy 394.928966 -57.411351) (xy 394.899642 -57.411874)
			(xy 394.872388 -57.411414) (xy 394.818434 -57.403661) (xy 394.766133 -57.388308) (xy 394.71655 -57.365668)
			(xy 394.670694 -57.3362) (xy 394.629499 -57.300506) (xy 394.593804 -57.259312) (xy 394.564336 -57.213457)
			(xy 394.541694 -57.163874) (xy 394.52634 -57.111573) (xy 394.518587 -57.05762) (xy 394.518134 -57.030366)
			(xy 394.518667 -57.001039) (xy 394.527638 -56.943074) (xy 394.545377 -56.887167) (xy 394.571468 -56.834635)
			(xy 394.605294 -56.786717) (xy 394.646058 -56.744543) (xy 394.692798 -56.709108) (xy 394.744413 -56.681247)
			(xy 394.77188 -56.670956) (xy 394.785524 -56.665589) (xy 394.80921 -56.648332) (xy 394.827027 -56.625062)
			(xy 394.837508 -56.597694) (xy 394.839792 -56.568476) (xy 394.833692 -56.539811) (xy 394.819709 -56.514056)
			(xy 394.809726 -56.503316) (xy 393.884404 -55.577994) (xy 393.858242 -55.58282) (xy 393.841243 -55.585694)
			(xy 393.806901 -55.588746) (xy 393.789662 -55.588916) (xy 393.762412 -55.588428) (xy 393.708468 -55.580667)
			(xy 393.656178 -55.565308) (xy 393.606605 -55.542665) (xy 393.560758 -55.513198) (xy 393.519572 -55.477507)
			(xy 393.483884 -55.436317) (xy 393.45442 -55.390469) (xy 393.431781 -55.340894) (xy 393.416427 -55.288602)
			(xy 393.40867 -55.234658) (xy 393.408154 -55.207408) (xy 393.408308 -55.190168) (xy 393.411357 -55.155824)
			(xy 393.41425 -55.138828) (xy 393.419076 -55.112666) (xy 391.111486 -52.805076) (xy 389.462772 -52.805076)
			(xy 389.45312 -52.84343) (xy 389.445764 -52.870509) (xy 389.424193 -52.922309) (xy 389.395266 -52.97039)
			(xy 389.359608 -53.013714) (xy 389.317987 -53.051347) (xy 389.271303 -53.082477) (xy 389.220561 -53.106432)
			(xy 389.166858 -53.122695) (xy 389.111352 -53.130916) (xy 389.05524 -53.130916) (xy 388.999734 -53.122695)
			(xy 388.946031 -53.106432) (xy 388.895289 -53.082477) (xy 388.848605 -53.051347) (xy 388.806984 -53.013714)
			(xy 388.771326 -52.97039) (xy 388.742399 -52.922309) (xy 388.720828 -52.870509) (xy 388.713472 -52.84343)
			(xy 388.70382 -52.805076) (xy 388.197598 -52.805076) (xy 388.182581 -52.805612) (xy 388.153845 -52.814342)
			(xy 388.128888 -52.831049) (xy 388.109864 -52.854289) (xy 388.098418 -52.882056) (xy 388.095537 -52.911951)
			(xy 388.10147 -52.941392) (xy 388.115706 -52.967837) (xy 388.12597 -52.978812) (xy 388.146993 -53.000444)
			(xy 388.182631 -53.049109) (xy 388.21017 -53.102775) (xy 388.228923 -53.160105) (xy 388.238423 -53.219671)
			(xy 388.239 -53.24983) (xy 388.238936 -53.260329) (xy 388.237791 -53.281296) (xy 388.236714 -53.29174)
			(xy 388.235613 -53.306745) (xy 388.241184 -53.336295) (xy 388.255116 -53.362943) (xy 388.276203 -53.384381)
			(xy 388.302618 -53.398751) (xy 388.332073 -53.404808) (xy 388.362015 -53.402028) (xy 388.37616 -53.396896)
			(xy 388.399221 -53.387882) (xy 388.447084 -53.375208) (xy 388.496183 -53.368826) (xy 388.52094 -53.368448)
			(xy 388.548196 -53.368914) (xy 388.602153 -53.376677) (xy 388.654455 -53.392041) (xy 388.704039 -53.414691)
			(xy 388.749894 -53.444168) (xy 388.791088 -53.47987) (xy 388.826781 -53.521071) (xy 388.856248 -53.566933)
			(xy 388.878888 -53.616521) (xy 388.89424 -53.668827) (xy 388.901992 -53.722785) (xy 388.901989 -53.749956)
			(xy 389.037574 -53.749956) (xy 389.041645 -53.694334) (xy 389.053771 -53.639897) (xy 389.073694 -53.587806)
			(xy 389.10099 -53.539171) (xy 389.135076 -53.495028) (xy 389.175225 -53.456319) (xy 389.220583 -53.423868)
			(xy 389.270183 -53.398367) (xy 389.322967 -53.38036) (xy 389.37781 -53.37023) (xy 389.433544 -53.368193)
			(xy 389.488981 -53.374293) (xy 389.542938 -53.388399) (xy 389.594267 -53.410211) (xy 389.641873 -53.439265)
			(xy 389.684741 -53.47494) (xy 389.721958 -53.516477) (xy 389.752731 -53.56299) (xy 389.776403 -53.613487)
			(xy 389.792471 -53.666894) (xy 389.800591 -53.72207) (xy 389.8011 -53.749956) (xy 389.800591 -53.777842)
			(xy 389.792471 -53.833018) (xy 389.776403 -53.886425) (xy 389.752731 -53.936922) (xy 389.721958 -53.983435)
			(xy 389.684741 -54.024972) (xy 389.641873 -54.060647) (xy 389.594267 -54.089701) (xy 389.542938 -54.111513)
			(xy 389.488981 -54.125619) (xy 389.433544 -54.131719) (xy 389.37781 -54.129682) (xy 389.322967 -54.119552)
			(xy 389.270183 -54.101545) (xy 389.220583 -54.076044) (xy 389.175225 -54.043593) (xy 389.135076 -54.004884)
			(xy 389.10099 -53.960741) (xy 389.073694 -53.912106) (xy 389.053771 -53.860015) (xy 389.041645 -53.805578)
			(xy 389.037574 -53.749956) (xy 388.901989 -53.749956) (xy 388.901986 -53.777297) (xy 388.894222 -53.831254)
			(xy 388.878859 -53.883556) (xy 388.856208 -53.93314) (xy 388.826732 -53.978995) (xy 388.791029 -54.020189)
			(xy 388.749828 -54.055882) (xy 388.703966 -54.085349) (xy 388.654377 -54.107988) (xy 388.602072 -54.12334)
			(xy 388.548113 -54.131092) (xy 388.493601 -54.131086) (xy 388.439645 -54.123322) (xy 388.387343 -54.107958)
			(xy 388.337759 -54.085308) (xy 388.291904 -54.055831) (xy 388.25071 -54.020128) (xy 388.215017 -53.978927)
			(xy 388.185551 -53.933065) (xy 388.162911 -53.883476) (xy 388.147559 -53.83117) (xy 388.139808 -53.777212)
			(xy 388.139432 -53.749956) (xy 388.139496 -53.739457) (xy 388.140642 -53.71849) (xy 388.141718 -53.708046)
			(xy 388.142832 -53.69303) (xy 388.137277 -53.663452) (xy 388.123348 -53.636774) (xy 388.102254 -53.615309)
			(xy 388.075822 -53.600919) (xy 388.046345 -53.594851) (xy 388.016378 -53.597631) (xy 388.002272 -53.60289)
			(xy 387.979211 -53.6119) (xy 387.931347 -53.624566) (xy 387.882248 -53.630939) (xy 387.857492 -53.631338)
			(xy 387.83024 -53.630852) (xy 387.776292 -53.623094) (xy 387.723996 -53.607739) (xy 387.674418 -53.585098)
			(xy 387.628567 -53.555632) (xy 387.587375 -53.519941) (xy 387.551682 -53.478751) (xy 387.522213 -53.432901)
			(xy 387.499569 -53.383324) (xy 387.48421 -53.33103) (xy 387.47645 -53.277082) (xy 387.475984 -53.24983)
			(xy 387.476554 -53.21967) (xy 387.486046 -53.160101) (xy 387.504798 -53.10277) (xy 387.532343 -53.049105)
			(xy 387.567993 -53.000447) (xy 387.589014 -52.978812) (xy 387.599294 -52.967849) (xy 387.613533 -52.9414)
			(xy 387.619469 -52.911954) (xy 387.616588 -52.882054) (xy 387.605139 -52.854283) (xy 387.586111 -52.83104)
			(xy 387.561148 -52.814332) (xy 387.532405 -52.805603) (xy 387.517386 -52.805076) (xy 374.372886 -52.805076)
			(xy 374.359097 -52.805536) (xy 374.332527 -52.81292) (xy 374.308902 -52.827145) (xy 374.289946 -52.847174)
			(xy 374.277041 -52.871546) (xy 374.27113 -52.898482) (xy 374.272643 -52.926018) (xy 374.28147 -52.952145)
			(xy 374.288812 -52.963826) (xy 374.304348 -52.987646) (xy 374.328945 -53.038919) (xy 374.34565 -53.093277)
			(xy 374.354093 -53.149514) (xy 374.354598 -53.177948) (xy 374.354108 -53.205197) (xy 374.346346 -53.259139)
			(xy 374.330987 -53.311427) (xy 374.308343 -53.360997) (xy 374.278875 -53.406841) (xy 374.243184 -53.448025)
			(xy 374.201995 -53.48371) (xy 374.156147 -53.513171) (xy 374.106573 -53.535807) (xy 374.054282 -53.551159)
			(xy 374.000339 -53.558913) (xy 373.97309 -53.559456) (xy 373.945714 -53.558983) (xy 373.891524 -53.551153)
			(xy 373.839011 -53.535657) (xy 373.789253 -53.512811) (xy 373.743272 -53.483086) (xy 373.702014 -53.447092)
			(xy 373.666326 -53.405569) (xy 373.636941 -53.35937) (xy 373.614463 -53.309445) (xy 373.599354 -53.256818)
			(xy 373.595138 -53.229764) (xy 373.592832 -53.216211) (xy 373.581985 -53.190961) (xy 373.564793 -53.169521)
			(xy 373.542503 -53.153446) (xy 373.516732 -53.143903) (xy 373.489349 -53.141582) (xy 373.475758 -53.143658)
			(xy 373.458393 -53.146723) (xy 373.423285 -53.150035) (xy 373.405654 -53.150262) (xy 373.37665 -53.149725)
			(xy 373.319311 -53.140951) (xy 373.263961 -53.123596) (xy 373.211877 -53.098062) (xy 373.164259 -53.064936)
			(xy 373.122205 -53.024982) (xy 373.086685 -52.979122) (xy 373.058518 -52.928413) (xy 373.038354 -52.874024)
			(xy 373.03202 -52.845716) (xy 373.023638 -52.805076) (xy 370.331238 -52.805076) (xy 370.317454 -52.805542)
			(xy 370.290896 -52.812933) (xy 370.267283 -52.827161) (xy 370.248337 -52.847187) (xy 370.235439 -52.871552)
			(xy 370.22953 -52.898479) (xy 370.23104 -52.926005) (xy 370.23986 -52.952124) (xy 370.247164 -52.963826)
			(xy 370.262702 -52.987645) (xy 370.287302 -53.038917) (xy 370.30401 -53.093276) (xy 370.312453 -53.149514)
			(xy 370.31295 -53.177948) (xy 370.312464 -53.205199) (xy 370.304708 -53.259147) (xy 370.289353 -53.311442)
			(xy 370.266711 -53.361019) (xy 370.237245 -53.406869) (xy 370.201554 -53.44806) (xy 370.199629 -53.449728)
			(xy 370.448076 -53.449728) (xy 370.452147 -53.394106) (xy 370.464273 -53.339669) (xy 370.484196 -53.287578)
			(xy 370.511492 -53.238943) (xy 370.545578 -53.1948) (xy 370.585727 -53.156091) (xy 370.631085 -53.12364)
			(xy 370.680685 -53.098139) (xy 370.733469 -53.080132) (xy 370.788312 -53.070002) (xy 370.844046 -53.067965)
			(xy 370.899483 -53.074065) (xy 370.95344 -53.088171) (xy 371.004769 -53.109983) (xy 371.052375 -53.139037)
			(xy 371.095243 -53.174712) (xy 371.13246 -53.216249) (xy 371.163233 -53.262762) (xy 371.186905 -53.313259)
			(xy 371.202973 -53.366666) (xy 371.211093 -53.421842) (xy 371.211602 -53.449728) (xy 371.211093 -53.477614)
			(xy 371.202973 -53.53279) (xy 371.186905 -53.586197) (xy 371.163233 -53.636694) (xy 371.151148 -53.65496)
			(xy 380.59817 -53.65496) (xy 380.602241 -53.599338) (xy 380.614367 -53.544901) (xy 380.63429 -53.49281)
			(xy 380.661586 -53.444175) (xy 380.695672 -53.400032) (xy 380.735821 -53.361323) (xy 380.781179 -53.328872)
			(xy 380.830779 -53.303371) (xy 380.883563 -53.285364) (xy 380.938406 -53.275234) (xy 380.99414 -53.273197)
			(xy 381.049577 -53.279297) (xy 381.103534 -53.293403) (xy 381.154863 -53.315215) (xy 381.202469 -53.344269)
			(xy 381.245337 -53.379944) (xy 381.282554 -53.421481) (xy 381.313327 -53.467994) (xy 381.336999 -53.518491)
			(xy 381.346343 -53.54955) (xy 386.208268 -53.54955) (xy 386.212339 -53.493928) (xy 386.224465 -53.439491)
			(xy 386.244388 -53.3874) (xy 386.271684 -53.338765) (xy 386.30577 -53.294622) (xy 386.345919 -53.255913)
			(xy 386.391277 -53.223462) (xy 386.440877 -53.197961) (xy 386.493661 -53.179954) (xy 386.548504 -53.169824)
			(xy 386.604238 -53.167787) (xy 386.659675 -53.173887) (xy 386.713632 -53.187993) (xy 386.764961 -53.209805)
			(xy 386.812567 -53.238859) (xy 386.855435 -53.274534) (xy 386.892652 -53.316071) (xy 386.923425 -53.362584)
			(xy 386.947097 -53.413081) (xy 386.963165 -53.466488) (xy 386.971285 -53.521664) (xy 386.971794 -53.54955)
			(xy 386.971285 -53.577436) (xy 386.963165 -53.632612) (xy 386.947097 -53.686019) (xy 386.923425 -53.736516)
			(xy 386.892652 -53.783029) (xy 386.855435 -53.824566) (xy 386.812567 -53.860241) (xy 386.764961 -53.889295)
			(xy 386.713632 -53.911107) (xy 386.659675 -53.925213) (xy 386.604238 -53.931313) (xy 386.548504 -53.929276)
			(xy 386.493661 -53.919146) (xy 386.440877 -53.901139) (xy 386.391277 -53.875638) (xy 386.345919 -53.843187)
			(xy 386.30577 -53.804478) (xy 386.271684 -53.760335) (xy 386.244388 -53.7117) (xy 386.224465 -53.659609)
			(xy 386.212339 -53.605172) (xy 386.208268 -53.54955) (xy 381.346343 -53.54955) (xy 381.353067 -53.571898)
			(xy 381.361187 -53.627074) (xy 381.361696 -53.65496) (xy 381.361187 -53.682846) (xy 381.353067 -53.738022)
			(xy 381.336999 -53.791429) (xy 381.313327 -53.841926) (xy 381.282554 -53.888439) (xy 381.245337 -53.929976)
			(xy 381.202469 -53.965651) (xy 381.154863 -53.994705) (xy 381.103534 -54.016517) (xy 381.049577 -54.030623)
			(xy 380.99414 -54.036723) (xy 380.938406 -54.034686) (xy 380.883563 -54.024556) (xy 380.830779 -54.006549)
			(xy 380.781179 -53.981048) (xy 380.735821 -53.948597) (xy 380.695672 -53.909888) (xy 380.661586 -53.865745)
			(xy 380.63429 -53.81711) (xy 380.614367 -53.765019) (xy 380.602241 -53.710582) (xy 380.59817 -53.65496)
			(xy 371.151148 -53.65496) (xy 371.13246 -53.683207) (xy 371.095243 -53.724744) (xy 371.052375 -53.760419)
			(xy 371.004769 -53.789473) (xy 370.95344 -53.811285) (xy 370.899483 -53.825391) (xy 370.844046 -53.831491)
			(xy 370.788312 -53.829454) (xy 370.733469 -53.819324) (xy 370.680685 -53.801317) (xy 370.631085 -53.775816)
			(xy 370.585727 -53.743365) (xy 370.545578 -53.704656) (xy 370.511492 -53.660513) (xy 370.484196 -53.611878)
			(xy 370.464273 -53.559787) (xy 370.452147 -53.50535) (xy 370.448076 -53.449728) (xy 370.199629 -53.449728)
			(xy 370.160363 -53.483751) (xy 370.114513 -53.513217) (xy 370.064936 -53.535859) (xy 370.012641 -53.551214)
			(xy 369.958693 -53.55897) (xy 369.904191 -53.55897) (xy 369.850243 -53.551214) (xy 369.797948 -53.535859)
			(xy 369.748371 -53.513217) (xy 369.702521 -53.483751) (xy 369.66133 -53.44806) (xy 369.625639 -53.406869)
			(xy 369.596173 -53.361019) (xy 369.573531 -53.311442) (xy 369.558176 -53.259147) (xy 369.55042 -53.205199)
			(xy 369.549934 -53.177948) (xy 369.550462 -53.149516) (xy 369.558911 -53.093284) (xy 369.575614 -53.038928)
			(xy 369.6002 -52.987654) (xy 369.61572 -52.963826) (xy 369.623096 -52.952163) (xy 369.631931 -52.926032)
			(xy 369.633448 -52.898489) (xy 369.627534 -52.871546) (xy 369.614623 -52.84717) (xy 369.595656 -52.827141)
			(xy 369.572019 -52.812922) (xy 369.545438 -52.80555) (xy 369.531646 -52.805076) (xy 354.56622 -52.805076)
			(xy 353.839018 -53.532278) (xy 365.996218 -53.532278) (xy 366.000289 -53.476656) (xy 366.012415 -53.422219)
			(xy 366.032338 -53.370128) (xy 366.059634 -53.321493) (xy 366.09372 -53.27735) (xy 366.133869 -53.238641)
			(xy 366.179227 -53.20619) (xy 366.228827 -53.180689) (xy 366.281611 -53.162682) (xy 366.336454 -53.152552)
			(xy 366.392188 -53.150515) (xy 366.447625 -53.156615) (xy 366.501582 -53.170721) (xy 366.552911 -53.192533)
			(xy 366.600517 -53.221587) (xy 366.643385 -53.257262) (xy 366.680602 -53.298799) (xy 366.711375 -53.345312)
			(xy 366.735047 -53.395809) (xy 366.751115 -53.449216) (xy 366.759235 -53.504392) (xy 366.759744 -53.532278)
			(xy 366.759235 -53.560164) (xy 366.751115 -53.61534) (xy 366.735047 -53.668747) (xy 366.711375 -53.719244)
			(xy 366.680602 -53.765757) (xy 366.643385 -53.807294) (xy 366.600517 -53.842969) (xy 366.552911 -53.872023)
			(xy 366.501582 -53.893835) (xy 366.447625 -53.907941) (xy 366.392188 -53.914041) (xy 366.336454 -53.912004)
			(xy 366.281611 -53.901874) (xy 366.228827 -53.883867) (xy 366.179227 -53.858366) (xy 366.133869 -53.825915)
			(xy 366.09372 -53.787206) (xy 366.059634 -53.743063) (xy 366.032338 -53.694428) (xy 366.012415 -53.642337)
			(xy 366.000289 -53.5879) (xy 365.996218 -53.532278) (xy 353.839018 -53.532278) (xy 353.767644 -53.603652)
			(xy 351.964244 -53.603652) (xy 347.61678 -49.256188) (xy 345.545664 -49.256188) (xy 345.532248 -49.256561)
			(xy 345.506325 -49.263484) (xy 345.483102 -49.276922) (xy 345.464182 -49.295946) (xy 345.450872 -49.319242)
			(xy 345.44409 -49.345202) (xy 345.444307 -49.372031) (xy 345.451506 -49.397878) (xy 345.458034 -49.409604)
			(xy 345.469832 -49.430277) (xy 345.488438 -49.474089) (xy 345.501041 -49.51999) (xy 345.507416 -49.567161)
			(xy 345.507818 -49.59096) (xy 345.50732 -49.617609) (xy 345.499377 -49.670313) (xy 345.483667 -49.721243)
			(xy 345.460541 -49.769264) (xy 345.430517 -49.813301) (xy 345.394265 -49.852372) (xy 345.352594 -49.885603)
			(xy 345.306436 -49.912252) (xy 345.256822 -49.931724) (xy 345.20486 -49.943584) (xy 345.15171 -49.947568)
			(xy 345.09856 -49.943584) (xy 345.046598 -49.931724) (xy 344.996984 -49.912252) (xy 344.950826 -49.885603)
			(xy 344.909155 -49.852372) (xy 344.872903 -49.813301) (xy 344.842879 -49.769264) (xy 344.819753 -49.721243)
			(xy 344.804043 -49.670313) (xy 344.7961 -49.617609) (xy 344.795602 -49.59096) (xy 344.796015 -49.567161)
			(xy 344.802386 -49.51999) (xy 344.814983 -49.474088) (xy 344.833581 -49.430273) (xy 344.845386 -49.409604)
			(xy 344.851874 -49.397861) (xy 344.859069 -49.372023) (xy 344.859285 -49.345204) (xy 344.852506 -49.319254)
			(xy 344.839202 -49.295966) (xy 344.820291 -49.276948) (xy 344.797078 -49.263513) (xy 344.771167 -49.256588)
			(xy 344.757756 -49.256188) (xy 344.480642 -49.256188) (xy 344.473022 -49.258728) (xy 344.446309 -49.266788)
			(xy 344.391192 -49.275465) (xy 344.363294 -49.276) (xy 344.335393 -49.275504) (xy 344.280272 -49.26682)
			(xy 344.253566 -49.258728) (xy 344.245946 -49.256188) (xy 344.007186 -49.256188) (xy 343.993266 -49.25662)
			(xy 343.966461 -49.264142) (xy 343.942684 -49.278622) (xy 343.9237 -49.298986) (xy 343.91092 -49.323719)
			(xy 343.905293 -49.350984) (xy 343.90584 -49.3649) (xy 343.906602 -49.389792) (xy 343.906104 -49.416441)
			(xy 343.898161 -49.469145) (xy 343.882451 -49.520075) (xy 343.859325 -49.568096) (xy 343.829301 -49.612133)
			(xy 343.793049 -49.651204) (xy 343.751378 -49.684435) (xy 343.70522 -49.711084) (xy 343.655606 -49.730556)
			(xy 343.603644 -49.742416) (xy 343.550494 -49.7464) (xy 343.497344 -49.742416) (xy 343.445382 -49.730556)
			(xy 343.395768 -49.711084) (xy 343.34961 -49.684435) (xy 343.307939 -49.651204) (xy 343.271687 -49.612133)
			(xy 343.241663 -49.568096) (xy 343.218537 -49.520075) (xy 343.202827 -49.469145) (xy 343.194884 -49.416441)
			(xy 343.194386 -49.389792) (xy 343.195148 -49.3649) (xy 343.195691 -49.350985) (xy 343.190065 -49.323722)
			(xy 343.177285 -49.298991) (xy 343.158301 -49.27863) (xy 343.134524 -49.264153) (xy 343.107721 -49.256634)
			(xy 343.093802 -49.256188) (xy 342.852502 -49.256188) (xy 342.844882 -49.258728) (xy 342.818168 -49.266785)
			(xy 342.763051 -49.275456) (xy 342.735154 -49.276) (xy 342.707252 -49.275509) (xy 342.652129 -49.266834)
			(xy 342.625426 -49.258728) (xy 342.617806 -49.256188) (xy 342.375236 -49.256188) (xy 342.361344 -49.256696)
			(xy 342.334607 -49.264258) (xy 342.310898 -49.27875) (xy 342.291976 -49.299097) (xy 342.279241 -49.323793)
			(xy 342.273636 -49.351008) (xy 342.274144 -49.3649) (xy 342.274906 -49.390046) (xy 342.274408 -49.416695)
			(xy 342.266465 -49.469399) (xy 342.250755 -49.520329) (xy 342.227629 -49.56835) (xy 342.197605 -49.612387)
			(xy 342.161353 -49.651458) (xy 342.119682 -49.684689) (xy 342.073524 -49.711338) (xy 342.02391 -49.73081)
			(xy 341.971948 -49.74267) (xy 341.918798 -49.746654) (xy 341.865648 -49.74267) (xy 341.813686 -49.73081)
			(xy 341.764072 -49.711338) (xy 341.717914 -49.684689) (xy 341.676243 -49.651458) (xy 341.639991 -49.612387)
			(xy 341.609967 -49.56835) (xy 341.586841 -49.520329) (xy 341.571131 -49.469399) (xy 341.563188 -49.416695)
			(xy 341.56269 -49.390046) (xy 341.563452 -49.3649) (xy 341.563952 -49.351009) (xy 341.558348 -49.323796)
			(xy 341.545614 -49.299103) (xy 341.526692 -49.278757) (xy 341.502986 -49.264268) (xy 341.476251 -49.256708)
			(xy 341.46236 -49.256188) (xy 341.224108 -49.256188) (xy 341.216488 -49.258728) (xy 341.189605 -49.266926)
			(xy 341.134099 -49.275738) (xy 341.105998 -49.276254) (xy 341.077896 -49.27575) (xy 341.022384 -49.266953)
			(xy 340.995508 -49.258728) (xy 340.987888 -49.256188) (xy 339.252052 -49.256188) (xy 339.23763 -49.256654)
			(xy 339.209919 -49.264657) (xy 339.185556 -49.280094) (xy 339.166485 -49.301732) (xy 339.154232 -49.327842)
			(xy 339.149775 -49.356338) (xy 339.15347 -49.384943) (xy 339.165022 -49.411371) (xy 339.17382 -49.422812)
			(xy 339.189292 -49.442074) (xy 339.215328 -49.484062) (xy 339.235306 -49.529248) (xy 339.248842 -49.576763)
			(xy 339.255676 -49.625693) (xy 339.256116 -49.650396) (xy 339.255567 -49.67838) (xy 339.246813 -49.733658)
			(xy 339.229519 -49.786886) (xy 339.204111 -49.836753) (xy 339.171215 -49.882032) (xy 339.131641 -49.921607)
			(xy 339.086363 -49.954505) (xy 339.036497 -49.979914) (xy 338.983269 -49.99721) (xy 338.927992 -50.005966)
			(xy 338.900008 -50.006504) (xy 338.872947 -50.005999) (xy 338.81945 -49.997806) (xy 338.767809 -49.981608)
			(xy 338.719216 -49.957777) (xy 338.674792 -49.926864) (xy 338.63556 -49.889582) (xy 338.602426 -49.846789)
			(xy 338.588858 -49.82337) (xy 338.581917 -49.811724) (xy 338.563006 -49.792311) (xy 338.539655 -49.778556)
			(xy 338.513509 -49.771428) (xy 338.486407 -49.771428) (xy 338.460261 -49.778556) (xy 338.43691 -49.792311)
			(xy 338.417999 -49.811724) (xy 338.411058 -49.82337) (xy 338.397482 -49.846785) (xy 338.364352 -49.889583)
			(xy 338.325123 -49.92687) (xy 338.2807 -49.957787) (xy 338.232108 -49.981622) (xy 338.180468 -49.997823)
			(xy 338.126969 -50.006018) (xy 338.072847 -50.006018) (xy 338.019348 -49.997823) (xy 337.967708 -49.981622)
			(xy 337.919116 -49.957787) (xy 337.874693 -49.92687) (xy 337.835464 -49.889583) (xy 337.802334 -49.846785)
			(xy 337.788758 -49.82337) (xy 337.781817 -49.811724) (xy 337.762906 -49.792311) (xy 337.739555 -49.778556)
			(xy 337.713409 -49.771428) (xy 337.686307 -49.771428) (xy 337.660161 -49.778556) (xy 337.63681 -49.792311)
			(xy 337.617899 -49.811724) (xy 337.610958 -49.82337) (xy 337.598558 -49.844799) (xy 337.56874 -49.884321)
			(xy 337.533733 -49.919329) (xy 337.494213 -49.949149) (xy 337.472782 -49.961546) (xy 337.461147 -49.96849)
			(xy 337.441753 -49.9874) (xy 337.428015 -50.010744) (xy 337.420898 -50.036879) (xy 337.420904 -50.063966)
			(xy 337.428032 -50.090097) (xy 337.441781 -50.113435) (xy 337.461183 -50.132337) (xy 337.472782 -50.139346)
			(xy 337.496199 -50.15292) (xy 337.539002 -50.186048) (xy 337.576294 -50.225276) (xy 337.607215 -50.269699)
			(xy 337.631053 -50.318292) (xy 337.647257 -50.369935) (xy 337.655454 -50.423436) (xy 337.655454 -50.450496)
			(xy 339.344 -50.450496) (xy 339.344482 -50.424761) (xy 339.351872 -50.373826) (xy 339.366528 -50.324488)
			(xy 339.388142 -50.277778) (xy 339.416263 -50.234671) (xy 339.450304 -50.196068) (xy 339.489554 -50.162774)
			(xy 339.511132 -50.148744) (xy 339.522706 -50.140989) (xy 339.541389 -50.120331) (xy 339.553805 -50.095398)
			(xy 339.559033 -50.06804) (xy 339.556686 -50.040286) (xy 339.546938 -50.014194) (xy 339.539072 -50.002694)
			(xy 339.522984 -49.979699) (xy 339.497451 -49.929728) (xy 339.48007 -49.876371) (xy 339.471271 -49.820948)
			(xy 339.470746 -49.79289) (xy 339.471244 -49.766241) (xy 339.479187 -49.713537) (xy 339.494897 -49.662607)
			(xy 339.518023 -49.614586) (xy 339.548047 -49.570549) (xy 339.584299 -49.531478) (xy 339.62597 -49.498247)
			(xy 339.672128 -49.471598) (xy 339.721742 -49.452126) (xy 339.773704 -49.440266) (xy 339.826854 -49.436283)
			(xy 339.880004 -49.440266) (xy 339.931966 -49.452126) (xy 339.98158 -49.471598) (xy 340.027738 -49.498247)
			(xy 340.069409 -49.531478) (xy 340.105661 -49.570549) (xy 340.135685 -49.614586) (xy 340.158811 -49.662607)
			(xy 340.174521 -49.713537) (xy 340.182464 -49.766241) (xy 340.182962 -49.79289) (xy 340.182565 -49.818628)
			(xy 340.175161 -49.869567) (xy 340.170174 -49.886341) (xy 342.379544 -49.886341) (xy 342.379544 -49.833043)
			(xy 342.387487 -49.780339) (xy 342.403197 -49.729409) (xy 342.426323 -49.681388) (xy 342.456347 -49.637351)
			(xy 342.492599 -49.59828) (xy 342.53427 -49.565049) (xy 342.580428 -49.5384) (xy 342.630042 -49.518928)
			(xy 342.682004 -49.507068) (xy 342.735154 -49.503085) (xy 342.788304 -49.507068) (xy 342.840266 -49.518928)
			(xy 342.88988 -49.5384) (xy 342.936038 -49.565049) (xy 342.977709 -49.59828) (xy 343.013961 -49.637351)
			(xy 343.043985 -49.681388) (xy 343.067111 -49.729409) (xy 343.082821 -49.780339) (xy 343.090764 -49.833043)
			(xy 343.091262 -49.859692) (xy 343.090764 -49.886341) (xy 344.010224 -49.886341) (xy 344.010224 -49.833043)
			(xy 344.018167 -49.780339) (xy 344.033877 -49.729409) (xy 344.057003 -49.681388) (xy 344.087027 -49.637351)
			(xy 344.123279 -49.59828) (xy 344.16495 -49.565049) (xy 344.211108 -49.5384) (xy 344.260722 -49.518928)
			(xy 344.312684 -49.507068) (xy 344.365834 -49.503085) (xy 344.418984 -49.507068) (xy 344.470946 -49.518928)
			(xy 344.52056 -49.5384) (xy 344.566718 -49.565049) (xy 344.608389 -49.59828) (xy 344.644641 -49.637351)
			(xy 344.674665 -49.681388) (xy 344.697791 -49.729409) (xy 344.713501 -49.780339) (xy 344.721444 -49.833043)
			(xy 344.721942 -49.859692) (xy 344.721444 -49.886341) (xy 344.713501 -49.939045) (xy 344.697791 -49.989975)
			(xy 344.674665 -50.037996) (xy 344.644641 -50.082033) (xy 344.608389 -50.121104) (xy 344.566718 -50.154335)
			(xy 344.52056 -50.180984) (xy 344.470946 -50.200456) (xy 344.418984 -50.212316) (xy 344.365834 -50.2163)
			(xy 344.312684 -50.212316) (xy 344.260722 -50.200456) (xy 344.211108 -50.180984) (xy 344.16495 -50.154335)
			(xy 344.123279 -50.121104) (xy 344.087027 -50.082033) (xy 344.057003 -50.037996) (xy 344.033877 -49.989975)
			(xy 344.018167 -49.939045) (xy 344.010224 -49.886341) (xy 343.090764 -49.886341) (xy 343.082821 -49.939045)
			(xy 343.067111 -49.989975) (xy 343.043985 -50.037996) (xy 343.013961 -50.082033) (xy 342.977709 -50.121104)
			(xy 342.936038 -50.154335) (xy 342.88988 -50.180984) (xy 342.840266 -50.200456) (xy 342.788304 -50.212316)
			(xy 342.735154 -50.2163) (xy 342.682004 -50.212316) (xy 342.630042 -50.200456) (xy 342.580428 -50.180984)
			(xy 342.53427 -50.154335) (xy 342.492599 -50.121104) (xy 342.456347 -50.082033) (xy 342.426323 -50.037996)
			(xy 342.403197 -49.989975) (xy 342.387487 -49.939045) (xy 342.379544 -49.886341) (xy 340.170174 -49.886341)
			(xy 340.160492 -49.918908) (xy 340.138865 -49.965619) (xy 340.11073 -50.008725) (xy 340.076676 -50.047326)
			(xy 340.037414 -50.080615) (xy 340.01583 -50.094642) (xy 340.004293 -50.102441) (xy 339.985624 -50.12309)
			(xy 339.973216 -50.148009) (xy 339.96799 -50.175352) (xy 339.970331 -50.20309) (xy 339.980068 -50.22917)
			(xy 339.98789 -50.240692) (xy 340.003979 -50.263685) (xy 340.029511 -50.313658) (xy 340.043464 -50.356495)
			(xy 341.565728 -50.356495) (xy 341.565728 -50.303197) (xy 341.573671 -50.250493) (xy 341.589381 -50.199563)
			(xy 341.612507 -50.151542) (xy 341.642531 -50.107505) (xy 341.678783 -50.068434) (xy 341.720454 -50.035203)
			(xy 341.766612 -50.008554) (xy 341.816226 -49.989082) (xy 341.868188 -49.977222) (xy 341.921338 -49.973239)
			(xy 341.974488 -49.977222) (xy 342.02645 -49.989082) (xy 342.076064 -50.008554) (xy 342.122222 -50.035203)
			(xy 342.163893 -50.068434) (xy 342.200145 -50.107505) (xy 342.230169 -50.151542) (xy 342.253295 -50.199563)
			(xy 342.269005 -50.250493) (xy 342.276948 -50.303197) (xy 342.277446 -50.329846) (xy 342.276953 -50.356241)
			(xy 343.194884 -50.356241) (xy 343.194884 -50.302943) (xy 343.202827 -50.250239) (xy 343.218537 -50.199309)
			(xy 343.241663 -50.151288) (xy 343.271687 -50.107251) (xy 343.307939 -50.06818) (xy 343.34961 -50.034949)
			(xy 343.395768 -50.0083) (xy 343.445382 -49.988828) (xy 343.497344 -49.976968) (xy 343.550494 -49.972985)
			(xy 343.603644 -49.976968) (xy 343.655606 -49.988828) (xy 343.70522 -50.0083) (xy 343.751378 -50.034949)
			(xy 343.793049 -50.06818) (xy 343.829301 -50.107251) (xy 343.859325 -50.151288) (xy 343.882451 -50.199309)
			(xy 343.898161 -50.250239) (xy 343.906104 -50.302943) (xy 343.906602 -50.329592) (xy 343.906104 -50.356241)
			(xy 343.898161 -50.408945) (xy 343.882451 -50.459875) (xy 343.859325 -50.507896) (xy 343.829301 -50.551933)
			(xy 343.793049 -50.591004) (xy 343.751378 -50.624235) (xy 343.70522 -50.650884) (xy 343.655606 -50.670356)
			(xy 343.603644 -50.682216) (xy 343.550494 -50.6862) (xy 343.497344 -50.682216) (xy 343.445382 -50.670356)
			(xy 343.395768 -50.650884) (xy 343.34961 -50.624235) (xy 343.307939 -50.591004) (xy 343.271687 -50.551933)
			(xy 343.241663 -50.507896) (xy 343.218537 -50.459875) (xy 343.202827 -50.408945) (xy 343.194884 -50.356241)
			(xy 342.276953 -50.356241) (xy 342.276948 -50.356495) (xy 342.269005 -50.409199) (xy 342.253295 -50.460129)
			(xy 342.230169 -50.50815) (xy 342.200145 -50.552187) (xy 342.163893 -50.591258) (xy 342.122222 -50.624489)
			(xy 342.076064 -50.651138) (xy 342.02645 -50.67061) (xy 341.974488 -50.68247) (xy 341.921338 -50.686454)
			(xy 341.868188 -50.68247) (xy 341.816226 -50.67061) (xy 341.766612 -50.651138) (xy 341.720454 -50.624489)
			(xy 341.678783 -50.591258) (xy 341.642531 -50.552187) (xy 341.612507 -50.50815) (xy 341.589381 -50.460129)
			(xy 341.573671 -50.409199) (xy 341.565728 -50.356495) (xy 340.043464 -50.356495) (xy 340.046891 -50.367015)
			(xy 340.05569 -50.422438) (xy 340.056216 -50.450496) (xy 340.055718 -50.477145) (xy 340.047775 -50.529849)
			(xy 340.032065 -50.580779) (xy 340.008939 -50.6288) (xy 339.978915 -50.672837) (xy 339.942663 -50.711908)
			(xy 339.900992 -50.745139) (xy 339.854834 -50.771788) (xy 339.80522 -50.79126) (xy 339.753258 -50.80312)
			(xy 339.700108 -50.807104) (xy 339.646958 -50.80312) (xy 339.594996 -50.79126) (xy 339.545382 -50.771788)
			(xy 339.499224 -50.745139) (xy 339.457553 -50.711908) (xy 339.421301 -50.672837) (xy 339.391277 -50.6288)
			(xy 339.368151 -50.580779) (xy 339.352441 -50.529849) (xy 339.344498 -50.477145) (xy 339.344 -50.450496)
			(xy 337.655454 -50.450496) (xy 337.655454 -50.477561) (xy 337.647258 -50.531061) (xy 337.631054 -50.582704)
			(xy 337.607217 -50.631298) (xy 337.576296 -50.675721) (xy 337.539005 -50.714949) (xy 337.496203 -50.748078)
			(xy 337.472782 -50.761646) (xy 337.461147 -50.76859) (xy 337.441753 -50.7875) (xy 337.428015 -50.810844)
			(xy 337.423849 -50.826141) (xy 342.382084 -50.826141) (xy 342.382084 -50.772843) (xy 342.390027 -50.720139)
			(xy 342.405737 -50.669209) (xy 342.428863 -50.621188) (xy 342.458887 -50.577151) (xy 342.495139 -50.53808)
			(xy 342.53681 -50.504849) (xy 342.582968 -50.4782) (xy 342.632582 -50.458728) (xy 342.684544 -50.446868)
			(xy 342.737694 -50.442885) (xy 342.790844 -50.446868) (xy 342.842806 -50.458728) (xy 342.89242 -50.4782)
			(xy 342.938578 -50.504849) (xy 342.980249 -50.53808) (xy 343.016501 -50.577151) (xy 343.046525 -50.621188)
			(xy 343.069651 -50.669209) (xy 343.085361 -50.720139) (xy 343.093304 -50.772843) (xy 343.093802 -50.799492)
			(xy 343.093304 -50.826141) (xy 343.093266 -50.826395) (xy 344.0087 -50.826395) (xy 344.0087 -50.773097)
			(xy 344.016643 -50.720393) (xy 344.032353 -50.669463) (xy 344.055479 -50.621442) (xy 344.085503 -50.577405)
			(xy 344.121755 -50.538334) (xy 344.163426 -50.505103) (xy 344.209584 -50.478454) (xy 344.259198 -50.458982)
			(xy 344.31116 -50.447122) (xy 344.36431 -50.443139) (xy 344.41746 -50.447122) (xy 344.469422 -50.458982)
			(xy 344.519036 -50.478454) (xy 344.565194 -50.505103) (xy 344.606865 -50.538334) (xy 344.643117 -50.577405)
			(xy 344.671046 -50.618369) (xy 344.7961 -50.618369) (xy 344.7961 -50.565071) (xy 344.804043 -50.512367)
			(xy 344.819753 -50.461437) (xy 344.842879 -50.413416) (xy 344.872903 -50.369379) (xy 344.909155 -50.330308)
			(xy 344.950826 -50.297077) (xy 344.996984 -50.270428) (xy 345.046598 -50.250956) (xy 345.09856 -50.239096)
			(xy 345.15171 -50.235113) (xy 345.20486 -50.239096) (xy 345.256822 -50.250956) (xy 345.306436 -50.270428)
			(xy 345.352594 -50.297077) (xy 345.394265 -50.330308) (xy 345.430517 -50.369379) (xy 345.460541 -50.413416)
			(xy 345.483667 -50.461437) (xy 345.499377 -50.512367) (xy 345.50732 -50.565071) (xy 345.507818 -50.59172)
			(xy 345.50732 -50.618369) (xy 345.499377 -50.671073) (xy 345.483667 -50.722003) (xy 345.460541 -50.770024)
			(xy 345.430517 -50.814061) (xy 345.394265 -50.853132) (xy 345.352594 -50.886363) (xy 345.306436 -50.913012)
			(xy 345.256822 -50.932484) (xy 345.20486 -50.944344) (xy 345.15171 -50.948328) (xy 345.09856 -50.944344)
			(xy 345.046598 -50.932484) (xy 344.996984 -50.913012) (xy 344.950826 -50.886363) (xy 344.909155 -50.853132)
			(xy 344.872903 -50.814061) (xy 344.842879 -50.770024) (xy 344.819753 -50.722003) (xy 344.804043 -50.671073)
			(xy 344.7961 -50.618369) (xy 344.671046 -50.618369) (xy 344.673141 -50.621442) (xy 344.696267 -50.669463)
			(xy 344.711977 -50.720393) (xy 344.71992 -50.773097) (xy 344.720418 -50.799746) (xy 344.71992 -50.826395)
			(xy 344.711977 -50.879099) (xy 344.696267 -50.930029) (xy 344.673141 -50.97805) (xy 344.643117 -51.022087)
			(xy 344.606865 -51.061158) (xy 344.565194 -51.094389) (xy 344.519036 -51.121038) (xy 344.469422 -51.14051)
			(xy 344.41746 -51.15237) (xy 344.36431 -51.156354) (xy 344.31116 -51.15237) (xy 344.259198 -51.14051)
			(xy 344.209584 -51.121038) (xy 344.163426 -51.094389) (xy 344.121755 -51.061158) (xy 344.085503 -51.022087)
			(xy 344.055479 -50.97805) (xy 344.032353 -50.930029) (xy 344.016643 -50.879099) (xy 344.0087 -50.826395)
			(xy 343.093266 -50.826395) (xy 343.085361 -50.878845) (xy 343.069651 -50.929775) (xy 343.046525 -50.977796)
			(xy 343.016501 -51.021833) (xy 342.980249 -51.060904) (xy 342.938578 -51.094135) (xy 342.89242 -51.120784)
			(xy 342.842806 -51.140256) (xy 342.790844 -51.152116) (xy 342.737694 -51.1561) (xy 342.684544 -51.152116)
			(xy 342.632582 -51.140256) (xy 342.582968 -51.120784) (xy 342.53681 -51.094135) (xy 342.495139 -51.060904)
			(xy 342.458887 -51.021833) (xy 342.428863 -50.977796) (xy 342.405737 -50.929775) (xy 342.390027 -50.878845)
			(xy 342.382084 -50.826141) (xy 337.423849 -50.826141) (xy 337.420898 -50.836979) (xy 337.420904 -50.864066)
			(xy 337.428032 -50.890197) (xy 337.441781 -50.913535) (xy 337.461183 -50.932437) (xy 337.472782 -50.939446)
			(xy 337.496195 -50.953022) (xy 337.538987 -50.986153) (xy 337.576268 -51.025383) (xy 337.607177 -51.069807)
			(xy 337.631002 -51.118399) (xy 337.647192 -51.17004) (xy 337.655374 -51.223536) (xy 337.655916 -51.250596)
			(xy 337.655645 -51.2651) (xy 339.328942 -51.2651) (xy 339.332926 -51.21194) (xy 339.344789 -51.159968)
			(xy 339.364266 -51.110344) (xy 339.390922 -51.064178) (xy 339.424161 -51.0225) (xy 339.463241 -50.986243)
			(xy 339.507288 -50.956215) (xy 339.55532 -50.933088) (xy 339.606261 -50.917378) (xy 339.658975 -50.909437)
			(xy 339.68563 -50.908966) (xy 339.711635 -50.909445) (xy 339.763092 -50.917008) (xy 339.812903 -50.93197)
			(xy 339.860012 -50.954012) (xy 339.903416 -50.982667) (xy 339.92312 -50.999644) (xy 339.934424 -51.009028)
			(xy 339.96097 -51.021574) (xy 339.989992 -51.026033) (xy 340.01908 -51.022035) (xy 340.045822 -51.009911)
			(xy 340.057232 -51.00066) (xy 340.076746 -50.984292) (xy 340.119583 -50.956739) (xy 340.165908 -50.93557)
			(xy 340.214777 -50.921215) (xy 340.265191 -50.913968) (xy 340.290658 -50.913538) (xy 340.317315 -50.913916)
			(xy 340.370033 -50.921857) (xy 340.420979 -50.937566) (xy 340.469015 -50.960694) (xy 340.513066 -50.990723)
			(xy 340.55215 -51.026983) (xy 340.585392 -51.068663) (xy 340.612051 -51.114832) (xy 340.631529 -51.16446)
			(xy 340.643394 -51.216436) (xy 340.647378 -51.2696) (xy 340.645378 -51.296295) (xy 341.565728 -51.296295)
			(xy 341.565728 -51.242997) (xy 341.573671 -51.190293) (xy 341.589381 -51.139363) (xy 341.612507 -51.091342)
			(xy 341.642531 -51.047305) (xy 341.678783 -51.008234) (xy 341.720454 -50.975003) (xy 341.766612 -50.948354)
			(xy 341.816226 -50.928882) (xy 341.868188 -50.917022) (xy 341.921338 -50.913039) (xy 341.974488 -50.917022)
			(xy 342.02645 -50.928882) (xy 342.076064 -50.948354) (xy 342.122222 -50.975003) (xy 342.163893 -51.008234)
			(xy 342.200145 -51.047305) (xy 342.230169 -51.091342) (xy 342.253295 -51.139363) (xy 342.269005 -51.190293)
			(xy 342.276948 -51.242997) (xy 342.277446 -51.269646) (xy 342.276953 -51.296041) (xy 343.194884 -51.296041)
			(xy 343.194884 -51.242743) (xy 343.202827 -51.190039) (xy 343.218537 -51.139109) (xy 343.241663 -51.091088)
			(xy 343.271687 -51.047051) (xy 343.307939 -51.00798) (xy 343.34961 -50.974749) (xy 343.395768 -50.9481)
			(xy 343.445382 -50.928628) (xy 343.497344 -50.916768) (xy 343.550494 -50.912785) (xy 343.603644 -50.916768)
			(xy 343.655606 -50.928628) (xy 343.70522 -50.9481) (xy 343.751378 -50.974749) (xy 343.793049 -51.00798)
			(xy 343.829301 -51.047051) (xy 343.859325 -51.091088) (xy 343.882451 -51.139109) (xy 343.898161 -51.190039)
			(xy 343.906104 -51.242743) (xy 343.906602 -51.269392) (xy 343.906104 -51.296041) (xy 343.898161 -51.348745)
			(xy 343.882451 -51.399675) (xy 343.859325 -51.447696) (xy 343.829301 -51.491733) (xy 343.793049 -51.530804)
			(xy 343.751378 -51.564035) (xy 343.70522 -51.590684) (xy 343.655606 -51.610156) (xy 343.603644 -51.622016)
			(xy 343.550494 -51.626) (xy 343.497344 -51.622016) (xy 343.445382 -51.610156) (xy 343.395768 -51.590684)
			(xy 343.34961 -51.564035) (xy 343.307939 -51.530804) (xy 343.271687 -51.491733) (xy 343.241663 -51.447696)
			(xy 343.218537 -51.399675) (xy 343.202827 -51.348745) (xy 343.194884 -51.296041) (xy 342.276953 -51.296041)
			(xy 342.276948 -51.296295) (xy 342.269005 -51.348999) (xy 342.253295 -51.399929) (xy 342.230169 -51.44795)
			(xy 342.200145 -51.491987) (xy 342.163893 -51.531058) (xy 342.122222 -51.564289) (xy 342.076064 -51.590938)
			(xy 342.02645 -51.61041) (xy 341.974488 -51.62227) (xy 341.921338 -51.626254) (xy 341.868188 -51.62227)
			(xy 341.816226 -51.61041) (xy 341.766612 -51.590938) (xy 341.720454 -51.564289) (xy 341.678783 -51.531058)
			(xy 341.642531 -51.491987) (xy 341.612507 -51.44795) (xy 341.589381 -51.399929) (xy 341.573671 -51.348999)
			(xy 341.565728 -51.296295) (xy 340.645378 -51.296295) (xy 340.643394 -51.322764) (xy 340.631529 -51.37474)
			(xy 340.612051 -51.424368) (xy 340.585392 -51.470537) (xy 340.55215 -51.512217) (xy 340.513066 -51.548477)
			(xy 340.469015 -51.578506) (xy 340.420979 -51.601634) (xy 340.370033 -51.617343) (xy 340.317315 -51.625284)
			(xy 340.290658 -51.625754) (xy 340.264653 -51.625277) (xy 340.213196 -51.617713) (xy 340.163385 -51.60275)
			(xy 340.116277 -51.580708) (xy 340.072872 -51.552053) (xy 340.053168 -51.535076) (xy 340.041874 -51.525679)
			(xy 340.015324 -51.513132) (xy 339.986299 -51.508674) (xy 339.957208 -51.512676) (xy 339.930465 -51.524805)
			(xy 339.919056 -51.53406) (xy 339.899549 -51.550437) (xy 339.856709 -51.577987) (xy 339.810382 -51.599155)
			(xy 339.761513 -51.613508) (xy 339.711097 -51.620753) (xy 339.68563 -51.621182) (xy 339.658975 -51.620763)
			(xy 339.606261 -51.612822) (xy 339.55532 -51.597112) (xy 339.507288 -51.573985) (xy 339.463241 -51.543957)
			(xy 339.424161 -51.5077) (xy 339.390922 -51.466022) (xy 339.364266 -51.419856) (xy 339.344789 -51.370232)
			(xy 339.332926 -51.31826) (xy 339.328942 -51.2651) (xy 337.655645 -51.2651) (xy 337.655418 -51.277245)
			(xy 337.647475 -51.329949) (xy 337.631765 -51.380879) (xy 337.608639 -51.4289) (xy 337.578615 -51.472937)
			(xy 337.542363 -51.512008) (xy 337.500692 -51.545239) (xy 337.454534 -51.571888) (xy 337.40492 -51.59136)
			(xy 337.352958 -51.60322) (xy 337.299808 -51.607204) (xy 337.246658 -51.60322) (xy 337.194696 -51.59136)
			(xy 337.145082 -51.571888) (xy 337.098924 -51.545239) (xy 337.057253 -51.512008) (xy 337.021001 -51.472937)
			(xy 336.990977 -51.4289) (xy 336.967851 -51.380879) (xy 336.952141 -51.329949) (xy 336.944198 -51.277245)
			(xy 336.9437 -51.250596) (xy 336.944206 -51.223536) (xy 336.9524 -51.170039) (xy 336.9686 -51.1184)
			(xy 336.992432 -51.069809) (xy 337.023345 -51.025387) (xy 337.060628 -50.986157) (xy 337.103421 -50.953024)
			(xy 337.126834 -50.939446) (xy 337.13849 -50.932508) (xy 337.157922 -50.913596) (xy 337.171694 -50.890238)
			(xy 337.178834 -50.86408) (xy 337.17884 -50.836964) (xy 337.171711 -50.810803) (xy 337.15795 -50.787439)
			(xy 337.138526 -50.768519) (xy 337.126834 -50.761646) (xy 337.103422 -50.748068) (xy 337.06063 -50.714935)
			(xy 337.023348 -50.675705) (xy 336.992435 -50.631283) (xy 336.968605 -50.582692) (xy 336.952406 -50.531054)
			(xy 336.944212 -50.477558) (xy 336.944212 -50.423438) (xy 336.952407 -50.369942) (xy 336.968606 -50.318304)
			(xy 336.992437 -50.269714) (xy 337.02335 -50.225292) (xy 337.060633 -50.186062) (xy 337.103425 -50.15293)
			(xy 337.126834 -50.139346) (xy 337.13849 -50.132408) (xy 337.157922 -50.113496) (xy 337.171694 -50.090138)
			(xy 337.178834 -50.06398) (xy 337.17884 -50.036864) (xy 337.171711 -50.010703) (xy 337.15795 -49.987339)
			(xy 337.138526 -49.968419) (xy 337.126834 -49.961546) (xy 337.105405 -49.949146) (xy 337.065884 -49.919327)
			(xy 337.030876 -49.88432) (xy 337.001057 -49.844799) (xy 336.988658 -49.82337) (xy 336.981717 -49.811724)
			(xy 336.962806 -49.792311) (xy 336.939455 -49.778556) (xy 336.913309 -49.771428) (xy 336.886207 -49.771428)
			(xy 336.860061 -49.778556) (xy 336.83671 -49.792311) (xy 336.817799 -49.811724) (xy 336.810858 -49.82337)
			(xy 336.797282 -49.846785) (xy 336.764152 -49.889583) (xy 336.724923 -49.92687) (xy 336.6805 -49.957787)
			(xy 336.631908 -49.981622) (xy 336.580268 -49.997823) (xy 336.526769 -50.006018) (xy 336.472647 -50.006018)
			(xy 336.419148 -49.997823) (xy 336.367508 -49.981622) (xy 336.318916 -49.957787) (xy 336.274493 -49.92687)
			(xy 336.235264 -49.889583) (xy 336.202134 -49.846785) (xy 336.188558 -49.82337) (xy 336.181617 -49.811724)
			(xy 336.162706 -49.792311) (xy 336.139355 -49.778556) (xy 336.113209 -49.771428) (xy 336.086107 -49.771428)
			(xy 336.059961 -49.778556) (xy 336.03661 -49.792311) (xy 336.017699 -49.811724) (xy 336.010758 -49.82337)
			(xy 335.998358 -49.844799) (xy 335.96854 -49.884321) (xy 335.933533 -49.919329) (xy 335.894013 -49.949149)
			(xy 335.872582 -49.961546) (xy 335.860947 -49.96849) (xy 335.841553 -49.9874) (xy 335.827815 -50.010744)
			(xy 335.820698 -50.036879) (xy 335.820704 -50.063966) (xy 335.827832 -50.090097) (xy 335.841581 -50.113435)
			(xy 335.860983 -50.132337) (xy 335.872582 -50.139346) (xy 335.895999 -50.15292) (xy 335.938802 -50.186048)
			(xy 335.976094 -50.225276) (xy 336.007015 -50.269699) (xy 336.030853 -50.318292) (xy 336.047057 -50.369935)
			(xy 336.055254 -50.423436) (xy 336.055254 -50.477561) (xy 336.047058 -50.531061) (xy 336.030854 -50.582704)
			(xy 336.007017 -50.631298) (xy 335.976096 -50.675721) (xy 335.938805 -50.714949) (xy 335.896003 -50.748078)
			(xy 335.872582 -50.761646) (xy 335.860947 -50.76859) (xy 335.841553 -50.7875) (xy 335.827815 -50.810844)
			(xy 335.820698 -50.836979) (xy 335.820704 -50.864066) (xy 335.827832 -50.890197) (xy 335.841581 -50.913535)
			(xy 335.860983 -50.932437) (xy 335.872582 -50.939446) (xy 335.895995 -50.953022) (xy 335.938787 -50.986153)
			(xy 335.976068 -51.025383) (xy 336.006977 -51.069807) (xy 336.030802 -51.118399) (xy 336.046992 -51.17004)
			(xy 336.055174 -51.223536) (xy 336.055716 -51.250596) (xy 336.055218 -51.277245) (xy 336.047275 -51.329949)
			(xy 336.031565 -51.380879) (xy 336.008439 -51.4289) (xy 335.978415 -51.472937) (xy 335.942163 -51.512008)
			(xy 335.900492 -51.545239) (xy 335.854334 -51.571888) (xy 335.80472 -51.59136) (xy 335.752758 -51.60322)
			(xy 335.699608 -51.607204) (xy 335.646458 -51.60322) (xy 335.594496 -51.59136) (xy 335.544882 -51.571888)
			(xy 335.498724 -51.545239) (xy 335.457053 -51.512008) (xy 335.420801 -51.472937) (xy 335.390777 -51.4289)
			(xy 335.367651 -51.380879) (xy 335.351941 -51.329949) (xy 335.343998 -51.277245) (xy 335.3435 -51.250596)
			(xy 335.344006 -51.223536) (xy 335.3522 -51.170039) (xy 335.3684 -51.1184) (xy 335.392232 -51.069809)
			(xy 335.423145 -51.025387) (xy 335.460428 -50.986157) (xy 335.503221 -50.953024) (xy 335.526634 -50.939446)
			(xy 335.53829 -50.932508) (xy 335.557722 -50.913596) (xy 335.571494 -50.890238) (xy 335.578634 -50.86408)
			(xy 335.57864 -50.836964) (xy 335.571511 -50.810803) (xy 335.55775 -50.787439) (xy 335.538326 -50.768519)
			(xy 335.526634 -50.761646) (xy 335.503222 -50.748068) (xy 335.46043 -50.714935) (xy 335.423148 -50.675705)
			(xy 335.392235 -50.631283) (xy 335.368405 -50.582692) (xy 335.352206 -50.531054) (xy 335.344012 -50.477558)
			(xy 335.344012 -50.423438) (xy 335.352207 -50.369942) (xy 335.368406 -50.318304) (xy 335.392237 -50.269714)
			(xy 335.42315 -50.225292) (xy 335.460433 -50.186062) (xy 335.503225 -50.15293) (xy 335.526634 -50.139346)
			(xy 335.53829 -50.132408) (xy 335.557722 -50.113496) (xy 335.571494 -50.090138) (xy 335.578634 -50.06398)
			(xy 335.57864 -50.036864) (xy 335.571511 -50.010703) (xy 335.55775 -49.987339) (xy 335.538326 -49.968419)
			(xy 335.526634 -49.961546) (xy 335.505205 -49.949146) (xy 335.465684 -49.919327) (xy 335.430676 -49.88432)
			(xy 335.400857 -49.844799) (xy 335.388458 -49.82337) (xy 335.381517 -49.811724) (xy 335.362606 -49.792311)
			(xy 335.339255 -49.778556) (xy 335.313109 -49.771428) (xy 335.286007 -49.771428) (xy 335.259861 -49.778556)
			(xy 335.23651 -49.792311) (xy 335.217599 -49.811724) (xy 335.210658 -49.82337) (xy 335.197082 -49.846785)
			(xy 335.163952 -49.889583) (xy 335.124723 -49.92687) (xy 335.0803 -49.957787) (xy 335.031708 -49.981622)
			(xy 334.980068 -49.997823) (xy 334.926569 -50.006018) (xy 334.872447 -50.006018) (xy 334.818948 -49.997823)
			(xy 334.767308 -49.981622) (xy 334.718716 -49.957787) (xy 334.674293 -49.92687) (xy 334.635064 -49.889583)
			(xy 334.601934 -49.846785) (xy 334.588358 -49.82337) (xy 334.581417 -49.811724) (xy 334.562506 -49.792311)
			(xy 334.539155 -49.778556) (xy 334.513009 -49.771428) (xy 334.485907 -49.771428) (xy 334.459761 -49.778556)
			(xy 334.43641 -49.792311) (xy 334.417499 -49.811724) (xy 334.410558 -49.82337) (xy 334.396983 -49.846784)
			(xy 334.363852 -49.889578) (xy 334.324623 -49.92686) (xy 334.280199 -49.957771) (xy 334.231606 -49.981597)
			(xy 334.179965 -49.997788) (xy 334.126468 -50.005971) (xy 334.099408 -50.006504) (xy 334.073662 -50.00605)
			(xy 334.022707 -49.998632) (xy 333.973352 -49.983952) (xy 333.926627 -49.962313) (xy 333.883507 -49.934169)
			(xy 333.844892 -49.900107) (xy 333.827882 -49.880774) (xy 333.818466 -49.870376) (xy 333.795186 -49.854745)
			(xy 333.768534 -49.846031) (xy 333.740516 -49.844888) (xy 333.713242 -49.851404) (xy 333.688767 -49.865087)
			(xy 333.67853 -49.874678) (xy 333.545688 -50.007774) (xy 333.545688 -50.443384) (xy 333.585312 -50.452274)
			(xy 333.611324 -50.458543) (xy 333.66123 -50.47783) (xy 333.707686 -50.504372) (xy 333.749644 -50.537571)
			(xy 333.786158 -50.576679) (xy 333.816404 -50.620813) (xy 333.8397 -50.668979) (xy 333.855522 -50.72009)
			(xy 333.863512 -50.772994) (xy 333.86395 -50.799746) (xy 333.863398 -50.827728) (xy 333.854637 -50.883002)
			(xy 333.837339 -50.936226) (xy 333.811929 -50.986088) (xy 333.779033 -51.031363) (xy 333.73946 -51.070936)
			(xy 333.694185 -51.103831) (xy 333.644322 -51.129241) (xy 333.591098 -51.146538) (xy 333.535824 -51.155298)
			(xy 333.507842 -51.155854) (xy 333.477424 -51.155237) (xy 333.417472 -51.144901) (xy 333.36015 -51.124524)
			(xy 333.333344 -51.110134) (xy 333.319867 -51.103202) (xy 333.290268 -51.096765) (xy 333.260083 -51.099291)
			(xy 333.231966 -51.110557) (xy 333.208388 -51.129574) (xy 333.191424 -51.154668) (xy 333.182564 -51.183634)
			(xy 333.18196 -51.19878) (xy 333.18196 -51.34102) (xy 333.18248 -51.356204) (xy 333.191329 -51.385251)
			(xy 333.208328 -51.410412) (xy 333.231975 -51.429461) (xy 333.260178 -51.440715) (xy 333.290443 -51.443178)
			(xy 333.320094 -51.436632) (xy 333.333598 -51.429666) (xy 333.360504 -51.415147) (xy 333.41806 -51.394539)
			(xy 333.478291 -51.384069) (xy 333.508858 -51.383438) (xy 333.535508 -51.383908) (xy 333.588213 -51.391846)
			(xy 333.639146 -51.407552) (xy 333.687169 -51.430673) (xy 333.731209 -51.460695) (xy 333.770282 -51.496945)
			(xy 333.803516 -51.538615) (xy 333.830168 -51.584772) (xy 333.849642 -51.634387) (xy 333.861503 -51.68635)
			(xy 333.865486 -51.7395) (xy 344.007714 -51.7395) (xy 344.011697 -51.686353) (xy 344.023557 -51.634393)
			(xy 344.043028 -51.584781) (xy 344.069677 -51.538625) (xy 344.102907 -51.496956) (xy 344.141977 -51.460706)
			(xy 344.186013 -51.430684) (xy 344.234032 -51.407561) (xy 344.284961 -51.391852) (xy 344.337662 -51.38391)
			(xy 344.36431 -51.383438) (xy 344.390461 -51.383895) (xy 344.442197 -51.391563) (xy 344.492254 -51.40672)
			(xy 344.539554 -51.429038) (xy 344.58308 -51.458037) (xy 344.621894 -51.493093) (xy 344.638884 -51.512978)
			(xy 344.64784 -51.523164) (xy 344.670001 -51.538786) (xy 344.695494 -51.548021) (xy 344.722519 -51.550218)
			(xy 344.749168 -51.54522) (xy 344.773561 -51.533382) (xy 344.793976 -51.515538) (xy 344.808972 -51.492948)
			(xy 344.813636 -51.480212) (xy 344.822956 -51.45397) (xy 344.84853 -51.404506) (xy 344.88149 -51.359624)
			(xy 344.921032 -51.320417) (xy 344.966193 -51.28784) (xy 345.015873 -51.262687) (xy 345.068861 -51.245571)
			(xy 345.123868 -51.236908) (xy 345.15171 -51.236372) (xy 345.178357 -51.236911) (xy 345.231056 -51.244855)
			(xy 345.281983 -51.260565) (xy 345.329999 -51.28369) (xy 345.374033 -51.313713) (xy 345.4131 -51.349963)
			(xy 345.446328 -51.391631) (xy 345.472975 -51.437785) (xy 345.492445 -51.487396) (xy 345.504304 -51.539354)
			(xy 345.508287 -51.5925) (xy 345.504304 -51.645646) (xy 345.492445 -51.697604) (xy 345.472975 -51.747215)
			(xy 345.446328 -51.793369) (xy 345.4131 -51.835037) (xy 345.374033 -51.871287) (xy 345.329999 -51.90131)
			(xy 345.281983 -51.924435) (xy 345.231056 -51.940145) (xy 345.178357 -51.948089) (xy 345.15171 -51.948588)
			(xy 345.12556 -51.948108) (xy 345.073826 -51.940443) (xy 345.023769 -51.92529) (xy 344.976469 -51.902976)
			(xy 344.932942 -51.873982) (xy 344.894127 -51.838931) (xy 344.877136 -51.819048) (xy 344.868164 -51.808876)
			(xy 344.846007 -51.793249) (xy 344.820517 -51.784009) (xy 344.793493 -51.781809) (xy 344.766844 -51.786804)
			(xy 344.742452 -51.798642) (xy 344.722039 -51.816486) (xy 344.707046 -51.839077) (xy 344.702384 -51.851814)
			(xy 344.693148 -51.878088) (xy 344.667562 -51.927555) (xy 344.634591 -51.972438) (xy 344.595036 -52.011644)
			(xy 344.549863 -52.044217) (xy 344.500172 -52.069363) (xy 344.447172 -52.086471) (xy 344.392156 -52.095124)
			(xy 344.36431 -52.095654) (xy 344.337662 -52.09509) (xy 344.284961 -52.087148) (xy 344.234032 -52.071439)
			(xy 344.186013 -52.048316) (xy 344.141977 -52.018294) (xy 344.102907 -51.982044) (xy 344.069677 -51.940375)
			(xy 344.043028 -51.894219) (xy 344.023557 -51.844607) (xy 344.011697 -51.792647) (xy 344.007714 -51.7395)
			(xy 333.865486 -51.7395) (xy 333.861503 -51.79265) (xy 333.849642 -51.844613) (xy 333.830168 -51.894228)
			(xy 333.803516 -51.940385) (xy 333.770282 -51.982055) (xy 333.731209 -52.018305) (xy 333.687169 -52.048327)
			(xy 333.639146 -52.071448) (xy 333.588213 -52.087154) (xy 333.535508 -52.095092) (xy 333.508858 -52.095654)
			(xy 333.478294 -52.094995) (xy 333.418071 -52.084513) (xy 333.360518 -52.063914) (xy 333.333598 -52.049426)
			(xy 333.320109 -52.042446) (xy 333.290461 -52.035933) (xy 333.260208 -52.038415) (xy 333.232019 -52.049674)
			(xy 333.20838 -52.068717) (xy 333.191377 -52.093863) (xy 333.18251 -52.122894) (xy 333.18196 -52.138072)
			(xy 333.18196 -52.377848) (xy 333.47787 -52.673758) (xy 333.495224 -52.691743) (xy 333.505593 -52.705995)
			(xy 334.782658 -52.705995) (xy 334.782658 -52.652697) (xy 334.790601 -52.599993) (xy 334.806311 -52.549063)
			(xy 334.829437 -52.501042) (xy 334.859461 -52.457005) (xy 334.895713 -52.417934) (xy 334.937384 -52.384703)
			(xy 334.983542 -52.358054) (xy 335.033156 -52.338582) (xy 335.085118 -52.326722) (xy 335.138268 -52.322739)
			(xy 335.191418 -52.326722) (xy 335.24338 -52.338582) (xy 335.292994 -52.358054) (xy 335.339152 -52.384703)
			(xy 335.380823 -52.417934) (xy 335.417075 -52.457005) (xy 335.447099 -52.501042) (xy 335.470225 -52.549063)
			(xy 335.485935 -52.599993) (xy 335.493878 -52.652697) (xy 335.494376 -52.679346) (xy 335.493878 -52.705995)
			(xy 338.038938 -52.705995) (xy 338.038938 -52.652697) (xy 338.046881 -52.599993) (xy 338.062591 -52.549063)
			(xy 338.085717 -52.501042) (xy 338.115741 -52.457005) (xy 338.151993 -52.417934) (xy 338.193664 -52.384703)
			(xy 338.239822 -52.358054) (xy 338.289436 -52.338582) (xy 338.341398 -52.326722) (xy 338.394548 -52.322739)
			(xy 338.447698 -52.326722) (xy 338.49966 -52.338582) (xy 338.549274 -52.358054) (xy 338.595432 -52.384703)
			(xy 338.637103 -52.417934) (xy 338.673355 -52.457005) (xy 338.699532 -52.4954) (xy 339.267318 -52.4954)
			(xy 339.271301 -52.442253) (xy 339.28316 -52.390294) (xy 339.302632 -52.340683) (xy 339.32928 -52.294528)
			(xy 339.362509 -52.25286) (xy 339.401578 -52.21661) (xy 339.445614 -52.186588) (xy 339.493632 -52.163465)
			(xy 339.54456 -52.147757) (xy 339.59726 -52.139815) (xy 339.623908 -52.139342) (xy 339.652254 -52.139895)
			(xy 339.708228 -52.148895) (xy 339.762064 -52.166665) (xy 339.787484 -52.17922) (xy 339.801493 -52.185838)
			(xy 339.831986 -52.191224) (xy 339.862692 -52.187225) (xy 339.890789 -52.174209) (xy 339.913696 -52.153373)
			(xy 339.929306 -52.12663) (xy 339.93328 -52.111656) (xy 339.939738 -52.08583) (xy 339.95923 -52.036294)
			(xy 339.985883 -51.990215) (xy 340.019102 -51.948619) (xy 340.058147 -51.912435) (xy 340.102145 -51.882471)
			(xy 340.150115 -51.859394) (xy 340.200988 -51.843719) (xy 340.253628 -51.835797) (xy 340.280244 -51.835304)
			(xy 340.306892 -51.835781) (xy 340.359592 -51.84373) (xy 340.410519 -51.859445) (xy 340.458535 -51.882573)
			(xy 340.502568 -51.912599) (xy 340.541635 -51.948853) (xy 340.574862 -51.990523) (xy 340.601509 -52.03668)
			(xy 340.620978 -52.086293) (xy 340.632837 -52.138253) (xy 340.63682 -52.1914) (xy 340.63347 -52.236095)
			(xy 343.19463 -52.236095) (xy 343.19463 -52.182797) (xy 343.202573 -52.130093) (xy 343.218283 -52.079163)
			(xy 343.241409 -52.031142) (xy 343.271433 -51.987105) (xy 343.307685 -51.948034) (xy 343.349356 -51.914803)
			(xy 343.395514 -51.888154) (xy 343.445128 -51.868682) (xy 343.49709 -51.856822) (xy 343.55024 -51.852839)
			(xy 343.60339 -51.856822) (xy 343.655352 -51.868682) (xy 343.704966 -51.888154) (xy 343.751124 -51.914803)
			(xy 343.792795 -51.948034) (xy 343.829047 -51.987105) (xy 343.859071 -52.031142) (xy 343.882197 -52.079163)
			(xy 343.897907 -52.130093) (xy 343.90585 -52.182797) (xy 343.906348 -52.209446) (xy 343.90585 -52.236095)
			(xy 343.897907 -52.288799) (xy 343.882197 -52.339729) (xy 343.859071 -52.38775) (xy 343.829047 -52.431787)
			(xy 343.792795 -52.470858) (xy 343.751124 -52.504089) (xy 343.704966 -52.530738) (xy 343.655352 -52.55021)
			(xy 343.60339 -52.56207) (xy 343.55024 -52.566054) (xy 343.49709 -52.56207) (xy 343.445128 -52.55021)
			(xy 343.395514 -52.530738) (xy 343.349356 -52.504089) (xy 343.307685 -52.470858) (xy 343.271433 -52.431787)
			(xy 343.241409 -52.38775) (xy 343.218283 -52.339729) (xy 343.202573 -52.288799) (xy 343.19463 -52.236095)
			(xy 340.63347 -52.236095) (xy 340.632837 -52.244547) (xy 340.620978 -52.296507) (xy 340.601509 -52.34612)
			(xy 340.574862 -52.392277) (xy 340.541635 -52.433947) (xy 340.502568 -52.470201) (xy 340.458535 -52.500227)
			(xy 340.410519 -52.523355) (xy 340.359592 -52.53907) (xy 340.306892 -52.547019) (xy 340.280244 -52.54752)
			(xy 340.251898 -52.546952) (xy 340.195925 -52.537959) (xy 340.142089 -52.520194) (xy 340.116668 -52.507642)
			(xy 340.102675 -52.500992) (xy 340.072176 -52.49562) (xy 340.041469 -52.499628) (xy 340.013372 -52.51265)
			(xy 339.990464 -52.533489) (xy 339.974849 -52.560232) (xy 339.970872 -52.575206) (xy 339.964432 -52.601038)
			(xy 339.944942 -52.650577) (xy 339.928329 -52.6793) (xy 344.007714 -52.6793) (xy 344.011697 -52.626153)
			(xy 344.023557 -52.574193) (xy 344.043028 -52.524581) (xy 344.069677 -52.478425) (xy 344.102907 -52.436756)
			(xy 344.141977 -52.400506) (xy 344.186013 -52.370484) (xy 344.234032 -52.347361) (xy 344.284961 -52.331652)
			(xy 344.337662 -52.32371) (xy 344.36431 -52.323238) (xy 344.392139 -52.323804) (xy 344.447121 -52.332451)
			(xy 344.500087 -52.349549) (xy 344.549748 -52.374681) (xy 344.594893 -52.407234) (xy 344.634422 -52.446416)
			(xy 344.65133 -52.468526) (xy 344.660779 -52.480458) (xy 344.685232 -52.498554) (xy 344.713929 -52.508647)
			(xy 344.744327 -52.509843) (xy 344.773729 -52.502036) (xy 344.799528 -52.485917) (xy 344.819438 -52.462916)
			(xy 344.826082 -52.449222) (xy 344.836903 -52.425903) (xy 344.864227 -52.38236) (xy 344.89753 -52.3432)
			(xy 344.93612 -52.309238) (xy 344.979194 -52.28118) (xy 345.025856 -52.25961) (xy 345.075135 -52.244976)
			(xy 345.126007 -52.237583) (xy 345.15171 -52.237132) (xy 345.178362 -52.23755) (xy 345.23107 -52.245496)
			(xy 345.282005 -52.261209) (xy 345.33003 -52.284338) (xy 345.374071 -52.314365) (xy 345.413144 -52.350622)
			(xy 345.446378 -52.392296) (xy 345.47303 -52.438459) (xy 345.492503 -52.488078) (xy 345.504364 -52.540045)
			(xy 345.508348 -52.5932) (xy 345.504364 -52.646355) (xy 345.492503 -52.698322) (xy 345.47303 -52.747941)
			(xy 345.446378 -52.794104) (xy 345.413144 -52.835778) (xy 345.374071 -52.872035) (xy 345.33003 -52.902062)
			(xy 345.282005 -52.925191) (xy 345.26792 -52.929536) (xy 347.47455 -52.929536) (xy 347.478526 -52.87521)
			(xy 347.490369 -52.822041) (xy 347.509828 -52.771164) (xy 347.536488 -52.723662) (xy 347.569779 -52.680548)
			(xy 347.608993 -52.642741) (xy 347.653295 -52.611046) (xy 347.701738 -52.58614) (xy 347.753292 -52.568552)
			(xy 347.806858 -52.558658) (xy 347.861293 -52.556668) (xy 347.915438 -52.562626) (xy 347.968138 -52.576404)
			(xy 348.018271 -52.597708) (xy 348.064767 -52.626084) (xy 348.106637 -52.660928) (xy 348.142986 -52.701497)
			(xy 348.173042 -52.746926) (xy 348.196163 -52.796247) (xy 348.211856 -52.848409) (xy 348.219787 -52.9023)
			(xy 348.220284 -52.929536) (xy 348.220108 -52.939188) (xy 348.944182 -52.939188) (xy 348.948253 -52.883566)
			(xy 348.960379 -52.829129) (xy 348.980302 -52.777038) (xy 349.007598 -52.728403) (xy 349.041684 -52.68426)
			(xy 349.081833 -52.645551) (xy 349.127191 -52.6131) (xy 349.176791 -52.587599) (xy 349.229575 -52.569592)
			(xy 349.284418 -52.559462) (xy 349.340152 -52.557425) (xy 349.395589 -52.563525) (xy 349.449546 -52.577631)
			(xy 349.500875 -52.599443) (xy 349.548481 -52.628497) (xy 349.591349 -52.664172) (xy 349.628566 -52.705709)
			(xy 349.659339 -52.752222) (xy 349.683011 -52.802719) (xy 349.699079 -52.856126) (xy 349.707199 -52.911302)
			(xy 349.707708 -52.939188) (xy 349.707199 -52.967074) (xy 349.699079 -53.02225) (xy 349.683011 -53.075657)
			(xy 349.659339 -53.126154) (xy 349.628566 -53.172667) (xy 349.591349 -53.214204) (xy 349.548481 -53.249879)
			(xy 349.500875 -53.278933) (xy 349.449546 -53.300745) (xy 349.395589 -53.314851) (xy 349.340152 -53.320951)
			(xy 349.284418 -53.318914) (xy 349.229575 -53.308784) (xy 349.176791 -53.290777) (xy 349.127191 -53.265276)
			(xy 349.081833 -53.232825) (xy 349.041684 -53.194116) (xy 349.007598 -53.149973) (xy 348.980302 -53.101338)
			(xy 348.960379 -53.049247) (xy 348.948253 -52.99481) (xy 348.944182 -52.939188) (xy 348.220108 -52.939188)
			(xy 348.219787 -52.956772) (xy 348.211856 -53.010663) (xy 348.196163 -53.062825) (xy 348.173042 -53.112146)
			(xy 348.142986 -53.157575) (xy 348.106637 -53.198144) (xy 348.064767 -53.232988) (xy 348.018271 -53.261364)
			(xy 347.968138 -53.282668) (xy 347.915438 -53.296446) (xy 347.861293 -53.302404) (xy 347.806858 -53.300414)
			(xy 347.753292 -53.29052) (xy 347.701738 -53.272932) (xy 347.653295 -53.248026) (xy 347.608993 -53.216331)
			(xy 347.569779 -53.178524) (xy 347.536488 -53.13541) (xy 347.509828 -53.087908) (xy 347.490369 -53.037031)
			(xy 347.478526 -52.983862) (xy 347.47455 -52.929536) (xy 345.26792 -52.929536) (xy 345.23107 -52.940904)
			(xy 345.178362 -52.94885) (xy 345.15171 -52.949348) (xy 345.123879 -52.948846) (xy 345.068893 -52.940186)
			(xy 345.015925 -52.923076) (xy 344.966265 -52.897932) (xy 344.921122 -52.865367) (xy 344.881596 -52.826175)
			(xy 344.86469 -52.80406) (xy 344.855214 -52.792153) (xy 344.830767 -52.77406) (xy 344.802076 -52.763967)
			(xy 344.771685 -52.762768) (xy 344.742289 -52.77057) (xy 344.716493 -52.786682) (xy 344.696583 -52.809674)
			(xy 344.689938 -52.823364) (xy 344.679174 -52.846711) (xy 344.651844 -52.890257) (xy 344.618533 -52.929418)
			(xy 344.579935 -52.963379) (xy 344.536852 -52.991434) (xy 344.490182 -53.012998) (xy 344.440895 -53.027625)
			(xy 344.390016 -53.035008) (xy 344.36431 -53.035454) (xy 344.337662 -53.03489) (xy 344.284961 -53.026948)
			(xy 344.234032 -53.011239) (xy 344.186013 -52.988116) (xy 344.141977 -52.958094) (xy 344.102907 -52.921844)
			(xy 344.069677 -52.880175) (xy 344.043028 -52.834019) (xy 344.023557 -52.784407) (xy 344.011697 -52.732447)
			(xy 344.007714 -52.6793) (xy 339.928329 -52.6793) (xy 339.918289 -52.696659) (xy 339.885068 -52.738257)
			(xy 339.846021 -52.774442) (xy 339.80202 -52.804406) (xy 339.754045 -52.827481) (xy 339.703169 -52.843152)
			(xy 339.650526 -52.851068) (xy 339.623908 -52.851558) (xy 339.59726 -52.850985) (xy 339.54456 -52.843043)
			(xy 339.493632 -52.827335) (xy 339.445614 -52.804212) (xy 339.401578 -52.77419) (xy 339.362509 -52.73794)
			(xy 339.32928 -52.696272) (xy 339.302632 -52.650117) (xy 339.28316 -52.600506) (xy 339.271301 -52.548547)
			(xy 339.267318 -52.4954) (xy 338.699532 -52.4954) (xy 338.703379 -52.501042) (xy 338.726505 -52.549063)
			(xy 338.742215 -52.599993) (xy 338.750158 -52.652697) (xy 338.750656 -52.679346) (xy 338.750158 -52.705995)
			(xy 338.742215 -52.758699) (xy 338.726505 -52.809629) (xy 338.703379 -52.85765) (xy 338.673355 -52.901687)
			(xy 338.637103 -52.940758) (xy 338.595432 -52.973989) (xy 338.549274 -53.000638) (xy 338.49966 -53.02011)
			(xy 338.447698 -53.03197) (xy 338.394548 -53.035954) (xy 338.341398 -53.03197) (xy 338.289436 -53.02011)
			(xy 338.239822 -53.000638) (xy 338.193664 -52.973989) (xy 338.151993 -52.940758) (xy 338.115741 -52.901687)
			(xy 338.085717 -52.85765) (xy 338.062591 -52.809629) (xy 338.046881 -52.758699) (xy 338.038938 -52.705995)
			(xy 335.493878 -52.705995) (xy 335.485935 -52.758699) (xy 335.470225 -52.809629) (xy 335.447099 -52.85765)
			(xy 335.417075 -52.901687) (xy 335.380823 -52.940758) (xy 335.339152 -52.973989) (xy 335.292994 -53.000638)
			(xy 335.24338 -53.02011) (xy 335.191418 -53.03197) (xy 335.138268 -53.035954) (xy 335.085118 -53.03197)
			(xy 335.033156 -53.02011) (xy 334.983542 -53.000638) (xy 334.937384 -52.973989) (xy 334.895713 -52.940758)
			(xy 334.859461 -52.901687) (xy 334.829437 -52.85765) (xy 334.806311 -52.809629) (xy 334.790601 -52.758699)
			(xy 334.782658 -52.705995) (xy 333.505593 -52.705995) (xy 333.524625 -52.732155) (xy 333.547333 -52.776674)
			(xy 333.562787 -52.8242) (xy 333.570608 -52.87356) (xy 333.571088 -52.898548) (xy 333.571088 -53.175895)
			(xy 333.969858 -53.175895) (xy 333.969858 -53.122597) (xy 333.977801 -53.069893) (xy 333.993511 -53.018963)
			(xy 334.016637 -52.970942) (xy 334.046661 -52.926905) (xy 334.082913 -52.887834) (xy 334.124584 -52.854603)
			(xy 334.170742 -52.827954) (xy 334.220356 -52.808482) (xy 334.272318 -52.796622) (xy 334.325468 -52.792639)
			(xy 334.378618 -52.796622) (xy 334.43058 -52.808482) (xy 334.480194 -52.827954) (xy 334.526352 -52.854603)
			(xy 334.568023 -52.887834) (xy 334.604275 -52.926905) (xy 334.634299 -52.970942) (xy 334.657425 -53.018963)
			(xy 334.673135 -53.069893) (xy 334.681078 -53.122597) (xy 334.681576 -53.149246) (xy 334.681078 -53.175895)
			(xy 335.597998 -53.175895) (xy 335.597998 -53.122597) (xy 335.605941 -53.069893) (xy 335.621651 -53.018963)
			(xy 335.644777 -52.970942) (xy 335.674801 -52.926905) (xy 335.711053 -52.887834) (xy 335.752724 -52.854603)
			(xy 335.798882 -52.827954) (xy 335.848496 -52.808482) (xy 335.900458 -52.796622) (xy 335.953608 -52.792639)
			(xy 336.006758 -52.796622) (xy 336.05872 -52.808482) (xy 336.108334 -52.827954) (xy 336.154492 -52.854603)
			(xy 336.196163 -52.887834) (xy 336.232415 -52.926905) (xy 336.262439 -52.970942) (xy 336.285565 -53.018963)
			(xy 336.301275 -53.069893) (xy 336.309218 -53.122597) (xy 336.309716 -53.149246) (xy 336.309218 -53.175895)
			(xy 337.226138 -53.175895) (xy 337.226138 -53.122597) (xy 337.234081 -53.069893) (xy 337.249791 -53.018963)
			(xy 337.272917 -52.970942) (xy 337.302941 -52.926905) (xy 337.339193 -52.887834) (xy 337.380864 -52.854603)
			(xy 337.427022 -52.827954) (xy 337.476636 -52.808482) (xy 337.528598 -52.796622) (xy 337.581748 -52.792639)
			(xy 337.634898 -52.796622) (xy 337.68686 -52.808482) (xy 337.736474 -52.827954) (xy 337.782632 -52.854603)
			(xy 337.824303 -52.887834) (xy 337.860555 -52.926905) (xy 337.890579 -52.970942) (xy 337.913705 -53.018963)
			(xy 337.929415 -53.069893) (xy 337.937358 -53.122597) (xy 337.937856 -53.149246) (xy 337.937358 -53.175895)
			(xy 339.935048 -53.175895) (xy 339.935048 -53.122597) (xy 339.942991 -53.069893) (xy 339.958701 -53.018963)
			(xy 339.981827 -52.970942) (xy 340.011851 -52.926905) (xy 340.048103 -52.887834) (xy 340.089774 -52.854603)
			(xy 340.135932 -52.827954) (xy 340.185546 -52.808482) (xy 340.237508 -52.796622) (xy 340.290658 -52.792639)
			(xy 340.343808 -52.796622) (xy 340.39577 -52.808482) (xy 340.445384 -52.827954) (xy 340.491542 -52.854603)
			(xy 340.533213 -52.887834) (xy 340.569465 -52.926905) (xy 340.599489 -52.970942) (xy 340.622615 -53.018963)
			(xy 340.638325 -53.069893) (xy 340.646268 -53.122597) (xy 340.646766 -53.149246) (xy 340.646273 -53.175641)
			(xy 341.565728 -53.175641) (xy 341.565728 -53.122343) (xy 341.573671 -53.069639) (xy 341.589381 -53.018709)
			(xy 341.612507 -52.970688) (xy 341.642531 -52.926651) (xy 341.678783 -52.88758) (xy 341.720454 -52.854349)
			(xy 341.766612 -52.8277) (xy 341.816226 -52.808228) (xy 341.868188 -52.796368) (xy 341.921338 -52.792385)
			(xy 341.974488 -52.796368) (xy 342.02645 -52.808228) (xy 342.076064 -52.8277) (xy 342.122222 -52.854349)
			(xy 342.163893 -52.88758) (xy 342.200145 -52.926651) (xy 342.230169 -52.970688) (xy 342.253295 -53.018709)
			(xy 342.269005 -53.069639) (xy 342.276948 -53.122343) (xy 342.277446 -53.148992) (xy 342.276948 -53.175641)
			(xy 342.269005 -53.228345) (xy 342.253295 -53.279275) (xy 342.230169 -53.327296) (xy 342.200145 -53.371333)
			(xy 342.163893 -53.410404) (xy 342.122222 -53.443635) (xy 342.076064 -53.470284) (xy 342.02645 -53.489756)
			(xy 341.974488 -53.501616) (xy 341.921338 -53.5056) (xy 341.868188 -53.501616) (xy 341.816226 -53.489756)
			(xy 341.766612 -53.470284) (xy 341.720454 -53.443635) (xy 341.678783 -53.410404) (xy 341.642531 -53.371333)
			(xy 341.612507 -53.327296) (xy 341.589381 -53.279275) (xy 341.573671 -53.228345) (xy 341.565728 -53.175641)
			(xy 340.646273 -53.175641) (xy 340.646268 -53.175895) (xy 340.638325 -53.228599) (xy 340.622615 -53.279529)
			(xy 340.599489 -53.32755) (xy 340.569465 -53.371587) (xy 340.533213 -53.410658) (xy 340.491542 -53.443889)
			(xy 340.445384 -53.470538) (xy 340.39577 -53.49001) (xy 340.343808 -53.50187) (xy 340.290658 -53.505854)
			(xy 340.237508 -53.50187) (xy 340.185546 -53.49001) (xy 340.135932 -53.470538) (xy 340.089774 -53.443889)
			(xy 340.048103 -53.410658) (xy 340.011851 -53.371587) (xy 339.981827 -53.32755) (xy 339.958701 -53.279529)
			(xy 339.942991 -53.228599) (xy 339.935048 -53.175895) (xy 337.937358 -53.175895) (xy 337.929415 -53.228599)
			(xy 337.913705 -53.279529) (xy 337.890579 -53.32755) (xy 337.860555 -53.371587) (xy 337.824303 -53.410658)
			(xy 337.782632 -53.443889) (xy 337.736474 -53.470538) (xy 337.68686 -53.49001) (xy 337.634898 -53.50187)
			(xy 337.581748 -53.505854) (xy 337.528598 -53.50187) (xy 337.476636 -53.49001) (xy 337.427022 -53.470538)
			(xy 337.380864 -53.443889) (xy 337.339193 -53.410658) (xy 337.302941 -53.371587) (xy 337.272917 -53.32755)
			(xy 337.249791 -53.279529) (xy 337.234081 -53.228599) (xy 337.226138 -53.175895) (xy 336.309218 -53.175895)
			(xy 336.301275 -53.228599) (xy 336.285565 -53.279529) (xy 336.262439 -53.32755) (xy 336.232415 -53.371587)
			(xy 336.196163 -53.410658) (xy 336.154492 -53.443889) (xy 336.108334 -53.470538) (xy 336.05872 -53.49001)
			(xy 336.006758 -53.50187) (xy 335.953608 -53.505854) (xy 335.900458 -53.50187) (xy 335.848496 -53.49001)
			(xy 335.798882 -53.470538) (xy 335.752724 -53.443889) (xy 335.711053 -53.410658) (xy 335.674801 -53.371587)
			(xy 335.644777 -53.32755) (xy 335.621651 -53.279529) (xy 335.605941 -53.228599) (xy 335.597998 -53.175895)
			(xy 334.681078 -53.175895) (xy 334.673135 -53.228599) (xy 334.657425 -53.279529) (xy 334.634299 -53.32755)
			(xy 334.604275 -53.371587) (xy 334.568023 -53.410658) (xy 334.526352 -53.443889) (xy 334.480194 -53.470538)
			(xy 334.43058 -53.49001) (xy 334.378618 -53.50187) (xy 334.325468 -53.505854) (xy 334.272318 -53.50187)
			(xy 334.220356 -53.49001) (xy 334.170742 -53.470538) (xy 334.124584 -53.443889) (xy 334.082913 -53.410658)
			(xy 334.046661 -53.371587) (xy 334.016637 -53.32755) (xy 333.993511 -53.279529) (xy 333.977801 -53.228599)
			(xy 333.969858 -53.175895) (xy 333.571088 -53.175895) (xy 333.571088 -53.645795) (xy 336.410798 -53.645795)
			(xy 336.410798 -53.592497) (xy 336.418741 -53.539793) (xy 336.434451 -53.488863) (xy 336.457577 -53.440842)
			(xy 336.487601 -53.396805) (xy 336.523853 -53.357734) (xy 336.565524 -53.324503) (xy 336.611682 -53.297854)
			(xy 336.661296 -53.278382) (xy 336.713258 -53.266522) (xy 336.766408 -53.262539) (xy 336.819558 -53.266522)
			(xy 336.87152 -53.278382) (xy 336.921134 -53.297854) (xy 336.967292 -53.324503) (xy 337.008963 -53.357734)
			(xy 337.045215 -53.396805) (xy 337.075239 -53.440842) (xy 337.098365 -53.488863) (xy 337.114075 -53.539793)
			(xy 337.122018 -53.592497) (xy 337.122516 -53.619146) (xy 337.122018 -53.645795) (xy 338.038938 -53.645795)
			(xy 338.038938 -53.592497) (xy 338.046881 -53.539793) (xy 338.062591 -53.488863) (xy 338.085717 -53.440842)
			(xy 338.115741 -53.396805) (xy 338.151993 -53.357734) (xy 338.193664 -53.324503) (xy 338.239822 -53.297854)
			(xy 338.289436 -53.278382) (xy 338.341398 -53.266522) (xy 338.394548 -53.262539) (xy 338.447698 -53.266522)
			(xy 338.49966 -53.278382) (xy 338.549274 -53.297854) (xy 338.595432 -53.324503) (xy 338.637103 -53.357734)
			(xy 338.673355 -53.396805) (xy 338.703379 -53.440842) (xy 338.726505 -53.488863) (xy 338.742215 -53.539793)
			(xy 338.750158 -53.592497) (xy 338.750656 -53.619146) (xy 338.750163 -53.645541) (xy 342.379544 -53.645541)
			(xy 342.379544 -53.592243) (xy 342.387487 -53.539539) (xy 342.403197 -53.488609) (xy 342.426323 -53.440588)
			(xy 342.456347 -53.396551) (xy 342.492599 -53.35748) (xy 342.53427 -53.324249) (xy 342.580428 -53.2976)
			(xy 342.630042 -53.278128) (xy 342.682004 -53.266268) (xy 342.735154 -53.262285) (xy 342.788304 -53.266268)
			(xy 342.840266 -53.278128) (xy 342.88988 -53.2976) (xy 342.936038 -53.324249) (xy 342.977709 -53.35748)
			(xy 343.013961 -53.396551) (xy 343.043985 -53.440588) (xy 343.067111 -53.488609) (xy 343.082821 -53.539539)
			(xy 343.090764 -53.592243) (xy 343.091262 -53.618892) (xy 343.090764 -53.645541) (xy 343.082821 -53.698245)
			(xy 343.067111 -53.749175) (xy 343.043985 -53.797196) (xy 343.013961 -53.841233) (xy 342.977709 -53.880304)
			(xy 342.936038 -53.913535) (xy 342.88988 -53.940184) (xy 342.840266 -53.959656) (xy 342.788304 -53.971516)
			(xy 342.735154 -53.9755) (xy 342.682004 -53.971516) (xy 342.630042 -53.959656) (xy 342.580428 -53.940184)
			(xy 342.53427 -53.913535) (xy 342.492599 -53.880304) (xy 342.456347 -53.841233) (xy 342.426323 -53.797196)
			(xy 342.403197 -53.749175) (xy 342.387487 -53.698245) (xy 342.379544 -53.645541) (xy 338.750163 -53.645541)
			(xy 338.750158 -53.645795) (xy 338.742215 -53.698499) (xy 338.726505 -53.749429) (xy 338.703379 -53.79745)
			(xy 338.673355 -53.841487) (xy 338.637103 -53.880558) (xy 338.595432 -53.913789) (xy 338.549274 -53.940438)
			(xy 338.49966 -53.95991) (xy 338.447698 -53.97177) (xy 338.394548 -53.975754) (xy 338.341398 -53.97177)
			(xy 338.289436 -53.95991) (xy 338.239822 -53.940438) (xy 338.193664 -53.913789) (xy 338.151993 -53.880558)
			(xy 338.115741 -53.841487) (xy 338.085717 -53.79745) (xy 338.062591 -53.749429) (xy 338.046881 -53.698499)
			(xy 338.038938 -53.645795) (xy 337.122018 -53.645795) (xy 337.114075 -53.698499) (xy 337.098365 -53.749429)
			(xy 337.075239 -53.79745) (xy 337.045215 -53.841487) (xy 337.008963 -53.880558) (xy 336.967292 -53.913789)
			(xy 336.921134 -53.940438) (xy 336.87152 -53.95991) (xy 336.819558 -53.97177) (xy 336.766408 -53.975754)
			(xy 336.713258 -53.97177) (xy 336.661296 -53.95991) (xy 336.611682 -53.940438) (xy 336.565524 -53.913789)
			(xy 336.523853 -53.880558) (xy 336.487601 -53.841487) (xy 336.457577 -53.79745) (xy 336.434451 -53.749429)
			(xy 336.418741 -53.698499) (xy 336.410798 -53.645795) (xy 333.571088 -53.645795) (xy 333.571088 -53.889148)
			(xy 333.570573 -53.91413) (xy 333.562717 -53.963475) (xy 333.547251 -54.010986) (xy 333.524555 -54.0555)
			(xy 333.495187 -54.095924) (xy 333.47787 -54.113938) (xy 333.476113 -54.115695) (xy 337.226138 -54.115695)
			(xy 337.226138 -54.062397) (xy 337.234081 -54.009693) (xy 337.249791 -53.958763) (xy 337.272917 -53.910742)
			(xy 337.302941 -53.866705) (xy 337.339193 -53.827634) (xy 337.380864 -53.794403) (xy 337.427022 -53.767754)
			(xy 337.476636 -53.748282) (xy 337.528598 -53.736422) (xy 337.581748 -53.732439) (xy 337.634898 -53.736422)
			(xy 337.68686 -53.748282) (xy 337.736474 -53.767754) (xy 337.782632 -53.794403) (xy 337.824303 -53.827634)
			(xy 337.860555 -53.866705) (xy 337.890579 -53.910742) (xy 337.913705 -53.958763) (xy 337.929415 -54.009693)
			(xy 337.937358 -54.062397) (xy 337.937856 -54.089046) (xy 337.937358 -54.115695) (xy 341.565728 -54.115695)
			(xy 341.565728 -54.062397) (xy 341.573671 -54.009693) (xy 341.589381 -53.958763) (xy 341.612507 -53.910742)
			(xy 341.642531 -53.866705) (xy 341.678783 -53.827634) (xy 341.720454 -53.794403) (xy 341.766612 -53.767754)
			(xy 341.816226 -53.748282) (xy 341.868188 -53.736422) (xy 341.921338 -53.732439) (xy 341.974488 -53.736422)
			(xy 342.02645 -53.748282) (xy 342.076064 -53.767754) (xy 342.122222 -53.794403) (xy 342.163893 -53.827634)
			(xy 342.200145 -53.866705) (xy 342.230169 -53.910742) (xy 342.253295 -53.958763) (xy 342.269005 -54.009693)
			(xy 342.276948 -54.062397) (xy 342.277446 -54.089046) (xy 342.276953 -54.115441) (xy 343.194884 -54.115441)
			(xy 343.194884 -54.062143) (xy 343.202827 -54.009439) (xy 343.218537 -53.958509) (xy 343.241663 -53.910488)
			(xy 343.271687 -53.866451) (xy 343.307939 -53.82738) (xy 343.34961 -53.794149) (xy 343.395768 -53.7675)
			(xy 343.445382 -53.748028) (xy 343.497344 -53.736168) (xy 343.550494 -53.732185) (xy 343.603644 -53.736168)
			(xy 343.655606 -53.748028) (xy 343.70522 -53.7675) (xy 343.751378 -53.794149) (xy 343.793049 -53.82738)
			(xy 343.829301 -53.866451) (xy 343.859325 -53.910488) (xy 343.882451 -53.958509) (xy 343.898161 -54.009439)
			(xy 343.906104 -54.062143) (xy 343.906602 -54.088792) (xy 343.906104 -54.115441) (xy 343.898161 -54.168145)
			(xy 343.882451 -54.219075) (xy 343.859325 -54.267096) (xy 343.829301 -54.311133) (xy 343.793049 -54.350204)
			(xy 343.751378 -54.383435) (xy 343.70522 -54.410084) (xy 343.655606 -54.429556) (xy 343.603644 -54.441416)
			(xy 343.550494 -54.4454) (xy 343.497344 -54.441416) (xy 343.445382 -54.429556) (xy 343.395768 -54.410084)
			(xy 343.34961 -54.383435) (xy 343.307939 -54.350204) (xy 343.271687 -54.311133) (xy 343.241663 -54.267096)
			(xy 343.218537 -54.219075) (xy 343.202827 -54.168145) (xy 343.194884 -54.115441) (xy 342.276953 -54.115441)
			(xy 342.276948 -54.115695) (xy 342.269005 -54.168399) (xy 342.253295 -54.219329) (xy 342.230169 -54.26735)
			(xy 342.200145 -54.311387) (xy 342.163893 -54.350458) (xy 342.122222 -54.383689) (xy 342.076064 -54.410338)
			(xy 342.02645 -54.42981) (xy 341.974488 -54.44167) (xy 341.921338 -54.445654) (xy 341.868188 -54.44167)
			(xy 341.816226 -54.42981) (xy 341.766612 -54.410338) (xy 341.720454 -54.383689) (xy 341.678783 -54.350458)
			(xy 341.642531 -54.311387) (xy 341.612507 -54.26735) (xy 341.589381 -54.219329) (xy 341.573671 -54.168399)
			(xy 341.565728 -54.115695) (xy 337.937358 -54.115695) (xy 337.929415 -54.168399) (xy 337.913705 -54.219329)
			(xy 337.890579 -54.26735) (xy 337.860555 -54.311387) (xy 337.824303 -54.350458) (xy 337.782632 -54.383689)
			(xy 337.736474 -54.410338) (xy 337.68686 -54.42981) (xy 337.634898 -54.44167) (xy 337.581748 -54.445654)
			(xy 337.528598 -54.44167) (xy 337.476636 -54.42981) (xy 337.427022 -54.410338) (xy 337.380864 -54.383689)
			(xy 337.339193 -54.350458) (xy 337.302941 -54.311387) (xy 337.272917 -54.26735) (xy 337.249791 -54.219329)
			(xy 337.234081 -54.168399) (xy 337.226138 -54.115695) (xy 333.476113 -54.115695) (xy 333.43977 -54.152038)
			(xy 333.49057 -54.202838) (xy 333.511398 -54.202838) (xy 333.539313 -54.203484) (xy 333.594431 -54.2124)
			(xy 333.647482 -54.22981) (xy 333.697164 -54.255287) (xy 333.742262 -54.288206) (xy 333.781668 -54.327762)
			(xy 333.814417 -54.372983) (xy 333.839707 -54.422762) (xy 333.856916 -54.475878) (xy 333.865624 -54.531029)
			(xy 333.866236 -54.558946) (xy 333.86571 -54.585595) (xy 336.410798 -54.585595) (xy 336.410798 -54.532297)
			(xy 336.418741 -54.479593) (xy 336.434451 -54.428663) (xy 336.457577 -54.380642) (xy 336.487601 -54.336605)
			(xy 336.523853 -54.297534) (xy 336.565524 -54.264303) (xy 336.611682 -54.237654) (xy 336.661296 -54.218182)
			(xy 336.713258 -54.206322) (xy 336.766408 -54.202339) (xy 336.819558 -54.206322) (xy 336.87152 -54.218182)
			(xy 336.921134 -54.237654) (xy 336.967292 -54.264303) (xy 337.008963 -54.297534) (xy 337.045215 -54.336605)
			(xy 337.075239 -54.380642) (xy 337.098365 -54.428663) (xy 337.114075 -54.479593) (xy 337.122018 -54.532297)
			(xy 337.122516 -54.558946) (xy 337.122018 -54.585595) (xy 338.038938 -54.585595) (xy 338.038938 -54.532297)
			(xy 338.046881 -54.479593) (xy 338.062591 -54.428663) (xy 338.085717 -54.380642) (xy 338.115741 -54.336605)
			(xy 338.151993 -54.297534) (xy 338.193664 -54.264303) (xy 338.239822 -54.237654) (xy 338.289436 -54.218182)
			(xy 338.341398 -54.206322) (xy 338.394548 -54.202339) (xy 338.447698 -54.206322) (xy 338.49966 -54.218182)
			(xy 338.549274 -54.237654) (xy 338.595432 -54.264303) (xy 338.637103 -54.297534) (xy 338.673355 -54.336605)
			(xy 338.703379 -54.380642) (xy 338.726505 -54.428663) (xy 338.742215 -54.479593) (xy 338.750158 -54.532297)
			(xy 338.750656 -54.558946) (xy 338.750158 -54.585595) (xy 339.122248 -54.585595) (xy 339.122248 -54.532297)
			(xy 339.130191 -54.479593) (xy 339.145901 -54.428663) (xy 339.169027 -54.380642) (xy 339.199051 -54.336605)
			(xy 339.235303 -54.297534) (xy 339.276974 -54.264303) (xy 339.323132 -54.237654) (xy 339.372746 -54.218182)
			(xy 339.424708 -54.206322) (xy 339.477858 -54.202339) (xy 339.531008 -54.206322) (xy 339.58297 -54.218182)
			(xy 339.632584 -54.237654) (xy 339.678742 -54.264303) (xy 339.720413 -54.297534) (xy 339.756665 -54.336605)
			(xy 339.786689 -54.380642) (xy 339.809815 -54.428663) (xy 339.825525 -54.479593) (xy 339.833468 -54.532297)
			(xy 339.833966 -54.558946) (xy 339.833468 -54.585595) (xy 340.750388 -54.585595) (xy 340.750388 -54.532297)
			(xy 340.758331 -54.479593) (xy 340.774041 -54.428663) (xy 340.797167 -54.380642) (xy 340.827191 -54.336605)
			(xy 340.863443 -54.297534) (xy 340.905114 -54.264303) (xy 340.951272 -54.237654) (xy 341.000886 -54.218182)
			(xy 341.052848 -54.206322) (xy 341.105998 -54.202339) (xy 341.159148 -54.206322) (xy 341.21111 -54.218182)
			(xy 341.260724 -54.237654) (xy 341.306882 -54.264303) (xy 341.348553 -54.297534) (xy 341.384805 -54.336605)
			(xy 341.414829 -54.380642) (xy 341.437955 -54.428663) (xy 341.453665 -54.479593) (xy 341.461608 -54.532297)
			(xy 341.462106 -54.558946) (xy 341.461613 -54.585341) (xy 342.379544 -54.585341) (xy 342.379544 -54.532043)
			(xy 342.387487 -54.479339) (xy 342.403197 -54.428409) (xy 342.426323 -54.380388) (xy 342.456347 -54.336351)
			(xy 342.492599 -54.29728) (xy 342.53427 -54.264049) (xy 342.580428 -54.2374) (xy 342.630042 -54.217928)
			(xy 342.682004 -54.206068) (xy 342.735154 -54.202085) (xy 342.788304 -54.206068) (xy 342.840266 -54.217928)
			(xy 342.88988 -54.2374) (xy 342.936038 -54.264049) (xy 342.977709 -54.29728) (xy 343.013961 -54.336351)
			(xy 343.043985 -54.380388) (xy 343.067111 -54.428409) (xy 343.082821 -54.479339) (xy 343.090764 -54.532043)
			(xy 343.091262 -54.558692) (xy 343.091262 -54.5587) (xy 344.007984 -54.5587) (xy 344.011967 -54.505553)
			(xy 344.023826 -54.453592) (xy 344.043296 -54.40398) (xy 344.069943 -54.357823) (xy 344.103171 -54.316152)
			(xy 344.142238 -54.2799) (xy 344.186271 -54.249874) (xy 344.234288 -54.226746) (xy 344.285215 -54.211032)
			(xy 344.337916 -54.203084) (xy 344.364564 -54.202584) (xy 344.389502 -54.202992) (xy 344.438893 -54.209937)
			(xy 344.48683 -54.223709) (xy 344.532374 -54.244038) (xy 344.574635 -54.270527) (xy 344.612783 -54.302657)
			(xy 344.62974 -54.320948) (xy 344.639336 -54.331034) (xy 344.662818 -54.34597) (xy 344.68946 -54.354016)
			(xy 344.717285 -54.354573) (xy 344.744228 -54.347601) (xy 344.76829 -54.333617) (xy 344.787685 -54.313658)
			(xy 344.800974 -54.289206) (xy 344.804492 -54.275736) (xy 344.810896 -54.249835) (xy 344.830304 -54.20014)
			(xy 344.856913 -54.153898) (xy 344.890125 -54.112145) (xy 344.929197 -54.075817) (xy 344.973253 -54.045727)
			(xy 345.021306 -54.02255) (xy 345.072281 -54.006805) (xy 345.125034 -53.998843) (xy 345.15171 -53.998368)
			(xy 345.178357 -53.998915) (xy 345.231056 -54.006859) (xy 345.281981 -54.022569) (xy 345.329997 -54.045693)
			(xy 345.37403 -54.075716) (xy 345.413097 -54.111965) (xy 345.446325 -54.153633) (xy 345.472971 -54.199787)
			(xy 345.492442 -54.249397) (xy 345.5043 -54.301355) (xy 345.508283 -54.3545) (xy 345.5043 -54.407645)
			(xy 345.493943 -54.453028) (xy 369.480082 -54.453028) (xy 369.484153 -54.397406) (xy 369.496279 -54.342969)
			(xy 369.516202 -54.290878) (xy 369.543498 -54.242243) (xy 369.577584 -54.1981) (xy 369.617733 -54.159391)
			(xy 369.663091 -54.12694) (xy 369.712691 -54.101439) (xy 369.765475 -54.083432) (xy 369.820318 -54.073302)
			(xy 369.876052 -54.071265) (xy 369.931489 -54.077365) (xy 369.985446 -54.091471) (xy 370.036775 -54.113283)
			(xy 370.060739 -54.127908) (xy 371.773448 -54.127908) (xy 371.777519 -54.072286) (xy 371.789645 -54.017849)
			(xy 371.809568 -53.965758) (xy 371.836864 -53.917123) (xy 371.87095 -53.87298) (xy 371.911099 -53.834271)
			(xy 371.956457 -53.80182) (xy 372.006057 -53.776319) (xy 372.058841 -53.758312) (xy 372.113684 -53.748182)
			(xy 372.169418 -53.746145) (xy 372.224855 -53.752245) (xy 372.278812 -53.766351) (xy 372.330141 -53.788163)
			(xy 372.377747 -53.817217) (xy 372.420615 -53.852892) (xy 372.457832 -53.894429) (xy 372.488605 -53.940942)
			(xy 372.512277 -53.991439) (xy 372.528345 -54.044846) (xy 372.536465 -54.100022) (xy 372.536974 -54.127908)
			(xy 372.536465 -54.155794) (xy 372.528345 -54.21097) (xy 372.512277 -54.264377) (xy 372.488605 -54.314874)
			(xy 372.457832 -54.361387) (xy 372.420615 -54.402924) (xy 372.377747 -54.438599) (xy 372.330141 -54.467653)
			(xy 372.278812 -54.489465) (xy 372.224855 -54.503571) (xy 372.169418 -54.509671) (xy 372.113684 -54.507634)
			(xy 372.058841 -54.497504) (xy 372.006057 -54.479497) (xy 371.956457 -54.453996) (xy 371.911099 -54.421545)
			(xy 371.87095 -54.382836) (xy 371.836864 -54.338693) (xy 371.809568 -54.290058) (xy 371.789645 -54.237967)
			(xy 371.777519 -54.18353) (xy 371.773448 -54.127908) (xy 370.060739 -54.127908) (xy 370.084381 -54.142337)
			(xy 370.127249 -54.178012) (xy 370.164466 -54.219549) (xy 370.195239 -54.266062) (xy 370.218911 -54.316559)
			(xy 370.234979 -54.369966) (xy 370.243099 -54.425142) (xy 370.243608 -54.453028) (xy 370.243099 -54.480914)
			(xy 370.234979 -54.53609) (xy 370.218911 -54.589497) (xy 370.195239 -54.639994) (xy 370.164466 -54.686507)
			(xy 370.127249 -54.728044) (xy 370.084381 -54.763719) (xy 370.036775 -54.792773) (xy 369.985446 -54.814585)
			(xy 369.931489 -54.828691) (xy 369.876052 -54.834791) (xy 369.820318 -54.832754) (xy 369.765475 -54.822624)
			(xy 369.712691 -54.804617) (xy 369.663091 -54.779116) (xy 369.617733 -54.746665) (xy 369.577584 -54.707956)
			(xy 369.543498 -54.663813) (xy 369.516202 -54.615178) (xy 369.496279 -54.563087) (xy 369.484153 -54.50865)
			(xy 369.480082 -54.453028) (xy 345.493943 -54.453028) (xy 345.492442 -54.459603) (xy 345.472971 -54.509213)
			(xy 345.446325 -54.555367) (xy 345.413097 -54.597035) (xy 345.37403 -54.633284) (xy 345.329997 -54.663307)
			(xy 345.281982 -54.686431) (xy 345.231056 -54.702141) (xy 345.178357 -54.710085) (xy 345.15171 -54.710584)
			(xy 345.126771 -54.710204) (xy 345.077379 -54.703255) (xy 345.029441 -54.689478) (xy 344.983896 -54.669144)
			(xy 344.941636 -54.642649) (xy 344.903489 -54.610514) (xy 344.886534 -54.59222) (xy 344.876928 -54.582152)
			(xy 344.853451 -54.567229) (xy 344.826818 -54.559193) (xy 344.799004 -54.55864) (xy 344.772073 -54.565611)
			(xy 344.748021 -54.57959) (xy 344.728633 -54.599538) (xy 344.715344 -54.623978) (xy 344.711782 -54.637432)
			(xy 344.70538 -54.663334) (xy 344.685974 -54.713031) (xy 344.659367 -54.759275) (xy 344.626155 -54.801029)
			(xy 344.587083 -54.837358) (xy 344.581824 -54.84095) (xy 381.386086 -54.84095) (xy 381.386086 -54.78645)
			(xy 381.393842 -54.732505) (xy 381.409195 -54.680213) (xy 381.431835 -54.630638) (xy 381.461298 -54.58479)
			(xy 381.496987 -54.543601) (xy 381.538174 -54.50791) (xy 381.584021 -54.478444) (xy 381.633595 -54.455802)
			(xy 381.685886 -54.440446) (xy 381.73983 -54.432687) (xy 381.76708 -54.4322) (xy 381.793409 -54.432635)
			(xy 381.845567 -54.439868) (xy 381.896232 -54.454213) (xy 381.944441 -54.475397) (xy 381.989273 -54.503016)
			(xy 382.029877 -54.536545) (xy 382.048004 -54.555644) (xy 382.05785 -54.565647) (xy 382.081773 -54.580311)
			(xy 382.108778 -54.587929) (xy 382.136836 -54.587929) (xy 382.163841 -54.580311) (xy 382.187764 -54.565647)
			(xy 382.19761 -54.555644) (xy 382.215749 -54.536558) (xy 382.256359 -54.503044) (xy 382.301192 -54.475433)
			(xy 382.349396 -54.45425) (xy 382.400056 -54.439897) (xy 382.452207 -54.432647) (xy 382.478534 -54.4322)
			(xy 382.50498 -54.432628) (xy 382.557365 -54.439939) (xy 382.608237 -54.454416) (xy 382.656622 -54.475781)
			(xy 382.701593 -54.503625) (xy 382.742285 -54.537414) (xy 382.777921 -54.5765) (xy 382.79324 -54.598062)
			(xy 382.80159 -54.609445) (xy 382.823298 -54.627474) (xy 382.849112 -54.638873) (xy 382.87706 -54.642772)
			(xy 382.905008 -54.638873) (xy 382.930822 -54.627474) (xy 382.95253 -54.609445) (xy 382.96088 -54.598062)
			(xy 382.976206 -54.576506) (xy 383.011841 -54.537423) (xy 383.052533 -54.503637) (xy 383.097503 -54.475796)
			(xy 383.145887 -54.454433) (xy 383.196758 -54.439959) (xy 383.249141 -54.432652) (xy 383.275586 -54.4322)
			(xy 383.30284 -54.432646) (xy 383.356794 -54.440402) (xy 383.409094 -54.455757) (xy 383.458677 -54.478399)
			(xy 383.504533 -54.507867) (xy 383.545728 -54.543562) (xy 383.581424 -54.584756) (xy 383.610894 -54.630611)
			(xy 383.633538 -54.680193) (xy 383.648895 -54.732493) (xy 383.655332 -54.777258) (xy 385.218809 -54.777258)
			(xy 385.218809 -54.722742) (xy 385.226568 -54.668781) (xy 385.241928 -54.616474) (xy 385.264576 -54.566885)
			(xy 385.294051 -54.521024) (xy 385.329754 -54.479825) (xy 385.370956 -54.444127) (xy 385.41682 -54.414657)
			(xy 385.466411 -54.392014) (xy 385.51872 -54.37666) (xy 385.572682 -54.368906) (xy 385.59994 -54.368446)
			(xy 385.625795 -54.368876) (xy 385.67703 -54.375882) (xy 385.726848 -54.389747) (xy 385.774335 -54.410217)
			(xy 385.818621 -54.436916) (xy 385.858893 -54.469354) (xy 385.894412 -54.506936) (xy 385.90982 -54.527704)
			(xy 385.918263 -54.538625) (xy 385.939798 -54.555875) (xy 385.965156 -54.566753) (xy 385.992497 -54.570468)
			(xy 386.019838 -54.566753) (xy 386.045196 -54.555875) (xy 386.066731 -54.538625) (xy 386.075174 -54.527704)
			(xy 386.090628 -54.506974) (xy 386.12615 -54.469405) (xy 386.166418 -54.436975) (xy 386.210696 -54.410278)
			(xy 386.258173 -54.389803) (xy 386.307979 -54.375926) (xy 386.359203 -54.368899) (xy 386.385054 -54.368446)
			(xy 386.414246 -54.368994) (xy 386.471946 -54.377909) (xy 386.527616 -54.395508) (xy 386.579955 -54.421381)
			(xy 386.627744 -54.454922) (xy 386.669866 -54.495351) (xy 386.70534 -54.541723) (xy 386.719826 -54.567074)
			(xy 386.726743 -54.578813) (xy 386.745666 -54.598402) (xy 386.769095 -54.612291) (xy 386.795362 -54.619492)
			(xy 386.822598 -54.619492) (xy 386.848865 -54.612291) (xy 386.872294 -54.598402) (xy 386.891217 -54.578813)
			(xy 386.898134 -54.567074) (xy 386.912639 -54.541733) (xy 386.948097 -54.495347) (xy 386.990211 -54.454909)
			(xy 387.037996 -54.421362) (xy 387.090337 -54.395491) (xy 387.14601 -54.377901) (xy 387.203713 -54.369002)
			(xy 387.232906 -54.368446) (xy 387.260154 -54.369025) (xy 387.314094 -54.376781) (xy 387.366382 -54.392135)
			(xy 387.415952 -54.414773) (xy 387.461796 -54.444236) (xy 387.502981 -54.479923) (xy 387.538667 -54.521108)
			(xy 387.56813 -54.566953) (xy 387.590767 -54.616524) (xy 387.60612 -54.668812) (xy 387.613876 -54.722752)
			(xy 387.613876 -54.777248) (xy 387.60612 -54.831188) (xy 387.590767 -54.883476) (xy 387.56813 -54.933047)
			(xy 387.538667 -54.978892) (xy 387.502981 -55.020077) (xy 387.461796 -55.055764) (xy 387.415952 -55.085227)
			(xy 387.366382 -55.107865) (xy 387.314094 -55.123219) (xy 387.260154 -55.130975) (xy 387.232906 -55.131462)
			(xy 387.203716 -55.130862) (xy 387.146018 -55.121956) (xy 387.09035 -55.104365) (xy 387.038011 -55.078502)
			(xy 386.990222 -55.044968) (xy 386.948098 -55.004547) (xy 386.912621 -54.958182) (xy 386.898134 -54.932834)
			(xy 386.891217 -54.921095) (xy 386.872294 -54.901506) (xy 386.848865 -54.887617) (xy 386.822598 -54.880416)
			(xy 386.795362 -54.880416) (xy 386.769095 -54.887617) (xy 386.745666 -54.901506) (xy 386.726743 -54.921095)
			(xy 386.719826 -54.932834) (xy 386.705353 -54.958194) (xy 386.66989 -55.00458) (xy 386.62777 -55.045017)
			(xy 386.579979 -55.078562) (xy 386.527633 -55.10443) (xy 386.471956 -55.122016) (xy 386.414248 -55.130909)
			(xy 386.385054 -55.131462) (xy 386.359199 -55.131033) (xy 386.307964 -55.124026) (xy 386.258146 -55.110161)
			(xy 386.210659 -55.089691) (xy 386.166374 -55.062992) (xy 386.126102 -55.030554) (xy 386.090582 -54.992972)
			(xy 386.075174 -54.972204) (xy 386.066758 -54.96124) (xy 386.045244 -54.943906) (xy 386.019872 -54.932971)
			(xy 385.992497 -54.929235) (xy 385.965122 -54.932971) (xy 385.93975 -54.943906) (xy 385.918236 -54.96124)
			(xy 385.90982 -54.972204) (xy 385.894372 -54.992938) (xy 385.858849 -55.030507) (xy 385.81858 -55.062937)
			(xy 385.774301 -55.089633) (xy 385.726823 -55.110107) (xy 385.677016 -55.123984) (xy 385.625792 -55.131009)
			(xy 385.59994 -55.131462) (xy 385.572682 -55.131094) (xy 385.51872 -55.12334) (xy 385.466411 -55.107986)
			(xy 385.41682 -55.085343) (xy 385.370956 -55.055873) (xy 385.329754 -55.020175) (xy 385.294051 -54.978976)
			(xy 385.264576 -54.933115) (xy 385.241928 -54.883526) (xy 385.226568 -54.831219) (xy 385.218809 -54.777258)
			(xy 383.655332 -54.777258) (xy 383.656653 -54.786446) (xy 383.656653 -54.840954) (xy 383.648895 -54.894907)
			(xy 383.633538 -54.947207) (xy 383.610894 -54.996789) (xy 383.581424 -55.042644) (xy 383.545728 -55.083838)
			(xy 383.504533 -55.119533) (xy 383.458677 -55.149001) (xy 383.409094 -55.171643) (xy 383.356794 -55.186998)
			(xy 383.30284 -55.194754) (xy 383.275586 -55.195216) (xy 383.249141 -55.194766) (xy 383.196757 -55.187458)
			(xy 383.145886 -55.172984) (xy 383.097501 -55.151623) (xy 383.05253 -55.123782) (xy 383.011837 -55.089997)
			(xy 382.9762 -55.050915) (xy 382.96088 -55.029354) (xy 382.95253 -55.017971) (xy 382.930822 -54.999942)
			(xy 382.905008 -54.988543) (xy 382.87706 -54.984644) (xy 382.849112 -54.988543) (xy 382.823298 -54.999942)
			(xy 382.80159 -55.017971) (xy 382.79324 -55.029354) (xy 382.777907 -55.050904) (xy 382.742272 -55.089987)
			(xy 382.701581 -55.123773) (xy 382.656613 -55.151614) (xy 382.60823 -55.172978) (xy 382.55736 -55.187453)
			(xy 382.504979 -55.194763) (xy 382.478534 -55.195216) (xy 382.452204 -55.194798) (xy 382.400045 -55.187565)
			(xy 382.349378 -55.173218) (xy 382.301169 -55.152031) (xy 382.256337 -55.124408) (xy 382.215736 -55.090874)
			(xy 382.19761 -55.071772) (xy 382.187789 -55.061721) (xy 382.163879 -55.046973) (xy 382.136853 -55.039309)
			(xy 382.108761 -55.039309) (xy 382.081735 -55.046973) (xy 382.057825 -55.061721) (xy 382.048004 -55.071772)
			(xy 382.029861 -55.090854) (xy 381.989252 -55.124368) (xy 381.944419 -55.151979) (xy 381.896216 -55.173163)
			(xy 381.845557 -55.187517) (xy 381.793406 -55.194768) (xy 381.76708 -55.195216) (xy 381.73983 -55.194713)
			(xy 381.685886 -55.186954) (xy 381.633595 -55.171598) (xy 381.584021 -55.148956) (xy 381.538174 -55.11949)
			(xy 381.496987 -55.083799) (xy 381.461298 -55.04261) (xy 381.431835 -54.996762) (xy 381.409195 -54.947187)
			(xy 381.393842 -54.894895) (xy 381.386086 -54.84095) (xy 344.581824 -54.84095) (xy 344.543026 -54.867448)
			(xy 344.494971 -54.890624) (xy 344.443995 -54.906368) (xy 344.39124 -54.914327) (xy 344.364564 -54.9148)
			(xy 344.337916 -54.914316) (xy 344.285215 -54.906368) (xy 344.234288 -54.890654) (xy 344.186271 -54.867526)
			(xy 344.142238 -54.8375) (xy 344.103171 -54.801248) (xy 344.069943 -54.759577) (xy 344.043296 -54.71342)
			(xy 344.023826 -54.663808) (xy 344.011967 -54.611847) (xy 344.007984 -54.5587) (xy 343.091262 -54.5587)
			(xy 343.090764 -54.585341) (xy 343.082821 -54.638045) (xy 343.067111 -54.688975) (xy 343.043985 -54.736996)
			(xy 343.013961 -54.781033) (xy 342.977709 -54.820104) (xy 342.936038 -54.853335) (xy 342.88988 -54.879984)
			(xy 342.840266 -54.899456) (xy 342.788304 -54.911316) (xy 342.735154 -54.9153) (xy 342.682004 -54.911316)
			(xy 342.630042 -54.899456) (xy 342.580428 -54.879984) (xy 342.53427 -54.853335) (xy 342.492599 -54.820104)
			(xy 342.456347 -54.781033) (xy 342.426323 -54.736996) (xy 342.403197 -54.688975) (xy 342.387487 -54.638045)
			(xy 342.379544 -54.585341) (xy 341.461613 -54.585341) (xy 341.461608 -54.585595) (xy 341.453665 -54.638299)
			(xy 341.437955 -54.689229) (xy 341.414829 -54.73725) (xy 341.384805 -54.781287) (xy 341.348553 -54.820358)
			(xy 341.306882 -54.853589) (xy 341.260724 -54.880238) (xy 341.21111 -54.89971) (xy 341.159148 -54.91157)
			(xy 341.105998 -54.915554) (xy 341.052848 -54.91157) (xy 341.000886 -54.89971) (xy 340.951272 -54.880238)
			(xy 340.905114 -54.853589) (xy 340.863443 -54.820358) (xy 340.827191 -54.781287) (xy 340.797167 -54.73725)
			(xy 340.774041 -54.689229) (xy 340.758331 -54.638299) (xy 340.750388 -54.585595) (xy 339.833468 -54.585595)
			(xy 339.825525 -54.638299) (xy 339.809815 -54.689229) (xy 339.786689 -54.73725) (xy 339.756665 -54.781287)
			(xy 339.720413 -54.820358) (xy 339.678742 -54.853589) (xy 339.632584 -54.880238) (xy 339.58297 -54.89971)
			(xy 339.531008 -54.91157) (xy 339.477858 -54.915554) (xy 339.424708 -54.91157) (xy 339.372746 -54.89971)
			(xy 339.323132 -54.880238) (xy 339.276974 -54.853589) (xy 339.235303 -54.820358) (xy 339.199051 -54.781287)
			(xy 339.169027 -54.73725) (xy 339.145901 -54.689229) (xy 339.130191 -54.638299) (xy 339.122248 -54.585595)
			(xy 338.750158 -54.585595) (xy 338.742215 -54.638299) (xy 338.726505 -54.689229) (xy 338.703379 -54.73725)
			(xy 338.673355 -54.781287) (xy 338.637103 -54.820358) (xy 338.595432 -54.853589) (xy 338.549274 -54.880238)
			(xy 338.49966 -54.89971) (xy 338.447698 -54.91157) (xy 338.394548 -54.915554) (xy 338.341398 -54.91157)
			(xy 338.289436 -54.89971) (xy 338.239822 -54.880238) (xy 338.193664 -54.853589) (xy 338.151993 -54.820358)
			(xy 338.115741 -54.781287) (xy 338.085717 -54.73725) (xy 338.062591 -54.689229) (xy 338.046881 -54.638299)
			(xy 338.038938 -54.585595) (xy 337.122018 -54.585595) (xy 337.114075 -54.638299) (xy 337.098365 -54.689229)
			(xy 337.075239 -54.73725) (xy 337.045215 -54.781287) (xy 337.008963 -54.820358) (xy 336.967292 -54.853589)
			(xy 336.921134 -54.880238) (xy 336.87152 -54.89971) (xy 336.819558 -54.91157) (xy 336.766408 -54.915554)
			(xy 336.713258 -54.91157) (xy 336.661296 -54.89971) (xy 336.611682 -54.880238) (xy 336.565524 -54.853589)
			(xy 336.523853 -54.820358) (xy 336.487601 -54.781287) (xy 336.457577 -54.73725) (xy 336.434451 -54.689229)
			(xy 336.418741 -54.638299) (xy 336.410798 -54.585595) (xy 333.86571 -54.585595) (xy 333.865684 -54.586928)
			(xy 333.856923 -54.642201) (xy 333.839625 -54.695423) (xy 333.814215 -54.745285) (xy 333.781318 -54.790559)
			(xy 333.741745 -54.83013) (xy 333.69647 -54.863024) (xy 333.646607 -54.888432) (xy 333.593383 -54.905727)
			(xy 333.53811 -54.914485) (xy 333.510128 -54.915054) (xy 333.47937 -54.914406) (xy 333.418769 -54.903834)
			(xy 333.360888 -54.882998) (xy 333.333852 -54.868318) (xy 333.320374 -54.861292) (xy 333.290721 -54.854693)
			(xy 333.260438 -54.857105) (xy 333.232204 -54.868315) (xy 333.208515 -54.887332) (xy 333.191465 -54.912475)
			(xy 333.182563 -54.94152) (xy 333.18196 -54.95671) (xy 333.18196 -55.055495) (xy 335.597998 -55.055495)
			(xy 335.597998 -55.002197) (xy 335.605941 -54.949493) (xy 335.621651 -54.898563) (xy 335.644777 -54.850542)
			(xy 335.674801 -54.806505) (xy 335.711053 -54.767434) (xy 335.752724 -54.734203) (xy 335.798882 -54.707554)
			(xy 335.848496 -54.688082) (xy 335.900458 -54.676222) (xy 335.953608 -54.672239) (xy 336.006758 -54.676222)
			(xy 336.05872 -54.688082) (xy 336.108334 -54.707554) (xy 336.154492 -54.734203) (xy 336.196163 -54.767434)
			(xy 336.232415 -54.806505) (xy 336.262439 -54.850542) (xy 336.285565 -54.898563) (xy 336.301275 -54.949493)
			(xy 336.309218 -55.002197) (xy 336.309716 -55.028846) (xy 336.309218 -55.055495) (xy 337.226138 -55.055495)
			(xy 337.226138 -55.002197) (xy 337.234081 -54.949493) (xy 337.249791 -54.898563) (xy 337.272917 -54.850542)
			(xy 337.302941 -54.806505) (xy 337.339193 -54.767434) (xy 337.380864 -54.734203) (xy 337.427022 -54.707554)
			(xy 337.476636 -54.688082) (xy 337.528598 -54.676222) (xy 337.581748 -54.672239) (xy 337.634898 -54.676222)
			(xy 337.68686 -54.688082) (xy 337.736474 -54.707554) (xy 337.782632 -54.734203) (xy 337.824303 -54.767434)
			(xy 337.860555 -54.806505) (xy 337.890579 -54.850542) (xy 337.913705 -54.898563) (xy 337.929415 -54.949493)
			(xy 337.937358 -55.002197) (xy 337.937856 -55.028846) (xy 337.937358 -55.055495) (xy 339.935048 -55.055495)
			(xy 339.935048 -55.002197) (xy 339.942991 -54.949493) (xy 339.958701 -54.898563) (xy 339.981827 -54.850542)
			(xy 340.011851 -54.806505) (xy 340.048103 -54.767434) (xy 340.089774 -54.734203) (xy 340.135932 -54.707554)
			(xy 340.185546 -54.688082) (xy 340.237508 -54.676222) (xy 340.290658 -54.672239) (xy 340.343808 -54.676222)
			(xy 340.39577 -54.688082) (xy 340.445384 -54.707554) (xy 340.491542 -54.734203) (xy 340.533213 -54.767434)
			(xy 340.569465 -54.806505) (xy 340.599489 -54.850542) (xy 340.622615 -54.898563) (xy 340.638325 -54.949493)
			(xy 340.646268 -55.002197) (xy 340.646766 -55.028846) (xy 340.646268 -55.055495) (xy 341.565728 -55.055495)
			(xy 341.565728 -55.002197) (xy 341.573671 -54.949493) (xy 341.589381 -54.898563) (xy 341.612507 -54.850542)
			(xy 341.642531 -54.806505) (xy 341.678783 -54.767434) (xy 341.720454 -54.734203) (xy 341.766612 -54.707554)
			(xy 341.816226 -54.688082) (xy 341.868188 -54.676222) (xy 341.921338 -54.672239) (xy 341.974488 -54.676222)
			(xy 342.02645 -54.688082) (xy 342.076064 -54.707554) (xy 342.122222 -54.734203) (xy 342.163893 -54.767434)
			(xy 342.200145 -54.806505) (xy 342.230169 -54.850542) (xy 342.253295 -54.898563) (xy 342.269005 -54.949493)
			(xy 342.276948 -55.002197) (xy 342.277446 -55.028846) (xy 342.276953 -55.055241) (xy 343.194884 -55.055241)
			(xy 343.194884 -55.001943) (xy 343.202827 -54.949239) (xy 343.218537 -54.898309) (xy 343.241663 -54.850288)
			(xy 343.271687 -54.806251) (xy 343.307939 -54.76718) (xy 343.34961 -54.733949) (xy 343.395768 -54.7073)
			(xy 343.445382 -54.687828) (xy 343.497344 -54.675968) (xy 343.550494 -54.671985) (xy 343.603644 -54.675968)
			(xy 343.655606 -54.687828) (xy 343.70522 -54.7073) (xy 343.751378 -54.733949) (xy 343.793049 -54.76718)
			(xy 343.829301 -54.806251) (xy 343.859325 -54.850288) (xy 343.882451 -54.898309) (xy 343.898161 -54.949239)
			(xy 343.906104 -55.001943) (xy 343.906602 -55.028592) (xy 343.906104 -55.055241) (xy 343.898161 -55.107945)
			(xy 343.882451 -55.158875) (xy 343.859325 -55.206896) (xy 343.829301 -55.250933) (xy 343.793049 -55.290004)
			(xy 343.751378 -55.323235) (xy 343.70522 -55.349884) (xy 343.655606 -55.369356) (xy 343.603644 -55.381216)
			(xy 343.550494 -55.3852) (xy 343.497344 -55.381216) (xy 343.445382 -55.369356) (xy 343.395768 -55.349884)
			(xy 343.34961 -55.323235) (xy 343.307939 -55.290004) (xy 343.271687 -55.250933) (xy 343.241663 -55.206896)
			(xy 343.218537 -55.158875) (xy 343.202827 -55.107945) (xy 343.194884 -55.055241) (xy 342.276953 -55.055241)
			(xy 342.276948 -55.055495) (xy 342.269005 -55.108199) (xy 342.253295 -55.159129) (xy 342.230169 -55.20715)
			(xy 342.200145 -55.251187) (xy 342.163893 -55.290258) (xy 342.122222 -55.323489) (xy 342.076064 -55.350138)
			(xy 342.02645 -55.36961) (xy 341.974488 -55.38147) (xy 341.921338 -55.385454) (xy 341.868188 -55.38147)
			(xy 341.816226 -55.36961) (xy 341.766612 -55.350138) (xy 341.720454 -55.323489) (xy 341.678783 -55.290258)
			(xy 341.642531 -55.251187) (xy 341.612507 -55.20715) (xy 341.589381 -55.159129) (xy 341.573671 -55.108199)
			(xy 341.565728 -55.055495) (xy 340.646268 -55.055495) (xy 340.638325 -55.108199) (xy 340.622615 -55.159129)
			(xy 340.599489 -55.20715) (xy 340.569465 -55.251187) (xy 340.533213 -55.290258) (xy 340.491542 -55.323489)
			(xy 340.445384 -55.350138) (xy 340.39577 -55.36961) (xy 340.343808 -55.38147) (xy 340.290658 -55.385454)
			(xy 340.237508 -55.38147) (xy 340.185546 -55.36961) (xy 340.135932 -55.350138) (xy 340.089774 -55.323489)
			(xy 340.048103 -55.290258) (xy 340.011851 -55.251187) (xy 339.981827 -55.20715) (xy 339.958701 -55.159129)
			(xy 339.942991 -55.108199) (xy 339.935048 -55.055495) (xy 337.937358 -55.055495) (xy 337.929415 -55.108199)
			(xy 337.913705 -55.159129) (xy 337.890579 -55.20715) (xy 337.860555 -55.251187) (xy 337.824303 -55.290258)
			(xy 337.782632 -55.323489) (xy 337.736474 -55.350138) (xy 337.68686 -55.36961) (xy 337.634898 -55.38147)
			(xy 337.581748 -55.385454) (xy 337.528598 -55.38147) (xy 337.476636 -55.36961) (xy 337.427022 -55.350138)
			(xy 337.380864 -55.323489) (xy 337.339193 -55.290258) (xy 337.302941 -55.251187) (xy 337.272917 -55.20715)
			(xy 337.249791 -55.159129) (xy 337.234081 -55.108199) (xy 337.226138 -55.055495) (xy 336.309218 -55.055495)
			(xy 336.301275 -55.108199) (xy 336.285565 -55.159129) (xy 336.262439 -55.20715) (xy 336.232415 -55.251187)
			(xy 336.196163 -55.290258) (xy 336.154492 -55.323489) (xy 336.108334 -55.350138) (xy 336.05872 -55.36961)
			(xy 336.006758 -55.38147) (xy 335.953608 -55.385454) (xy 335.900458 -55.38147) (xy 335.848496 -55.36961)
			(xy 335.798882 -55.350138) (xy 335.752724 -55.323489) (xy 335.711053 -55.290258) (xy 335.674801 -55.251187)
			(xy 335.644777 -55.20715) (xy 335.621651 -55.159129) (xy 335.605941 -55.108199) (xy 335.597998 -55.055495)
			(xy 333.18196 -55.055495) (xy 333.18196 -55.525395) (xy 334.782658 -55.525395) (xy 334.782658 -55.472097)
			(xy 334.790601 -55.419393) (xy 334.806311 -55.368463) (xy 334.829437 -55.320442) (xy 334.859461 -55.276405)
			(xy 334.895713 -55.237334) (xy 334.937384 -55.204103) (xy 334.983542 -55.177454) (xy 335.033156 -55.157982)
			(xy 335.085118 -55.146122) (xy 335.138268 -55.142139) (xy 335.191418 -55.146122) (xy 335.24338 -55.157982)
			(xy 335.292994 -55.177454) (xy 335.339152 -55.204103) (xy 335.380823 -55.237334) (xy 335.417075 -55.276405)
			(xy 335.447099 -55.320442) (xy 335.470225 -55.368463) (xy 335.485935 -55.419393) (xy 335.493878 -55.472097)
			(xy 335.494376 -55.498746) (xy 335.493878 -55.525395) (xy 336.412068 -55.525395) (xy 336.412068 -55.472097)
			(xy 336.420011 -55.419393) (xy 336.435721 -55.368463) (xy 336.458847 -55.320442) (xy 336.488871 -55.276405)
			(xy 336.525123 -55.237334) (xy 336.566794 -55.204103) (xy 336.612952 -55.177454) (xy 336.662566 -55.157982)
			(xy 336.714528 -55.146122) (xy 336.767678 -55.142139) (xy 336.820828 -55.146122) (xy 336.87279 -55.157982)
			(xy 336.922404 -55.177454) (xy 336.968562 -55.204103) (xy 337.010233 -55.237334) (xy 337.046485 -55.276405)
			(xy 337.076509 -55.320442) (xy 337.099635 -55.368463) (xy 337.115345 -55.419393) (xy 337.123288 -55.472097)
			(xy 337.123786 -55.498746) (xy 337.123288 -55.525395) (xy 338.038938 -55.525395) (xy 338.038938 -55.472097)
			(xy 338.046881 -55.419393) (xy 338.062591 -55.368463) (xy 338.085717 -55.320442) (xy 338.115741 -55.276405)
			(xy 338.151993 -55.237334) (xy 338.193664 -55.204103) (xy 338.239822 -55.177454) (xy 338.289436 -55.157982)
			(xy 338.341398 -55.146122) (xy 338.394548 -55.142139) (xy 338.447698 -55.146122) (xy 338.49966 -55.157982)
			(xy 338.549274 -55.177454) (xy 338.595432 -55.204103) (xy 338.637103 -55.237334) (xy 338.673355 -55.276405)
			(xy 338.703379 -55.320442) (xy 338.726505 -55.368463) (xy 338.742215 -55.419393) (xy 338.750158 -55.472097)
			(xy 338.750656 -55.498746) (xy 338.750158 -55.525395) (xy 339.122248 -55.525395) (xy 339.122248 -55.472097)
			(xy 339.130191 -55.419393) (xy 339.145901 -55.368463) (xy 339.169027 -55.320442) (xy 339.199051 -55.276405)
			(xy 339.235303 -55.237334) (xy 339.276974 -55.204103) (xy 339.323132 -55.177454) (xy 339.372746 -55.157982)
			(xy 339.424708 -55.146122) (xy 339.477858 -55.142139) (xy 339.531008 -55.146122) (xy 339.58297 -55.157982)
			(xy 339.632584 -55.177454) (xy 339.678742 -55.204103) (xy 339.720413 -55.237334) (xy 339.756665 -55.276405)
			(xy 339.786689 -55.320442) (xy 339.809815 -55.368463) (xy 339.825525 -55.419393) (xy 339.833468 -55.472097)
			(xy 339.833966 -55.498746) (xy 339.833468 -55.525395) (xy 340.750388 -55.525395) (xy 340.750388 -55.472097)
			(xy 340.758331 -55.419393) (xy 340.774041 -55.368463) (xy 340.797167 -55.320442) (xy 340.827191 -55.276405)
			(xy 340.863443 -55.237334) (xy 340.905114 -55.204103) (xy 340.951272 -55.177454) (xy 341.000886 -55.157982)
			(xy 341.052848 -55.146122) (xy 341.105998 -55.142139) (xy 341.159148 -55.146122) (xy 341.21111 -55.157982)
			(xy 341.260724 -55.177454) (xy 341.306882 -55.204103) (xy 341.348553 -55.237334) (xy 341.384805 -55.276405)
			(xy 341.414829 -55.320442) (xy 341.437955 -55.368463) (xy 341.453665 -55.419393) (xy 341.461608 -55.472097)
			(xy 341.462106 -55.498746) (xy 341.461613 -55.525141) (xy 342.379544 -55.525141) (xy 342.379544 -55.471843)
			(xy 342.387487 -55.419139) (xy 342.403197 -55.368209) (xy 342.426323 -55.320188) (xy 342.456347 -55.276151)
			(xy 342.492599 -55.23708) (xy 342.53427 -55.203849) (xy 342.580428 -55.1772) (xy 342.630042 -55.157728)
			(xy 342.682004 -55.145868) (xy 342.735154 -55.141885) (xy 342.788304 -55.145868) (xy 342.840266 -55.157728)
			(xy 342.88988 -55.1772) (xy 342.936038 -55.203849) (xy 342.977709 -55.23708) (xy 343.013961 -55.276151)
			(xy 343.043985 -55.320188) (xy 343.067111 -55.368209) (xy 343.082821 -55.419139) (xy 343.090764 -55.471843)
			(xy 343.091262 -55.498492) (xy 343.091262 -55.4985) (xy 344.007984 -55.4985) (xy 344.011967 -55.445353)
			(xy 344.023826 -55.393392) (xy 344.043296 -55.34378) (xy 344.069943 -55.297623) (xy 344.103171 -55.255952)
			(xy 344.142238 -55.2197) (xy 344.186271 -55.189674) (xy 344.234288 -55.166546) (xy 344.285215 -55.150832)
			(xy 344.337916 -55.142884) (xy 344.364564 -55.142384) (xy 344.390797 -55.142811) (xy 344.442697 -55.150498)
			(xy 344.492909 -55.165713) (xy 344.540347 -55.188126) (xy 344.583986 -55.217252) (xy 344.622883 -55.252462)
			(xy 344.6399 -55.272432) (xy 344.648839 -55.282555) (xy 344.67087 -55.298153) (xy 344.696221 -55.307428)
			(xy 344.723117 -55.309732) (xy 344.749676 -55.304902) (xy 344.774039 -55.293278) (xy 344.794502 -55.275672)
			(xy 344.809632 -55.253317) (xy 344.814398 -55.240682) (xy 344.823816 -55.214635) (xy 344.849549 -55.165591)
			(xy 344.882562 -55.121119) (xy 344.922059 -55.082293) (xy 344.967089 -55.050046) (xy 345.016566 -55.025155)
			(xy 345.069299 -55.008222) (xy 345.124017 -54.999652) (xy 345.15171 -54.999128) (xy 345.178362 -54.999554)
			(xy 345.231069 -55.0075) (xy 345.282004 -55.023213) (xy 345.330028 -55.046341) (xy 345.374068 -55.076368)
			(xy 345.413141 -55.112624) (xy 345.446375 -55.154299) (xy 345.473026 -55.200461) (xy 345.4924 -55.249826)
			(xy 389.303258 -55.249826) (xy 389.307329 -55.194204) (xy 389.319455 -55.139767) (xy 389.339378 -55.087676)
			(xy 389.366674 -55.039041) (xy 389.40076 -54.994898) (xy 389.440909 -54.956189) (xy 389.486267 -54.923738)
			(xy 389.535867 -54.898237) (xy 389.588651 -54.88023) (xy 389.643494 -54.8701) (xy 389.699228 -54.868063)
			(xy 389.754665 -54.874163) (xy 389.808622 -54.888269) (xy 389.859951 -54.910081) (xy 389.907557 -54.939135)
			(xy 389.950425 -54.97481) (xy 389.987642 -55.016347) (xy 390.018415 -55.06286) (xy 390.042087 -55.113357)
			(xy 390.058155 -55.166764) (xy 390.066275 -55.22194) (xy 390.066784 -55.249826) (xy 390.066275 -55.277712)
			(xy 390.058155 -55.332888) (xy 390.042087 -55.386295) (xy 390.018415 -55.436792) (xy 389.987642 -55.483305)
			(xy 389.950425 -55.524842) (xy 389.907557 -55.560517) (xy 389.859951 -55.589571) (xy 389.808622 -55.611383)
			(xy 389.754665 -55.625489) (xy 389.699228 -55.631589) (xy 389.643494 -55.629552) (xy 389.588651 -55.619422)
			(xy 389.535867 -55.601415) (xy 389.486267 -55.575914) (xy 389.440909 -55.543463) (xy 389.40076 -55.504754)
			(xy 389.366674 -55.460611) (xy 389.339378 -55.411976) (xy 389.319455 -55.359885) (xy 389.307329 -55.305448)
			(xy 389.303258 -55.249826) (xy 345.4924 -55.249826) (xy 345.492499 -55.250079) (xy 345.50436 -55.302046)
			(xy 345.508344 -55.3552) (xy 345.50436 -55.408354) (xy 345.492499 -55.460321) (xy 345.473026 -55.509939)
			(xy 345.446375 -55.556101) (xy 345.413141 -55.597776) (xy 345.374068 -55.634032) (xy 345.330028 -55.664059)
			(xy 345.282004 -55.687187) (xy 345.231069 -55.7029) (xy 345.178362 -55.710846) (xy 345.15171 -55.711344)
			(xy 345.125479 -55.710856) (xy 345.073582 -55.703179) (xy 345.023372 -55.687976) (xy 344.975934 -55.665575)
			(xy 344.932293 -55.63646) (xy 344.893393 -55.601261) (xy 344.876374 -55.581296) (xy 344.867474 -55.571135)
			(xy 344.845435 -55.555532) (xy 344.820075 -55.546255) (xy 344.79317 -55.543953) (xy 344.766603 -55.548788)
			(xy 344.742234 -55.560421) (xy 344.721769 -55.578038) (xy 344.70664 -55.600406) (xy 344.701876 -55.613046)
			(xy 344.692439 -55.639087) (xy 344.666713 -55.688134) (xy 344.633705 -55.732608) (xy 344.594211 -55.771438)
			(xy 344.549184 -55.803686) (xy 344.499707 -55.828577) (xy 344.446975 -55.84551) (xy 344.392256 -55.854077)
			(xy 344.364564 -55.8546) (xy 344.337916 -55.854116) (xy 344.285215 -55.846168) (xy 344.234288 -55.830454)
			(xy 344.186271 -55.807326) (xy 344.142238 -55.7773) (xy 344.103171 -55.741048) (xy 344.069943 -55.699377)
			(xy 344.043296 -55.65322) (xy 344.023826 -55.603608) (xy 344.011967 -55.551647) (xy 344.007984 -55.4985)
			(xy 343.091262 -55.4985) (xy 343.090764 -55.525141) (xy 343.082821 -55.577845) (xy 343.067111 -55.628775)
			(xy 343.043985 -55.676796) (xy 343.013961 -55.720833) (xy 342.977709 -55.759904) (xy 342.936038 -55.793135)
			(xy 342.88988 -55.819784) (xy 342.840266 -55.839256) (xy 342.788304 -55.851116) (xy 342.735154 -55.8551)
			(xy 342.682004 -55.851116) (xy 342.630042 -55.839256) (xy 342.580428 -55.819784) (xy 342.53427 -55.793135)
			(xy 342.492599 -55.759904) (xy 342.456347 -55.720833) (xy 342.426323 -55.676796) (xy 342.403197 -55.628775)
			(xy 342.387487 -55.577845) (xy 342.379544 -55.525141) (xy 341.461613 -55.525141) (xy 341.461608 -55.525395)
			(xy 341.453665 -55.578099) (xy 341.437955 -55.629029) (xy 341.414829 -55.67705) (xy 341.384805 -55.721087)
			(xy 341.348553 -55.760158) (xy 341.306882 -55.793389) (xy 341.260724 -55.820038) (xy 341.21111 -55.83951)
			(xy 341.159148 -55.85137) (xy 341.105998 -55.855354) (xy 341.052848 -55.85137) (xy 341.000886 -55.83951)
			(xy 340.951272 -55.820038) (xy 340.905114 -55.793389) (xy 340.863443 -55.760158) (xy 340.827191 -55.721087)
			(xy 340.797167 -55.67705) (xy 340.774041 -55.629029) (xy 340.758331 -55.578099) (xy 340.750388 -55.525395)
			(xy 339.833468 -55.525395) (xy 339.825525 -55.578099) (xy 339.809815 -55.629029) (xy 339.786689 -55.67705)
			(xy 339.756665 -55.721087) (xy 339.720413 -55.760158) (xy 339.678742 -55.793389) (xy 339.632584 -55.820038)
			(xy 339.58297 -55.83951) (xy 339.531008 -55.85137) (xy 339.477858 -55.855354) (xy 339.424708 -55.85137)
			(xy 339.372746 -55.83951) (xy 339.323132 -55.820038) (xy 339.276974 -55.793389) (xy 339.235303 -55.760158)
			(xy 339.199051 -55.721087) (xy 339.169027 -55.67705) (xy 339.145901 -55.629029) (xy 339.130191 -55.578099)
			(xy 339.122248 -55.525395) (xy 338.750158 -55.525395) (xy 338.742215 -55.578099) (xy 338.726505 -55.629029)
			(xy 338.703379 -55.67705) (xy 338.673355 -55.721087) (xy 338.637103 -55.760158) (xy 338.595432 -55.793389)
			(xy 338.549274 -55.820038) (xy 338.49966 -55.83951) (xy 338.447698 -55.85137) (xy 338.394548 -55.855354)
			(xy 338.341398 -55.85137) (xy 338.289436 -55.83951) (xy 338.239822 -55.820038) (xy 338.193664 -55.793389)
			(xy 338.151993 -55.760158) (xy 338.115741 -55.721087) (xy 338.085717 -55.67705) (xy 338.062591 -55.629029)
			(xy 338.046881 -55.578099) (xy 338.038938 -55.525395) (xy 337.123288 -55.525395) (xy 337.115345 -55.578099)
			(xy 337.099635 -55.629029) (xy 337.076509 -55.67705) (xy 337.046485 -55.721087) (xy 337.010233 -55.760158)
			(xy 336.968562 -55.793389) (xy 336.922404 -55.820038) (xy 336.87279 -55.83951) (xy 336.820828 -55.85137)
			(xy 336.767678 -55.855354) (xy 336.714528 -55.85137) (xy 336.662566 -55.83951) (xy 336.612952 -55.820038)
			(xy 336.566794 -55.793389) (xy 336.525123 -55.760158) (xy 336.488871 -55.721087) (xy 336.458847 -55.67705)
			(xy 336.435721 -55.629029) (xy 336.420011 -55.578099) (xy 336.412068 -55.525395) (xy 335.493878 -55.525395)
			(xy 335.485935 -55.578099) (xy 335.470225 -55.629029) (xy 335.447099 -55.67705) (xy 335.417075 -55.721087)
			(xy 335.380823 -55.760158) (xy 335.339152 -55.793389) (xy 335.292994 -55.820038) (xy 335.24338 -55.83951)
			(xy 335.191418 -55.85137) (xy 335.138268 -55.855354) (xy 335.085118 -55.85137) (xy 335.033156 -55.83951)
			(xy 334.983542 -55.820038) (xy 334.937384 -55.793389) (xy 334.895713 -55.760158) (xy 334.859461 -55.721087)
			(xy 334.829437 -55.67705) (xy 334.806311 -55.629029) (xy 334.790601 -55.578099) (xy 334.782658 -55.525395)
			(xy 333.18196 -55.525395) (xy 333.18196 -55.623968) (xy 333.253588 -55.695596) (xy 333.253588 -55.995295)
			(xy 335.597998 -55.995295) (xy 335.597998 -55.941997) (xy 335.605941 -55.889293) (xy 335.621651 -55.838363)
			(xy 335.644777 -55.790342) (xy 335.674801 -55.746305) (xy 335.711053 -55.707234) (xy 335.752724 -55.674003)
			(xy 335.798882 -55.647354) (xy 335.848496 -55.627882) (xy 335.900458 -55.616022) (xy 335.953608 -55.612039)
			(xy 336.006758 -55.616022) (xy 336.05872 -55.627882) (xy 336.108334 -55.647354) (xy 336.154492 -55.674003)
			(xy 336.196163 -55.707234) (xy 336.232415 -55.746305) (xy 336.262439 -55.790342) (xy 336.285565 -55.838363)
			(xy 336.301275 -55.889293) (xy 336.309218 -55.941997) (xy 336.309716 -55.968646) (xy 336.309218 -55.995295)
			(xy 337.226138 -55.995295) (xy 337.226138 -55.941997) (xy 337.234081 -55.889293) (xy 337.249791 -55.838363)
			(xy 337.272917 -55.790342) (xy 337.302941 -55.746305) (xy 337.339193 -55.707234) (xy 337.380864 -55.674003)
			(xy 337.427022 -55.647354) (xy 337.476636 -55.627882) (xy 337.528598 -55.616022) (xy 337.581748 -55.612039)
			(xy 337.634898 -55.616022) (xy 337.68686 -55.627882) (xy 337.736474 -55.647354) (xy 337.782632 -55.674003)
			(xy 337.824303 -55.707234) (xy 337.860555 -55.746305) (xy 337.890579 -55.790342) (xy 337.913705 -55.838363)
			(xy 337.929415 -55.889293) (xy 337.937358 -55.941997) (xy 337.937856 -55.968646) (xy 337.937358 -55.995295)
			(xy 339.935048 -55.995295) (xy 339.935048 -55.941997) (xy 339.942991 -55.889293) (xy 339.958701 -55.838363)
			(xy 339.981827 -55.790342) (xy 340.011851 -55.746305) (xy 340.048103 -55.707234) (xy 340.089774 -55.674003)
			(xy 340.135932 -55.647354) (xy 340.185546 -55.627882) (xy 340.237508 -55.616022) (xy 340.290658 -55.612039)
			(xy 340.343808 -55.616022) (xy 340.39577 -55.627882) (xy 340.445384 -55.647354) (xy 340.491542 -55.674003)
			(xy 340.533213 -55.707234) (xy 340.569465 -55.746305) (xy 340.599489 -55.790342) (xy 340.622615 -55.838363)
			(xy 340.638325 -55.889293) (xy 340.646268 -55.941997) (xy 340.646766 -55.968646) (xy 340.646268 -55.995295)
			(xy 341.565728 -55.995295) (xy 341.565728 -55.941997) (xy 341.573671 -55.889293) (xy 341.589381 -55.838363)
			(xy 341.612507 -55.790342) (xy 341.642531 -55.746305) (xy 341.678783 -55.707234) (xy 341.720454 -55.674003)
			(xy 341.766612 -55.647354) (xy 341.816226 -55.627882) (xy 341.868188 -55.616022) (xy 341.921338 -55.612039)
			(xy 341.974488 -55.616022) (xy 342.02645 -55.627882) (xy 342.076064 -55.647354) (xy 342.122222 -55.674003)
			(xy 342.163893 -55.707234) (xy 342.200145 -55.746305) (xy 342.230169 -55.790342) (xy 342.253295 -55.838363)
			(xy 342.269005 -55.889293) (xy 342.276948 -55.941997) (xy 342.277446 -55.968646) (xy 342.276953 -55.995041)
			(xy 343.194884 -55.995041) (xy 343.194884 -55.941743) (xy 343.202827 -55.889039) (xy 343.218537 -55.838109)
			(xy 343.241663 -55.790088) (xy 343.271687 -55.746051) (xy 343.307939 -55.70698) (xy 343.34961 -55.673749)
			(xy 343.395768 -55.6471) (xy 343.445382 -55.627628) (xy 343.497344 -55.615768) (xy 343.550494 -55.611785)
			(xy 343.603644 -55.615768) (xy 343.655606 -55.627628) (xy 343.70522 -55.6471) (xy 343.751378 -55.673749)
			(xy 343.793049 -55.70698) (xy 343.829301 -55.746051) (xy 343.859325 -55.790088) (xy 343.882451 -55.838109)
			(xy 343.898161 -55.889039) (xy 343.906104 -55.941743) (xy 343.906602 -55.968392) (xy 343.906104 -55.995041)
			(xy 343.898161 -56.047745) (xy 343.882451 -56.098675) (xy 343.859325 -56.146696) (xy 343.829301 -56.190733)
			(xy 343.793049 -56.229804) (xy 343.751378 -56.263035) (xy 343.70522 -56.289684) (xy 343.655606 -56.309156)
			(xy 343.603644 -56.321016) (xy 343.550494 -56.325) (xy 343.497344 -56.321016) (xy 343.445382 -56.309156)
			(xy 343.395768 -56.289684) (xy 343.34961 -56.263035) (xy 343.307939 -56.229804) (xy 343.271687 -56.190733)
			(xy 343.241663 -56.146696) (xy 343.218537 -56.098675) (xy 343.202827 -56.047745) (xy 343.194884 -55.995041)
			(xy 342.276953 -55.995041) (xy 342.276948 -55.995295) (xy 342.269005 -56.047999) (xy 342.253295 -56.098929)
			(xy 342.230169 -56.14695) (xy 342.200145 -56.190987) (xy 342.163893 -56.230058) (xy 342.122222 -56.263289)
			(xy 342.076064 -56.289938) (xy 342.02645 -56.30941) (xy 341.974488 -56.32127) (xy 341.921338 -56.325254)
			(xy 341.868188 -56.32127) (xy 341.816226 -56.30941) (xy 341.766612 -56.289938) (xy 341.720454 -56.263289)
			(xy 341.678783 -56.230058) (xy 341.642531 -56.190987) (xy 341.612507 -56.14695) (xy 341.589381 -56.098929)
			(xy 341.573671 -56.047999) (xy 341.565728 -55.995295) (xy 340.646268 -55.995295) (xy 340.638325 -56.047999)
			(xy 340.622615 -56.098929) (xy 340.599489 -56.14695) (xy 340.569465 -56.190987) (xy 340.533213 -56.230058)
			(xy 340.491542 -56.263289) (xy 340.445384 -56.289938) (xy 340.39577 -56.30941) (xy 340.343808 -56.32127)
			(xy 340.290658 -56.325254) (xy 340.237508 -56.32127) (xy 340.185546 -56.30941) (xy 340.135932 -56.289938)
			(xy 340.089774 -56.263289) (xy 340.048103 -56.230058) (xy 340.011851 -56.190987) (xy 339.981827 -56.14695)
			(xy 339.958701 -56.098929) (xy 339.942991 -56.047999) (xy 339.935048 -55.995295) (xy 337.937358 -55.995295)
			(xy 337.929415 -56.047999) (xy 337.913705 -56.098929) (xy 337.890579 -56.14695) (xy 337.860555 -56.190987)
			(xy 337.824303 -56.230058) (xy 337.782632 -56.263289) (xy 337.736474 -56.289938) (xy 337.68686 -56.30941)
			(xy 337.634898 -56.32127) (xy 337.581748 -56.325254) (xy 337.528598 -56.32127) (xy 337.476636 -56.30941)
			(xy 337.427022 -56.289938) (xy 337.380864 -56.263289) (xy 337.339193 -56.230058) (xy 337.302941 -56.190987)
			(xy 337.272917 -56.14695) (xy 337.249791 -56.098929) (xy 337.234081 -56.047999) (xy 337.226138 -55.995295)
			(xy 336.309218 -55.995295) (xy 336.301275 -56.047999) (xy 336.285565 -56.098929) (xy 336.262439 -56.14695)
			(xy 336.232415 -56.190987) (xy 336.196163 -56.230058) (xy 336.154492 -56.263289) (xy 336.108334 -56.289938)
			(xy 336.05872 -56.30941) (xy 336.006758 -56.32127) (xy 335.953608 -56.325254) (xy 335.900458 -56.32127)
			(xy 335.848496 -56.30941) (xy 335.798882 -56.289938) (xy 335.752724 -56.263289) (xy 335.711053 -56.230058)
			(xy 335.674801 -56.190987) (xy 335.644777 -56.14695) (xy 335.621651 -56.098929) (xy 335.605941 -56.047999)
			(xy 335.597998 -55.995295) (xy 333.253588 -55.995295) (xy 333.253588 -56.008016) (xy 333.254025 -56.021954)
			(xy 333.261574 -56.048789) (xy 333.276104 -56.07258) (xy 333.29653 -56.09155) (xy 333.321329 -56.104283)
			(xy 333.348648 -56.10983) (xy 333.376449 -56.107776) (xy 333.389732 -56.10352) (xy 333.418923 -56.093697)
			(xy 333.47959 -56.083102) (xy 333.510382 -56.082438) (xy 333.537031 -56.08291) (xy 333.589733 -56.090851)
			(xy 333.640663 -56.106558) (xy 333.688683 -56.129681) (xy 333.73272 -56.159703) (xy 333.77179 -56.195954)
			(xy 333.805021 -56.237622) (xy 333.831671 -56.283778) (xy 333.851143 -56.333391) (xy 333.863003 -56.385352)
			(xy 333.866986 -56.4385) (xy 333.864985 -56.465195) (xy 334.782658 -56.465195) (xy 334.782658 -56.411897)
			(xy 334.790601 -56.359193) (xy 334.806311 -56.308263) (xy 334.829437 -56.260242) (xy 334.859461 -56.216205)
			(xy 334.895713 -56.177134) (xy 334.937384 -56.143903) (xy 334.983542 -56.117254) (xy 335.033156 -56.097782)
			(xy 335.085118 -56.085922) (xy 335.138268 -56.081939) (xy 335.191418 -56.085922) (xy 335.24338 -56.097782)
			(xy 335.292994 -56.117254) (xy 335.339152 -56.143903) (xy 335.380823 -56.177134) (xy 335.417075 -56.216205)
			(xy 335.447099 -56.260242) (xy 335.470225 -56.308263) (xy 335.485935 -56.359193) (xy 335.493878 -56.411897)
			(xy 335.494376 -56.438546) (xy 335.493878 -56.465195) (xy 336.411814 -56.465195) (xy 336.411814 -56.411897)
			(xy 336.419757 -56.359193) (xy 336.435467 -56.308263) (xy 336.458593 -56.260242) (xy 336.488617 -56.216205)
			(xy 336.524869 -56.177134) (xy 336.56654 -56.143903) (xy 336.612698 -56.117254) (xy 336.662312 -56.097782)
			(xy 336.714274 -56.085922) (xy 336.767424 -56.081939) (xy 336.820574 -56.085922) (xy 336.872536 -56.097782)
			(xy 336.92215 -56.117254) (xy 336.968308 -56.143903) (xy 337.009979 -56.177134) (xy 337.046231 -56.216205)
			(xy 337.076255 -56.260242) (xy 337.099381 -56.308263) (xy 337.115091 -56.359193) (xy 337.123034 -56.411897)
			(xy 337.123532 -56.438546) (xy 337.123034 -56.465195) (xy 338.040208 -56.465195) (xy 338.040208 -56.411897)
			(xy 338.048151 -56.359193) (xy 338.063861 -56.308263) (xy 338.086987 -56.260242) (xy 338.117011 -56.216205)
			(xy 338.153263 -56.177134) (xy 338.194934 -56.143903) (xy 338.241092 -56.117254) (xy 338.290706 -56.097782)
			(xy 338.342668 -56.085922) (xy 338.395818 -56.081939) (xy 338.448968 -56.085922) (xy 338.50093 -56.097782)
			(xy 338.550544 -56.117254) (xy 338.596702 -56.143903) (xy 338.638373 -56.177134) (xy 338.674625 -56.216205)
			(xy 338.704649 -56.260242) (xy 338.727775 -56.308263) (xy 338.743485 -56.359193) (xy 338.751428 -56.411897)
			(xy 338.751926 -56.438546) (xy 338.751428 -56.465195) (xy 339.122248 -56.465195) (xy 339.122248 -56.411897)
			(xy 339.130191 -56.359193) (xy 339.145901 -56.308263) (xy 339.169027 -56.260242) (xy 339.199051 -56.216205)
			(xy 339.235303 -56.177134) (xy 339.276974 -56.143903) (xy 339.323132 -56.117254) (xy 339.372746 -56.097782)
			(xy 339.424708 -56.085922) (xy 339.477858 -56.081939) (xy 339.531008 -56.085922) (xy 339.58297 -56.097782)
			(xy 339.632584 -56.117254) (xy 339.678742 -56.143903) (xy 339.720413 -56.177134) (xy 339.756665 -56.216205)
			(xy 339.786689 -56.260242) (xy 339.809815 -56.308263) (xy 339.825525 -56.359193) (xy 339.833468 -56.411897)
			(xy 339.833966 -56.438546) (xy 339.833468 -56.465195) (xy 340.750388 -56.465195) (xy 340.750388 -56.411897)
			(xy 340.758331 -56.359193) (xy 340.774041 -56.308263) (xy 340.797167 -56.260242) (xy 340.827191 -56.216205)
			(xy 340.863443 -56.177134) (xy 340.905114 -56.143903) (xy 340.951272 -56.117254) (xy 341.000886 -56.097782)
			(xy 341.052848 -56.085922) (xy 341.105998 -56.081939) (xy 341.159148 -56.085922) (xy 341.21111 -56.097782)
			(xy 341.260724 -56.117254) (xy 341.306882 -56.143903) (xy 341.348553 -56.177134) (xy 341.384805 -56.216205)
			(xy 341.414829 -56.260242) (xy 341.437955 -56.308263) (xy 341.453665 -56.359193) (xy 341.461608 -56.411897)
			(xy 341.462106 -56.438546) (xy 341.461613 -56.464941) (xy 342.379544 -56.464941) (xy 342.379544 -56.411643)
			(xy 342.387487 -56.358939) (xy 342.403197 -56.308009) (xy 342.426323 -56.259988) (xy 342.456347 -56.215951)
			(xy 342.492599 -56.17688) (xy 342.53427 -56.143649) (xy 342.580428 -56.117) (xy 342.630042 -56.097528)
			(xy 342.682004 -56.085668) (xy 342.735154 -56.081685) (xy 342.788304 -56.085668) (xy 342.840266 -56.097528)
			(xy 342.88988 -56.117) (xy 342.936038 -56.143649) (xy 342.977709 -56.17688) (xy 343.013961 -56.215951)
			(xy 343.043985 -56.259988) (xy 343.067111 -56.308009) (xy 343.082821 -56.358939) (xy 343.090764 -56.411643)
			(xy 343.091262 -56.438292) (xy 343.090764 -56.464941) (xy 344.008954 -56.464941) (xy 344.008954 -56.411643)
			(xy 344.016897 -56.358939) (xy 344.032607 -56.308009) (xy 344.055733 -56.259988) (xy 344.085757 -56.215951)
			(xy 344.122009 -56.17688) (xy 344.16368 -56.143649) (xy 344.209838 -56.117) (xy 344.259452 -56.097528)
			(xy 344.311414 -56.085668) (xy 344.364564 -56.081685) (xy 344.417714 -56.085668) (xy 344.469676 -56.097528)
			(xy 344.51929 -56.117) (xy 344.565448 -56.143649) (xy 344.607119 -56.17688) (xy 344.643371 -56.215951)
			(xy 344.673395 -56.259988) (xy 344.67723 -56.267951) (xy 350.634558 -56.267951) (xy 350.634558 -56.213449)
			(xy 350.642313 -56.159503) (xy 350.657667 -56.107209) (xy 350.680306 -56.057632) (xy 350.70977 -56.011782)
			(xy 350.745458 -55.970591) (xy 350.786645 -55.934897) (xy 350.832492 -55.905428) (xy 350.882066 -55.882783)
			(xy 350.934358 -55.867423) (xy 350.988303 -55.859661) (xy 351.015554 -55.859172) (xy 351.042924 -55.859605)
			(xy 351.097102 -55.867417) (xy 351.14961 -55.882887) (xy 351.19937 -55.905697) (xy 351.245361 -55.935381)
			(xy 351.286642 -55.971329) (xy 351.30486 -55.99176) (xy 351.315028 -56.002834) (xy 351.340383 -56.018963)
			(xy 351.369337 -56.02701) (xy 351.399379 -56.026279) (xy 351.427906 -56.016832) (xy 351.452447 -55.999489)
			(xy 351.462086 -55.98795) (xy 351.480252 -55.96539) (xy 351.522267 -55.925521) (xy 351.569829 -55.892467)
			(xy 351.621844 -55.866987) (xy 351.677115 -55.84967) (xy 351.73437 -55.840913) (xy 351.76333 -55.840376)
			(xy 351.790192 -55.840832) (xy 351.843385 -55.848373) (xy 351.894994 -55.863302) (xy 351.943998 -55.885323)
			(xy 351.986031 -55.911856) (xy 356.394927 -55.911856) (xy 356.394927 -55.857344) (xy 356.402685 -55.803388)
			(xy 356.418043 -55.751084) (xy 356.440689 -55.701499) (xy 356.470161 -55.655642) (xy 356.505859 -55.614445)
			(xy 356.547058 -55.578749) (xy 356.592917 -55.549279) (xy 356.642503 -55.526636) (xy 356.694807 -55.511281)
			(xy 356.748764 -55.503526) (xy 356.77602 -55.503064) (xy 356.802197 -55.50348) (xy 356.854058 -55.510648)
			(xy 356.90445 -55.524847) (xy 356.952424 -55.545809) (xy 356.997078 -55.57314) (xy 357.037571 -55.606325)
			(xy 357.055674 -55.625238) (xy 357.065508 -55.635167) (xy 357.08936 -55.64971) (xy 357.116255 -55.657263)
			(xy 357.144191 -55.657263) (xy 357.171086 -55.64971) (xy 357.194938 -55.635167) (xy 357.204772 -55.625238)
			(xy 357.222909 -55.606333) (xy 357.263449 -55.573149) (xy 357.308146 -55.545821) (xy 357.35616 -55.524861)
			(xy 357.406589 -55.510665) (xy 357.458485 -55.503498) (xy 357.48468 -55.503064) (xy 358.34828 -55.503064)
			(xy 358.376048 -55.503558) (xy 358.431 -55.511603) (xy 358.484205 -55.527526) (xy 358.534542 -55.55099)
			(xy 358.580947 -55.581501) (xy 358.602026 -55.599584) (xy 358.613428 -55.609052) (xy 358.640278 -55.621569)
			(xy 358.66959 -55.625862) (xy 358.698902 -55.621569) (xy 358.725752 -55.609052) (xy 358.737154 -55.599584)
			(xy 358.75823 -55.581497) (xy 358.804638 -55.550991) (xy 358.854975 -55.52753) (xy 358.908181 -55.511609)
			(xy 358.963132 -55.503563) (xy 358.9909 -55.503064) (xy 359.020591 -55.503619) (xy 359.079256 -55.512832)
			(xy 359.135785 -55.53102) (xy 359.188815 -55.557744) (xy 359.237066 -55.592359) (xy 359.258616 -55.612792)
			(xy 359.268315 -55.621766) (xy 359.291253 -55.634865) (xy 359.316783 -55.641642) (xy 359.343197 -55.641642)
			(xy 359.368727 -55.634865) (xy 359.391665 -55.621766) (xy 359.401364 -55.612792) (xy 359.422923 -55.592369)
			(xy 359.471169 -55.557748) (xy 359.524196 -55.531022) (xy 359.580725 -55.512837) (xy 359.639389 -55.503632)
			(xy 359.66908 -55.503064) (xy 359.697927 -55.503579) (xy 359.754965 -55.512258) (xy 359.810042 -55.529438)
			(xy 359.8619 -55.554724) (xy 359.909353 -55.587539) (xy 359.9307 -55.60695) (xy 359.942285 -55.617105)
			(xy 359.969979 -55.630567) (xy 360.000423 -55.635193) (xy 360.030867 -55.630567) (xy 360.058561 -55.617105)
			(xy 360.070146 -55.60695) (xy 360.091509 -55.587521) (xy 360.139013 -55.554693) (xy 360.190925 -55.529404)
			(xy 360.246057 -55.512232) (xy 360.303148 -55.503572) (xy 360.33202 -55.503064) (xy 361.19562 -55.503064)
			(xy 361.225193 -55.503627) (xy 361.283637 -55.512712) (xy 361.339978 -55.530707) (xy 361.392867 -55.557182)
			(xy 361.441037 -55.591502) (xy 361.462574 -55.611776) (xy 361.472255 -55.620631) (xy 361.495088 -55.633538)
			(xy 361.520453 -55.640211) (xy 361.546681 -55.640211) (xy 361.572046 -55.633538) (xy 361.594879 -55.620631)
			(xy 361.60456 -55.611776) (xy 361.626087 -55.591528) (xy 361.674207 -55.557225) (xy 361.727041 -55.53075)
			(xy 361.783325 -55.512739) (xy 361.841712 -55.503621) (xy 361.87126 -55.503064) (xy 361.898513 -55.503581)
			(xy 361.952464 -55.511332) (xy 362.004763 -55.526684) (xy 362.054344 -55.549322) (xy 362.100199 -55.578787)
			(xy 362.141394 -55.614478) (xy 362.177089 -55.655669) (xy 362.206558 -55.70152) (xy 362.229202 -55.7511)
			(xy 362.244559 -55.803397) (xy 362.252317 -55.857347) (xy 362.252317 -55.911853) (xy 362.83895 -55.911853)
			(xy 362.83895 -55.857347) (xy 362.846707 -55.803395) (xy 362.862063 -55.751096) (xy 362.884706 -55.701516)
			(xy 362.914174 -55.655662) (xy 362.949869 -55.614469) (xy 362.991062 -55.578774) (xy 363.036916 -55.549306)
			(xy 363.086496 -55.526663) (xy 363.138795 -55.511307) (xy 363.192747 -55.50355) (xy 363.22 -55.503064)
			(xy 363.249548 -55.503628) (xy 363.307937 -55.512741) (xy 363.364224 -55.530747) (xy 363.41706 -55.557217)
			(xy 363.465183 -55.591517) (xy 363.4867 -55.611776) (xy 363.496381 -55.620631) (xy 363.519214 -55.633538)
			(xy 363.544579 -55.640211) (xy 363.570807 -55.640211) (xy 363.596172 -55.633538) (xy 363.619005 -55.620631)
			(xy 363.628686 -55.611776) (xy 363.650238 -55.591517) (xy 363.6984 -55.557186) (xy 363.751285 -55.5307)
			(xy 363.807624 -55.512695) (xy 363.866067 -55.503602) (xy 363.89564 -55.503064) (xy 364.75924 -55.503064)
			(xy 364.788814 -55.503615) (xy 364.847258 -55.512703) (xy 364.903599 -55.530701) (xy 364.956488 -55.557179)
			(xy 365.004658 -55.591501) (xy 365.026194 -55.611776) (xy 365.035875 -55.620631) (xy 365.058708 -55.633538)
			(xy 365.084073 -55.640211) (xy 365.110301 -55.640211) (xy 365.135666 -55.633538) (xy 365.158499 -55.620631)
			(xy 365.16818 -55.611776) (xy 365.189699 -55.591519) (xy 365.237821 -55.557216) (xy 365.290657 -55.530744)
			(xy 365.346942 -55.512735) (xy 365.405332 -55.50362) (xy 365.43488 -55.503064) (xy 365.462132 -55.503582)
			(xy 365.516081 -55.511336) (xy 365.568377 -55.526689) (xy 365.617956 -55.549329) (xy 365.663809 -55.578794)
			(xy 365.705001 -55.614485) (xy 365.740694 -55.655675) (xy 365.770162 -55.701526) (xy 365.792278 -55.749952)
			(xy 387.66191 -55.749952) (xy 387.665981 -55.69433) (xy 387.678107 -55.639893) (xy 387.69803 -55.587802)
			(xy 387.725326 -55.539167) (xy 387.759412 -55.495024) (xy 387.799561 -55.456315) (xy 387.844919 -55.423864)
			(xy 387.894519 -55.398363) (xy 387.947303 -55.380356) (xy 388.002146 -55.370226) (xy 388.05788 -55.368189)
			(xy 388.113317 -55.374289) (xy 388.167274 -55.388395) (xy 388.218603 -55.410207) (xy 388.266209 -55.439261)
			(xy 388.309077 -55.474936) (xy 388.346294 -55.516473) (xy 388.377067 -55.562986) (xy 388.400739 -55.613483)
			(xy 388.416807 -55.66689) (xy 388.424927 -55.722066) (xy 388.425436 -55.749952) (xy 388.424927 -55.777838)
			(xy 388.416807 -55.833014) (xy 388.400739 -55.886421) (xy 388.377067 -55.936918) (xy 388.346294 -55.983431)
			(xy 388.309077 -56.024968) (xy 388.266209 -56.060643) (xy 388.218603 -56.089697) (xy 388.167274 -56.111509)
			(xy 388.113317 -56.125615) (xy 388.05788 -56.131715) (xy 388.002146 -56.129678) (xy 387.947303 -56.119548)
			(xy 387.894519 -56.101541) (xy 387.844919 -56.07604) (xy 387.799561 -56.043589) (xy 387.759412 -56.00488)
			(xy 387.725326 -55.960737) (xy 387.69803 -55.912102) (xy 387.678107 -55.860011) (xy 387.665981 -55.805574)
			(xy 387.66191 -55.749952) (xy 365.792278 -55.749952) (xy 365.792804 -55.751104) (xy 365.80816 -55.8034)
			(xy 365.815917 -55.857348) (xy 365.815917 -55.911852) (xy 365.80816 -55.9658) (xy 365.792804 -56.018096)
			(xy 365.770162 -56.067674) (xy 365.740694 -56.113525) (xy 365.705001 -56.154715) (xy 365.663809 -56.190406)
			(xy 365.617956 -56.219871) (xy 365.568377 -56.242511) (xy 365.516081 -56.257864) (xy 365.462132 -56.265618)
			(xy 365.43488 -56.26608) (xy 365.405331 -56.265544) (xy 365.346939 -56.256427) (xy 365.290652 -56.238415)
			(xy 365.237816 -56.211938) (xy 365.189695 -56.177631) (xy 365.16818 -56.157368) (xy 365.158521 -56.148466)
			(xy 365.1357 -56.13548) (xy 365.110316 -56.128763) (xy 365.084058 -56.128763) (xy 365.058674 -56.13548)
			(xy 365.035853 -56.148466) (xy 365.026194 -56.157368) (xy 365.004658 -56.177644) (xy 364.956491 -56.211972)
			(xy 364.903602 -56.238453) (xy 364.84726 -56.256455) (xy 364.788814 -56.265544) (xy 364.75924 -56.26608)
			(xy 363.89564 -56.26608) (xy 363.866065 -56.265558) (xy 363.807619 -56.256465) (xy 363.751276 -56.238461)
			(xy 363.698388 -56.211977) (xy 363.650221 -56.177647) (xy 363.628686 -56.157368) (xy 363.619027 -56.148466)
			(xy 363.596206 -56.13548) (xy 363.570822 -56.128763) (xy 363.544564 -56.128763) (xy 363.51918 -56.13548)
			(xy 363.496359 -56.148466) (xy 363.4867 -56.157368) (xy 363.465181 -56.177625) (xy 363.41706 -56.21193)
			(xy 363.364224 -56.238403) (xy 363.307938 -56.256412) (xy 363.249548 -56.265526) (xy 363.22 -56.26608)
			(xy 363.192747 -56.26565) (xy 363.138795 -56.257893) (xy 363.086496 -56.242537) (xy 363.036916 -56.219894)
			(xy 362.991062 -56.190426) (xy 362.949869 -56.154731) (xy 362.914174 -56.113538) (xy 362.884706 -56.067684)
			(xy 362.862063 -56.018104) (xy 362.846707 -55.965805) (xy 362.83895 -55.911853) (xy 362.252317 -55.911853)
			(xy 362.244559 -55.965803) (xy 362.229202 -56.0181) (xy 362.206558 -56.06768) (xy 362.177089 -56.113531)
			(xy 362.141394 -56.154722) (xy 362.100199 -56.190413) (xy 362.054344 -56.219878) (xy 362.004763 -56.242516)
			(xy 361.952464 -56.257868) (xy 361.898513 -56.265619) (xy 361.87126 -56.26608) (xy 361.84171 -56.265556)
			(xy 361.783318 -56.256436) (xy 361.727031 -56.238421) (xy 361.674195 -56.211942) (xy 361.626075 -56.177632)
			(xy 361.60456 -56.157368) (xy 361.594901 -56.148466) (xy 361.57208 -56.13548) (xy 361.546696 -56.128763)
			(xy 361.520438 -56.128763) (xy 361.495054 -56.13548) (xy 361.472233 -56.148466) (xy 361.462574 -56.157368)
			(xy 361.441047 -56.177654) (xy 361.392877 -56.21198) (xy 361.339986 -56.23846) (xy 361.283642 -56.256459)
			(xy 361.225195 -56.265545) (xy 361.19562 -56.26608) (xy 360.33202 -56.26608) (xy 360.303151 -56.265538)
			(xy 360.246069 -56.256862) (xy 360.190945 -56.239688) (xy 360.139035 -56.21441) (xy 360.091524 -56.181602)
			(xy 360.070146 -56.162194) (xy 360.058586 -56.151985) (xy 360.030896 -56.138437) (xy 360.000423 -56.133779)
			(xy 359.96995 -56.138437) (xy 359.94226 -56.151985) (xy 359.9307 -56.162194) (xy 359.909333 -56.181578)
			(xy 359.861877 -56.214379) (xy 359.810023 -56.239661) (xy 359.754953 -56.256847) (xy 359.697924 -56.265545)
			(xy 359.66908 -56.26608) (xy 359.63939 -56.265491) (xy 359.580726 -56.256289) (xy 359.524197 -56.23811)
			(xy 359.471166 -56.211393) (xy 359.422914 -56.176783) (xy 359.401364 -56.156352) (xy 359.391665 -56.147378)
			(xy 359.368727 -56.134279) (xy 359.343197 -56.127502) (xy 359.316783 -56.127502) (xy 359.291253 -56.134279)
			(xy 359.268315 -56.147378) (xy 359.258616 -56.156352) (xy 359.237056 -56.176775) (xy 359.188812 -56.211398)
			(xy 359.135785 -56.238125) (xy 359.079256 -56.25631) (xy 359.020591 -56.265514) (xy 358.9909 -56.26608)
			(xy 358.96313 -56.265611) (xy 358.908178 -56.257562) (xy 358.854971 -56.241635) (xy 358.804635 -56.218164)
			(xy 358.758232 -56.187647) (xy 358.737154 -56.16956) (xy 358.725752 -56.160092) (xy 358.698902 -56.147575)
			(xy 358.66959 -56.143282) (xy 358.640278 -56.147575) (xy 358.613428 -56.160092) (xy 358.602026 -56.16956)
			(xy 358.580964 -56.187663) (xy 358.534552 -56.218165) (xy 358.48421 -56.241623) (xy 358.431002 -56.25754)
			(xy 358.376049 -56.265582) (xy 358.34828 -56.26608) (xy 357.48468 -56.26608) (xy 357.458485 -56.265645)
			(xy 357.406588 -56.258478) (xy 357.356158 -56.244283) (xy 357.308143 -56.223326) (xy 357.263444 -56.196)
			(xy 357.222901 -56.162818) (xy 357.204772 -56.143906) (xy 357.194963 -56.133929) (xy 357.171124 -56.119302)
			(xy 357.144207 -56.111703) (xy 357.116239 -56.111703) (xy 357.089322 -56.119302) (xy 357.065483 -56.133929)
			(xy 357.055674 -56.143906) (xy 357.037578 -56.162821) (xy 356.997064 -56.195971) (xy 356.952402 -56.223278)
			(xy 356.90443 -56.244231) (xy 356.854046 -56.258436) (xy 356.802194 -56.265628) (xy 356.77602 -56.26608)
			(xy 356.748764 -56.265674) (xy 356.694807 -56.257919) (xy 356.642503 -56.242564) (xy 356.592917 -56.219921)
			(xy 356.547058 -56.190451) (xy 356.505859 -56.154755) (xy 356.470161 -56.113558) (xy 356.440689 -56.067701)
			(xy 356.418043 -56.018116) (xy 356.402685 -55.965812) (xy 356.394927 -55.911856) (xy 351.986031 -55.911856)
			(xy 351.989429 -55.914001) (xy 352.030387 -55.948769) (xy 352.066062 -55.988939) (xy 352.095749 -56.033716)
			(xy 352.118862 -56.082215) (xy 352.134941 -56.133477) (xy 352.139758 -56.159908) (xy 352.142669 -56.174482)
			(xy 352.155724 -56.201166) (xy 352.17589 -56.22298) (xy 352.201469 -56.238087) (xy 352.230308 -56.245215)
			(xy 352.245168 -56.244998) (xy 352.264472 -56.24449) (xy 352.291724 -56.244981) (xy 352.345674 -56.252734)
			(xy 352.397971 -56.268087) (xy 352.447551 -56.290726) (xy 352.493404 -56.320191) (xy 352.534597 -56.355882)
			(xy 352.570291 -56.397072) (xy 352.59976 -56.442923) (xy 352.622403 -56.492501) (xy 352.637759 -56.544797)
			(xy 352.645517 -56.598746) (xy 352.64598 -56.625998) (xy 352.645486 -56.654128) (xy 352.637224 -56.709778)
			(xy 352.620878 -56.763611) (xy 352.596802 -56.814459) (xy 352.56552 -56.86122) (xy 352.527709 -56.90288)
			(xy 352.48419 -56.938535) (xy 352.460306 -56.953404) (xy 352.447564 -56.961695) (xy 352.427203 -56.984243)
			(xy 352.414358 -57.011776) (xy 352.410161 -57.041866) (xy 352.414984 -57.071862) (xy 352.42119 -57.085738)
			(xy 352.433586 -57.11211) (xy 352.451138 -57.167671) (xy 352.460011 -57.22526) (xy 352.46012 -57.231048)
			(xy 358.749626 -57.231048) (xy 358.749626 -57.176552) (xy 358.757382 -57.122611) (xy 358.772735 -57.070323)
			(xy 358.795373 -57.020752) (xy 358.824836 -56.974908) (xy 358.860523 -56.933723) (xy 358.901708 -56.898036)
			(xy 358.947552 -56.868573) (xy 358.997123 -56.845935) (xy 359.049411 -56.830582) (xy 359.103352 -56.822826)
			(xy 359.1306 -56.82234) (xy 359.156391 -56.822766) (xy 359.207501 -56.829732) (xy 359.257206 -56.843524)
			(xy 359.304598 -56.86389) (xy 359.348813 -56.890458) (xy 359.389043 -56.922743) (xy 359.424554 -56.960156)
			(xy 359.439972 -56.980836) (xy 359.449098 -56.992545) (xy 359.472613 -57.010637) (xy 359.500339 -57.021197)
			(xy 359.529931 -57.023333) (xy 359.558886 -57.016863) (xy 359.584755 -57.002336) (xy 359.59542 -56.992012)
			(xy 359.613472 -56.973971) (xy 359.653525 -56.942342) (xy 359.697436 -56.916333) (xy 359.744421 -56.896406)
			(xy 359.793642 -56.882919) (xy 359.844222 -56.87611) (xy 359.86974 -56.87568) (xy 359.896988 -56.876193)
			(xy 359.95093 -56.883954) (xy 360.003218 -56.899312) (xy 360.052789 -56.921955) (xy 360.098633 -56.951421)
			(xy 360.139817 -56.987111) (xy 360.175503 -57.028299) (xy 360.204965 -57.074146) (xy 360.227602 -57.123719)
			(xy 360.235468 -57.150508) (xy 361.446062 -57.150508) (xy 361.450133 -57.094886) (xy 361.462259 -57.040449)
			(xy 361.482182 -56.988358) (xy 361.509478 -56.939723) (xy 361.543564 -56.89558) (xy 361.583713 -56.856871)
			(xy 361.629071 -56.82442) (xy 361.678671 -56.798919) (xy 361.731455 -56.780912) (xy 361.786298 -56.770782)
			(xy 361.842032 -56.768745) (xy 361.897469 -56.774845) (xy 361.951426 -56.788951) (xy 362.002755 -56.810763)
			(xy 362.050361 -56.839817) (xy 362.093229 -56.875492) (xy 362.130446 -56.917029) (xy 362.161219 -56.963542)
			(xy 362.184891 -57.014039) (xy 362.200959 -57.067446) (xy 362.209079 -57.122622) (xy 362.209588 -57.150508)
			(xy 362.209079 -57.178394) (xy 362.206454 -57.196228) (xy 362.868462 -57.196228) (xy 362.872533 -57.140606)
			(xy 362.884659 -57.086169) (xy 362.904582 -57.034078) (xy 362.931878 -56.985443) (xy 362.965964 -56.9413)
			(xy 363.006113 -56.902591) (xy 363.051471 -56.87014) (xy 363.101071 -56.844639) (xy 363.153855 -56.826632)
			(xy 363.208698 -56.816502) (xy 363.264432 -56.814465) (xy 363.319869 -56.820565) (xy 363.373826 -56.834671)
			(xy 363.425155 -56.856483) (xy 363.472761 -56.885537) (xy 363.504257 -56.911748) (xy 365.756442 -56.911748)
			(xy 365.760513 -56.856126) (xy 365.772639 -56.801689) (xy 365.792562 -56.749598) (xy 365.819858 -56.700963)
			(xy 365.853944 -56.65682) (xy 365.894093 -56.618111) (xy 365.939451 -56.58566) (xy 365.989051 -56.560159)
			(xy 366.041835 -56.542152) (xy 366.096678 -56.532022) (xy 366.152412 -56.529985) (xy 366.207849 -56.536085)
			(xy 366.261806 -56.550191) (xy 366.313135 -56.572003) (xy 366.360741 -56.601057) (xy 366.403609 -56.636732)
			(xy 366.440826 -56.678269) (xy 366.471599 -56.724782) (xy 366.495271 -56.775279) (xy 366.511339 -56.828686)
			(xy 366.519459 -56.883862) (xy 366.519968 -56.911748) (xy 366.519459 -56.939634) (xy 366.511339 -56.99481)
			(xy 366.495271 -57.048217) (xy 366.471599 -57.098714) (xy 366.440826 -57.145227) (xy 366.403609 -57.186764)
			(xy 366.360741 -57.222439) (xy 366.313135 -57.251493) (xy 366.284192 -57.263792) (xy 374.739914 -57.263792)
			(xy 374.743985 -57.20817) (xy 374.756111 -57.153733) (xy 374.776034 -57.101642) (xy 374.80333 -57.053007)
			(xy 374.837416 -57.008864) (xy 374.877565 -56.970155) (xy 374.922923 -56.937704) (xy 374.972523 -56.912203)
			(xy 375.025307 -56.894196) (xy 375.08015 -56.884066) (xy 375.135884 -56.882029) (xy 375.191321 -56.888129)
			(xy 375.245278 -56.902235) (xy 375.296607 -56.924047) (xy 375.344213 -56.953101) (xy 375.387081 -56.988776)
			(xy 375.424298 -57.030313) (xy 375.455071 -57.076826) (xy 375.478743 -57.127323) (xy 375.494811 -57.18073)
			(xy 375.501204 -57.224168) (xy 379.784862 -57.224168) (xy 379.788933 -57.168546) (xy 379.801059 -57.114109)
			(xy 379.820982 -57.062018) (xy 379.848278 -57.013383) (xy 379.882364 -56.96924) (xy 379.922513 -56.930531)
			(xy 379.967871 -56.89808) (xy 380.017471 -56.872579) (xy 380.070255 -56.854572) (xy 380.125098 -56.844442)
			(xy 380.180832 -56.842405) (xy 380.236269 -56.848505) (xy 380.290226 -56.862611) (xy 380.341555 -56.884423)
			(xy 380.389161 -56.913477) (xy 380.432029 -56.949152) (xy 380.469246 -56.990689) (xy 380.500019 -57.037202)
			(xy 380.523691 -57.087699) (xy 380.539759 -57.141106) (xy 380.547879 -57.196282) (xy 380.548388 -57.224168)
			(xy 380.547879 -57.252054) (xy 380.544133 -57.277508) (xy 381.085342 -57.277508) (xy 381.089413 -57.221886)
			(xy 381.101539 -57.167449) (xy 381.121462 -57.115358) (xy 381.148758 -57.066723) (xy 381.182844 -57.02258)
			(xy 381.222993 -56.983871) (xy 381.268351 -56.95142) (xy 381.317951 -56.925919) (xy 381.370735 -56.907912)
			(xy 381.425578 -56.897782) (xy 381.481312 -56.895745) (xy 381.536749 -56.901845) (xy 381.590706 -56.915951)
			(xy 381.642035 -56.937763) (xy 381.689641 -56.966817) (xy 381.732509 -57.002492) (xy 381.769726 -57.044029)
			(xy 381.800499 -57.090542) (xy 381.824171 -57.141039) (xy 381.840239 -57.194446) (xy 381.848359 -57.249622)
			(xy 381.848868 -57.277508) (xy 381.983994 -57.277508) (xy 381.988065 -57.221886) (xy 382.000191 -57.167449)
			(xy 382.020114 -57.115358) (xy 382.04741 -57.066723) (xy 382.081496 -57.02258) (xy 382.121645 -56.983871)
			(xy 382.167003 -56.95142) (xy 382.216603 -56.925919) (xy 382.269387 -56.907912) (xy 382.32423 -56.897782)
			(xy 382.379964 -56.895745) (xy 382.435401 -56.901845) (xy 382.489358 -56.915951) (xy 382.540687 -56.937763)
			(xy 382.588293 -56.966817) (xy 382.631161 -57.002492) (xy 382.668378 -57.044029) (xy 382.699151 -57.090542)
			(xy 382.722823 -57.141039) (xy 382.738891 -57.194446) (xy 382.747011 -57.249622) (xy 382.74752 -57.277508)
			(xy 382.747455 -57.281064) (xy 383.1623 -57.281064) (xy 383.166371 -57.225442) (xy 383.178497 -57.171005)
			(xy 383.19842 -57.118914) (xy 383.225716 -57.070279) (xy 383.259802 -57.026136) (xy 383.299951 -56.987427)
			(xy 383.345309 -56.954976) (xy 383.394909 -56.929475) (xy 383.447693 -56.911468) (xy 383.502536 -56.901338)
			(xy 383.55827 -56.899301) (xy 383.613707 -56.905401) (xy 383.667664 -56.919507) (xy 383.718993 -56.941319)
			(xy 383.766599 -56.970373) (xy 383.809467 -57.006048) (xy 383.846684 -57.047585) (xy 383.877457 -57.094098)
			(xy 383.901129 -57.144595) (xy 383.911467 -57.178956) (xy 387.26059 -57.178956) (xy 387.264661 -57.123334)
			(xy 387.276787 -57.068897) (xy 387.29671 -57.016806) (xy 387.324006 -56.968171) (xy 387.358092 -56.924028)
			(xy 387.398241 -56.885319) (xy 387.443599 -56.852868) (xy 387.493199 -56.827367) (xy 387.545983 -56.80936)
			(xy 387.600826 -56.79923) (xy 387.65656 -56.797193) (xy 387.711997 -56.803293) (xy 387.765954 -56.817399)
			(xy 387.817283 -56.839211) (xy 387.864889 -56.868265) (xy 387.907757 -56.90394) (xy 387.944974 -56.945477)
			(xy 387.975747 -56.99199) (xy 387.999419 -57.042487) (xy 388.015487 -57.095894) (xy 388.023607 -57.15107)
			(xy 388.024116 -57.178956) (xy 388.023607 -57.206842) (xy 388.015487 -57.262018) (xy 388.001096 -57.309851)
			(xy 388.155166 -57.309851) (xy 388.155166 -57.255349) (xy 388.162922 -57.201401) (xy 388.178277 -57.149106)
			(xy 388.200917 -57.099529) (xy 388.230382 -57.053678) (xy 388.266073 -57.012487) (xy 388.307262 -56.976794)
			(xy 388.353111 -56.947327) (xy 388.402688 -56.924684) (xy 388.454982 -56.909326) (xy 388.508929 -56.901567)
			(xy 388.53618 -56.90108) (xy 388.563048 -56.90153) (xy 388.616252 -56.909073) (xy 388.667869 -56.924012)
			(xy 388.716877 -56.946052) (xy 388.762304 -56.974755) (xy 388.803251 -57.009553) (xy 388.821422 -57.02935)
			(xy 388.83169 -57.040094) (xy 388.856975 -57.055681) (xy 388.885673 -57.06334) (xy 388.915362 -57.062424)
			(xy 388.943535 -57.053011) (xy 388.967811 -57.035895) (xy 388.977378 -57.024524) (xy 388.995557 -57.002125)
			(xy 389.037563 -56.962587) (xy 389.085041 -56.929821) (xy 389.136909 -56.904572) (xy 389.191985 -56.887416)
			(xy 389.249017 -56.878744) (xy 389.27786 -56.87822) (xy 389.305962 -56.878727) (xy 389.361558 -56.886968)
			(xy 389.415344 -56.903277) (xy 389.466154 -56.927302) (xy 389.512889 -56.958522) (xy 389.554537 -56.996262)
			(xy 389.572754 -57.017666) (xy 389.582816 -57.029096) (xy 389.608188 -57.045909) (xy 389.637387 -57.0545)
			(xy 389.667821 -57.054107) (xy 389.696789 -57.044765) (xy 389.721718 -57.027302) (xy 389.731504 -57.015634)
			(xy 389.749682 -56.993128) (xy 389.791693 -56.953356) (xy 389.839222 -56.920376) (xy 389.891184 -56.894945)
			(xy 389.946387 -56.877645) (xy 390.003569 -56.868871) (xy 390.032494 -56.868314) (xy 390.059749 -56.868732)
			(xy 390.113703 -56.876489) (xy 390.166005 -56.891846) (xy 390.215589 -56.914489) (xy 390.261445 -56.943959)
			(xy 390.302641 -56.979654) (xy 390.338338 -57.02085) (xy 390.367808 -57.066706) (xy 390.390452 -57.116289)
			(xy 390.40581 -57.168591) (xy 390.413567 -57.222545) (xy 390.413567 -57.277055) (xy 390.40581 -57.331009)
			(xy 390.390452 -57.383311) (xy 390.367808 -57.432894) (xy 390.338338 -57.47875) (xy 390.302641 -57.519946)
			(xy 390.261445 -57.555641) (xy 390.215589 -57.585111) (xy 390.166005 -57.607754) (xy 390.113703 -57.623111)
			(xy 390.059749 -57.630868) (xy 390.032494 -57.63133) (xy 390.00439 -57.630873) (xy 389.948791 -57.622624)
			(xy 389.895003 -57.606306) (xy 389.844193 -57.582272) (xy 389.797459 -57.551042) (xy 389.755814 -57.513293)
			(xy 389.7376 -57.491884) (xy 389.727484 -57.480503) (xy 389.70213 -57.46368) (xy 389.672943 -57.455078)
			(xy 389.642517 -57.455461) (xy 389.613556 -57.464795) (xy 389.588633 -57.48225) (xy 389.57885 -57.493916)
			(xy 389.560654 -57.516406) (xy 389.518646 -57.556178) (xy 389.471119 -57.589157) (xy 389.419162 -57.614591)
			(xy 389.363962 -57.631895) (xy 389.306784 -57.640675) (xy 389.27786 -57.641236) (xy 389.250993 -57.640754)
			(xy 389.197791 -57.633217) (xy 389.146175 -57.618283) (xy 389.097167 -57.59625) (xy 389.051739 -57.567552)
			(xy 389.01079 -57.53276) (xy 388.992618 -57.512966) (xy 388.982411 -57.502158) (xy 388.957109 -57.486572)
			(xy 388.928394 -57.478919) (xy 388.898691 -57.479847) (xy 388.870509 -57.489276) (xy 388.846228 -57.506411)
			(xy 388.836662 -57.517792) (xy 388.818464 -57.540175) (xy 388.776462 -57.579713) (xy 388.728988 -57.612481)
			(xy 388.677124 -57.637733) (xy 388.622051 -57.654892) (xy 388.565022 -57.663569) (xy 388.53618 -57.664096)
			(xy 388.508929 -57.663633) (xy 388.454982 -57.655874) (xy 388.402688 -57.640516) (xy 388.353111 -57.617873)
			(xy 388.307262 -57.588406) (xy 388.266073 -57.552713) (xy 388.230382 -57.511522) (xy 388.200917 -57.465671)
			(xy 388.178277 -57.416094) (xy 388.162922 -57.363799) (xy 388.155166 -57.309851) (xy 388.001096 -57.309851)
			(xy 387.999419 -57.315425) (xy 387.975747 -57.365922) (xy 387.944974 -57.412435) (xy 387.907757 -57.453972)
			(xy 387.864889 -57.489647) (xy 387.817283 -57.518701) (xy 387.765954 -57.540513) (xy 387.711997 -57.554619)
			(xy 387.65656 -57.560719) (xy 387.600826 -57.558682) (xy 387.545983 -57.548552) (xy 387.493199 -57.530545)
			(xy 387.443599 -57.505044) (xy 387.398241 -57.472593) (xy 387.358092 -57.433884) (xy 387.324006 -57.389741)
			(xy 387.29671 -57.341106) (xy 387.276787 -57.289015) (xy 387.264661 -57.234578) (xy 387.26059 -57.178956)
			(xy 383.911467 -57.178956) (xy 383.917197 -57.198002) (xy 383.925317 -57.253178) (xy 383.925826 -57.281064)
			(xy 383.925317 -57.30895) (xy 383.917197 -57.364126) (xy 383.901129 -57.417533) (xy 383.877457 -57.46803)
			(xy 383.846684 -57.514543) (xy 383.809467 -57.55608) (xy 383.766599 -57.591755) (xy 383.718993 -57.620809)
			(xy 383.667664 -57.642621) (xy 383.613707 -57.656727) (xy 383.55827 -57.662827) (xy 383.502536 -57.66079)
			(xy 383.447693 -57.65066) (xy 383.394909 -57.632653) (xy 383.345309 -57.607152) (xy 383.299951 -57.574701)
			(xy 383.259802 -57.535992) (xy 383.225716 -57.491849) (xy 383.19842 -57.443214) (xy 383.178497 -57.391123)
			(xy 383.166371 -57.336686) (xy 383.1623 -57.281064) (xy 382.747455 -57.281064) (xy 382.747011 -57.305394)
			(xy 382.738891 -57.36057) (xy 382.722823 -57.413977) (xy 382.699151 -57.464474) (xy 382.668378 -57.510987)
			(xy 382.631161 -57.552524) (xy 382.588293 -57.588199) (xy 382.540687 -57.617253) (xy 382.489358 -57.639065)
			(xy 382.435401 -57.653171) (xy 382.379964 -57.659271) (xy 382.32423 -57.657234) (xy 382.269387 -57.647104)
			(xy 382.216603 -57.629097) (xy 382.167003 -57.603596) (xy 382.121645 -57.571145) (xy 382.081496 -57.532436)
			(xy 382.04741 -57.488293) (xy 382.020114 -57.439658) (xy 382.000191 -57.387567) (xy 381.988065 -57.33313)
			(xy 381.983994 -57.277508) (xy 381.848868 -57.277508) (xy 381.848359 -57.305394) (xy 381.840239 -57.36057)
			(xy 381.824171 -57.413977) (xy 381.800499 -57.464474) (xy 381.769726 -57.510987) (xy 381.732509 -57.552524)
			(xy 381.689641 -57.588199) (xy 381.642035 -57.617253) (xy 381.590706 -57.639065) (xy 381.536749 -57.653171)
			(xy 381.481312 -57.659271) (xy 381.425578 -57.657234) (xy 381.370735 -57.647104) (xy 381.317951 -57.629097)
			(xy 381.268351 -57.603596) (xy 381.222993 -57.571145) (xy 381.182844 -57.532436) (xy 381.148758 -57.488293)
			(xy 381.121462 -57.439658) (xy 381.101539 -57.387567) (xy 381.089413 -57.33313) (xy 381.085342 -57.277508)
			(xy 380.544133 -57.277508) (xy 380.539759 -57.30723) (xy 380.523691 -57.360637) (xy 380.500019 -57.411134)
			(xy 380.469246 -57.457647) (xy 380.432029 -57.499184) (xy 380.389161 -57.534859) (xy 380.341555 -57.563913)
			(xy 380.290226 -57.585725) (xy 380.236269 -57.599831) (xy 380.180832 -57.605931) (xy 380.125098 -57.603894)
			(xy 380.070255 -57.593764) (xy 380.017471 -57.575757) (xy 379.967871 -57.550256) (xy 379.922513 -57.517805)
			(xy 379.882364 -57.479096) (xy 379.848278 -57.434953) (xy 379.820982 -57.386318) (xy 379.801059 -57.334227)
			(xy 379.788933 -57.27979) (xy 379.784862 -57.224168) (xy 375.501204 -57.224168) (xy 375.502931 -57.235906)
			(xy 375.50344 -57.263792) (xy 375.502931 -57.291678) (xy 375.494811 -57.346854) (xy 375.478743 -57.400261)
			(xy 375.455071 -57.450758) (xy 375.424298 -57.497271) (xy 375.387081 -57.538808) (xy 375.344213 -57.574483)
			(xy 375.296607 -57.603537) (xy 375.245278 -57.625349) (xy 375.191321 -57.639455) (xy 375.135884 -57.645555)
			(xy 375.08015 -57.643518) (xy 375.025307 -57.633388) (xy 374.972523 -57.615381) (xy 374.922923 -57.58988)
			(xy 374.877565 -57.557429) (xy 374.837416 -57.51872) (xy 374.80333 -57.474577) (xy 374.776034 -57.425942)
			(xy 374.756111 -57.373851) (xy 374.743985 -57.319414) (xy 374.739914 -57.263792) (xy 366.284192 -57.263792)
			(xy 366.261806 -57.273305) (xy 366.207849 -57.287411) (xy 366.152412 -57.293511) (xy 366.096678 -57.291474)
			(xy 366.041835 -57.281344) (xy 365.989051 -57.263337) (xy 365.939451 -57.237836) (xy 365.894093 -57.205385)
			(xy 365.853944 -57.166676) (xy 365.819858 -57.122533) (xy 365.792562 -57.073898) (xy 365.772639 -57.021807)
			(xy 365.760513 -56.96737) (xy 365.756442 -56.911748) (xy 363.504257 -56.911748) (xy 363.515629 -56.921212)
			(xy 363.552846 -56.962749) (xy 363.583619 -57.009262) (xy 363.607291 -57.059759) (xy 363.623359 -57.113166)
			(xy 363.631479 -57.168342) (xy 363.631988 -57.196228) (xy 363.631479 -57.224114) (xy 363.623359 -57.27929)
			(xy 363.607291 -57.332697) (xy 363.583619 -57.383194) (xy 363.552846 -57.429707) (xy 363.515629 -57.471244)
			(xy 363.472761 -57.506919) (xy 363.425155 -57.535973) (xy 363.373826 -57.557785) (xy 363.319869 -57.571891)
			(xy 363.264432 -57.577991) (xy 363.208698 -57.575954) (xy 363.153855 -57.565824) (xy 363.101071 -57.547817)
			(xy 363.051471 -57.522316) (xy 363.006113 -57.489865) (xy 362.965964 -57.451156) (xy 362.931878 -57.407013)
			(xy 362.904582 -57.358378) (xy 362.884659 -57.306287) (xy 362.872533 -57.25185) (xy 362.868462 -57.196228)
			(xy 362.206454 -57.196228) (xy 362.200959 -57.23357) (xy 362.184891 -57.286977) (xy 362.161219 -57.337474)
			(xy 362.130446 -57.383987) (xy 362.093229 -57.425524) (xy 362.050361 -57.461199) (xy 362.002755 -57.490253)
			(xy 361.951426 -57.512065) (xy 361.897469 -57.526171) (xy 361.842032 -57.532271) (xy 361.786298 -57.530234)
			(xy 361.731455 -57.520104) (xy 361.678671 -57.502097) (xy 361.629071 -57.476596) (xy 361.583713 -57.444145)
			(xy 361.543564 -57.405436) (xy 361.509478 -57.361293) (xy 361.482182 -57.312658) (xy 361.462259 -57.260567)
			(xy 361.450133 -57.20613) (xy 361.446062 -57.150508) (xy 360.235468 -57.150508) (xy 360.242955 -57.176009)
			(xy 360.25071 -57.229951) (xy 360.25071 -57.284449) (xy 360.242955 -57.338391) (xy 360.227602 -57.390681)
			(xy 360.204965 -57.440254) (xy 360.175503 -57.486101) (xy 360.139817 -57.527289) (xy 360.098633 -57.562979)
			(xy 360.052789 -57.592445) (xy 360.003218 -57.615088) (xy 359.95093 -57.630446) (xy 359.896988 -57.638207)
			(xy 359.86974 -57.638696) (xy 359.84395 -57.638226) (xy 359.792843 -57.631265) (xy 359.74314 -57.61748)
			(xy 359.695748 -57.597121) (xy 359.651533 -57.57056) (xy 359.611302 -57.538283) (xy 359.575788 -57.500876)
			(xy 359.560368 -57.4802) (xy 359.551307 -57.468434) (xy 359.527777 -57.450337) (xy 359.500034 -57.439778)
			(xy 359.470426 -57.437652) (xy 359.441459 -57.444138) (xy 359.415584 -57.458688) (xy 359.40492 -57.469024)
			(xy 359.386885 -57.487083) (xy 359.346829 -57.518712) (xy 359.302915 -57.54472) (xy 359.255926 -57.564644)
			(xy 359.206702 -57.578128) (xy 359.156119 -57.58493) (xy 359.1306 -57.585356) (xy 359.103352 -57.584774)
			(xy 359.049411 -57.577018) (xy 358.997123 -57.561665) (xy 358.947552 -57.539027) (xy 358.901708 -57.509564)
			(xy 358.860523 -57.473877) (xy 358.824836 -57.432692) (xy 358.795373 -57.386848) (xy 358.772735 -57.337277)
			(xy 358.757382 -57.284989) (xy 358.749626 -57.231048) (xy 352.46012 -57.231048) (xy 352.46056 -57.254394)
			(xy 352.460139 -57.281649) (xy 352.452382 -57.335604) (xy 352.437024 -57.387905) (xy 352.414379 -57.437489)
			(xy 352.384907 -57.483344) (xy 352.349208 -57.524538) (xy 352.30801 -57.560232) (xy 352.262152 -57.589699)
			(xy 352.212566 -57.612339) (xy 352.160263 -57.62769) (xy 352.106307 -57.635442) (xy 352.079052 -57.635902)
			(xy 352.050822 -57.635438) (xy 351.994976 -57.627138) (xy 351.940964 -57.610696) (xy 351.889966 -57.586473)
			(xy 351.843095 -57.554996) (xy 351.801376 -57.516955) (xy 351.76572 -57.473179) (xy 351.736907 -57.424625)
			(xy 351.715565 -57.372355) (xy 351.702162 -57.31751) (xy 351.699068 -57.289446) (xy 351.697441 -57.275965)
			(xy 351.687971 -57.250525) (xy 351.672124 -57.228486) (xy 351.651024 -57.211408) (xy 351.626165 -57.200504)
			(xy 351.59931 -57.196546) (xy 351.585784 -57.197752) (xy 351.574462 -57.199048) (xy 351.551714 -57.200448)
			(xy 351.540318 -57.200546) (xy 351.513069 -57.200005) (xy 351.459125 -57.192252) (xy 351.406834 -57.176901)
			(xy 351.357259 -57.154265) (xy 351.311411 -57.124804) (xy 351.270221 -57.089118) (xy 351.23453 -57.047934)
			(xy 351.205062 -57.00209) (xy 351.182418 -56.952519) (xy 351.16706 -56.90023) (xy 351.159299 -56.846287)
			(xy 351.15881 -56.819038) (xy 351.159028 -56.799532) (xy 351.162975 -56.76072) (xy 351.166684 -56.741568)
			(xy 351.16899 -56.728085) (xy 351.167219 -56.700803) (xy 351.158274 -56.674967) (xy 351.142795 -56.65243)
			(xy 351.121893 -56.634806) (xy 351.097065 -56.623359) (xy 351.070089 -56.618908) (xy 351.056448 -56.619902)
			(xy 351.046257 -56.620953) (xy 351.025799 -56.622099) (xy 351.015554 -56.622188) (xy 350.988303 -56.621739)
			(xy 350.934358 -56.613977) (xy 350.882066 -56.598617) (xy 350.832492 -56.575972) (xy 350.786645 -56.546503)
			(xy 350.745458 -56.510809) (xy 350.70977 -56.469618) (xy 350.680306 -56.423768) (xy 350.657667 -56.374191)
			(xy 350.642313 -56.321897) (xy 350.634558 -56.267951) (xy 344.67723 -56.267951) (xy 344.696521 -56.308009)
			(xy 344.712231 -56.358939) (xy 344.720174 -56.411643) (xy 344.720672 -56.438292) (xy 344.720174 -56.464941)
			(xy 344.712231 -56.517645) (xy 344.696521 -56.568575) (xy 344.673395 -56.616596) (xy 344.643371 -56.660633)
			(xy 344.607119 -56.699704) (xy 344.565448 -56.732935) (xy 344.51929 -56.759584) (xy 344.469676 -56.779056)
			(xy 344.417714 -56.790916) (xy 344.364564 -56.7949) (xy 344.311414 -56.790916) (xy 344.259452 -56.779056)
			(xy 344.209838 -56.759584) (xy 344.16368 -56.732935) (xy 344.122009 -56.699704) (xy 344.085757 -56.660633)
			(xy 344.055733 -56.616596) (xy 344.032607 -56.568575) (xy 344.016897 -56.517645) (xy 344.008954 -56.464941)
			(xy 343.090764 -56.464941) (xy 343.082821 -56.517645) (xy 343.067111 -56.568575) (xy 343.043985 -56.616596)
			(xy 343.013961 -56.660633) (xy 342.977709 -56.699704) (xy 342.936038 -56.732935) (xy 342.88988 -56.759584)
			(xy 342.840266 -56.779056) (xy 342.788304 -56.790916) (xy 342.735154 -56.7949) (xy 342.682004 -56.790916)
			(xy 342.630042 -56.779056) (xy 342.580428 -56.759584) (xy 342.53427 -56.732935) (xy 342.492599 -56.699704)
			(xy 342.456347 -56.660633) (xy 342.426323 -56.616596) (xy 342.403197 -56.568575) (xy 342.387487 -56.517645)
			(xy 342.379544 -56.464941) (xy 341.461613 -56.464941) (xy 341.461608 -56.465195) (xy 341.453665 -56.517899)
			(xy 341.437955 -56.568829) (xy 341.414829 -56.61685) (xy 341.384805 -56.660887) (xy 341.348553 -56.699958)
			(xy 341.306882 -56.733189) (xy 341.260724 -56.759838) (xy 341.21111 -56.77931) (xy 341.159148 -56.79117)
			(xy 341.105998 -56.795154) (xy 341.052848 -56.79117) (xy 341.000886 -56.77931) (xy 340.951272 -56.759838)
			(xy 340.905114 -56.733189) (xy 340.863443 -56.699958) (xy 340.827191 -56.660887) (xy 340.797167 -56.61685)
			(xy 340.774041 -56.568829) (xy 340.758331 -56.517899) (xy 340.750388 -56.465195) (xy 339.833468 -56.465195)
			(xy 339.825525 -56.517899) (xy 339.809815 -56.568829) (xy 339.786689 -56.61685) (xy 339.756665 -56.660887)
			(xy 339.720413 -56.699958) (xy 339.678742 -56.733189) (xy 339.632584 -56.759838) (xy 339.58297 -56.77931)
			(xy 339.531008 -56.79117) (xy 339.477858 -56.795154) (xy 339.424708 -56.79117) (xy 339.372746 -56.77931)
			(xy 339.323132 -56.759838) (xy 339.276974 -56.733189) (xy 339.235303 -56.699958) (xy 339.199051 -56.660887)
			(xy 339.169027 -56.61685) (xy 339.145901 -56.568829) (xy 339.130191 -56.517899) (xy 339.122248 -56.465195)
			(xy 338.751428 -56.465195) (xy 338.743485 -56.517899) (xy 338.727775 -56.568829) (xy 338.704649 -56.61685)
			(xy 338.674625 -56.660887) (xy 338.638373 -56.699958) (xy 338.596702 -56.733189) (xy 338.550544 -56.759838)
			(xy 338.50093 -56.77931) (xy 338.448968 -56.79117) (xy 338.395818 -56.795154) (xy 338.342668 -56.79117)
			(xy 338.290706 -56.77931) (xy 338.241092 -56.759838) (xy 338.194934 -56.733189) (xy 338.153263 -56.699958)
			(xy 338.117011 -56.660887) (xy 338.086987 -56.61685) (xy 338.063861 -56.568829) (xy 338.048151 -56.517899)
			(xy 338.040208 -56.465195) (xy 337.123034 -56.465195) (xy 337.115091 -56.517899) (xy 337.099381 -56.568829)
			(xy 337.076255 -56.61685) (xy 337.046231 -56.660887) (xy 337.009979 -56.699958) (xy 336.968308 -56.733189)
			(xy 336.92215 -56.759838) (xy 336.872536 -56.77931) (xy 336.820574 -56.79117) (xy 336.767424 -56.795154)
			(xy 336.714274 -56.79117) (xy 336.662312 -56.77931) (xy 336.612698 -56.759838) (xy 336.56654 -56.733189)
			(xy 336.524869 -56.699958) (xy 336.488617 -56.660887) (xy 336.458593 -56.61685) (xy 336.435467 -56.568829)
			(xy 336.419757 -56.517899) (xy 336.411814 -56.465195) (xy 335.493878 -56.465195) (xy 335.485935 -56.517899)
			(xy 335.470225 -56.568829) (xy 335.447099 -56.61685) (xy 335.417075 -56.660887) (xy 335.380823 -56.699958)
			(xy 335.339152 -56.733189) (xy 335.292994 -56.759838) (xy 335.24338 -56.77931) (xy 335.191418 -56.79117)
			(xy 335.138268 -56.795154) (xy 335.085118 -56.79117) (xy 335.033156 -56.77931) (xy 334.983542 -56.759838)
			(xy 334.937384 -56.733189) (xy 334.895713 -56.699958) (xy 334.859461 -56.660887) (xy 334.829437 -56.61685)
			(xy 334.806311 -56.568829) (xy 334.790601 -56.517899) (xy 334.782658 -56.465195) (xy 333.864985 -56.465195)
			(xy 333.863003 -56.491648) (xy 333.851143 -56.543609) (xy 333.831671 -56.593222) (xy 333.805021 -56.639378)
			(xy 333.77179 -56.681046) (xy 333.73272 -56.717297) (xy 333.688683 -56.747319) (xy 333.640663 -56.770442)
			(xy 333.589733 -56.786149) (xy 333.537031 -56.79409) (xy 333.510382 -56.794654) (xy 333.479589 -56.793999)
			(xy 333.418924 -56.783392) (xy 333.389732 -56.773572) (xy 333.376475 -56.769241) (xy 333.348669 -56.767209)
			(xy 333.321351 -56.772774) (xy 333.296556 -56.785522) (xy 333.276134 -56.804501) (xy 333.261607 -56.828298)
			(xy 333.254059 -56.855136) (xy 333.253588 -56.869076) (xy 333.253588 -56.935095) (xy 335.597998 -56.935095)
			(xy 335.597998 -56.881797) (xy 335.605941 -56.829093) (xy 335.621651 -56.778163) (xy 335.644777 -56.730142)
			(xy 335.674801 -56.686105) (xy 335.711053 -56.647034) (xy 335.752724 -56.613803) (xy 335.798882 -56.587154)
			(xy 335.848496 -56.567682) (xy 335.900458 -56.555822) (xy 335.953608 -56.551839) (xy 336.006758 -56.555822)
			(xy 336.05872 -56.567682) (xy 336.108334 -56.587154) (xy 336.154492 -56.613803) (xy 336.196163 -56.647034)
			(xy 336.232415 -56.686105) (xy 336.262439 -56.730142) (xy 336.285565 -56.778163) (xy 336.301275 -56.829093)
			(xy 336.309218 -56.881797) (xy 336.309716 -56.908446) (xy 336.309218 -56.935095) (xy 337.225884 -56.935095)
			(xy 337.225884 -56.881797) (xy 337.233827 -56.829093) (xy 337.249537 -56.778163) (xy 337.272663 -56.730142)
			(xy 337.302687 -56.686105) (xy 337.338939 -56.647034) (xy 337.38061 -56.613803) (xy 337.426768 -56.587154)
			(xy 337.476382 -56.567682) (xy 337.528344 -56.555822) (xy 337.581494 -56.551839) (xy 337.634644 -56.555822)
			(xy 337.686606 -56.567682) (xy 337.73622 -56.587154) (xy 337.782378 -56.613803) (xy 337.824049 -56.647034)
			(xy 337.860301 -56.686105) (xy 337.890325 -56.730142) (xy 337.913451 -56.778163) (xy 337.929161 -56.829093)
			(xy 337.937104 -56.881797) (xy 337.937602 -56.908446) (xy 337.937104 -56.935095) (xy 337.929161 -56.987799)
			(xy 337.917989 -57.024016) (xy 347.457522 -57.024016) (xy 347.458043 -56.996131) (xy 347.466355 -56.940984)
			(xy 347.482793 -56.887692) (xy 347.506991 -56.837446) (xy 347.538407 -56.791367) (xy 347.57634 -56.750485)
			(xy 347.619942 -56.715713) (xy 347.66824 -56.687828) (xy 347.720155 -56.667453) (xy 347.774526 -56.655043)
			(xy 347.83014 -56.650876) (xy 347.885754 -56.655043) (xy 347.940125 -56.667453) (xy 347.99204 -56.687828)
			(xy 348.040338 -56.715713) (xy 348.08394 -56.750485) (xy 348.121873 -56.791367) (xy 348.153289 -56.837446)
			(xy 348.177487 -56.887692) (xy 348.193925 -56.940984) (xy 348.202237 -56.996131) (xy 348.202758 -57.024016)
			(xy 348.202343 -57.049164) (xy 348.195616 -57.099006) (xy 348.182246 -57.147491) (xy 348.162477 -57.193737)
			(xy 348.149926 -57.215532) (xy 348.143211 -57.227663) (xy 348.135862 -57.254384) (xy 348.135983 -57.282096)
			(xy 348.143564 -57.308752) (xy 348.158046 -57.332381) (xy 348.178357 -57.351235) (xy 348.202996 -57.36392)
			(xy 348.216474 -57.36717) (xy 348.241606 -57.372786) (xy 348.29015 -57.389964) (xy 348.335868 -57.413661)
			(xy 348.377887 -57.443428) (xy 348.415409 -57.478696) (xy 348.447717 -57.518793) (xy 348.46133 -57.540652)
			(xy 348.469329 -57.553206) (xy 348.491259 -57.57332) (xy 348.518061 -57.586249) (xy 348.547453 -57.590891)
			(xy 348.576935 -57.586853) (xy 348.603997 -57.574477) (xy 348.615508 -57.565036) (xy 348.636482 -57.547232)
			(xy 348.682594 -57.517224) (xy 348.732536 -57.494147) (xy 348.785274 -57.478478) (xy 348.839714 -57.470541)
			(xy 348.867222 -57.47004) (xy 348.894478 -57.470435) (xy 348.948434 -57.478196) (xy 349.000736 -57.493557)
			(xy 349.050319 -57.516206) (xy 349.096175 -57.54568) (xy 349.137368 -57.581381) (xy 349.173062 -57.622582)
			(xy 349.202528 -57.668442) (xy 349.225167 -57.71803) (xy 349.240519 -57.770335) (xy 349.24827 -57.824292)
			(xy 349.24873 -57.851548) (xy 349.248222 -57.870852) (xy 349.247971 -57.884011) (xy 349.253389 -57.909756)
			(xy 349.265198 -57.933266) (xy 349.282615 -57.952984) (xy 349.304488 -57.967605) (xy 349.329367 -57.97616)
			(xy 349.342456 -57.977532) (xy 349.370961 -57.980116) (xy 349.426803 -57.99266) (xy 349.480143 -58.013408)
			(xy 349.529784 -58.041894) (xy 349.574611 -58.077477) (xy 349.613618 -58.119359) (xy 349.645929 -58.166599)
			(xy 349.670818 -58.218138) (xy 349.687727 -58.272816) (xy 349.696275 -58.329407) (xy 349.696786 -58.358024)
			(xy 349.6963 -58.385275) (xy 349.688544 -58.439223) (xy 349.673189 -58.491518) (xy 349.650547 -58.541095)
			(xy 349.621081 -58.586945) (xy 349.58539 -58.628136) (xy 349.544199 -58.663827) (xy 349.504951 -58.68905)
			(xy 358.335586 -58.68905) (xy 358.335586 -58.63455) (xy 358.343342 -58.580605) (xy 358.358695 -58.528313)
			(xy 358.381335 -58.478738) (xy 358.410798 -58.43289) (xy 358.446487 -58.391701) (xy 358.487674 -58.35601)
			(xy 358.533521 -58.326544) (xy 358.583095 -58.303902) (xy 358.635386 -58.288546) (xy 358.68933 -58.280787)
			(xy 358.71658 -58.2803) (xy 358.743446 -58.280741) (xy 358.796643 -58.288303) (xy 358.848254 -58.303252)
			(xy 358.897257 -58.325293) (xy 358.942685 -58.353989) (xy 358.983638 -58.388774) (xy 359.019307 -58.42896)
			(xy 359.048986 -58.473751) (xy 359.07209 -58.522263) (xy 359.080562 -58.547762) (xy 359.085341 -58.561404)
			(xy 359.101436 -58.585404) (xy 359.1236 -58.603946) (xy 359.150065 -58.615551) (xy 359.178719 -58.619291)
			(xy 359.207276 -58.614869) (xy 359.233457 -58.602637) (xy 359.244646 -58.593482) (xy 359.26565 -58.575729)
			(xy 359.31177 -58.545773) (xy 359.36171 -58.522744) (xy 359.414438 -58.507119) (xy 359.468863 -58.499223)
			(xy 359.49636 -58.49874) (xy 359.523618 -58.499104) (xy 359.57758 -58.506858) (xy 359.62989 -58.522212)
			(xy 359.679481 -58.544855) (xy 359.725345 -58.574326) (xy 359.766548 -58.610024) (xy 359.80225 -58.651223)
			(xy 359.831726 -58.697084) (xy 359.854374 -58.746673) (xy 359.869734 -58.798981) (xy 359.877493 -58.852942)
			(xy 359.877493 -58.907458) (xy 359.869734 -58.961419) (xy 359.854374 -59.013727) (xy 359.831726 -59.063316)
			(xy 359.80225 -59.109177) (xy 359.79153 -59.121548) (xy 362.415836 -59.121548) (xy 362.416381 -59.092254)
			(xy 362.42535 -59.034357) (xy 362.443055 -58.978508) (xy 362.469081 -58.926018) (xy 362.502817 -58.878118)
			(xy 362.543471 -58.83593) (xy 362.566458 -58.817764) (xy 362.577138 -58.809091) (xy 362.593833 -58.78724)
			(xy 362.604073 -58.761718) (xy 362.607113 -58.734388) (xy 362.602729 -58.70724) (xy 362.591242 -58.682255)
			(xy 362.582714 -58.67146) (xy 362.565843 -58.650726) (xy 362.537448 -58.605438) (xy 362.51566 -58.556627)
			(xy 362.500908 -58.50525) (xy 362.493481 -58.452315) (xy 362.493052 -58.425588) (xy 362.493566 -58.398338)
			(xy 362.501324 -58.344394) (xy 362.516678 -58.292102) (xy 362.539318 -58.242527) (xy 362.568782 -58.196679)
			(xy 362.60447 -58.15549) (xy 362.645656 -58.119798) (xy 362.691503 -58.090331) (xy 362.741076 -58.067688)
			(xy 362.793366 -58.05233) (xy 362.84731 -58.044568) (xy 362.87456 -58.04408) (xy 362.903486 -58.044653)
			(xy 362.960675 -58.053382) (xy 363.01589 -58.070646) (xy 363.067866 -58.096049) (xy 363.11541 -58.12901)
			(xy 363.157432 -58.168771) (xy 363.192969 -58.214421) (xy 363.207554 -58.239406) (xy 363.214474 -58.25086)
			(xy 363.233113 -58.270043) (xy 363.2561 -58.283719) (xy 363.281851 -58.290949) (xy 363.308597 -58.291233)
			(xy 363.334497 -58.284554) (xy 363.357769 -58.27137) (xy 363.367574 -58.262266) (xy 363.389115 -58.241771)
			(xy 363.437399 -58.207075) (xy 363.490482 -58.180291) (xy 363.547078 -58.162069) (xy 363.605815 -58.15285)
			(xy 363.635544 -58.152284) (xy 363.662793 -58.152789) (xy 363.716734 -58.16055) (xy 363.769023 -58.175909)
			(xy 363.818593 -58.198552) (xy 363.864437 -58.228019) (xy 363.905622 -58.26371) (xy 363.941308 -58.304898)
			(xy 363.970769 -58.350745) (xy 363.993407 -58.400318) (xy 364.008759 -58.452609) (xy 364.016514 -58.506551)
			(xy 364.016514 -58.561049) (xy 364.016514 -58.561051) (xy 371.43257 -58.561051) (xy 371.43257 -58.506549)
			(xy 371.440326 -58.452602) (xy 371.45568 -58.400307) (xy 371.478321 -58.35073) (xy 371.507786 -58.30488)
			(xy 371.543476 -58.263689) (xy 371.584665 -58.227997) (xy 371.630514 -58.198529) (xy 371.68009 -58.175887)
			(xy 371.732384 -58.16053) (xy 371.786331 -58.152771) (xy 371.813582 -58.152284) (xy 371.842257 -58.152824)
			(xy 371.898964 -58.161394) (xy 371.953748 -58.178357) (xy 372.005374 -58.203332) (xy 372.05268 -58.235756)
			(xy 372.094597 -58.274897) (xy 372.112794 -58.297064) (xy 372.12172 -58.307774) (xy 372.144262 -58.324171)
			(xy 372.170403 -58.33385) (xy 372.198188 -58.336087) (xy 372.22554 -58.330715) (xy 372.250415 -58.318136)
			(xy 372.270953 -58.299289) (xy 372.278656 -58.287666) (xy 372.293672 -58.264422) (xy 372.329377 -58.222146)
			(xy 372.370813 -58.185469) (xy 372.417113 -58.155163) (xy 372.467304 -58.13186) (xy 372.520334 -58.116052)
			(xy 372.575092 -58.108068) (xy 372.60276 -58.10758) (xy 372.630014 -58.108065) (xy 372.683967 -58.115817)
			(xy 372.736268 -58.131169) (xy 372.785852 -58.153808) (xy 372.831709 -58.183274) (xy 372.872905 -58.218967)
			(xy 372.908602 -58.260159) (xy 372.938073 -58.306013) (xy 372.960717 -58.355594) (xy 372.976075 -58.407893)
			(xy 372.983833 -58.461846) (xy 372.983833 -58.516354) (xy 372.976075 -58.570307) (xy 372.972477 -58.58256)
			(xy 373.330214 -58.58256) (xy 373.334285 -58.526938) (xy 373.346411 -58.472501) (xy 373.366334 -58.42041)
			(xy 373.39363 -58.371775) (xy 373.427716 -58.327632) (xy 373.467865 -58.288923) (xy 373.513223 -58.256472)
			(xy 373.562823 -58.230971) (xy 373.615607 -58.212964) (xy 373.67045 -58.202834) (xy 373.726184 -58.200797)
			(xy 373.781621 -58.206897) (xy 373.835578 -58.221003) (xy 373.886907 -58.242815) (xy 373.934513 -58.271869)
			(xy 373.977381 -58.307544) (xy 374.014598 -58.349081) (xy 374.045371 -58.395594) (xy 374.069043 -58.446091)
			(xy 374.085111 -58.499498) (xy 374.093231 -58.554674) (xy 374.09374 -58.58256) (xy 374.093231 -58.610446)
			(xy 374.089784 -58.633868) (xy 382.754122 -58.633868) (xy 382.758193 -58.578246) (xy 382.770319 -58.523809)
			(xy 382.790242 -58.471718) (xy 382.817538 -58.423083) (xy 382.851624 -58.37894) (xy 382.891773 -58.340231)
			(xy 382.937131 -58.30778) (xy 382.986731 -58.282279) (xy 383.039515 -58.264272) (xy 383.094358 -58.254142)
			(xy 383.150092 -58.252105) (xy 383.205529 -58.258205) (xy 383.259486 -58.272311) (xy 383.310815 -58.294123)
			(xy 383.358421 -58.323177) (xy 383.401289 -58.358852) (xy 383.438506 -58.400389) (xy 383.469279 -58.446902)
			(xy 383.492951 -58.497399) (xy 383.509019 -58.550806) (xy 383.517139 -58.605982) (xy 383.517648 -58.633868)
			(xy 383.517139 -58.661754) (xy 383.511001 -58.703464) (xy 384.306062 -58.703464) (xy 384.310133 -58.647842)
			(xy 384.322259 -58.593405) (xy 384.342182 -58.541314) (xy 384.369478 -58.492679) (xy 384.403564 -58.448536)
			(xy 384.443713 -58.409827) (xy 384.489071 -58.377376) (xy 384.538671 -58.351875) (xy 384.591455 -58.333868)
			(xy 384.646298 -58.323738) (xy 384.702032 -58.321701) (xy 384.757469 -58.327801) (xy 384.811426 -58.341907)
			(xy 384.862755 -58.363719) (xy 384.910361 -58.392773) (xy 384.953229 -58.428448) (xy 384.990446 -58.469985)
			(xy 385.021219 -58.516498) (xy 385.044891 -58.566995) (xy 385.060959 -58.620402) (xy 385.069079 -58.675578)
			(xy 385.069588 -58.703464) (xy 385.069079 -58.73135) (xy 385.060959 -58.786526) (xy 385.044891 -58.839933)
			(xy 385.021219 -58.89043) (xy 384.990446 -58.936943) (xy 384.953229 -58.97848) (xy 384.910361 -59.014155)
			(xy 384.862755 -59.043209) (xy 384.811426 -59.065021) (xy 384.757469 -59.079127) (xy 384.702032 -59.085227)
			(xy 384.646298 -59.08319) (xy 384.591455 -59.07306) (xy 384.538671 -59.055053) (xy 384.489071 -59.029552)
			(xy 384.443713 -58.997101) (xy 384.403564 -58.958392) (xy 384.369478 -58.914249) (xy 384.342182 -58.865614)
			(xy 384.322259 -58.813523) (xy 384.310133 -58.759086) (xy 384.306062 -58.703464) (xy 383.511001 -58.703464)
			(xy 383.509019 -58.71693) (xy 383.492951 -58.770337) (xy 383.469279 -58.820834) (xy 383.438506 -58.867347)
			(xy 383.401289 -58.908884) (xy 383.358421 -58.944559) (xy 383.310815 -58.973613) (xy 383.259486 -58.995425)
			(xy 383.205529 -59.009531) (xy 383.150092 -59.015631) (xy 383.094358 -59.013594) (xy 383.039515 -59.003464)
			(xy 382.986731 -58.985457) (xy 382.937131 -58.959956) (xy 382.891773 -58.927505) (xy 382.851624 -58.888796)
			(xy 382.817538 -58.844653) (xy 382.790242 -58.796018) (xy 382.770319 -58.743927) (xy 382.758193 -58.68949)
			(xy 382.754122 -58.633868) (xy 374.089784 -58.633868) (xy 374.085111 -58.665622) (xy 374.069043 -58.719029)
			(xy 374.045371 -58.769526) (xy 374.014598 -58.816039) (xy 373.977381 -58.857576) (xy 373.934513 -58.893251)
			(xy 373.886907 -58.922305) (xy 373.835578 -58.944117) (xy 373.781621 -58.958223) (xy 373.726184 -58.964323)
			(xy 373.67045 -58.962286) (xy 373.615607 -58.952156) (xy 373.562823 -58.934149) (xy 373.513223 -58.908648)
			(xy 373.467865 -58.876197) (xy 373.427716 -58.837488) (xy 373.39363 -58.793345) (xy 373.366334 -58.74471)
			(xy 373.346411 -58.692619) (xy 373.334285 -58.638182) (xy 373.330214 -58.58256) (xy 372.972477 -58.58256)
			(xy 372.960717 -58.622606) (xy 372.938073 -58.672187) (xy 372.908602 -58.718041) (xy 372.872905 -58.759233)
			(xy 372.831709 -58.794926) (xy 372.785852 -58.824392) (xy 372.736268 -58.847031) (xy 372.683967 -58.862383)
			(xy 372.630014 -58.870135) (xy 372.60276 -58.870596) (xy 372.574083 -58.870105) (xy 372.517374 -58.861526)
			(xy 372.462588 -58.844553) (xy 372.410962 -58.819569) (xy 372.363658 -58.787137) (xy 372.321744 -58.747987)
			(xy 372.303548 -58.725816) (xy 372.294571 -58.715152) (xy 372.27204 -58.698759) (xy 372.245912 -58.689079)
			(xy 372.218139 -58.686837) (xy 372.190796 -58.692199) (xy 372.165927 -58.704766) (xy 372.145391 -58.723598)
			(xy 372.137686 -58.735214) (xy 372.122635 -58.758434) (xy 372.086937 -58.800712) (xy 372.045507 -58.83739)
			(xy 371.999213 -58.8677) (xy 371.949028 -58.891006) (xy 371.896002 -58.90682) (xy 371.841249 -58.914809)
			(xy 371.813582 -58.9153) (xy 371.786331 -58.914829) (xy 371.732384 -58.90707) (xy 371.68009 -58.891713)
			(xy 371.630514 -58.869071) (xy 371.584665 -58.839603) (xy 371.543476 -58.803911) (xy 371.507786 -58.76272)
			(xy 371.478321 -58.71687) (xy 371.45568 -58.667293) (xy 371.440326 -58.614998) (xy 371.43257 -58.561051)
			(xy 364.016514 -58.561051) (xy 364.008759 -58.614991) (xy 363.993407 -58.667282) (xy 363.970769 -58.716855)
			(xy 363.941308 -58.762702) (xy 363.905622 -58.80389) (xy 363.864437 -58.839581) (xy 363.818593 -58.869048)
			(xy 363.769023 -58.891691) (xy 363.716734 -58.90705) (xy 363.662793 -58.914811) (xy 363.635544 -58.9153)
			(xy 363.606618 -58.914734) (xy 363.549428 -58.906005) (xy 363.494212 -58.888741) (xy 363.442236 -58.863336)
			(xy 363.394692 -58.830375) (xy 363.35267 -58.790612) (xy 363.317134 -58.74496) (xy 363.30255 -58.719974)
			(xy 363.295754 -58.70844) (xy 363.277089 -58.689254) (xy 363.254077 -58.675581) (xy 363.228301 -58.668361)
			(xy 363.201535 -58.668092) (xy 363.17562 -58.674791) (xy 363.152338 -58.687998) (xy 363.14253 -58.697114)
			(xy 363.133718 -58.705692) (xy 363.115161 -58.721833) (xy 363.105446 -58.729372) (xy 363.094734 -58.738009)
			(xy 363.078039 -58.759869) (xy 363.067801 -58.785399) (xy 363.064768 -58.812738) (xy 363.06916 -58.839892)
			(xy 363.080656 -58.864881) (xy 363.08919 -58.875676) (xy 363.106078 -58.896397) (xy 363.134471 -58.941688)
			(xy 363.156255 -58.990503) (xy 363.171003 -59.041883) (xy 363.178426 -59.09482) (xy 363.178852 -59.121548)
			(xy 363.178366 -59.148799) (xy 363.17061 -59.202747) (xy 363.155255 -59.255042) (xy 363.132613 -59.304619)
			(xy 363.103147 -59.350469) (xy 363.067456 -59.39166) (xy 363.026265 -59.427351) (xy 362.980415 -59.456817)
			(xy 362.930838 -59.479459) (xy 362.878543 -59.494814) (xy 362.824595 -59.50257) (xy 362.770093 -59.50257)
			(xy 362.716145 -59.494814) (xy 362.66385 -59.479459) (xy 362.614273 -59.456817) (xy 362.568423 -59.427351)
			(xy 362.527232 -59.39166) (xy 362.491541 -59.350469) (xy 362.462075 -59.304619) (xy 362.439433 -59.255042)
			(xy 362.424078 -59.202747) (xy 362.416322 -59.148799) (xy 362.415836 -59.121548) (xy 359.79153 -59.121548)
			(xy 359.766548 -59.150376) (xy 359.725345 -59.186074) (xy 359.679481 -59.215545) (xy 359.62989 -59.238188)
			(xy 359.57758 -59.253542) (xy 359.523618 -59.261296) (xy 359.49636 -59.261756) (xy 359.469497 -59.261241)
			(xy 359.416305 -59.253685) (xy 359.364698 -59.238744) (xy 359.315697 -59.216712) (xy 359.27027 -59.188025)
			(xy 359.229317 -59.153249) (xy 359.193646 -59.113074) (xy 359.163962 -59.068292) (xy 359.140854 -59.019789)
			(xy 359.132378 -58.994294) (xy 359.127523 -58.980681) (xy 359.111446 -58.956679) (xy 359.089298 -58.938133)
			(xy 359.062845 -58.926524) (xy 359.034201 -58.922778) (xy 359.005652 -58.927195) (xy 358.979479 -58.939421)
			(xy 358.968294 -58.948574) (xy 358.947307 -58.966348) (xy 358.901183 -58.996303) (xy 358.851239 -59.019328)
			(xy 358.798506 -59.034948) (xy 358.744078 -59.042838) (xy 358.71658 -59.043316) (xy 358.68933 -59.042813)
			(xy 358.635386 -59.035054) (xy 358.583095 -59.019698) (xy 358.533521 -58.997056) (xy 358.487674 -58.96759)
			(xy 358.446487 -58.931899) (xy 358.410798 -58.89071) (xy 358.381335 -58.844862) (xy 358.358695 -58.795287)
			(xy 358.343342 -58.742995) (xy 358.335586 -58.68905) (xy 349.504951 -58.68905) (xy 349.498349 -58.693293)
			(xy 349.448772 -58.715935) (xy 349.396477 -58.73129) (xy 349.342529 -58.739046) (xy 349.288027 -58.739046)
			(xy 349.234079 -58.73129) (xy 349.181784 -58.715935) (xy 349.132207 -58.693293) (xy 349.086357 -58.663827)
			(xy 349.045166 -58.628136) (xy 349.009475 -58.586945) (xy 348.980009 -58.541095) (xy 348.957367 -58.491518)
			(xy 348.942012 -58.439223) (xy 348.934256 -58.385275) (xy 348.93377 -58.358024) (xy 348.934278 -58.33872)
			(xy 348.934556 -58.325561) (xy 348.92913 -58.299815) (xy 348.917316 -58.276304) (xy 348.899894 -58.256586)
			(xy 348.878017 -58.241966) (xy 348.853135 -58.233411) (xy 348.840044 -58.23204) (xy 348.813555 -58.22967)
			(xy 348.76155 -58.218545) (xy 348.711597 -58.200299) (xy 348.664665 -58.175286) (xy 348.621665 -58.143992)
			(xy 348.583433 -58.107026) (xy 348.550711 -58.065103) (xy 348.537022 -58.042302) (xy 348.529164 -58.029658)
			(xy 348.507481 -58.009275) (xy 348.480845 -57.996005) (xy 348.451514 -57.990976) (xy 348.421978 -57.994614)
			(xy 348.394744 -58.00661) (xy 348.383098 -58.015886) (xy 348.362766 -58.032561) (xy 348.318338 -58.060687)
			(xy 348.270396 -58.082287) (xy 348.219894 -58.096932) (xy 348.167835 -58.104331) (xy 348.141544 -58.104786)
			(xy 348.114926 -58.104325) (xy 348.062231 -58.096754) (xy 348.01115 -58.08176) (xy 347.962723 -58.059647)
			(xy 347.917936 -58.030868) (xy 347.877702 -57.996006) (xy 347.84284 -57.955773) (xy 347.814058 -57.910988)
			(xy 347.791945 -57.862562) (xy 347.776949 -57.811481) (xy 347.769376 -57.758786) (xy 347.768926 -57.732168)
			(xy 347.769322 -57.70702) (xy 347.776053 -57.657176) (xy 347.789428 -57.608691) (xy 347.809204 -57.562446)
			(xy 347.821758 -57.540652) (xy 347.828503 -57.528536) (xy 347.835851 -57.50181) (xy 347.835728 -57.474092)
			(xy 347.828142 -57.447432) (xy 347.813655 -57.423801) (xy 347.793337 -57.404946) (xy 347.768691 -57.392262)
			(xy 347.75521 -57.389014) (xy 347.727564 -57.382761) (xy 347.67441 -57.363092) (xy 347.624848 -57.3356)
			(xy 347.580021 -57.300918) (xy 347.540964 -57.259847) (xy 347.508579 -57.213334) (xy 347.483612 -57.162453)
			(xy 347.466639 -57.108377) (xy 347.458053 -57.052354) (xy 347.457522 -57.024016) (xy 337.917989 -57.024016)
			(xy 337.913451 -57.038729) (xy 337.890325 -57.08675) (xy 337.860301 -57.130787) (xy 337.824049 -57.169858)
			(xy 337.782378 -57.203089) (xy 337.73622 -57.229738) (xy 337.686606 -57.24921) (xy 337.634644 -57.26107)
			(xy 337.581494 -57.265054) (xy 337.528344 -57.26107) (xy 337.476382 -57.24921) (xy 337.426768 -57.229738)
			(xy 337.38061 -57.203089) (xy 337.338939 -57.169858) (xy 337.302687 -57.130787) (xy 337.272663 -57.08675)
			(xy 337.249537 -57.038729) (xy 337.233827 -56.987799) (xy 337.225884 -56.935095) (xy 336.309218 -56.935095)
			(xy 336.301275 -56.987799) (xy 336.285565 -57.038729) (xy 336.262439 -57.08675) (xy 336.232415 -57.130787)
			(xy 336.196163 -57.169858) (xy 336.154492 -57.203089) (xy 336.108334 -57.229738) (xy 336.05872 -57.24921)
			(xy 336.006758 -57.26107) (xy 335.953608 -57.265054) (xy 335.900458 -57.26107) (xy 335.848496 -57.24921)
			(xy 335.798882 -57.229738) (xy 335.752724 -57.203089) (xy 335.711053 -57.169858) (xy 335.674801 -57.130787)
			(xy 335.644777 -57.08675) (xy 335.621651 -57.038729) (xy 335.605941 -56.987799) (xy 335.597998 -56.935095)
			(xy 333.253588 -56.935095) (xy 333.253588 -57.483989) (xy 338.04478 -57.483989) (xy 338.04478 -57.430691)
			(xy 338.052723 -57.377987) (xy 338.068433 -57.327057) (xy 338.091559 -57.279036) (xy 338.121583 -57.234999)
			(xy 338.157835 -57.195928) (xy 338.199506 -57.162697) (xy 338.245664 -57.136048) (xy 338.295278 -57.116576)
			(xy 338.34724 -57.104716) (xy 338.40039 -57.100733) (xy 338.45354 -57.104716) (xy 338.505502 -57.116576)
			(xy 338.555116 -57.136048) (xy 338.601274 -57.162697) (xy 338.642945 -57.195928) (xy 338.679197 -57.234999)
			(xy 338.709221 -57.279036) (xy 338.732347 -57.327057) (xy 338.748057 -57.377987) (xy 338.756 -57.430691)
			(xy 338.756498 -57.45734) (xy 338.756 -57.483989) (xy 338.753933 -57.497705) (xy 345.131634 -57.497705)
			(xy 345.131634 -57.444407) (xy 345.139577 -57.391703) (xy 345.155287 -57.340773) (xy 345.178413 -57.292752)
			(xy 345.208437 -57.248715) (xy 345.244689 -57.209644) (xy 345.28636 -57.176413) (xy 345.332518 -57.149764)
			(xy 345.382132 -57.130292) (xy 345.434094 -57.118432) (xy 345.487244 -57.114449) (xy 345.540394 -57.118432)
			(xy 345.592356 -57.130292) (xy 345.64197 -57.149764) (xy 345.688128 -57.176413) (xy 345.729799 -57.209644)
			(xy 345.766051 -57.248715) (xy 345.796075 -57.292752) (xy 345.819201 -57.340773) (xy 345.834911 -57.391703)
			(xy 345.842854 -57.444407) (xy 345.843352 -57.471056) (xy 345.842854 -57.497705) (xy 345.834911 -57.550409)
			(xy 345.819201 -57.601339) (xy 345.796075 -57.64936) (xy 345.766051 -57.693397) (xy 345.729799 -57.732468)
			(xy 345.688128 -57.765699) (xy 345.64197 -57.792348) (xy 345.592356 -57.81182) (xy 345.540394 -57.82368)
			(xy 345.487244 -57.827664) (xy 345.434094 -57.82368) (xy 345.382132 -57.81182) (xy 345.332518 -57.792348)
			(xy 345.28636 -57.765699) (xy 345.244689 -57.732468) (xy 345.208437 -57.693397) (xy 345.178413 -57.64936)
			(xy 345.155287 -57.601339) (xy 345.139577 -57.550409) (xy 345.131634 -57.497705) (xy 338.753933 -57.497705)
			(xy 338.748057 -57.536693) (xy 338.732347 -57.587623) (xy 338.709221 -57.635644) (xy 338.679197 -57.679681)
			(xy 338.642945 -57.718752) (xy 338.601274 -57.751983) (xy 338.555116 -57.778632) (xy 338.505502 -57.798104)
			(xy 338.45354 -57.809964) (xy 338.40039 -57.813948) (xy 338.34724 -57.809964) (xy 338.295278 -57.798104)
			(xy 338.245664 -57.778632) (xy 338.199506 -57.751983) (xy 338.157835 -57.718752) (xy 338.121583 -57.679681)
			(xy 338.091559 -57.635644) (xy 338.068433 -57.587623) (xy 338.052723 -57.536693) (xy 338.04478 -57.483989)
			(xy 333.253588 -57.483989) (xy 333.253588 -59.007502) (xy 334.401139 -60.155053) (xy 335.428834 -60.155053)
			(xy 335.428834 -60.101755) (xy 335.436777 -60.049051) (xy 335.452487 -59.998121) (xy 335.475613 -59.9501)
			(xy 335.505637 -59.906063) (xy 335.541889 -59.866992) (xy 335.58356 -59.833761) (xy 335.629718 -59.807112)
			(xy 335.679332 -59.78764) (xy 335.731294 -59.77578) (xy 335.784444 -59.771797) (xy 335.837594 -59.77578)
			(xy 335.889556 -59.78764) (xy 335.93917 -59.807112) (xy 335.985328 -59.833761) (xy 336.026999 -59.866992)
			(xy 336.063251 -59.906063) (xy 336.069879 -59.915785) (xy 336.544148 -59.915785) (xy 336.544148 -59.862487)
			(xy 336.552091 -59.809783) (xy 336.567801 -59.758853) (xy 336.590927 -59.710832) (xy 336.620951 -59.666795)
			(xy 336.657203 -59.627724) (xy 336.698874 -59.594493) (xy 336.745032 -59.567844) (xy 336.794646 -59.548372)
			(xy 336.846608 -59.536512) (xy 336.899758 -59.532529) (xy 336.952908 -59.536512) (xy 337.00487 -59.548372)
			(xy 337.054484 -59.567844) (xy 337.100642 -59.594493) (xy 337.142313 -59.627724) (xy 337.178565 -59.666795)
			(xy 337.208589 -59.710832) (xy 337.231715 -59.758853) (xy 337.237742 -59.778392) (xy 338.414878 -59.778392)
			(xy 338.418854 -59.724066) (xy 338.430697 -59.670897) (xy 338.450156 -59.62002) (xy 338.476816 -59.572518)
			(xy 338.510107 -59.529404) (xy 338.549321 -59.491597) (xy 338.593623 -59.459902) (xy 338.642066 -59.434996)
			(xy 338.69362 -59.417408) (xy 338.747186 -59.407514) (xy 338.801621 -59.405524) (xy 338.855766 -59.411482)
			(xy 338.908466 -59.42526) (xy 338.958599 -59.446564) (xy 339.005095 -59.47494) (xy 339.046965 -59.509784)
			(xy 339.083314 -59.550353) (xy 339.11337 -59.595782) (xy 339.136491 -59.645103) (xy 339.152184 -59.697265)
			(xy 339.160115 -59.751156) (xy 339.160612 -59.778392) (xy 339.160115 -59.805628) (xy 339.152184 -59.859519)
			(xy 339.136491 -59.911681) (xy 339.11337 -59.961002) (xy 339.083314 -60.006431) (xy 339.046965 -60.047)
			(xy 339.033997 -60.057792) (xy 345.349078 -60.057792) (xy 345.353054 -60.003466) (xy 345.364897 -59.950297)
			(xy 345.384356 -59.89942) (xy 345.411016 -59.851918) (xy 345.444307 -59.808804) (xy 345.483521 -59.770997)
			(xy 345.527823 -59.739302) (xy 345.576266 -59.714396) (xy 345.62782 -59.696808) (xy 345.681386 -59.686914)
			(xy 345.735821 -59.684924) (xy 345.789966 -59.690882) (xy 345.842666 -59.70466) (xy 345.892799 -59.725964)
			(xy 345.939295 -59.75434) (xy 345.981165 -59.789184) (xy 346.017514 -59.829753) (xy 346.04757 -59.875182)
			(xy 346.070691 -59.924503) (xy 346.086384 -59.976665) (xy 346.094315 -60.030556) (xy 346.094443 -60.037554)
			(xy 349.026149 -60.037554) (xy 349.026149 -59.983046) (xy 349.033907 -59.929091) (xy 349.049265 -59.876791)
			(xy 349.07191 -59.827208) (xy 349.10138 -59.781353) (xy 349.137077 -59.740159) (xy 349.178274 -59.704465)
			(xy 349.224131 -59.674997) (xy 349.273715 -59.652356) (xy 349.326017 -59.637002) (xy 349.379972 -59.629248)
			(xy 349.407226 -59.628786) (xy 349.436632 -59.629333) (xy 349.494748 -59.638349) (xy 349.550792 -59.65618)
			(xy 349.603435 -59.682402) (xy 349.651428 -59.716394) (xy 349.67291 -59.736482) (xy 349.683484 -59.746129)
			(xy 349.708741 -59.75958) (xy 349.736735 -59.765505) (xy 349.765275 -59.76344) (xy 349.792125 -59.753547)
			(xy 349.815182 -59.736601) (xy 349.824294 -59.72556) (xy 349.842495 -59.702814) (xy 349.884582 -59.662542)
			(xy 349.932305 -59.629139) (xy 349.984552 -59.603382) (xy 350.040109 -59.585871) (xy 350.097682 -59.577013)
			(xy 350.126808 -59.576462) (xy 350.152507 -59.576907) (xy 350.20344 -59.583803) (xy 350.252988 -59.59747)
			(xy 350.300254 -59.617661) (xy 350.344385 -59.64401) (xy 350.384581 -59.676041) (xy 350.402652 -59.694318)
			(xy 350.412546 -59.704127) (xy 350.436494 -59.718351) (xy 350.463397 -59.725564) (xy 350.491248 -59.725226)
			(xy 350.517969 -59.717365) (xy 350.541565 -59.702565) (xy 350.551242 -59.69254) (xy 350.569422 -59.673242)
			(xy 350.610164 -59.639317) (xy 350.655209 -59.611359) (xy 350.703691 -59.589904) (xy 350.754675 -59.575367)
			(xy 350.807182 -59.568027) (xy 350.83369 -59.567572) (xy 350.861632 -59.568038) (xy 350.916917 -59.576203)
			(xy 350.97042 -59.592345) (xy 351.020996 -59.616118) (xy 351.067563 -59.647015) (xy 351.109125 -59.684374)
			(xy 351.144793 -59.727396) (xy 351.173805 -59.77516) (xy 351.195538 -59.826646) (xy 351.203006 -59.853576)
			(xy 351.207045 -59.867183) (xy 351.221412 -59.891645) (xy 351.241944 -59.911222) (xy 351.267063 -59.924408)
			(xy 351.294837 -59.93019) (xy 351.323131 -59.928123) (xy 351.33661 -59.92368) (xy 351.368449 -59.912672)
			(xy 351.434755 -59.900793) (xy 351.468436 -59.900058) (xy 351.495533 -59.900511) (xy 351.549183 -59.908172)
			(xy 351.601208 -59.923349) (xy 351.650562 -59.945737) (xy 351.69625 -59.974884) (xy 351.737353 -60.010204)
			(xy 351.773044 -60.050986) (xy 351.802603 -60.096409) (xy 351.825436 -60.145558) (xy 351.841083 -60.197444)
			(xy 351.845626 -60.224162) (xy 351.848334 -60.238317) (xy 351.860501 -60.264426) (xy 351.879465 -60.286107)
			(xy 351.903723 -60.30164) (xy 351.931349 -60.309794) (xy 351.960154 -60.309922) (xy 351.987851 -60.302013)
			(xy 352.000312 -60.294774) (xy 352.023279 -60.280798) (xy 352.072293 -60.258708) (xy 352.12392 -60.243707)
			(xy 352.17714 -60.23609) (xy 352.20402 -60.235592) (xy 352.231285 -60.236037) (xy 352.285259 -60.243803)
			(xy 352.337577 -60.259175) (xy 352.387175 -60.281838) (xy 352.43304 -60.311332) (xy 352.474239 -60.347055)
			(xy 352.509933 -60.38828) (xy 352.539393 -60.434166) (xy 352.562021 -60.48378) (xy 352.571837 -60.517278)
			(xy 355.27107 -60.517278) (xy 355.271556 -60.490027) (xy 355.279312 -60.436079) (xy 355.294667 -60.383784)
			(xy 355.317309 -60.334207) (xy 355.346775 -60.288357) (xy 355.382466 -60.247166) (xy 355.423657 -60.211475)
			(xy 355.469507 -60.182009) (xy 355.519084 -60.159367) (xy 355.571379 -60.144012) (xy 355.625327 -60.136256)
			(xy 355.679829 -60.136256) (xy 355.733777 -60.144012) (xy 355.786072 -60.159367) (xy 355.835649 -60.182009)
			(xy 355.881499 -60.211475) (xy 355.92269 -60.247166) (xy 355.958381 -60.288357) (xy 355.987847 -60.334207)
			(xy 356.010489 -60.383784) (xy 356.025844 -60.436079) (xy 356.0336 -60.490027) (xy 356.034086 -60.517278)
			(xy 356.03367 -60.543785) (xy 356.026377 -60.596293) (xy 356.011873 -60.647282) (xy 356.001574 -60.67171)
			(xy 355.996152 -60.685077) (xy 355.992379 -60.713666) (xy 355.996748 -60.742171) (xy 356.008911 -60.768317)
			(xy 356.027898 -60.790022) (xy 356.052196 -60.805553) (xy 356.079866 -60.813673) (xy 356.094284 -60.814204)
			(xy 356.526592 -60.814204) (xy 356.540535 -60.813798) (xy 356.567375 -60.806234) (xy 356.591171 -60.791694)
			(xy 356.610148 -60.771261) (xy 356.622894 -60.746458) (xy 356.628458 -60.719133) (xy 356.626426 -60.691321)
			(xy 356.622096 -60.67806) (xy 356.611447 -60.646607) (xy 356.599953 -60.581211) (xy 356.599236 -60.548012)
			(xy 356.599722 -60.520761) (xy 356.607478 -60.466813) (xy 356.622833 -60.414518) (xy 356.645475 -60.364941)
			(xy 356.674941 -60.319091) (xy 356.710632 -60.2779) (xy 356.751823 -60.242209) (xy 356.797673 -60.212743)
			(xy 356.84725 -60.190101) (xy 356.899545 -60.174746) (xy 356.953493 -60.16699) (xy 357.007995 -60.16699)
			(xy 357.061943 -60.174746) (xy 357.114238 -60.190101) (xy 357.163815 -60.212743) (xy 357.209665 -60.242209)
			(xy 357.250856 -60.2779) (xy 357.286547 -60.319091) (xy 357.316013 -60.364941) (xy 357.338655 -60.414518)
			(xy 357.35401 -60.466813) (xy 357.361766 -60.520761) (xy 357.362252 -60.548012) (xy 357.361759 -60.576693)
			(xy 357.353156 -60.633407) (xy 357.336161 -60.688195) (xy 357.311157 -60.739821) (xy 357.278706 -60.787123)
			(xy 357.239541 -60.829035) (xy 357.225531 -60.840112) (xy 358.73512 -60.840112) (xy 358.739191 -60.78449)
			(xy 358.751317 -60.730053) (xy 358.77124 -60.677962) (xy 358.798536 -60.629327) (xy 358.832622 -60.585184)
			(xy 358.872771 -60.546475) (xy 358.918129 -60.514024) (xy 358.967729 -60.488523) (xy 359.020513 -60.470516)
			(xy 359.075356 -60.460386) (xy 359.13109 -60.458349) (xy 359.186527 -60.464449) (xy 359.240484 -60.478555)
			(xy 359.252709 -60.48375) (xy 363.328964 -60.48375) (xy 363.333035 -60.428128) (xy 363.345161 -60.373691)
			(xy 363.365084 -60.3216) (xy 363.39238 -60.272965) (xy 363.426466 -60.228822) (xy 363.466615 -60.190113)
			(xy 363.511973 -60.157662) (xy 363.561573 -60.132161) (xy 363.614357 -60.114154) (xy 363.6692 -60.104024)
			(xy 363.724934 -60.101987) (xy 363.780371 -60.108087) (xy 363.834328 -60.122193) (xy 363.885657 -60.144005)
			(xy 363.933263 -60.173059) (xy 363.976131 -60.208734) (xy 364.013348 -60.250271) (xy 364.044121 -60.296784)
			(xy 364.067793 -60.347281) (xy 364.083861 -60.400688) (xy 364.091981 -60.455864) (xy 364.09249 -60.48375)
			(xy 364.091981 -60.511636) (xy 364.090858 -60.519265) (xy 366.539765 -60.519265) (xy 366.547519 -60.465316)
			(xy 366.562872 -60.413019) (xy 366.585511 -60.363439) (xy 366.614976 -60.317586) (xy 366.650667 -60.276393)
			(xy 366.691856 -60.240699) (xy 366.737706 -60.211229) (xy 366.787284 -60.188585) (xy 366.839579 -60.173227)
			(xy 366.893528 -60.165467) (xy 366.92078 -60.16498) (xy 366.939898 -60.165203) (xy 366.977944 -60.169022)
			(xy 366.996726 -60.1726) (xy 367.010462 -60.174979) (xy 367.038256 -60.172923) (xy 367.064458 -60.163427)
			(xy 367.087116 -60.147198) (xy 367.104539 -60.125446) (xy 367.115431 -60.099793) (xy 367.118978 -60.072149)
			(xy 367.117376 -60.0583) (xy 367.115479 -60.044536) (xy 367.113447 -60.016822) (xy 367.113312 -60.002928)
			(xy 367.113781 -59.975675) (xy 367.121535 -59.921723) (xy 367.136889 -59.869424) (xy 367.159529 -59.819843)
			(xy 367.188996 -59.773989) (xy 367.224689 -59.732795) (xy 367.265882 -59.697101) (xy 367.311736 -59.667633)
			(xy 367.361317 -59.644991) (xy 367.413615 -59.629637) (xy 367.467567 -59.621882) (xy 367.49482 -59.62142)
			(xy 367.519878 -59.621791) (xy 367.56957 -59.628286) (xy 367.59388 -59.634374) (xy 367.607409 -59.637459)
			(xy 367.635141 -59.637164) (xy 367.661767 -59.629407) (xy 367.685318 -59.614763) (xy 367.704052 -59.594314)
			(xy 367.716583 -59.569573) (xy 367.721983 -59.542372) (xy 367.719855 -59.51472) (xy 367.715546 -59.501532)
			(xy 367.704727 -59.469854) (xy 367.693106 -59.403936) (xy 367.692432 -59.370468) (xy 367.692912 -59.34322)
			(xy 367.700672 -59.28928) (xy 367.716029 -59.236993) (xy 367.738671 -59.187423) (xy 367.768136 -59.14158)
			(xy 367.803826 -59.100397) (xy 367.845012 -59.064712) (xy 367.890858 -59.035252) (xy 367.94043 -59.012615)
			(xy 367.992719 -58.997264) (xy 368.04666 -58.98951) (xy 368.101156 -58.989511) (xy 368.155097 -58.997267)
			(xy 368.207385 -59.012621) (xy 368.256956 -59.035259) (xy 368.3028 -59.064722) (xy 368.343986 -59.100409)
			(xy 368.379673 -59.141593) (xy 368.409137 -59.187437) (xy 368.431776 -59.237008) (xy 368.447131 -59.289295)
			(xy 368.454889 -59.343236) (xy 368.454891 -59.397732) (xy 368.447138 -59.451673) (xy 368.431788 -59.503962)
			(xy 368.409152 -59.553535) (xy 368.379693 -59.599381) (xy 368.344008 -59.640569) (xy 368.302826 -59.676259)
			(xy 368.256984 -59.705725) (xy 368.207415 -59.728368) (xy 368.155128 -59.743726) (xy 368.101188 -59.751487)
			(xy 368.07394 -59.751976) (xy 368.048882 -59.751613) (xy 367.999189 -59.745113) (xy 367.97488 -59.739022)
			(xy 367.961359 -59.735901) (xy 367.933625 -59.736205) (xy 367.906999 -59.743969) (xy 367.883448 -59.758619)
			(xy 367.864714 -59.779072) (xy 367.852183 -59.803815) (xy 367.846781 -59.83102) (xy 367.848907 -59.858674)
			(xy 367.853214 -59.871864) (xy 367.864031 -59.903542) (xy 367.875654 -59.96946) (xy 367.876328 -60.002928)
			(xy 367.875848 -60.030179) (xy 367.868088 -60.084126) (xy 367.852731 -60.13642) (xy 367.830088 -60.185996)
			(xy 367.800621 -60.231845) (xy 367.764929 -60.273034) (xy 367.723738 -60.308725) (xy 367.677889 -60.338192)
			(xy 367.628312 -60.360834) (xy 367.576018 -60.37619) (xy 367.522071 -60.383949) (xy 367.49482 -60.384436)
			(xy 367.475702 -60.384213) (xy 367.437656 -60.380394) (xy 367.418874 -60.376816) (xy 367.40514 -60.374419)
			(xy 367.377343 -60.376475) (xy 367.351137 -60.385973) (xy 367.328478 -60.402204) (xy 367.311054 -60.42396)
			(xy 367.300164 -60.449618) (xy 367.29662 -60.477265) (xy 367.298224 -60.491116) (xy 367.300122 -60.50488)
			(xy 367.302153 -60.532594) (xy 367.302288 -60.546488) (xy 367.301835 -60.57374) (xy 367.29408 -60.627689)
			(xy 367.278726 -60.679986) (xy 367.256086 -60.729565) (xy 367.226621 -60.775418) (xy 367.19093 -60.816611)
			(xy 367.149739 -60.852305) (xy 367.103889 -60.881773) (xy 367.054311 -60.904417) (xy 367.002016 -60.919774)
			(xy 366.948067 -60.927533) (xy 366.893563 -60.927535) (xy 366.839613 -60.919781) (xy 366.787316 -60.904427)
			(xy 366.737737 -60.881787) (xy 366.691884 -60.852322) (xy 366.650691 -60.816631) (xy 366.614997 -60.775442)
			(xy 366.585528 -60.729591) (xy 366.562884 -60.680014) (xy 366.547526 -60.627718) (xy 366.539767 -60.573769)
			(xy 366.539765 -60.519265) (xy 364.090858 -60.519265) (xy 364.083861 -60.566812) (xy 364.067793 -60.620219)
			(xy 364.044121 -60.670716) (xy 364.013348 -60.717229) (xy 363.976131 -60.758766) (xy 363.933263 -60.794441)
			(xy 363.885657 -60.823495) (xy 363.834328 -60.845307) (xy 363.780371 -60.859413) (xy 363.724934 -60.865513)
			(xy 363.6692 -60.863476) (xy 363.614357 -60.853346) (xy 363.561573 -60.835339) (xy 363.511973 -60.809838)
			(xy 363.466615 -60.777387) (xy 363.426466 -60.738678) (xy 363.39238 -60.694535) (xy 363.365084 -60.6459)
			(xy 363.345161 -60.593809) (xy 363.333035 -60.539372) (xy 363.328964 -60.48375) (xy 359.252709 -60.48375)
			(xy 359.291813 -60.500367) (xy 359.339419 -60.529421) (xy 359.382287 -60.565096) (xy 359.419504 -60.606633)
			(xy 359.450277 -60.653146) (xy 359.473949 -60.703643) (xy 359.490017 -60.75705) (xy 359.498137 -60.812226)
			(xy 359.498646 -60.840112) (xy 359.498137 -60.867998) (xy 359.490017 -60.923174) (xy 359.473949 -60.976581)
			(xy 359.450277 -61.027078) (xy 359.419504 -61.073591) (xy 359.382287 -61.115128) (xy 359.339419 -61.150803)
			(xy 359.291813 -61.179857) (xy 359.240484 -61.201669) (xy 359.186527 -61.215775) (xy 359.13109 -61.221875)
			(xy 359.075356 -61.219838) (xy 359.020513 -61.209708) (xy 358.967729 -61.191701) (xy 358.918129 -61.1662)
			(xy 358.872771 -61.133749) (xy 358.832622 -61.09504) (xy 358.798536 -61.050897) (xy 358.77124 -61.002262)
			(xy 358.751317 -60.950171) (xy 358.739191 -60.895734) (xy 358.73512 -60.840112) (xy 357.225531 -60.840112)
			(xy 357.194544 -60.864612) (xy 357.144728 -60.893052) (xy 357.118158 -60.903866) (xy 357.105526 -60.909273)
			(xy 357.083533 -60.925727) (xy 357.066714 -60.947443) (xy 357.056287 -60.972853) (xy 357.053002 -61.000123)
			(xy 357.057098 -61.027283) (xy 357.062278 -61.04001) (xy 357.072807 -61.064645) (xy 357.087619 -61.11613)
			(xy 357.0951 -61.169179) (xy 357.095552 -61.195966) (xy 357.095067 -61.223237) (xy 357.087309 -61.277223)
			(xy 357.071947 -61.329556) (xy 357.049292 -61.37917) (xy 357.019807 -61.425054) (xy 356.984092 -61.466275)
			(xy 356.942873 -61.501993) (xy 356.896991 -61.531481) (xy 356.847379 -61.554138) (xy 356.795047 -61.569504)
			(xy 356.741061 -61.577265) (xy 356.71379 -61.577728) (xy 355.85019 -61.577728) (xy 355.822917 -61.577308)
			(xy 355.768927 -61.569543) (xy 355.716591 -61.554174) (xy 355.666976 -61.531513) (xy 355.621091 -61.502021)
			(xy 355.57987 -61.466299) (xy 355.544153 -61.425074) (xy 355.514666 -61.379185) (xy 355.492011 -61.329567)
			(xy 355.476647 -61.27723) (xy 355.468889 -61.223239) (xy 355.468428 -61.195966) (xy 355.468829 -61.17032)
			(xy 355.475711 -61.119492) (xy 355.489347 -61.070046) (xy 355.509491 -61.022876) (xy 355.522276 -61.00064)
			(xy 355.529037 -60.988459) (xy 355.536347 -60.961587) (xy 355.536117 -60.93374) (xy 355.528362 -60.906993)
			(xy 355.513662 -60.883341) (xy 355.493113 -60.864547) (xy 355.480874 -60.857892) (xy 355.457564 -60.845639)
			(xy 355.414237 -60.815706) (xy 355.375441 -60.780095) (xy 355.341914 -60.739485) (xy 355.314294 -60.694648)
			(xy 355.293107 -60.646437) (xy 355.278755 -60.595769) (xy 355.271512 -60.543609) (xy 355.27107 -60.517278)
			(xy 352.571837 -60.517278) (xy 352.577355 -60.536109) (xy 352.585083 -60.590089) (xy 352.585528 -60.617354)
			(xy 352.585528 -61.480954) (xy 352.585034 -61.508212) (xy 352.577284 -61.562175) (xy 352.561935 -61.614486)
			(xy 352.539301 -61.664082) (xy 352.50984 -61.709952) (xy 352.474153 -61.751165) (xy 352.432965 -61.78688)
			(xy 352.387115 -61.816373) (xy 352.337536 -61.839042) (xy 352.285235 -61.854427) (xy 352.231278 -61.862215)
			(xy 352.20402 -61.862716) (xy 352.176953 -61.862221) (xy 352.123373 -61.854496) (xy 352.071416 -61.839296)
			(xy 352.022119 -61.816925) (xy 351.999042 -61.802772) (xy 351.986705 -61.795531) (xy 351.959284 -61.78744)
			(xy 351.930695 -61.787273) (xy 351.903181 -61.795043) (xy 351.878903 -61.810141) (xy 351.859765 -61.83138)
			(xy 351.847269 -61.857095) (xy 351.844356 -61.871098) (xy 351.839344 -61.897312) (xy 351.822922 -61.948094)
			(xy 351.799585 -61.996093) (xy 351.769789 -62.040372) (xy 351.734115 -62.080069) (xy 351.693258 -62.114409)
			(xy 351.648015 -62.142721) (xy 351.59927 -62.164455) (xy 351.547972 -62.179186) (xy 351.495122 -62.186626)
			(xy 351.468436 -62.187074) (xy 351.441179 -62.186682) (xy 351.387219 -62.178928) (xy 351.334912 -62.163574)
			(xy 351.285323 -62.140931) (xy 351.239462 -62.111462) (xy 351.198261 -62.075765) (xy 351.16256 -62.034567)
			(xy 351.133086 -61.988708) (xy 351.110439 -61.939121) (xy 351.09508 -61.886816) (xy 351.087321 -61.832857)
			(xy 351.087321 -61.778343) (xy 351.09508 -61.724384) (xy 351.110439 -61.672079) (xy 351.133086 -61.622492)
			(xy 351.16256 -61.576633) (xy 351.198261 -61.535435) (xy 351.239462 -61.499738) (xy 351.285323 -61.470269)
			(xy 351.334912 -61.447626) (xy 351.387219 -61.432272) (xy 351.441179 -61.424518) (xy 351.468436 -61.424058)
			(xy 351.498126 -61.424655) (xy 351.556788 -61.433858) (xy 351.613317 -61.452036) (xy 351.666348 -61.478751)
			(xy 351.7146 -61.513357) (xy 351.736152 -61.533786) (xy 351.74373 -61.540595) (xy 351.762603 -61.548207)
			(xy 351.78295 -61.547893) (xy 351.80158 -61.539703) (xy 351.815568 -61.524923) (xy 351.822719 -61.505871)
			(xy 351.822766 -61.495686) (xy 351.822512 -61.480954) (xy 351.822512 -60.617354) (xy 351.823274 -60.592208)
			(xy 351.823478 -60.581918) (xy 351.816722 -60.5625) (xy 351.802877 -60.547302) (xy 351.784171 -60.538772)
			(xy 351.763617 -60.538283) (xy 351.744527 -60.545914) (xy 351.736914 -60.552838) (xy 351.715325 -60.573371)
			(xy 351.66697 -60.608174) (xy 351.613792 -60.635034) (xy 351.557083 -60.653297) (xy 351.498225 -60.662521)
			(xy 351.468436 -60.663074) (xy 351.440496 -60.662551) (xy 351.385215 -60.654391) (xy 351.331716 -60.638255)
			(xy 351.281142 -60.614488) (xy 351.234576 -60.583598) (xy 351.193013 -60.546247) (xy 351.157343 -60.503232)
			(xy 351.128329 -60.455475) (xy 351.106591 -60.403997) (xy 351.09912 -60.37707) (xy 351.095079 -60.363466)
			(xy 351.080706 -60.33901) (xy 351.060173 -60.319439) (xy 351.035057 -60.306254) (xy 351.007287 -60.30047)
			(xy 350.978995 -60.302529) (xy 350.965516 -60.306966) (xy 350.933675 -60.317969) (xy 350.86737 -60.329851)
			(xy 350.83369 -60.330588) (xy 350.80799 -60.33016) (xy 350.757056 -60.323262) (xy 350.707507 -60.309593)
			(xy 350.66024 -60.2894) (xy 350.616111 -60.263047) (xy 350.575915 -60.231012) (xy 350.557846 -60.212732)
			(xy 350.547951 -60.202926) (xy 350.524002 -60.188709) (xy 350.4971 -60.181501) (xy 350.469252 -60.181838)
			(xy 350.442532 -60.189696) (xy 350.418935 -60.204489) (xy 350.409256 -60.21451) (xy 350.391067 -60.233799)
			(xy 350.350328 -60.267727) (xy 350.305285 -60.295688) (xy 350.256805 -60.317144) (xy 350.205821 -60.331682)
			(xy 350.153316 -60.339023) (xy 350.126808 -60.339478) (xy 350.097402 -60.33892) (xy 350.039286 -60.329908)
			(xy 349.983242 -60.312081) (xy 349.930599 -60.28586) (xy 349.882606 -60.251869) (xy 349.861124 -60.231782)
			(xy 349.850515 -60.222177) (xy 349.825269 -60.208729) (xy 349.797285 -60.202801) (xy 349.768754 -60.204859)
			(xy 349.74191 -60.21474) (xy 349.718854 -60.231671) (xy 349.70974 -60.242704) (xy 349.691593 -60.265495)
			(xy 349.649493 -60.305761) (xy 349.601759 -60.339158) (xy 349.549501 -60.364906) (xy 349.493935 -60.382408)
			(xy 349.436354 -60.391256) (xy 349.407226 -60.391802) (xy 349.379972 -60.391352) (xy 349.326017 -60.383598)
			(xy 349.273715 -60.368244) (xy 349.224131 -60.345603) (xy 349.178274 -60.316135) (xy 349.137077 -60.280441)
			(xy 349.10138 -60.239247) (xy 349.07191 -60.193392) (xy 349.049265 -60.143809) (xy 349.033907 -60.091509)
			(xy 349.026149 -60.037554) (xy 346.094443 -60.037554) (xy 346.094812 -60.057792) (xy 346.094315 -60.085028)
			(xy 346.086384 -60.138919) (xy 346.070691 -60.191081) (xy 346.04757 -60.240402) (xy 346.017514 -60.285831)
			(xy 345.981165 -60.3264) (xy 345.939295 -60.361244) (xy 345.892799 -60.38962) (xy 345.842666 -60.410924)
			(xy 345.789966 -60.424702) (xy 345.735821 -60.43066) (xy 345.681386 -60.42867) (xy 345.62782 -60.418776)
			(xy 345.576266 -60.401188) (xy 345.527823 -60.376282) (xy 345.483521 -60.344587) (xy 345.444307 -60.30678)
			(xy 345.411016 -60.263666) (xy 345.384356 -60.216164) (xy 345.364897 -60.165287) (xy 345.353054 -60.112118)
			(xy 345.349078 -60.057792) (xy 339.033997 -60.057792) (xy 339.005095 -60.081844) (xy 338.958599 -60.11022)
			(xy 338.908466 -60.131524) (xy 338.855766 -60.145302) (xy 338.801621 -60.15126) (xy 338.747186 -60.14927)
			(xy 338.69362 -60.139376) (xy 338.642066 -60.121788) (xy 338.593623 -60.096882) (xy 338.549321 -60.065187)
			(xy 338.510107 -60.02738) (xy 338.476816 -59.984266) (xy 338.450156 -59.936764) (xy 338.430697 -59.885887)
			(xy 338.418854 -59.832718) (xy 338.414878 -59.778392) (xy 337.237742 -59.778392) (xy 337.247425 -59.809783)
			(xy 337.255368 -59.862487) (xy 337.255866 -59.889136) (xy 337.255368 -59.915785) (xy 337.247425 -59.968489)
			(xy 337.231715 -60.019419) (xy 337.208589 -60.06744) (xy 337.178565 -60.111477) (xy 337.142313 -60.150548)
			(xy 337.100642 -60.183779) (xy 337.054484 -60.210428) (xy 337.00487 -60.2299) (xy 336.952908 -60.24176)
			(xy 336.899758 -60.245744) (xy 336.846608 -60.24176) (xy 336.794646 -60.2299) (xy 336.745032 -60.210428)
			(xy 336.698874 -60.183779) (xy 336.657203 -60.150548) (xy 336.620951 -60.111477) (xy 336.590927 -60.06744)
			(xy 336.567801 -60.019419) (xy 336.552091 -59.968489) (xy 336.544148 -59.915785) (xy 336.069879 -59.915785)
			(xy 336.093275 -59.9501) (xy 336.116401 -59.998121) (xy 336.132111 -60.049051) (xy 336.140054 -60.101755)
			(xy 336.140552 -60.128404) (xy 336.140054 -60.155053) (xy 336.132111 -60.207757) (xy 336.116401 -60.258687)
			(xy 336.093275 -60.306708) (xy 336.063251 -60.350745) (xy 336.026999 -60.389816) (xy 335.985328 -60.423047)
			(xy 335.93917 -60.449696) (xy 335.889556 -60.469168) (xy 335.837594 -60.481028) (xy 335.784444 -60.485012)
			(xy 335.731294 -60.481028) (xy 335.679332 -60.469168) (xy 335.629718 -60.449696) (xy 335.58356 -60.423047)
			(xy 335.541889 -60.389816) (xy 335.505637 -60.350745) (xy 335.475613 -60.306708) (xy 335.452487 -60.258687)
			(xy 335.436777 -60.207757) (xy 335.428834 -60.155053) (xy 334.401139 -60.155053) (xy 336.144108 -61.898022)
			(xy 336.172556 -61.890402) (xy 336.197338 -61.884002) (xy 336.248057 -61.877121) (xy 336.273648 -61.876686)
			(xy 336.300897 -61.877175) (xy 336.35484 -61.884937) (xy 336.407129 -61.900296) (xy 336.456701 -61.92294)
			(xy 336.502546 -61.952408) (xy 336.543731 -61.988099) (xy 336.579418 -62.029288) (xy 336.60888 -62.075136)
			(xy 336.631518 -62.12471) (xy 336.646872 -62.177001) (xy 336.654628 -62.230945) (xy 336.655156 -62.258194)
			(xy 336.654728 -62.283786) (xy 336.647849 -62.334506) (xy 336.64144 -62.359286) (xy 336.63382 -62.387734)
			(xy 337.867837 -63.621751) (xy 349.565466 -63.621751) (xy 349.565466 -63.567249) (xy 349.573222 -63.513303)
			(xy 349.588576 -63.461009) (xy 349.611215 -63.411432) (xy 349.640679 -63.365582) (xy 349.676369 -63.324391)
			(xy 349.717556 -63.288699) (xy 349.763404 -63.259231) (xy 349.812979 -63.236587) (xy 349.865271 -63.221228)
			(xy 349.919217 -63.213468) (xy 349.946468 -63.21298) (xy 349.976159 -63.213551) (xy 350.034823 -63.222759)
			(xy 350.091352 -63.240943) (xy 350.144382 -63.267664) (xy 350.192634 -63.302276) (xy 350.214184 -63.322708)
			(xy 350.22174 -63.32954) (xy 350.24062 -63.337142) (xy 350.26097 -63.336821) (xy 350.2796 -63.328628)
			(xy 350.29359 -63.313846) (xy 350.300748 -63.294794) (xy 350.300798 -63.284608) (xy 350.300544 -63.269876)
			(xy 350.300544 -62.406276) (xy 350.301306 -62.38113) (xy 350.301502 -62.370846) (xy 350.29473 -62.351448)
			(xy 350.280884 -62.336267) (xy 350.26219 -62.327742) (xy 350.241649 -62.327243) (xy 350.222563 -62.33485)
			(xy 350.214946 -62.34176) (xy 350.19339 -62.36233) (xy 350.145026 -62.397126) (xy 350.091839 -62.423979)
			(xy 350.035123 -62.442234) (xy 349.976259 -62.451448) (xy 349.946468 -62.451996) (xy 349.919217 -62.451532)
			(xy 349.865271 -62.443772) (xy 349.812979 -62.428413) (xy 349.763404 -62.405769) (xy 349.717556 -62.376301)
			(xy 349.676369 -62.340609) (xy 349.640679 -62.299418) (xy 349.611215 -62.253568) (xy 349.588576 -62.203991)
			(xy 349.573222 -62.151697) (xy 349.565466 -62.097751) (xy 349.565466 -62.043249) (xy 349.573222 -61.989303)
			(xy 349.588576 -61.937009) (xy 349.611215 -61.887432) (xy 349.640679 -61.841582) (xy 349.676369 -61.800391)
			(xy 349.717556 -61.764699) (xy 349.763404 -61.735231) (xy 349.812979 -61.712587) (xy 349.865271 -61.697228)
			(xy 349.919217 -61.689468) (xy 349.946468 -61.68898) (xy 349.973563 -61.689469) (xy 350.027208 -61.697133)
			(xy 350.079229 -61.71231) (xy 350.128579 -61.734696) (xy 350.174264 -61.76384) (xy 350.215366 -61.799155)
			(xy 350.251057 -61.839931) (xy 350.280619 -61.885347) (xy 350.303457 -61.93449) (xy 350.319111 -61.986369)
			(xy 350.323658 -62.013084) (xy 350.326307 -62.027252) (xy 350.338484 -62.053366) (xy 350.357459 -62.075049)
			(xy 350.381727 -62.090582) (xy 350.409363 -62.098733) (xy 350.438176 -62.098855) (xy 350.465881 -62.090939)
			(xy 350.478344 -62.083696) (xy 350.501319 -62.06975) (xy 350.55034 -62.047716) (xy 350.601967 -62.032777)
			(xy 350.65518 -62.02523) (xy 350.682052 -62.024768) (xy 350.709303 -62.0253) (xy 350.76325 -62.03305)
			(xy 350.815545 -62.048398) (xy 350.865123 -62.071034) (xy 350.910975 -62.100494) (xy 350.952168 -62.136181)
			(xy 350.987862 -62.177367) (xy 351.017332 -62.223213) (xy 351.039976 -62.272788) (xy 351.055335 -62.32508)
			(xy 351.063095 -62.379026) (xy 351.06356 -62.406276) (xy 351.06356 -63.269876) (xy 351.063122 -63.29713)
			(xy 351.055367 -63.351085) (xy 351.040012 -63.403386) (xy 351.017369 -63.452969) (xy 350.987899 -63.498825)
			(xy 350.952202 -63.540019) (xy 350.911006 -63.575713) (xy 350.865148 -63.60518) (xy 350.815564 -63.62782)
			(xy 350.763261 -63.643172) (xy 350.709306 -63.650924) (xy 350.682052 -63.651384) (xy 350.654993 -63.650906)
			(xy 350.601417 -63.643269) (xy 350.549457 -63.62814) (xy 350.500155 -63.605824) (xy 350.477074 -63.591694)
			(xy 350.464723 -63.584477) (xy 350.437306 -63.576379) (xy 350.408719 -63.576206) (xy 350.381206 -63.583971)
			(xy 350.356928 -63.599066) (xy 350.337791 -63.620303) (xy 350.325299 -63.646017) (xy 350.322388 -63.66002)
			(xy 350.317362 -63.686231) (xy 350.300939 -63.737011) (xy 350.277602 -63.785007) (xy 350.247807 -63.829285)
			(xy 350.212134 -63.868981) (xy 350.171279 -63.90332) (xy 350.126039 -63.931634) (xy 350.077296 -63.953369)
			(xy 350.026 -63.968102) (xy 349.973153 -63.975546) (xy 349.946468 -63.975996) (xy 349.919217 -63.975532)
			(xy 349.865271 -63.967772) (xy 349.812979 -63.952413) (xy 349.763404 -63.929769) (xy 349.717556 -63.900301)
			(xy 349.676369 -63.864609) (xy 349.640679 -63.823418) (xy 349.611215 -63.777568) (xy 349.588576 -63.727991)
			(xy 349.573222 -63.675697) (xy 349.565466 -63.621751) (xy 337.867837 -63.621751) (xy 339.575648 -65.329562)
			(xy 352.362008 -65.329562) (xy 352.362008 -64.465962) (xy 352.362445 -64.439266) (xy 352.369889 -64.386395)
			(xy 352.384626 -64.335078) (xy 352.40637 -64.286313) (xy 352.434695 -64.241054) (xy 352.46905 -64.200183)
			(xy 352.508764 -64.164496) (xy 352.530664 -64.149224) (xy 352.542197 -64.141029) (xy 352.560481 -64.119447)
			(xy 352.572151 -64.093681) (xy 352.576312 -64.065703) (xy 352.572646 -64.037656) (xy 352.561434 -64.011688)
			(xy 352.543534 -63.989786) (xy 352.532188 -63.98133) (xy 352.510857 -63.965959) (xy 352.472169 -63.930359)
			(xy 352.438738 -63.889781) (xy 352.4112 -63.844994) (xy 352.390076 -63.796849) (xy 352.375767 -63.746259)
			(xy 352.368544 -63.694182) (xy 352.368104 -63.667894) (xy 352.368553 -63.640768) (xy 352.376239 -63.587064)
			(xy 352.391455 -63.53499) (xy 352.413894 -63.485596) (xy 352.443104 -63.439879) (xy 352.478496 -63.398761)
			(xy 352.519355 -63.363072) (xy 352.564858 -63.33353) (xy 352.614087 -63.310732) (xy 352.666049 -63.295137)
			(xy 352.719696 -63.287061) (xy 352.746818 -63.286386) (xy 352.760084 -63.28586) (xy 352.785671 -63.278809)
			(xy 352.808574 -63.265398) (xy 352.827243 -63.246534) (xy 352.840415 -63.223493) (xy 352.8472 -63.197835)
			(xy 352.847139 -63.171295) (xy 352.8441 -63.15837) (xy 352.83792 -63.133878) (xy 352.831288 -63.083804)
			(xy 352.830892 -63.058548) (xy 352.831378 -63.031297) (xy 352.839134 -62.977349) (xy 352.854489 -62.925054)
			(xy 352.877131 -62.875477) (xy 352.906597 -62.829627) (xy 352.942288 -62.788436) (xy 352.983479 -62.752745)
			(xy 353.029329 -62.723279) (xy 353.078906 -62.700637) (xy 353.131201 -62.685282) (xy 353.185149 -62.677526)
			(xy 353.239651 -62.677526) (xy 353.293599 -62.685282) (xy 353.345894 -62.700637) (xy 353.395471 -62.723279)
			(xy 353.441321 -62.752745) (xy 353.482512 -62.788436) (xy 353.518203 -62.829627) (xy 353.547669 -62.875477)
			(xy 353.570311 -62.925054) (xy 353.585666 -62.977349) (xy 353.593422 -63.031297) (xy 353.593908 -63.058548)
			(xy 353.593393 -63.085672) (xy 353.585715 -63.139373) (xy 353.570507 -63.191445) (xy 353.548075 -63.240838)
			(xy 353.518872 -63.286554) (xy 353.483487 -63.327672) (xy 353.442634 -63.363363) (xy 353.397137 -63.392906)
			(xy 353.347913 -63.415706) (xy 353.295956 -63.431302) (xy 353.242314 -63.43938) (xy 353.215194 -63.440056)
			(xy 353.199711 -63.440802) (xy 353.170232 -63.450316) (xy 353.144958 -63.468224) (xy 353.126209 -63.492882)
			(xy 353.115708 -63.522024) (xy 353.114419 -63.552973) (xy 353.117912 -63.568072) (xy 353.1241 -63.592562)
			(xy 353.130727 -63.642638) (xy 353.13112 -63.667894) (xy 353.130659 -63.6946) (xy 353.123198 -63.747489)
			(xy 353.108435 -63.79882) (xy 353.098393 -63.82131) (xy 363.201202 -63.82131) (xy 363.205273 -63.765688)
			(xy 363.217399 -63.711251) (xy 363.237322 -63.65916) (xy 363.264618 -63.610525) (xy 363.298704 -63.566382)
			(xy 363.338853 -63.527673) (xy 363.384211 -63.495222) (xy 363.433811 -63.469721) (xy 363.486595 -63.451714)
			(xy 363.541438 -63.441584) (xy 363.597172 -63.439547) (xy 363.652609 -63.445647) (xy 363.706566 -63.459753)
			(xy 363.757895 -63.481565) (xy 363.805501 -63.510619) (xy 363.848369 -63.546294) (xy 363.885586 -63.587831)
			(xy 363.916359 -63.634344) (xy 363.940031 -63.684841) (xy 363.956099 -63.738248) (xy 363.964219 -63.793424)
			(xy 363.964728 -63.82131) (xy 363.964219 -63.849196) (xy 363.956099 -63.904372) (xy 363.940031 -63.957779)
			(xy 363.916359 -64.008276) (xy 363.885586 -64.054789) (xy 363.848369 -64.096326) (xy 363.805501 -64.132001)
			(xy 363.757895 -64.161055) (xy 363.706566 -64.182867) (xy 363.652609 -64.196973) (xy 363.597172 -64.203073)
			(xy 363.541438 -64.201036) (xy 363.486595 -64.190906) (xy 363.433811 -64.172899) (xy 363.384211 -64.147398)
			(xy 363.338853 -64.114947) (xy 363.298704 -64.076238) (xy 363.264618 -64.032095) (xy 363.237322 -63.98346)
			(xy 363.217399 -63.931369) (xy 363.205273 -63.876932) (xy 363.201202 -63.82131) (xy 353.098393 -63.82131)
			(xy 353.086658 -63.847591) (xy 353.058293 -63.89285) (xy 353.023894 -63.93371) (xy 352.984134 -63.969375)
			(xy 352.96221 -63.984632) (xy 352.950711 -63.992877) (xy 352.932443 -64.014473) (xy 352.920798 -64.040251)
			(xy 352.916671 -64.068234) (xy 352.920378 -64.096276) (xy 352.931635 -64.122226) (xy 352.949577 -64.144093)
			(xy 352.96094 -64.152526) (xy 352.982303 -64.167854) (xy 353.02099 -64.203462) (xy 353.054417 -64.244048)
			(xy 353.081951 -64.288842) (xy 353.103069 -64.336994) (xy 353.117372 -64.38759) (xy 353.124588 -64.439672)
			(xy 353.125024 -64.465962) (xy 353.125024 -65.329562) (xy 353.124504 -65.358299) (xy 353.115893 -65.415125)
			(xy 353.09886 -65.470018) (xy 353.07379 -65.521736) (xy 353.04125 -65.569112) (xy 353.001975 -65.611074)
			(xy 352.979736 -65.629282) (xy 352.969124 -65.638225) (xy 352.952739 -65.660608) (xy 352.942979 -65.686574)
			(xy 352.940565 -65.714208) (xy 352.945674 -65.741473) (xy 352.957929 -65.766358) (xy 352.976427 -65.787029)
			(xy 352.987864 -65.79489) (xy 353.010661 -65.809987) (xy 353.052087 -65.845671) (xy 353.075769 -65.872868)
			(xy 362.871512 -65.872868) (xy 362.871921 -65.84559) (xy 362.879696 -65.791591) (xy 362.895082 -65.739251)
			(xy 362.917767 -65.689635) (xy 362.947287 -65.643756) (xy 362.983041 -65.60255) (xy 363.024299 -65.566855)
			(xy 363.070221 -65.537402) (xy 363.119869 -65.514789) (xy 363.172233 -65.499478) (xy 363.199172 -65.49517)
			(xy 363.213701 -65.492567) (xy 363.240486 -65.480195) (xy 363.262619 -65.460685) (xy 363.278253 -65.435665)
			(xy 363.286087 -65.40722) (xy 363.285466 -65.377723) (xy 363.276442 -65.349633) (xy 363.268514 -65.337182)
			(xy 363.252744 -65.313203) (xy 363.227751 -65.261543) (xy 363.21078 -65.206722) (xy 363.202214 -65.149976)
			(xy 363.201712 -65.121282) (xy 363.202198 -65.094031) (xy 363.209954 -65.040083) (xy 363.225309 -64.987788)
			(xy 363.247951 -64.938211) (xy 363.277417 -64.892361) (xy 363.313108 -64.85117) (xy 363.354299 -64.815479)
			(xy 363.400149 -64.786013) (xy 363.449726 -64.763371) (xy 363.502021 -64.748016) (xy 363.555969 -64.74026)
			(xy 363.610471 -64.74026) (xy 363.664419 -64.748016) (xy 363.716714 -64.763371) (xy 363.766291 -64.786013)
			(xy 363.812141 -64.815479) (xy 363.853332 -64.85117) (xy 363.889023 -64.892361) (xy 363.918489 -64.938211)
			(xy 363.941131 -64.987788) (xy 363.956486 -65.040083) (xy 363.964242 -65.094031) (xy 363.964728 -65.121282)
			(xy 363.964239 -65.148557) (xy 363.956472 -65.202551) (xy 363.941093 -65.254888) (xy 363.918418 -65.304501)
			(xy 363.888906 -65.350378) (xy 363.853162 -65.391585) (xy 363.811912 -65.42728) (xy 363.766 -65.456737)
			(xy 363.716359 -65.479353) (xy 363.664004 -65.494669) (xy 363.637068 -65.49898) (xy 363.622551 -65.501625)
			(xy 363.595781 -65.514001) (xy 363.573661 -65.533506) (xy 363.558032 -65.558516) (xy 363.553299 -65.575688)
			(xy 371.461282 -65.575688) (xy 371.465353 -65.520066) (xy 371.477479 -65.465629) (xy 371.497402 -65.413538)
			(xy 371.524698 -65.364903) (xy 371.558784 -65.32076) (xy 371.598933 -65.282051) (xy 371.644291 -65.2496)
			(xy 371.693891 -65.224099) (xy 371.746675 -65.206092) (xy 371.801518 -65.195962) (xy 371.857252 -65.193925)
			(xy 371.912689 -65.200025) (xy 371.966646 -65.214131) (xy 372.017975 -65.235943) (xy 372.065581 -65.264997)
			(xy 372.108449 -65.300672) (xy 372.145666 -65.342209) (xy 372.176439 -65.388722) (xy 372.200111 -65.439219)
			(xy 372.216179 -65.492626) (xy 372.224299 -65.547802) (xy 372.224808 -65.575688) (xy 372.224299 -65.603574)
			(xy 372.216179 -65.65875) (xy 372.200111 -65.712157) (xy 372.176439 -65.762654) (xy 372.145666 -65.809167)
			(xy 372.108449 -65.850704) (xy 372.065581 -65.886379) (xy 372.017975 -65.915433) (xy 371.966646 -65.937245)
			(xy 371.912689 -65.951351) (xy 371.857252 -65.957451) (xy 371.801518 -65.955414) (xy 371.746675 -65.945284)
			(xy 371.693891 -65.927277) (xy 371.644291 -65.901776) (xy 371.598933 -65.869325) (xy 371.558784 -65.830616)
			(xy 371.524698 -65.786473) (xy 371.497402 -65.737838) (xy 371.477479 -65.685747) (xy 371.465353 -65.63131)
			(xy 371.461282 -65.575688) (xy 363.553299 -65.575688) (xy 363.550196 -65.586948) (xy 363.550805 -65.616433)
			(xy 363.55981 -65.644517) (xy 363.567726 -65.656968) (xy 363.583522 -65.68093) (xy 363.608508 -65.732597)
			(xy 363.625472 -65.787423) (xy 363.63403 -65.844172) (xy 363.634528 -65.872868) (xy 363.634042 -65.900119)
			(xy 363.626286 -65.954067) (xy 363.610931 -66.006362) (xy 363.588289 -66.055939) (xy 363.558823 -66.101789)
			(xy 363.523132 -66.14298) (xy 363.481941 -66.178671) (xy 363.436091 -66.208137) (xy 363.386514 -66.230779)
			(xy 363.334219 -66.246134) (xy 363.280271 -66.25389) (xy 363.225769 -66.25389) (xy 363.171821 -66.246134)
			(xy 363.119526 -66.230779) (xy 363.069949 -66.208137) (xy 363.024099 -66.178671) (xy 362.982908 -66.14298)
			(xy 362.947217 -66.101789) (xy 362.917751 -66.055939) (xy 362.895109 -66.006362) (xy 362.879754 -65.954067)
			(xy 362.871998 -65.900119) (xy 362.871512 -65.872868) (xy 353.075769 -65.872868) (xy 353.087992 -65.886906)
			(xy 353.11764 -65.932847) (xy 353.140422 -65.982551) (xy 353.155873 -66.034999) (xy 353.163674 -66.089116)
			(xy 353.16414 -66.116454) (xy 353.163654 -66.143705) (xy 353.155898 -66.197653) (xy 353.140543 -66.249948)
			(xy 353.117901 -66.299525) (xy 353.088435 -66.345375) (xy 353.052744 -66.386566) (xy 353.012711 -66.421254)
			(xy 361.827062 -66.421254) (xy 361.831133 -66.365632) (xy 361.843259 -66.311195) (xy 361.863182 -66.259104)
			(xy 361.890478 -66.210469) (xy 361.924564 -66.166326) (xy 361.964713 -66.127617) (xy 362.010071 -66.095166)
			(xy 362.059671 -66.069665) (xy 362.112455 -66.051658) (xy 362.167298 -66.041528) (xy 362.223032 -66.039491)
			(xy 362.278469 -66.045591) (xy 362.332426 -66.059697) (xy 362.383755 -66.081509) (xy 362.431361 -66.110563)
			(xy 362.474229 -66.146238) (xy 362.511446 -66.187775) (xy 362.542219 -66.234288) (xy 362.565891 -66.284785)
			(xy 362.581959 -66.338192) (xy 362.590079 -66.393368) (xy 362.590588 -66.421254) (xy 362.590079 -66.44914)
			(xy 362.581959 -66.504316) (xy 362.565891 -66.557723) (xy 362.542219 -66.60822) (xy 362.511446 -66.654733)
			(xy 362.474229 -66.69627) (xy 362.431361 -66.731945) (xy 362.383755 -66.760999) (xy 362.332426 -66.782811)
			(xy 362.278469 -66.796917) (xy 362.223032 -66.803017) (xy 362.167298 -66.80098) (xy 362.112455 -66.79085)
			(xy 362.059671 -66.772843) (xy 362.010071 -66.747342) (xy 361.964713 -66.714891) (xy 361.924564 -66.676182)
			(xy 361.890478 -66.632039) (xy 361.863182 -66.583404) (xy 361.843259 -66.531313) (xy 361.831133 -66.476876)
			(xy 361.827062 -66.421254) (xy 353.012711 -66.421254) (xy 353.011553 -66.422257) (xy 352.965703 -66.451723)
			(xy 352.916126 -66.474365) (xy 352.863831 -66.48972) (xy 352.809883 -66.497476) (xy 352.755381 -66.497476)
			(xy 352.701433 -66.48972) (xy 352.649138 -66.474365) (xy 352.599561 -66.451723) (xy 352.553711 -66.422257)
			(xy 352.51252 -66.386566) (xy 352.476829 -66.345375) (xy 352.447363 -66.299525) (xy 352.424721 -66.249948)
			(xy 352.409366 -66.197653) (xy 352.40161 -66.143705) (xy 352.401124 -66.116454) (xy 352.401637 -66.087716)
			(xy 352.410247 -66.030889) (xy 352.42728 -65.975996) (xy 352.452351 -65.924277) (xy 352.484894 -65.876901)
			(xy 352.524172 -65.834941) (xy 352.546412 -65.816734) (xy 352.556972 -65.807762) (xy 352.573341 -65.785425)
			(xy 352.583094 -65.759506) (xy 352.58551 -65.731919) (xy 352.580412 -65.704699) (xy 352.568176 -65.679856)
			(xy 352.549704 -65.659224) (xy 352.538284 -65.65138) (xy 352.515447 -65.63631) (xy 352.474 -65.600589)
			(xy 352.438082 -65.559313) (xy 352.408432 -65.513327) (xy 352.385657 -65.463576) (xy 352.370226 -65.411082)
			(xy 352.362455 -65.35692) (xy 352.362008 -65.329562) (xy 339.575648 -65.329562) (xy 341.561542 -67.315456)
			(xy 349.535911 -67.315456) (xy 349.535911 -67.260944) (xy 349.543669 -67.206986) (xy 349.559027 -67.154682)
			(xy 349.581672 -67.105096) (xy 349.611144 -67.059237) (xy 349.646842 -67.01804) (xy 349.68804 -66.982342)
			(xy 349.733899 -66.95287) (xy 349.783486 -66.930226) (xy 349.83579 -66.914868) (xy 349.889748 -66.907111)
			(xy 349.917004 -66.906648) (xy 349.946697 -66.907177) (xy 350.005363 -66.916393) (xy 350.061894 -66.934585)
			(xy 350.114923 -66.961316) (xy 350.163172 -66.995939) (xy 350.18472 -67.016376) (xy 350.192224 -67.023275)
			(xy 350.211123 -67.030881) (xy 350.231492 -67.030555) (xy 350.250137 -67.022347) (xy 350.264135 -67.007546)
			(xy 350.27129 -66.988472) (xy 350.271334 -66.978276) (xy 350.27108 -66.963544) (xy 350.27108 -66.099944)
			(xy 350.271842 -66.074798) (xy 350.272106 -66.064505) (xy 350.265343 -66.045077) (xy 350.251485 -66.029872)
			(xy 350.232765 -66.02134) (xy 350.212198 -66.020856) (xy 350.193098 -66.028497) (xy 350.185482 -66.035428)
			(xy 350.163906 -66.055975) (xy 350.115547 -66.090776) (xy 350.062366 -66.117633) (xy 350.005655 -66.135894)
			(xy 349.946794 -66.145113) (xy 349.917004 -66.145664) (xy 349.889748 -66.145289) (xy 349.83579 -66.137532)
			(xy 349.783486 -66.122174) (xy 349.733899 -66.09953) (xy 349.68804 -66.070058) (xy 349.646842 -66.03436)
			(xy 349.611144 -65.993163) (xy 349.581672 -65.947304) (xy 349.559027 -65.897718) (xy 349.543669 -65.845414)
			(xy 349.535911 -65.791456) (xy 349.535911 -65.736944) (xy 349.543669 -65.682986) (xy 349.559027 -65.630682)
			(xy 349.581672 -65.581096) (xy 349.611144 -65.535237) (xy 349.646842 -65.49404) (xy 349.68804 -65.458342)
			(xy 349.733899 -65.42887) (xy 349.783486 -65.406226) (xy 349.83579 -65.390868) (xy 349.889748 -65.383111)
			(xy 349.917004 -65.382648) (xy 349.9441 -65.383139) (xy 349.997748 -65.390795) (xy 350.049772 -65.405968)
			(xy 350.099125 -65.428351) (xy 350.144813 -65.457494) (xy 350.185916 -65.49281) (xy 350.221607 -65.533588)
			(xy 350.251167 -65.579007) (xy 350.274002 -65.628153) (xy 350.28965 -65.680036) (xy 350.294194 -65.706752)
			(xy 350.296954 -65.720895) (xy 350.309114 -65.746998) (xy 350.328069 -65.768676) (xy 350.352317 -65.784209)
			(xy 350.379934 -65.792366) (xy 350.40873 -65.792499) (xy 350.436421 -65.784598) (xy 350.44888 -65.777364)
			(xy 350.471845 -65.763399) (xy 350.520869 -65.741371) (xy 350.5725 -65.726437) (xy 350.625715 -65.718895)
			(xy 350.652588 -65.718436) (xy 350.679843 -65.718867) (xy 350.733797 -65.726623) (xy 350.786098 -65.74198)
			(xy 350.835681 -65.764624) (xy 350.881536 -65.794095) (xy 350.92273 -65.829792) (xy 350.958424 -65.870989)
			(xy 350.987891 -65.916847) (xy 351.010531 -65.966432) (xy 351.025884 -66.018734) (xy 351.033636 -66.072689)
			(xy 351.034096 -66.099944) (xy 351.034096 -66.963544) (xy 351.033663 -66.990797) (xy 351.0259 -67.044747)
			(xy 351.010539 -67.097044) (xy 350.987892 -67.146622) (xy 350.95842 -67.192473) (xy 350.922723 -67.233663)
			(xy 350.881528 -67.269353) (xy 350.835673 -67.298819) (xy 350.786091 -67.321459) (xy 350.733792 -67.336812)
			(xy 350.679841 -67.344567) (xy 350.652588 -67.345052) (xy 350.625528 -67.344608) (xy 350.57195 -67.336962)
			(xy 350.51999 -67.321824) (xy 350.47069 -67.299497) (xy 350.44761 -67.285362) (xy 350.435324 -67.278022)
			(xy 350.407883 -67.269924) (xy 350.379273 -67.26976) (xy 350.351741 -67.277543) (xy 350.327451 -67.292662)
			(xy 350.308312 -67.313929) (xy 350.295827 -67.339672) (xy 350.292924 -67.353688) (xy 350.28784 -67.379887)
			(xy 350.271423 -67.430664) (xy 350.248093 -67.478659) (xy 350.218304 -67.522936) (xy 350.182638 -67.562632)
			(xy 350.14179 -67.596973) (xy 350.096556 -67.625288) (xy 350.047819 -67.647026) (xy 349.996529 -67.661763)
			(xy 349.943686 -67.669212) (xy 349.917004 -67.669664) (xy 349.889748 -67.669289) (xy 349.83579 -67.661532)
			(xy 349.783486 -67.646174) (xy 349.733899 -67.62353) (xy 349.68804 -67.594058) (xy 349.646842 -67.55836)
			(xy 349.611144 -67.517163) (xy 349.581672 -67.471304) (xy 349.559027 -67.421718) (xy 349.543669 -67.369414)
			(xy 349.535911 -67.315456) (xy 341.561542 -67.315456) (xy 344.146886 -69.9008) (xy 351.72269 -69.9008)
			(xy 351.723155 -69.87416) (xy 351.73058 -69.8214) (xy 351.745273 -69.770186) (xy 351.766947 -69.721514)
			(xy 351.795181 -69.67633) (xy 351.829425 -69.635513) (xy 351.869015 -69.599856) (xy 351.890838 -69.58457)
			(xy 351.902304 -69.576384) (xy 351.920529 -69.55491) (xy 351.932194 -69.529274) (xy 351.936413 -69.501427)
			(xy 351.932864 -69.473487) (xy 351.921819 -69.447578) (xy 351.904116 -69.425673) (xy 351.89287 -69.417184)
			(xy 351.871888 -69.401762) (xy 351.833856 -69.366196) (xy 351.801012 -69.325789) (xy 351.773966 -69.281293)
			(xy 351.753219 -69.233534) (xy 351.739157 -69.183398) (xy 351.732041 -69.131815) (xy 351.73158 -69.10578)
			(xy 351.73158 -68.24218) (xy 351.732134 -68.212949) (xy 351.741068 -68.155174) (xy 351.75871 -68.099437)
			(xy 351.784646 -68.047043) (xy 351.81827 -67.999217) (xy 351.858794 -67.95708) (xy 351.881694 -67.938904)
			(xy 351.89219 -67.930388) (xy 351.908546 -67.908876) (xy 351.918694 -67.883829) (xy 351.921924 -67.856999)
			(xy 351.918012 -67.83026) (xy 351.90723 -67.80548) (xy 351.890332 -67.78439) (xy 351.879662 -67.77609)
			(xy 351.855817 -67.757941) (xy 351.813496 -67.715524) (xy 351.778319 -67.667018) (xy 351.751148 -67.613613)
			(xy 351.732651 -67.556621) (xy 351.723281 -67.497439) (xy 351.72269 -67.46748) (xy 351.723176 -67.440229)
			(xy 351.730932 -67.386281) (xy 351.746287 -67.333986) (xy 351.768929 -67.284409) (xy 351.798395 -67.238559)
			(xy 351.834086 -67.197368) (xy 351.875277 -67.161677) (xy 351.921127 -67.132211) (xy 351.970704 -67.109569)
			(xy 352.022999 -67.094214) (xy 352.076947 -67.086458) (xy 352.131449 -67.086458) (xy 352.185397 -67.094214)
			(xy 352.237692 -67.109569) (xy 352.287269 -67.132211) (xy 352.333119 -67.161677) (xy 352.37431 -67.197368)
			(xy 352.410001 -67.238559) (xy 352.439467 -67.284409) (xy 352.462109 -67.333986) (xy 352.477464 -67.386281)
			(xy 352.48522 -67.440229) (xy 352.485706 -67.46748) (xy 352.485167 -67.496682) (xy 352.476262 -67.554403)
			(xy 352.458657 -67.61009) (xy 352.432764 -67.662441) (xy 352.399189 -67.710229) (xy 352.358718 -67.752338)
			(xy 352.335846 -67.770502) (xy 352.325367 -67.779086) (xy 352.308931 -67.800602) (xy 352.298726 -67.825681)
			(xy 352.295468 -67.85256) (xy 352.299388 -67.879351) (xy 352.310209 -67.90417) (xy 352.327171 -67.925275)
			(xy 352.337878 -67.93357) (xy 352.358407 -67.949019) (xy 352.395541 -67.984528) (xy 352.427573 -68.024699)
			(xy 352.453923 -68.068806) (xy 352.474116 -68.11605) (xy 352.487785 -68.165577) (xy 352.494683 -68.216491)
			(xy 352.495104 -68.24218) (xy 352.495104 -68.372984) (xy 362.569743 -68.372984) (xy 362.577495 -68.319031)
			(xy 362.592846 -68.266731) (xy 362.615484 -68.217147) (xy 362.644948 -68.17129) (xy 362.680638 -68.130093)
			(xy 362.721828 -68.094395) (xy 362.767679 -68.064921) (xy 362.817258 -68.042273) (xy 362.869555 -68.026911)
			(xy 362.923507 -68.019149) (xy 362.95076 -68.01866) (xy 362.981002 -68.01924) (xy 363.040722 -68.028814)
			(xy 363.069632 -68.03771) (xy 363.083193 -68.041682) (xy 363.111422 -68.042741) (xy 363.13886 -68.036023)
			(xy 363.163406 -68.022041) (xy 363.183179 -68.001866) (xy 363.196664 -67.977043) (xy 363.202829 -67.949475)
			(xy 363.202474 -67.935348) (xy 363.201966 -67.914012) (xy 363.202523 -67.885125) (xy 363.21122 -67.828008)
			(xy 363.228432 -67.772857) (xy 363.253766 -67.720933) (xy 363.286641 -67.673423) (xy 363.326305 -67.631416)
			(xy 363.371852 -67.595871) (xy 363.396784 -67.581272) (xy 363.408313 -67.574271) (xy 363.427549 -67.55538)
			(xy 363.44117 -67.532113) (xy 363.448229 -67.506093) (xy 363.448232 -67.479132) (xy 363.44118 -67.45311)
			(xy 363.427564 -67.42984) (xy 363.408333 -67.410945) (xy 363.396784 -67.40398) (xy 363.371828 -67.389397)
			(xy 363.326234 -67.353874) (xy 363.286521 -67.311879) (xy 363.253601 -67.264371) (xy 363.228225 -67.212441)
			(xy 363.210976 -67.157276) (xy 363.202249 -67.100139) (xy 363.201712 -67.07124) (xy 363.202198 -67.043989)
			(xy 363.209954 -66.990041) (xy 363.225309 -66.937746) (xy 363.247951 -66.888169) (xy 363.277417 -66.842319)
			(xy 363.313108 -66.801128) (xy 363.354299 -66.765437) (xy 363.400149 -66.735971) (xy 363.449726 -66.713329)
			(xy 363.502021 -66.697974) (xy 363.555969 -66.690218) (xy 363.610471 -66.690218) (xy 363.664419 -66.697974)
			(xy 363.716714 -66.713329) (xy 363.766291 -66.735971) (xy 363.812141 -66.765437) (xy 363.853332 -66.801128)
			(xy 363.889023 -66.842319) (xy 363.918489 -66.888169) (xy 363.941131 -66.937746) (xy 363.956486 -66.990041)
			(xy 363.964242 -67.043989) (xy 363.964728 -67.07124) (xy 371.303802 -67.07124) (xy 371.307873 -67.015618)
			(xy 371.319999 -66.961181) (xy 371.339922 -66.90909) (xy 371.367218 -66.860455) (xy 371.401304 -66.816312)
			(xy 371.441453 -66.777603) (xy 371.486811 -66.745152) (xy 371.536411 -66.719651) (xy 371.589195 -66.701644)
			(xy 371.644038 -66.691514) (xy 371.699772 -66.689477) (xy 371.755209 -66.695577) (xy 371.809166 -66.709683)
			(xy 371.860495 -66.731495) (xy 371.908101 -66.760549) (xy 371.950969 -66.796224) (xy 371.988186 -66.837761)
			(xy 372.018959 -66.884274) (xy 372.042631 -66.934771) (xy 372.058699 -66.988178) (xy 372.066819 -67.043354)
			(xy 372.067328 -67.07124) (xy 372.066819 -67.099126) (xy 372.058699 -67.154302) (xy 372.042631 -67.207709)
			(xy 372.018959 -67.258206) (xy 371.988186 -67.304719) (xy 371.950969 -67.346256) (xy 371.908101 -67.381931)
			(xy 371.860495 -67.410985) (xy 371.809166 -67.432797) (xy 371.755209 -67.446903) (xy 371.699772 -67.453003)
			(xy 371.644038 -67.450966) (xy 371.589195 -67.440836) (xy 371.536411 -67.422829) (xy 371.486811 -67.397328)
			(xy 371.441453 -67.364877) (xy 371.401304 -67.326168) (xy 371.367218 -67.282025) (xy 371.339922 -67.23339)
			(xy 371.319999 -67.181299) (xy 371.307873 -67.126862) (xy 371.303802 -67.07124) (xy 363.964728 -67.07124)
			(xy 363.964216 -67.100129) (xy 363.955511 -67.157248) (xy 363.938291 -67.2124) (xy 363.91295 -67.264325)
			(xy 363.880069 -67.311833) (xy 363.840398 -67.35384) (xy 363.794845 -67.389383) (xy 363.76991 -67.40398)
			(xy 363.758334 -67.410909) (xy 363.739096 -67.429813) (xy 363.725474 -67.453093) (xy 363.71842 -67.479127)
			(xy 363.718423 -67.506099) (xy 363.725484 -67.53213) (xy 363.738491 -67.554348) (xy 373.968262 -67.554348)
			(xy 373.972333 -67.498726) (xy 373.984459 -67.444289) (xy 374.004382 -67.392198) (xy 374.031678 -67.343563)
			(xy 374.065764 -67.29942) (xy 374.105913 -67.260711) (xy 374.151271 -67.22826) (xy 374.200871 -67.202759)
			(xy 374.253655 -67.184752) (xy 374.308498 -67.174622) (xy 374.364232 -67.172585) (xy 374.419669 -67.178685)
			(xy 374.473626 -67.192791) (xy 374.524955 -67.214603) (xy 374.572561 -67.243657) (xy 374.615429 -67.279332)
			(xy 374.652646 -67.320869) (xy 374.683419 -67.367382) (xy 374.707091 -67.417879) (xy 374.723159 -67.471286)
			(xy 374.731279 -67.526462) (xy 374.731788 -67.554348) (xy 374.731279 -67.582234) (xy 374.723159 -67.63741)
			(xy 374.707091 -67.690817) (xy 374.683419 -67.741314) (xy 374.652646 -67.787827) (xy 374.615429 -67.829364)
			(xy 374.572561 -67.865039) (xy 374.524955 -67.894093) (xy 374.473626 -67.915905) (xy 374.419669 -67.930011)
			(xy 374.364232 -67.936111) (xy 374.308498 -67.934074) (xy 374.253655 -67.923944) (xy 374.200871 -67.905937)
			(xy 374.151271 -67.880436) (xy 374.105913 -67.847985) (xy 374.065764 -67.809276) (xy 374.031678 -67.765133)
			(xy 374.004382 -67.716498) (xy 373.984459 -67.664407) (xy 373.972333 -67.60997) (xy 373.968262 -67.554348)
			(xy 363.738491 -67.554348) (xy 363.739111 -67.555407) (xy 363.758355 -67.574306) (xy 363.76991 -67.581272)
			(xy 363.794887 -67.595821) (xy 363.840482 -67.631348) (xy 363.880194 -67.67335) (xy 363.913113 -67.720863)
			(xy 363.938484 -67.772799) (xy 363.955728 -67.82797) (xy 363.964449 -67.885111) (xy 363.964982 -67.914012)
			(xy 363.964556 -67.941266) (xy 363.956797 -67.99522) (xy 363.941438 -68.04752) (xy 363.918792 -68.097102)
			(xy 363.889321 -68.142957) (xy 363.853623 -68.18415) (xy 363.812426 -68.219843) (xy 363.766569 -68.24931)
			(xy 363.716985 -68.271951) (xy 363.664683 -68.287305) (xy 363.610728 -68.295059) (xy 363.583474 -68.29552)
			(xy 363.553233 -68.294933) (xy 363.493512 -68.285364) (xy 363.464602 -68.27647) (xy 363.451026 -68.272557)
			(xy 363.422806 -68.271491) (xy 363.395374 -68.278201) (xy 363.370833 -68.292174) (xy 363.351062 -68.312338)
			(xy 363.337576 -68.33715) (xy 363.331408 -68.364709) (xy 363.33176 -68.378832) (xy 363.332268 -68.400168)
			(xy 363.331856 -68.427421) (xy 363.324104 -68.481374) (xy 363.308752 -68.533674) (xy 363.286113 -68.583257)
			(xy 363.256649 -68.629114) (xy 363.220958 -68.670311) (xy 363.179767 -68.706009) (xy 363.133916 -68.735481)
			(xy 363.084337 -68.758129) (xy 363.032039 -68.77349) (xy 362.978088 -68.781252) (xy 362.923581 -68.781257)
			(xy 362.869628 -68.773504) (xy 362.817328 -68.758153) (xy 362.767745 -68.735515) (xy 362.721888 -68.70605)
			(xy 362.680691 -68.67036) (xy 362.644993 -68.62917) (xy 362.61552 -68.583318) (xy 362.592872 -68.533739)
			(xy 362.577511 -68.481442) (xy 362.569749 -68.427491) (xy 362.569743 -68.372984) (xy 352.495104 -68.372984)
			(xy 352.495104 -69.10578) (xy 352.49465 -69.13245) (xy 352.487234 -69.185271) (xy 352.472531 -69.236544)
			(xy 352.450827 -69.285268) (xy 352.422546 -69.330493) (xy 352.388239 -69.371336) (xy 352.348576 -69.407)
			(xy 352.326702 -69.422264) (xy 352.315274 -69.430445) (xy 352.297137 -69.451905) (xy 352.285531 -69.477494)
			(xy 352.281335 -69.505277) (xy 352.284865 -69.533152) (xy 352.295854 -69.559012) (xy 352.313472 -69.5809)
			(xy 352.32467 -69.589396) (xy 352.328574 -69.592254) (xy 371.350467 -69.592254) (xy 371.350467 -69.537746)
			(xy 371.358225 -69.483793) (xy 371.373583 -69.431494) (xy 371.396227 -69.381913) (xy 371.425698 -69.336059)
			(xy 371.461395 -69.294867) (xy 371.502591 -69.259174) (xy 371.548448 -69.229708) (xy 371.598032 -69.207069)
			(xy 371.650333 -69.191717) (xy 371.704286 -69.183965) (xy 371.73154 -69.183504) (xy 371.758143 -69.183997)
			(xy 371.810834 -69.19137) (xy 371.861989 -69.205997) (xy 371.910613 -69.227592) (xy 371.955764 -69.255737)
			(xy 371.996565 -69.289885) (xy 372.032222 -69.329373) (xy 372.047516 -69.351144) (xy 372.05585 -69.362624)
			(xy 372.077594 -69.380828) (xy 372.103507 -69.392346) (xy 372.13159 -69.396286) (xy 372.159673 -69.392346)
			(xy 372.185586 -69.380828) (xy 372.20733 -69.362624) (xy 372.215664 -69.351144) (xy 372.230971 -69.329383)
			(xy 372.266635 -69.289903) (xy 372.307437 -69.255759) (xy 372.352584 -69.227612) (xy 372.401204 -69.206009)
			(xy 372.452352 -69.191366) (xy 372.505039 -69.183969) (xy 372.53164 -69.183504) (xy 372.55889 -69.183969)
			(xy 372.612835 -69.19173) (xy 372.665127 -69.207089) (xy 372.714701 -69.229733) (xy 372.760548 -69.259201)
			(xy 372.801734 -69.294894) (xy 372.837423 -69.336085) (xy 372.866886 -69.381934) (xy 372.889525 -69.431511)
			(xy 372.904879 -69.483804) (xy 372.912634 -69.53775) (xy 372.912634 -69.59225) (xy 372.904879 -69.646196)
			(xy 372.889525 -69.698489) (xy 372.866886 -69.748066) (xy 372.837423 -69.793915) (xy 372.801734 -69.835106)
			(xy 372.760548 -69.870799) (xy 372.714701 -69.900267) (xy 372.665127 -69.922911) (xy 372.612835 -69.93827)
			(xy 372.55889 -69.946031) (xy 372.53164 -69.94652) (xy 372.505037 -69.946032) (xy 372.452346 -69.938656)
			(xy 372.401192 -69.924028) (xy 372.352568 -69.902432) (xy 372.307417 -69.874286) (xy 372.266616 -69.840139)
			(xy 372.230958 -69.800651) (xy 372.215664 -69.77888) (xy 372.20733 -69.7674) (xy 372.185586 -69.749196)
			(xy 372.159673 -69.737678) (xy 372.13159 -69.733738) (xy 372.103507 -69.737678) (xy 372.077594 -69.749196)
			(xy 372.05585 -69.7674) (xy 372.047516 -69.77888) (xy 372.032229 -69.800656) (xy 371.996561 -69.840134)
			(xy 371.955756 -69.874276) (xy 371.910604 -69.902421) (xy 371.861982 -69.924022) (xy 371.810831 -69.938662)
			(xy 371.758142 -69.946056) (xy 371.73154 -69.94652) (xy 371.704286 -69.946035) (xy 371.650333 -69.938283)
			(xy 371.598032 -69.922931) (xy 371.548448 -69.900292) (xy 371.502591 -69.870826) (xy 371.461395 -69.835133)
			(xy 371.425698 -69.793941) (xy 371.396227 -69.748087) (xy 371.373583 -69.698506) (xy 371.358225 -69.646207)
			(xy 371.350467 -69.592254) (xy 352.328574 -69.592254) (xy 352.345676 -69.604772) (xy 352.383666 -69.640364)
			(xy 352.416466 -69.680789) (xy 352.443468 -69.725297) (xy 352.464171 -69.773061) (xy 352.478189 -69.823196)
			(xy 352.485265 -69.874771) (xy 352.485706 -69.9008) (xy 352.48522 -69.928051) (xy 352.477464 -69.981999)
			(xy 352.462109 -70.034294) (xy 352.439467 -70.083871) (xy 352.410001 -70.129721) (xy 352.37431 -70.170912)
			(xy 352.333119 -70.206603) (xy 352.287269 -70.236069) (xy 352.237692 -70.258711) (xy 352.185397 -70.274066)
			(xy 352.131449 -70.281822) (xy 352.076947 -70.281822) (xy 352.022999 -70.274066) (xy 351.970704 -70.258711)
			(xy 351.921127 -70.236069) (xy 351.875277 -70.206603) (xy 351.834086 -70.170912) (xy 351.798395 -70.129721)
			(xy 351.768929 -70.083871) (xy 351.746287 -70.034294) (xy 351.730932 -69.981999) (xy 351.723176 -69.928051)
			(xy 351.72269 -69.9008) (xy 344.146886 -69.9008) (xy 344.901266 -70.65518) (xy 368.850162 -70.65518)
			(xy 368.854233 -70.599558) (xy 368.866359 -70.545121) (xy 368.886282 -70.49303) (xy 368.913578 -70.444395)
			(xy 368.947664 -70.400252) (xy 368.987813 -70.361543) (xy 369.033171 -70.329092) (xy 369.082771 -70.303591)
			(xy 369.135555 -70.285584) (xy 369.190398 -70.275454) (xy 369.246132 -70.273417) (xy 369.301569 -70.279517)
			(xy 369.355526 -70.293623) (xy 369.406855 -70.315435) (xy 369.454461 -70.344489) (xy 369.497329 -70.380164)
			(xy 369.534546 -70.421701) (xy 369.565319 -70.468214) (xy 369.588991 -70.518711) (xy 369.605059 -70.572118)
			(xy 369.613179 -70.627294) (xy 369.613688 -70.65518) (xy 369.613179 -70.683066) (xy 369.605059 -70.738242)
			(xy 369.588991 -70.791649) (xy 369.565319 -70.842146) (xy 369.534546 -70.888659) (xy 369.497329 -70.930196)
			(xy 369.454461 -70.965871) (xy 369.406855 -70.994925) (xy 369.355526 -71.016737) (xy 369.301569 -71.030843)
			(xy 369.246132 -71.036943) (xy 369.190398 -71.034906) (xy 369.135555 -71.024776) (xy 369.082771 -71.006769)
			(xy 369.033171 -70.981268) (xy 368.987813 -70.948817) (xy 368.947664 -70.910108) (xy 368.913578 -70.865965)
			(xy 368.886282 -70.81733) (xy 368.866359 -70.765239) (xy 368.854233 -70.710802) (xy 368.850162 -70.65518)
			(xy 344.901266 -70.65518) (xy 345.248484 -71.002398) (xy 346.041726 -71.002398) (xy 346.052902 -70.966838)
			(xy 346.061936 -70.939879) (xy 346.086862 -70.888779) (xy 346.119095 -70.841943) (xy 346.15792 -70.800408)
			(xy 346.202479 -70.765094) (xy 346.251783 -70.736782) (xy 346.304744 -70.7161) (xy 346.360186 -70.703504)
			(xy 346.416884 -70.699274) (xy 346.473582 -70.703504) (xy 346.529024 -70.7161) (xy 346.581985 -70.736782)
			(xy 346.631289 -70.765094) (xy 346.675848 -70.800408) (xy 346.714673 -70.841943) (xy 346.746906 -70.888779)
			(xy 346.771832 -70.939879) (xy 346.780866 -70.966838) (xy 346.792042 -71.002398) (xy 347.565726 -71.002398)
			(xy 347.576902 -70.966838) (xy 347.585936 -70.939879) (xy 347.610862 -70.888779) (xy 347.643095 -70.841943)
			(xy 347.68192 -70.800408) (xy 347.726479 -70.765094) (xy 347.775783 -70.736782) (xy 347.828744 -70.7161)
			(xy 347.884186 -70.703504) (xy 347.940884 -70.699274) (xy 347.997582 -70.703504) (xy 348.053024 -70.7161)
			(xy 348.105985 -70.736782) (xy 348.155289 -70.765094) (xy 348.199848 -70.800408) (xy 348.238673 -70.841943)
			(xy 348.270906 -70.888779) (xy 348.295832 -70.939879) (xy 348.304866 -70.966838) (xy 348.316042 -71.002398)
			(xy 348.596204 -71.002398) (xy 353.082606 -75.4888) (xy 369.340382 -75.4888) (xy 369.344453 -75.433178)
			(xy 369.356579 -75.378741) (xy 369.376502 -75.32665) (xy 369.403798 -75.278015) (xy 369.437884 -75.233872)
			(xy 369.478033 -75.195163) (xy 369.523391 -75.162712) (xy 369.572991 -75.137211) (xy 369.625775 -75.119204)
			(xy 369.680618 -75.109074) (xy 369.736352 -75.107037) (xy 369.791789 -75.113137) (xy 369.845746 -75.127243)
			(xy 369.897075 -75.149055) (xy 369.944681 -75.178109) (xy 369.987549 -75.213784) (xy 370.024766 -75.255321)
			(xy 370.055539 -75.301834) (xy 370.079211 -75.352331) (xy 370.095279 -75.405738) (xy 370.103399 -75.460914)
			(xy 370.103908 -75.4888) (xy 370.103399 -75.516686) (xy 370.095279 -75.571862) (xy 370.079211 -75.625269)
			(xy 370.055539 -75.675766) (xy 370.024766 -75.722279) (xy 369.987549 -75.763816) (xy 369.944681 -75.799491)
			(xy 369.897075 -75.828545) (xy 369.845746 -75.850357) (xy 369.791789 -75.864463) (xy 369.736352 -75.870563)
			(xy 369.680618 -75.868526) (xy 369.625775 -75.858396) (xy 369.572991 -75.840389) (xy 369.523391 -75.814888)
			(xy 369.478033 -75.782437) (xy 369.437884 -75.743728) (xy 369.403798 -75.699585) (xy 369.376502 -75.65095)
			(xy 369.356579 -75.598859) (xy 369.344453 -75.544422) (xy 369.340382 -75.4888) (xy 353.082606 -75.4888)
			(xy 360.037634 -82.443828)
		)
		(stroke
			(width 0)
			(type solid)
		)
		(fill yes)
		(layer "In11.Cu")
		(net "P1V8_PCH_AUX")
	)
	(gr_poly
		(pts
			(xy 342.6206 -326.227948) (xy 371.6782 -326.227948) (xy 375.031 -329.580748) (xy 379.8824 -329.580748)
			(xy 382.7018 -332.400148) (xy 390.0424 -332.400148) (xy 390.652 -331.790548) (xy 390.652 -316.677548)
			(xy 373.2276 -299.253148) (xy 373.2276 -296.433748) (xy 370.205 -293.411148) (xy 369.1128 -293.411148)
			(xy 368.2492 -292.547548) (xy 366.8014 -292.547548) (xy 365.887 -291.633148) (xy 365.887 -283.251148)
			(xy 364.5662 -281.930348) (xy 364.5662 -280.93162) (xy 364.56112 -280.921206) (xy 364.550918 -280.898809)
			(xy 364.536528 -280.851745) (xy 364.529293 -280.803066) (xy 364.528862 -280.778458) (xy 364.528862 -280.77795)
			(xy 364.5293 -280.753344) (xy 364.536559 -280.704671) (xy 364.550939 -280.657607) (xy 364.56112 -280.635202)
			(xy 364.5662 -280.624788) (xy 364.5662 -280.389584) (xy 364.565729 -280.375016) (xy 364.55751 -280.347065)
			(xy 364.541742 -280.322565) (xy 364.519706 -280.303505) (xy 364.49319 -280.291432) (xy 364.464345 -280.287326)
			(xy 364.449868 -280.289) (xy 364.434891 -280.291612) (xy 364.404618 -280.294414) (xy 364.389416 -280.294588)
			(xy 364.363443 -280.294106) (xy 364.312137 -280.285982) (xy 364.262733 -280.269932) (xy 364.216449 -280.246351)
			(xy 364.174423 -280.215819) (xy 364.137691 -280.179089) (xy 364.107157 -280.137065) (xy 364.083574 -280.090782)
			(xy 364.067521 -280.041379) (xy 364.059395 -279.990073) (xy 364.059395 -279.938127) (xy 364.067521 -279.886821)
			(xy 364.083574 -279.837418) (xy 364.107157 -279.791135) (xy 364.137691 -279.749111) (xy 364.174423 -279.712381)
			(xy 364.216449 -279.681849) (xy 364.262733 -279.658268) (xy 364.312137 -279.642218) (xy 364.363443 -279.634094)
			(xy 364.389416 -279.63368) (xy 364.404618 -279.633851) (xy 364.434893 -279.636648) (xy 364.449868 -279.639268)
			(xy 364.464348 -279.640916) (xy 364.493192 -279.636831) (xy 364.519709 -279.624769) (xy 364.541741 -279.60571)
			(xy 364.557495 -279.581206) (xy 364.565688 -279.55325) (xy 364.5662 -279.538684) (xy 364.5662 -279.30348)
			(xy 364.56112 -279.293066) (xy 364.550914 -279.270669) (xy 364.536516 -279.223607) (xy 364.529272 -279.174927)
			(xy 364.528862 -279.150318) (xy 364.528862 -279.14981) (xy 364.529296 -279.125203) (xy 364.536546 -279.076527)
			(xy 364.550919 -279.029459) (xy 364.56112 -279.007062) (xy 364.5662 -278.996648) (xy 364.5662 -278.761698)
			(xy 364.565697 -278.74699) (xy 364.557295 -278.718799) (xy 364.541217 -278.694164) (xy 364.518792 -278.675126)
			(xy 364.491876 -278.663257) (xy 364.462695 -278.659541) (xy 364.44809 -278.661368) (xy 364.433486 -278.663862)
			(xy 364.403977 -278.666528) (xy 364.389162 -278.666702) (xy 364.363193 -278.66619) (xy 364.311895 -278.65806)
			(xy 364.2625 -278.642005) (xy 364.216225 -278.618422) (xy 364.174208 -278.587891) (xy 364.137485 -278.551163)
			(xy 364.106958 -278.509142) (xy 364.08338 -278.462864) (xy 364.067332 -278.413468) (xy 364.059207 -278.362169)
			(xy 364.059207 -278.310231) (xy 364.067332 -278.258932) (xy 364.08338 -278.209536) (xy 364.106958 -278.163258)
			(xy 364.137485 -278.121237) (xy 364.174208 -278.084509) (xy 364.216225 -278.053978) (xy 364.2625 -278.030395)
			(xy 364.311895 -278.01434) (xy 364.363193 -278.00621) (xy 364.389162 -278.005794) (xy 364.403977 -278.00597)
			(xy 364.433486 -278.008636) (xy 364.44809 -278.011128) (xy 364.462693 -278.013034) (xy 364.491897 -278.009338)
			(xy 364.518834 -277.997466) (xy 364.541268 -277.978406) (xy 364.557335 -277.95374) (xy 364.565701 -277.925517)
			(xy 364.5662 -277.910798) (xy 364.5662 -277.675848) (xy 364.560866 -277.665434) (xy 364.550613 -277.643002)
			(xy 364.536125 -277.59586) (xy 364.528798 -277.547088) (xy 364.528793 -277.497769) (xy 364.536112 -277.448997)
			(xy 364.550592 -277.401851) (xy 364.560866 -277.37943) (xy 364.5662 -277.369016) (xy 364.5662 -277.133812)
			(xy 364.565698 -277.119103) (xy 364.557299 -277.090908) (xy 364.541222 -277.06627) (xy 364.518796 -277.047228)
			(xy 364.491878 -277.035358) (xy 364.462694 -277.031641) (xy 364.44809 -277.033482) (xy 364.433486 -277.035976)
			(xy 364.403977 -277.038644) (xy 364.389162 -277.038816) (xy 364.3632 -277.038304) (xy 364.311915 -277.030176)
			(xy 364.262533 -277.014126) (xy 364.21627 -276.990549) (xy 364.174264 -276.960025) (xy 364.13755 -276.923307)
			(xy 364.107031 -276.881298) (xy 364.08346 -276.835031) (xy 364.067415 -276.785648) (xy 364.059293 -276.734362)
			(xy 364.059293 -276.682438) (xy 364.067415 -276.631152) (xy 364.08346 -276.581769) (xy 364.107031 -276.535502)
			(xy 364.13755 -276.493493) (xy 364.174264 -276.456775) (xy 364.21627 -276.426251) (xy 364.262533 -276.402674)
			(xy 364.311915 -276.386624) (xy 364.3632 -276.378496) (xy 364.389162 -276.377908) (xy 364.403977 -276.378084)
			(xy 364.433486 -276.380751) (xy 364.44809 -276.383242) (xy 364.462694 -276.385149) (xy 364.491899 -276.381452)
			(xy 364.518838 -276.369581) (xy 364.541274 -276.350521) (xy 364.557344 -276.325856) (xy 364.565713 -276.297632)
			(xy 364.5662 -276.282912) (xy 364.5662 -276.047962) (xy 364.56112 -276.037548) (xy 364.550915 -276.015151)
			(xy 364.536519 -275.968088) (xy 364.529278 -275.919408) (xy 364.528862 -275.8948) (xy 364.528862 -275.894292)
			(xy 364.529297 -275.869685) (xy 364.53655 -275.82101) (xy 364.550925 -275.773943) (xy 364.56112 -275.751544)
			(xy 364.5662 -275.74113) (xy 364.5662 -275.50618) (xy 364.565707 -275.491464) (xy 364.55732 -275.463252)
			(xy 364.541245 -275.438596) (xy 364.518815 -275.41954) (xy 364.491886 -275.40766) (xy 364.46269 -275.403942)
			(xy 364.44809 -275.40585) (xy 364.433486 -275.408344) (xy 364.403977 -275.411011) (xy 364.389162 -275.411184)
			(xy 364.363194 -275.410672) (xy 364.311899 -275.402542) (xy 364.262507 -275.386489) (xy 364.216234 -275.362907)
			(xy 364.17422 -275.332377) (xy 364.137498 -275.295651) (xy 364.106973 -275.253633) (xy 364.083397 -275.207358)
			(xy 364.067349 -275.157964) (xy 364.059225 -275.106668) (xy 364.059225 -275.054732) (xy 364.067349 -275.003436)
			(xy 364.083397 -274.954042) (xy 364.106973 -274.907767) (xy 364.137498 -274.865749) (xy 364.17422 -274.829023)
			(xy 364.216234 -274.798493) (xy 364.262507 -274.774911) (xy 364.311899 -274.758858) (xy 364.363194 -274.750728)
			(xy 364.389162 -274.750276) (xy 364.403977 -274.750452) (xy 364.433486 -274.753118) (xy 364.44809 -274.75561)
			(xy 364.462692 -274.757517) (xy 364.491895 -274.75382) (xy 364.51883 -274.741948) (xy 364.541261 -274.722887)
			(xy 364.557324 -274.698221) (xy 364.565686 -274.669998) (xy 364.5662 -274.65528) (xy 364.5662 -274.513294)
			(xy 364.397036 -274.34413) (xy 364.386597 -274.33435) (xy 364.361582 -274.3205) (xy 364.333709 -274.314125)
			(xy 364.305161 -274.315727) (xy 364.278175 -274.325179) (xy 364.254867 -274.341741) (xy 364.237063 -274.364114)
			(xy 364.231174 -274.37715) (xy 364.222233 -274.400969) (xy 364.19809 -274.445751) (xy 364.167375 -274.486308)
			(xy 364.130812 -274.521684) (xy 364.089264 -274.551045) (xy 364.043711 -274.573699) (xy 363.995226 -274.589111)
			(xy 363.944954 -274.596918) (xy 363.919516 -274.597368) (xy 363.893545 -274.596886) (xy 363.842244 -274.588763)
			(xy 363.792844 -274.572715) (xy 363.746563 -274.549137) (xy 363.704541 -274.518608) (xy 363.667811 -274.481882)
			(xy 363.637279 -274.439862) (xy 363.613696 -274.393584) (xy 363.597644 -274.344186) (xy 363.589516 -274.292884)
			(xy 363.589062 -274.266914) (xy 363.589528 -274.241475) (xy 363.59732 -274.191198) (xy 363.612721 -274.142708)
			(xy 363.635369 -274.097149) (xy 363.664728 -274.055597) (xy 363.700106 -274.019033) (xy 363.740667 -273.98832)
			(xy 363.785455 -273.964183) (xy 363.80928 -273.955256) (xy 363.822331 -273.949379) (xy 363.844744 -273.9316)
			(xy 363.861336 -273.908294) (xy 363.870799 -273.881296) (xy 363.87239 -273.852731) (xy 363.865983 -273.824849)
			(xy 363.852081 -273.799845) (xy 363.8423 -273.789394) (xy 363.712252 -273.659346) (xy 363.676184 -273.693382)
			(xy 363.657678 -273.710216) (xy 363.616539 -273.73868) (xy 363.57158 -273.760619) (xy 363.523828 -273.775533)
			(xy 363.474375 -273.78308) (xy 363.449362 -273.783552) (xy 363.435392 -273.783298) (xy 363.42828 -273.78279)
			(xy 363.403451 -273.780748) (xy 363.354775 -273.77014) (xy 363.308242 -273.752349) (xy 363.264906 -273.727777)
			(xy 363.225748 -273.69698) (xy 363.191654 -273.660655) (xy 363.163397 -273.619626) (xy 363.141617 -273.574822)
			(xy 363.126807 -273.527256) (xy 363.119302 -273.478007) (xy 363.118908 -273.453098) (xy 363.118908 -273.445986)
			(xy 363.119846 -273.422564) (xy 363.127509 -273.37632) (xy 363.141618 -273.331619) (xy 363.161891 -273.289356)
			(xy 363.187923 -273.250374) (xy 363.203236 -273.232626) (xy 363.209078 -273.226022) (xy 363.229144 -273.176238)
			(xy 363.020864 -272.967958) (xy 362.998004 -272.969228) (xy 362.979716 -272.969736) (xy 362.979462 -272.969736)
			(xy 362.953015 -272.969212) (xy 362.900797 -272.960783) (xy 362.850588 -272.944145) (xy 362.803669 -272.919723)
			(xy 362.761238 -272.888141) (xy 362.724379 -272.850205) (xy 362.694031 -272.806882) (xy 362.670971 -272.75928)
			(xy 362.655785 -272.708613) (xy 362.651802 -272.682462) (xy 362.649008 -272.660872) (xy 362.649008 -272.639282)
			(xy 362.649516 -272.620994) (xy 362.650786 -272.59788) (xy 362.018072 -271.965166) (xy 362.008297 -271.95602)
			(xy 361.985066 -271.942735) (xy 361.959181 -271.935938) (xy 361.93242 -271.936096) (xy 361.906618 -271.943199)
			(xy 361.883546 -271.956758) (xy 361.864787 -271.975844) (xy 361.857798 -271.987264) (xy 361.845142 -272.008823)
			(xy 361.814347 -272.0482) (xy 361.777971 -272.082488) (xy 361.736843 -272.110903) (xy 361.691904 -272.132796)
			(xy 361.644178 -272.147669) (xy 361.594757 -272.15518) (xy 361.569762 -272.155666) (xy 361.543796 -272.155154)
			(xy 361.492505 -272.147025) (xy 361.443117 -272.130973) (xy 361.396847 -272.107394) (xy 361.354836 -272.076867)
			(xy 361.318116 -272.040144) (xy 361.287593 -271.99813) (xy 361.264017 -271.951859) (xy 361.247969 -271.902469)
			(xy 361.239844 -271.851178) (xy 361.239308 -271.825212) (xy 361.239398 -271.812462) (xy 361.241303 -271.787033)
			(xy 361.243118 -271.774412) (xy 361.24739 -271.750072) (xy 361.262206 -271.702929) (xy 361.283873 -271.658516)
			(xy 361.311909 -271.617822) (xy 361.345689 -271.581754) (xy 361.38446 -271.551115) (xy 361.405678 -271.538446)
			(xy 361.417451 -271.531681) (xy 361.437191 -271.513052) (xy 361.451331 -271.489883) (xy 361.458873 -271.46381)
			(xy 361.459286 -271.43667) (xy 361.45254 -271.410379) (xy 361.439111 -271.386791) (xy 361.429808 -271.376902)
			(xy 361.213654 -271.160748) (xy 361.213654 -263.852406) (xy 361.260136 -263.805924) (xy 361.252008 -263.777222)
			(xy 361.246085 -263.755021) (xy 361.239714 -263.709518) (xy 361.239308 -263.686544) (xy 361.239788 -263.660571)
			(xy 361.247907 -263.609265) (xy 361.263952 -263.55986) (xy 361.287529 -263.513573) (xy 361.318056 -263.471545)
			(xy 361.354783 -263.43481) (xy 361.396803 -263.404272) (xy 361.443084 -263.380684) (xy 361.492485 -263.364626)
			(xy 361.543789 -263.356494) (xy 361.569762 -263.35609) (xy 361.592736 -263.356485) (xy 361.638241 -263.36286)
			(xy 361.66044 -263.36879) (xy 361.689142 -263.376918) (xy 364.274354 -260.791706) (xy 366.635284 -260.791706)
			(xy 368.646964 -258.780026) (xy 368.646964 -258.643628) (xy 368.638836 -258.630928) (xy 368.626267 -258.610778)
			(xy 368.606414 -258.567637) (xy 368.592949 -258.522096) (xy 368.586149 -258.475095) (xy 368.58575 -258.45135)
			(xy 368.586232 -258.425799) (xy 368.594111 -258.375308) (xy 368.609674 -258.326633) (xy 368.632549 -258.280936)
			(xy 368.646964 -258.259834) (xy 368.646964 -257.474466) (xy 368.632527 -257.453374) (xy 368.609644 -257.407674)
			(xy 368.594075 -257.358994) (xy 368.586194 -257.308495) (xy 368.586187 -257.257386) (xy 368.594056 -257.206886)
			(xy 368.609613 -257.158201) (xy 368.632485 -257.112496) (xy 368.646964 -257.091434) (xy 368.646964 -256.854706)
			(xy 368.633114 -256.833879) (xy 368.611181 -256.78893) (xy 368.596272 -256.741188) (xy 368.588729 -256.691745)
			(xy 368.588723 -256.64173) (xy 368.596255 -256.592286) (xy 368.611153 -256.544541) (xy 368.633076 -256.499586)
			(xy 368.646964 -256.478786) (xy 368.646964 -255.721866) (xy 368.632527 -255.700774) (xy 368.609644 -255.655074)
			(xy 368.594075 -255.606394) (xy 368.586194 -255.555895) (xy 368.586187 -255.504786) (xy 368.594056 -255.454286)
			(xy 368.609613 -255.405601) (xy 368.632485 -255.359896) (xy 368.646964 -255.338834) (xy 368.646964 -255.137666)
			(xy 368.632527 -255.116574) (xy 368.609644 -255.070874) (xy 368.594075 -255.022194) (xy 368.586194 -254.971695)
			(xy 368.586187 -254.920586) (xy 368.594056 -254.870086) (xy 368.609613 -254.821401) (xy 368.632485 -254.775696)
			(xy 368.646964 -254.754634) (xy 368.646964 -253.385066) (xy 368.632527 -253.363974) (xy 368.609644 -253.318274)
			(xy 368.594075 -253.269594) (xy 368.586194 -253.219095) (xy 368.586187 -253.167986) (xy 368.594056 -253.117486)
			(xy 368.609613 -253.068801) (xy 368.632485 -253.023096) (xy 368.646964 -253.002034) (xy 368.646964 -252.800866)
			(xy 368.632527 -252.779774) (xy 368.609644 -252.734074) (xy 368.594075 -252.685394) (xy 368.586194 -252.634895)
			(xy 368.586187 -252.583786) (xy 368.594056 -252.533286) (xy 368.609613 -252.484601) (xy 368.632485 -252.438896)
			(xy 368.646964 -252.417834) (xy 368.646964 -251.632466) (xy 368.632527 -251.611374) (xy 368.609644 -251.565674)
			(xy 368.594075 -251.516994) (xy 368.586194 -251.466495) (xy 368.586187 -251.415386) (xy 368.594056 -251.364886)
			(xy 368.609613 -251.316201) (xy 368.632485 -251.270496) (xy 368.646964 -251.249434) (xy 368.646964 -251.048266)
			(xy 368.632527 -251.027174) (xy 368.609644 -250.981474) (xy 368.594075 -250.932794) (xy 368.586194 -250.882295)
			(xy 368.586187 -250.831186) (xy 368.594056 -250.780686) (xy 368.609613 -250.732001) (xy 368.632485 -250.686296)
			(xy 368.646964 -250.665234) (xy 368.646964 -249.279918) (xy 368.640614 -249.268234) (xy 368.627367 -249.243437)
			(xy 368.608585 -249.190452) (xy 368.599044 -249.135052) (xy 368.59845 -249.106944) (xy 368.599035 -249.078836)
			(xy 368.608583 -249.023436) (xy 368.627361 -248.970448) (xy 368.640614 -248.945654) (xy 368.646964 -248.93397)
			(xy 368.646964 -248.548906) (xy 368.629343 -248.528551) (xy 368.600277 -248.483238) (xy 368.578946 -248.433809)
			(xy 368.565916 -248.381575) (xy 368.561532 -248.327919) (xy 368.56591 -248.274263) (xy 368.578934 -248.222027)
			(xy 368.600258 -248.172596) (xy 368.629319 -248.127279) (xy 368.646964 -248.106946) (xy 368.646964 -247.543066)
			(xy 368.632527 -247.521974) (xy 368.609644 -247.476274) (xy 368.594075 -247.427594) (xy 368.586194 -247.377095)
			(xy 368.586187 -247.325986) (xy 368.594056 -247.275486) (xy 368.609613 -247.226801) (xy 368.632485 -247.181096)
			(xy 368.646964 -247.160034) (xy 368.646964 -246.958866) (xy 368.63782 -246.945404) (xy 368.625374 -246.924576)
			(xy 368.619024 -246.912892) (xy 368.574066 -246.884698) (xy 368.539522 -246.898414) (xy 368.532664 -246.90451)
			(xy 368.51437 -246.920442) (xy 368.473987 -246.947323) (xy 368.430107 -246.968007) (xy 368.383674 -246.982051)
			(xy 368.335685 -246.989151) (xy 368.31143 -246.9896) (xy 368.29238 -246.989092) (xy 368.292126 -246.989092)
			(xy 368.265029 -246.986953) (xy 368.212021 -246.97495) (xy 368.161686 -246.954446) (xy 368.115378 -246.925994)
			(xy 368.094514 -246.908574) (xy 368.08283 -246.898414) (xy 368.071274 -246.889777) (xy 368.044636 -246.878734)
			(xy 368.015972 -246.87559) (xy 367.987574 -246.880597) (xy 367.961713 -246.893354) (xy 367.95075 -246.902732)
			(xy 367.932246 -246.919092) (xy 367.891293 -246.946699) (xy 367.846686 -246.967901) (xy 367.799419 -246.982223)
			(xy 367.750547 -246.989348) (xy 367.701158 -246.989117) (xy 367.676684 -246.98579) (xy 367.653776 -246.981844)
			(xy 367.609288 -246.96837) (xy 367.567125 -246.948801) (xy 367.528116 -246.923521) (xy 367.510314 -246.908574)
			(xy 367.50498 -246.903748) (xy 367.50371 -246.902732) (xy 367.49275 -246.89335) (xy 367.466895 -246.880578)
			(xy 367.438497 -246.875571) (xy 367.409833 -246.878729) (xy 367.383206 -246.8898) (xy 367.37163 -246.898414)
			(xy 367.359946 -246.908574) (xy 367.341809 -246.923786) (xy 367.302008 -246.949409) (xy 367.258963 -246.9691)
			(xy 367.21355 -246.982457) (xy 367.166698 -246.989206) (xy 367.14303 -246.9896) (xy 367.13033 -246.989346)
			(xy 367.123472 -246.989092) (xy 367.097232 -246.987028) (xy 367.045849 -246.975633) (xy 366.996921 -246.956241)
			(xy 366.951683 -246.92934) (xy 366.91128 -246.895611) (xy 366.876731 -246.855906) (xy 366.84891 -246.811228)
			(xy 366.828521 -246.762707) (xy 366.816077 -246.711568) (xy 366.811893 -246.659103) (xy 366.816076 -246.606638)
			(xy 366.828519 -246.555498) (xy 366.848908 -246.506976) (xy 366.876728 -246.462298) (xy 366.911276 -246.422593)
			(xy 366.951679 -246.388863) (xy 366.996916 -246.361962) (xy 367.045844 -246.342568) (xy 367.097227 -246.331172)
			(xy 367.123472 -246.3292) (xy 367.13033 -246.328946) (xy 367.14303 -246.328692) (xy 367.166701 -246.329074)
			(xy 367.213564 -246.335788) (xy 367.258987 -246.349132) (xy 367.302035 -246.368832) (xy 367.341825 -246.394483)
			(xy 367.359946 -246.409718) (xy 367.37163 -246.419878) (xy 367.383186 -246.428522) (xy 367.409827 -246.439576)
			(xy 367.438498 -246.44273) (xy 367.466906 -246.43773) (xy 367.492777 -246.424975) (xy 367.50371 -246.41556)
			(xy 367.522211 -246.399194) (xy 367.563162 -246.371574) (xy 367.607769 -246.350361) (xy 367.655038 -246.336028)
			(xy 367.703914 -246.328895) (xy 367.753308 -246.329121) (xy 367.777776 -246.332502) (xy 367.800682 -246.336451)
			(xy 367.845166 -246.349932) (xy 367.887325 -246.369507) (xy 367.926328 -246.39479) (xy 367.944146 -246.409718)
			(xy 367.94948 -246.414544) (xy 367.95075 -246.41556) (xy 367.961709 -246.424949) (xy 367.987567 -246.437732)
			(xy 368.015972 -246.44275) (xy 368.044644 -246.439599) (xy 368.071282 -246.428533) (xy 368.08283 -246.419878)
			(xy 368.094514 -246.409718) (xy 368.112652 -246.39451) (xy 368.152454 -246.368894) (xy 368.195501 -246.349212)
			(xy 368.240913 -246.335864) (xy 368.287763 -246.329123) (xy 368.31143 -246.328692) (xy 368.32413 -246.328946)
			(xy 368.330988 -246.3292) (xy 368.359405 -246.331483) (xy 368.414885 -246.344575) (xy 368.467291 -246.367002)
			(xy 368.491516 -246.382032) (xy 368.503225 -246.388856) (xy 368.529164 -246.396676) (xy 368.556247 -246.397398)
			(xy 368.582565 -246.39097) (xy 368.606265 -246.377844) (xy 368.625678 -246.358947) (xy 368.639436 -246.335608)
			(xy 368.646569 -246.309472) (xy 368.646964 -246.295926) (xy 368.646964 -245.790466) (xy 368.632527 -245.769374)
			(xy 368.609644 -245.723674) (xy 368.594075 -245.674994) (xy 368.586194 -245.624495) (xy 368.586187 -245.573386)
			(xy 368.594056 -245.522886) (xy 368.609613 -245.474201) (xy 368.632485 -245.428496) (xy 368.646964 -245.407434)
			(xy 368.646964 -245.206266) (xy 368.632527 -245.185174) (xy 368.609644 -245.139474) (xy 368.594075 -245.090794)
			(xy 368.586194 -245.040295) (xy 368.586187 -244.989186) (xy 368.594056 -244.938686) (xy 368.609613 -244.890001)
			(xy 368.632485 -244.844296) (xy 368.646964 -244.823234) (xy 368.646964 -244.622066) (xy 368.632527 -244.600974)
			(xy 368.609644 -244.555274) (xy 368.594075 -244.506594) (xy 368.586194 -244.456095) (xy 368.586187 -244.404986)
			(xy 368.594056 -244.354486) (xy 368.609613 -244.305801) (xy 368.632485 -244.260096) (xy 368.646964 -244.239034)
			(xy 368.646964 -244.037866) (xy 368.632527 -244.016774) (xy 368.609644 -243.971074) (xy 368.594075 -243.922394)
			(xy 368.586194 -243.871895) (xy 368.586187 -243.820786) (xy 368.594056 -243.770286) (xy 368.609613 -243.721601)
			(xy 368.632485 -243.675896) (xy 368.646964 -243.654834) (xy 368.646964 -240.928652) (xy 368.630535 -240.91021)
			(xy 368.602769 -240.869366) (xy 368.581385 -240.824848) (xy 368.566859 -240.777644) (xy 368.559513 -240.728806)
			(xy 368.559511 -240.679418) (xy 368.566854 -240.630579) (xy 368.581377 -240.583374) (xy 368.602757 -240.538854)
			(xy 368.63052 -240.498008) (xy 368.646964 -240.47958) (xy 368.646964 -240.344452) (xy 368.629516 -240.324841)
			(xy 368.600418 -240.281156) (xy 368.578588 -240.233422) (xy 368.564574 -240.182838) (xy 368.558729 -240.130675)
			(xy 368.5612 -240.078245) (xy 368.571925 -240.026863) (xy 368.590634 -239.977821) (xy 368.603276 -239.954816)
			(xy 368.616546 -239.932785) (xy 368.648828 -239.892749) (xy 368.686919 -239.858194) (xy 368.729901 -239.829953)
			(xy 368.776738 -239.808709) (xy 368.801396 -239.8014) (xy 368.81435 -239.797844) (xy 369.127278 -239.484916)
			(xy 369.127278 -238.82223) (xy 368.808254 -238.503206) (xy 362.109512 -238.503206) (xy 362.089336 -238.515795)
			(xy 362.046135 -238.535673) (xy 362.000527 -238.549143) (xy 361.953458 -238.555925) (xy 361.92968 -238.556292)
			(xy 361.905906 -238.555875) (xy 361.858849 -238.549066) (xy 361.813246 -238.535606) (xy 361.770034 -238.515771)
			(xy 361.749848 -238.503206) (xy 361.169712 -238.503206) (xy 361.149536 -238.515795) (xy 361.106335 -238.535673)
			(xy 361.060727 -238.549143) (xy 361.013658 -238.555925) (xy 360.98988 -238.556292) (xy 360.966106 -238.555875)
			(xy 360.919049 -238.549066) (xy 360.873446 -238.535606) (xy 360.830234 -238.515771) (xy 360.810048 -238.503206)
			(xy 360.229912 -238.503206) (xy 360.209736 -238.515795) (xy 360.166535 -238.535673) (xy 360.120927 -238.549143)
			(xy 360.073858 -238.555925) (xy 360.05008 -238.556292) (xy 360.026306 -238.555875) (xy 359.979249 -238.549066)
			(xy 359.933646 -238.535606) (xy 359.890434 -238.515771) (xy 359.870248 -238.503206) (xy 359.290112 -238.503206)
			(xy 359.269936 -238.515795) (xy 359.226735 -238.535673) (xy 359.181127 -238.549143) (xy 359.134058 -238.555925)
			(xy 359.11028 -238.556292) (xy 359.086506 -238.555875) (xy 359.039449 -238.549066) (xy 358.993846 -238.535606)
			(xy 358.950634 -238.515771) (xy 358.930448 -238.503206) (xy 358.350312 -238.503206) (xy 358.330136 -238.515795)
			(xy 358.286935 -238.535673) (xy 358.241327 -238.549143) (xy 358.194258 -238.555925) (xy 358.17048 -238.556292)
			(xy 358.146706 -238.555875) (xy 358.099649 -238.549066) (xy 358.054046 -238.535606) (xy 358.010834 -238.515771)
			(xy 357.990648 -238.503206) (xy 357.410512 -238.503206) (xy 357.390336 -238.515795) (xy 357.347135 -238.535673)
			(xy 357.301527 -238.549143) (xy 357.254458 -238.555925) (xy 357.23068 -238.556292) (xy 357.206906 -238.555875)
			(xy 357.159849 -238.549066) (xy 357.114246 -238.535606) (xy 357.071034 -238.515771) (xy 357.050848 -238.503206)
			(xy 351.898204 -238.503206) (xy 351.562416 -238.838994) (xy 351.552799 -238.849225) (xy 351.539084 -238.873714)
			(xy 351.532553 -238.901012) (xy 351.5337 -238.929056) (xy 351.542438 -238.955729) (xy 351.558108 -238.979016)
			(xy 351.579525 -238.997158) (xy 351.592134 -239.003332) (xy 351.624646 -239.018826) (xy 351.642449 -239.028738)
			(xy 351.67569 -239.052303) (xy 351.69094 -239.065816) (xy 351.701902 -239.075202) (xy 351.72776 -239.08798)
			(xy 351.756164 -239.092998) (xy 351.784836 -239.089851) (xy 351.811476 -239.078792) (xy 351.82302 -239.070134)
			(xy 351.834704 -239.059974) (xy 351.852843 -239.044767) (xy 351.892646 -239.019154) (xy 351.935692 -238.999472)
			(xy 351.981104 -238.986125) (xy 352.027954 -238.979384) (xy 352.05162 -238.978948) (xy 352.06432 -238.979202)
			(xy 352.071178 -238.979456) (xy 352.097411 -238.981523) (xy 352.148781 -238.992923) (xy 352.197695 -239.012317)
			(xy 352.242919 -239.039217) (xy 352.28331 -239.072942) (xy 352.317847 -239.11264) (xy 352.345658 -239.157309)
			(xy 352.366041 -239.20582) (xy 352.37848 -239.256947) (xy 352.382662 -239.3094) (xy 352.381928 -239.318605)
			(xy 352.789491 -239.318605) (xy 352.789491 -239.266671) (xy 352.797616 -239.215376) (xy 352.813664 -239.165983)
			(xy 352.837242 -239.119709) (xy 352.867768 -239.077693) (xy 352.904491 -239.04097) (xy 352.946507 -239.010444)
			(xy 352.992781 -238.986866) (xy 353.042174 -238.970818) (xy 353.093469 -238.962693) (xy 353.145403 -238.962693)
			(xy 353.196698 -238.970818) (xy 353.246091 -238.986866) (xy 353.292365 -239.010444) (xy 353.334381 -239.04097)
			(xy 353.358778 -239.065367) (xy 361.129835 -239.065367) (xy 361.129835 -239.013433) (xy 361.13796 -238.962138)
			(xy 361.154008 -238.912745) (xy 361.177586 -238.866471) (xy 361.208112 -238.824455) (xy 361.244835 -238.787732)
			(xy 361.286851 -238.757206) (xy 361.333125 -238.733628) (xy 361.382518 -238.71758) (xy 361.433813 -238.709455)
			(xy 361.485747 -238.709455) (xy 361.537042 -238.71758) (xy 361.586435 -238.733628) (xy 361.632709 -238.757206)
			(xy 361.674725 -238.787732) (xy 361.711448 -238.824455) (xy 361.741974 -238.866471) (xy 361.765552 -238.912745)
			(xy 361.7816 -238.962138) (xy 361.789725 -239.013433) (xy 361.790234 -239.0394) (xy 361.789725 -239.065367)
			(xy 361.7816 -239.116662) (xy 361.765552 -239.166055) (xy 361.741974 -239.212329) (xy 361.711448 -239.254345)
			(xy 361.674725 -239.291068) (xy 361.632709 -239.321594) (xy 361.611554 -239.332373) (xy 365.024083 -239.332373)
			(xy 365.024083 -239.280427) (xy 365.032209 -239.22912) (xy 365.048262 -239.179716) (xy 365.071846 -239.133431)
			(xy 365.102379 -239.091406) (xy 365.139112 -239.054674) (xy 365.181138 -239.024141) (xy 365.227423 -239.000559)
			(xy 365.276827 -238.984508) (xy 365.328135 -238.976382) (xy 365.354108 -238.9759) (xy 365.378659 -238.976358)
			(xy 365.427226 -238.983593) (xy 365.474188 -238.997932) (xy 365.518512 -239.01906) (xy 365.559224 -239.046512)
			(xy 365.577628 -239.062768) (xy 365.589117 -239.072571) (xy 365.616354 -239.085585) (xy 365.646208 -239.090053)
			(xy 365.676062 -239.085585) (xy 365.703299 -239.072571) (xy 365.714788 -239.062768) (xy 365.733188 -239.046504)
			(xy 365.773892 -239.019034) (xy 365.818216 -238.997895) (xy 365.865182 -238.983554) (xy 365.913754 -238.976327)
			(xy 365.938308 -238.9759) (xy 365.962859 -238.976358) (xy 366.011426 -238.983593) (xy 366.058388 -238.997932)
			(xy 366.102712 -239.01906) (xy 366.143424 -239.046512) (xy 366.161828 -239.062768) (xy 366.173317 -239.072571)
			(xy 366.200554 -239.085585) (xy 366.230408 -239.090053) (xy 366.260262 -239.085585) (xy 366.287499 -239.072571)
			(xy 366.298988 -239.062768) (xy 366.317388 -239.046504) (xy 366.358092 -239.019034) (xy 366.402416 -238.997895)
			(xy 366.449382 -238.983554) (xy 366.497954 -238.976327) (xy 366.522508 -238.9759) (xy 366.548871 -238.976435)
			(xy 366.600927 -238.984813) (xy 366.650996 -239.001341) (xy 366.69781 -239.0256) (xy 366.740185 -239.056977)
			(xy 366.758982 -239.075468) (xy 366.768533 -239.084596) (xy 366.791212 -239.098123) (xy 366.816599 -239.105389)
			(xy 366.843 -239.105911) (xy 366.868654 -239.099651) (xy 366.891849 -239.08703) (xy 366.90173 -239.078262)
			(xy 366.92028 -239.061264) (xy 366.961541 -239.032475) (xy 367.00669 -239.010278) (xy 367.054684 -238.995187)
			(xy 367.104413 -238.987551) (xy 367.129568 -238.987076) (xy 367.154121 -238.987504) (xy 367.202688 -238.994747)
			(xy 367.24965 -239.009094) (xy 367.293974 -239.030228) (xy 367.334684 -239.057686) (xy 367.353088 -239.073944)
			(xy 367.364577 -239.083747) (xy 367.391814 -239.096761) (xy 367.421668 -239.101229) (xy 367.451522 -239.096761)
			(xy 367.478759 -239.083747) (xy 367.490248 -239.073944) (xy 367.50866 -239.057695) (xy 367.549362 -239.030224)
			(xy 367.593683 -239.009083) (xy 367.640646 -238.994738) (xy 367.689215 -238.987506) (xy 367.713768 -238.987076)
			(xy 367.738321 -238.987504) (xy 367.786888 -238.994747) (xy 367.83385 -239.009094) (xy 367.878174 -239.030228)
			(xy 367.918884 -239.057686) (xy 367.937288 -239.073944) (xy 367.948777 -239.083747) (xy 367.976014 -239.096761)
			(xy 368.005868 -239.101229) (xy 368.035722 -239.096761) (xy 368.062959 -239.083747) (xy 368.074448 -239.073944)
			(xy 368.09286 -239.057695) (xy 368.133562 -239.030224) (xy 368.177883 -239.009083) (xy 368.224846 -238.994738)
			(xy 368.273415 -238.987506) (xy 368.297968 -238.987076) (xy 368.323941 -238.987497) (xy 368.375249 -238.995618)
			(xy 368.424654 -239.011667) (xy 368.47094 -239.035247) (xy 368.512968 -239.065778) (xy 368.549701 -239.102508)
			(xy 368.580236 -239.144532) (xy 368.603821 -239.190816) (xy 368.619874 -239.24022) (xy 368.628001 -239.291527)
			(xy 368.628001 -239.343473) (xy 368.619874 -239.39478) (xy 368.603821 -239.444184) (xy 368.580236 -239.490468)
			(xy 368.549701 -239.532492) (xy 368.512968 -239.569222) (xy 368.47094 -239.599753) (xy 368.424654 -239.623333)
			(xy 368.375249 -239.639382) (xy 368.323941 -239.647503) (xy 368.297968 -239.647984) (xy 368.273416 -239.647545)
			(xy 368.224848 -239.640306) (xy 368.177886 -239.625963) (xy 368.133562 -239.60483) (xy 368.092851 -239.577374)
			(xy 368.074448 -239.561116) (xy 368.062959 -239.551313) (xy 368.035722 -239.538299) (xy 368.005868 -239.533831)
			(xy 367.976014 -239.538299) (xy 367.948777 -239.551313) (xy 367.937288 -239.561116) (xy 367.91891 -239.577405)
			(xy 367.878198 -239.604868) (xy 367.833868 -239.626001) (xy 367.786898 -239.640336) (xy 367.738323 -239.647559)
			(xy 367.713768 -239.647984) (xy 367.689216 -239.647545) (xy 367.640648 -239.640306) (xy 367.593686 -239.625963)
			(xy 367.549362 -239.60483) (xy 367.508651 -239.577374) (xy 367.490248 -239.561116) (xy 367.478759 -239.551313)
			(xy 367.451522 -239.538299) (xy 367.421668 -239.533831) (xy 367.391814 -239.538299) (xy 367.364577 -239.551313)
			(xy 367.353088 -239.561116) (xy 367.33471 -239.577405) (xy 367.293998 -239.604868) (xy 367.249668 -239.626001)
			(xy 367.202698 -239.640336) (xy 367.154123 -239.647559) (xy 367.129568 -239.647984) (xy 367.103204 -239.647469)
			(xy 367.051147 -239.639086) (xy 367.001078 -239.622554) (xy 366.954264 -239.59829) (xy 366.911891 -239.56691)
			(xy 366.893094 -239.548416) (xy 366.883564 -239.539265) (xy 366.860879 -239.525742) (xy 366.835487 -239.518479)
			(xy 366.809081 -239.517963) (xy 366.783424 -239.524226) (xy 366.760227 -239.536852) (xy 366.750346 -239.545622)
			(xy 366.731818 -239.562645) (xy 366.69055 -239.591428) (xy 366.645395 -239.613618) (xy 366.597396 -239.628704)
			(xy 366.547665 -239.636335) (xy 366.522508 -239.636808) (xy 366.497955 -239.636399) (xy 366.449386 -239.629152)
			(xy 366.402424 -239.614801) (xy 366.3581 -239.593662) (xy 366.317391 -239.5662) (xy 366.298988 -239.54994)
			(xy 366.287499 -239.540137) (xy 366.260262 -239.527123) (xy 366.230408 -239.522655) (xy 366.200554 -239.527123)
			(xy 366.173317 -239.540137) (xy 366.161828 -239.54994) (xy 366.143423 -239.566198) (xy 366.10272 -239.593668)
			(xy 366.058397 -239.614808) (xy 366.011432 -239.629151) (xy 365.962861 -239.63638) (xy 365.938308 -239.636808)
			(xy 365.913755 -239.636399) (xy 365.865186 -239.629152) (xy 365.818224 -239.614801) (xy 365.7739 -239.593662)
			(xy 365.733191 -239.5662) (xy 365.714788 -239.54994) (xy 365.703299 -239.540137) (xy 365.676062 -239.527123)
			(xy 365.646208 -239.522655) (xy 365.616354 -239.527123) (xy 365.589117 -239.540137) (xy 365.577628 -239.54994)
			(xy 365.559223 -239.566198) (xy 365.51852 -239.593668) (xy 365.474197 -239.614808) (xy 365.427232 -239.629151)
			(xy 365.378661 -239.63638) (xy 365.354108 -239.636808) (xy 365.328135 -239.636418) (xy 365.276827 -239.628292)
			(xy 365.227423 -239.612241) (xy 365.181138 -239.588659) (xy 365.139112 -239.558126) (xy 365.102379 -239.521394)
			(xy 365.071846 -239.479369) (xy 365.048262 -239.433084) (xy 365.032209 -239.38368) (xy 365.024083 -239.332373)
			(xy 361.611554 -239.332373) (xy 361.586435 -239.345172) (xy 361.537042 -239.36122) (xy 361.485747 -239.369345)
			(xy 361.433813 -239.369345) (xy 361.382518 -239.36122) (xy 361.333125 -239.345172) (xy 361.286851 -239.321594)
			(xy 361.244835 -239.291068) (xy 361.208112 -239.254345) (xy 361.177586 -239.212329) (xy 361.154008 -239.166055)
			(xy 361.13796 -239.116662) (xy 361.129835 -239.065367) (xy 353.358778 -239.065367) (xy 353.371104 -239.077693)
			(xy 353.40163 -239.119709) (xy 353.425208 -239.165983) (xy 353.441256 -239.215376) (xy 353.449381 -239.266671)
			(xy 353.44989 -239.292638) (xy 353.449381 -239.318605) (xy 353.441256 -239.3699) (xy 353.425208 -239.419293)
			(xy 353.40163 -239.465567) (xy 353.371104 -239.507583) (xy 353.334381 -239.544306) (xy 353.292365 -239.574832)
			(xy 353.246091 -239.59841) (xy 353.196698 -239.614458) (xy 353.145403 -239.622583) (xy 353.093469 -239.622583)
			(xy 353.042174 -239.614458) (xy 352.992781 -239.59841) (xy 352.946507 -239.574832) (xy 352.904491 -239.544306)
			(xy 352.867768 -239.507583) (xy 352.837242 -239.465567) (xy 352.813664 -239.419293) (xy 352.797616 -239.3699)
			(xy 352.789491 -239.318605) (xy 352.381928 -239.318605) (xy 352.37848 -239.361853) (xy 352.366041 -239.41298)
			(xy 352.345658 -239.461491) (xy 352.317847 -239.50616) (xy 352.283309 -239.545859) (xy 352.242919 -239.579583)
			(xy 352.197695 -239.606483) (xy 352.14878 -239.625877) (xy 352.097411 -239.637277) (xy 352.071178 -239.639348)
			(xy 352.06432 -239.639602) (xy 352.05162 -239.639856) (xy 352.02795 -239.639471) (xy 351.981089 -239.632751)
			(xy 351.93567 -239.619403) (xy 351.892625 -239.599701) (xy 351.852837 -239.57405) (xy 351.834704 -239.55883)
			(xy 351.82302 -239.54867) (xy 351.811466 -239.54003) (xy 351.784829 -239.528983) (xy 351.756165 -239.52584)
			(xy 351.727767 -239.530852) (xy 351.70191 -239.543617) (xy 351.69094 -239.552988) (xy 351.68967 -239.554004)
			(xy 351.684336 -239.55883) (xy 351.6662 -239.574043) (xy 351.6264 -239.599669) (xy 351.583354 -239.619361)
			(xy 351.537941 -239.632718) (xy 351.491088 -239.639467) (xy 351.46742 -239.639856) (xy 351.45218 -239.639856)
			(xy 351.436432 -239.638586) (xy 351.427796 -239.63757) (xy 351.413496 -239.636335) (xy 351.385179 -239.640947)
			(xy 351.35926 -239.653248) (xy 351.337782 -239.672269) (xy 351.322438 -239.696511) (xy 351.314438 -239.724063)
			(xy 351.314004 -239.738408) (xy 351.314004 -239.879183) (xy 357.840789 -239.879183) (xy 357.840789 -239.827249)
			(xy 357.848914 -239.775954) (xy 357.864962 -239.726561) (xy 357.88854 -239.680287) (xy 357.919066 -239.638271)
			(xy 357.955789 -239.601548) (xy 357.997805 -239.571022) (xy 358.044079 -239.547444) (xy 358.093472 -239.531396)
			(xy 358.144767 -239.523271) (xy 358.196701 -239.523271) (xy 358.247996 -239.531396) (xy 358.297389 -239.547444)
			(xy 358.343663 -239.571022) (xy 358.385679 -239.601548) (xy 358.422402 -239.638271) (xy 358.452928 -239.680287)
			(xy 358.476506 -239.726561) (xy 358.492554 -239.775954) (xy 358.500679 -239.827249) (xy 358.501188 -239.853216)
			(xy 358.500679 -239.879183) (xy 358.492554 -239.930478) (xy 358.476506 -239.979871) (xy 358.452928 -240.026145)
			(xy 358.422402 -240.068161) (xy 358.385679 -240.104884) (xy 358.343663 -240.13541) (xy 358.297389 -240.158988)
			(xy 358.247996 -240.175036) (xy 358.196701 -240.183161) (xy 358.144767 -240.183161) (xy 358.093472 -240.175036)
			(xy 358.044079 -240.158988) (xy 357.997805 -240.13541) (xy 357.955789 -240.104884) (xy 357.919066 -240.068161)
			(xy 357.88854 -240.026145) (xy 357.864962 -239.979871) (xy 357.848914 -239.930478) (xy 357.840789 -239.879183)
			(xy 351.314004 -239.879183) (xy 351.314004 -241.172492) (xy 356.03561 -241.172492) (xy 356.036065 -241.14794)
			(xy 356.0433 -241.099374) (xy 356.05764 -241.052412) (xy 356.078769 -241.008087) (xy 356.106222 -240.967376)
			(xy 356.122478 -240.948972) (xy 356.132289 -240.937489) (xy 356.145302 -240.91025) (xy 356.149768 -240.880394)
			(xy 356.145298 -240.850539) (xy 356.132282 -240.823301) (xy 356.122478 -240.811812) (xy 356.106199 -240.793425)
			(xy 356.078735 -240.752715) (xy 356.057601 -240.708388) (xy 356.043263 -240.66142) (xy 356.036037 -240.612846)
			(xy 356.03561 -240.588292) (xy 356.036119 -240.562325) (xy 356.044244 -240.51103) (xy 356.060292 -240.461637)
			(xy 356.08387 -240.415363) (xy 356.114396 -240.373347) (xy 356.151119 -240.336624) (xy 356.193135 -240.306098)
			(xy 356.239409 -240.28252) (xy 356.288802 -240.266472) (xy 356.340097 -240.258347) (xy 356.392031 -240.258347)
			(xy 356.443326 -240.266472) (xy 356.492719 -240.28252) (xy 356.538993 -240.306098) (xy 356.581009 -240.336624)
			(xy 356.617732 -240.373347) (xy 356.648258 -240.415363) (xy 356.671836 -240.461637) (xy 356.687884 -240.51103)
			(xy 356.696009 -240.562325) (xy 356.696518 -240.588292) (xy 356.696106 -240.612845) (xy 356.688859 -240.661413)
			(xy 356.67913 -240.693253) (xy 361.130089 -240.693253) (xy 361.130089 -240.641319) (xy 361.138214 -240.590024)
			(xy 361.154262 -240.540631) (xy 361.17784 -240.494357) (xy 361.208366 -240.452341) (xy 361.245089 -240.415618)
			(xy 361.287105 -240.385092) (xy 361.333379 -240.361514) (xy 361.382772 -240.345466) (xy 361.434067 -240.337341)
			(xy 361.486001 -240.337341) (xy 361.537296 -240.345466) (xy 361.586689 -240.361514) (xy 361.632963 -240.385092)
			(xy 361.674979 -240.415618) (xy 361.711702 -240.452341) (xy 361.742228 -240.494357) (xy 361.765806 -240.540631)
			(xy 361.781854 -240.590024) (xy 361.789979 -240.641319) (xy 361.790488 -240.667286) (xy 361.789979 -240.693253)
			(xy 361.781854 -240.744548) (xy 361.765806 -240.793941) (xy 361.742228 -240.840215) (xy 361.711702 -240.882231)
			(xy 361.674979 -240.918954) (xy 361.632963 -240.94948) (xy 361.586689 -240.973058) (xy 361.537296 -240.989106)
			(xy 361.486001 -240.997231) (xy 361.434067 -240.997231) (xy 361.382772 -240.989106) (xy 361.333379 -240.973058)
			(xy 361.287105 -240.94948) (xy 361.245089 -240.918954) (xy 361.208366 -240.882231) (xy 361.17784 -240.840215)
			(xy 361.154262 -240.793941) (xy 361.138214 -240.744548) (xy 361.130089 -240.693253) (xy 356.67913 -240.693253)
			(xy 356.674509 -240.708376) (xy 356.653371 -240.752699) (xy 356.62591 -240.793409) (xy 356.60965 -240.811812)
			(xy 356.599852 -240.823306) (xy 356.586834 -240.850541) (xy 356.582363 -240.880394) (xy 356.586831 -240.910248)
			(xy 356.599846 -240.937484) (xy 356.60965 -240.948972) (xy 356.625909 -240.967376) (xy 356.653379 -241.00808)
			(xy 356.674518 -241.052403) (xy 356.688861 -241.099368) (xy 356.69609 -241.147939) (xy 356.696518 -241.172492)
			(xy 356.696009 -241.198459) (xy 356.687884 -241.249754) (xy 356.671836 -241.299147) (xy 356.648258 -241.345421)
			(xy 356.617732 -241.387437) (xy 356.581009 -241.42416) (xy 356.538993 -241.454686) (xy 356.492719 -241.478264)
			(xy 356.443326 -241.494312) (xy 356.392031 -241.502437) (xy 356.340097 -241.502437) (xy 356.288802 -241.494312)
			(xy 356.239409 -241.478264) (xy 356.193135 -241.454686) (xy 356.151119 -241.42416) (xy 356.114396 -241.387437)
			(xy 356.08387 -241.345421) (xy 356.060292 -241.299147) (xy 356.044244 -241.249754) (xy 356.036119 -241.198459)
			(xy 356.03561 -241.172492) (xy 351.314004 -241.172492) (xy 351.314004 -241.507069) (xy 357.840789 -241.507069)
			(xy 357.840789 -241.455135) (xy 357.848914 -241.40384) (xy 357.864962 -241.354447) (xy 357.88854 -241.308173)
			(xy 357.919066 -241.266157) (xy 357.955789 -241.229434) (xy 357.997805 -241.198908) (xy 358.044079 -241.17533)
			(xy 358.093472 -241.159282) (xy 358.144767 -241.151157) (xy 358.196701 -241.151157) (xy 358.247996 -241.159282)
			(xy 358.297389 -241.17533) (xy 358.343663 -241.198908) (xy 358.385679 -241.229434) (xy 358.422402 -241.266157)
			(xy 358.452928 -241.308173) (xy 358.476506 -241.354447) (xy 358.492554 -241.40384) (xy 358.500679 -241.455135)
			(xy 358.501188 -241.481102) (xy 358.500679 -241.507069) (xy 358.492554 -241.558364) (xy 358.476506 -241.607757)
			(xy 358.452928 -241.654031) (xy 358.444776 -241.665252) (xy 363.032802 -241.665252) (xy 363.033235 -241.6407)
			(xy 363.040476 -241.592132) (xy 363.054821 -241.54517) (xy 363.075955 -241.500846) (xy 363.103412 -241.460135)
			(xy 363.11967 -241.441732) (xy 363.129521 -241.43028) (xy 363.14253 -241.40303) (xy 363.14699 -241.373164)
			(xy 363.142509 -241.343302) (xy 363.129481 -241.316061) (xy 363.11967 -241.304572) (xy 363.103419 -241.286162)
			(xy 363.07595 -241.245458) (xy 363.054811 -241.201137) (xy 363.040467 -241.154174) (xy 363.033233 -241.105605)
			(xy 363.032802 -241.081052) (xy 363.033311 -241.055085) (xy 363.041436 -241.00379) (xy 363.057484 -240.954397)
			(xy 363.081062 -240.908123) (xy 363.111588 -240.866107) (xy 363.148311 -240.829384) (xy 363.190327 -240.798858)
			(xy 363.236601 -240.77528) (xy 363.285994 -240.759232) (xy 363.337289 -240.751107) (xy 363.389223 -240.751107)
			(xy 363.440518 -240.759232) (xy 363.489911 -240.77528) (xy 363.536185 -240.798858) (xy 363.578201 -240.829384)
			(xy 363.614924 -240.866107) (xy 363.64545 -240.908123) (xy 363.669028 -240.954397) (xy 363.685076 -241.00379)
			(xy 363.693201 -241.055085) (xy 363.69371 -241.081052) (xy 363.693276 -241.105604) (xy 363.686035 -241.154172)
			(xy 363.67169 -241.201134) (xy 363.650557 -241.245458) (xy 363.6231 -241.286168) (xy 363.606842 -241.304572)
			(xy 363.597084 -241.316097) (xy 363.584063 -241.343321) (xy 363.579584 -241.373164) (xy 363.584042 -241.403011)
			(xy 363.597044 -241.430244) (xy 363.606842 -241.441732) (xy 363.623081 -241.460153) (xy 363.650554 -241.500852)
			(xy 363.671697 -241.545171) (xy 363.686044 -241.592132) (xy 363.693279 -241.6407) (xy 363.69371 -241.665252)
			(xy 363.693201 -241.691219) (xy 363.685076 -241.742514) (xy 363.669028 -241.791907) (xy 363.64545 -241.838181)
			(xy 363.614924 -241.880197) (xy 363.578201 -241.91692) (xy 363.536185 -241.947446) (xy 363.489911 -241.971024)
			(xy 363.440518 -241.987072) (xy 363.389223 -241.995197) (xy 363.337289 -241.995197) (xy 363.285994 -241.987072)
			(xy 363.236601 -241.971024) (xy 363.190327 -241.947446) (xy 363.148311 -241.91692) (xy 363.111588 -241.880197)
			(xy 363.081062 -241.838181) (xy 363.057484 -241.791907) (xy 363.041436 -241.742514) (xy 363.033311 -241.691219)
			(xy 363.032802 -241.665252) (xy 358.444776 -241.665252) (xy 358.422402 -241.696047) (xy 358.385679 -241.73277)
			(xy 358.343663 -241.763296) (xy 358.297389 -241.786874) (xy 358.247996 -241.802922) (xy 358.196701 -241.811047)
			(xy 358.144767 -241.811047) (xy 358.093472 -241.802922) (xy 358.044079 -241.786874) (xy 357.997805 -241.763296)
			(xy 357.955789 -241.73277) (xy 357.919066 -241.696047) (xy 357.88854 -241.654031) (xy 357.864962 -241.607757)
			(xy 357.848914 -241.558364) (xy 357.840789 -241.507069) (xy 351.314004 -241.507069) (xy 351.314004 -242.320885)
			(xy 361.130089 -242.320885) (xy 361.130089 -242.268951) (xy 361.138214 -242.217656) (xy 361.154262 -242.168263)
			(xy 361.17784 -242.121989) (xy 361.208366 -242.079973) (xy 361.245089 -242.04325) (xy 361.287105 -242.012724)
			(xy 361.333379 -241.989146) (xy 361.382772 -241.973098) (xy 361.434067 -241.964973) (xy 361.486001 -241.964973)
			(xy 361.537296 -241.973098) (xy 361.586689 -241.989146) (xy 361.632963 -242.012724) (xy 361.674979 -242.04325)
			(xy 361.711702 -242.079973) (xy 361.742228 -242.121989) (xy 361.765806 -242.168263) (xy 361.781854 -242.217656)
			(xy 361.789979 -242.268951) (xy 361.790488 -242.294918) (xy 361.789979 -242.320885) (xy 361.781854 -242.37218)
			(xy 361.765806 -242.421573) (xy 361.742228 -242.467847) (xy 361.711702 -242.509863) (xy 361.674979 -242.546586)
			(xy 361.632963 -242.577112) (xy 361.586689 -242.60069) (xy 361.537296 -242.616738) (xy 361.486001 -242.624863)
			(xy 361.434067 -242.624863) (xy 361.382772 -242.616738) (xy 361.333379 -242.60069) (xy 361.287105 -242.577112)
			(xy 361.245089 -242.546586) (xy 361.208366 -242.509863) (xy 361.17784 -242.467847) (xy 361.154262 -242.421573)
			(xy 361.138214 -242.37218) (xy 361.130089 -242.320885) (xy 351.314004 -242.320885) (xy 351.314004 -243.134955)
			(xy 357.840789 -243.134955) (xy 357.840789 -243.083021) (xy 357.848914 -243.031726) (xy 357.864962 -242.982333)
			(xy 357.88854 -242.936059) (xy 357.919066 -242.894043) (xy 357.955789 -242.85732) (xy 357.997805 -242.826794)
			(xy 358.044079 -242.803216) (xy 358.093472 -242.787168) (xy 358.144767 -242.779043) (xy 358.196701 -242.779043)
			(xy 358.247996 -242.787168) (xy 358.297389 -242.803216) (xy 358.343663 -242.826794) (xy 358.385679 -242.85732)
			(xy 358.422402 -242.894043) (xy 358.452928 -242.936059) (xy 358.476506 -242.982333) (xy 358.47798 -242.986869)
			(xy 365.433835 -242.986869) (xy 365.433835 -242.934931) (xy 365.44196 -242.883632) (xy 365.45801 -242.834235)
			(xy 365.48159 -242.787958) (xy 365.51212 -242.745939) (xy 365.548846 -242.709213) (xy 365.590866 -242.678685)
			(xy 365.637144 -242.655106) (xy 365.686541 -242.639058) (xy 365.737841 -242.630934) (xy 365.76381 -242.630452)
			(xy 365.789671 -242.630958) (xy 365.840762 -242.639005) (xy 365.889975 -242.654916) (xy 365.936106 -242.678303)
			(xy 365.978029 -242.708593) (xy 365.996728 -242.726464) (xy 366.006443 -242.735509) (xy 366.029452 -242.748721)
			(xy 366.055089 -242.755558) (xy 366.081623 -242.755558) (xy 366.10726 -242.748721) (xy 366.130269 -242.735509)
			(xy 366.139984 -242.726464) (xy 366.158664 -242.708574) (xy 366.200598 -242.678296) (xy 366.246735 -242.654916)
			(xy 366.295949 -242.639006) (xy 366.347041 -242.630952) (xy 366.372902 -242.630452) (xy 366.39887 -242.630949)
			(xy 366.450165 -242.639074) (xy 366.499559 -242.655123) (xy 366.545833 -242.678702) (xy 366.587849 -242.709228)
			(xy 366.624573 -242.745952) (xy 366.6551 -242.787969) (xy 366.678678 -242.834243) (xy 366.694726 -242.883637)
			(xy 366.702851 -242.934932) (xy 366.702851 -242.986868) (xy 366.694726 -243.038163) (xy 366.678678 -243.087557)
			(xy 366.6551 -243.133831) (xy 366.624573 -243.175848) (xy 366.587849 -243.212572) (xy 366.545833 -243.243098)
			(xy 366.499559 -243.266677) (xy 366.450165 -243.282726) (xy 366.39887 -243.290851) (xy 366.372902 -243.29136)
			(xy 366.347042 -243.290843) (xy 366.295951 -243.282798) (xy 366.246739 -243.26689) (xy 366.200607 -243.243506)
			(xy 366.158683 -243.213218) (xy 366.139984 -243.195348) (xy 366.130269 -243.186303) (xy 366.10726 -243.173091)
			(xy 366.081623 -243.166254) (xy 366.055089 -243.166254) (xy 366.029452 -243.173091) (xy 366.006443 -243.186303)
			(xy 365.996728 -243.195348) (xy 365.978028 -243.213217) (xy 365.936101 -243.243502) (xy 365.88997 -243.266887)
			(xy 365.840759 -243.282802) (xy 365.78967 -243.290859) (xy 365.76381 -243.29136) (xy 365.737841 -243.290866)
			(xy 365.686541 -243.282742) (xy 365.637144 -243.266694) (xy 365.590866 -243.243115) (xy 365.548846 -243.212587)
			(xy 365.51212 -243.175861) (xy 365.48159 -243.133842) (xy 365.45801 -243.087565) (xy 365.44196 -243.038168)
			(xy 365.433835 -242.986869) (xy 358.47798 -242.986869) (xy 358.492554 -243.031726) (xy 358.500679 -243.083021)
			(xy 358.501188 -243.108988) (xy 358.500679 -243.134955) (xy 358.492554 -243.18625) (xy 358.476506 -243.235643)
			(xy 358.452928 -243.281917) (xy 358.422402 -243.323933) (xy 358.385679 -243.360656) (xy 358.343663 -243.391182)
			(xy 358.297389 -243.41476) (xy 358.247996 -243.430808) (xy 358.196701 -243.438933) (xy 358.144767 -243.438933)
			(xy 358.093472 -243.430808) (xy 358.044079 -243.41476) (xy 357.997805 -243.391182) (xy 357.955789 -243.360656)
			(xy 357.919066 -243.323933) (xy 357.88854 -243.281917) (xy 357.864962 -243.235643) (xy 357.848914 -243.18625)
			(xy 357.840789 -243.134955) (xy 351.314004 -243.134955) (xy 351.314004 -243.948771) (xy 361.130089 -243.948771)
			(xy 361.130089 -243.896837) (xy 361.138214 -243.845542) (xy 361.154262 -243.796149) (xy 361.17784 -243.749875)
			(xy 361.208366 -243.707859) (xy 361.245089 -243.671136) (xy 361.287105 -243.64061) (xy 361.333379 -243.617032)
			(xy 361.382772 -243.600984) (xy 361.434067 -243.592859) (xy 361.486001 -243.592859) (xy 361.537296 -243.600984)
			(xy 361.586689 -243.617032) (xy 361.632963 -243.64061) (xy 361.674979 -243.671136) (xy 361.711702 -243.707859)
			(xy 361.742228 -243.749875) (xy 361.765806 -243.796149) (xy 361.781854 -243.845542) (xy 361.789979 -243.896837)
			(xy 361.790488 -243.922804) (xy 361.789979 -243.948771) (xy 361.781854 -244.000066) (xy 361.765806 -244.049459)
			(xy 361.742228 -244.095733) (xy 361.711702 -244.137749) (xy 361.674979 -244.174472) (xy 361.632963 -244.204998)
			(xy 361.586689 -244.228576) (xy 361.537296 -244.244624) (xy 361.486001 -244.252749) (xy 361.434067 -244.252749)
			(xy 361.382772 -244.244624) (xy 361.333379 -244.228576) (xy 361.287105 -244.204998) (xy 361.245089 -244.174472)
			(xy 361.208366 -244.137749) (xy 361.17784 -244.095733) (xy 361.154262 -244.049459) (xy 361.138214 -244.000066)
			(xy 361.130089 -243.948771) (xy 351.314004 -243.948771) (xy 351.314004 -245.347236) (xy 356.04323 -245.347236)
			(xy 356.043672 -245.322684) (xy 356.050914 -245.274118) (xy 356.065258 -245.227156) (xy 356.086389 -245.182832)
			(xy 356.113842 -245.142121) (xy 356.130098 -245.123716) (xy 356.139864 -245.112198) (xy 356.152879 -245.084971)
			(xy 356.157353 -245.055127) (xy 356.152895 -245.02528) (xy 356.139894 -244.998046) (xy 356.130098 -244.986556)
			(xy 356.113843 -244.968148) (xy 356.086375 -244.927445) (xy 356.065236 -244.883122) (xy 356.050892 -244.836159)
			(xy 356.04366 -244.787589) (xy 356.04323 -244.763036) (xy 356.043739 -244.737069) (xy 356.051864 -244.685774)
			(xy 356.067912 -244.636381) (xy 356.09149 -244.590107) (xy 356.122016 -244.548091) (xy 356.158739 -244.511368)
			(xy 356.200755 -244.480842) (xy 356.247029 -244.457264) (xy 356.296422 -244.441216) (xy 356.347717 -244.433091)
			(xy 356.399651 -244.433091) (xy 356.450946 -244.441216) (xy 356.500339 -244.457264) (xy 356.546613 -244.480842)
			(xy 356.588629 -244.511368) (xy 356.625352 -244.548091) (xy 356.655878 -244.590107) (xy 356.679456 -244.636381)
			(xy 356.695504 -244.685774) (xy 356.703629 -244.737069) (xy 356.704129 -244.762587) (xy 357.840789 -244.762587)
			(xy 357.840789 -244.710653) (xy 357.848914 -244.659358) (xy 357.864962 -244.609965) (xy 357.88854 -244.563691)
			(xy 357.919066 -244.521675) (xy 357.955789 -244.484952) (xy 357.997805 -244.454426) (xy 358.044079 -244.430848)
			(xy 358.093472 -244.4148) (xy 358.144767 -244.406675) (xy 358.196701 -244.406675) (xy 358.247996 -244.4148)
			(xy 358.297389 -244.430848) (xy 358.343663 -244.454426) (xy 358.385679 -244.484952) (xy 358.422402 -244.521675)
			(xy 358.452928 -244.563691) (xy 358.476506 -244.609965) (xy 358.492554 -244.659358) (xy 358.500679 -244.710653)
			(xy 358.501188 -244.73662) (xy 358.500679 -244.762587) (xy 358.492554 -244.813882) (xy 358.476506 -244.863275)
			(xy 358.452928 -244.909549) (xy 358.422402 -244.951565) (xy 358.385679 -244.988288) (xy 358.343663 -245.018814)
			(xy 358.297389 -245.042392) (xy 358.247996 -245.05844) (xy 358.196701 -245.066565) (xy 358.144767 -245.066565)
			(xy 358.093472 -245.05844) (xy 358.044079 -245.042392) (xy 357.997805 -245.018814) (xy 357.955789 -244.988288)
			(xy 357.919066 -244.951565) (xy 357.88854 -244.909549) (xy 357.864962 -244.863275) (xy 357.848914 -244.813882)
			(xy 357.840789 -244.762587) (xy 356.704129 -244.762587) (xy 356.704138 -244.763036) (xy 356.703687 -244.787588)
			(xy 356.696449 -244.836154) (xy 356.682108 -244.883116) (xy 356.660978 -244.92744) (xy 356.633526 -244.968151)
			(xy 356.61727 -244.986556) (xy 356.607428 -244.998016) (xy 356.594412 -245.025263) (xy 356.589948 -245.055127)
			(xy 356.594428 -245.084988) (xy 356.607457 -245.112228) (xy 356.61727 -245.123716) (xy 356.633553 -245.142099)
			(xy 356.661019 -245.182809) (xy 356.682153 -245.227137) (xy 356.69649 -245.274107) (xy 356.703713 -245.322681)
			(xy 356.704138 -245.347236) (xy 356.703629 -245.373203) (xy 356.695504 -245.424498) (xy 356.679456 -245.473891)
			(xy 356.655878 -245.520165) (xy 356.625352 -245.562181) (xy 356.610876 -245.576657) (xy 361.130089 -245.576657)
			(xy 361.130089 -245.524723) (xy 361.138214 -245.473428) (xy 361.154262 -245.424035) (xy 361.17784 -245.377761)
			(xy 361.208366 -245.335745) (xy 361.245089 -245.299022) (xy 361.287105 -245.268496) (xy 361.333379 -245.244918)
			(xy 361.382772 -245.22887) (xy 361.434067 -245.220745) (xy 361.486001 -245.220745) (xy 361.537296 -245.22887)
			(xy 361.586689 -245.244918) (xy 361.632963 -245.268496) (xy 361.674979 -245.299022) (xy 361.711702 -245.335745)
			(xy 361.742228 -245.377761) (xy 361.751782 -245.396512) (xy 363.025182 -245.396512) (xy 363.025596 -245.371959)
			(xy 363.032842 -245.323391) (xy 363.047192 -245.276428) (xy 363.06833 -245.232105) (xy 363.095791 -245.191395)
			(xy 363.11205 -245.172992) (xy 363.121844 -245.161495) (xy 363.134862 -245.134261) (xy 363.139334 -245.104409)
			(xy 363.134867 -245.074556) (xy 363.121854 -245.04732) (xy 363.11205 -245.035832) (xy 363.095793 -245.017427)
			(xy 363.068322 -244.976723) (xy 363.047183 -244.932401) (xy 363.03284 -244.885436) (xy 363.02561 -244.836865)
			(xy 363.025182 -244.812312) (xy 363.025691 -244.786345) (xy 363.033816 -244.73505) (xy 363.049864 -244.685657)
			(xy 363.073442 -244.639383) (xy 363.103968 -244.597367) (xy 363.140691 -244.560644) (xy 363.182707 -244.530118)
			(xy 363.228981 -244.50654) (xy 363.278374 -244.490492) (xy 363.329669 -244.482367) (xy 363.381603 -244.482367)
			(xy 363.432898 -244.490492) (xy 363.482291 -244.50654) (xy 363.528565 -244.530118) (xy 363.570581 -244.560644)
			(xy 363.607304 -244.597367) (xy 363.63783 -244.639383) (xy 363.661408 -244.685657) (xy 363.677456 -244.73505)
			(xy 363.685581 -244.786345) (xy 363.68609 -244.812312) (xy 363.685637 -244.836864) (xy 363.678402 -244.88543)
			(xy 363.664061 -244.932393) (xy 363.642932 -244.976717) (xy 363.615478 -245.017428) (xy 363.599222 -245.035832)
			(xy 363.589407 -245.047312) (xy 363.576395 -245.074552) (xy 363.571929 -245.104409) (xy 363.5764 -245.134265)
			(xy 363.589417 -245.161503) (xy 363.599222 -245.172992) (xy 363.615503 -245.191378) (xy 363.642967 -245.232088)
			(xy 363.664101 -245.276415) (xy 363.678438 -245.323384) (xy 363.685664 -245.371958) (xy 363.68609 -245.396512)
			(xy 363.685581 -245.422479) (xy 363.677456 -245.473774) (xy 363.661408 -245.523167) (xy 363.63783 -245.569441)
			(xy 363.607304 -245.611457) (xy 363.570581 -245.64818) (xy 363.528565 -245.678706) (xy 363.482291 -245.702284)
			(xy 363.432898 -245.718332) (xy 363.381603 -245.726457) (xy 363.329669 -245.726457) (xy 363.278374 -245.718332)
			(xy 363.228981 -245.702284) (xy 363.182707 -245.678706) (xy 363.140691 -245.64818) (xy 363.103968 -245.611457)
			(xy 363.073442 -245.569441) (xy 363.049864 -245.523167) (xy 363.033816 -245.473774) (xy 363.025691 -245.422479)
			(xy 363.025182 -245.396512) (xy 361.751782 -245.396512) (xy 361.765806 -245.424035) (xy 361.781854 -245.473428)
			(xy 361.789979 -245.524723) (xy 361.790488 -245.55069) (xy 361.789979 -245.576657) (xy 361.781854 -245.627952)
			(xy 361.765806 -245.677345) (xy 361.742228 -245.723619) (xy 361.711702 -245.765635) (xy 361.674979 -245.802358)
			(xy 361.632963 -245.832884) (xy 361.586689 -245.856462) (xy 361.537296 -245.87251) (xy 361.486001 -245.880635)
			(xy 361.434067 -245.880635) (xy 361.382772 -245.87251) (xy 361.333379 -245.856462) (xy 361.287105 -245.832884)
			(xy 361.245089 -245.802358) (xy 361.208366 -245.765635) (xy 361.17784 -245.723619) (xy 361.154262 -245.677345)
			(xy 361.138214 -245.627952) (xy 361.130089 -245.576657) (xy 356.610876 -245.576657) (xy 356.588629 -245.598904)
			(xy 356.546613 -245.62943) (xy 356.500339 -245.653008) (xy 356.450946 -245.669056) (xy 356.399651 -245.677181)
			(xy 356.347717 -245.677181) (xy 356.296422 -245.669056) (xy 356.247029 -245.653008) (xy 356.200755 -245.62943)
			(xy 356.158739 -245.598904) (xy 356.122016 -245.562181) (xy 356.09149 -245.520165) (xy 356.067912 -245.473891)
			(xy 356.051864 -245.424498) (xy 356.043739 -245.373203) (xy 356.04323 -245.347236) (xy 351.314004 -245.347236)
			(xy 351.314004 -246.278654) (xy 351.314418 -246.288259) (xy 351.321479 -246.306126) (xy 351.334596 -246.320162)
			(xy 351.351945 -246.328413) (xy 351.361502 -246.329454) (xy 351.389297 -246.331899) (xy 351.443546 -246.344928)
			(xy 351.494836 -246.366884) (xy 351.541709 -246.397144) (xy 351.56267 -246.41556) (xy 351.569782 -246.422164)
			(xy 351.571814 -246.422672) (xy 351.583335 -246.430527) (xy 351.609465 -246.440232) (xy 351.637247 -246.442505)
			(xy 351.664607 -246.437176) (xy 351.689505 -246.424644) (xy 351.700084 -246.41556) (xy 351.718586 -246.399198)
			(xy 351.759538 -246.371588) (xy 351.804145 -246.350385) (xy 351.851412 -246.336062) (xy 351.900286 -246.32894)
			(xy 351.949675 -246.329177) (xy 351.97415 -246.332502) (xy 351.997057 -246.33645) (xy 352.041543 -246.349927)
			(xy 352.083704 -246.3695) (xy 352.122709 -246.394781) (xy 352.14052 -246.409718) (xy 352.145854 -246.414544)
			(xy 352.147124 -246.41556) (xy 352.158084 -246.424953) (xy 352.183943 -246.437743) (xy 352.212352 -246.442767)
			(xy 352.241029 -246.439621) (xy 352.267674 -246.428558) (xy 352.279204 -246.419878) (xy 352.290888 -246.409718)
			(xy 352.309025 -246.394508) (xy 352.348827 -246.36889) (xy 352.391874 -246.349204) (xy 352.437286 -246.335852)
			(xy 352.484137 -246.329108) (xy 352.507804 -246.328692) (xy 352.520504 -246.328946) (xy 352.527362 -246.3292)
			(xy 352.551077 -246.331021) (xy 352.597663 -246.340613) (xy 352.642392 -246.356785) (xy 352.68434 -246.379203)
			(xy 352.722642 -246.407402) (xy 352.756505 -246.440801) (xy 352.771202 -246.459502) (xy 352.780785 -246.471258)
			(xy 352.805352 -246.489017) (xy 352.834047 -246.498792) (xy 352.864347 -246.499722) (xy 352.893587 -246.491727)
			(xy 352.919198 -246.475508) (xy 352.929444 -246.464328) (xy 352.945192 -246.445118) (xy 352.981475 -246.411197)
			(xy 353.022431 -246.383093) (xy 353.067135 -246.361441) (xy 353.114578 -246.346731) (xy 353.163689 -246.339294)
			(xy 353.188524 -246.338852) (xy 353.214277 -246.339346) (xy 353.265159 -246.347336) (xy 353.314187 -246.363119)
			(xy 353.360174 -246.386314) (xy 353.402009 -246.416359) (xy 353.42068 -246.434102) (xy 353.43037 -246.443095)
			(xy 353.453302 -246.456227) (xy 353.478841 -246.463022) (xy 353.505267 -246.463022) (xy 353.530806 -246.456227)
			(xy 353.553738 -246.443095) (xy 353.563428 -246.434102) (xy 353.582103 -246.416361) (xy 353.62393 -246.386304)
			(xy 353.669916 -246.363104) (xy 353.718946 -246.347322) (xy 353.76983 -246.339341) (xy 353.795584 -246.338852)
			(xy 353.821554 -246.339334) (xy 353.872854 -246.347456) (xy 353.922252 -246.363505) (xy 353.968531 -246.387083)
			(xy 353.973197 -246.390473) (xy 357.840789 -246.390473) (xy 357.840789 -246.338539) (xy 357.848914 -246.287244)
			(xy 357.864962 -246.237851) (xy 357.88854 -246.191577) (xy 357.919066 -246.149561) (xy 357.955789 -246.112838)
			(xy 357.997805 -246.082312) (xy 358.044079 -246.058734) (xy 358.093472 -246.042686) (xy 358.144767 -246.034561)
			(xy 358.196701 -246.034561) (xy 358.247996 -246.042686) (xy 358.297389 -246.058734) (xy 358.343663 -246.082312)
			(xy 358.385679 -246.112838) (xy 358.422402 -246.149561) (xy 358.452928 -246.191577) (xy 358.476506 -246.237851)
			(xy 358.492554 -246.287244) (xy 358.500679 -246.338539) (xy 358.501188 -246.364506) (xy 358.500679 -246.390473)
			(xy 358.492554 -246.441768) (xy 358.476506 -246.491161) (xy 358.452928 -246.537435) (xy 358.422402 -246.579451)
			(xy 358.385679 -246.616174) (xy 358.343663 -246.6467) (xy 358.297389 -246.670278) (xy 358.247996 -246.686326)
			(xy 358.196701 -246.694451) (xy 358.144767 -246.694451) (xy 358.093472 -246.686326) (xy 358.044079 -246.670278)
			(xy 357.997805 -246.6467) (xy 357.955789 -246.616174) (xy 357.919066 -246.579451) (xy 357.88854 -246.537435)
			(xy 357.864962 -246.491161) (xy 357.848914 -246.441768) (xy 357.840789 -246.390473) (xy 353.973197 -246.390473)
			(xy 354.010551 -246.417611) (xy 354.047279 -246.454337) (xy 354.077809 -246.496356) (xy 354.101389 -246.542634)
			(xy 354.11744 -246.592031) (xy 354.125565 -246.64333) (xy 354.125565 -246.695269) (xy 365.433835 -246.695269)
			(xy 365.433835 -246.643331) (xy 365.44196 -246.592032) (xy 365.45801 -246.542635) (xy 365.48159 -246.496358)
			(xy 365.51212 -246.454339) (xy 365.548846 -246.417613) (xy 365.590866 -246.387085) (xy 365.637144 -246.363506)
			(xy 365.686541 -246.347458) (xy 365.737841 -246.339334) (xy 365.76381 -246.338852) (xy 365.789131 -246.339362)
			(xy 365.839183 -246.347072) (xy 365.887474 -246.362324) (xy 365.932874 -246.384763) (xy 365.974321 -246.413862)
			(xy 365.992918 -246.431054) (xy 366.00276 -246.439978) (xy 366.025974 -246.452879) (xy 366.051735 -246.459337)
			(xy 366.078289 -246.458913) (xy 366.10383 -246.451636) (xy 366.12662 -246.438) (xy 366.136174 -246.428768)
			(xy 366.15495 -246.410186) (xy 366.197343 -246.378672) (xy 366.244205 -246.354294) (xy 366.294346 -246.337673)
			(xy 366.346491 -246.329232) (xy 366.372902 -246.328692) (xy 366.398873 -246.32911) (xy 366.450175 -246.337235)
			(xy 366.499574 -246.353286) (xy 366.545854 -246.376867) (xy 366.587875 -246.407398) (xy 366.624603 -246.444126)
			(xy 366.655134 -246.486148) (xy 366.678714 -246.532428) (xy 366.694765 -246.581827) (xy 366.702891 -246.633129)
			(xy 366.702891 -246.685071) (xy 366.694765 -246.736373) (xy 366.678714 -246.785772) (xy 366.655134 -246.832052)
			(xy 366.624603 -246.874074) (xy 366.587875 -246.910802) (xy 366.545854 -246.941333) (xy 366.499574 -246.964914)
			(xy 366.450175 -246.980965) (xy 366.398873 -246.98909) (xy 366.372902 -246.9896) (xy 366.347578 -246.989157)
			(xy 366.297522 -246.981433) (xy 366.24923 -246.966166) (xy 366.203831 -246.943712) (xy 366.162388 -246.914597)
			(xy 366.143794 -246.897398) (xy 366.133939 -246.888491) (xy 366.110728 -246.875595) (xy 366.084972 -246.869139)
			(xy 366.058422 -246.86956) (xy 366.032884 -246.876831) (xy 366.010094 -246.890457) (xy 366.000538 -246.899684)
			(xy 365.981748 -246.918251) (xy 365.93936 -246.94977) (xy 365.892501 -246.974151) (xy 365.842363 -246.990775)
			(xy 365.790221 -246.999219) (xy 365.76381 -246.99976) (xy 365.737841 -246.999266) (xy 365.686541 -246.991142)
			(xy 365.637144 -246.975094) (xy 365.590866 -246.951515) (xy 365.548846 -246.920987) (xy 365.51212 -246.884261)
			(xy 365.48159 -246.842242) (xy 365.45801 -246.795965) (xy 365.44196 -246.746568) (xy 365.433835 -246.695269)
			(xy 354.125565 -246.695269) (xy 354.125565 -246.69527) (xy 354.11744 -246.746569) (xy 354.101389 -246.795966)
			(xy 354.077809 -246.842244) (xy 354.047279 -246.884263) (xy 354.010551 -246.920989) (xy 353.968531 -246.951517)
			(xy 353.922252 -246.975095) (xy 353.872854 -246.991144) (xy 353.821554 -246.999266) (xy 353.795584 -246.99976)
			(xy 353.769831 -246.999267) (xy 353.718948 -246.991278) (xy 353.669919 -246.975496) (xy 353.62393 -246.952303)
			(xy 353.582094 -246.922259) (xy 353.563428 -246.90451) (xy 353.553738 -246.895517) (xy 353.530806 -246.882385)
			(xy 353.505267 -246.87559) (xy 353.478841 -246.87559) (xy 353.453302 -246.882385) (xy 353.43037 -246.895517)
			(xy 353.42068 -246.90451) (xy 353.402008 -246.922256) (xy 353.360183 -246.952321) (xy 353.314197 -246.975529)
			(xy 353.265166 -246.991317) (xy 353.214279 -246.999301) (xy 353.188524 -246.99976) (xy 353.163113 -246.999296)
			(xy 353.112889 -246.991519) (xy 353.064448 -246.976144) (xy 353.018933 -246.953534) (xy 352.977415 -246.924222)
			(xy 352.940875 -246.888899) (xy 352.925126 -246.86895) (xy 352.915546 -246.857199) (xy 352.890986 -246.839451)
			(xy 352.8623 -246.82969) (xy 352.832013 -246.828773) (xy 352.802789 -246.836782) (xy 352.777201 -246.853011)
			(xy 352.766884 -246.864124) (xy 352.751135 -246.883332) (xy 352.71485 -246.917252) (xy 352.673894 -246.945355)
			(xy 352.629191 -246.967007) (xy 352.581749 -246.981718) (xy 352.532639 -246.989158) (xy 352.507804 -246.9896)
			(xy 352.488754 -246.989092) (xy 352.4885 -246.989092) (xy 352.461404 -246.986951) (xy 352.408398 -246.974944)
			(xy 352.358066 -246.954437) (xy 352.311761 -246.925983) (xy 352.290888 -246.908574) (xy 352.279204 -246.898414)
			(xy 352.267649 -246.88978) (xy 352.241013 -246.878744) (xy 352.212353 -246.875607) (xy 352.18396 -246.880619)
			(xy 352.158106 -246.893379) (xy 352.147124 -246.902732) (xy 352.12862 -246.91909) (xy 352.087666 -246.946694)
			(xy 352.043059 -246.967892) (xy 351.995793 -246.982211) (xy 351.946921 -246.989333) (xy 351.897534 -246.989097)
			(xy 351.873058 -246.98579) (xy 351.850151 -246.981843) (xy 351.805665 -246.968366) (xy 351.763504 -246.948794)
			(xy 351.724497 -246.923512) (xy 351.706688 -246.908574) (xy 351.701354 -246.903748) (xy 351.700084 -246.902732)
			(xy 351.688595 -246.892929) (xy 351.661358 -246.879915) (xy 351.631504 -246.875447) (xy 351.60165 -246.879915)
			(xy 351.574413 -246.892929) (xy 351.562924 -246.902732) (xy 351.561654 -246.903748) (xy 351.555304 -246.909336)
			(xy 351.534787 -246.926368) (xy 351.489346 -246.954266) (xy 351.440013 -246.974499) (xy 351.388069 -246.98654)
			(xy 351.361502 -246.988838) (xy 351.351934 -246.989859) (xy 351.334548 -246.99807) (xy 351.321421 -247.01212)
			(xy 351.314407 -247.030022) (xy 351.314004 -247.039638) (xy 351.314004 -247.204289) (xy 361.130089 -247.204289)
			(xy 361.130089 -247.152355) (xy 361.138214 -247.10106) (xy 361.154262 -247.051667) (xy 361.17784 -247.005393)
			(xy 361.208366 -246.963377) (xy 361.245089 -246.926654) (xy 361.287105 -246.896128) (xy 361.333379 -246.87255)
			(xy 361.382772 -246.856502) (xy 361.434067 -246.848377) (xy 361.486001 -246.848377) (xy 361.537296 -246.856502)
			(xy 361.586689 -246.87255) (xy 361.632963 -246.896128) (xy 361.674979 -246.926654) (xy 361.711702 -246.963377)
			(xy 361.742228 -247.005393) (xy 361.765806 -247.051667) (xy 361.781854 -247.10106) (xy 361.789979 -247.152355)
			(xy 361.790488 -247.178322) (xy 361.789979 -247.204289) (xy 361.781854 -247.255584) (xy 361.765806 -247.304977)
			(xy 361.742228 -247.351251) (xy 361.711702 -247.393267) (xy 361.674979 -247.42999) (xy 361.632963 -247.460516)
			(xy 361.586689 -247.484094) (xy 361.537296 -247.500142) (xy 361.486001 -247.508267) (xy 361.434067 -247.508267)
			(xy 361.382772 -247.500142) (xy 361.333379 -247.484094) (xy 361.287105 -247.460516) (xy 361.245089 -247.42999)
			(xy 361.208366 -247.393267) (xy 361.17784 -247.351251) (xy 361.154262 -247.304977) (xy 361.138214 -247.255584)
			(xy 361.130089 -247.204289) (xy 351.314004 -247.204289) (xy 351.314004 -248.018105) (xy 357.840789 -248.018105)
			(xy 357.840789 -247.966171) (xy 357.848914 -247.914876) (xy 357.864962 -247.865483) (xy 357.88854 -247.819209)
			(xy 357.919066 -247.777193) (xy 357.955789 -247.74047) (xy 357.997805 -247.709944) (xy 358.044079 -247.686366)
			(xy 358.093472 -247.670318) (xy 358.144767 -247.662193) (xy 358.196701 -247.662193) (xy 358.247996 -247.670318)
			(xy 358.297389 -247.686366) (xy 358.343663 -247.709944) (xy 358.385679 -247.74047) (xy 358.422402 -247.777193)
			(xy 358.452928 -247.819209) (xy 358.476506 -247.865483) (xy 358.492554 -247.914876) (xy 358.500679 -247.966171)
			(xy 358.501188 -247.992138) (xy 358.500679 -248.018105) (xy 358.492554 -248.0694) (xy 358.476506 -248.118793)
			(xy 358.452928 -248.165067) (xy 358.422402 -248.207083) (xy 358.385679 -248.243806) (xy 358.343663 -248.274332)
			(xy 358.297389 -248.29791) (xy 358.247996 -248.313958) (xy 358.196701 -248.322083) (xy 358.144767 -248.322083)
			(xy 358.093472 -248.313958) (xy 358.044079 -248.29791) (xy 357.997805 -248.274332) (xy 357.955789 -248.243806)
			(xy 357.919066 -248.207083) (xy 357.88854 -248.165067) (xy 357.864962 -248.118793) (xy 357.848914 -248.0694)
			(xy 357.840789 -248.018105) (xy 351.314004 -248.018105) (xy 351.314004 -249.00509) (xy 356.04323 -249.00509)
			(xy 356.043705 -248.980539) (xy 356.050938 -248.931974) (xy 356.065275 -248.885013) (xy 356.086399 -248.840689)
			(xy 356.113845 -248.799976) (xy 356.130098 -248.78157) (xy 356.139909 -248.770088) (xy 356.152919 -248.742848)
			(xy 356.157384 -248.712993) (xy 356.152915 -248.683138) (xy 356.139901 -248.6559) (xy 356.130098 -248.64441)
			(xy 356.113822 -248.626021) (xy 356.086356 -248.585312) (xy 356.065221 -248.540985) (xy 356.050883 -248.494017)
			(xy 356.043657 -248.445444) (xy 356.04323 -248.42089) (xy 356.043739 -248.394923) (xy 356.051864 -248.343628)
			(xy 356.067912 -248.294235) (xy 356.09149 -248.247961) (xy 356.122016 -248.205945) (xy 356.158739 -248.169222)
			(xy 356.200755 -248.138696) (xy 356.247029 -248.115118) (xy 356.296422 -248.09907) (xy 356.347717 -248.090945)
			(xy 356.399651 -248.090945) (xy 356.450946 -248.09907) (xy 356.500339 -248.115118) (xy 356.546613 -248.138696)
			(xy 356.588629 -248.169222) (xy 356.625352 -248.205945) (xy 356.655878 -248.247961) (xy 356.679456 -248.294235)
			(xy 356.695504 -248.343628) (xy 356.703629 -248.394923) (xy 356.704138 -248.42089) (xy 356.70372 -248.445443)
			(xy 356.696474 -248.494011) (xy 356.682125 -248.540973) (xy 356.660988 -248.585296) (xy 356.633529 -248.626006)
			(xy 356.61727 -248.64441) (xy 356.607472 -248.655905) (xy 356.594452 -248.683139) (xy 356.589979 -248.712993)
			(xy 356.594447 -248.742847) (xy 356.607464 -248.770083) (xy 356.61727 -248.78157) (xy 356.633532 -248.799972)
			(xy 356.655264 -248.832175) (xy 361.130089 -248.832175) (xy 361.130089 -248.780241) (xy 361.138214 -248.728946)
			(xy 361.154262 -248.679553) (xy 361.17784 -248.633279) (xy 361.208366 -248.591263) (xy 361.245089 -248.55454)
			(xy 361.287105 -248.524014) (xy 361.333379 -248.500436) (xy 361.382772 -248.484388) (xy 361.434067 -248.476263)
			(xy 361.486001 -248.476263) (xy 361.537296 -248.484388) (xy 361.586689 -248.500436) (xy 361.632963 -248.524014)
			(xy 361.674979 -248.55454) (xy 361.711702 -248.591263) (xy 361.742228 -248.633279) (xy 361.765806 -248.679553)
			(xy 361.781854 -248.728946) (xy 361.789979 -248.780241) (xy 361.790488 -248.806208) (xy 361.789979 -248.832175)
			(xy 361.781854 -248.88347) (xy 361.765806 -248.932863) (xy 361.742228 -248.979137) (xy 361.711702 -249.021153)
			(xy 361.674979 -249.057876) (xy 361.632963 -249.088402) (xy 361.586689 -249.11198) (xy 361.537296 -249.128028)
			(xy 361.486001 -249.136153) (xy 361.434067 -249.136153) (xy 361.382772 -249.128028) (xy 361.333379 -249.11198)
			(xy 361.287105 -249.088402) (xy 361.245089 -249.057876) (xy 361.208366 -249.021153) (xy 361.17784 -248.979137)
			(xy 361.154262 -248.932863) (xy 361.138214 -248.88347) (xy 361.130089 -248.832175) (xy 356.655264 -248.832175)
			(xy 356.661001 -248.840676) (xy 356.682139 -248.885) (xy 356.696481 -248.931965) (xy 356.70371 -248.980537)
			(xy 356.704138 -249.00509) (xy 356.703629 -249.031057) (xy 356.695504 -249.082352) (xy 356.679456 -249.131745)
			(xy 356.655878 -249.178019) (xy 356.625352 -249.220035) (xy 356.618555 -249.226832) (xy 362.992162 -249.226832)
			(xy 362.992593 -249.20228) (xy 362.999836 -249.153712) (xy 363.014182 -249.106751) (xy 363.035316 -249.062427)
			(xy 363.062773 -249.021716) (xy 363.07903 -249.003312) (xy 363.088806 -248.9918) (xy 363.101829 -248.964572)
			(xy 363.106306 -248.934724) (xy 363.101843 -248.904873) (xy 363.088833 -248.877639) (xy 363.07903 -248.866152)
			(xy 363.062779 -248.847742) (xy 363.035308 -248.807039) (xy 363.014168 -248.762718) (xy 362.999824 -248.715754)
			(xy 362.992592 -248.667185) (xy 362.992162 -248.642632) (xy 362.992671 -248.616665) (xy 363.000796 -248.56537)
			(xy 363.016844 -248.515977) (xy 363.040422 -248.469703) (xy 363.070948 -248.427687) (xy 363.107671 -248.390964)
			(xy 363.149687 -248.360438) (xy 363.195961 -248.33686) (xy 363.245354 -248.320812) (xy 363.296649 -248.312687)
			(xy 363.348583 -248.312687) (xy 363.399878 -248.320812) (xy 363.449271 -248.33686) (xy 363.495545 -248.360438)
			(xy 363.537561 -248.390964) (xy 363.574284 -248.427687) (xy 363.60481 -248.469703) (xy 363.628388 -248.515977)
			(xy 363.644436 -248.56537) (xy 363.652561 -248.616665) (xy 363.65307 -248.642632) (xy 363.652609 -248.667183)
			(xy 363.645372 -248.715749) (xy 363.631032 -248.76271) (xy 363.609905 -248.807034) (xy 363.582456 -248.847747)
			(xy 363.566202 -248.866152) (xy 363.556369 -248.877617) (xy 363.543362 -248.904863) (xy 363.5389 -248.934724)
			(xy 363.543375 -248.964582) (xy 363.556395 -248.991822) (xy 363.566202 -249.003312) (xy 363.582489 -249.021692)
			(xy 363.609953 -249.062404) (xy 363.631086 -249.106733) (xy 363.645422 -249.153702) (xy 363.652645 -249.202277)
			(xy 363.65307 -249.226832) (xy 363.652561 -249.252799) (xy 363.644436 -249.304094) (xy 363.628388 -249.353487)
			(xy 363.60481 -249.399761) (xy 363.574284 -249.441777) (xy 363.537561 -249.4785) (xy 363.495545 -249.509026)
			(xy 363.449271 -249.532604) (xy 363.399878 -249.548652) (xy 363.348583 -249.556777) (xy 363.296649 -249.556777)
			(xy 363.245354 -249.548652) (xy 363.195961 -249.532604) (xy 363.149687 -249.509026) (xy 363.107671 -249.4785)
			(xy 363.070948 -249.441777) (xy 363.040422 -249.399761) (xy 363.016844 -249.353487) (xy 363.000796 -249.304094)
			(xy 362.992671 -249.252799) (xy 362.992162 -249.226832) (xy 356.618555 -249.226832) (xy 356.588629 -249.256758)
			(xy 356.546613 -249.287284) (xy 356.500339 -249.310862) (xy 356.450946 -249.32691) (xy 356.399651 -249.335035)
			(xy 356.347717 -249.335035) (xy 356.296422 -249.32691) (xy 356.247029 -249.310862) (xy 356.200755 -249.287284)
			(xy 356.158739 -249.256758) (xy 356.122016 -249.220035) (xy 356.09149 -249.178019) (xy 356.067912 -249.131745)
			(xy 356.051864 -249.082352) (xy 356.043739 -249.031057) (xy 356.04323 -249.00509) (xy 351.314004 -249.00509)
			(xy 351.314004 -249.645991) (xy 357.840789 -249.645991) (xy 357.840789 -249.594057) (xy 357.848914 -249.542762)
			(xy 357.864962 -249.493369) (xy 357.88854 -249.447095) (xy 357.919066 -249.405079) (xy 357.955789 -249.368356)
			(xy 357.997805 -249.33783) (xy 358.044079 -249.314252) (xy 358.093472 -249.298204) (xy 358.144767 -249.290079)
			(xy 358.196701 -249.290079) (xy 358.247996 -249.298204) (xy 358.297389 -249.314252) (xy 358.343663 -249.33783)
			(xy 358.385679 -249.368356) (xy 358.422402 -249.405079) (xy 358.452928 -249.447095) (xy 358.476506 -249.493369)
			(xy 358.492554 -249.542762) (xy 358.500679 -249.594057) (xy 358.501188 -249.620024) (xy 358.500679 -249.645991)
			(xy 358.492554 -249.697286) (xy 358.476506 -249.746679) (xy 358.452928 -249.792953) (xy 358.422402 -249.834969)
			(xy 358.385679 -249.871692) (xy 358.343663 -249.902218) (xy 358.297389 -249.925796) (xy 358.247996 -249.941844)
			(xy 358.196701 -249.949969) (xy 358.144767 -249.949969) (xy 358.093472 -249.941844) (xy 358.044079 -249.925796)
			(xy 357.997805 -249.902218) (xy 357.955789 -249.871692) (xy 357.919066 -249.834969) (xy 357.88854 -249.792953)
			(xy 357.864962 -249.746679) (xy 357.848914 -249.697286) (xy 357.840789 -249.645991) (xy 351.314004 -249.645991)
			(xy 351.314004 -250.363072) (xy 353.066795 -250.363072) (xy 353.066795 -250.311128) (xy 353.074921 -250.259823)
			(xy 353.090973 -250.210421) (xy 353.114555 -250.164138) (xy 353.145087 -250.122115) (xy 353.181818 -250.085385)
			(xy 353.223842 -250.054853) (xy 353.270125 -250.031271) (xy 353.319527 -250.01522) (xy 353.370832 -250.007095)
			(xy 353.396804 -250.006612) (xy 353.422558 -250.007091) (xy 353.473444 -250.015072) (xy 353.522474 -250.030855)
			(xy 353.56846 -250.054059) (xy 353.610287 -250.084119) (xy 353.62896 -250.101862) (xy 353.63865 -250.110855)
			(xy 353.661582 -250.123987) (xy 353.687121 -250.130782) (xy 353.713547 -250.130782) (xy 353.739086 -250.123987)
			(xy 353.762018 -250.110855) (xy 353.771708 -250.101862) (xy 353.790394 -250.084135) (xy 353.832224 -250.054086)
			(xy 353.878207 -250.030887) (xy 353.927232 -250.0151) (xy 353.978112 -250.007107) (xy 354.003864 -250.006612)
			(xy 354.029832 -250.00716) (xy 354.081131 -250.01528) (xy 354.130527 -250.031325) (xy 354.176805 -250.0549)
			(xy 354.218825 -250.085425) (xy 354.255552 -250.122148) (xy 354.286081 -250.164164) (xy 354.309661 -250.21044)
			(xy 354.325712 -250.259834) (xy 354.333837 -250.311132) (xy 354.333837 -250.363068) (xy 354.333836 -250.363072)
			(xy 365.433795 -250.363072) (xy 365.433795 -250.311128) (xy 365.441921 -250.259822) (xy 365.457973 -250.21042)
			(xy 365.481556 -250.164137) (xy 365.512089 -250.122113) (xy 365.54882 -250.085383) (xy 365.590845 -250.054851)
			(xy 365.637129 -250.031269) (xy 365.686532 -250.015219) (xy 365.737838 -250.007094) (xy 365.76381 -250.006612)
			(xy 365.789672 -250.007101) (xy 365.840764 -250.015149) (xy 365.889978 -250.031063) (xy 365.936109 -250.054454)
			(xy 365.978031 -250.08475) (xy 365.996728 -250.102624) (xy 366.006443 -250.111669) (xy 366.029452 -250.124881)
			(xy 366.055089 -250.131718) (xy 366.081623 -250.131718) (xy 366.10726 -250.124881) (xy 366.130269 -250.111669)
			(xy 366.139984 -250.102624) (xy 366.158674 -250.084744) (xy 366.200604 -250.054462) (xy 366.246738 -250.03108)
			(xy 366.295951 -250.015167) (xy 366.347041 -250.007112) (xy 366.372902 -250.006612) (xy 366.398866 -250.007189)
			(xy 366.450156 -250.015313) (xy 366.499543 -250.03136) (xy 366.545812 -250.054936) (xy 366.587823 -250.085459)
			(xy 366.624542 -250.122178) (xy 366.655065 -250.16419) (xy 366.678641 -250.210459) (xy 366.694687 -250.259846)
			(xy 366.702811 -250.311136) (xy 366.702811 -250.363064) (xy 366.694687 -250.414354) (xy 366.678641 -250.463741)
			(xy 366.655065 -250.51001) (xy 366.624542 -250.552022) (xy 366.587823 -250.588741) (xy 366.545812 -250.619264)
			(xy 366.499543 -250.64284) (xy 366.450156 -250.658887) (xy 366.398866 -250.667011) (xy 366.372902 -250.66752)
			(xy 366.347041 -250.667014) (xy 366.29595 -250.658969) (xy 366.246737 -250.643058) (xy 366.200605 -250.619671)
			(xy 366.158682 -250.58938) (xy 366.139984 -250.571508) (xy 366.130269 -250.562463) (xy 366.10726 -250.549251)
			(xy 366.081623 -250.542414) (xy 366.055089 -250.542414) (xy 366.029452 -250.549251) (xy 366.006443 -250.562463)
			(xy 365.996728 -250.571508) (xy 365.978038 -250.589387) (xy 365.936107 -250.619668) (xy 365.889973 -250.64305)
			(xy 365.840761 -250.658963) (xy 365.789671 -250.667019) (xy 365.76381 -250.66752) (xy 365.737838 -250.667106)
			(xy 365.686532 -250.658981) (xy 365.637129 -250.642931) (xy 365.590845 -250.619349) (xy 365.54882 -250.588817)
			(xy 365.512089 -250.552087) (xy 365.481556 -250.510063) (xy 365.457973 -250.46378) (xy 365.441921 -250.414378)
			(xy 365.433795 -250.363072) (xy 354.333836 -250.363072) (xy 354.325712 -250.414366) (xy 354.309661 -250.46376)
			(xy 354.286081 -250.510036) (xy 354.255552 -250.552052) (xy 354.218825 -250.588775) (xy 354.176805 -250.6193)
			(xy 354.130527 -250.642875) (xy 354.081131 -250.65892) (xy 354.029832 -250.66704) (xy 354.003864 -250.66752)
			(xy 353.97811 -250.667052) (xy 353.927223 -250.659067) (xy 353.878193 -250.64328) (xy 353.832208 -250.620075)
			(xy 353.790381 -250.590014) (xy 353.771708 -250.57227) (xy 353.762018 -250.563277) (xy 353.739086 -250.550145)
			(xy 353.713547 -250.54335) (xy 353.687121 -250.54335) (xy 353.661582 -250.550145) (xy 353.63865 -250.563277)
			(xy 353.62896 -250.57227) (xy 353.610293 -250.590018) (xy 353.568458 -250.620063) (xy 353.522469 -250.643258)
			(xy 353.47344 -250.65904) (xy 353.422557 -250.667028) (xy 353.396804 -250.66752) (xy 353.370832 -250.667105)
			(xy 353.319527 -250.65898) (xy 353.270125 -250.642929) (xy 353.223842 -250.619347) (xy 353.181818 -250.588815)
			(xy 353.145087 -250.552085) (xy 353.114555 -250.510062) (xy 353.090973 -250.463779) (xy 353.074921 -250.414377)
			(xy 353.066795 -250.363072) (xy 351.314004 -250.363072) (xy 351.314004 -252.659134) (xy 356.04323 -252.659134)
			(xy 356.043671 -252.634582) (xy 356.050913 -252.586016) (xy 356.065257 -252.539054) (xy 356.086388 -252.49473)
			(xy 356.113842 -252.454019) (xy 356.130098 -252.435614) (xy 356.139866 -252.424098) (xy 356.152881 -252.39687)
			(xy 356.157355 -252.367025) (xy 356.152896 -252.337178) (xy 356.139895 -252.309944) (xy 356.130098 -252.298454)
			(xy 356.113843 -252.280047) (xy 356.086374 -252.239343) (xy 356.065235 -252.195021) (xy 356.050891 -252.148057)
			(xy 356.04366 -252.099487) (xy 356.04323 -252.074934) (xy 356.043739 -252.048967) (xy 356.051864 -251.997672)
			(xy 356.067912 -251.948279) (xy 356.09149 -251.902005) (xy 356.122016 -251.859989) (xy 356.158739 -251.823266)
			(xy 356.200755 -251.79274) (xy 356.247029 -251.769162) (xy 356.296422 -251.753114) (xy 356.347717 -251.744989)
			(xy 356.399651 -251.744989) (xy 356.450946 -251.753114) (xy 356.500339 -251.769162) (xy 356.546613 -251.79274)
			(xy 356.588629 -251.823266) (xy 356.625352 -251.859989) (xy 356.655878 -251.902005) (xy 356.679456 -251.948279)
			(xy 356.695504 -251.997672) (xy 356.703629 -252.048967) (xy 356.704138 -252.074934) (xy 356.703686 -252.099486)
			(xy 356.696448 -252.148052) (xy 356.682107 -252.195014) (xy 356.660978 -252.239338) (xy 356.633525 -252.280049)
			(xy 356.61727 -252.298454) (xy 356.60743 -252.309915) (xy 356.594414 -252.337162) (xy 356.589949 -252.367025)
			(xy 356.594428 -252.396887) (xy 356.607458 -252.424126) (xy 356.61727 -252.435614) (xy 356.633552 -252.453998)
			(xy 356.661018 -252.494708) (xy 356.682153 -252.539036) (xy 356.69649 -252.586005) (xy 356.703713 -252.634579)
			(xy 356.704138 -252.659134) (xy 356.703629 -252.685101) (xy 356.695504 -252.736396) (xy 356.679456 -252.785789)
			(xy 356.669315 -252.805692) (xy 363.042962 -252.805692) (xy 363.04343 -252.781141) (xy 363.050664 -252.732575)
			(xy 363.065001 -252.685614) (xy 363.086127 -252.641289) (xy 363.113576 -252.600577) (xy 363.12983 -252.582172)
			(xy 363.139645 -252.570691) (xy 363.152664 -252.543452) (xy 363.157133 -252.513594) (xy 363.15266 -252.483737)
			(xy 363.139638 -252.456499) (xy 363.12983 -252.445012) (xy 363.11356 -252.426618) (xy 363.086092 -252.385911)
			(xy 363.064955 -252.341585) (xy 363.050616 -252.294618) (xy 363.043389 -252.246046) (xy 363.042962 -252.221492)
			(xy 363.043471 -252.195525) (xy 363.051596 -252.14423) (xy 363.067644 -252.094837) (xy 363.091222 -252.048563)
			(xy 363.121748 -252.006547) (xy 363.158471 -251.969824) (xy 363.200487 -251.939298) (xy 363.246761 -251.91572)
			(xy 363.296154 -251.899672) (xy 363.347449 -251.891547) (xy 363.399383 -251.891547) (xy 363.450678 -251.899672)
			(xy 363.500071 -251.91572) (xy 363.546345 -251.939298) (xy 363.588361 -251.969824) (xy 363.625084 -252.006547)
			(xy 363.65561 -252.048563) (xy 363.679188 -252.094837) (xy 363.695236 -252.14423) (xy 363.703361 -252.195525)
			(xy 363.70387 -252.221492) (xy 363.703445 -252.246044) (xy 363.696199 -252.294612) (xy 363.681851 -252.341573)
			(xy 363.660716 -252.385897) (xy 363.633259 -252.426608) (xy 363.617002 -252.445012) (xy 363.607208 -252.456508)
			(xy 363.594197 -252.483743) (xy 363.589728 -252.513594) (xy 363.594193 -252.543446) (xy 363.607202 -252.570682)
			(xy 363.617002 -252.582172) (xy 363.63327 -252.600568) (xy 363.660737 -252.641275) (xy 363.681873 -252.6856)
			(xy 363.696214 -252.732566) (xy 363.703442 -252.781138) (xy 363.70387 -252.805692) (xy 363.703361 -252.831659)
			(xy 363.695236 -252.882954) (xy 363.679188 -252.932347) (xy 363.65561 -252.978621) (xy 363.625084 -253.020637)
			(xy 363.588361 -253.05736) (xy 363.546345 -253.087886) (xy 363.500071 -253.111464) (xy 363.450678 -253.127512)
			(xy 363.399383 -253.135637) (xy 363.347449 -253.135637) (xy 363.296154 -253.127512) (xy 363.246761 -253.111464)
			(xy 363.200487 -253.087886) (xy 363.158471 -253.05736) (xy 363.121748 -253.020637) (xy 363.091222 -252.978621)
			(xy 363.067644 -252.932347) (xy 363.051596 -252.882954) (xy 363.043471 -252.831659) (xy 363.042962 -252.805692)
			(xy 356.669315 -252.805692) (xy 356.655878 -252.832063) (xy 356.625352 -252.874079) (xy 356.588629 -252.910802)
			(xy 356.546613 -252.941328) (xy 356.500339 -252.964906) (xy 356.450946 -252.980954) (xy 356.399651 -252.989079)
			(xy 356.347717 -252.989079) (xy 356.296422 -252.980954) (xy 356.247029 -252.964906) (xy 356.200755 -252.941328)
			(xy 356.158739 -252.910802) (xy 356.122016 -252.874079) (xy 356.09149 -252.832063) (xy 356.067912 -252.785789)
			(xy 356.051864 -252.736396) (xy 356.043739 -252.685101) (xy 356.04323 -252.659134) (xy 351.314004 -252.659134)
			(xy 351.314004 -254.040971) (xy 353.066815 -254.040971) (xy 353.066815 -253.989029) (xy 353.07494 -253.937728)
			(xy 353.090991 -253.888329) (xy 353.114572 -253.842049) (xy 353.145103 -253.800028) (xy 353.181831 -253.7633)
			(xy 353.223852 -253.73277) (xy 353.270132 -253.70919) (xy 353.319532 -253.693139) (xy 353.370833 -253.685015)
			(xy 353.396804 -253.684532) (xy 353.422558 -253.685005) (xy 353.473445 -253.692987) (xy 353.522475 -253.708771)
			(xy 353.568461 -253.731976) (xy 353.610287 -253.762038) (xy 353.62896 -253.779782) (xy 353.63865 -253.788775)
			(xy 353.661582 -253.801907) (xy 353.687121 -253.808702) (xy 353.713547 -253.808702) (xy 353.739086 -253.801907)
			(xy 353.762018 -253.788775) (xy 353.771708 -253.779782) (xy 353.790381 -253.762041) (xy 353.832216 -253.731997)
			(xy 353.878203 -253.708802) (xy 353.92723 -253.693018) (xy 353.978111 -253.685027) (xy 354.003864 -253.684532)
			(xy 354.029834 -253.68504) (xy 354.081135 -253.69316) (xy 354.130535 -253.709206) (xy 354.176815 -253.732783)
			(xy 354.218838 -253.76331) (xy 354.255567 -253.800035) (xy 354.286098 -253.842054) (xy 354.30968 -253.888332)
			(xy 354.325731 -253.93773) (xy 354.326994 -253.945703) (xy 361.239817 -253.945703) (xy 361.239817 -253.893769)
			(xy 361.247942 -253.842474) (xy 361.26399 -253.793081) (xy 361.287568 -253.746807) (xy 361.318094 -253.704791)
			(xy 361.354817 -253.668068) (xy 361.396833 -253.637542) (xy 361.443107 -253.613964) (xy 361.4925 -253.597916)
			(xy 361.543795 -253.589791) (xy 361.595729 -253.589791) (xy 361.647024 -253.597916) (xy 361.696417 -253.613964)
			(xy 361.742691 -253.637542) (xy 361.784707 -253.668068) (xy 361.82143 -253.704791) (xy 361.851956 -253.746807)
			(xy 361.875534 -253.793081) (xy 361.891582 -253.842474) (xy 361.899707 -253.893769) (xy 361.900216 -253.919736)
			(xy 361.899707 -253.945703) (xy 361.891582 -253.996998) (xy 361.877295 -254.040971) (xy 365.433815 -254.040971)
			(xy 365.433815 -253.989029) (xy 365.441941 -253.937727) (xy 365.457992 -253.888327) (xy 365.481573 -253.842047)
			(xy 365.512104 -253.800026) (xy 365.548833 -253.763298) (xy 365.590856 -253.732768) (xy 365.637137 -253.709188)
			(xy 365.686537 -253.693138) (xy 365.737839 -253.685014) (xy 365.76381 -253.684532) (xy 365.78967 -253.685043)
			(xy 365.840761 -253.69309) (xy 365.889974 -253.709) (xy 365.936105 -253.732385) (xy 365.978029 -253.762674)
			(xy 365.996728 -253.780544) (xy 366.006443 -253.789589) (xy 366.029452 -253.802801) (xy 366.055089 -253.809638)
			(xy 366.081623 -253.809638) (xy 366.10726 -253.802801) (xy 366.130269 -253.789589) (xy 366.139984 -253.780544)
			(xy 366.158678 -253.762668) (xy 366.200606 -253.732384) (xy 366.246739 -253.709001) (xy 366.295951 -253.693087)
			(xy 366.347041 -253.685032) (xy 366.372902 -253.684532) (xy 366.398868 -253.685069) (xy 366.450161 -253.693194)
			(xy 366.499551 -253.709242) (xy 366.545823 -253.732819) (xy 366.587836 -253.763344) (xy 366.624558 -253.800065)
			(xy 366.655082 -253.842079) (xy 366.678659 -253.888351) (xy 366.694707 -253.937741) (xy 366.702831 -253.989034)
			(xy 366.702831 -254.040966) (xy 366.694707 -254.092259) (xy 366.678659 -254.141649) (xy 366.655082 -254.187921)
			(xy 366.624558 -254.229935) (xy 366.587836 -254.266656) (xy 366.545823 -254.297181) (xy 366.499551 -254.320758)
			(xy 366.450161 -254.336806) (xy 366.398868 -254.344931) (xy 366.372902 -254.34544) (xy 366.347042 -254.344929)
			(xy 366.295951 -254.336883) (xy 366.246738 -254.320974) (xy 366.200606 -254.297588) (xy 366.158683 -254.267299)
			(xy 366.139984 -254.249428) (xy 366.130269 -254.240383) (xy 366.10726 -254.227171) (xy 366.081623 -254.220334)
			(xy 366.055089 -254.220334) (xy 366.029452 -254.227171) (xy 366.006443 -254.240383) (xy 365.996728 -254.249428)
			(xy 365.978041 -254.267311) (xy 365.936109 -254.297591) (xy 365.889974 -254.320972) (xy 365.840761 -254.336884)
			(xy 365.789671 -254.344939) (xy 365.76381 -254.34544) (xy 365.737839 -254.344986) (xy 365.686537 -254.336862)
			(xy 365.637137 -254.320812) (xy 365.590856 -254.297232) (xy 365.548833 -254.266702) (xy 365.512104 -254.229974)
			(xy 365.481573 -254.187953) (xy 365.457992 -254.141673) (xy 365.441941 -254.092273) (xy 365.433815 -254.040971)
			(xy 361.877295 -254.040971) (xy 361.875534 -254.046391) (xy 361.851956 -254.092665) (xy 361.82143 -254.134681)
			(xy 361.784707 -254.171404) (xy 361.742691 -254.20193) (xy 361.696417 -254.225508) (xy 361.647024 -254.241556)
			(xy 361.595729 -254.249681) (xy 361.543795 -254.249681) (xy 361.4925 -254.241556) (xy 361.443107 -254.225508)
			(xy 361.396833 -254.20193) (xy 361.354817 -254.171404) (xy 361.318094 -254.134681) (xy 361.287568 -254.092665)
			(xy 361.26399 -254.046391) (xy 361.247942 -253.996998) (xy 361.239817 -253.945703) (xy 354.326994 -253.945703)
			(xy 354.333857 -253.98903) (xy 354.333857 -254.04097) (xy 354.325731 -254.09227) (xy 354.30968 -254.141668)
			(xy 354.286098 -254.187946) (xy 354.255567 -254.229965) (xy 354.218838 -254.26669) (xy 354.176815 -254.297217)
			(xy 354.130535 -254.320794) (xy 354.081135 -254.33684) (xy 354.029834 -254.34496) (xy 354.003864 -254.34544)
			(xy 353.97811 -254.344966) (xy 353.927224 -254.336982) (xy 353.878194 -254.321197) (xy 353.832209 -254.297993)
			(xy 353.790382 -254.267933) (xy 353.771708 -254.25019) (xy 353.762018 -254.241197) (xy 353.739086 -254.228065)
			(xy 353.713547 -254.22127) (xy 353.687121 -254.22127) (xy 353.661582 -254.228065) (xy 353.63865 -254.241197)
			(xy 353.62896 -254.25019) (xy 353.610296 -254.267941) (xy 353.56846 -254.297985) (xy 353.52247 -254.321179)
			(xy 353.473441 -254.33696) (xy 353.422557 -254.344948) (xy 353.396804 -254.34544) (xy 353.370833 -254.344985)
			(xy 353.319532 -254.336861) (xy 353.270132 -254.32081) (xy 353.223852 -254.29723) (xy 353.181831 -254.2667)
			(xy 353.145103 -254.229972) (xy 353.114572 -254.187951) (xy 353.090991 -254.141671) (xy 353.07494 -254.092272)
			(xy 353.066815 -254.040971) (xy 351.314004 -254.040971) (xy 351.314004 -254.759519) (xy 357.950517 -254.759519)
			(xy 357.950517 -254.707585) (xy 357.958642 -254.65629) (xy 357.97469 -254.606897) (xy 357.998268 -254.560623)
			(xy 358.028794 -254.518607) (xy 358.065517 -254.481884) (xy 358.107533 -254.451358) (xy 358.153807 -254.42778)
			(xy 358.2032 -254.411732) (xy 358.254495 -254.403607) (xy 358.306429 -254.403607) (xy 358.357724 -254.411732)
			(xy 358.407117 -254.42778) (xy 358.453391 -254.451358) (xy 358.495407 -254.481884) (xy 358.53213 -254.518607)
			(xy 358.562656 -254.560623) (xy 358.586234 -254.606897) (xy 358.602282 -254.65629) (xy 358.610407 -254.707585)
			(xy 358.610916 -254.733552) (xy 358.610407 -254.759519) (xy 358.602282 -254.810814) (xy 358.586234 -254.860207)
			(xy 358.562656 -254.906481) (xy 358.53213 -254.948497) (xy 358.495407 -254.98522) (xy 358.453391 -255.015746)
			(xy 358.407117 -255.039324) (xy 358.357724 -255.055372) (xy 358.306429 -255.063497) (xy 358.254495 -255.063497)
			(xy 358.2032 -255.055372) (xy 358.153807 -255.039324) (xy 358.107533 -255.015746) (xy 358.065517 -254.98522)
			(xy 358.028794 -254.948497) (xy 357.998268 -254.906481) (xy 357.97469 -254.860207) (xy 357.958642 -254.810814)
			(xy 357.950517 -254.759519) (xy 351.314004 -254.759519) (xy 351.314004 -256.257806) (xy 351.386394 -256.330196)
			(xy 356.04323 -256.330196) (xy 356.043648 -256.305643) (xy 356.050895 -256.257076) (xy 356.065245 -256.210114)
			(xy 356.086382 -256.165791) (xy 356.11384 -256.12508) (xy 356.130098 -256.106676) (xy 356.139903 -256.095189)
			(xy 356.152914 -256.067951) (xy 356.15738 -256.038097) (xy 356.152912 -256.008244) (xy 356.1399 -255.981006)
			(xy 356.130098 -255.969516) (xy 356.113825 -255.951124) (xy 356.086359 -255.910416) (xy 356.065223 -255.86609)
			(xy 356.050884 -255.819123) (xy 356.043657 -255.77055) (xy 356.04323 -255.745996) (xy 356.043739 -255.720029)
			(xy 356.051864 -255.668734) (xy 356.067912 -255.619341) (xy 356.09149 -255.573067) (xy 356.122016 -255.531051)
			(xy 356.158739 -255.494328) (xy 356.200755 -255.463802) (xy 356.247029 -255.440224) (xy 356.296422 -255.424176)
			(xy 356.347717 -255.416051) (xy 356.399651 -255.416051) (xy 356.450946 -255.424176) (xy 356.500339 -255.440224)
			(xy 356.546613 -255.463802) (xy 356.588629 -255.494328) (xy 356.625352 -255.531051) (xy 356.655878 -255.573067)
			(xy 356.656144 -255.573589) (xy 361.239817 -255.573589) (xy 361.239817 -255.521655) (xy 361.247942 -255.47036)
			(xy 361.26399 -255.420967) (xy 361.287568 -255.374693) (xy 361.318094 -255.332677) (xy 361.354817 -255.295954)
			(xy 361.396833 -255.265428) (xy 361.443107 -255.24185) (xy 361.4925 -255.225802) (xy 361.543795 -255.217677)
			(xy 361.595729 -255.217677) (xy 361.647024 -255.225802) (xy 361.696417 -255.24185) (xy 361.742691 -255.265428)
			(xy 361.784707 -255.295954) (xy 361.82143 -255.332677) (xy 361.851956 -255.374693) (xy 361.875534 -255.420967)
			(xy 361.891582 -255.47036) (xy 361.899707 -255.521655) (xy 361.900216 -255.547622) (xy 361.899707 -255.573589)
			(xy 361.891582 -255.624884) (xy 361.875534 -255.674277) (xy 361.851956 -255.720551) (xy 361.82143 -255.762567)
			(xy 361.784707 -255.79929) (xy 361.742691 -255.829816) (xy 361.696417 -255.853394) (xy 361.647024 -255.869442)
			(xy 361.595729 -255.877567) (xy 361.543795 -255.877567) (xy 361.4925 -255.869442) (xy 361.443107 -255.853394)
			(xy 361.396833 -255.829816) (xy 361.354817 -255.79929) (xy 361.318094 -255.762567) (xy 361.287568 -255.720551)
			(xy 361.26399 -255.674277) (xy 361.247942 -255.624884) (xy 361.239817 -255.573589) (xy 356.656144 -255.573589)
			(xy 356.679456 -255.619341) (xy 356.695504 -255.668734) (xy 356.703629 -255.720029) (xy 356.704138 -255.745996)
			(xy 356.703723 -255.770549) (xy 356.696476 -255.819117) (xy 356.682126 -255.866079) (xy 356.660989 -255.910403)
			(xy 356.633529 -255.951113) (xy 356.61727 -255.969516) (xy 356.607467 -255.981006) (xy 356.594446 -256.008242)
			(xy 356.589975 -256.038097) (xy 356.594445 -256.067952) (xy 356.607463 -256.095189) (xy 356.61727 -256.106676)
			(xy 356.633534 -256.125075) (xy 356.661003 -256.165781) (xy 356.682141 -256.210105) (xy 356.696482 -256.257071)
			(xy 356.70371 -256.305642) (xy 356.704138 -256.330196) (xy 356.703629 -256.356163) (xy 356.69868 -256.387405)
			(xy 357.950517 -256.387405) (xy 357.950517 -256.335471) (xy 357.958642 -256.284176) (xy 357.97469 -256.234783)
			(xy 357.998268 -256.188509) (xy 358.028794 -256.146493) (xy 358.065517 -256.10977) (xy 358.107533 -256.079244)
			(xy 358.153807 -256.055666) (xy 358.2032 -256.039618) (xy 358.254495 -256.031493) (xy 358.306429 -256.031493)
			(xy 358.357724 -256.039618) (xy 358.407117 -256.055666) (xy 358.453391 -256.079244) (xy 358.495407 -256.10977)
			(xy 358.53213 -256.146493) (xy 358.562656 -256.188509) (xy 358.586234 -256.234783) (xy 358.602282 -256.284176)
			(xy 358.610407 -256.335471) (xy 358.610916 -256.361438) (xy 358.610407 -256.387405) (xy 358.610054 -256.389632)
			(xy 363.037882 -256.389632) (xy 363.038308 -256.365079) (xy 363.045552 -256.316512) (xy 363.059899 -256.26955)
			(xy 363.081034 -256.225226) (xy 363.108492 -256.184515) (xy 363.12475 -256.166112) (xy 363.134524 -256.154599)
			(xy 363.147545 -256.127371) (xy 363.152021 -256.097524) (xy 363.147559 -256.067674) (xy 363.134551 -256.04044)
			(xy 363.12475 -256.028952) (xy 363.108502 -256.010539) (xy 363.08103 -255.969837) (xy 363.059889 -255.925517)
			(xy 363.045544 -255.878554) (xy 363.038312 -255.829985) (xy 363.037882 -255.805432) (xy 363.038391 -255.779465)
			(xy 363.046516 -255.72817) (xy 363.062564 -255.678777) (xy 363.086142 -255.632503) (xy 363.116668 -255.590487)
			(xy 363.153391 -255.553764) (xy 363.195407 -255.523238) (xy 363.241681 -255.49966) (xy 363.291074 -255.483612)
			(xy 363.342369 -255.475487) (xy 363.394303 -255.475487) (xy 363.445598 -255.483612) (xy 363.494991 -255.49966)
			(xy 363.541265 -255.523238) (xy 363.583281 -255.553764) (xy 363.620004 -255.590487) (xy 363.65053 -255.632503)
			(xy 363.674108 -255.678777) (xy 363.690156 -255.72817) (xy 363.698281 -255.779465) (xy 363.69879 -255.805432)
			(xy 363.698349 -255.829984) (xy 363.691111 -255.878551) (xy 363.676767 -255.925514) (xy 363.655635 -255.969838)
			(xy 363.628179 -256.010548) (xy 363.611922 -256.028952) (xy 363.602088 -256.040417) (xy 363.589078 -256.067663)
			(xy 363.584615 -256.097524) (xy 363.589092 -256.127383) (xy 363.602114 -256.154623) (xy 363.611922 -256.166112)
			(xy 363.628212 -256.18449) (xy 363.655675 -256.225202) (xy 363.676807 -256.269532) (xy 363.691142 -256.316502)
			(xy 363.698365 -256.365077) (xy 363.69879 -256.389632) (xy 363.698281 -256.415599) (xy 363.690156 -256.466894)
			(xy 363.674108 -256.516287) (xy 363.65053 -256.562561) (xy 363.620004 -256.604577) (xy 363.583281 -256.6413)
			(xy 363.541265 -256.671826) (xy 363.494991 -256.695404) (xy 363.445598 -256.711452) (xy 363.394303 -256.719577)
			(xy 363.342369 -256.719577) (xy 363.291074 -256.711452) (xy 363.241681 -256.695404) (xy 363.195407 -256.671826)
			(xy 363.153391 -256.6413) (xy 363.116668 -256.604577) (xy 363.086142 -256.562561) (xy 363.062564 -256.516287)
			(xy 363.046516 -256.466894) (xy 363.038391 -256.415599) (xy 363.037882 -256.389632) (xy 358.610054 -256.389632)
			(xy 358.602282 -256.4387) (xy 358.586234 -256.488093) (xy 358.562656 -256.534367) (xy 358.53213 -256.576383)
			(xy 358.495407 -256.613106) (xy 358.453391 -256.643632) (xy 358.407117 -256.66721) (xy 358.357724 -256.683258)
			(xy 358.306429 -256.691383) (xy 358.254495 -256.691383) (xy 358.2032 -256.683258) (xy 358.153807 -256.66721)
			(xy 358.107533 -256.643632) (xy 358.065517 -256.613106) (xy 358.028794 -256.576383) (xy 357.998268 -256.534367)
			(xy 357.97469 -256.488093) (xy 357.958642 -256.4387) (xy 357.950517 -256.387405) (xy 356.69868 -256.387405)
			(xy 356.695504 -256.407458) (xy 356.679456 -256.456851) (xy 356.655878 -256.503125) (xy 356.625352 -256.545141)
			(xy 356.588629 -256.581864) (xy 356.546613 -256.61239) (xy 356.500339 -256.635968) (xy 356.450946 -256.652016)
			(xy 356.399651 -256.660141) (xy 356.347717 -256.660141) (xy 356.296422 -256.652016) (xy 356.247029 -256.635968)
			(xy 356.200755 -256.61239) (xy 356.158739 -256.581864) (xy 356.122016 -256.545141) (xy 356.09149 -256.503125)
			(xy 356.067912 -256.456851) (xy 356.051864 -256.407458) (xy 356.043739 -256.356163) (xy 356.04323 -256.330196)
			(xy 351.386394 -256.330196) (xy 351.527364 -256.471166) (xy 352.744024 -256.471166) (xy 353.409504 -257.136646)
			(xy 353.409504 -257.201221) (xy 361.239817 -257.201221) (xy 361.239817 -257.149287) (xy 361.247942 -257.097992)
			(xy 361.26399 -257.048599) (xy 361.287568 -257.002325) (xy 361.318094 -256.960309) (xy 361.354817 -256.923586)
			(xy 361.396833 -256.89306) (xy 361.443107 -256.869482) (xy 361.4925 -256.853434) (xy 361.543795 -256.845309)
			(xy 361.595729 -256.845309) (xy 361.647024 -256.853434) (xy 361.696417 -256.869482) (xy 361.742691 -256.89306)
			(xy 361.784707 -256.923586) (xy 361.82143 -256.960309) (xy 361.851956 -257.002325) (xy 361.875534 -257.048599)
			(xy 361.891582 -257.097992) (xy 361.899707 -257.149287) (xy 361.900216 -257.175254) (xy 361.899707 -257.201221)
			(xy 361.891582 -257.252516) (xy 361.875534 -257.301909) (xy 361.851956 -257.348183) (xy 361.82143 -257.390199)
			(xy 361.784707 -257.426922) (xy 361.742691 -257.457448) (xy 361.696417 -257.481026) (xy 361.647024 -257.497074)
			(xy 361.595729 -257.505199) (xy 361.543795 -257.505199) (xy 361.4925 -257.497074) (xy 361.443107 -257.481026)
			(xy 361.396833 -257.457448) (xy 361.354817 -257.426922) (xy 361.318094 -257.390199) (xy 361.287568 -257.348183)
			(xy 361.26399 -257.301909) (xy 361.247942 -257.252516) (xy 361.239817 -257.201221) (xy 353.409504 -257.201221)
			(xy 353.409504 -257.359912) (xy 353.451922 -257.367024) (xy 353.476757 -257.371709) (xy 353.524722 -257.387625)
			(xy 353.569701 -257.410664) (xy 353.610645 -257.440288) (xy 353.62896 -257.457702) (xy 353.63865 -257.466695)
			(xy 353.661582 -257.479827) (xy 353.687121 -257.486622) (xy 353.713547 -257.486622) (xy 353.739086 -257.479827)
			(xy 353.762018 -257.466695) (xy 353.771708 -257.457702) (xy 353.790382 -257.439959) (xy 353.832209 -257.4099)
			(xy 353.878195 -257.386697) (xy 353.927224 -257.370912) (xy 353.97811 -257.362928) (xy 354.003864 -257.362452)
			(xy 354.029835 -257.362932) (xy 354.081137 -257.371053) (xy 354.130538 -257.387099) (xy 354.176819 -257.410676)
			(xy 354.218843 -257.441204) (xy 354.255573 -257.47793) (xy 354.286105 -257.51995) (xy 354.309687 -257.566229)
			(xy 354.325739 -257.615628) (xy 354.333865 -257.666929) (xy 354.333865 -257.718871) (xy 354.325739 -257.770172)
			(xy 354.309687 -257.819571) (xy 354.286105 -257.86585) (xy 354.255573 -257.90787) (xy 354.218843 -257.944596)
			(xy 354.176819 -257.975124) (xy 354.130538 -257.998701) (xy 354.081137 -258.014747) (xy 354.079305 -258.015037)
			(xy 357.950517 -258.015037) (xy 357.950517 -257.963103) (xy 357.958642 -257.911808) (xy 357.97469 -257.862415)
			(xy 357.998268 -257.816141) (xy 358.028794 -257.774125) (xy 358.065517 -257.737402) (xy 358.107533 -257.706876)
			(xy 358.153807 -257.683298) (xy 358.2032 -257.66725) (xy 358.254495 -257.659125) (xy 358.306429 -257.659125)
			(xy 358.357724 -257.66725) (xy 358.407117 -257.683298) (xy 358.453391 -257.706876) (xy 358.469898 -257.718869)
			(xy 365.433835 -257.718869) (xy 365.433835 -257.666931) (xy 365.44196 -257.615632) (xy 365.45801 -257.566235)
			(xy 365.48159 -257.519958) (xy 365.51212 -257.477939) (xy 365.548846 -257.441213) (xy 365.590866 -257.410685)
			(xy 365.637144 -257.387106) (xy 365.686541 -257.371058) (xy 365.737841 -257.362934) (xy 365.76381 -257.362452)
			(xy 365.789671 -257.362958) (xy 365.840762 -257.371005) (xy 365.889975 -257.386916) (xy 365.936106 -257.410303)
			(xy 365.978029 -257.440593) (xy 365.996728 -257.458464) (xy 366.006443 -257.467509) (xy 366.029452 -257.480721)
			(xy 366.055089 -257.487558) (xy 366.081623 -257.487558) (xy 366.10726 -257.480721) (xy 366.130269 -257.467509)
			(xy 366.139984 -257.458464) (xy 366.158664 -257.440574) (xy 366.200598 -257.410296) (xy 366.246735 -257.386916)
			(xy 366.295949 -257.371006) (xy 366.347041 -257.362952) (xy 366.372902 -257.362452) (xy 366.39887 -257.362949)
			(xy 366.450165 -257.371074) (xy 366.499559 -257.387123) (xy 366.545833 -257.410702) (xy 366.587849 -257.441228)
			(xy 366.624573 -257.477952) (xy 366.6551 -257.519969) (xy 366.678678 -257.566243) (xy 366.694726 -257.615637)
			(xy 366.702851 -257.666932) (xy 366.702851 -257.718868) (xy 366.694726 -257.770163) (xy 366.678678 -257.819557)
			(xy 366.6551 -257.865831) (xy 366.624573 -257.907848) (xy 366.587849 -257.944572) (xy 366.545833 -257.975098)
			(xy 366.499559 -257.998677) (xy 366.450165 -258.014726) (xy 366.39887 -258.022851) (xy 366.372902 -258.02336)
			(xy 366.347042 -258.022843) (xy 366.295951 -258.014798) (xy 366.246739 -257.99889) (xy 366.200607 -257.975506)
			(xy 366.158683 -257.945218) (xy 366.139984 -257.927348) (xy 366.130269 -257.918303) (xy 366.10726 -257.905091)
			(xy 366.081623 -257.898254) (xy 366.055089 -257.898254) (xy 366.029452 -257.905091) (xy 366.006443 -257.918303)
			(xy 365.996728 -257.927348) (xy 365.978028 -257.945217) (xy 365.936101 -257.975502) (xy 365.88997 -257.998887)
			(xy 365.840759 -258.014802) (xy 365.78967 -258.022859) (xy 365.76381 -258.02336) (xy 365.737841 -258.022866)
			(xy 365.686541 -258.014742) (xy 365.637144 -257.998694) (xy 365.590866 -257.975115) (xy 365.548846 -257.944587)
			(xy 365.51212 -257.907861) (xy 365.48159 -257.865842) (xy 365.45801 -257.819565) (xy 365.44196 -257.770168)
			(xy 365.433835 -257.718869) (xy 358.469898 -257.718869) (xy 358.495407 -257.737402) (xy 358.53213 -257.774125)
			(xy 358.562656 -257.816141) (xy 358.586234 -257.862415) (xy 358.602282 -257.911808) (xy 358.610407 -257.963103)
			(xy 358.610916 -257.98907) (xy 358.610407 -258.015037) (xy 358.602282 -258.066332) (xy 358.586234 -258.115725)
			(xy 358.562656 -258.161999) (xy 358.53213 -258.204015) (xy 358.495407 -258.240738) (xy 358.453391 -258.271264)
			(xy 358.407117 -258.294842) (xy 358.357724 -258.31089) (xy 358.306429 -258.319015) (xy 358.254495 -258.319015)
			(xy 358.2032 -258.31089) (xy 358.153807 -258.294842) (xy 358.107533 -258.271264) (xy 358.065517 -258.240738)
			(xy 358.028794 -258.204015) (xy 357.998268 -258.161999) (xy 357.97469 -258.115725) (xy 357.958642 -258.066332)
			(xy 357.950517 -258.015037) (xy 354.079305 -258.015037) (xy 354.029835 -258.022868) (xy 354.003864 -258.02336)
			(xy 353.978111 -258.022865) (xy 353.92723 -258.014874) (xy 353.878203 -257.99909) (xy 353.832217 -257.975894)
			(xy 353.790383 -257.945849) (xy 353.771708 -257.92811) (xy 353.762018 -257.919117) (xy 353.739086 -257.905985)
			(xy 353.713547 -257.89919) (xy 353.687121 -257.89919) (xy 353.661582 -257.905985) (xy 353.63865 -257.919117)
			(xy 353.62896 -257.92811) (xy 353.610641 -257.94552) (xy 353.569693 -257.975136) (xy 353.524716 -257.998179)
			(xy 353.476758 -258.014112) (xy 353.451922 -258.018788) (xy 353.409504 -258.0259) (xy 353.409504 -259.578348)
			(xy 356.04323 -259.578348) (xy 356.043679 -259.553796) (xy 356.050919 -259.50523) (xy 356.065261 -259.458269)
			(xy 356.086391 -259.413945) (xy 356.113843 -259.373233) (xy 356.130098 -259.354828) (xy 356.139853 -259.343301)
			(xy 356.152869 -259.316077) (xy 356.157345 -259.286236) (xy 356.15289 -259.256391) (xy 356.139893 -259.229158)
			(xy 356.130098 -259.217668) (xy 356.113849 -259.199256) (xy 356.08638 -259.158553) (xy 356.065239 -259.114232)
			(xy 356.050894 -259.06727) (xy 356.043661 -259.018701) (xy 356.04323 -258.994148) (xy 356.043739 -258.968181)
			(xy 356.051864 -258.916886) (xy 356.067912 -258.867493) (xy 356.09149 -258.821219) (xy 356.122016 -258.779203)
			(xy 356.158739 -258.74248) (xy 356.200755 -258.711954) (xy 356.247029 -258.688376) (xy 356.296422 -258.672328)
			(xy 356.347717 -258.664203) (xy 356.399651 -258.664203) (xy 356.450946 -258.672328) (xy 356.500339 -258.688376)
			(xy 356.546613 -258.711954) (xy 356.588629 -258.74248) (xy 356.625352 -258.779203) (xy 356.655878 -258.821219)
			(xy 356.659897 -258.829107) (xy 361.239817 -258.829107) (xy 361.239817 -258.777173) (xy 361.247942 -258.725878)
			(xy 361.26399 -258.676485) (xy 361.287568 -258.630211) (xy 361.318094 -258.588195) (xy 361.354817 -258.551472)
			(xy 361.396833 -258.520946) (xy 361.443107 -258.497368) (xy 361.4925 -258.48132) (xy 361.543795 -258.473195)
			(xy 361.595729 -258.473195) (xy 361.647024 -258.48132) (xy 361.696417 -258.497368) (xy 361.742691 -258.520946)
			(xy 361.784707 -258.551472) (xy 361.82143 -258.588195) (xy 361.851956 -258.630211) (xy 361.875534 -258.676485)
			(xy 361.891582 -258.725878) (xy 361.899707 -258.777173) (xy 361.900216 -258.80314) (xy 361.899707 -258.829107)
			(xy 361.891582 -258.880402) (xy 361.875534 -258.929795) (xy 361.851956 -258.976069) (xy 361.82143 -259.018085)
			(xy 361.784707 -259.054808) (xy 361.742691 -259.085334) (xy 361.696417 -259.108912) (xy 361.647024 -259.12496)
			(xy 361.595729 -259.133085) (xy 361.543795 -259.133085) (xy 361.4925 -259.12496) (xy 361.443107 -259.108912)
			(xy 361.396833 -259.085334) (xy 361.354817 -259.054808) (xy 361.318094 -259.018085) (xy 361.287568 -258.976069)
			(xy 361.26399 -258.929795) (xy 361.247942 -258.880402) (xy 361.239817 -258.829107) (xy 356.659897 -258.829107)
			(xy 356.679456 -258.867493) (xy 356.695504 -258.916886) (xy 356.703629 -258.968181) (xy 356.704138 -258.994148)
			(xy 356.703695 -259.0187) (xy 356.696455 -259.067267) (xy 356.682111 -259.114228) (xy 356.66098 -259.158552)
			(xy 356.633526 -259.199264) (xy 356.61727 -259.217668) (xy 356.607416 -259.229119) (xy 356.594402 -259.256369)
			(xy 356.58994 -259.286236) (xy 356.594422 -259.316099) (xy 356.607456 -259.34334) (xy 356.61727 -259.354828)
			(xy 356.633512 -259.373246) (xy 356.660983 -259.413947) (xy 356.682126 -259.458266) (xy 356.696472 -259.505228)
			(xy 356.703707 -259.553796) (xy 356.704138 -259.578348) (xy 356.703629 -259.604315) (xy 356.697514 -259.642923)
			(xy 357.950517 -259.642923) (xy 357.950517 -259.590989) (xy 357.958642 -259.539694) (xy 357.97469 -259.490301)
			(xy 357.998268 -259.444027) (xy 358.028794 -259.402011) (xy 358.065517 -259.365288) (xy 358.107533 -259.334762)
			(xy 358.153807 -259.311184) (xy 358.2032 -259.295136) (xy 358.254495 -259.287011) (xy 358.306429 -259.287011)
			(xy 358.357724 -259.295136) (xy 358.407117 -259.311184) (xy 358.453391 -259.334762) (xy 358.495407 -259.365288)
			(xy 358.53213 -259.402011) (xy 358.562656 -259.444027) (xy 358.586234 -259.490301) (xy 358.602282 -259.539694)
			(xy 358.610407 -259.590989) (xy 358.610916 -259.616956) (xy 358.610563 -259.63499) (xy 363.035596 -259.63499)
			(xy 363.036054 -259.610439) (xy 363.043289 -259.561872) (xy 363.057628 -259.51491) (xy 363.078756 -259.470586)
			(xy 363.106208 -259.429874) (xy 363.122464 -259.41147) (xy 363.132278 -259.399989) (xy 363.145292 -259.372749)
			(xy 363.149759 -259.342893) (xy 363.145288 -259.313037) (xy 363.13227 -259.285799) (xy 363.122464 -259.27431)
			(xy 363.106198 -259.255912) (xy 363.078729 -259.215206) (xy 363.057591 -259.170882) (xy 363.04325 -259.123916)
			(xy 363.036023 -259.075344) (xy 363.035596 -259.05079) (xy 363.036105 -259.024823) (xy 363.04423 -258.973528)
			(xy 363.060278 -258.924135) (xy 363.083856 -258.877861) (xy 363.114382 -258.835845) (xy 363.151105 -258.799122)
			(xy 363.193121 -258.768596) (xy 363.239395 -258.745018) (xy 363.288788 -258.72897) (xy 363.340083 -258.720845)
			(xy 363.392017 -258.720845) (xy 363.443312 -258.72897) (xy 363.492705 -258.745018) (xy 363.538979 -258.768596)
			(xy 363.580995 -258.799122) (xy 363.617718 -258.835845) (xy 363.648244 -258.877861) (xy 363.671822 -258.924135)
			(xy 363.68787 -258.973528) (xy 363.695995 -259.024823) (xy 363.696504 -259.05079) (xy 363.696095 -259.075343)
			(xy 363.688848 -259.123912) (xy 363.674497 -259.170874) (xy 363.653358 -259.215198) (xy 363.625896 -259.255907)
			(xy 363.609636 -259.27431) (xy 363.599841 -259.285806) (xy 363.586825 -259.313041) (xy 363.582354 -259.342893)
			(xy 363.586821 -259.372745) (xy 363.599833 -259.399981) (xy 363.609636 -259.41147) (xy 363.625892 -259.429876)
			(xy 363.653363 -259.470579) (xy 363.674503 -259.514902) (xy 363.688846 -259.561866) (xy 363.696076 -259.610437)
			(xy 363.696504 -259.63499) (xy 363.695995 -259.660957) (xy 363.68787 -259.712252) (xy 363.671822 -259.761645)
			(xy 363.648244 -259.807919) (xy 363.617718 -259.849935) (xy 363.580995 -259.886658) (xy 363.538979 -259.917184)
			(xy 363.492705 -259.940762) (xy 363.443312 -259.95681) (xy 363.392017 -259.964935) (xy 363.340083 -259.964935)
			(xy 363.288788 -259.95681) (xy 363.239395 -259.940762) (xy 363.193121 -259.917184) (xy 363.151105 -259.886658)
			(xy 363.114382 -259.849935) (xy 363.083856 -259.807919) (xy 363.060278 -259.761645) (xy 363.04423 -259.712252)
			(xy 363.036105 -259.660957) (xy 363.035596 -259.63499) (xy 358.610563 -259.63499) (xy 358.610407 -259.642923)
			(xy 358.602282 -259.694218) (xy 358.586234 -259.743611) (xy 358.562656 -259.789885) (xy 358.53213 -259.831901)
			(xy 358.495407 -259.868624) (xy 358.453391 -259.89915) (xy 358.407117 -259.922728) (xy 358.357724 -259.938776)
			(xy 358.306429 -259.946901) (xy 358.254495 -259.946901) (xy 358.2032 -259.938776) (xy 358.153807 -259.922728)
			(xy 358.107533 -259.89915) (xy 358.065517 -259.868624) (xy 358.028794 -259.831901) (xy 357.998268 -259.789885)
			(xy 357.97469 -259.743611) (xy 357.958642 -259.694218) (xy 357.950517 -259.642923) (xy 356.697514 -259.642923)
			(xy 356.695504 -259.65561) (xy 356.679456 -259.705003) (xy 356.655878 -259.751277) (xy 356.625352 -259.793293)
			(xy 356.588629 -259.830016) (xy 356.546613 -259.860542) (xy 356.500339 -259.88412) (xy 356.450946 -259.900168)
			(xy 356.399651 -259.908293) (xy 356.347717 -259.908293) (xy 356.296422 -259.900168) (xy 356.247029 -259.88412)
			(xy 356.200755 -259.860542) (xy 356.158739 -259.830016) (xy 356.122016 -259.793293) (xy 356.09149 -259.751277)
			(xy 356.067912 -259.705003) (xy 356.051864 -259.65561) (xy 356.043739 -259.604315) (xy 356.04323 -259.578348)
			(xy 353.409504 -259.578348) (xy 353.409504 -260.456739) (xy 361.239817 -260.456739) (xy 361.239817 -260.404805)
			(xy 361.247942 -260.35351) (xy 361.26399 -260.304117) (xy 361.287568 -260.257843) (xy 361.318094 -260.215827)
			(xy 361.354817 -260.179104) (xy 361.396833 -260.148578) (xy 361.443107 -260.125) (xy 361.4925 -260.108952)
			(xy 361.543795 -260.100827) (xy 361.595729 -260.100827) (xy 361.647024 -260.108952) (xy 361.696417 -260.125)
			(xy 361.742691 -260.148578) (xy 361.784707 -260.179104) (xy 361.82143 -260.215827) (xy 361.851956 -260.257843)
			(xy 361.875534 -260.304117) (xy 361.891582 -260.35351) (xy 361.899707 -260.404805) (xy 361.900216 -260.430772)
			(xy 361.899707 -260.456739) (xy 361.891582 -260.508034) (xy 361.875534 -260.557427) (xy 361.851956 -260.603701)
			(xy 361.82143 -260.645717) (xy 361.784707 -260.68244) (xy 361.742691 -260.712966) (xy 361.696417 -260.736544)
			(xy 361.647024 -260.752592) (xy 361.595729 -260.760717) (xy 361.543795 -260.760717) (xy 361.4925 -260.752592)
			(xy 361.443107 -260.736544) (xy 361.396833 -260.712966) (xy 361.354817 -260.68244) (xy 361.318094 -260.645717)
			(xy 361.287568 -260.603701) (xy 361.26399 -260.557427) (xy 361.247942 -260.508034) (xy 361.239817 -260.456739)
			(xy 353.409504 -260.456739) (xy 353.409504 -261.063232) (xy 353.431094 -261.080758) (xy 353.438149 -261.087024)
			(xy 353.451619 -261.10024) (xy 353.458018 -261.107174) (xy 353.467755 -261.116463) (xy 353.490989 -261.130024)
			(xy 353.516957 -261.137047) (xy 353.543859 -261.137047) (xy 353.569827 -261.130024) (xy 353.593061 -261.116463)
			(xy 353.602798 -261.107174) (xy 353.620001 -261.088875) (xy 353.658956 -261.057177) (xy 353.702255 -261.031733)
			(xy 353.748905 -261.01313) (xy 353.797831 -261.001793) (xy 353.847908 -260.997986) (xy 353.897985 -261.001793)
			(xy 353.946911 -261.01313) (xy 353.993561 -261.031733) (xy 354.03686 -261.057177) (xy 354.075815 -261.088875)
			(xy 354.093018 -261.107174) (xy 354.102755 -261.116463) (xy 354.125989 -261.130024) (xy 354.151957 -261.137047)
			(xy 354.178859 -261.137047) (xy 354.204827 -261.130024) (xy 354.228061 -261.116463) (xy 354.237798 -261.107174)
			(xy 354.255001 -261.088875) (xy 354.293956 -261.057177) (xy 354.337255 -261.031733) (xy 354.383905 -261.01313)
			(xy 354.432831 -261.001793) (xy 354.482908 -260.997986) (xy 354.532985 -261.001793) (xy 354.581911 -261.01313)
			(xy 354.628561 -261.031733) (xy 354.67186 -261.057177) (xy 354.710815 -261.088875) (xy 354.728018 -261.107174)
			(xy 354.737755 -261.116463) (xy 354.760989 -261.130024) (xy 354.786957 -261.137047) (xy 354.813859 -261.137047)
			(xy 354.839827 -261.130024) (xy 354.863061 -261.116463) (xy 354.872798 -261.107174) (xy 354.891756 -261.087073)
			(xy 354.935138 -261.052859) (xy 354.983602 -261.02633) (xy 355.035801 -261.008223) (xy 355.090283 -260.999043)
			(xy 355.117908 -260.998462) (xy 355.143874 -260.998972) (xy 355.195165 -261.007097) (xy 355.244554 -261.023145)
			(xy 355.290825 -261.046722) (xy 355.332838 -261.077247) (xy 355.369558 -261.113969) (xy 355.400082 -261.155982)
			(xy 355.423658 -261.202253) (xy 355.439705 -261.251643) (xy 355.442741 -261.270809) (xy 357.950517 -261.270809)
			(xy 357.950517 -261.218875) (xy 357.958642 -261.16758) (xy 357.97469 -261.118187) (xy 357.998268 -261.071913)
			(xy 358.028794 -261.029897) (xy 358.065517 -260.993174) (xy 358.107533 -260.962648) (xy 358.153807 -260.93907)
			(xy 358.2032 -260.923022) (xy 358.254495 -260.914897) (xy 358.306429 -260.914897) (xy 358.357724 -260.923022)
			(xy 358.407117 -260.93907) (xy 358.453391 -260.962648) (xy 358.495407 -260.993174) (xy 358.53213 -261.029897)
			(xy 358.562656 -261.071913) (xy 358.586234 -261.118187) (xy 358.602282 -261.16758) (xy 358.610407 -261.218875)
			(xy 358.610916 -261.244842) (xy 358.610407 -261.270809) (xy 358.602282 -261.322104) (xy 358.586234 -261.371497)
			(xy 358.562656 -261.417771) (xy 358.53213 -261.459787) (xy 358.495407 -261.49651) (xy 358.453391 -261.527036)
			(xy 358.407117 -261.550614) (xy 358.357724 -261.566662) (xy 358.306429 -261.574787) (xy 358.254495 -261.574787)
			(xy 358.2032 -261.566662) (xy 358.153807 -261.550614) (xy 358.107533 -261.527036) (xy 358.065517 -261.49651)
			(xy 358.028794 -261.459787) (xy 357.998268 -261.417771) (xy 357.97469 -261.371497) (xy 357.958642 -261.322104)
			(xy 357.950517 -261.270809) (xy 355.442741 -261.270809) (xy 355.447829 -261.302934) (xy 355.447829 -261.354866)
			(xy 355.439705 -261.406157) (xy 355.423658 -261.455547) (xy 355.400082 -261.501818) (xy 355.369558 -261.543831)
			(xy 355.332838 -261.580553) (xy 355.290825 -261.611078) (xy 355.244554 -261.634655) (xy 355.195165 -261.650703)
			(xy 355.143874 -261.658828) (xy 355.117908 -261.65937) (xy 355.090281 -261.658815) (xy 355.035797 -261.649632)
			(xy 354.983596 -261.631522) (xy 354.935132 -261.604986) (xy 354.891752 -261.570765) (xy 354.872798 -261.550658)
			(xy 354.863061 -261.541369) (xy 354.839827 -261.527808) (xy 354.813859 -261.520785) (xy 354.786957 -261.520785)
			(xy 354.760989 -261.527808) (xy 354.737755 -261.541369) (xy 354.728018 -261.550658) (xy 354.710815 -261.568957)
			(xy 354.67186 -261.600655) (xy 354.628561 -261.626099) (xy 354.581911 -261.644702) (xy 354.532985 -261.656039)
			(xy 354.482908 -261.659846) (xy 354.432831 -261.656039) (xy 354.383905 -261.644702) (xy 354.337255 -261.626099)
			(xy 354.293956 -261.600655) (xy 354.255001 -261.568957) (xy 354.237798 -261.550658) (xy 354.228061 -261.541369)
			(xy 354.204827 -261.527808) (xy 354.178859 -261.520785) (xy 354.151957 -261.520785) (xy 354.125989 -261.527808)
			(xy 354.102755 -261.541369) (xy 354.093018 -261.550658) (xy 354.075815 -261.568957) (xy 354.03686 -261.600655)
			(xy 353.993561 -261.626099) (xy 353.946911 -261.644702) (xy 353.897985 -261.656039) (xy 353.847908 -261.659846)
			(xy 353.797831 -261.656039) (xy 353.748905 -261.644702) (xy 353.702255 -261.626099) (xy 353.658956 -261.600655)
			(xy 353.620001 -261.568957) (xy 353.602798 -261.550658) (xy 353.593061 -261.541369) (xy 353.569827 -261.527808)
			(xy 353.543859 -261.520785) (xy 353.516957 -261.520785) (xy 353.490989 -261.527808) (xy 353.467755 -261.541369)
			(xy 353.458018 -261.550658) (xy 353.451625 -261.557598) (xy 353.438155 -261.570814) (xy 353.431094 -261.577074)
			(xy 353.409504 -261.5946) (xy 353.409504 -262.084625) (xy 361.239817 -262.084625) (xy 361.239817 -262.032691)
			(xy 361.247942 -261.981396) (xy 361.26399 -261.932003) (xy 361.287568 -261.885729) (xy 361.318094 -261.843713)
			(xy 361.354817 -261.80699) (xy 361.396833 -261.776464) (xy 361.443107 -261.752886) (xy 361.4925 -261.736838)
			(xy 361.543795 -261.728713) (xy 361.595729 -261.728713) (xy 361.647024 -261.736838) (xy 361.696417 -261.752886)
			(xy 361.742691 -261.776464) (xy 361.784707 -261.80699) (xy 361.82143 -261.843713) (xy 361.851956 -261.885729)
			(xy 361.875534 -261.932003) (xy 361.891582 -261.981396) (xy 361.899707 -262.032691) (xy 361.900216 -262.058658)
			(xy 361.899707 -262.084625) (xy 361.891582 -262.13592) (xy 361.875534 -262.185313) (xy 361.851956 -262.231587)
			(xy 361.82143 -262.273603) (xy 361.784707 -262.310326) (xy 361.742691 -262.340852) (xy 361.696417 -262.36443)
			(xy 361.647024 -262.380478) (xy 361.595729 -262.388603) (xy 361.543795 -262.388603) (xy 361.4925 -262.380478)
			(xy 361.443107 -262.36443) (xy 361.396833 -262.340852) (xy 361.354817 -262.310326) (xy 361.318094 -262.273603)
			(xy 361.287568 -262.231587) (xy 361.26399 -262.185313) (xy 361.247942 -262.13592) (xy 361.239817 -262.084625)
			(xy 353.409504 -262.084625) (xy 353.409504 -262.898441) (xy 357.950517 -262.898441) (xy 357.950517 -262.846507)
			(xy 357.958642 -262.795212) (xy 357.97469 -262.745819) (xy 357.998268 -262.699545) (xy 358.028794 -262.657529)
			(xy 358.065517 -262.620806) (xy 358.107533 -262.59028) (xy 358.153807 -262.566702) (xy 358.2032 -262.550654)
			(xy 358.254495 -262.542529) (xy 358.306429 -262.542529) (xy 358.357724 -262.550654) (xy 358.407117 -262.566702)
			(xy 358.453391 -262.59028) (xy 358.495407 -262.620806) (xy 358.53213 -262.657529) (xy 358.562656 -262.699545)
			(xy 358.586234 -262.745819) (xy 358.602282 -262.795212) (xy 358.610407 -262.846507) (xy 358.610916 -262.872474)
			(xy 358.610407 -262.898441) (xy 358.602282 -262.949736) (xy 358.586234 -262.999129) (xy 358.562656 -263.045403)
			(xy 358.53213 -263.087419) (xy 358.495407 -263.124142) (xy 358.453391 -263.154668) (xy 358.407117 -263.178246)
			(xy 358.357724 -263.194294) (xy 358.306429 -263.202419) (xy 358.254495 -263.202419) (xy 358.2032 -263.194294)
			(xy 358.153807 -263.178246) (xy 358.107533 -263.154668) (xy 358.065517 -263.124142) (xy 358.028794 -263.087419)
			(xy 357.998268 -263.045403) (xy 357.97469 -262.999129) (xy 357.958642 -262.949736) (xy 357.950517 -262.898441)
			(xy 353.409504 -262.898441) (xy 353.409504 -264.074148) (xy 353.409977 -264.088866) (xy 353.418342 -264.117086)
			(xy 353.43442 -264.141742) (xy 353.45687 -264.160778) (xy 353.483822 -264.172608) (xy 353.513031 -264.176246)
			(xy 353.527614 -264.174224) (xy 353.540981 -264.172172) (xy 353.567939 -264.170009) (xy 353.581462 -264.169906)
			(xy 353.607436 -264.170386) (xy 353.658746 -264.178507) (xy 353.708154 -264.194556) (xy 353.754442 -264.218136)
			(xy 353.796472 -264.248668) (xy 353.833207 -264.285399) (xy 353.863744 -264.327425) (xy 353.88733 -264.373711)
			(xy 353.903384 -264.423117) (xy 353.911511 -264.474426) (xy 353.911511 -264.526327) (xy 354.191317 -264.526327)
			(xy 354.191317 -264.474393) (xy 354.199442 -264.423098) (xy 354.21549 -264.373705) (xy 354.239068 -264.327431)
			(xy 354.269594 -264.285415) (xy 354.306317 -264.248692) (xy 354.348333 -264.218166) (xy 354.394607 -264.194588)
			(xy 354.444 -264.17854) (xy 354.495295 -264.170415) (xy 354.547229 -264.170415) (xy 354.598524 -264.17854)
			(xy 354.647917 -264.194588) (xy 354.694191 -264.218166) (xy 354.736207 -264.248692) (xy 354.77293 -264.285415)
			(xy 354.803456 -264.327431) (xy 354.827034 -264.373705) (xy 354.843082 -264.423098) (xy 354.851207 -264.474393)
			(xy 354.851716 -264.50036) (xy 354.851207 -264.526327) (xy 355.131371 -264.526327) (xy 355.131371 -264.474393)
			(xy 355.139496 -264.423098) (xy 355.155544 -264.373705) (xy 355.179122 -264.327431) (xy 355.209648 -264.285415)
			(xy 355.246371 -264.248692) (xy 355.288387 -264.218166) (xy 355.334661 -264.194588) (xy 355.384054 -264.17854)
			(xy 355.435349 -264.170415) (xy 355.487283 -264.170415) (xy 355.538578 -264.17854) (xy 355.587971 -264.194588)
			(xy 355.634245 -264.218166) (xy 355.676261 -264.248692) (xy 355.712984 -264.285415) (xy 355.74351 -264.327431)
			(xy 355.767088 -264.373705) (xy 355.783136 -264.423098) (xy 355.791261 -264.474393) (xy 355.79177 -264.50036)
			(xy 355.791261 -264.526327) (xy 356.071171 -264.526327) (xy 356.071171 -264.474393) (xy 356.079296 -264.423098)
			(xy 356.095344 -264.373705) (xy 356.118922 -264.327431) (xy 356.149448 -264.285415) (xy 356.186171 -264.248692)
			(xy 356.228187 -264.218166) (xy 356.274461 -264.194588) (xy 356.323854 -264.17854) (xy 356.375149 -264.170415)
			(xy 356.427083 -264.170415) (xy 356.478378 -264.17854) (xy 356.527771 -264.194588) (xy 356.574045 -264.218166)
			(xy 356.616061 -264.248692) (xy 356.652784 -264.285415) (xy 356.68331 -264.327431) (xy 356.706888 -264.373705)
			(xy 356.722936 -264.423098) (xy 356.731061 -264.474393) (xy 356.73157 -264.50036) (xy 356.731061 -264.526327)
			(xy 356.722936 -264.577622) (xy 356.706888 -264.627015) (xy 356.68331 -264.673289) (xy 356.652784 -264.715305)
			(xy 356.616061 -264.752028) (xy 356.574045 -264.782554) (xy 356.527771 -264.806132) (xy 356.478378 -264.82218)
			(xy 356.427083 -264.830305) (xy 356.375149 -264.830305) (xy 356.323854 -264.82218) (xy 356.274461 -264.806132)
			(xy 356.228187 -264.782554) (xy 356.186171 -264.752028) (xy 356.149448 -264.715305) (xy 356.118922 -264.673289)
			(xy 356.095344 -264.627015) (xy 356.079296 -264.577622) (xy 356.071171 -264.526327) (xy 355.791261 -264.526327)
			(xy 355.783136 -264.577622) (xy 355.767088 -264.627015) (xy 355.74351 -264.673289) (xy 355.712984 -264.715305)
			(xy 355.676261 -264.752028) (xy 355.634245 -264.782554) (xy 355.587971 -264.806132) (xy 355.538578 -264.82218)
			(xy 355.487283 -264.830305) (xy 355.435349 -264.830305) (xy 355.384054 -264.82218) (xy 355.334661 -264.806132)
			(xy 355.288387 -264.782554) (xy 355.246371 -264.752028) (xy 355.209648 -264.715305) (xy 355.179122 -264.673289)
			(xy 355.155544 -264.627015) (xy 355.139496 -264.577622) (xy 355.131371 -264.526327) (xy 354.851207 -264.526327)
			(xy 354.843082 -264.577622) (xy 354.827034 -264.627015) (xy 354.803456 -264.673289) (xy 354.77293 -264.715305)
			(xy 354.736207 -264.752028) (xy 354.694191 -264.782554) (xy 354.647917 -264.806132) (xy 354.598524 -264.82218)
			(xy 354.547229 -264.830305) (xy 354.495295 -264.830305) (xy 354.444 -264.82218) (xy 354.394607 -264.806132)
			(xy 354.348333 -264.782554) (xy 354.306317 -264.752028) (xy 354.269594 -264.715305) (xy 354.239068 -264.673289)
			(xy 354.21549 -264.627015) (xy 354.199442 -264.577622) (xy 354.191317 -264.526327) (xy 353.911511 -264.526327)
			(xy 353.911511 -264.526374) (xy 353.903384 -264.577683) (xy 353.88733 -264.627089) (xy 353.863744 -264.673375)
			(xy 353.833207 -264.715401) (xy 353.796472 -264.752132) (xy 353.754442 -264.782664) (xy 353.708154 -264.806244)
			(xy 353.658746 -264.822293) (xy 353.607436 -264.830414) (xy 353.581462 -264.830814) (xy 353.56794 -264.830696)
			(xy 353.540982 -264.828538) (xy 353.527614 -264.826496) (xy 353.513037 -264.824604) (xy 353.483889 -264.828304)
			(xy 353.456998 -264.840143) (xy 353.434585 -264.859143) (xy 353.418504 -264.883733) (xy 353.410082 -264.911882)
			(xy 353.409504 -264.926572) (xy 353.409504 -265.170412) (xy 353.413822 -265.180064) (xy 353.42453 -265.205549)
			(xy 353.438248 -265.259096) (xy 353.442866 -265.314178) (xy 353.440693 -265.340143) (xy 353.721671 -265.340143)
			(xy 353.721671 -265.288209) (xy 353.729796 -265.236914) (xy 353.745844 -265.187521) (xy 353.769422 -265.141247)
			(xy 353.799948 -265.099231) (xy 353.836671 -265.062508) (xy 353.878687 -265.031982) (xy 353.924961 -265.008404)
			(xy 353.974354 -264.992356) (xy 354.025649 -264.984231) (xy 354.077583 -264.984231) (xy 354.128878 -264.992356)
			(xy 354.178271 -265.008404) (xy 354.224545 -265.031982) (xy 354.266561 -265.062508) (xy 354.303284 -265.099231)
			(xy 354.33381 -265.141247) (xy 354.357388 -265.187521) (xy 354.373436 -265.236914) (xy 354.381561 -265.288209)
			(xy 354.38207 -265.314176) (xy 354.381561 -265.340143) (xy 354.661471 -265.340143) (xy 354.661471 -265.288209)
			(xy 354.669596 -265.236914) (xy 354.685644 -265.187521) (xy 354.709222 -265.141247) (xy 354.739748 -265.099231)
			(xy 354.776471 -265.062508) (xy 354.818487 -265.031982) (xy 354.864761 -265.008404) (xy 354.914154 -264.992356)
			(xy 354.965449 -264.984231) (xy 355.017383 -264.984231) (xy 355.068678 -264.992356) (xy 355.118071 -265.008404)
			(xy 355.164345 -265.031982) (xy 355.206361 -265.062508) (xy 355.243084 -265.099231) (xy 355.27361 -265.141247)
			(xy 355.297188 -265.187521) (xy 355.313236 -265.236914) (xy 355.321361 -265.288209) (xy 355.32187 -265.314176)
			(xy 355.321361 -265.340143) (xy 355.601271 -265.340143) (xy 355.601271 -265.288209) (xy 355.609396 -265.236914)
			(xy 355.625444 -265.187521) (xy 355.649022 -265.141247) (xy 355.679548 -265.099231) (xy 355.716271 -265.062508)
			(xy 355.758287 -265.031982) (xy 355.804561 -265.008404) (xy 355.853954 -264.992356) (xy 355.905249 -264.984231)
			(xy 355.957183 -264.984231) (xy 356.008478 -264.992356) (xy 356.057871 -265.008404) (xy 356.104145 -265.031982)
			(xy 356.146161 -265.062508) (xy 356.182884 -265.099231) (xy 356.21341 -265.141247) (xy 356.236988 -265.187521)
			(xy 356.253036 -265.236914) (xy 356.261161 -265.288209) (xy 356.26167 -265.314176) (xy 356.261161 -265.340143)
			(xy 356.541071 -265.340143) (xy 356.541071 -265.288209) (xy 356.549196 -265.236914) (xy 356.565244 -265.187521)
			(xy 356.588822 -265.141247) (xy 356.619348 -265.099231) (xy 356.656071 -265.062508) (xy 356.698087 -265.031982)
			(xy 356.744361 -265.008404) (xy 356.793754 -264.992356) (xy 356.845049 -264.984231) (xy 356.896983 -264.984231)
			(xy 356.948278 -264.992356) (xy 356.997671 -265.008404) (xy 357.043945 -265.031982) (xy 357.085961 -265.062508)
			(xy 357.122684 -265.099231) (xy 357.15321 -265.141247) (xy 357.176788 -265.187521) (xy 357.192836 -265.236914)
			(xy 357.200961 -265.288209) (xy 357.20147 -265.314176) (xy 357.200961 -265.340143) (xy 357.192836 -265.391438)
			(xy 357.176788 -265.440831) (xy 357.15321 -265.487105) (xy 357.122684 -265.529121) (xy 357.085961 -265.565844)
			(xy 357.043945 -265.59637) (xy 356.997671 -265.619948) (xy 356.948278 -265.635996) (xy 356.896983 -265.644121)
			(xy 356.845049 -265.644121) (xy 356.793754 -265.635996) (xy 356.744361 -265.619948) (xy 356.698087 -265.59637)
			(xy 356.656071 -265.565844) (xy 356.619348 -265.529121) (xy 356.588822 -265.487105) (xy 356.565244 -265.440831)
			(xy 356.549196 -265.391438) (xy 356.541071 -265.340143) (xy 356.261161 -265.340143) (xy 356.253036 -265.391438)
			(xy 356.236988 -265.440831) (xy 356.21341 -265.487105) (xy 356.182884 -265.529121) (xy 356.146161 -265.565844)
			(xy 356.104145 -265.59637) (xy 356.057871 -265.619948) (xy 356.008478 -265.635996) (xy 355.957183 -265.644121)
			(xy 355.905249 -265.644121) (xy 355.853954 -265.635996) (xy 355.804561 -265.619948) (xy 355.758287 -265.59637)
			(xy 355.716271 -265.565844) (xy 355.679548 -265.529121) (xy 355.649022 -265.487105) (xy 355.625444 -265.440831)
			(xy 355.609396 -265.391438) (xy 355.601271 -265.340143) (xy 355.321361 -265.340143) (xy 355.313236 -265.391438)
			(xy 355.297188 -265.440831) (xy 355.27361 -265.487105) (xy 355.243084 -265.529121) (xy 355.206361 -265.565844)
			(xy 355.164345 -265.59637) (xy 355.118071 -265.619948) (xy 355.068678 -265.635996) (xy 355.017383 -265.644121)
			(xy 354.965449 -265.644121) (xy 354.914154 -265.635996) (xy 354.864761 -265.619948) (xy 354.818487 -265.59637)
			(xy 354.776471 -265.565844) (xy 354.739748 -265.529121) (xy 354.709222 -265.487105) (xy 354.685644 -265.440831)
			(xy 354.669596 -265.391438) (xy 354.661471 -265.340143) (xy 354.381561 -265.340143) (xy 354.373436 -265.391438)
			(xy 354.357388 -265.440831) (xy 354.33381 -265.487105) (xy 354.303284 -265.529121) (xy 354.266561 -265.565844)
			(xy 354.224545 -265.59637) (xy 354.178271 -265.619948) (xy 354.128878 -265.635996) (xy 354.077583 -265.644121)
			(xy 354.025649 -265.644121) (xy 353.974354 -265.635996) (xy 353.924961 -265.619948) (xy 353.878687 -265.59637)
			(xy 353.836671 -265.565844) (xy 353.799948 -265.529121) (xy 353.769422 -265.487105) (xy 353.745844 -265.440831)
			(xy 353.729796 -265.391438) (xy 353.721671 -265.340143) (xy 353.440693 -265.340143) (xy 353.438256 -265.369261)
			(xy 353.424544 -265.422809) (xy 353.413822 -265.448288) (xy 353.409504 -265.45794) (xy 353.409504 -265.702034)
			(xy 353.409988 -265.716743) (xy 353.418368 -265.744942) (xy 353.434449 -265.769575) (xy 353.456894 -265.788592)
			(xy 353.483833 -265.80041) (xy 353.513025 -265.804046) (xy 353.527614 -265.80211) (xy 353.540981 -265.800058)
			(xy 353.567939 -265.797895) (xy 353.581462 -265.797792) (xy 353.60743 -265.798272) (xy 353.658726 -265.806391)
			(xy 353.708121 -265.822435) (xy 353.754397 -265.84601) (xy 353.796416 -265.876533) (xy 353.833142 -265.913255)
			(xy 353.86367 -265.95527) (xy 353.88725 -266.001544) (xy 353.9033 -266.050937) (xy 353.911425 -266.102232)
			(xy 353.911425 -266.154168) (xy 353.911418 -266.154213) (xy 354.191317 -266.154213) (xy 354.191317 -266.102279)
			(xy 354.199442 -266.050984) (xy 354.21549 -266.001591) (xy 354.239068 -265.955317) (xy 354.269594 -265.913301)
			(xy 354.306317 -265.876578) (xy 354.348333 -265.846052) (xy 354.394607 -265.822474) (xy 354.444 -265.806426)
			(xy 354.495295 -265.798301) (xy 354.547229 -265.798301) (xy 354.598524 -265.806426) (xy 354.647917 -265.822474)
			(xy 354.694191 -265.846052) (xy 354.736207 -265.876578) (xy 354.77293 -265.913301) (xy 354.803456 -265.955317)
			(xy 354.827034 -266.001591) (xy 354.843082 -266.050984) (xy 354.851207 -266.102279) (xy 354.851716 -266.128246)
			(xy 354.851207 -266.154213) (xy 355.131117 -266.154213) (xy 355.131117 -266.102279) (xy 355.139242 -266.050984)
			(xy 355.15529 -266.001591) (xy 355.178868 -265.955317) (xy 355.209394 -265.913301) (xy 355.246117 -265.876578)
			(xy 355.288133 -265.846052) (xy 355.334407 -265.822474) (xy 355.3838 -265.806426) (xy 355.435095 -265.798301)
			(xy 355.487029 -265.798301) (xy 355.538324 -265.806426) (xy 355.587717 -265.822474) (xy 355.633991 -265.846052)
			(xy 355.676007 -265.876578) (xy 355.71273 -265.913301) (xy 355.743256 -265.955317) (xy 355.766834 -266.001591)
			(xy 355.782882 -266.050984) (xy 355.791007 -266.102279) (xy 355.791516 -266.128246) (xy 355.791007 -266.154213)
			(xy 356.070917 -266.154213) (xy 356.070917 -266.102279) (xy 356.079042 -266.050984) (xy 356.09509 -266.001591)
			(xy 356.118668 -265.955317) (xy 356.149194 -265.913301) (xy 356.185917 -265.876578) (xy 356.227933 -265.846052)
			(xy 356.274207 -265.822474) (xy 356.3236 -265.806426) (xy 356.374895 -265.798301) (xy 356.426829 -265.798301)
			(xy 356.478124 -265.806426) (xy 356.527517 -265.822474) (xy 356.573791 -265.846052) (xy 356.615807 -265.876578)
			(xy 356.65253 -265.913301) (xy 356.683056 -265.955317) (xy 356.706634 -266.001591) (xy 356.722682 -266.050984)
			(xy 356.730807 -266.102279) (xy 356.731316 -266.128246) (xy 356.730807 -266.154213) (xy 357.010971 -266.154213)
			(xy 357.010971 -266.102279) (xy 357.019096 -266.050984) (xy 357.035144 -266.001591) (xy 357.058722 -265.955317)
			(xy 357.089248 -265.913301) (xy 357.125971 -265.876578) (xy 357.167987 -265.846052) (xy 357.214261 -265.822474)
			(xy 357.263654 -265.806426) (xy 357.314949 -265.798301) (xy 357.366883 -265.798301) (xy 357.418178 -265.806426)
			(xy 357.467571 -265.822474) (xy 357.513845 -265.846052) (xy 357.555861 -265.876578) (xy 357.592584 -265.913301)
			(xy 357.62311 -265.955317) (xy 357.646688 -266.001591) (xy 357.662736 -266.050984) (xy 357.670861 -266.102279)
			(xy 357.67137 -266.128246) (xy 357.670861 -266.154213) (xy 357.662736 -266.205508) (xy 357.646688 -266.254901)
			(xy 357.62311 -266.301175) (xy 357.592584 -266.343191) (xy 357.555861 -266.379914) (xy 357.513845 -266.41044)
			(xy 357.467571 -266.434018) (xy 357.418178 -266.450066) (xy 357.366883 -266.458191) (xy 357.314949 -266.458191)
			(xy 357.263654 -266.450066) (xy 357.214261 -266.434018) (xy 357.167987 -266.41044) (xy 357.125971 -266.379914)
			(xy 357.089248 -266.343191) (xy 357.058722 -266.301175) (xy 357.035144 -266.254901) (xy 357.019096 -266.205508)
			(xy 357.010971 -266.154213) (xy 356.730807 -266.154213) (xy 356.722682 -266.205508) (xy 356.706634 -266.254901)
			(xy 356.683056 -266.301175) (xy 356.65253 -266.343191) (xy 356.615807 -266.379914) (xy 356.573791 -266.41044)
			(xy 356.527517 -266.434018) (xy 356.478124 -266.450066) (xy 356.426829 -266.458191) (xy 356.374895 -266.458191)
			(xy 356.3236 -266.450066) (xy 356.274207 -266.434018) (xy 356.227933 -266.41044) (xy 356.185917 -266.379914)
			(xy 356.149194 -266.343191) (xy 356.118668 -266.301175) (xy 356.09509 -266.254901) (xy 356.079042 -266.205508)
			(xy 356.070917 -266.154213) (xy 355.791007 -266.154213) (xy 355.782882 -266.205508) (xy 355.766834 -266.254901)
			(xy 355.743256 -266.301175) (xy 355.71273 -266.343191) (xy 355.676007 -266.379914) (xy 355.633991 -266.41044)
			(xy 355.587717 -266.434018) (xy 355.538324 -266.450066) (xy 355.487029 -266.458191) (xy 355.435095 -266.458191)
			(xy 355.3838 -266.450066) (xy 355.334407 -266.434018) (xy 355.288133 -266.41044) (xy 355.246117 -266.379914)
			(xy 355.209394 -266.343191) (xy 355.178868 -266.301175) (xy 355.15529 -266.254901) (xy 355.139242 -266.205508)
			(xy 355.131117 -266.154213) (xy 354.851207 -266.154213) (xy 354.843082 -266.205508) (xy 354.827034 -266.254901)
			(xy 354.803456 -266.301175) (xy 354.77293 -266.343191) (xy 354.736207 -266.379914) (xy 354.694191 -266.41044)
			(xy 354.647917 -266.434018) (xy 354.598524 -266.450066) (xy 354.547229 -266.458191) (xy 354.495295 -266.458191)
			(xy 354.444 -266.450066) (xy 354.394607 -266.434018) (xy 354.348333 -266.41044) (xy 354.306317 -266.379914)
			(xy 354.269594 -266.343191) (xy 354.239068 -266.301175) (xy 354.21549 -266.254901) (xy 354.199442 -266.205508)
			(xy 354.191317 -266.154213) (xy 353.911418 -266.154213) (xy 353.9033 -266.205463) (xy 353.88725 -266.254856)
			(xy 353.86367 -266.30113) (xy 353.833142 -266.343145) (xy 353.796416 -266.379867) (xy 353.754397 -266.41039)
			(xy 353.708121 -266.433965) (xy 353.658726 -266.450009) (xy 353.60743 -266.458128) (xy 353.581462 -266.4587)
			(xy 353.56794 -266.458582) (xy 353.540982 -266.456424) (xy 353.527614 -266.454382) (xy 353.513036 -266.452491)
			(xy 353.483887 -266.45619) (xy 353.456994 -266.468029) (xy 353.43458 -266.487028) (xy 353.418496 -266.511618)
			(xy 353.410071 -266.539768) (xy 353.409504 -266.554458) (xy 353.409504 -266.798044) (xy 353.413822 -266.807696)
			(xy 353.424527 -266.833181) (xy 353.43824 -266.886727) (xy 353.442854 -266.941807) (xy 353.440678 -266.967775)
			(xy 353.721671 -266.967775) (xy 353.721671 -266.915841) (xy 353.729796 -266.864546) (xy 353.745844 -266.815153)
			(xy 353.769422 -266.768879) (xy 353.799948 -266.726863) (xy 353.836671 -266.69014) (xy 353.878687 -266.659614)
			(xy 353.924961 -266.636036) (xy 353.974354 -266.619988) (xy 354.025649 -266.611863) (xy 354.077583 -266.611863)
			(xy 354.128878 -266.619988) (xy 354.178271 -266.636036) (xy 354.224545 -266.659614) (xy 354.266561 -266.69014)
			(xy 354.303284 -266.726863) (xy 354.33381 -266.768879) (xy 354.357388 -266.815153) (xy 354.373436 -266.864546)
			(xy 354.381561 -266.915841) (xy 354.38207 -266.941808) (xy 354.381561 -266.967775) (xy 354.661471 -266.967775)
			(xy 354.661471 -266.915841) (xy 354.669596 -266.864546) (xy 354.685644 -266.815153) (xy 354.709222 -266.768879)
			(xy 354.739748 -266.726863) (xy 354.776471 -266.69014) (xy 354.818487 -266.659614) (xy 354.864761 -266.636036)
			(xy 354.914154 -266.619988) (xy 354.965449 -266.611863) (xy 355.017383 -266.611863) (xy 355.068678 -266.619988)
			(xy 355.118071 -266.636036) (xy 355.164345 -266.659614) (xy 355.206361 -266.69014) (xy 355.243084 -266.726863)
			(xy 355.27361 -266.768879) (xy 355.297188 -266.815153) (xy 355.313236 -266.864546) (xy 355.321361 -266.915841)
			(xy 355.32187 -266.941808) (xy 355.321361 -266.967775) (xy 355.601271 -266.967775) (xy 355.601271 -266.915841)
			(xy 355.609396 -266.864546) (xy 355.625444 -266.815153) (xy 355.649022 -266.768879) (xy 355.679548 -266.726863)
			(xy 355.716271 -266.69014) (xy 355.758287 -266.659614) (xy 355.804561 -266.636036) (xy 355.853954 -266.619988)
			(xy 355.905249 -266.611863) (xy 355.957183 -266.611863) (xy 356.008478 -266.619988) (xy 356.057871 -266.636036)
			(xy 356.104145 -266.659614) (xy 356.146161 -266.69014) (xy 356.182884 -266.726863) (xy 356.21341 -266.768879)
			(xy 356.236988 -266.815153) (xy 356.253036 -266.864546) (xy 356.261161 -266.915841) (xy 356.26167 -266.941808)
			(xy 356.261161 -266.967775) (xy 356.541071 -266.967775) (xy 356.541071 -266.915841) (xy 356.549196 -266.864546)
			(xy 356.565244 -266.815153) (xy 356.588822 -266.768879) (xy 356.619348 -266.726863) (xy 356.656071 -266.69014)
			(xy 356.698087 -266.659614) (xy 356.744361 -266.636036) (xy 356.793754 -266.619988) (xy 356.845049 -266.611863)
			(xy 356.896983 -266.611863) (xy 356.948278 -266.619988) (xy 356.997671 -266.636036) (xy 357.043945 -266.659614)
			(xy 357.085961 -266.69014) (xy 357.122684 -266.726863) (xy 357.15321 -266.768879) (xy 357.176788 -266.815153)
			(xy 357.192836 -266.864546) (xy 357.200961 -266.915841) (xy 357.20147 -266.941808) (xy 357.200961 -266.967775)
			(xy 357.480617 -266.967775) (xy 357.480617 -266.915841) (xy 357.488742 -266.864546) (xy 357.50479 -266.815153)
			(xy 357.528368 -266.768879) (xy 357.558894 -266.726863) (xy 357.595617 -266.69014) (xy 357.637633 -266.659614)
			(xy 357.683907 -266.636036) (xy 357.7333 -266.619988) (xy 357.784595 -266.611863) (xy 357.836529 -266.611863)
			(xy 357.887824 -266.619988) (xy 357.937217 -266.636036) (xy 357.983491 -266.659614) (xy 358.025507 -266.69014)
			(xy 358.06223 -266.726863) (xy 358.092756 -266.768879) (xy 358.116334 -266.815153) (xy 358.132382 -266.864546)
			(xy 358.140507 -266.915841) (xy 358.141016 -266.941808) (xy 358.140507 -266.967775) (xy 358.132382 -267.01907)
			(xy 358.116334 -267.068463) (xy 358.092756 -267.114737) (xy 358.06223 -267.156753) (xy 358.025507 -267.193476)
			(xy 357.983491 -267.224002) (xy 357.937217 -267.24758) (xy 357.887824 -267.263628) (xy 357.836529 -267.271753)
			(xy 357.784595 -267.271753) (xy 357.7333 -267.263628) (xy 357.683907 -267.24758) (xy 357.637633 -267.224002)
			(xy 357.595617 -267.193476) (xy 357.558894 -267.156753) (xy 357.528368 -267.114737) (xy 357.50479 -267.068463)
			(xy 357.488742 -267.01907) (xy 357.480617 -266.967775) (xy 357.200961 -266.967775) (xy 357.192836 -267.01907)
			(xy 357.176788 -267.068463) (xy 357.15321 -267.114737) (xy 357.122684 -267.156753) (xy 357.085961 -267.193476)
			(xy 357.043945 -267.224002) (xy 356.997671 -267.24758) (xy 356.948278 -267.263628) (xy 356.896983 -267.271753)
			(xy 356.845049 -267.271753) (xy 356.793754 -267.263628) (xy 356.744361 -267.24758) (xy 356.698087 -267.224002)
			(xy 356.656071 -267.193476) (xy 356.619348 -267.156753) (xy 356.588822 -267.114737) (xy 356.565244 -267.068463)
			(xy 356.549196 -267.01907) (xy 356.541071 -266.967775) (xy 356.261161 -266.967775) (xy 356.253036 -267.01907)
			(xy 356.236988 -267.068463) (xy 356.21341 -267.114737) (xy 356.182884 -267.156753) (xy 356.146161 -267.193476)
			(xy 356.104145 -267.224002) (xy 356.057871 -267.24758) (xy 356.008478 -267.263628) (xy 355.957183 -267.271753)
			(xy 355.905249 -267.271753) (xy 355.853954 -267.263628) (xy 355.804561 -267.24758) (xy 355.758287 -267.224002)
			(xy 355.716271 -267.193476) (xy 355.679548 -267.156753) (xy 355.649022 -267.114737) (xy 355.625444 -267.068463)
			(xy 355.609396 -267.01907) (xy 355.601271 -266.967775) (xy 355.321361 -266.967775) (xy 355.313236 -267.01907)
			(xy 355.297188 -267.068463) (xy 355.27361 -267.114737) (xy 355.243084 -267.156753) (xy 355.206361 -267.193476)
			(xy 355.164345 -267.224002) (xy 355.118071 -267.24758) (xy 355.068678 -267.263628) (xy 355.017383 -267.271753)
			(xy 354.965449 -267.271753) (xy 354.914154 -267.263628) (xy 354.864761 -267.24758) (xy 354.818487 -267.224002)
			(xy 354.776471 -267.193476) (xy 354.739748 -267.156753) (xy 354.709222 -267.114737) (xy 354.685644 -267.068463)
			(xy 354.669596 -267.01907) (xy 354.661471 -266.967775) (xy 354.381561 -266.967775) (xy 354.373436 -267.01907)
			(xy 354.357388 -267.068463) (xy 354.33381 -267.114737) (xy 354.303284 -267.156753) (xy 354.266561 -267.193476)
			(xy 354.224545 -267.224002) (xy 354.178271 -267.24758) (xy 354.128878 -267.263628) (xy 354.077583 -267.271753)
			(xy 354.025649 -267.271753) (xy 353.974354 -267.263628) (xy 353.924961 -267.24758) (xy 353.878687 -267.224002)
			(xy 353.836671 -267.193476) (xy 353.799948 -267.156753) (xy 353.769422 -267.114737) (xy 353.745844 -267.068463)
			(xy 353.729796 -267.01907) (xy 353.721671 -266.967775) (xy 353.440678 -266.967775) (xy 353.438238 -266.996888)
			(xy 353.424523 -267.050433) (xy 353.413822 -267.07592) (xy 353.409504 -267.085572) (xy 353.409504 -267.329666)
			(xy 353.409979 -267.344382) (xy 353.418348 -267.372598) (xy 353.434426 -267.397249) (xy 353.456875 -267.416281)
			(xy 353.483824 -267.428108) (xy 353.513029 -267.431746) (xy 353.527614 -267.429742) (xy 353.540981 -267.427691)
			(xy 353.567939 -267.425528) (xy 353.581462 -267.425424) (xy 353.607435 -267.425904) (xy 353.658742 -267.434025)
			(xy 353.708147 -267.450072) (xy 353.754433 -267.473652) (xy 353.79646 -267.504182) (xy 353.833194 -267.540911)
			(xy 353.863728 -267.582935) (xy 353.887313 -267.629218) (xy 353.903366 -267.678621) (xy 353.911493 -267.729927)
			(xy 353.911493 -267.781845) (xy 354.191317 -267.781845) (xy 354.191317 -267.729911) (xy 354.199442 -267.678616)
			(xy 354.21549 -267.629223) (xy 354.239068 -267.582949) (xy 354.269594 -267.540933) (xy 354.306317 -267.50421)
			(xy 354.348333 -267.473684) (xy 354.394607 -267.450106) (xy 354.444 -267.434058) (xy 354.495295 -267.425933)
			(xy 354.547229 -267.425933) (xy 354.598524 -267.434058) (xy 354.647917 -267.450106) (xy 354.694191 -267.473684)
			(xy 354.736207 -267.50421) (xy 354.77293 -267.540933) (xy 354.803456 -267.582949) (xy 354.827034 -267.629223)
			(xy 354.843082 -267.678616) (xy 354.851207 -267.729911) (xy 354.851716 -267.755878) (xy 354.851207 -267.781845)
			(xy 355.131117 -267.781845) (xy 355.131117 -267.729911) (xy 355.139242 -267.678616) (xy 355.15529 -267.629223)
			(xy 355.178868 -267.582949) (xy 355.209394 -267.540933) (xy 355.246117 -267.50421) (xy 355.288133 -267.473684)
			(xy 355.334407 -267.450106) (xy 355.3838 -267.434058) (xy 355.435095 -267.425933) (xy 355.487029 -267.425933)
			(xy 355.538324 -267.434058) (xy 355.587717 -267.450106) (xy 355.633991 -267.473684) (xy 355.676007 -267.50421)
			(xy 355.71273 -267.540933) (xy 355.743256 -267.582949) (xy 355.766834 -267.629223) (xy 355.782882 -267.678616)
			(xy 355.791007 -267.729911) (xy 355.791516 -267.755878) (xy 355.791007 -267.781845) (xy 356.070917 -267.781845)
			(xy 356.070917 -267.729911) (xy 356.079042 -267.678616) (xy 356.09509 -267.629223) (xy 356.118668 -267.582949)
			(xy 356.149194 -267.540933) (xy 356.185917 -267.50421) (xy 356.227933 -267.473684) (xy 356.274207 -267.450106)
			(xy 356.3236 -267.434058) (xy 356.374895 -267.425933) (xy 356.426829 -267.425933) (xy 356.478124 -267.434058)
			(xy 356.527517 -267.450106) (xy 356.573791 -267.473684) (xy 356.615807 -267.50421) (xy 356.65253 -267.540933)
			(xy 356.683056 -267.582949) (xy 356.706634 -267.629223) (xy 356.722682 -267.678616) (xy 356.730807 -267.729911)
			(xy 356.731316 -267.755878) (xy 356.730807 -267.781845) (xy 357.010717 -267.781845) (xy 357.010717 -267.729911)
			(xy 357.018842 -267.678616) (xy 357.03489 -267.629223) (xy 357.058468 -267.582949) (xy 357.088994 -267.540933)
			(xy 357.125717 -267.50421) (xy 357.167733 -267.473684) (xy 357.214007 -267.450106) (xy 357.2634 -267.434058)
			(xy 357.314695 -267.425933) (xy 357.366629 -267.425933) (xy 357.417924 -267.434058) (xy 357.467317 -267.450106)
			(xy 357.513591 -267.473684) (xy 357.555607 -267.50421) (xy 357.59233 -267.540933) (xy 357.622856 -267.582949)
			(xy 357.646434 -267.629223) (xy 357.662482 -267.678616) (xy 357.670607 -267.729911) (xy 357.671116 -267.755878)
			(xy 357.670607 -267.781845) (xy 357.950517 -267.781845) (xy 357.950517 -267.729911) (xy 357.958642 -267.678616)
			(xy 357.97469 -267.629223) (xy 357.998268 -267.582949) (xy 358.028794 -267.540933) (xy 358.065517 -267.50421)
			(xy 358.107533 -267.473684) (xy 358.153807 -267.450106) (xy 358.2032 -267.434058) (xy 358.254495 -267.425933)
			(xy 358.306429 -267.425933) (xy 358.357724 -267.434058) (xy 358.407117 -267.450106) (xy 358.453391 -267.473684)
			(xy 358.495407 -267.50421) (xy 358.53213 -267.540933) (xy 358.562656 -267.582949) (xy 358.586234 -267.629223)
			(xy 358.602282 -267.678616) (xy 358.610407 -267.729911) (xy 358.610916 -267.755878) (xy 358.610407 -267.781845)
			(xy 358.602282 -267.83314) (xy 358.586234 -267.882533) (xy 358.562656 -267.928807) (xy 358.53213 -267.970823)
			(xy 358.495407 -268.007546) (xy 358.453391 -268.038072) (xy 358.407117 -268.06165) (xy 358.357724 -268.077698)
			(xy 358.306429 -268.085823) (xy 358.254495 -268.085823) (xy 358.2032 -268.077698) (xy 358.153807 -268.06165)
			(xy 358.107533 -268.038072) (xy 358.065517 -268.007546) (xy 358.028794 -267.970823) (xy 357.998268 -267.928807)
			(xy 357.97469 -267.882533) (xy 357.958642 -267.83314) (xy 357.950517 -267.781845) (xy 357.670607 -267.781845)
			(xy 357.662482 -267.83314) (xy 357.646434 -267.882533) (xy 357.622856 -267.928807) (xy 357.59233 -267.970823)
			(xy 357.555607 -268.007546) (xy 357.513591 -268.038072) (xy 357.467317 -268.06165) (xy 357.417924 -268.077698)
			(xy 357.366629 -268.085823) (xy 357.314695 -268.085823) (xy 357.2634 -268.077698) (xy 357.214007 -268.06165)
			(xy 357.167733 -268.038072) (xy 357.125717 -268.007546) (xy 357.088994 -267.970823) (xy 357.058468 -267.928807)
			(xy 357.03489 -267.882533) (xy 357.018842 -267.83314) (xy 357.010717 -267.781845) (xy 356.730807 -267.781845)
			(xy 356.722682 -267.83314) (xy 356.706634 -267.882533) (xy 356.683056 -267.928807) (xy 356.65253 -267.970823)
			(xy 356.615807 -268.007546) (xy 356.573791 -268.038072) (xy 356.527517 -268.06165) (xy 356.478124 -268.077698)
			(xy 356.426829 -268.085823) (xy 356.374895 -268.085823) (xy 356.3236 -268.077698) (xy 356.274207 -268.06165)
			(xy 356.227933 -268.038072) (xy 356.185917 -268.007546) (xy 356.149194 -267.970823) (xy 356.118668 -267.928807)
			(xy 356.09509 -267.882533) (xy 356.079042 -267.83314) (xy 356.070917 -267.781845) (xy 355.791007 -267.781845)
			(xy 355.782882 -267.83314) (xy 355.766834 -267.882533) (xy 355.743256 -267.928807) (xy 355.71273 -267.970823)
			(xy 355.676007 -268.007546) (xy 355.633991 -268.038072) (xy 355.587717 -268.06165) (xy 355.538324 -268.077698)
			(xy 355.487029 -268.085823) (xy 355.435095 -268.085823) (xy 355.3838 -268.077698) (xy 355.334407 -268.06165)
			(xy 355.288133 -268.038072) (xy 355.246117 -268.007546) (xy 355.209394 -267.970823) (xy 355.178868 -267.928807)
			(xy 355.15529 -267.882533) (xy 355.139242 -267.83314) (xy 355.131117 -267.781845) (xy 354.851207 -267.781845)
			(xy 354.843082 -267.83314) (xy 354.827034 -267.882533) (xy 354.803456 -267.928807) (xy 354.77293 -267.970823)
			(xy 354.736207 -268.007546) (xy 354.694191 -268.038072) (xy 354.647917 -268.06165) (xy 354.598524 -268.077698)
			(xy 354.547229 -268.085823) (xy 354.495295 -268.085823) (xy 354.444 -268.077698) (xy 354.394607 -268.06165)
			(xy 354.348333 -268.038072) (xy 354.306317 -268.007546) (xy 354.269594 -267.970823) (xy 354.239068 -267.928807)
			(xy 354.21549 -267.882533) (xy 354.199442 -267.83314) (xy 354.191317 -267.781845) (xy 353.911493 -267.781845)
			(xy 353.911493 -267.781873) (xy 353.903366 -267.833179) (xy 353.887313 -267.882582) (xy 353.863728 -267.928865)
			(xy 353.833194 -267.970889) (xy 353.79646 -268.007618) (xy 353.754433 -268.038148) (xy 353.708147 -268.061728)
			(xy 353.658742 -268.077775) (xy 353.607435 -268.085896) (xy 353.581462 -268.086332) (xy 353.56794 -268.086214)
			(xy 353.540982 -268.084056) (xy 353.527614 -268.082014) (xy 353.513038 -268.080122) (xy 353.483892 -268.083822)
			(xy 353.457002 -268.095661) (xy 353.434592 -268.114661) (xy 353.418515 -268.139252) (xy 353.410098 -268.167401)
			(xy 353.409504 -268.18209) (xy 353.409504 -268.42593) (xy 353.413822 -268.435582) (xy 353.424528 -268.461067)
			(xy 353.438244 -268.514613) (xy 353.442859 -268.569695) (xy 353.440684 -268.595661) (xy 353.721671 -268.595661)
			(xy 353.721671 -268.543727) (xy 353.729796 -268.492432) (xy 353.745844 -268.443039) (xy 353.769422 -268.396765)
			(xy 353.799948 -268.354749) (xy 353.836671 -268.318026) (xy 353.878687 -268.2875) (xy 353.924961 -268.263922)
			(xy 353.974354 -268.247874) (xy 354.025649 -268.239749) (xy 354.077583 -268.239749) (xy 354.128878 -268.247874)
			(xy 354.178271 -268.263922) (xy 354.224545 -268.2875) (xy 354.266561 -268.318026) (xy 354.303284 -268.354749)
			(xy 354.33381 -268.396765) (xy 354.357388 -268.443039) (xy 354.373436 -268.492432) (xy 354.381561 -268.543727)
			(xy 354.38207 -268.569694) (xy 354.381561 -268.595661) (xy 354.661471 -268.595661) (xy 354.661471 -268.543727)
			(xy 354.669596 -268.492432) (xy 354.685644 -268.443039) (xy 354.709222 -268.396765) (xy 354.739748 -268.354749)
			(xy 354.776471 -268.318026) (xy 354.818487 -268.2875) (xy 354.864761 -268.263922) (xy 354.914154 -268.247874)
			(xy 354.965449 -268.239749) (xy 355.017383 -268.239749) (xy 355.068678 -268.247874) (xy 355.118071 -268.263922)
			(xy 355.164345 -268.2875) (xy 355.206361 -268.318026) (xy 355.243084 -268.354749) (xy 355.27361 -268.396765)
			(xy 355.297188 -268.443039) (xy 355.313236 -268.492432) (xy 355.321361 -268.543727) (xy 355.32187 -268.569694)
			(xy 355.321361 -268.595661) (xy 355.601271 -268.595661) (xy 355.601271 -268.543727) (xy 355.609396 -268.492432)
			(xy 355.625444 -268.443039) (xy 355.649022 -268.396765) (xy 355.679548 -268.354749) (xy 355.716271 -268.318026)
			(xy 355.758287 -268.2875) (xy 355.804561 -268.263922) (xy 355.853954 -268.247874) (xy 355.905249 -268.239749)
			(xy 355.957183 -268.239749) (xy 356.008478 -268.247874) (xy 356.057871 -268.263922) (xy 356.104145 -268.2875)
			(xy 356.146161 -268.318026) (xy 356.182884 -268.354749) (xy 356.21341 -268.396765) (xy 356.236988 -268.443039)
			(xy 356.253036 -268.492432) (xy 356.261161 -268.543727) (xy 356.26167 -268.569694) (xy 356.261161 -268.595661)
			(xy 356.540817 -268.595661) (xy 356.540817 -268.543727) (xy 356.548942 -268.492432) (xy 356.56499 -268.443039)
			(xy 356.588568 -268.396765) (xy 356.619094 -268.354749) (xy 356.655817 -268.318026) (xy 356.697833 -268.2875)
			(xy 356.744107 -268.263922) (xy 356.7935 -268.247874) (xy 356.844795 -268.239749) (xy 356.896729 -268.239749)
			(xy 356.948024 -268.247874) (xy 356.997417 -268.263922) (xy 357.043691 -268.2875) (xy 357.085707 -268.318026)
			(xy 357.12243 -268.354749) (xy 357.152956 -268.396765) (xy 357.176534 -268.443039) (xy 357.192582 -268.492432)
			(xy 357.200707 -268.543727) (xy 357.201216 -268.569694) (xy 357.200707 -268.595661) (xy 357.480617 -268.595661)
			(xy 357.480617 -268.543727) (xy 357.488742 -268.492432) (xy 357.50479 -268.443039) (xy 357.528368 -268.396765)
			(xy 357.558894 -268.354749) (xy 357.595617 -268.318026) (xy 357.637633 -268.2875) (xy 357.683907 -268.263922)
			(xy 357.7333 -268.247874) (xy 357.784595 -268.239749) (xy 357.836529 -268.239749) (xy 357.887824 -268.247874)
			(xy 357.937217 -268.263922) (xy 357.983491 -268.2875) (xy 358.025507 -268.318026) (xy 358.06223 -268.354749)
			(xy 358.092756 -268.396765) (xy 358.116334 -268.443039) (xy 358.132382 -268.492432) (xy 358.140507 -268.543727)
			(xy 358.141016 -268.569694) (xy 358.140507 -268.595661) (xy 358.132382 -268.646956) (xy 358.116334 -268.696349)
			(xy 358.092756 -268.742623) (xy 358.06223 -268.784639) (xy 358.025507 -268.821362) (xy 357.983491 -268.851888)
			(xy 357.937217 -268.875466) (xy 357.887824 -268.891514) (xy 357.836529 -268.899639) (xy 357.784595 -268.899639)
			(xy 357.7333 -268.891514) (xy 357.683907 -268.875466) (xy 357.637633 -268.851888) (xy 357.595617 -268.821362)
			(xy 357.558894 -268.784639) (xy 357.528368 -268.742623) (xy 357.50479 -268.696349) (xy 357.488742 -268.646956)
			(xy 357.480617 -268.595661) (xy 357.200707 -268.595661) (xy 357.192582 -268.646956) (xy 357.176534 -268.696349)
			(xy 357.152956 -268.742623) (xy 357.12243 -268.784639) (xy 357.085707 -268.821362) (xy 357.043691 -268.851888)
			(xy 356.997417 -268.875466) (xy 356.948024 -268.891514) (xy 356.896729 -268.899639) (xy 356.844795 -268.899639)
			(xy 356.7935 -268.891514) (xy 356.744107 -268.875466) (xy 356.697833 -268.851888) (xy 356.655817 -268.821362)
			(xy 356.619094 -268.784639) (xy 356.588568 -268.742623) (xy 356.56499 -268.696349) (xy 356.548942 -268.646956)
			(xy 356.540817 -268.595661) (xy 356.261161 -268.595661) (xy 356.253036 -268.646956) (xy 356.236988 -268.696349)
			(xy 356.21341 -268.742623) (xy 356.182884 -268.784639) (xy 356.146161 -268.821362) (xy 356.104145 -268.851888)
			(xy 356.057871 -268.875466) (xy 356.008478 -268.891514) (xy 355.957183 -268.899639) (xy 355.905249 -268.899639)
			(xy 355.853954 -268.891514) (xy 355.804561 -268.875466) (xy 355.758287 -268.851888) (xy 355.716271 -268.821362)
			(xy 355.679548 -268.784639) (xy 355.649022 -268.742623) (xy 355.625444 -268.696349) (xy 355.609396 -268.646956)
			(xy 355.601271 -268.595661) (xy 355.321361 -268.595661) (xy 355.313236 -268.646956) (xy 355.297188 -268.696349)
			(xy 355.27361 -268.742623) (xy 355.243084 -268.784639) (xy 355.206361 -268.821362) (xy 355.164345 -268.851888)
			(xy 355.118071 -268.875466) (xy 355.068678 -268.891514) (xy 355.017383 -268.899639) (xy 354.965449 -268.899639)
			(xy 354.914154 -268.891514) (xy 354.864761 -268.875466) (xy 354.818487 -268.851888) (xy 354.776471 -268.821362)
			(xy 354.739748 -268.784639) (xy 354.709222 -268.742623) (xy 354.685644 -268.696349) (xy 354.669596 -268.646956)
			(xy 354.661471 -268.595661) (xy 354.381561 -268.595661) (xy 354.373436 -268.646956) (xy 354.357388 -268.696349)
			(xy 354.33381 -268.742623) (xy 354.303284 -268.784639) (xy 354.266561 -268.821362) (xy 354.224545 -268.851888)
			(xy 354.178271 -268.875466) (xy 354.128878 -268.891514) (xy 354.077583 -268.899639) (xy 354.025649 -268.899639)
			(xy 353.974354 -268.891514) (xy 353.924961 -268.875466) (xy 353.878687 -268.851888) (xy 353.836671 -268.821362)
			(xy 353.799948 -268.784639) (xy 353.769422 -268.742623) (xy 353.745844 -268.696349) (xy 353.729796 -268.646956)
			(xy 353.721671 -268.595661) (xy 353.440684 -268.595661) (xy 353.438246 -268.624776) (xy 353.424532 -268.678322)
			(xy 353.413822 -268.703806) (xy 353.409504 -268.713458) (xy 353.409504 -268.957298) (xy 353.409984 -268.972011)
			(xy 353.418357 -269.000219) (xy 353.434437 -269.024861) (xy 353.456884 -269.043886) (xy 353.483828 -269.055709)
			(xy 353.513027 -269.059346) (xy 353.527614 -269.057374) (xy 353.540981 -269.055323) (xy 353.567939 -269.053159)
			(xy 353.581462 -269.053056) (xy 353.607432 -269.053536) (xy 353.658735 -269.061656) (xy 353.708135 -269.077702)
			(xy 353.754416 -269.101279) (xy 353.796439 -269.131806) (xy 353.833169 -269.168532) (xy 353.863701 -269.210551)
			(xy 353.887283 -269.25683) (xy 353.903335 -269.306228) (xy 353.911461 -269.35753) (xy 353.911461 -269.40947)
			(xy 353.91146 -269.409477) (xy 354.191317 -269.409477) (xy 354.191317 -269.357543) (xy 354.199442 -269.306248)
			(xy 354.21549 -269.256855) (xy 354.239068 -269.210581) (xy 354.269594 -269.168565) (xy 354.306317 -269.131842)
			(xy 354.348333 -269.101316) (xy 354.394607 -269.077738) (xy 354.444 -269.06169) (xy 354.495295 -269.053565)
			(xy 354.547229 -269.053565) (xy 354.598524 -269.06169) (xy 354.647917 -269.077738) (xy 354.694191 -269.101316)
			(xy 354.736207 -269.131842) (xy 354.77293 -269.168565) (xy 354.803456 -269.210581) (xy 354.827034 -269.256855)
			(xy 354.843082 -269.306248) (xy 354.851207 -269.357543) (xy 354.851716 -269.38351) (xy 354.851207 -269.409477)
			(xy 355.131117 -269.409477) (xy 355.131117 -269.357543) (xy 355.139242 -269.306248) (xy 355.15529 -269.256855)
			(xy 355.178868 -269.210581) (xy 355.209394 -269.168565) (xy 355.246117 -269.131842) (xy 355.288133 -269.101316)
			(xy 355.334407 -269.077738) (xy 355.3838 -269.06169) (xy 355.435095 -269.053565) (xy 355.487029 -269.053565)
			(xy 355.538324 -269.06169) (xy 355.587717 -269.077738) (xy 355.633991 -269.101316) (xy 355.676007 -269.131842)
			(xy 355.71273 -269.168565) (xy 355.743256 -269.210581) (xy 355.766834 -269.256855) (xy 355.782882 -269.306248)
			(xy 355.791007 -269.357543) (xy 355.791516 -269.38351) (xy 355.791007 -269.409477) (xy 356.070917 -269.409477)
			(xy 356.070917 -269.357543) (xy 356.079042 -269.306248) (xy 356.09509 -269.256855) (xy 356.118668 -269.210581)
			(xy 356.149194 -269.168565) (xy 356.185917 -269.131842) (xy 356.227933 -269.101316) (xy 356.274207 -269.077738)
			(xy 356.3236 -269.06169) (xy 356.374895 -269.053565) (xy 356.426829 -269.053565) (xy 356.478124 -269.06169)
			(xy 356.527517 -269.077738) (xy 356.573791 -269.101316) (xy 356.615807 -269.131842) (xy 356.65253 -269.168565)
			(xy 356.683056 -269.210581) (xy 356.706634 -269.256855) (xy 356.722682 -269.306248) (xy 356.730807 -269.357543)
			(xy 356.731316 -269.38351) (xy 356.730807 -269.409477) (xy 357.010717 -269.409477) (xy 357.010717 -269.357543)
			(xy 357.018842 -269.306248) (xy 357.03489 -269.256855) (xy 357.058468 -269.210581) (xy 357.088994 -269.168565)
			(xy 357.125717 -269.131842) (xy 357.167733 -269.101316) (xy 357.214007 -269.077738) (xy 357.2634 -269.06169)
			(xy 357.314695 -269.053565) (xy 357.366629 -269.053565) (xy 357.417924 -269.06169) (xy 357.467317 -269.077738)
			(xy 357.513591 -269.101316) (xy 357.555607 -269.131842) (xy 357.59233 -269.168565) (xy 357.622856 -269.210581)
			(xy 357.646434 -269.256855) (xy 357.662482 -269.306248) (xy 357.670607 -269.357543) (xy 357.671116 -269.38351)
			(xy 357.670607 -269.409477) (xy 357.950517 -269.409477) (xy 357.950517 -269.357543) (xy 357.958642 -269.306248)
			(xy 357.97469 -269.256855) (xy 357.998268 -269.210581) (xy 358.028794 -269.168565) (xy 358.065517 -269.131842)
			(xy 358.107533 -269.101316) (xy 358.153807 -269.077738) (xy 358.2032 -269.06169) (xy 358.254495 -269.053565)
			(xy 358.306429 -269.053565) (xy 358.357724 -269.06169) (xy 358.407117 -269.077738) (xy 358.453391 -269.101316)
			(xy 358.495407 -269.131842) (xy 358.53213 -269.168565) (xy 358.562656 -269.210581) (xy 358.586234 -269.256855)
			(xy 358.602282 -269.306248) (xy 358.610407 -269.357543) (xy 358.610916 -269.38351) (xy 358.610407 -269.409477)
			(xy 358.602282 -269.460772) (xy 358.586234 -269.510165) (xy 358.562656 -269.556439) (xy 358.53213 -269.598455)
			(xy 358.495407 -269.635178) (xy 358.453391 -269.665704) (xy 358.407117 -269.689282) (xy 358.357724 -269.70533)
			(xy 358.306429 -269.713455) (xy 358.254495 -269.713455) (xy 358.2032 -269.70533) (xy 358.153807 -269.689282)
			(xy 358.107533 -269.665704) (xy 358.065517 -269.635178) (xy 358.028794 -269.598455) (xy 357.998268 -269.556439)
			(xy 357.97469 -269.510165) (xy 357.958642 -269.460772) (xy 357.950517 -269.409477) (xy 357.670607 -269.409477)
			(xy 357.662482 -269.460772) (xy 357.646434 -269.510165) (xy 357.622856 -269.556439) (xy 357.59233 -269.598455)
			(xy 357.555607 -269.635178) (xy 357.513591 -269.665704) (xy 357.467317 -269.689282) (xy 357.417924 -269.70533)
			(xy 357.366629 -269.713455) (xy 357.314695 -269.713455) (xy 357.2634 -269.70533) (xy 357.214007 -269.689282)
			(xy 357.167733 -269.665704) (xy 357.125717 -269.635178) (xy 357.088994 -269.598455) (xy 357.058468 -269.556439)
			(xy 357.03489 -269.510165) (xy 357.018842 -269.460772) (xy 357.010717 -269.409477) (xy 356.730807 -269.409477)
			(xy 356.722682 -269.460772) (xy 356.706634 -269.510165) (xy 356.683056 -269.556439) (xy 356.65253 -269.598455)
			(xy 356.615807 -269.635178) (xy 356.573791 -269.665704) (xy 356.527517 -269.689282) (xy 356.478124 -269.70533)
			(xy 356.426829 -269.713455) (xy 356.374895 -269.713455) (xy 356.3236 -269.70533) (xy 356.274207 -269.689282)
			(xy 356.227933 -269.665704) (xy 356.185917 -269.635178) (xy 356.149194 -269.598455) (xy 356.118668 -269.556439)
			(xy 356.09509 -269.510165) (xy 356.079042 -269.460772) (xy 356.070917 -269.409477) (xy 355.791007 -269.409477)
			(xy 355.782882 -269.460772) (xy 355.766834 -269.510165) (xy 355.743256 -269.556439) (xy 355.71273 -269.598455)
			(xy 355.676007 -269.635178) (xy 355.633991 -269.665704) (xy 355.587717 -269.689282) (xy 355.538324 -269.70533)
			(xy 355.487029 -269.713455) (xy 355.435095 -269.713455) (xy 355.3838 -269.70533) (xy 355.334407 -269.689282)
			(xy 355.288133 -269.665704) (xy 355.246117 -269.635178) (xy 355.209394 -269.598455) (xy 355.178868 -269.556439)
			(xy 355.15529 -269.510165) (xy 355.139242 -269.460772) (xy 355.131117 -269.409477) (xy 354.851207 -269.409477)
			(xy 354.843082 -269.460772) (xy 354.827034 -269.510165) (xy 354.803456 -269.556439) (xy 354.77293 -269.598455)
			(xy 354.736207 -269.635178) (xy 354.694191 -269.665704) (xy 354.647917 -269.689282) (xy 354.598524 -269.70533)
			(xy 354.547229 -269.713455) (xy 354.495295 -269.713455) (xy 354.444 -269.70533) (xy 354.394607 -269.689282)
			(xy 354.348333 -269.665704) (xy 354.306317 -269.635178) (xy 354.269594 -269.598455) (xy 354.239068 -269.556439)
			(xy 354.21549 -269.510165) (xy 354.199442 -269.460772) (xy 354.191317 -269.409477) (xy 353.91146 -269.409477)
			(xy 353.903335 -269.460772) (xy 353.887283 -269.51017) (xy 353.863701 -269.556449) (xy 353.833169 -269.598468)
			(xy 353.796439 -269.635194) (xy 353.754416 -269.665721) (xy 353.708135 -269.689298) (xy 353.658735 -269.705344)
			(xy 353.607432 -269.713464) (xy 353.581462 -269.713964) (xy 353.56794 -269.713846) (xy 353.540982 -269.711688)
			(xy 353.527614 -269.709646) (xy 353.513035 -269.707754) (xy 353.483882 -269.711454) (xy 353.456985 -269.723292)
			(xy 353.434565 -269.74229) (xy 353.418474 -269.76688) (xy 353.41004 -269.79503) (xy 353.409504 -269.809722)
			(xy 353.409504 -270.053816) (xy 353.413822 -270.063468) (xy 353.42453 -270.088953) (xy 353.438247 -270.142499)
			(xy 353.442865 -270.197582) (xy 353.440691 -270.223547) (xy 353.721671 -270.223547) (xy 353.721671 -270.171613)
			(xy 353.729796 -270.120318) (xy 353.745844 -270.070925) (xy 353.769422 -270.024651) (xy 353.799948 -269.982635)
			(xy 353.836671 -269.945912) (xy 353.878687 -269.915386) (xy 353.924961 -269.891808) (xy 353.974354 -269.87576)
			(xy 354.025649 -269.867635) (xy 354.077583 -269.867635) (xy 354.128878 -269.87576) (xy 354.178271 -269.891808)
			(xy 354.224545 -269.915386) (xy 354.266561 -269.945912) (xy 354.303284 -269.982635) (xy 354.33381 -270.024651)
			(xy 354.357388 -270.070925) (xy 354.373436 -270.120318) (xy 354.381561 -270.171613) (xy 354.38207 -270.19758)
			(xy 354.381561 -270.223547) (xy 354.661471 -270.223547) (xy 354.661471 -270.171613) (xy 354.669596 -270.120318)
			(xy 354.685644 -270.070925) (xy 354.709222 -270.024651) (xy 354.739748 -269.982635) (xy 354.776471 -269.945912)
			(xy 354.818487 -269.915386) (xy 354.864761 -269.891808) (xy 354.914154 -269.87576) (xy 354.965449 -269.867635)
			(xy 355.017383 -269.867635) (xy 355.068678 -269.87576) (xy 355.118071 -269.891808) (xy 355.164345 -269.915386)
			(xy 355.206361 -269.945912) (xy 355.243084 -269.982635) (xy 355.27361 -270.024651) (xy 355.297188 -270.070925)
			(xy 355.313236 -270.120318) (xy 355.321361 -270.171613) (xy 355.32187 -270.19758) (xy 355.321361 -270.223547)
			(xy 355.601271 -270.223547) (xy 355.601271 -270.171613) (xy 355.609396 -270.120318) (xy 355.625444 -270.070925)
			(xy 355.649022 -270.024651) (xy 355.679548 -269.982635) (xy 355.716271 -269.945912) (xy 355.758287 -269.915386)
			(xy 355.804561 -269.891808) (xy 355.853954 -269.87576) (xy 355.905249 -269.867635) (xy 355.957183 -269.867635)
			(xy 356.008478 -269.87576) (xy 356.057871 -269.891808) (xy 356.104145 -269.915386) (xy 356.146161 -269.945912)
			(xy 356.182884 -269.982635) (xy 356.21341 -270.024651) (xy 356.236988 -270.070925) (xy 356.253036 -270.120318)
			(xy 356.261161 -270.171613) (xy 356.26167 -270.19758) (xy 356.261161 -270.223547) (xy 356.540817 -270.223547)
			(xy 356.540817 -270.171613) (xy 356.548942 -270.120318) (xy 356.56499 -270.070925) (xy 356.588568 -270.024651)
			(xy 356.619094 -269.982635) (xy 356.655817 -269.945912) (xy 356.697833 -269.915386) (xy 356.744107 -269.891808)
			(xy 356.7935 -269.87576) (xy 356.844795 -269.867635) (xy 356.896729 -269.867635) (xy 356.948024 -269.87576)
			(xy 356.997417 -269.891808) (xy 357.043691 -269.915386) (xy 357.085707 -269.945912) (xy 357.12243 -269.982635)
			(xy 357.152956 -270.024651) (xy 357.176534 -270.070925) (xy 357.192582 -270.120318) (xy 357.200707 -270.171613)
			(xy 357.201216 -270.19758) (xy 357.200707 -270.223547) (xy 357.480617 -270.223547) (xy 357.480617 -270.171613)
			(xy 357.488742 -270.120318) (xy 357.50479 -270.070925) (xy 357.528368 -270.024651) (xy 357.558894 -269.982635)
			(xy 357.595617 -269.945912) (xy 357.637633 -269.915386) (xy 357.683907 -269.891808) (xy 357.7333 -269.87576)
			(xy 357.784595 -269.867635) (xy 357.836529 -269.867635) (xy 357.887824 -269.87576) (xy 357.937217 -269.891808)
			(xy 357.983491 -269.915386) (xy 358.025507 -269.945912) (xy 358.06223 -269.982635) (xy 358.092756 -270.024651)
			(xy 358.116334 -270.070925) (xy 358.132382 -270.120318) (xy 358.140507 -270.171613) (xy 358.141016 -270.19758)
			(xy 358.140507 -270.223547) (xy 358.132382 -270.274842) (xy 358.116334 -270.324235) (xy 358.092756 -270.370509)
			(xy 358.06223 -270.412525) (xy 358.025507 -270.449248) (xy 357.983491 -270.479774) (xy 357.937217 -270.503352)
			(xy 357.887824 -270.5194) (xy 357.836529 -270.527525) (xy 357.784595 -270.527525) (xy 357.7333 -270.5194)
			(xy 357.683907 -270.503352) (xy 357.637633 -270.479774) (xy 357.595617 -270.449248) (xy 357.558894 -270.412525)
			(xy 357.528368 -270.370509) (xy 357.50479 -270.324235) (xy 357.488742 -270.274842) (xy 357.480617 -270.223547)
			(xy 357.200707 -270.223547) (xy 357.192582 -270.274842) (xy 357.176534 -270.324235) (xy 357.152956 -270.370509)
			(xy 357.12243 -270.412525) (xy 357.085707 -270.449248) (xy 357.043691 -270.479774) (xy 356.997417 -270.503352)
			(xy 356.948024 -270.5194) (xy 356.896729 -270.527525) (xy 356.844795 -270.527525) (xy 356.7935 -270.5194)
			(xy 356.744107 -270.503352) (xy 356.697833 -270.479774) (xy 356.655817 -270.449248) (xy 356.619094 -270.412525)
			(xy 356.588568 -270.370509) (xy 356.56499 -270.324235) (xy 356.548942 -270.274842) (xy 356.540817 -270.223547)
			(xy 356.261161 -270.223547) (xy 356.253036 -270.274842) (xy 356.236988 -270.324235) (xy 356.21341 -270.370509)
			(xy 356.182884 -270.412525) (xy 356.146161 -270.449248) (xy 356.104145 -270.479774) (xy 356.057871 -270.503352)
			(xy 356.008478 -270.5194) (xy 355.957183 -270.527525) (xy 355.905249 -270.527525) (xy 355.853954 -270.5194)
			(xy 355.804561 -270.503352) (xy 355.758287 -270.479774) (xy 355.716271 -270.449248) (xy 355.679548 -270.412525)
			(xy 355.649022 -270.370509) (xy 355.625444 -270.324235) (xy 355.609396 -270.274842) (xy 355.601271 -270.223547)
			(xy 355.321361 -270.223547) (xy 355.313236 -270.274842) (xy 355.297188 -270.324235) (xy 355.27361 -270.370509)
			(xy 355.243084 -270.412525) (xy 355.206361 -270.449248) (xy 355.164345 -270.479774) (xy 355.118071 -270.503352)
			(xy 355.068678 -270.5194) (xy 355.017383 -270.527525) (xy 354.965449 -270.527525) (xy 354.914154 -270.5194)
			(xy 354.864761 -270.503352) (xy 354.818487 -270.479774) (xy 354.776471 -270.449248) (xy 354.739748 -270.412525)
			(xy 354.709222 -270.370509) (xy 354.685644 -270.324235) (xy 354.669596 -270.274842) (xy 354.661471 -270.223547)
			(xy 354.381561 -270.223547) (xy 354.373436 -270.274842) (xy 354.357388 -270.324235) (xy 354.33381 -270.370509)
			(xy 354.303284 -270.412525) (xy 354.266561 -270.449248) (xy 354.224545 -270.479774) (xy 354.178271 -270.503352)
			(xy 354.128878 -270.5194) (xy 354.077583 -270.527525) (xy 354.025649 -270.527525) (xy 353.974354 -270.5194)
			(xy 353.924961 -270.503352) (xy 353.878687 -270.479774) (xy 353.836671 -270.449248) (xy 353.799948 -270.412525)
			(xy 353.769422 -270.370509) (xy 353.745844 -270.324235) (xy 353.729796 -270.274842) (xy 353.721671 -270.223547)
			(xy 353.440691 -270.223547) (xy 353.438253 -270.252664) (xy 353.424542 -270.306212) (xy 353.413822 -270.331692)
			(xy 353.409504 -270.341344) (xy 353.409504 -270.585184) (xy 353.409982 -270.599898) (xy 353.418353 -270.62811)
			(xy 353.434432 -270.652756) (xy 353.45688 -270.671784) (xy 353.483827 -270.683609) (xy 353.513028 -270.687246)
			(xy 353.527614 -270.68526) (xy 353.540981 -270.683209) (xy 353.567939 -270.681045) (xy 353.581462 -270.680942)
			(xy 353.607434 -270.681422) (xy 353.658738 -270.689542) (xy 353.70814 -270.705589) (xy 353.754424 -270.729167)
			(xy 353.796448 -270.759695) (xy 353.83318 -270.796423) (xy 353.863713 -270.838444) (xy 353.887296 -270.884725)
			(xy 353.903349 -270.934125) (xy 353.911475 -270.985428) (xy 353.911475 -271.037363) (xy 354.191317 -271.037363)
			(xy 354.191317 -270.985429) (xy 354.199442 -270.934134) (xy 354.21549 -270.884741) (xy 354.239068 -270.838467)
			(xy 354.269594 -270.796451) (xy 354.306317 -270.759728) (xy 354.348333 -270.729202) (xy 354.394607 -270.705624)
			(xy 354.444 -270.689576) (xy 354.495295 -270.681451) (xy 354.547229 -270.681451) (xy 354.598524 -270.689576)
			(xy 354.647917 -270.705624) (xy 354.694191 -270.729202) (xy 354.736207 -270.759728) (xy 354.77293 -270.796451)
			(xy 354.803456 -270.838467) (xy 354.827034 -270.884741) (xy 354.843082 -270.934134) (xy 354.851207 -270.985429)
			(xy 354.851716 -271.011396) (xy 354.851207 -271.037363) (xy 355.131117 -271.037363) (xy 355.131117 -270.985429)
			(xy 355.139242 -270.934134) (xy 355.15529 -270.884741) (xy 355.178868 -270.838467) (xy 355.209394 -270.796451)
			(xy 355.246117 -270.759728) (xy 355.288133 -270.729202) (xy 355.334407 -270.705624) (xy 355.3838 -270.689576)
			(xy 355.435095 -270.681451) (xy 355.487029 -270.681451) (xy 355.538324 -270.689576) (xy 355.587717 -270.705624)
			(xy 355.633991 -270.729202) (xy 355.676007 -270.759728) (xy 355.71273 -270.796451) (xy 355.743256 -270.838467)
			(xy 355.766834 -270.884741) (xy 355.782882 -270.934134) (xy 355.791007 -270.985429) (xy 355.791516 -271.011396)
			(xy 355.791007 -271.037363) (xy 356.070917 -271.037363) (xy 356.070917 -270.985429) (xy 356.079042 -270.934134)
			(xy 356.09509 -270.884741) (xy 356.118668 -270.838467) (xy 356.149194 -270.796451) (xy 356.185917 -270.759728)
			(xy 356.227933 -270.729202) (xy 356.274207 -270.705624) (xy 356.3236 -270.689576) (xy 356.374895 -270.681451)
			(xy 356.426829 -270.681451) (xy 356.478124 -270.689576) (xy 356.527517 -270.705624) (xy 356.573791 -270.729202)
			(xy 356.615807 -270.759728) (xy 356.65253 -270.796451) (xy 356.683056 -270.838467) (xy 356.706634 -270.884741)
			(xy 356.722682 -270.934134) (xy 356.730807 -270.985429) (xy 356.731316 -271.011396) (xy 356.730807 -271.037363)
			(xy 357.010717 -271.037363) (xy 357.010717 -270.985429) (xy 357.018842 -270.934134) (xy 357.03489 -270.884741)
			(xy 357.058468 -270.838467) (xy 357.088994 -270.796451) (xy 357.125717 -270.759728) (xy 357.167733 -270.729202)
			(xy 357.214007 -270.705624) (xy 357.2634 -270.689576) (xy 357.314695 -270.681451) (xy 357.366629 -270.681451)
			(xy 357.417924 -270.689576) (xy 357.467317 -270.705624) (xy 357.513591 -270.729202) (xy 357.555607 -270.759728)
			(xy 357.59233 -270.796451) (xy 357.622856 -270.838467) (xy 357.646434 -270.884741) (xy 357.662482 -270.934134)
			(xy 357.670607 -270.985429) (xy 357.671116 -271.011396) (xy 357.670607 -271.037363) (xy 357.950517 -271.037363)
			(xy 357.950517 -270.985429) (xy 357.958642 -270.934134) (xy 357.97469 -270.884741) (xy 357.998268 -270.838467)
			(xy 358.028794 -270.796451) (xy 358.065517 -270.759728) (xy 358.107533 -270.729202) (xy 358.153807 -270.705624)
			(xy 358.2032 -270.689576) (xy 358.254495 -270.681451) (xy 358.306429 -270.681451) (xy 358.357724 -270.689576)
			(xy 358.407117 -270.705624) (xy 358.453391 -270.729202) (xy 358.495407 -270.759728) (xy 358.53213 -270.796451)
			(xy 358.562656 -270.838467) (xy 358.586234 -270.884741) (xy 358.602282 -270.934134) (xy 358.610407 -270.985429)
			(xy 358.610916 -271.011396) (xy 358.610407 -271.037363) (xy 358.602282 -271.088658) (xy 358.586234 -271.138051)
			(xy 358.562656 -271.184325) (xy 358.53213 -271.226341) (xy 358.495407 -271.263064) (xy 358.453391 -271.29359)
			(xy 358.407117 -271.317168) (xy 358.357724 -271.333216) (xy 358.306429 -271.341341) (xy 358.254495 -271.341341)
			(xy 358.2032 -271.333216) (xy 358.153807 -271.317168) (xy 358.107533 -271.29359) (xy 358.065517 -271.263064)
			(xy 358.028794 -271.226341) (xy 357.998268 -271.184325) (xy 357.97469 -271.138051) (xy 357.958642 -271.088658)
			(xy 357.950517 -271.037363) (xy 357.670607 -271.037363) (xy 357.662482 -271.088658) (xy 357.646434 -271.138051)
			(xy 357.622856 -271.184325) (xy 357.59233 -271.226341) (xy 357.555607 -271.263064) (xy 357.513591 -271.29359)
			(xy 357.467317 -271.317168) (xy 357.417924 -271.333216) (xy 357.366629 -271.341341) (xy 357.314695 -271.341341)
			(xy 357.2634 -271.333216) (xy 357.214007 -271.317168) (xy 357.167733 -271.29359) (xy 357.125717 -271.263064)
			(xy 357.088994 -271.226341) (xy 357.058468 -271.184325) (xy 357.03489 -271.138051) (xy 357.018842 -271.088658)
			(xy 357.010717 -271.037363) (xy 356.730807 -271.037363) (xy 356.722682 -271.088658) (xy 356.706634 -271.138051)
			(xy 356.683056 -271.184325) (xy 356.65253 -271.226341) (xy 356.615807 -271.263064) (xy 356.573791 -271.29359)
			(xy 356.527517 -271.317168) (xy 356.478124 -271.333216) (xy 356.426829 -271.341341) (xy 356.374895 -271.341341)
			(xy 356.3236 -271.333216) (xy 356.274207 -271.317168) (xy 356.227933 -271.29359) (xy 356.185917 -271.263064)
			(xy 356.149194 -271.226341) (xy 356.118668 -271.184325) (xy 356.09509 -271.138051) (xy 356.079042 -271.088658)
			(xy 356.070917 -271.037363) (xy 355.791007 -271.037363) (xy 355.782882 -271.088658) (xy 355.766834 -271.138051)
			(xy 355.743256 -271.184325) (xy 355.71273 -271.226341) (xy 355.676007 -271.263064) (xy 355.633991 -271.29359)
			(xy 355.587717 -271.317168) (xy 355.538324 -271.333216) (xy 355.487029 -271.341341) (xy 355.435095 -271.341341)
			(xy 355.3838 -271.333216) (xy 355.334407 -271.317168) (xy 355.288133 -271.29359) (xy 355.246117 -271.263064)
			(xy 355.209394 -271.226341) (xy 355.178868 -271.184325) (xy 355.15529 -271.138051) (xy 355.139242 -271.088658)
			(xy 355.131117 -271.037363) (xy 354.851207 -271.037363) (xy 354.843082 -271.088658) (xy 354.827034 -271.138051)
			(xy 354.803456 -271.184325) (xy 354.77293 -271.226341) (xy 354.736207 -271.263064) (xy 354.694191 -271.29359)
			(xy 354.647917 -271.317168) (xy 354.598524 -271.333216) (xy 354.547229 -271.341341) (xy 354.495295 -271.341341)
			(xy 354.444 -271.333216) (xy 354.394607 -271.317168) (xy 354.348333 -271.29359) (xy 354.306317 -271.263064)
			(xy 354.269594 -271.226341) (xy 354.239068 -271.184325) (xy 354.21549 -271.138051) (xy 354.199442 -271.088658)
			(xy 354.191317 -271.037363) (xy 353.911475 -271.037363) (xy 353.911475 -271.037372) (xy 353.903349 -271.088675)
			(xy 353.887296 -271.138075) (xy 353.863713 -271.184356) (xy 353.83318 -271.226377) (xy 353.796448 -271.263105)
			(xy 353.754424 -271.293633) (xy 353.70814 -271.317211) (xy 353.658738 -271.333258) (xy 353.607434 -271.341378)
			(xy 353.581462 -271.34185) (xy 353.56794 -271.341732) (xy 353.540982 -271.339574) (xy 353.527614 -271.337532)
			(xy 353.513034 -271.335641) (xy 353.48388 -271.339341) (xy 353.456982 -271.351178) (xy 353.43456 -271.370176)
			(xy 353.418465 -271.394765) (xy 353.410028 -271.422915) (xy 353.409504 -271.437608) (xy 353.409504 -271.681448)
			(xy 353.413822 -271.6911) (xy 353.424527 -271.716585) (xy 353.438239 -271.770131) (xy 353.442852 -271.825211)
			(xy 353.440676 -271.851179) (xy 353.721671 -271.851179) (xy 353.721671 -271.799245) (xy 353.729796 -271.74795)
			(xy 353.745844 -271.698557) (xy 353.769422 -271.652283) (xy 353.799948 -271.610267) (xy 353.836671 -271.573544)
			(xy 353.878687 -271.543018) (xy 353.924961 -271.51944) (xy 353.974354 -271.503392) (xy 354.025649 -271.495267)
			(xy 354.077583 -271.495267) (xy 354.128878 -271.503392) (xy 354.178271 -271.51944) (xy 354.224545 -271.543018)
			(xy 354.266561 -271.573544) (xy 354.303284 -271.610267) (xy 354.33381 -271.652283) (xy 354.357388 -271.698557)
			(xy 354.373436 -271.74795) (xy 354.381561 -271.799245) (xy 354.38207 -271.825212) (xy 354.381561 -271.851179)
			(xy 354.661471 -271.851179) (xy 354.661471 -271.799245) (xy 354.669596 -271.74795) (xy 354.685644 -271.698557)
			(xy 354.709222 -271.652283) (xy 354.739748 -271.610267) (xy 354.776471 -271.573544) (xy 354.818487 -271.543018)
			(xy 354.864761 -271.51944) (xy 354.914154 -271.503392) (xy 354.965449 -271.495267) (xy 355.017383 -271.495267)
			(xy 355.068678 -271.503392) (xy 355.118071 -271.51944) (xy 355.164345 -271.543018) (xy 355.206361 -271.573544)
			(xy 355.243084 -271.610267) (xy 355.27361 -271.652283) (xy 355.297188 -271.698557) (xy 355.313236 -271.74795)
			(xy 355.321361 -271.799245) (xy 355.32187 -271.825212) (xy 355.321361 -271.851179) (xy 355.601271 -271.851179)
			(xy 355.601271 -271.799245) (xy 355.609396 -271.74795) (xy 355.625444 -271.698557) (xy 355.649022 -271.652283)
			(xy 355.679548 -271.610267) (xy 355.716271 -271.573544) (xy 355.758287 -271.543018) (xy 355.804561 -271.51944)
			(xy 355.853954 -271.503392) (xy 355.905249 -271.495267) (xy 355.957183 -271.495267) (xy 356.008478 -271.503392)
			(xy 356.057871 -271.51944) (xy 356.104145 -271.543018) (xy 356.146161 -271.573544) (xy 356.182884 -271.610267)
			(xy 356.21341 -271.652283) (xy 356.236988 -271.698557) (xy 356.253036 -271.74795) (xy 356.261161 -271.799245)
			(xy 356.26167 -271.825212) (xy 356.261161 -271.851179) (xy 356.541071 -271.851179) (xy 356.541071 -271.799245)
			(xy 356.549196 -271.74795) (xy 356.565244 -271.698557) (xy 356.588822 -271.652283) (xy 356.619348 -271.610267)
			(xy 356.656071 -271.573544) (xy 356.698087 -271.543018) (xy 356.744361 -271.51944) (xy 356.793754 -271.503392)
			(xy 356.845049 -271.495267) (xy 356.896983 -271.495267) (xy 356.948278 -271.503392) (xy 356.997671 -271.51944)
			(xy 357.043945 -271.543018) (xy 357.085961 -271.573544) (xy 357.122684 -271.610267) (xy 357.15321 -271.652283)
			(xy 357.176788 -271.698557) (xy 357.192836 -271.74795) (xy 357.200961 -271.799245) (xy 357.20147 -271.825212)
			(xy 357.200961 -271.851179) (xy 357.480363 -271.851179) (xy 357.480363 -271.799245) (xy 357.488488 -271.74795)
			(xy 357.504536 -271.698557) (xy 357.528114 -271.652283) (xy 357.55864 -271.610267) (xy 357.595363 -271.573544)
			(xy 357.637379 -271.543018) (xy 357.683653 -271.51944) (xy 357.733046 -271.503392) (xy 357.784341 -271.495267)
			(xy 357.836275 -271.495267) (xy 357.88757 -271.503392) (xy 357.936963 -271.51944) (xy 357.983237 -271.543018)
			(xy 358.025253 -271.573544) (xy 358.061976 -271.610267) (xy 358.092502 -271.652283) (xy 358.11608 -271.698557)
			(xy 358.132128 -271.74795) (xy 358.140253 -271.799245) (xy 358.140762 -271.825212) (xy 358.140253 -271.851179)
			(xy 358.132128 -271.902474) (xy 358.11608 -271.951867) (xy 358.092502 -271.998141) (xy 358.061976 -272.040157)
			(xy 358.025253 -272.07688) (xy 357.983237 -272.107406) (xy 357.936963 -272.130984) (xy 357.88757 -272.147032)
			(xy 357.836275 -272.155157) (xy 357.784341 -272.155157) (xy 357.733046 -272.147032) (xy 357.683653 -272.130984)
			(xy 357.637379 -272.107406) (xy 357.595363 -272.07688) (xy 357.55864 -272.040157) (xy 357.528114 -271.998141)
			(xy 357.504536 -271.951867) (xy 357.488488 -271.902474) (xy 357.480363 -271.851179) (xy 357.200961 -271.851179)
			(xy 357.192836 -271.902474) (xy 357.176788 -271.951867) (xy 357.15321 -271.998141) (xy 357.122684 -272.040157)
			(xy 357.085961 -272.07688) (xy 357.043945 -272.107406) (xy 356.997671 -272.130984) (xy 356.948278 -272.147032)
			(xy 356.896983 -272.155157) (xy 356.845049 -272.155157) (xy 356.793754 -272.147032) (xy 356.744361 -272.130984)
			(xy 356.698087 -272.107406) (xy 356.656071 -272.07688) (xy 356.619348 -272.040157) (xy 356.588822 -271.998141)
			(xy 356.565244 -271.951867) (xy 356.549196 -271.902474) (xy 356.541071 -271.851179) (xy 356.261161 -271.851179)
			(xy 356.253036 -271.902474) (xy 356.236988 -271.951867) (xy 356.21341 -271.998141) (xy 356.182884 -272.040157)
			(xy 356.146161 -272.07688) (xy 356.104145 -272.107406) (xy 356.057871 -272.130984) (xy 356.008478 -272.147032)
			(xy 355.957183 -272.155157) (xy 355.905249 -272.155157) (xy 355.853954 -272.147032) (xy 355.804561 -272.130984)
			(xy 355.758287 -272.107406) (xy 355.716271 -272.07688) (xy 355.679548 -272.040157) (xy 355.649022 -271.998141)
			(xy 355.625444 -271.951867) (xy 355.609396 -271.902474) (xy 355.601271 -271.851179) (xy 355.321361 -271.851179)
			(xy 355.313236 -271.902474) (xy 355.297188 -271.951867) (xy 355.27361 -271.998141) (xy 355.243084 -272.040157)
			(xy 355.206361 -272.07688) (xy 355.164345 -272.107406) (xy 355.118071 -272.130984) (xy 355.068678 -272.147032)
			(xy 355.017383 -272.155157) (xy 354.965449 -272.155157) (xy 354.914154 -272.147032) (xy 354.864761 -272.130984)
			(xy 354.818487 -272.107406) (xy 354.776471 -272.07688) (xy 354.739748 -272.040157) (xy 354.709222 -271.998141)
			(xy 354.685644 -271.951867) (xy 354.669596 -271.902474) (xy 354.661471 -271.851179) (xy 354.381561 -271.851179)
			(xy 354.373436 -271.902474) (xy 354.357388 -271.951867) (xy 354.33381 -271.998141) (xy 354.303284 -272.040157)
			(xy 354.266561 -272.07688) (xy 354.224545 -272.107406) (xy 354.178271 -272.130984) (xy 354.128878 -272.147032)
			(xy 354.077583 -272.155157) (xy 354.025649 -272.155157) (xy 353.974354 -272.147032) (xy 353.924961 -272.130984)
			(xy 353.878687 -272.107406) (xy 353.836671 -272.07688) (xy 353.799948 -272.040157) (xy 353.769422 -271.998141)
			(xy 353.745844 -271.951867) (xy 353.729796 -271.902474) (xy 353.721671 -271.851179) (xy 353.440676 -271.851179)
			(xy 353.438236 -271.880291) (xy 353.42452 -271.933836) (xy 353.413822 -271.959324) (xy 353.409504 -271.968976)
			(xy 353.409504 -272.21307) (xy 353.40998 -272.227786) (xy 353.418349 -272.256001) (xy 353.434427 -272.28065)
			(xy 353.456876 -272.299681) (xy 353.483825 -272.311508) (xy 353.513029 -272.315146) (xy 353.527614 -272.313146)
			(xy 353.540981 -272.311095) (xy 353.567939 -272.308932) (xy 353.581462 -272.308828) (xy 353.607435 -272.309308)
			(xy 353.658741 -272.317429) (xy 353.708145 -272.333476) (xy 353.754431 -272.357055) (xy 353.796458 -272.387585)
			(xy 353.83319 -272.424314) (xy 353.863725 -272.466337) (xy 353.887309 -272.512619) (xy 353.903362 -272.562022)
			(xy 353.911489 -272.613327) (xy 353.911489 -272.665249) (xy 354.191317 -272.665249) (xy 354.191317 -272.613315)
			(xy 354.199442 -272.56202) (xy 354.21549 -272.512627) (xy 354.239068 -272.466353) (xy 354.269594 -272.424337)
			(xy 354.306317 -272.387614) (xy 354.348333 -272.357088) (xy 354.394607 -272.33351) (xy 354.444 -272.317462)
			(xy 354.495295 -272.309337) (xy 354.547229 -272.309337) (xy 354.598524 -272.317462) (xy 354.647917 -272.33351)
			(xy 354.694191 -272.357088) (xy 354.736207 -272.387614) (xy 354.77293 -272.424337) (xy 354.803456 -272.466353)
			(xy 354.827034 -272.512627) (xy 354.843082 -272.56202) (xy 354.851207 -272.613315) (xy 354.851716 -272.639282)
			(xy 354.851207 -272.665249) (xy 355.131117 -272.665249) (xy 355.131117 -272.613315) (xy 355.139242 -272.56202)
			(xy 355.15529 -272.512627) (xy 355.178868 -272.466353) (xy 355.209394 -272.424337) (xy 355.246117 -272.387614)
			(xy 355.288133 -272.357088) (xy 355.334407 -272.33351) (xy 355.3838 -272.317462) (xy 355.435095 -272.309337)
			(xy 355.487029 -272.309337) (xy 355.538324 -272.317462) (xy 355.587717 -272.33351) (xy 355.633991 -272.357088)
			(xy 355.676007 -272.387614) (xy 355.71273 -272.424337) (xy 355.743256 -272.466353) (xy 355.766834 -272.512627)
			(xy 355.782882 -272.56202) (xy 355.791007 -272.613315) (xy 355.791516 -272.639282) (xy 355.791007 -272.665249)
			(xy 356.070917 -272.665249) (xy 356.070917 -272.613315) (xy 356.079042 -272.56202) (xy 356.09509 -272.512627)
			(xy 356.118668 -272.466353) (xy 356.149194 -272.424337) (xy 356.185917 -272.387614) (xy 356.227933 -272.357088)
			(xy 356.274207 -272.33351) (xy 356.3236 -272.317462) (xy 356.374895 -272.309337) (xy 356.426829 -272.309337)
			(xy 356.478124 -272.317462) (xy 356.527517 -272.33351) (xy 356.573791 -272.357088) (xy 356.615807 -272.387614)
			(xy 356.65253 -272.424337) (xy 356.683056 -272.466353) (xy 356.706634 -272.512627) (xy 356.722682 -272.56202)
			(xy 356.730807 -272.613315) (xy 356.731316 -272.639282) (xy 356.730807 -272.665249) (xy 357.010717 -272.665249)
			(xy 357.010717 -272.613315) (xy 357.018842 -272.56202) (xy 357.03489 -272.512627) (xy 357.058468 -272.466353)
			(xy 357.088994 -272.424337) (xy 357.125717 -272.387614) (xy 357.167733 -272.357088) (xy 357.214007 -272.33351)
			(xy 357.2634 -272.317462) (xy 357.314695 -272.309337) (xy 357.366629 -272.309337) (xy 357.417924 -272.317462)
			(xy 357.467317 -272.33351) (xy 357.513591 -272.357088) (xy 357.555607 -272.387614) (xy 357.59233 -272.424337)
			(xy 357.622856 -272.466353) (xy 357.646434 -272.512627) (xy 357.662482 -272.56202) (xy 357.670607 -272.613315)
			(xy 357.671116 -272.639282) (xy 357.670607 -272.665249) (xy 357.950517 -272.665249) (xy 357.950517 -272.613315)
			(xy 357.958642 -272.56202) (xy 357.97469 -272.512627) (xy 357.998268 -272.466353) (xy 358.028794 -272.424337)
			(xy 358.065517 -272.387614) (xy 358.107533 -272.357088) (xy 358.153807 -272.33351) (xy 358.2032 -272.317462)
			(xy 358.254495 -272.309337) (xy 358.306429 -272.309337) (xy 358.357724 -272.317462) (xy 358.407117 -272.33351)
			(xy 358.453391 -272.357088) (xy 358.495407 -272.387614) (xy 358.53213 -272.424337) (xy 358.562656 -272.466353)
			(xy 358.586234 -272.512627) (xy 358.602282 -272.56202) (xy 358.610407 -272.613315) (xy 358.610916 -272.639282)
			(xy 358.610407 -272.665249) (xy 361.709717 -272.665249) (xy 361.709717 -272.613315) (xy 361.717842 -272.56202)
			(xy 361.73389 -272.512627) (xy 361.757468 -272.466353) (xy 361.787994 -272.424337) (xy 361.824717 -272.387614)
			(xy 361.866733 -272.357088) (xy 361.913007 -272.33351) (xy 361.9624 -272.317462) (xy 362.013695 -272.309337)
			(xy 362.065629 -272.309337) (xy 362.116924 -272.317462) (xy 362.166317 -272.33351) (xy 362.212591 -272.357088)
			(xy 362.254607 -272.387614) (xy 362.29133 -272.424337) (xy 362.321856 -272.466353) (xy 362.345434 -272.512627)
			(xy 362.361482 -272.56202) (xy 362.369607 -272.613315) (xy 362.370116 -272.639282) (xy 362.369607 -272.665249)
			(xy 362.361482 -272.716544) (xy 362.345434 -272.765937) (xy 362.321856 -272.812211) (xy 362.29133 -272.854227)
			(xy 362.254607 -272.89095) (xy 362.212591 -272.921476) (xy 362.166317 -272.945054) (xy 362.116924 -272.961102)
			(xy 362.065629 -272.969227) (xy 362.013695 -272.969227) (xy 361.9624 -272.961102) (xy 361.913007 -272.945054)
			(xy 361.866733 -272.921476) (xy 361.824717 -272.89095) (xy 361.787994 -272.854227) (xy 361.757468 -272.812211)
			(xy 361.73389 -272.765937) (xy 361.717842 -272.716544) (xy 361.709717 -272.665249) (xy 358.610407 -272.665249)
			(xy 358.602282 -272.716544) (xy 358.586234 -272.765937) (xy 358.562656 -272.812211) (xy 358.53213 -272.854227)
			(xy 358.495407 -272.89095) (xy 358.453391 -272.921476) (xy 358.407117 -272.945054) (xy 358.357724 -272.961102)
			(xy 358.306429 -272.969227) (xy 358.254495 -272.969227) (xy 358.2032 -272.961102) (xy 358.153807 -272.945054)
			(xy 358.107533 -272.921476) (xy 358.065517 -272.89095) (xy 358.028794 -272.854227) (xy 357.998268 -272.812211)
			(xy 357.97469 -272.765937) (xy 357.958642 -272.716544) (xy 357.950517 -272.665249) (xy 357.670607 -272.665249)
			(xy 357.662482 -272.716544) (xy 357.646434 -272.765937) (xy 357.622856 -272.812211) (xy 357.59233 -272.854227)
			(xy 357.555607 -272.89095) (xy 357.513591 -272.921476) (xy 357.467317 -272.945054) (xy 357.417924 -272.961102)
			(xy 357.366629 -272.969227) (xy 357.314695 -272.969227) (xy 357.2634 -272.961102) (xy 357.214007 -272.945054)
			(xy 357.167733 -272.921476) (xy 357.125717 -272.89095) (xy 357.088994 -272.854227) (xy 357.058468 -272.812211)
			(xy 357.03489 -272.765937) (xy 357.018842 -272.716544) (xy 357.010717 -272.665249) (xy 356.730807 -272.665249)
			(xy 356.722682 -272.716544) (xy 356.706634 -272.765937) (xy 356.683056 -272.812211) (xy 356.65253 -272.854227)
			(xy 356.615807 -272.89095) (xy 356.573791 -272.921476) (xy 356.527517 -272.945054) (xy 356.478124 -272.961102)
			(xy 356.426829 -272.969227) (xy 356.374895 -272.969227) (xy 356.3236 -272.961102) (xy 356.274207 -272.945054)
			(xy 356.227933 -272.921476) (xy 356.185917 -272.89095) (xy 356.149194 -272.854227) (xy 356.118668 -272.812211)
			(xy 356.09509 -272.765937) (xy 356.079042 -272.716544) (xy 356.070917 -272.665249) (xy 355.791007 -272.665249)
			(xy 355.782882 -272.716544) (xy 355.766834 -272.765937) (xy 355.743256 -272.812211) (xy 355.71273 -272.854227)
			(xy 355.676007 -272.89095) (xy 355.633991 -272.921476) (xy 355.587717 -272.945054) (xy 355.538324 -272.961102)
			(xy 355.487029 -272.969227) (xy 355.435095 -272.969227) (xy 355.3838 -272.961102) (xy 355.334407 -272.945054)
			(xy 355.288133 -272.921476) (xy 355.246117 -272.89095) (xy 355.209394 -272.854227) (xy 355.178868 -272.812211)
			(xy 355.15529 -272.765937) (xy 355.139242 -272.716544) (xy 355.131117 -272.665249) (xy 354.851207 -272.665249)
			(xy 354.843082 -272.716544) (xy 354.827034 -272.765937) (xy 354.803456 -272.812211) (xy 354.77293 -272.854227)
			(xy 354.736207 -272.89095) (xy 354.694191 -272.921476) (xy 354.647917 -272.945054) (xy 354.598524 -272.961102)
			(xy 354.547229 -272.969227) (xy 354.495295 -272.969227) (xy 354.444 -272.961102) (xy 354.394607 -272.945054)
			(xy 354.348333 -272.921476) (xy 354.306317 -272.89095) (xy 354.269594 -272.854227) (xy 354.239068 -272.812211)
			(xy 354.21549 -272.765937) (xy 354.199442 -272.716544) (xy 354.191317 -272.665249) (xy 353.911489 -272.665249)
			(xy 353.911489 -272.665273) (xy 353.903362 -272.716578) (xy 353.887309 -272.765981) (xy 353.863725 -272.812263)
			(xy 353.83319 -272.854287) (xy 353.796458 -272.891015) (xy 353.754431 -272.921545) (xy 353.708145 -272.945124)
			(xy 353.658741 -272.961171) (xy 353.607435 -272.969292) (xy 353.581462 -272.969736) (xy 353.56794 -272.969618)
			(xy 353.540982 -272.96746) (xy 353.527614 -272.965418) (xy 353.513033 -272.963527) (xy 353.483878 -272.967227)
			(xy 353.456978 -272.979064) (xy 353.434554 -272.998061) (xy 353.418457 -273.02265) (xy 353.410016 -273.050801)
			(xy 353.409504 -273.065494) (xy 353.409504 -273.435826) (xy 353.727004 -273.753326) (xy 353.813618 -273.753326)
			(xy 353.813618 -273.68373) (xy 353.801426 -273.669252) (xy 353.786323 -273.651148) (xy 353.760864 -273.611468)
			(xy 353.7413 -273.568574) (xy 353.728028 -273.523336) (xy 353.721316 -273.47667) (xy 353.720908 -273.453098)
			(xy 353.721418 -273.427111) (xy 353.729548 -273.375776) (xy 353.745609 -273.326346) (xy 353.769205 -273.280036)
			(xy 353.799755 -273.237988) (xy 353.836506 -273.201237) (xy 353.878554 -273.170687) (xy 353.924864 -273.147091)
			(xy 353.974294 -273.13103) (xy 354.025629 -273.1229) (xy 354.077603 -273.1229) (xy 354.128938 -273.13103)
			(xy 354.178368 -273.147091) (xy 354.224678 -273.170687) (xy 354.266726 -273.201237) (xy 354.303477 -273.237988)
			(xy 354.334027 -273.280036) (xy 354.357623 -273.326346) (xy 354.373684 -273.375776) (xy 354.381814 -273.427111)
			(xy 354.382324 -273.453098) (xy 354.381798 -273.479422) (xy 354.373424 -273.531399) (xy 354.356918 -273.581393)
			(xy 354.34524 -273.60499) (xy 354.338848 -273.618472) (xy 354.333371 -273.647789) (xy 354.33659 -273.677439)
			(xy 354.348231 -273.704897) (xy 354.367304 -273.727825) (xy 354.392183 -273.744271) (xy 354.420751 -273.752834)
			(xy 354.435664 -273.753326) (xy 354.607876 -273.753326) (xy 354.622498 -273.752852) (xy 354.650548 -273.744576)
			(xy 354.675105 -273.728696) (xy 354.694159 -273.706511) (xy 354.70615 -273.679838) (xy 354.710097 -273.650861)
			(xy 354.705675 -273.621953) (xy 354.699824 -273.608546) (xy 354.687591 -273.58448) (xy 354.670266 -273.533354)
			(xy 354.661494 -273.480089) (xy 354.660962 -273.453098) (xy 354.661471 -273.427131) (xy 354.669596 -273.375836)
			(xy 354.685644 -273.326443) (xy 354.709222 -273.280169) (xy 354.739748 -273.238153) (xy 354.776471 -273.20143)
			(xy 354.818487 -273.170904) (xy 354.864761 -273.147326) (xy 354.914154 -273.131278) (xy 354.965449 -273.123153)
			(xy 355.017383 -273.123153) (xy 355.068678 -273.131278) (xy 355.118071 -273.147326) (xy 355.164345 -273.170904)
			(xy 355.206361 -273.20143) (xy 355.243084 -273.238153) (xy 355.27361 -273.280169) (xy 355.297188 -273.326443)
			(xy 355.313236 -273.375836) (xy 355.321361 -273.427131) (xy 355.32187 -273.453098) (xy 355.321334 -273.480089)
			(xy 355.312561 -273.533354) (xy 355.295248 -273.584484) (xy 355.283008 -273.608546) (xy 355.277233 -273.621978)
			(xy 355.272818 -273.650869) (xy 355.276763 -273.679828) (xy 355.288743 -273.706486) (xy 355.30778 -273.728663)
			(xy 355.332316 -273.744543) (xy 355.360343 -273.752828) (xy 355.374956 -273.753326) (xy 355.547676 -273.753326)
			(xy 355.562298 -273.752852) (xy 355.590348 -273.744576) (xy 355.614905 -273.728696) (xy 355.633959 -273.706511)
			(xy 355.64595 -273.679838) (xy 355.649897 -273.650861) (xy 355.645475 -273.621953) (xy 355.639624 -273.608546)
			(xy 355.627391 -273.58448) (xy 355.610066 -273.533354) (xy 355.601294 -273.480089) (xy 355.600762 -273.453098)
			(xy 355.601271 -273.427131) (xy 355.609396 -273.375836) (xy 355.625444 -273.326443) (xy 355.649022 -273.280169)
			(xy 355.679548 -273.238153) (xy 355.716271 -273.20143) (xy 355.758287 -273.170904) (xy 355.804561 -273.147326)
			(xy 355.853954 -273.131278) (xy 355.905249 -273.123153) (xy 355.957183 -273.123153) (xy 356.008478 -273.131278)
			(xy 356.057871 -273.147326) (xy 356.104145 -273.170904) (xy 356.146161 -273.20143) (xy 356.182884 -273.238153)
			(xy 356.21341 -273.280169) (xy 356.236988 -273.326443) (xy 356.253036 -273.375836) (xy 356.261161 -273.427131)
			(xy 356.26167 -273.453098) (xy 356.261134 -273.480089) (xy 356.252361 -273.533354) (xy 356.235048 -273.584484)
			(xy 356.222808 -273.608546) (xy 356.217033 -273.621978) (xy 356.212618 -273.650869) (xy 356.216563 -273.679828)
			(xy 356.228543 -273.706486) (xy 356.24758 -273.728663) (xy 356.272116 -273.744543) (xy 356.300143 -273.752828)
			(xy 356.314756 -273.753326) (xy 356.487222 -273.753326) (xy 356.501839 -273.752846) (xy 356.529877 -273.744563)
			(xy 356.554422 -273.728681) (xy 356.573466 -273.7065) (xy 356.585451 -273.679834) (xy 356.589397 -273.650866)
			(xy 356.584979 -273.621967) (xy 356.57917 -273.608546) (xy 356.566939 -273.58448) (xy 356.549616 -273.533353)
			(xy 356.540847 -273.480089) (xy 356.540308 -273.453098) (xy 356.540817 -273.427131) (xy 356.548942 -273.375836)
			(xy 356.56499 -273.326443) (xy 356.588568 -273.280169) (xy 356.619094 -273.238153) (xy 356.655817 -273.20143)
			(xy 356.697833 -273.170904) (xy 356.744107 -273.147326) (xy 356.7935 -273.131278) (xy 356.844795 -273.123153)
			(xy 356.896729 -273.123153) (xy 356.948024 -273.131278) (xy 356.997417 -273.147326) (xy 357.043691 -273.170904)
			(xy 357.085707 -273.20143) (xy 357.12243 -273.238153) (xy 357.152956 -273.280169) (xy 357.176534 -273.326443)
			(xy 357.192582 -273.375836) (xy 357.200707 -273.427131) (xy 357.201216 -273.453098) (xy 357.200554 -273.482912)
			(xy 357.189816 -273.541566) (xy 357.17988 -273.569684) (xy 357.1748 -273.58467) (xy 357.227378 -273.675856)
			(xy 357.272082 -273.753326) (xy 357.427022 -273.753326) (xy 357.441639 -273.752846) (xy 357.469677 -273.744563)
			(xy 357.494222 -273.728681) (xy 357.513266 -273.7065) (xy 357.525251 -273.679834) (xy 357.529197 -273.650866)
			(xy 357.524779 -273.621967) (xy 357.51897 -273.608546) (xy 357.506739 -273.58448) (xy 357.489416 -273.533353)
			(xy 357.480647 -273.480089) (xy 357.480108 -273.453098) (xy 357.480617 -273.427131) (xy 357.488742 -273.375836)
			(xy 357.50479 -273.326443) (xy 357.528368 -273.280169) (xy 357.558894 -273.238153) (xy 357.595617 -273.20143)
			(xy 357.637633 -273.170904) (xy 357.683907 -273.147326) (xy 357.7333 -273.131278) (xy 357.784595 -273.123153)
			(xy 357.836529 -273.123153) (xy 357.887824 -273.131278) (xy 357.937217 -273.147326) (xy 357.983491 -273.170904)
			(xy 358.025507 -273.20143) (xy 358.06223 -273.238153) (xy 358.092756 -273.280169) (xy 358.116334 -273.326443)
			(xy 358.132382 -273.375836) (xy 358.140507 -273.427131) (xy 358.141016 -273.453098) (xy 358.1405 -273.479065)
			(xy 361.239817 -273.479065) (xy 361.239817 -273.427131) (xy 361.247942 -273.375836) (xy 361.26399 -273.326443)
			(xy 361.287568 -273.280169) (xy 361.318094 -273.238153) (xy 361.354817 -273.20143) (xy 361.396833 -273.170904)
			(xy 361.443107 -273.147326) (xy 361.4925 -273.131278) (xy 361.543795 -273.123153) (xy 361.595729 -273.123153)
			(xy 361.647024 -273.131278) (xy 361.696417 -273.147326) (xy 361.742691 -273.170904) (xy 361.784707 -273.20143)
			(xy 361.82143 -273.238153) (xy 361.851956 -273.280169) (xy 361.875534 -273.326443) (xy 361.891582 -273.375836)
			(xy 361.899707 -273.427131) (xy 361.900216 -273.453098) (xy 361.899707 -273.479065) (xy 362.179617 -273.479065)
			(xy 362.179617 -273.427131) (xy 362.187742 -273.375836) (xy 362.20379 -273.326443) (xy 362.227368 -273.280169)
			(xy 362.257894 -273.238153) (xy 362.294617 -273.20143) (xy 362.336633 -273.170904) (xy 362.382907 -273.147326)
			(xy 362.4323 -273.131278) (xy 362.483595 -273.123153) (xy 362.535529 -273.123153) (xy 362.586824 -273.131278)
			(xy 362.636217 -273.147326) (xy 362.682491 -273.170904) (xy 362.724507 -273.20143) (xy 362.76123 -273.238153)
			(xy 362.791756 -273.280169) (xy 362.815334 -273.326443) (xy 362.831382 -273.375836) (xy 362.839507 -273.427131)
			(xy 362.840016 -273.453098) (xy 362.839507 -273.479065) (xy 362.831382 -273.53036) (xy 362.815334 -273.579753)
			(xy 362.791756 -273.626027) (xy 362.76123 -273.668043) (xy 362.724507 -273.704766) (xy 362.682491 -273.735292)
			(xy 362.636217 -273.75887) (xy 362.586824 -273.774918) (xy 362.535529 -273.783043) (xy 362.483595 -273.783043)
			(xy 362.4323 -273.774918) (xy 362.382907 -273.75887) (xy 362.336633 -273.735292) (xy 362.294617 -273.704766)
			(xy 362.257894 -273.668043) (xy 362.227368 -273.626027) (xy 362.20379 -273.579753) (xy 362.187742 -273.53036)
			(xy 362.179617 -273.479065) (xy 361.899707 -273.479065) (xy 361.891582 -273.53036) (xy 361.875534 -273.579753)
			(xy 361.851956 -273.626027) (xy 361.82143 -273.668043) (xy 361.784707 -273.704766) (xy 361.742691 -273.735292)
			(xy 361.696417 -273.75887) (xy 361.647024 -273.774918) (xy 361.595729 -273.783043) (xy 361.543795 -273.783043)
			(xy 361.4925 -273.774918) (xy 361.443107 -273.75887) (xy 361.396833 -273.735292) (xy 361.354817 -273.704766)
			(xy 361.318094 -273.668043) (xy 361.287568 -273.626027) (xy 361.26399 -273.579753) (xy 361.247942 -273.53036)
			(xy 361.239817 -273.479065) (xy 358.1405 -273.479065) (xy 358.14048 -273.480089) (xy 358.131705 -273.533353)
			(xy 358.114389 -273.584482) (xy 358.102154 -273.608546) (xy 358.096378 -273.621976) (xy 358.091961 -273.650864)
			(xy 358.095904 -273.67982) (xy 358.107886 -273.706475) (xy 358.126925 -273.728646) (xy 358.151462 -273.744518)
			(xy 358.17949 -273.752793) (xy 358.194102 -273.753326) (xy 359.398824 -273.753326) (xy 359.637584 -273.992086)
			(xy 359.637584 -274.101306) (xy 359.653586 -274.116292) (xy 359.690053 -274.151065) (xy 359.758175 -274.225325)
			(xy 359.811261 -274.292881) (xy 361.709717 -274.292881) (xy 361.709717 -274.240947) (xy 361.717842 -274.189652)
			(xy 361.73389 -274.140259) (xy 361.757468 -274.093985) (xy 361.787994 -274.051969) (xy 361.824717 -274.015246)
			(xy 361.866733 -273.98472) (xy 361.913007 -273.961142) (xy 361.9624 -273.945094) (xy 362.013695 -273.936969)
			(xy 362.065629 -273.936969) (xy 362.116924 -273.945094) (xy 362.166317 -273.961142) (xy 362.212591 -273.98472)
			(xy 362.254607 -274.015246) (xy 362.29133 -274.051969) (xy 362.321856 -274.093985) (xy 362.345434 -274.140259)
			(xy 362.361482 -274.189652) (xy 362.369607 -274.240947) (xy 362.370116 -274.266914) (xy 362.369607 -274.292881)
			(xy 362.649517 -274.292881) (xy 362.649517 -274.240947) (xy 362.657642 -274.189652) (xy 362.67369 -274.140259)
			(xy 362.697268 -274.093985) (xy 362.727794 -274.051969) (xy 362.764517 -274.015246) (xy 362.806533 -273.98472)
			(xy 362.852807 -273.961142) (xy 362.9022 -273.945094) (xy 362.953495 -273.936969) (xy 363.005429 -273.936969)
			(xy 363.056724 -273.945094) (xy 363.106117 -273.961142) (xy 363.152391 -273.98472) (xy 363.194407 -274.015246)
			(xy 363.23113 -274.051969) (xy 363.261656 -274.093985) (xy 363.285234 -274.140259) (xy 363.301282 -274.189652)
			(xy 363.309407 -274.240947) (xy 363.309916 -274.266914) (xy 363.309407 -274.292881) (xy 363.301282 -274.344176)
			(xy 363.285234 -274.393569) (xy 363.261656 -274.439843) (xy 363.23113 -274.481859) (xy 363.194407 -274.518582)
			(xy 363.152391 -274.549108) (xy 363.106117 -274.572686) (xy 363.056724 -274.588734) (xy 363.005429 -274.596859)
			(xy 362.953495 -274.596859) (xy 362.9022 -274.588734) (xy 362.852807 -274.572686) (xy 362.806533 -274.549108)
			(xy 362.764517 -274.518582) (xy 362.727794 -274.481859) (xy 362.697268 -274.439843) (xy 362.67369 -274.393569)
			(xy 362.657642 -274.344176) (xy 362.649517 -274.292881) (xy 362.369607 -274.292881) (xy 362.361482 -274.344176)
			(xy 362.345434 -274.393569) (xy 362.321856 -274.439843) (xy 362.29133 -274.481859) (xy 362.254607 -274.518582)
			(xy 362.212591 -274.549108) (xy 362.166317 -274.572686) (xy 362.116924 -274.588734) (xy 362.065629 -274.596859)
			(xy 362.013695 -274.596859) (xy 361.9624 -274.588734) (xy 361.913007 -274.572686) (xy 361.866733 -274.549108)
			(xy 361.824717 -274.518582) (xy 361.787994 -274.481859) (xy 361.757468 -274.439843) (xy 361.73389 -274.393569)
			(xy 361.717842 -274.344176) (xy 361.709717 -274.292881) (xy 359.811261 -274.292881) (xy 359.820439 -274.30456)
			(xy 359.876483 -274.388311) (xy 359.925981 -274.476089) (xy 359.968645 -274.567385) (xy 360.004227 -274.661666)
			(xy 360.018838 -274.70989) (xy 360.022394 -274.722336) (xy 360.074464 -274.774406) (xy 360.074464 -274.886166)
			(xy 360.091736 -274.901406) (xy 360.129558 -274.9352) (xy 360.200478 -275.007723) (xy 360.265627 -275.085471)
			(xy 360.280803 -275.106697) (xy 361.239817 -275.106697) (xy 361.239817 -275.054763) (xy 361.247942 -275.003468)
			(xy 361.26399 -274.954075) (xy 361.287568 -274.907801) (xy 361.318094 -274.865785) (xy 361.354817 -274.829062)
			(xy 361.396833 -274.798536) (xy 361.443107 -274.774958) (xy 361.4925 -274.75891) (xy 361.543795 -274.750785)
			(xy 361.595729 -274.750785) (xy 361.647024 -274.75891) (xy 361.696417 -274.774958) (xy 361.742691 -274.798536)
			(xy 361.784707 -274.829062) (xy 361.82143 -274.865785) (xy 361.851956 -274.907801) (xy 361.875534 -274.954075)
			(xy 361.891582 -275.003468) (xy 361.899707 -275.054763) (xy 361.900216 -275.08073) (xy 361.899707 -275.106697)
			(xy 362.179363 -275.106697) (xy 362.179363 -275.054763) (xy 362.187488 -275.003468) (xy 362.203536 -274.954075)
			(xy 362.227114 -274.907801) (xy 362.25764 -274.865785) (xy 362.294363 -274.829062) (xy 362.336379 -274.798536)
			(xy 362.382653 -274.774958) (xy 362.432046 -274.75891) (xy 362.483341 -274.750785) (xy 362.535275 -274.750785)
			(xy 362.58657 -274.75891) (xy 362.635963 -274.774958) (xy 362.682237 -274.798536) (xy 362.724253 -274.829062)
			(xy 362.760976 -274.865785) (xy 362.791502 -274.907801) (xy 362.81508 -274.954075) (xy 362.831128 -275.003468)
			(xy 362.839253 -275.054763) (xy 362.839762 -275.08073) (xy 362.839253 -275.106697) (xy 363.119163 -275.106697)
			(xy 363.119163 -275.054763) (xy 363.127288 -275.003468) (xy 363.143336 -274.954075) (xy 363.166914 -274.907801)
			(xy 363.19744 -274.865785) (xy 363.234163 -274.829062) (xy 363.276179 -274.798536) (xy 363.322453 -274.774958)
			(xy 363.371846 -274.75891) (xy 363.423141 -274.750785) (xy 363.475075 -274.750785) (xy 363.52637 -274.75891)
			(xy 363.575763 -274.774958) (xy 363.622037 -274.798536) (xy 363.664053 -274.829062) (xy 363.700776 -274.865785)
			(xy 363.731302 -274.907801) (xy 363.75488 -274.954075) (xy 363.770928 -275.003468) (xy 363.779053 -275.054763)
			(xy 363.779562 -275.08073) (xy 363.779053 -275.106697) (xy 363.770928 -275.157992) (xy 363.75488 -275.207385)
			(xy 363.731302 -275.253659) (xy 363.700776 -275.295675) (xy 363.664053 -275.332398) (xy 363.622037 -275.362924)
			(xy 363.575763 -275.386502) (xy 363.52637 -275.40255) (xy 363.475075 -275.410675) (xy 363.423141 -275.410675)
			(xy 363.371846 -275.40255) (xy 363.322453 -275.386502) (xy 363.276179 -275.362924) (xy 363.234163 -275.332398)
			(xy 363.19744 -275.295675) (xy 363.166914 -275.253659) (xy 363.143336 -275.207385) (xy 363.127288 -275.157992)
			(xy 363.119163 -275.106697) (xy 362.839253 -275.106697) (xy 362.831128 -275.157992) (xy 362.81508 -275.207385)
			(xy 362.791502 -275.253659) (xy 362.760976 -275.295675) (xy 362.724253 -275.332398) (xy 362.682237 -275.362924)
			(xy 362.635963 -275.386502) (xy 362.58657 -275.40255) (xy 362.535275 -275.410675) (xy 362.483341 -275.410675)
			(xy 362.432046 -275.40255) (xy 362.382653 -275.386502) (xy 362.336379 -275.362924) (xy 362.294363 -275.332398)
			(xy 362.25764 -275.295675) (xy 362.227114 -275.253659) (xy 362.203536 -275.207385) (xy 362.187488 -275.157992)
			(xy 362.179363 -275.106697) (xy 361.899707 -275.106697) (xy 361.891582 -275.157992) (xy 361.875534 -275.207385)
			(xy 361.851956 -275.253659) (xy 361.82143 -275.295675) (xy 361.784707 -275.332398) (xy 361.742691 -275.362924)
			(xy 361.696417 -275.386502) (xy 361.647024 -275.40255) (xy 361.595729 -275.410675) (xy 361.543795 -275.410675)
			(xy 361.4925 -275.40255) (xy 361.443107 -275.386502) (xy 361.396833 -275.362924) (xy 361.354817 -275.332398)
			(xy 361.318094 -275.295675) (xy 361.287568 -275.253659) (xy 361.26399 -275.207385) (xy 361.247942 -275.157992)
			(xy 361.239817 -275.106697) (xy 360.280803 -275.106697) (xy 360.324622 -275.167986) (xy 360.377116 -275.254782)
			(xy 360.422798 -275.345349) (xy 360.461402 -275.439151) (xy 360.492698 -275.535638) (xy 360.516503 -275.634241)
			(xy 360.52506 -275.684234) (xy 360.566106 -275.718361) (xy 360.643151 -275.792256) (xy 360.71398 -275.872129)
			(xy 360.750545 -275.920767) (xy 361.709971 -275.920767) (xy 361.709971 -275.868833) (xy 361.718096 -275.817538)
			(xy 361.734144 -275.768145) (xy 361.757722 -275.721871) (xy 361.788248 -275.679855) (xy 361.824971 -275.643132)
			(xy 361.866987 -275.612606) (xy 361.913261 -275.589028) (xy 361.962654 -275.57298) (xy 362.013949 -275.564855)
			(xy 362.065883 -275.564855) (xy 362.117178 -275.57298) (xy 362.166571 -275.589028) (xy 362.212845 -275.612606)
			(xy 362.254861 -275.643132) (xy 362.291584 -275.679855) (xy 362.32211 -275.721871) (xy 362.345688 -275.768145)
			(xy 362.361736 -275.817538) (xy 362.369861 -275.868833) (xy 362.37037 -275.8948) (xy 362.369861 -275.920767)
			(xy 362.649517 -275.920767) (xy 362.649517 -275.868833) (xy 362.657642 -275.817538) (xy 362.67369 -275.768145)
			(xy 362.697268 -275.721871) (xy 362.727794 -275.679855) (xy 362.764517 -275.643132) (xy 362.806533 -275.612606)
			(xy 362.852807 -275.589028) (xy 362.9022 -275.57298) (xy 362.953495 -275.564855) (xy 363.005429 -275.564855)
			(xy 363.056724 -275.57298) (xy 363.106117 -275.589028) (xy 363.152391 -275.612606) (xy 363.194407 -275.643132)
			(xy 363.23113 -275.679855) (xy 363.261656 -275.721871) (xy 363.285234 -275.768145) (xy 363.301282 -275.817538)
			(xy 363.309407 -275.868833) (xy 363.309916 -275.8948) (xy 363.309407 -275.920767) (xy 363.589317 -275.920767)
			(xy 363.589317 -275.868833) (xy 363.597442 -275.817538) (xy 363.61349 -275.768145) (xy 363.637068 -275.721871)
			(xy 363.667594 -275.679855) (xy 363.704317 -275.643132) (xy 363.746333 -275.612606) (xy 363.792607 -275.589028)
			(xy 363.842 -275.57298) (xy 363.893295 -275.564855) (xy 363.945229 -275.564855) (xy 363.996524 -275.57298)
			(xy 364.045917 -275.589028) (xy 364.092191 -275.612606) (xy 364.134207 -275.643132) (xy 364.17093 -275.679855)
			(xy 364.201456 -275.721871) (xy 364.225034 -275.768145) (xy 364.241082 -275.817538) (xy 364.249207 -275.868833)
			(xy 364.249716 -275.8948) (xy 364.249207 -275.920767) (xy 364.241082 -275.972062) (xy 364.225034 -276.021455)
			(xy 364.201456 -276.067729) (xy 364.17093 -276.109745) (xy 364.134207 -276.146468) (xy 364.092191 -276.176994)
			(xy 364.045917 -276.200572) (xy 363.996524 -276.21662) (xy 363.945229 -276.224745) (xy 363.893295 -276.224745)
			(xy 363.842 -276.21662) (xy 363.792607 -276.200572) (xy 363.746333 -276.176994) (xy 363.704317 -276.146468)
			(xy 363.667594 -276.109745) (xy 363.637068 -276.067729) (xy 363.61349 -276.021455) (xy 363.597442 -275.972062)
			(xy 363.589317 -275.920767) (xy 363.309407 -275.920767) (xy 363.301282 -275.972062) (xy 363.285234 -276.021455)
			(xy 363.261656 -276.067729) (xy 363.23113 -276.109745) (xy 363.194407 -276.146468) (xy 363.152391 -276.176994)
			(xy 363.106117 -276.200572) (xy 363.056724 -276.21662) (xy 363.005429 -276.224745) (xy 362.953495 -276.224745)
			(xy 362.9022 -276.21662) (xy 362.852807 -276.200572) (xy 362.806533 -276.176994) (xy 362.764517 -276.146468)
			(xy 362.727794 -276.109745) (xy 362.697268 -276.067729) (xy 362.67369 -276.021455) (xy 362.657642 -275.972062)
			(xy 362.649517 -275.920767) (xy 362.369861 -275.920767) (xy 362.361736 -275.972062) (xy 362.345688 -276.021455)
			(xy 362.32211 -276.067729) (xy 362.291584 -276.109745) (xy 362.254861 -276.146468) (xy 362.212845 -276.176994)
			(xy 362.166571 -276.200572) (xy 362.117178 -276.21662) (xy 362.065883 -276.224745) (xy 362.013949 -276.224745)
			(xy 361.962654 -276.21662) (xy 361.913261 -276.200572) (xy 361.866987 -276.176994) (xy 361.824971 -276.146468)
			(xy 361.788248 -276.109745) (xy 361.757722 -276.067729) (xy 361.734144 -276.021455) (xy 361.718096 -275.972062)
			(xy 361.709971 -275.920767) (xy 360.750545 -275.920767) (xy 360.77813 -275.95746) (xy 360.835183 -276.04769)
			(xy 360.884767 -276.142231) (xy 360.926556 -276.240466) (xy 360.96028 -276.341753) (xy 360.985717 -276.445433)
			(xy 360.994706 -276.49805) (xy 361.037135 -276.533338) (xy 361.116603 -276.609923) (xy 361.189405 -276.692871)
			(xy 361.220256 -276.734583) (xy 362.179871 -276.734583) (xy 362.179871 -276.682649) (xy 362.187996 -276.631354)
			(xy 362.204044 -276.581961) (xy 362.227622 -276.535687) (xy 362.258148 -276.493671) (xy 362.294871 -276.456948)
			(xy 362.336887 -276.426422) (xy 362.383161 -276.402844) (xy 362.432554 -276.386796) (xy 362.483849 -276.378671)
			(xy 362.535783 -276.378671) (xy 362.587078 -276.386796) (xy 362.636471 -276.402844) (xy 362.682745 -276.426422)
			(xy 362.724761 -276.456948) (xy 362.761484 -276.493671) (xy 362.79201 -276.535687) (xy 362.815588 -276.581961)
			(xy 362.831636 -276.631354) (xy 362.839761 -276.682649) (xy 362.84027 -276.708616) (xy 362.839766 -276.734329)
			(xy 363.119417 -276.734329) (xy 363.119417 -276.682395) (xy 363.127542 -276.6311) (xy 363.14359 -276.581707)
			(xy 363.167168 -276.535433) (xy 363.197694 -276.493417) (xy 363.234417 -276.456694) (xy 363.276433 -276.426168)
			(xy 363.322707 -276.40259) (xy 363.3721 -276.386542) (xy 363.423395 -276.378417) (xy 363.475329 -276.378417)
			(xy 363.526624 -276.386542) (xy 363.576017 -276.40259) (xy 363.622291 -276.426168) (xy 363.664307 -276.456694)
			(xy 363.70103 -276.493417) (xy 363.731556 -276.535433) (xy 363.755134 -276.581707) (xy 363.771182 -276.6311)
			(xy 363.779307 -276.682395) (xy 363.779816 -276.708362) (xy 363.779307 -276.734329) (xy 363.771182 -276.785624)
			(xy 363.755134 -276.835017) (xy 363.731556 -276.881291) (xy 363.70103 -276.923307) (xy 363.664307 -276.96003)
			(xy 363.622291 -276.990556) (xy 363.576017 -277.014134) (xy 363.526624 -277.030182) (xy 363.475329 -277.038307)
			(xy 363.423395 -277.038307) (xy 363.3721 -277.030182) (xy 363.322707 -277.014134) (xy 363.276433 -276.990556)
			(xy 363.234417 -276.96003) (xy 363.197694 -276.923307) (xy 363.167168 -276.881291) (xy 363.14359 -276.835017)
			(xy 363.127542 -276.785624) (xy 363.119417 -276.734329) (xy 362.839766 -276.734329) (xy 362.839761 -276.734583)
			(xy 362.831636 -276.785878) (xy 362.815588 -276.835271) (xy 362.79201 -276.881545) (xy 362.761484 -276.923561)
			(xy 362.724761 -276.960284) (xy 362.682745 -276.99081) (xy 362.636471 -277.014388) (xy 362.587078 -277.030436)
			(xy 362.535783 -277.038561) (xy 362.483849 -277.038561) (xy 362.432554 -277.030436) (xy 362.383161 -277.014388)
			(xy 362.336887 -276.99081) (xy 362.294871 -276.960284) (xy 362.258148 -276.923561) (xy 362.227622 -276.881545)
			(xy 362.204044 -276.835271) (xy 362.187996 -276.785878) (xy 362.179871 -276.734583) (xy 361.220256 -276.734583)
			(xy 361.255033 -276.781603) (xy 361.28452 -276.82825) (xy 361.287568 -276.83333) (xy 361.372404 -276.918166)
			(xy 361.372404 -276.996398) (xy 361.376468 -277.005796) (xy 361.39673 -277.054839) (xy 361.430257 -277.155527)
			(xy 361.455593 -277.258581) (xy 361.472577 -277.363336) (xy 361.481096 -277.469117) (xy 361.481624 -277.522178)
			(xy 361.481624 -277.536656) (xy 361.481467 -277.548399) (xy 362.649517 -277.548399) (xy 362.649517 -277.496465)
			(xy 362.657642 -277.44517) (xy 362.67369 -277.395777) (xy 362.697268 -277.349503) (xy 362.727794 -277.307487)
			(xy 362.764517 -277.270764) (xy 362.806533 -277.240238) (xy 362.852807 -277.21666) (xy 362.9022 -277.200612)
			(xy 362.953495 -277.192487) (xy 363.005429 -277.192487) (xy 363.056724 -277.200612) (xy 363.106117 -277.21666)
			(xy 363.152391 -277.240238) (xy 363.194407 -277.270764) (xy 363.23113 -277.307487) (xy 363.261656 -277.349503)
			(xy 363.285234 -277.395777) (xy 363.301282 -277.44517) (xy 363.309407 -277.496465) (xy 363.309916 -277.522432)
			(xy 363.309412 -277.548145) (xy 363.589571 -277.548145) (xy 363.589571 -277.496211) (xy 363.597696 -277.444916)
			(xy 363.613744 -277.395523) (xy 363.637322 -277.349249) (xy 363.667848 -277.307233) (xy 363.704571 -277.27051)
			(xy 363.746587 -277.239984) (xy 363.792861 -277.216406) (xy 363.842254 -277.200358) (xy 363.893549 -277.192233)
			(xy 363.945483 -277.192233) (xy 363.996778 -277.200358) (xy 364.046171 -277.216406) (xy 364.092445 -277.239984)
			(xy 364.134461 -277.27051) (xy 364.171184 -277.307233) (xy 364.20171 -277.349249) (xy 364.225288 -277.395523)
			(xy 364.241336 -277.444916) (xy 364.249461 -277.496211) (xy 364.24997 -277.522178) (xy 364.249461 -277.548145)
			(xy 364.241336 -277.59944) (xy 364.225288 -277.648833) (xy 364.20171 -277.695107) (xy 364.171184 -277.737123)
			(xy 364.134461 -277.773846) (xy 364.092445 -277.804372) (xy 364.046171 -277.82795) (xy 363.996778 -277.843998)
			(xy 363.945483 -277.852123) (xy 363.893549 -277.852123) (xy 363.842254 -277.843998) (xy 363.792861 -277.82795)
			(xy 363.746587 -277.804372) (xy 363.704571 -277.773846) (xy 363.667848 -277.737123) (xy 363.637322 -277.695107)
			(xy 363.613744 -277.648833) (xy 363.597696 -277.59944) (xy 363.589571 -277.548145) (xy 363.309412 -277.548145)
			(xy 363.309407 -277.548399) (xy 363.301282 -277.599694) (xy 363.285234 -277.649087) (xy 363.261656 -277.695361)
			(xy 363.23113 -277.737377) (xy 363.194407 -277.7741) (xy 363.152391 -277.804626) (xy 363.106117 -277.828204)
			(xy 363.056724 -277.844252) (xy 363.005429 -277.852377) (xy 362.953495 -277.852377) (xy 362.9022 -277.844252)
			(xy 362.852807 -277.828204) (xy 362.806533 -277.804626) (xy 362.764517 -277.7741) (xy 362.727794 -277.737377)
			(xy 362.697268 -277.695361) (xy 362.67369 -277.649087) (xy 362.657642 -277.599694) (xy 362.649517 -277.548399)
			(xy 361.481467 -277.548399) (xy 361.48137 -277.555706) (xy 361.479492 -277.608634) (xy 361.468313 -277.71396)
			(xy 361.44873 -277.818052) (xy 361.42087 -277.92024) (xy 361.403392 -277.970234) (xy 361.397082 -277.987604)
			(xy 361.383618 -278.022026) (xy 361.376468 -278.039068) (xy 361.372404 -278.04872) (xy 361.372404 -278.137366)
			(xy 361.270042 -278.239728) (xy 361.26674 -278.244808) (xy 361.238425 -278.287276) (xy 361.180781 -278.362215)
			(xy 362.179617 -278.362215) (xy 362.179617 -278.310281) (xy 362.187742 -278.258986) (xy 362.20379 -278.209593)
			(xy 362.227368 -278.163319) (xy 362.257894 -278.121303) (xy 362.294617 -278.08458) (xy 362.336633 -278.054054)
			(xy 362.382907 -278.030476) (xy 362.4323 -278.014428) (xy 362.483595 -278.006303) (xy 362.535529 -278.006303)
			(xy 362.586824 -278.014428) (xy 362.636217 -278.030476) (xy 362.682491 -278.054054) (xy 362.724507 -278.08458)
			(xy 362.76123 -278.121303) (xy 362.791756 -278.163319) (xy 362.815334 -278.209593) (xy 362.831382 -278.258986)
			(xy 362.839507 -278.310281) (xy 362.840016 -278.336248) (xy 362.839507 -278.362215) (xy 363.119417 -278.362215)
			(xy 363.119417 -278.310281) (xy 363.127542 -278.258986) (xy 363.14359 -278.209593) (xy 363.167168 -278.163319)
			(xy 363.197694 -278.121303) (xy 363.234417 -278.08458) (xy 363.276433 -278.054054) (xy 363.322707 -278.030476)
			(xy 363.3721 -278.014428) (xy 363.423395 -278.006303) (xy 363.475329 -278.006303) (xy 363.526624 -278.014428)
			(xy 363.576017 -278.030476) (xy 363.622291 -278.054054) (xy 363.664307 -278.08458) (xy 363.70103 -278.121303)
			(xy 363.731556 -278.163319) (xy 363.755134 -278.209593) (xy 363.771182 -278.258986) (xy 363.779307 -278.310281)
			(xy 363.779816 -278.336248) (xy 363.779307 -278.362215) (xy 363.771182 -278.41351) (xy 363.755134 -278.462903)
			(xy 363.731556 -278.509177) (xy 363.70103 -278.551193) (xy 363.664307 -278.587916) (xy 363.622291 -278.618442)
			(xy 363.576017 -278.64202) (xy 363.526624 -278.658068) (xy 363.475329 -278.666193) (xy 363.423395 -278.666193)
			(xy 363.3721 -278.658068) (xy 363.322707 -278.64202) (xy 363.276433 -278.618442) (xy 363.234417 -278.587916)
			(xy 363.197694 -278.551193) (xy 363.167168 -278.509177) (xy 363.14359 -278.462903) (xy 363.127542 -278.41351)
			(xy 363.119417 -278.362215) (xy 362.839507 -278.362215) (xy 362.831382 -278.41351) (xy 362.815334 -278.462903)
			(xy 362.791756 -278.509177) (xy 362.76123 -278.551193) (xy 362.724507 -278.587916) (xy 362.682491 -278.618442)
			(xy 362.636217 -278.64202) (xy 362.586824 -278.658068) (xy 362.535529 -278.666193) (xy 362.483595 -278.666193)
			(xy 362.4323 -278.658068) (xy 362.382907 -278.64202) (xy 362.336633 -278.618442) (xy 362.294617 -278.587916)
			(xy 362.257894 -278.551193) (xy 362.227368 -278.509177) (xy 362.20379 -278.462903) (xy 362.187742 -278.41351)
			(xy 362.179617 -278.362215) (xy 361.180781 -278.362215) (xy 361.176187 -278.368188) (xy 361.107897 -278.444061)
			(xy 361.033961 -278.514443) (xy 360.994706 -278.547068) (xy 360.985664 -278.599745) (xy 360.96016 -278.703546)
			(xy 360.926354 -278.804947) (xy 360.884468 -278.903287) (xy 360.834777 -278.997923) (xy 360.777603 -279.088236)
			(xy 360.713322 -279.173635) (xy 360.710969 -279.176285) (xy 362.649517 -279.176285) (xy 362.649517 -279.124351)
			(xy 362.657642 -279.073056) (xy 362.67369 -279.023663) (xy 362.697268 -278.977389) (xy 362.727794 -278.935373)
			(xy 362.764517 -278.89865) (xy 362.806533 -278.868124) (xy 362.852807 -278.844546) (xy 362.9022 -278.828498)
			(xy 362.953495 -278.820373) (xy 363.005429 -278.820373) (xy 363.056724 -278.828498) (xy 363.106117 -278.844546)
			(xy 363.152391 -278.868124) (xy 363.194407 -278.89865) (xy 363.23113 -278.935373) (xy 363.261656 -278.977389)
			(xy 363.285234 -279.023663) (xy 363.301282 -279.073056) (xy 363.309407 -279.124351) (xy 363.309916 -279.150318)
			(xy 363.309407 -279.176285) (xy 363.589317 -279.176285) (xy 363.589317 -279.124351) (xy 363.597442 -279.073056)
			(xy 363.61349 -279.023663) (xy 363.637068 -278.977389) (xy 363.667594 -278.935373) (xy 363.704317 -278.89865)
			(xy 363.746333 -278.868124) (xy 363.792607 -278.844546) (xy 363.842 -278.828498) (xy 363.893295 -278.820373)
			(xy 363.945229 -278.820373) (xy 363.996524 -278.828498) (xy 364.045917 -278.844546) (xy 364.092191 -278.868124)
			(xy 364.134207 -278.89865) (xy 364.17093 -278.935373) (xy 364.201456 -278.977389) (xy 364.225034 -279.023663)
			(xy 364.241082 -279.073056) (xy 364.249207 -279.124351) (xy 364.249716 -279.150318) (xy 364.249207 -279.176285)
			(xy 364.241082 -279.22758) (xy 364.225034 -279.276973) (xy 364.201456 -279.323247) (xy 364.17093 -279.365263)
			(xy 364.134207 -279.401986) (xy 364.092191 -279.432512) (xy 364.045917 -279.45609) (xy 363.996524 -279.472138)
			(xy 363.945229 -279.480263) (xy 363.893295 -279.480263) (xy 363.842 -279.472138) (xy 363.792607 -279.45609)
			(xy 363.746333 -279.432512) (xy 363.704317 -279.401986) (xy 363.667594 -279.365263) (xy 363.637068 -279.323247)
			(xy 363.61349 -279.276973) (xy 363.597442 -279.22758) (xy 363.589317 -279.176285) (xy 363.309407 -279.176285)
			(xy 363.301282 -279.22758) (xy 363.285234 -279.276973) (xy 363.261656 -279.323247) (xy 363.23113 -279.365263)
			(xy 363.194407 -279.401986) (xy 363.152391 -279.432512) (xy 363.106117 -279.45609) (xy 363.056724 -279.472138)
			(xy 363.005429 -279.480263) (xy 362.953495 -279.480263) (xy 362.9022 -279.472138) (xy 362.852807 -279.45609)
			(xy 362.806533 -279.432512) (xy 362.764517 -279.401986) (xy 362.727794 -279.365263) (xy 362.697268 -279.323247)
			(xy 362.67369 -279.276973) (xy 362.657642 -279.22758) (xy 362.649517 -279.176285) (xy 360.710969 -279.176285)
			(xy 360.642353 -279.253563) (xy 360.56516 -279.327498) (xy 360.524044 -279.361646) (xy 360.524044 -279.990101)
			(xy 361.239817 -279.990101) (xy 361.239817 -279.938167) (xy 361.247942 -279.886872) (xy 361.26399 -279.837479)
			(xy 361.287568 -279.791205) (xy 361.318094 -279.749189) (xy 361.354817 -279.712466) (xy 361.396833 -279.68194)
			(xy 361.443107 -279.658362) (xy 361.4925 -279.642314) (xy 361.543795 -279.634189) (xy 361.595729 -279.634189)
			(xy 361.647024 -279.642314) (xy 361.696417 -279.658362) (xy 361.742691 -279.68194) (xy 361.784707 -279.712466)
			(xy 361.82143 -279.749189) (xy 361.851956 -279.791205) (xy 361.875534 -279.837479) (xy 361.891582 -279.886872)
			(xy 361.899707 -279.938167) (xy 361.900216 -279.964134) (xy 361.899707 -279.990101) (xy 361.891582 -280.041396)
			(xy 361.875534 -280.090789) (xy 361.851956 -280.137063) (xy 361.82143 -280.179079) (xy 361.784707 -280.215802)
			(xy 361.742691 -280.246328) (xy 361.696417 -280.269906) (xy 361.647024 -280.285954) (xy 361.595729 -280.294079)
			(xy 361.543795 -280.294079) (xy 361.4925 -280.285954) (xy 361.443107 -280.269906) (xy 361.396833 -280.246328)
			(xy 361.354817 -280.215802) (xy 361.318094 -280.179079) (xy 361.287568 -280.137063) (xy 361.26399 -280.090789)
			(xy 361.247942 -280.041396) (xy 361.239817 -279.990101) (xy 360.524044 -279.990101) (xy 360.524044 -280.561288)
			(xy 360.524806 -280.565352) (xy 360.531306 -280.607251) (xy 360.539569 -280.691644) (xy 360.541316 -280.734008)
			(xy 360.541824 -280.76398) (xy 360.541824 -280.778204) (xy 360.541276 -280.832431) (xy 360.532372 -280.940518)
			(xy 360.524044 -280.994104) (xy 360.524044 -281.617987) (xy 361.239817 -281.617987) (xy 361.239817 -281.566053)
			(xy 361.247942 -281.514758) (xy 361.26399 -281.465365) (xy 361.287568 -281.419091) (xy 361.318094 -281.377075)
			(xy 361.354817 -281.340352) (xy 361.396833 -281.309826) (xy 361.443107 -281.286248) (xy 361.4925 -281.2702)
			(xy 361.543795 -281.262075) (xy 361.595729 -281.262075) (xy 361.647024 -281.2702) (xy 361.696417 -281.286248)
			(xy 361.742691 -281.309826) (xy 361.784707 -281.340352) (xy 361.82143 -281.377075) (xy 361.851956 -281.419091)
			(xy 361.875534 -281.465365) (xy 361.891582 -281.514758) (xy 361.899707 -281.566053) (xy 361.900216 -281.59202)
			(xy 361.899707 -281.617987) (xy 361.891582 -281.669282) (xy 361.875534 -281.718675) (xy 361.851956 -281.764949)
			(xy 361.82143 -281.806965) (xy 361.784707 -281.843688) (xy 361.742691 -281.874214) (xy 361.696417 -281.897792)
			(xy 361.647024 -281.91384) (xy 361.595729 -281.921965) (xy 361.543795 -281.921965) (xy 361.4925 -281.91384)
			(xy 361.443107 -281.897792) (xy 361.396833 -281.874214) (xy 361.354817 -281.843688) (xy 361.318094 -281.806965)
			(xy 361.287568 -281.764949) (xy 361.26399 -281.718675) (xy 361.247942 -281.669282) (xy 361.239817 -281.617987)
			(xy 360.524044 -281.617987) (xy 360.524044 -282.189936) (xy 360.532361 -282.243523) (xy 360.541259 -282.35161)
			(xy 360.541824 -282.405836) (xy 360.541824 -282.42006) (xy 360.541316 -282.450032) (xy 360.539559 -282.492395)
			(xy 360.531299 -282.576788) (xy 360.524806 -282.618688) (xy 360.524044 -282.622752) (xy 360.524044 -282.935426)
			(xy 360.318558 -283.140912) (xy 360.29773 -283.171138) (xy 360.26279 -283.219144) (xy 360.239904 -283.245873)
			(xy 361.239817 -283.245873) (xy 361.239817 -283.193939) (xy 361.247942 -283.142644) (xy 361.26399 -283.093251)
			(xy 361.287568 -283.046977) (xy 361.318094 -283.004961) (xy 361.354817 -282.968238) (xy 361.396833 -282.937712)
			(xy 361.443107 -282.914134) (xy 361.4925 -282.898086) (xy 361.543795 -282.889961) (xy 361.595729 -282.889961)
			(xy 361.647024 -282.898086) (xy 361.696417 -282.914134) (xy 361.742691 -282.937712) (xy 361.784707 -282.968238)
			(xy 361.82143 -283.004961) (xy 361.851956 -283.046977) (xy 361.875534 -283.093251) (xy 361.891582 -283.142644)
			(xy 361.899707 -283.193939) (xy 361.900216 -283.219906) (xy 361.899707 -283.245873) (xy 364.059471 -283.245873)
			(xy 364.059471 -283.193939) (xy 364.067596 -283.142644) (xy 364.083644 -283.093251) (xy 364.107222 -283.046977)
			(xy 364.137748 -283.004961) (xy 364.174471 -282.968238) (xy 364.216487 -282.937712) (xy 364.262761 -282.914134)
			(xy 364.312154 -282.898086) (xy 364.363449 -282.889961) (xy 364.415383 -282.889961) (xy 364.466678 -282.898086)
			(xy 364.516071 -282.914134) (xy 364.562345 -282.937712) (xy 364.604361 -282.968238) (xy 364.641084 -283.004961)
			(xy 364.67161 -283.046977) (xy 364.695188 -283.093251) (xy 364.711236 -283.142644) (xy 364.719361 -283.193939)
			(xy 364.71987 -283.219906) (xy 364.719361 -283.245873) (xy 364.711236 -283.297168) (xy 364.695188 -283.346561)
			(xy 364.67161 -283.392835) (xy 364.641084 -283.434851) (xy 364.604361 -283.471574) (xy 364.562345 -283.5021)
			(xy 364.516071 -283.525678) (xy 364.466678 -283.541726) (xy 364.415383 -283.549851) (xy 364.363449 -283.549851)
			(xy 364.312154 -283.541726) (xy 364.262761 -283.525678) (xy 364.216487 -283.5021) (xy 364.174471 -283.471574)
			(xy 364.137748 -283.434851) (xy 364.107222 -283.392835) (xy 364.083644 -283.346561) (xy 364.067596 -283.297168)
			(xy 364.059471 -283.245873) (xy 361.899707 -283.245873) (xy 361.891582 -283.297168) (xy 361.875534 -283.346561)
			(xy 361.851956 -283.392835) (xy 361.82143 -283.434851) (xy 361.784707 -283.471574) (xy 361.742691 -283.5021)
			(xy 361.696417 -283.525678) (xy 361.647024 -283.541726) (xy 361.595729 -283.549851) (xy 361.543795 -283.549851)
			(xy 361.4925 -283.541726) (xy 361.443107 -283.525678) (xy 361.396833 -283.5021) (xy 361.354817 -283.471574)
			(xy 361.318094 -283.434851) (xy 361.287568 -283.392835) (xy 361.26399 -283.346561) (xy 361.247942 -283.297168)
			(xy 361.239817 -283.245873) (xy 360.239904 -283.245873) (xy 360.185562 -283.309342) (xy 360.100551 -283.392246)
			(xy 360.054906 -283.430218) (xy 360.047055 -283.476449) (xy 360.025637 -283.567752) (xy 359.997796 -283.657307)
			(xy 359.963673 -283.744661) (xy 359.92344 -283.829374) (xy 359.900728 -283.8704) (xy 359.890249 -283.888738)
			(xy 359.868273 -283.924812) (xy 359.856786 -283.942536) (xy 359.848404 -283.955236) (xy 359.848404 -284.140148)
			(xy 359.532682 -284.45587) (xy 359.528872 -284.466792) (xy 359.511278 -284.515962) (xy 359.469367 -284.611626)
			(xy 359.420033 -284.703682) (xy 359.363584 -284.791554) (xy 359.301275 -284.873505) (xy 361.239817 -284.873505)
			(xy 361.239817 -284.821571) (xy 361.247942 -284.770276) (xy 361.26399 -284.720883) (xy 361.287568 -284.674609)
			(xy 361.318094 -284.632593) (xy 361.354817 -284.59587) (xy 361.396833 -284.565344) (xy 361.443107 -284.541766)
			(xy 361.4925 -284.525718) (xy 361.543795 -284.517593) (xy 361.595729 -284.517593) (xy 361.647024 -284.525718)
			(xy 361.696417 -284.541766) (xy 361.742691 -284.565344) (xy 361.784707 -284.59587) (xy 361.82143 -284.632593)
			(xy 361.851956 -284.674609) (xy 361.875534 -284.720883) (xy 361.891582 -284.770276) (xy 361.899707 -284.821571)
			(xy 361.900216 -284.847538) (xy 361.899707 -284.873505) (xy 364.059471 -284.873505) (xy 364.059471 -284.821571)
			(xy 364.067596 -284.770276) (xy 364.083644 -284.720883) (xy 364.107222 -284.674609) (xy 364.137748 -284.632593)
			(xy 364.174471 -284.59587) (xy 364.216487 -284.565344) (xy 364.262761 -284.541766) (xy 364.312154 -284.525718)
			(xy 364.363449 -284.517593) (xy 364.415383 -284.517593) (xy 364.466678 -284.525718) (xy 364.516071 -284.541766)
			(xy 364.562345 -284.565344) (xy 364.604361 -284.59587) (xy 364.641084 -284.632593) (xy 364.67161 -284.674609)
			(xy 364.695188 -284.720883) (xy 364.711236 -284.770276) (xy 364.719361 -284.821571) (xy 364.71987 -284.847538)
			(xy 364.719361 -284.873505) (xy 364.711236 -284.9248) (xy 364.695188 -284.974193) (xy 364.67161 -285.020467)
			(xy 364.641084 -285.062483) (xy 364.604361 -285.099206) (xy 364.562345 -285.129732) (xy 364.516071 -285.15331)
			(xy 364.466678 -285.169358) (xy 364.415383 -285.177483) (xy 364.363449 -285.177483) (xy 364.312154 -285.169358)
			(xy 364.262761 -285.15331) (xy 364.216487 -285.129732) (xy 364.174471 -285.099206) (xy 364.137748 -285.062483)
			(xy 364.107222 -285.020467) (xy 364.083644 -284.974193) (xy 364.067596 -284.9248) (xy 364.059471 -284.873505)
			(xy 361.899707 -284.873505) (xy 361.891582 -284.9248) (xy 361.875534 -284.974193) (xy 361.851956 -285.020467)
			(xy 361.82143 -285.062483) (xy 361.784707 -285.099206) (xy 361.742691 -285.129732) (xy 361.696417 -285.15331)
			(xy 361.647024 -285.169358) (xy 361.595729 -285.177483) (xy 361.543795 -285.177483) (xy 361.4925 -285.169358)
			(xy 361.443107 -285.15331) (xy 361.396833 -285.129732) (xy 361.354817 -285.099206) (xy 361.318094 -285.062483)
			(xy 361.287568 -285.020467) (xy 361.26399 -284.974193) (xy 361.247942 -284.9248) (xy 361.239817 -284.873505)
			(xy 359.301275 -284.873505) (xy 359.300371 -284.874694) (xy 359.230791 -284.952583) (xy 359.155277 -285.024733)
			(xy 359.115106 -285.058104) (xy 359.106076 -285.110721) (xy 359.080607 -285.214405) (xy 359.046854 -285.315696)
			(xy 359.005036 -285.413932) (xy 358.955426 -285.508473) (xy 358.898349 -285.598702) (xy 358.834175 -285.68403)
			(xy 358.763325 -285.763901) (xy 358.686259 -285.837793) (xy 358.645206 -285.87192) (xy 358.636174 -285.924557)
			(xy 358.610697 -286.028281) (xy 358.576928 -286.12961) (xy 358.535088 -286.227881) (xy 358.48545 -286.322453)
			(xy 358.428338 -286.412709) (xy 358.364125 -286.498058) (xy 358.361167 -286.501391) (xy 361.239817 -286.501391)
			(xy 361.239817 -286.449457) (xy 361.247942 -286.398162) (xy 361.26399 -286.348769) (xy 361.287568 -286.302495)
			(xy 361.318094 -286.260479) (xy 361.354817 -286.223756) (xy 361.396833 -286.19323) (xy 361.443107 -286.169652)
			(xy 361.4925 -286.153604) (xy 361.543795 -286.145479) (xy 361.595729 -286.145479) (xy 361.647024 -286.153604)
			(xy 361.696417 -286.169652) (xy 361.742691 -286.19323) (xy 361.784707 -286.223756) (xy 361.82143 -286.260479)
			(xy 361.851956 -286.302495) (xy 361.875534 -286.348769) (xy 361.891582 -286.398162) (xy 361.899707 -286.449457)
			(xy 361.900216 -286.475424) (xy 361.899707 -286.501391) (xy 364.059471 -286.501391) (xy 364.059471 -286.449457)
			(xy 364.067596 -286.398162) (xy 364.083644 -286.348769) (xy 364.107222 -286.302495) (xy 364.137748 -286.260479)
			(xy 364.174471 -286.223756) (xy 364.216487 -286.19323) (xy 364.262761 -286.169652) (xy 364.312154 -286.153604)
			(xy 364.363449 -286.145479) (xy 364.415383 -286.145479) (xy 364.466678 -286.153604) (xy 364.516071 -286.169652)
			(xy 364.562345 -286.19323) (xy 364.604361 -286.223756) (xy 364.641084 -286.260479) (xy 364.67161 -286.302495)
			(xy 364.695188 -286.348769) (xy 364.711236 -286.398162) (xy 364.719361 -286.449457) (xy 364.71987 -286.475424)
			(xy 364.719361 -286.501391) (xy 364.711236 -286.552686) (xy 364.695188 -286.602079) (xy 364.67161 -286.648353)
			(xy 364.641084 -286.690369) (xy 364.604361 -286.727092) (xy 364.562345 -286.757618) (xy 364.516071 -286.781196)
			(xy 364.466678 -286.797244) (xy 364.415383 -286.805369) (xy 364.363449 -286.805369) (xy 364.312154 -286.797244)
			(xy 364.262761 -286.781196) (xy 364.216487 -286.757618) (xy 364.174471 -286.727092) (xy 364.137748 -286.690369)
			(xy 364.107222 -286.648353) (xy 364.083644 -286.602079) (xy 364.067596 -286.552686) (xy 364.059471 -286.501391)
			(xy 361.899707 -286.501391) (xy 361.891582 -286.552686) (xy 361.875534 -286.602079) (xy 361.851956 -286.648353)
			(xy 361.82143 -286.690369) (xy 361.784707 -286.727092) (xy 361.742691 -286.757618) (xy 361.696417 -286.781196)
			(xy 361.647024 -286.797244) (xy 361.595729 -286.805369) (xy 361.543795 -286.805369) (xy 361.4925 -286.797244)
			(xy 361.443107 -286.781196) (xy 361.396833 -286.757618) (xy 361.354817 -286.727092) (xy 361.318094 -286.690369)
			(xy 361.287568 -286.648353) (xy 361.26399 -286.602079) (xy 361.247942 -286.552686) (xy 361.239817 -286.501391)
			(xy 358.361167 -286.501391) (xy 358.293231 -286.577944) (xy 358.216117 -286.651845) (xy 358.175052 -286.68599)
			(xy 358.168699 -286.723724) (xy 358.15218 -286.798447) (xy 358.142032 -286.835342) (xy 358.139265 -286.848868)
			(xy 358.140263 -286.876447) (xy 358.148615 -286.90275) (xy 358.163711 -286.925853) (xy 358.184444 -286.944065)
			(xy 358.209301 -286.956056) (xy 358.236461 -286.960947) (xy 358.250236 -286.960056) (xy 358.280462 -286.958786)
			(xy 358.30643 -286.959266) (xy 358.357728 -286.967385) (xy 358.407123 -286.98343) (xy 358.453401 -287.007005)
			(xy 358.49542 -287.037529) (xy 358.532146 -287.074251) (xy 358.562676 -287.116267) (xy 358.586256 -287.162542)
			(xy 358.602306 -287.211935) (xy 358.610431 -287.263232) (xy 358.610431 -287.315168) (xy 358.602306 -287.366465)
			(xy 358.586256 -287.415858) (xy 358.562676 -287.462133) (xy 358.532146 -287.504149) (xy 358.49542 -287.540871)
			(xy 358.453401 -287.571395) (xy 358.407123 -287.59497) (xy 358.357728 -287.611015) (xy 358.30643 -287.619134)
			(xy 358.280462 -287.619694) (xy 358.255482 -287.61924) (xy 358.20609 -287.611728) (xy 358.158392 -287.596864)
			(xy 358.113476 -287.574989) (xy 358.072366 -287.5466) (xy 358.053894 -287.529778) (xy 358.04256 -287.5207)
			(xy 358.016124 -287.508718) (xy 357.987386 -287.504654) (xy 357.958665 -287.508838) (xy 357.93228 -287.520931)
			(xy 357.910361 -287.539957) (xy 357.894679 -287.56438) (xy 357.886499 -287.592228) (xy 357.886 -287.60674)
			(xy 357.886 -287.778952) (xy 357.92029 -287.79089) (xy 357.944204 -287.799792) (xy 357.989179 -287.823895)
			(xy 358.029921 -287.854617) (xy 358.065465 -287.891228) (xy 358.094967 -287.932861) (xy 358.117729 -287.97853)
			(xy 358.13321 -288.027151) (xy 358.141045 -288.077572) (xy 358.141048 -288.128599) (xy 358.140982 -288.129023)
			(xy 361.239817 -288.129023) (xy 361.239817 -288.077089) (xy 361.247942 -288.025794) (xy 361.26399 -287.976401)
			(xy 361.287568 -287.930127) (xy 361.318094 -287.888111) (xy 361.354817 -287.851388) (xy 361.396833 -287.820862)
			(xy 361.443107 -287.797284) (xy 361.4925 -287.781236) (xy 361.543795 -287.773111) (xy 361.595729 -287.773111)
			(xy 361.647024 -287.781236) (xy 361.696417 -287.797284) (xy 361.742691 -287.820862) (xy 361.784707 -287.851388)
			(xy 361.82143 -287.888111) (xy 361.851956 -287.930127) (xy 361.875534 -287.976401) (xy 361.891582 -288.025794)
			(xy 361.899707 -288.077089) (xy 361.900216 -288.103056) (xy 361.899707 -288.129023) (xy 364.059471 -288.129023)
			(xy 364.059471 -288.077089) (xy 364.067596 -288.025794) (xy 364.083644 -287.976401) (xy 364.107222 -287.930127)
			(xy 364.137748 -287.888111) (xy 364.174471 -287.851388) (xy 364.216487 -287.820862) (xy 364.262761 -287.797284)
			(xy 364.312154 -287.781236) (xy 364.363449 -287.773111) (xy 364.415383 -287.773111) (xy 364.466678 -287.781236)
			(xy 364.516071 -287.797284) (xy 364.562345 -287.820862) (xy 364.604361 -287.851388) (xy 364.641084 -287.888111)
			(xy 364.67161 -287.930127) (xy 364.695188 -287.976401) (xy 364.711236 -288.025794) (xy 364.719361 -288.077089)
			(xy 364.71987 -288.103056) (xy 364.719361 -288.129023) (xy 364.711236 -288.180318) (xy 364.695188 -288.229711)
			(xy 364.67161 -288.275985) (xy 364.641084 -288.318001) (xy 364.604361 -288.354724) (xy 364.562345 -288.38525)
			(xy 364.516071 -288.408828) (xy 364.466678 -288.424876) (xy 364.415383 -288.433001) (xy 364.363449 -288.433001)
			(xy 364.312154 -288.424876) (xy 364.262761 -288.408828) (xy 364.216487 -288.38525) (xy 364.174471 -288.354724)
			(xy 364.137748 -288.318001) (xy 364.107222 -288.275985) (xy 364.083644 -288.229711) (xy 364.067596 -288.180318)
			(xy 364.059471 -288.129023) (xy 361.899707 -288.129023) (xy 361.891582 -288.180318) (xy 361.875534 -288.229711)
			(xy 361.851956 -288.275985) (xy 361.82143 -288.318001) (xy 361.784707 -288.354724) (xy 361.742691 -288.38525)
			(xy 361.696417 -288.408828) (xy 361.647024 -288.424876) (xy 361.595729 -288.433001) (xy 361.543795 -288.433001)
			(xy 361.4925 -288.424876) (xy 361.443107 -288.408828) (xy 361.396833 -288.38525) (xy 361.354817 -288.354724)
			(xy 361.318094 -288.318001) (xy 361.287568 -288.275985) (xy 361.26399 -288.229711) (xy 361.247942 -288.180318)
			(xy 361.239817 -288.129023) (xy 358.140982 -288.129023) (xy 358.133217 -288.179021) (xy 358.11774 -288.227643)
			(xy 358.094982 -288.273314) (xy 358.065483 -288.31495) (xy 358.029943 -288.351564) (xy 357.989204 -288.382289)
			(xy 357.944231 -288.406396) (xy 357.92029 -288.415222) (xy 357.886 -288.42716) (xy 357.886 -288.675826)
			(xy 357.886473 -288.690124) (xy 357.894381 -288.717605) (xy 357.909599 -288.741815) (xy 357.930932 -288.760858)
			(xy 357.956709 -288.773238) (xy 357.984908 -288.777987) (xy 358.013318 -288.774731) (xy 358.039711 -288.763726)
			(xy 358.0511 -288.755074) (xy 358.063038 -288.74466) (xy 358.081197 -288.729309) (xy 358.121091 -288.703437)
			(xy 358.164284 -288.683555) (xy 358.209882 -288.670073) (xy 358.256941 -288.66327) (xy 358.280716 -288.662872)
			(xy 358.289352 -288.662872) (xy 358.314873 -288.66401) (xy 358.365129 -288.673178) (xy 358.413374 -288.689974)
			(xy 358.458458 -288.713996) (xy 358.499307 -288.744673) (xy 358.534946 -288.781272) (xy 358.564526 -288.822921)
			(xy 358.587342 -288.868628) (xy 358.602849 -288.917302) (xy 358.610679 -288.967783) (xy 358.61117 -288.993326)
			(xy 358.610659 -289.019292) (xy 358.602531 -289.070585) (xy 358.586481 -289.119975) (xy 358.562902 -289.166247)
			(xy 358.532375 -289.20826) (xy 358.495653 -289.244982) (xy 358.453638 -289.275507) (xy 358.407366 -289.299084)
			(xy 358.357975 -289.315134) (xy 358.306682 -289.32326) (xy 358.280716 -289.32378) (xy 358.256944 -289.323362)
			(xy 358.209892 -289.316541) (xy 358.164303 -289.303052) (xy 358.121114 -289.283173) (xy 358.081218 -289.257314)
			(xy 358.063038 -289.241992) (xy 358.057704 -289.23742) (xy 358.046621 -289.22755) (xy 358.020177 -289.214104)
			(xy 357.990985 -289.208825) (xy 357.961508 -289.212158) (xy 357.934232 -289.223822) (xy 357.911458 -289.242833)
			(xy 357.895109 -289.267586) (xy 357.886563 -289.295994) (xy 357.886 -289.310826) (xy 357.886 -291.646102)
			(xy 357.88727 -291.65169) (xy 357.89667 -291.69528) (xy 357.906723 -291.783886) (xy 357.907336 -291.828474)
			(xy 357.907336 -292.539166) (xy 357.908574 -292.553921) (xy 357.918452 -292.581821) (xy 357.935906 -292.605724)
			(xy 357.959474 -292.623627) (xy 357.987182 -292.634032) (xy 358.016709 -292.636066) (xy 358.045582 -292.62956)
			(xy 358.05872 -292.622732) (xy 358.080135 -292.611196) (xy 358.125264 -292.593047) (xy 358.172334 -292.580781)
			(xy 358.220581 -292.574598) (xy 358.244902 -292.574218) (xy 358.272151 -292.574704) (xy 358.326095 -292.582461)
			(xy 358.378386 -292.597815) (xy 358.427959 -292.620454) (xy 358.473806 -292.649919) (xy 358.514994 -292.685608)
			(xy 358.550682 -292.726795) (xy 358.580146 -292.772642) (xy 358.602786 -292.822216) (xy 358.61814 -292.874507)
			(xy 358.625896 -292.928451) (xy 358.625896 -292.982949) (xy 363.686604 -292.982949) (xy 363.686604 -292.928451)
			(xy 363.69436 -292.874507) (xy 363.709714 -292.822216) (xy 363.732354 -292.772642) (xy 363.761818 -292.726795)
			(xy 363.797506 -292.685608) (xy 363.838694 -292.649919) (xy 363.884541 -292.620454) (xy 363.934114 -292.597815)
			(xy 363.986405 -292.582461) (xy 364.040349 -292.574704) (xy 364.067598 -292.574218) (xy 364.094968 -292.574681)
			(xy 364.149148 -292.582499) (xy 364.201651 -292.597988) (xy 364.251398 -292.620831) (xy 364.297365 -292.650556)
			(xy 364.318296 -292.668198) (xy 364.329624 -292.677434) (xy 364.356181 -292.68961) (xy 364.385098 -292.693783)
			(xy 364.414015 -292.68961) (xy 364.440572 -292.677434) (xy 364.4519 -292.668198) (xy 364.472821 -292.650545)
			(xy 364.518797 -292.620835) (xy 364.568547 -292.598002) (xy 364.62105 -292.582514) (xy 364.675228 -292.57469)
			(xy 364.702598 -292.574218) (xy 364.729853 -292.574629) (xy 364.783808 -292.582386) (xy 364.836109 -292.597743)
			(xy 364.885693 -292.620387) (xy 364.93155 -292.649857) (xy 364.972746 -292.685553) (xy 365.008442 -292.726749)
			(xy 365.037912 -292.772605) (xy 365.060556 -292.822189) (xy 365.075914 -292.87449) (xy 365.083671 -292.928445)
			(xy 365.083671 -292.982955) (xy 365.075914 -293.03691) (xy 365.060556 -293.089211) (xy 365.037912 -293.138795)
			(xy 365.008442 -293.184651) (xy 364.972746 -293.225847) (xy 364.93155 -293.261543) (xy 364.885693 -293.291013)
			(xy 364.836109 -293.313657) (xy 364.783808 -293.329014) (xy 364.729853 -293.336771) (xy 364.702598 -293.337234)
			(xy 364.675227 -293.336785) (xy 364.621046 -293.328966) (xy 364.568543 -293.313473) (xy 364.518796 -293.290627)
			(xy 364.47283 -293.260898) (xy 364.4519 -293.243254) (xy 364.440572 -293.234018) (xy 364.414015 -293.221842)
			(xy 364.385098 -293.217669) (xy 364.356181 -293.221842) (xy 364.329624 -293.234018) (xy 364.318296 -293.243254)
			(xy 364.29737 -293.260901) (xy 364.251397 -293.290613) (xy 364.201647 -293.313449) (xy 364.149145 -293.328938)
			(xy 364.094968 -293.336762) (xy 364.067598 -293.337234) (xy 364.040349 -293.336696) (xy 363.986405 -293.328939)
			(xy 363.934114 -293.313585) (xy 363.884541 -293.290946) (xy 363.838694 -293.261481) (xy 363.797506 -293.225792)
			(xy 363.761818 -293.184605) (xy 363.732354 -293.138758) (xy 363.709714 -293.089184) (xy 363.69436 -293.036893)
			(xy 363.686604 -292.982949) (xy 358.625896 -292.982949) (xy 358.61814 -293.036893) (xy 358.602786 -293.089184)
			(xy 358.580146 -293.138758) (xy 358.550682 -293.184605) (xy 358.514994 -293.225792) (xy 358.473806 -293.261481)
			(xy 358.427959 -293.290946) (xy 358.378386 -293.313585) (xy 358.326095 -293.328939) (xy 358.272151 -293.336696)
			(xy 358.244902 -293.337234) (xy 358.220652 -293.336856) (xy 358.172545 -293.330706) (xy 358.125605 -293.318507)
			(xy 358.080591 -293.300454) (xy 358.059228 -293.288974) (xy 358.046078 -293.282074) (xy 358.017152 -293.275414)
			(xy 357.987531 -293.277337) (xy 357.959708 -293.287681) (xy 357.936026 -293.305576) (xy 357.918476 -293.329516)
			(xy 357.908537 -293.357486) (xy 357.907336 -293.372286) (xy 357.907336 -294.654732) (xy 357.908448 -294.668275)
			(xy 357.91691 -294.694086) (xy 357.931869 -294.71676) (xy 357.95227 -294.734695) (xy 357.976672 -294.746628)
			(xy 358.003354 -294.751716) (xy 358.030435 -294.7496) (xy 358.056004 -294.740431) (xy 358.067356 -294.732964)
			(xy 358.092243 -294.715114) (xy 358.146518 -294.686748) (xy 358.204629 -294.667422) (xy 358.265082 -294.657634)
			(xy 358.295702 -294.657018) (xy 358.322951 -294.657504) (xy 358.376895 -294.665261) (xy 358.429186 -294.680615)
			(xy 358.478759 -294.703254) (xy 358.524606 -294.732719) (xy 358.565794 -294.768408) (xy 358.601482 -294.809595)
			(xy 358.630946 -294.855442) (xy 358.653586 -294.905016) (xy 358.66894 -294.957307) (xy 358.676696 -295.011251)
			(xy 358.676696 -295.065749) (xy 363.572304 -295.065749) (xy 363.572304 -295.011251) (xy 363.58006 -294.957307)
			(xy 363.595414 -294.905016) (xy 363.618054 -294.855442) (xy 363.647518 -294.809595) (xy 363.683206 -294.768408)
			(xy 363.724394 -294.732719) (xy 363.770241 -294.703254) (xy 363.819814 -294.680615) (xy 363.872105 -294.665261)
			(xy 363.926049 -294.657504) (xy 363.953298 -294.657018) (xy 363.980668 -294.657481) (xy 364.034848 -294.665299)
			(xy 364.087351 -294.680788) (xy 364.137098 -294.703631) (xy 364.183065 -294.733356) (xy 364.203996 -294.750998)
			(xy 364.215324 -294.760234) (xy 364.241881 -294.77241) (xy 364.270798 -294.776583) (xy 364.299715 -294.77241)
			(xy 364.326272 -294.760234) (xy 364.3376 -294.750998) (xy 364.358521 -294.733345) (xy 364.404497 -294.703635)
			(xy 364.454247 -294.680802) (xy 364.50675 -294.665314) (xy 364.560928 -294.65749) (xy 364.588298 -294.657018)
			(xy 364.615553 -294.657429) (xy 364.669508 -294.665186) (xy 364.721809 -294.680543) (xy 364.771393 -294.703187)
			(xy 364.81725 -294.732657) (xy 364.858446 -294.768353) (xy 364.894142 -294.809549) (xy 364.923612 -294.855405)
			(xy 364.946256 -294.904989) (xy 364.961614 -294.95729) (xy 364.969371 -295.011245) (xy 364.969371 -295.038526)
			(xy 370.181376 -295.038526) (xy 370.185447 -294.982904) (xy 370.197573 -294.928467) (xy 370.217496 -294.876376)
			(xy 370.244792 -294.827741) (xy 370.278878 -294.783598) (xy 370.319027 -294.744889) (xy 370.364385 -294.712438)
			(xy 370.413985 -294.686937) (xy 370.466769 -294.66893) (xy 370.521612 -294.6588) (xy 370.577346 -294.656763)
			(xy 370.632783 -294.662863) (xy 370.68674 -294.676969) (xy 370.738069 -294.698781) (xy 370.785675 -294.727835)
			(xy 370.828543 -294.76351) (xy 370.86576 -294.805047) (xy 370.896533 -294.85156) (xy 370.920205 -294.902057)
			(xy 370.936273 -294.955464) (xy 370.944393 -295.01064) (xy 370.944902 -295.038526) (xy 370.944393 -295.066412)
			(xy 370.936273 -295.121588) (xy 370.920205 -295.174995) (xy 370.896533 -295.225492) (xy 370.86576 -295.272005)
			(xy 370.828543 -295.313542) (xy 370.785675 -295.349217) (xy 370.738069 -295.378271) (xy 370.68674 -295.400083)
			(xy 370.632783 -295.414189) (xy 370.577346 -295.420289) (xy 370.521612 -295.418252) (xy 370.466769 -295.408122)
			(xy 370.413985 -295.390115) (xy 370.364385 -295.364614) (xy 370.319027 -295.332163) (xy 370.278878 -295.293454)
			(xy 370.244792 -295.249311) (xy 370.217496 -295.200676) (xy 370.197573 -295.148585) (xy 370.185447 -295.094148)
			(xy 370.181376 -295.038526) (xy 364.969371 -295.038526) (xy 364.969371 -295.065755) (xy 364.961614 -295.11971)
			(xy 364.946256 -295.172011) (xy 364.923612 -295.221595) (xy 364.894142 -295.267451) (xy 364.858446 -295.308647)
			(xy 364.81725 -295.344343) (xy 364.771393 -295.373813) (xy 364.721809 -295.396457) (xy 364.669508 -295.411814)
			(xy 364.615553 -295.419571) (xy 364.588298 -295.420034) (xy 364.560927 -295.419585) (xy 364.506746 -295.411766)
			(xy 364.454243 -295.396273) (xy 364.404496 -295.373427) (xy 364.35853 -295.343698) (xy 364.3376 -295.326054)
			(xy 364.326272 -295.316818) (xy 364.299715 -295.304642) (xy 364.270798 -295.300469) (xy 364.241881 -295.304642)
			(xy 364.215324 -295.316818) (xy 364.203996 -295.326054) (xy 364.18307 -295.343701) (xy 364.137097 -295.373413)
			(xy 364.087347 -295.396249) (xy 364.034845 -295.411738) (xy 363.980668 -295.419562) (xy 363.953298 -295.420034)
			(xy 363.926049 -295.419496) (xy 363.872105 -295.411739) (xy 363.819814 -295.396385) (xy 363.770241 -295.373746)
			(xy 363.724394 -295.344281) (xy 363.683206 -295.308592) (xy 363.647518 -295.267405) (xy 363.618054 -295.221558)
			(xy 363.595414 -295.171984) (xy 363.58006 -295.119693) (xy 363.572304 -295.065749) (xy 358.676696 -295.065749)
			(xy 358.66894 -295.119693) (xy 358.653586 -295.171984) (xy 358.630946 -295.221558) (xy 358.601482 -295.267405)
			(xy 358.565794 -295.308592) (xy 358.524606 -295.344281) (xy 358.478759 -295.373746) (xy 358.429186 -295.396385)
			(xy 358.376895 -295.411739) (xy 358.322951 -295.419496) (xy 358.295702 -295.420034) (xy 358.265082 -295.419424)
			(xy 358.204628 -295.409635) (xy 358.146517 -295.390307) (xy 358.092243 -295.361938) (xy 358.067356 -295.344088)
			(xy 358.055986 -295.336634) (xy 358.030412 -295.327436) (xy 358.003318 -295.3253) (xy 357.976618 -295.330377)
			(xy 357.952199 -295.342308) (xy 357.931786 -295.360251) (xy 357.91682 -295.382938) (xy 357.90836 -295.408765)
			(xy 357.907336 -295.42232) (xy 357.907336 -296.813732) (xy 357.908448 -296.827275) (xy 357.91691 -296.853086)
			(xy 357.931869 -296.87576) (xy 357.95227 -296.893695) (xy 357.976672 -296.905628) (xy 358.003354 -296.910716)
			(xy 358.030435 -296.9086) (xy 358.056004 -296.899431) (xy 358.067356 -296.891964) (xy 358.092243 -296.874114)
			(xy 358.146518 -296.845748) (xy 358.204629 -296.826422) (xy 358.265082 -296.816634) (xy 358.295702 -296.816018)
			(xy 358.322951 -296.816504) (xy 358.376895 -296.824261) (xy 358.429186 -296.839615) (xy 358.478759 -296.862254)
			(xy 358.524606 -296.891719) (xy 358.565794 -296.927408) (xy 358.601482 -296.968595) (xy 358.630946 -297.014442)
			(xy 358.653586 -297.064016) (xy 358.66894 -297.116307) (xy 358.676696 -297.170251) (xy 358.676696 -297.224749)
			(xy 363.572304 -297.224749) (xy 363.572304 -297.170251) (xy 363.58006 -297.116307) (xy 363.595414 -297.064016)
			(xy 363.618054 -297.014442) (xy 363.647518 -296.968595) (xy 363.683206 -296.927408) (xy 363.724394 -296.891719)
			(xy 363.770241 -296.862254) (xy 363.819814 -296.839615) (xy 363.872105 -296.824261) (xy 363.926049 -296.816504)
			(xy 363.953298 -296.816018) (xy 363.980668 -296.816481) (xy 364.034848 -296.824299) (xy 364.087351 -296.839788)
			(xy 364.137098 -296.862631) (xy 364.183065 -296.892356) (xy 364.203996 -296.909998) (xy 364.215324 -296.919234)
			(xy 364.241881 -296.93141) (xy 364.270798 -296.935583) (xy 364.299715 -296.93141) (xy 364.326272 -296.919234)
			(xy 364.3376 -296.909998) (xy 364.358521 -296.892345) (xy 364.404497 -296.862635) (xy 364.454247 -296.839802)
			(xy 364.50675 -296.824314) (xy 364.560928 -296.81649) (xy 364.588298 -296.816018) (xy 364.615553 -296.816429)
			(xy 364.669508 -296.824186) (xy 364.721809 -296.839543) (xy 364.771393 -296.862187) (xy 364.81725 -296.891657)
			(xy 364.858446 -296.927353) (xy 364.894142 -296.968549) (xy 364.923612 -297.014405) (xy 364.946256 -297.063989)
			(xy 364.961614 -297.11629) (xy 364.969371 -297.170245) (xy 364.969371 -297.197526) (xy 370.181376 -297.197526)
			(xy 370.185447 -297.141904) (xy 370.197573 -297.087467) (xy 370.217496 -297.035376) (xy 370.244792 -296.986741)
			(xy 370.278878 -296.942598) (xy 370.319027 -296.903889) (xy 370.364385 -296.871438) (xy 370.413985 -296.845937)
			(xy 370.466769 -296.82793) (xy 370.521612 -296.8178) (xy 370.577346 -296.815763) (xy 370.632783 -296.821863)
			(xy 370.68674 -296.835969) (xy 370.738069 -296.857781) (xy 370.785675 -296.886835) (xy 370.828543 -296.92251)
			(xy 370.86576 -296.964047) (xy 370.896533 -297.01056) (xy 370.920205 -297.061057) (xy 370.936273 -297.114464)
			(xy 370.944393 -297.16964) (xy 370.944902 -297.197526) (xy 370.944393 -297.225412) (xy 370.936273 -297.280588)
			(xy 370.920205 -297.333995) (xy 370.896533 -297.384492) (xy 370.86576 -297.431005) (xy 370.828543 -297.472542)
			(xy 370.785675 -297.508217) (xy 370.738069 -297.537271) (xy 370.68674 -297.559083) (xy 370.632783 -297.573189)
			(xy 370.577346 -297.579289) (xy 370.521612 -297.577252) (xy 370.466769 -297.567122) (xy 370.413985 -297.549115)
			(xy 370.364385 -297.523614) (xy 370.319027 -297.491163) (xy 370.278878 -297.452454) (xy 370.244792 -297.408311)
			(xy 370.217496 -297.359676) (xy 370.197573 -297.307585) (xy 370.185447 -297.253148) (xy 370.181376 -297.197526)
			(xy 364.969371 -297.197526) (xy 364.969371 -297.224755) (xy 364.961614 -297.27871) (xy 364.946256 -297.331011)
			(xy 364.923612 -297.380595) (xy 364.894142 -297.426451) (xy 364.858446 -297.467647) (xy 364.81725 -297.503343)
			(xy 364.771393 -297.532813) (xy 364.721809 -297.555457) (xy 364.669508 -297.570814) (xy 364.615553 -297.578571)
			(xy 364.588298 -297.579034) (xy 364.560927 -297.578585) (xy 364.506746 -297.570766) (xy 364.454243 -297.555273)
			(xy 364.404496 -297.532427) (xy 364.35853 -297.502698) (xy 364.3376 -297.485054) (xy 364.326272 -297.475818)
			(xy 364.299715 -297.463642) (xy 364.270798 -297.459469) (xy 364.241881 -297.463642) (xy 364.215324 -297.475818)
			(xy 364.203996 -297.485054) (xy 364.18307 -297.502701) (xy 364.137097 -297.532413) (xy 364.087347 -297.555249)
			(xy 364.034845 -297.570738) (xy 363.980668 -297.578562) (xy 363.953298 -297.579034) (xy 363.926049 -297.578496)
			(xy 363.872105 -297.570739) (xy 363.819814 -297.555385) (xy 363.770241 -297.532746) (xy 363.724394 -297.503281)
			(xy 363.683206 -297.467592) (xy 363.647518 -297.426405) (xy 363.618054 -297.380558) (xy 363.595414 -297.330984)
			(xy 363.58006 -297.278693) (xy 363.572304 -297.224749) (xy 358.676696 -297.224749) (xy 358.66894 -297.278693)
			(xy 358.653586 -297.330984) (xy 358.630946 -297.380558) (xy 358.601482 -297.426405) (xy 358.565794 -297.467592)
			(xy 358.524606 -297.503281) (xy 358.478759 -297.532746) (xy 358.429186 -297.555385) (xy 358.376895 -297.570739)
			(xy 358.322951 -297.578496) (xy 358.295702 -297.579034) (xy 358.265082 -297.578424) (xy 358.204628 -297.568635)
			(xy 358.146517 -297.549307) (xy 358.092243 -297.520938) (xy 358.067356 -297.503088) (xy 358.055986 -297.495634)
			(xy 358.030412 -297.486436) (xy 358.003318 -297.4843) (xy 357.976618 -297.489377) (xy 357.952199 -297.501308)
			(xy 357.931786 -297.519251) (xy 357.91682 -297.541938) (xy 357.90836 -297.567765) (xy 357.907336 -297.58132)
			(xy 357.907336 -298.123356) (xy 357.906744 -298.167945) (xy 357.896692 -298.256554) (xy 357.88727 -298.30014)
			(xy 357.886 -298.305728) (xy 357.886 -299.303948) (xy 346.274136 -310.915812) (xy 341.700866 -312.695082)
			(xy 338.68621 -315.709738) (xy 345.576648 -315.709738) (xy 345.576648 -315.625042) (xy 345.584699 -315.540728)
			(xy 345.600728 -315.457562) (xy 345.624589 -315.376295) (xy 345.656068 -315.297665) (xy 345.694879 -315.222384)
			(xy 345.740669 -315.151132) (xy 345.793025 -315.084556) (xy 345.851473 -315.023258) (xy 345.915483 -314.967793)
			(xy 345.984475 -314.918664) (xy 346.057825 -314.876315) (xy 346.134868 -314.841131) (xy 346.214907 -314.813429)
			(xy 346.297216 -314.793461) (xy 346.381051 -314.781408) (xy 346.465652 -314.777378) (xy 346.550253 -314.781408)
			(xy 346.634088 -314.793461) (xy 346.716397 -314.813429) (xy 346.796436 -314.841131) (xy 346.873479 -314.876315)
			(xy 346.946829 -314.918664) (xy 347.015821 -314.967793) (xy 347.079831 -315.023258) (xy 347.138279 -315.084556)
			(xy 347.190635 -315.151132) (xy 347.236425 -315.222384) (xy 347.275236 -315.297665) (xy 347.306715 -315.376295)
			(xy 347.330576 -315.457562) (xy 347.346605 -315.540728) (xy 347.354656 -315.625042) (xy 347.35516 -315.66739)
			(xy 347.550237 -315.66739) (xy 347.554259 -315.58167) (xy 347.56629 -315.496702) (xy 347.586226 -315.413235)
			(xy 347.613889 -315.332001) (xy 347.649038 -315.253715) (xy 347.691364 -315.179064) (xy 347.740493 -315.108705)
			(xy 347.795996 -315.043255) (xy 347.857383 -314.983291) (xy 347.924116 -314.929338) (xy 347.995608 -314.881871)
			(xy 348.07123 -314.841307) (xy 348.150319 -314.808003) (xy 348.232179 -314.782251) (xy 348.31609 -314.764278)
			(xy 348.401316 -314.754242) (xy 348.487108 -314.75223) (xy 348.57271 -314.758261) (xy 348.657372 -314.772281)
			(xy 348.740349 -314.794167) (xy 348.820912 -314.823728) (xy 348.898352 -314.860702) (xy 348.971991 -314.904766)
			(xy 349.041179 -314.955532) (xy 349.10531 -315.012553) (xy 349.163819 -315.075329) (xy 349.216192 -315.143309)
			(xy 349.26197 -315.215894) (xy 349.30075 -315.292446) (xy 349.332191 -315.372294) (xy 349.356017 -315.454735)
			(xy 349.372018 -315.539045) (xy 349.380053 -315.624483) (xy 349.380556 -315.66739) (xy 349.38006 -315.709738)
			(xy 351.774248 -315.709738) (xy 351.774248 -315.625042) (xy 351.782299 -315.540728) (xy 351.798328 -315.457562)
			(xy 351.822189 -315.376295) (xy 351.853668 -315.297665) (xy 351.892479 -315.222384) (xy 351.938269 -315.151132)
			(xy 351.990625 -315.084556) (xy 352.049073 -315.023258) (xy 352.113083 -314.967793) (xy 352.182075 -314.918664)
			(xy 352.255425 -314.876315) (xy 352.332468 -314.841131) (xy 352.412507 -314.813429) (xy 352.494816 -314.793461)
			(xy 352.578651 -314.781408) (xy 352.663252 -314.777378) (xy 352.747853 -314.781408) (xy 352.831688 -314.793461)
			(xy 352.913997 -314.813429) (xy 352.994036 -314.841131) (xy 353.071079 -314.876315) (xy 353.144429 -314.918664)
			(xy 353.213421 -314.967793) (xy 353.277431 -315.023258) (xy 353.335879 -315.084556) (xy 353.388235 -315.151132)
			(xy 353.434025 -315.222384) (xy 353.472836 -315.297665) (xy 353.504315 -315.376295) (xy 353.528176 -315.457562)
			(xy 353.544205 -315.540728) (xy 353.552256 -315.625042) (xy 353.55276 -315.66739) (xy 353.747837 -315.66739)
			(xy 353.751859 -315.58167) (xy 353.76389 -315.496702) (xy 353.783826 -315.413235) (xy 353.811489 -315.332001)
			(xy 353.846638 -315.253715) (xy 353.888964 -315.179064) (xy 353.938093 -315.108705) (xy 353.993596 -315.043255)
			(xy 354.054983 -314.983291) (xy 354.121716 -314.929338) (xy 354.193208 -314.881871) (xy 354.26883 -314.841307)
			(xy 354.347919 -314.808003) (xy 354.429779 -314.782251) (xy 354.51369 -314.764278) (xy 354.598916 -314.754242)
			(xy 354.684708 -314.75223) (xy 354.77031 -314.758261) (xy 354.854972 -314.772281) (xy 354.937949 -314.794167)
			(xy 355.018512 -314.823728) (xy 355.095952 -314.860702) (xy 355.169591 -314.904766) (xy 355.238779 -314.955532)
			(xy 355.30291 -315.012553) (xy 355.361419 -315.075329) (xy 355.413792 -315.143309) (xy 355.45957 -315.215894)
			(xy 355.49835 -315.292446) (xy 355.529791 -315.372294) (xy 355.553617 -315.454735) (xy 355.569618 -315.539045)
			(xy 355.577653 -315.624483) (xy 355.578156 -315.66739) (xy 355.57766 -315.709738) (xy 357.952036 -315.709738)
			(xy 357.952036 -315.625042) (xy 357.960087 -315.540728) (xy 357.976116 -315.457562) (xy 357.999977 -315.376295)
			(xy 358.031456 -315.297665) (xy 358.070267 -315.222384) (xy 358.116057 -315.151132) (xy 358.168413 -315.084556)
			(xy 358.226861 -315.023258) (xy 358.290871 -314.967793) (xy 358.359863 -314.918664) (xy 358.433213 -314.876315)
			(xy 358.510256 -314.841131) (xy 358.590295 -314.813429) (xy 358.672604 -314.793461) (xy 358.756439 -314.781408)
			(xy 358.84104 -314.777378) (xy 358.925641 -314.781408) (xy 359.009476 -314.793461) (xy 359.091785 -314.813429)
			(xy 359.171824 -314.841131) (xy 359.248867 -314.876315) (xy 359.322217 -314.918664) (xy 359.391209 -314.967793)
			(xy 359.455219 -315.023258) (xy 359.513667 -315.084556) (xy 359.566023 -315.151132) (xy 359.611813 -315.222384)
			(xy 359.650624 -315.297665) (xy 359.682103 -315.376295) (xy 359.705964 -315.457562) (xy 359.721993 -315.540728)
			(xy 359.730044 -315.625042) (xy 359.730548 -315.66739) (xy 359.925625 -315.66739) (xy 359.929647 -315.58167)
			(xy 359.941678 -315.496702) (xy 359.961614 -315.413235) (xy 359.989277 -315.332001) (xy 360.024426 -315.253715)
			(xy 360.066752 -315.179064) (xy 360.115881 -315.108705) (xy 360.171384 -315.043255) (xy 360.232771 -314.983291)
			(xy 360.299504 -314.929338) (xy 360.370996 -314.881871) (xy 360.446618 -314.841307) (xy 360.525707 -314.808003)
			(xy 360.607567 -314.782251) (xy 360.691478 -314.764278) (xy 360.776704 -314.754242) (xy 360.862496 -314.75223)
			(xy 360.948098 -314.758261) (xy 361.03276 -314.772281) (xy 361.115737 -314.794167) (xy 361.1963 -314.823728)
			(xy 361.27374 -314.860702) (xy 361.347379 -314.904766) (xy 361.416567 -314.955532) (xy 361.480698 -315.012553)
			(xy 361.539207 -315.075329) (xy 361.59158 -315.143309) (xy 361.637358 -315.215894) (xy 361.676138 -315.292446)
			(xy 361.707579 -315.372294) (xy 361.731405 -315.454735) (xy 361.747406 -315.539045) (xy 361.755441 -315.624483)
			(xy 361.755944 -315.66739) (xy 361.755448 -315.709738) (xy 364.149636 -315.709738) (xy 364.149636 -315.625042)
			(xy 364.157687 -315.540728) (xy 364.173716 -315.457562) (xy 364.197577 -315.376295) (xy 364.229056 -315.297665)
			(xy 364.267867 -315.222384) (xy 364.313657 -315.151132) (xy 364.366013 -315.084556) (xy 364.424461 -315.023258)
			(xy 364.488471 -314.967793) (xy 364.557463 -314.918664) (xy 364.630813 -314.876315) (xy 364.707856 -314.841131)
			(xy 364.787895 -314.813429) (xy 364.870204 -314.793461) (xy 364.954039 -314.781408) (xy 365.03864 -314.777378)
			(xy 365.123241 -314.781408) (xy 365.207076 -314.793461) (xy 365.289385 -314.813429) (xy 365.369424 -314.841131)
			(xy 365.446467 -314.876315) (xy 365.519817 -314.918664) (xy 365.588809 -314.967793) (xy 365.652819 -315.023258)
			(xy 365.711267 -315.084556) (xy 365.763623 -315.151132) (xy 365.809413 -315.222384) (xy 365.848224 -315.297665)
			(xy 365.879703 -315.376295) (xy 365.903564 -315.457562) (xy 365.919593 -315.540728) (xy 365.927644 -315.625042)
			(xy 365.928148 -315.66739) (xy 366.123225 -315.66739) (xy 366.127247 -315.58167) (xy 366.139278 -315.496702)
			(xy 366.159214 -315.413235) (xy 366.186877 -315.332001) (xy 366.222026 -315.253715) (xy 366.264352 -315.179064)
			(xy 366.313481 -315.108705) (xy 366.368984 -315.043255) (xy 366.430371 -314.983291) (xy 366.497104 -314.929338)
			(xy 366.568596 -314.881871) (xy 366.644218 -314.841307) (xy 366.723307 -314.808003) (xy 366.805167 -314.782251)
			(xy 366.889078 -314.764278) (xy 366.974304 -314.754242) (xy 367.060096 -314.75223) (xy 367.145698 -314.758261)
			(xy 367.23036 -314.772281) (xy 367.313337 -314.794167) (xy 367.3939 -314.823728) (xy 367.47134 -314.860702)
			(xy 367.544979 -314.904766) (xy 367.614167 -314.955532) (xy 367.678298 -315.012553) (xy 367.736807 -315.075329)
			(xy 367.78918 -315.143309) (xy 367.834958 -315.215894) (xy 367.873738 -315.292446) (xy 367.905179 -315.372294)
			(xy 367.929005 -315.454735) (xy 367.945006 -315.539045) (xy 367.953041 -315.624483) (xy 367.953544 -315.66739)
			(xy 367.953048 -315.709738) (xy 370.347236 -315.709738) (xy 370.347236 -315.625042) (xy 370.355287 -315.540728)
			(xy 370.371316 -315.457562) (xy 370.395177 -315.376295) (xy 370.426656 -315.297665) (xy 370.465467 -315.222384)
			(xy 370.511257 -315.151132) (xy 370.563613 -315.084556) (xy 370.622061 -315.023258) (xy 370.686071 -314.967793)
			(xy 370.755063 -314.918664) (xy 370.828413 -314.876315) (xy 370.905456 -314.841131) (xy 370.985495 -314.813429)
			(xy 371.067804 -314.793461) (xy 371.151639 -314.781408) (xy 371.23624 -314.777378) (xy 371.320841 -314.781408)
			(xy 371.404676 -314.793461) (xy 371.486985 -314.813429) (xy 371.567024 -314.841131) (xy 371.644067 -314.876315)
			(xy 371.717417 -314.918664) (xy 371.786409 -314.967793) (xy 371.850419 -315.023258) (xy 371.908867 -315.084556)
			(xy 371.961223 -315.151132) (xy 372.007013 -315.222384) (xy 372.045824 -315.297665) (xy 372.077303 -315.376295)
			(xy 372.101164 -315.457562) (xy 372.117193 -315.540728) (xy 372.125244 -315.625042) (xy 372.125748 -315.66739)
			(xy 372.320825 -315.66739) (xy 372.324847 -315.58167) (xy 372.336878 -315.496702) (xy 372.356814 -315.413235)
			(xy 372.384477 -315.332001) (xy 372.419626 -315.253715) (xy 372.461952 -315.179064) (xy 372.511081 -315.108705)
			(xy 372.566584 -315.043255) (xy 372.627971 -314.983291) (xy 372.694704 -314.929338) (xy 372.766196 -314.881871)
			(xy 372.841818 -314.841307) (xy 372.920907 -314.808003) (xy 373.002767 -314.782251) (xy 373.086678 -314.764278)
			(xy 373.171904 -314.754242) (xy 373.257696 -314.75223) (xy 373.343298 -314.758261) (xy 373.42796 -314.772281)
			(xy 373.510937 -314.794167) (xy 373.5915 -314.823728) (xy 373.66894 -314.860702) (xy 373.742579 -314.904766)
			(xy 373.811767 -314.955532) (xy 373.875898 -315.012553) (xy 373.934407 -315.075329) (xy 373.98678 -315.143309)
			(xy 374.032558 -315.215894) (xy 374.071338 -315.292446) (xy 374.102779 -315.372294) (xy 374.126605 -315.454735)
			(xy 374.142606 -315.539045) (xy 374.150641 -315.624483) (xy 374.151144 -315.66739) (xy 374.150641 -315.710297)
			(xy 374.142606 -315.795735) (xy 374.126605 -315.880045) (xy 374.102779 -315.962486) (xy 374.071338 -316.042334)
			(xy 374.032558 -316.118886) (xy 373.98678 -316.191471) (xy 373.934407 -316.259451) (xy 373.875898 -316.322227)
			(xy 373.811767 -316.379248) (xy 373.742579 -316.430014) (xy 373.66894 -316.474078) (xy 373.5915 -316.511052)
			(xy 373.510937 -316.540613) (xy 373.42796 -316.562499) (xy 373.343298 -316.576519) (xy 373.257696 -316.58255)
			(xy 373.171904 -316.580538) (xy 373.086678 -316.570502) (xy 373.002767 -316.552529) (xy 372.920907 -316.526777)
			(xy 372.841818 -316.493473) (xy 372.766196 -316.452909) (xy 372.694704 -316.405442) (xy 372.627971 -316.351489)
			(xy 372.566584 -316.291525) (xy 372.511081 -316.226075) (xy 372.461952 -316.155716) (xy 372.419626 -316.081065)
			(xy 372.384477 -316.002779) (xy 372.356814 -315.921545) (xy 372.336878 -315.838078) (xy 372.324847 -315.75311)
			(xy 372.320825 -315.66739) (xy 372.125748 -315.66739) (xy 372.125244 -315.709738) (xy 372.117193 -315.794052)
			(xy 372.101164 -315.877218) (xy 372.077303 -315.958485) (xy 372.045824 -316.037115) (xy 372.007013 -316.112396)
			(xy 371.961223 -316.183648) (xy 371.908867 -316.250224) (xy 371.850419 -316.311522) (xy 371.786409 -316.366987)
			(xy 371.717417 -316.416116) (xy 371.644067 -316.458465) (xy 371.567024 -316.493649) (xy 371.486985 -316.521351)
			(xy 371.404676 -316.541319) (xy 371.320841 -316.553372) (xy 371.23624 -316.557403) (xy 371.151639 -316.553372)
			(xy 371.067804 -316.541319) (xy 370.985495 -316.521351) (xy 370.905456 -316.493649) (xy 370.828413 -316.458465)
			(xy 370.755063 -316.416116) (xy 370.686071 -316.366987) (xy 370.622061 -316.311522) (xy 370.563613 -316.250224)
			(xy 370.511257 -316.183648) (xy 370.465467 -316.112396) (xy 370.426656 -316.037115) (xy 370.395177 -315.958485)
			(xy 370.371316 -315.877218) (xy 370.355287 -315.794052) (xy 370.347236 -315.709738) (xy 367.953048 -315.709738)
			(xy 367.953041 -315.710297) (xy 367.945006 -315.795735) (xy 367.929005 -315.880045) (xy 367.905179 -315.962486)
			(xy 367.873738 -316.042334) (xy 367.834958 -316.118886) (xy 367.78918 -316.191471) (xy 367.736807 -316.259451)
			(xy 367.678298 -316.322227) (xy 367.614167 -316.379248) (xy 367.544979 -316.430014) (xy 367.47134 -316.474078)
			(xy 367.3939 -316.511052) (xy 367.313337 -316.540613) (xy 367.23036 -316.562499) (xy 367.145698 -316.576519)
			(xy 367.060096 -316.58255) (xy 366.974304 -316.580538) (xy 366.889078 -316.570502) (xy 366.805167 -316.552529)
			(xy 366.723307 -316.526777) (xy 366.644218 -316.493473) (xy 366.568596 -316.452909) (xy 366.497104 -316.405442)
			(xy 366.430371 -316.351489) (xy 366.368984 -316.291525) (xy 366.313481 -316.226075) (xy 366.264352 -316.155716)
			(xy 366.222026 -316.081065) (xy 366.186877 -316.002779) (xy 366.159214 -315.921545) (xy 366.139278 -315.838078)
			(xy 366.127247 -315.75311) (xy 366.123225 -315.66739) (xy 365.928148 -315.66739) (xy 365.927644 -315.709738)
			(xy 365.919593 -315.794052) (xy 365.903564 -315.877218) (xy 365.879703 -315.958485) (xy 365.848224 -316.037115)
			(xy 365.809413 -316.112396) (xy 365.763623 -316.183648) (xy 365.711267 -316.250224) (xy 365.652819 -316.311522)
			(xy 365.588809 -316.366987) (xy 365.519817 -316.416116) (xy 365.446467 -316.458465) (xy 365.369424 -316.493649)
			(xy 365.289385 -316.521351) (xy 365.207076 -316.541319) (xy 365.123241 -316.553372) (xy 365.03864 -316.557403)
			(xy 364.954039 -316.553372) (xy 364.870204 -316.541319) (xy 364.787895 -316.521351) (xy 364.707856 -316.493649)
			(xy 364.630813 -316.458465) (xy 364.557463 -316.416116) (xy 364.488471 -316.366987) (xy 364.424461 -316.311522)
			(xy 364.366013 -316.250224) (xy 364.313657 -316.183648) (xy 364.267867 -316.112396) (xy 364.229056 -316.037115)
			(xy 364.197577 -315.958485) (xy 364.173716 -315.877218) (xy 364.157687 -315.794052) (xy 364.149636 -315.709738)
			(xy 361.755448 -315.709738) (xy 361.755441 -315.710297) (xy 361.747406 -315.795735) (xy 361.731405 -315.880045)
			(xy 361.707579 -315.962486) (xy 361.676138 -316.042334) (xy 361.637358 -316.118886) (xy 361.59158 -316.191471)
			(xy 361.539207 -316.259451) (xy 361.480698 -316.322227) (xy 361.416567 -316.379248) (xy 361.347379 -316.430014)
			(xy 361.27374 -316.474078) (xy 361.1963 -316.511052) (xy 361.115737 -316.540613) (xy 361.03276 -316.562499)
			(xy 360.948098 -316.576519) (xy 360.862496 -316.58255) (xy 360.776704 -316.580538) (xy 360.691478 -316.570502)
			(xy 360.607567 -316.552529) (xy 360.525707 -316.526777) (xy 360.446618 -316.493473) (xy 360.370996 -316.452909)
			(xy 360.299504 -316.405442) (xy 360.232771 -316.351489) (xy 360.171384 -316.291525) (xy 360.115881 -316.226075)
			(xy 360.066752 -316.155716) (xy 360.024426 -316.081065) (xy 359.989277 -316.002779) (xy 359.961614 -315.921545)
			(xy 359.941678 -315.838078) (xy 359.929647 -315.75311) (xy 359.925625 -315.66739) (xy 359.730548 -315.66739)
			(xy 359.730044 -315.709738) (xy 359.721993 -315.794052) (xy 359.705964 -315.877218) (xy 359.682103 -315.958485)
			(xy 359.650624 -316.037115) (xy 359.611813 -316.112396) (xy 359.566023 -316.183648) (xy 359.513667 -316.250224)
			(xy 359.455219 -316.311522) (xy 359.391209 -316.366987) (xy 359.322217 -316.416116) (xy 359.248867 -316.458465)
			(xy 359.171824 -316.493649) (xy 359.091785 -316.521351) (xy 359.009476 -316.541319) (xy 358.925641 -316.553372)
			(xy 358.84104 -316.557403) (xy 358.756439 -316.553372) (xy 358.672604 -316.541319) (xy 358.590295 -316.521351)
			(xy 358.510256 -316.493649) (xy 358.433213 -316.458465) (xy 358.359863 -316.416116) (xy 358.290871 -316.366987)
			(xy 358.226861 -316.311522) (xy 358.168413 -316.250224) (xy 358.116057 -316.183648) (xy 358.070267 -316.112396)
			(xy 358.031456 -316.037115) (xy 357.999977 -315.958485) (xy 357.976116 -315.877218) (xy 357.960087 -315.794052)
			(xy 357.952036 -315.709738) (xy 355.57766 -315.709738) (xy 355.577653 -315.710297) (xy 355.569618 -315.795735)
			(xy 355.553617 -315.880045) (xy 355.529791 -315.962486) (xy 355.49835 -316.042334) (xy 355.45957 -316.118886)
			(xy 355.413792 -316.191471) (xy 355.361419 -316.259451) (xy 355.30291 -316.322227) (xy 355.238779 -316.379248)
			(xy 355.169591 -316.430014) (xy 355.095952 -316.474078) (xy 355.018512 -316.511052) (xy 354.937949 -316.540613)
			(xy 354.854972 -316.562499) (xy 354.77031 -316.576519) (xy 354.684708 -316.58255) (xy 354.598916 -316.580538)
			(xy 354.51369 -316.570502) (xy 354.429779 -316.552529) (xy 354.347919 -316.526777) (xy 354.26883 -316.493473)
			(xy 354.193208 -316.452909) (xy 354.121716 -316.405442) (xy 354.054983 -316.351489) (xy 353.993596 -316.291525)
			(xy 353.938093 -316.226075) (xy 353.888964 -316.155716) (xy 353.846638 -316.081065) (xy 353.811489 -316.002779)
			(xy 353.783826 -315.921545) (xy 353.76389 -315.838078) (xy 353.751859 -315.75311) (xy 353.747837 -315.66739)
			(xy 353.55276 -315.66739) (xy 353.552256 -315.709738) (xy 353.544205 -315.794052) (xy 353.528176 -315.877218)
			(xy 353.504315 -315.958485) (xy 353.472836 -316.037115) (xy 353.434025 -316.112396) (xy 353.388235 -316.183648)
			(xy 353.335879 -316.250224) (xy 353.277431 -316.311522) (xy 353.213421 -316.366987) (xy 353.144429 -316.416116)
			(xy 353.071079 -316.458465) (xy 352.994036 -316.493649) (xy 352.913997 -316.521351) (xy 352.831688 -316.541319)
			(xy 352.747853 -316.553372) (xy 352.663252 -316.557403) (xy 352.578651 -316.553372) (xy 352.494816 -316.541319)
			(xy 352.412507 -316.521351) (xy 352.332468 -316.493649) (xy 352.255425 -316.458465) (xy 352.182075 -316.416116)
			(xy 352.113083 -316.366987) (xy 352.049073 -316.311522) (xy 351.990625 -316.250224) (xy 351.938269 -316.183648)
			(xy 351.892479 -316.112396) (xy 351.853668 -316.037115) (xy 351.822189 -315.958485) (xy 351.798328 -315.877218)
			(xy 351.782299 -315.794052) (xy 351.774248 -315.709738) (xy 349.38006 -315.709738) (xy 349.380053 -315.710297)
			(xy 349.372018 -315.795735) (xy 349.356017 -315.880045) (xy 349.332191 -315.962486) (xy 349.30075 -316.042334)
			(xy 349.26197 -316.118886) (xy 349.216192 -316.191471) (xy 349.163819 -316.259451) (xy 349.10531 -316.322227)
			(xy 349.041179 -316.379248) (xy 348.971991 -316.430014) (xy 348.898352 -316.474078) (xy 348.820912 -316.511052)
			(xy 348.740349 -316.540613) (xy 348.657372 -316.562499) (xy 348.57271 -316.576519) (xy 348.487108 -316.58255)
			(xy 348.401316 -316.580538) (xy 348.31609 -316.570502) (xy 348.232179 -316.552529) (xy 348.150319 -316.526777)
			(xy 348.07123 -316.493473) (xy 347.995608 -316.452909) (xy 347.924116 -316.405442) (xy 347.857383 -316.351489)
			(xy 347.795996 -316.291525) (xy 347.740493 -316.226075) (xy 347.691364 -316.155716) (xy 347.649038 -316.081065)
			(xy 347.613889 -316.002779) (xy 347.586226 -315.921545) (xy 347.56629 -315.838078) (xy 347.554259 -315.75311)
			(xy 347.550237 -315.66739) (xy 347.35516 -315.66739) (xy 347.354656 -315.709738) (xy 347.346605 -315.794052)
			(xy 347.330576 -315.877218) (xy 347.306715 -315.958485) (xy 347.275236 -316.037115) (xy 347.236425 -316.112396)
			(xy 347.190635 -316.183648) (xy 347.138279 -316.250224) (xy 347.079831 -316.311522) (xy 347.015821 -316.366987)
			(xy 346.946829 -316.416116) (xy 346.873479 -316.458465) (xy 346.796436 -316.493649) (xy 346.716397 -316.521351)
			(xy 346.634088 -316.541319) (xy 346.550253 -316.553372) (xy 346.465652 -316.557403) (xy 346.381051 -316.553372)
			(xy 346.297216 -316.541319) (xy 346.214907 -316.521351) (xy 346.134868 -316.493649) (xy 346.057825 -316.458465)
			(xy 345.984475 -316.416116) (xy 345.915483 -316.366987) (xy 345.851473 -316.311522) (xy 345.793025 -316.250224)
			(xy 345.740669 -316.183648) (xy 345.694879 -316.112396) (xy 345.656068 -316.037115) (xy 345.624589 -315.958485)
			(xy 345.600728 -315.877218) (xy 345.584699 -315.794052) (xy 345.576648 -315.709738) (xy 338.68621 -315.709738)
			(xy 324.485 -329.910948) (xy 324.485 -332.247748) (xy 325.0438 -332.806548) (xy 336.042 -332.806548)
		)
		(stroke
			(width 0)
			(type solid)
		)
		(fill yes)
		(layer "In11.Cu")
		(net "PVCCIN_CPU0")
	)
	(gr_poly
		(pts
			(xy 224.03308 -59.787028) (xy 224.03308 -44.290488) (xy 223.233996 -43.491404) (xy 223.223375 -43.481557)
			(xy 223.197948 -43.467719) (xy 223.16966 -43.461566) (xy 223.140782 -43.463591) (xy 223.11363 -43.473633)
			(xy 223.090384 -43.490886) (xy 223.072908 -43.513964) (xy 223.062604 -43.541018) (xy 223.061022 -43.555412)
			(xy 223.05827 -43.583787) (xy 223.045421 -43.639327) (xy 223.024459 -43.692339) (xy 222.995849 -43.741646)
			(xy 222.960228 -43.786153) (xy 222.918386 -43.82487) (xy 222.871253 -43.856937) (xy 222.819878 -43.881641)
			(xy 222.765401 -43.898434) (xy 222.709033 -43.906942) (xy 222.68053 -43.907456) (xy 222.653276 -43.906972)
			(xy 222.599323 -43.89922) (xy 222.547021 -43.883867) (xy 222.497437 -43.861229) (xy 222.45158 -43.831764)
			(xy 222.410382 -43.796073) (xy 222.374683 -43.754883) (xy 222.345209 -43.709031) (xy 222.32256 -43.659452)
			(xy 222.307197 -43.607154) (xy 222.299433 -43.553202) (xy 222.299022 -43.525948) (xy 222.299548 -43.497441)
			(xy 222.308024 -43.441061) (xy 222.324795 -43.38657) (xy 222.349486 -43.33518) (xy 222.381549 -43.288037)
			(xy 222.420269 -43.246189) (xy 222.464786 -43.210568) (xy 222.514106 -43.181967) (xy 222.567133 -43.161022)
			(xy 222.622687 -43.148201) (xy 222.651066 -43.145456) (xy 222.665466 -43.143837) (xy 222.692556 -43.13359)
			(xy 222.715673 -43.116141) (xy 222.732951 -43.092896) (xy 222.742998 -43.065731) (xy 222.745002 -43.036838)
			(xy 222.738802 -43.008546) (xy 222.724898 -42.983138) (xy 222.715074 -42.972482) (xy 221.84106 -42.098468)
			(xy 208.915 -42.098468) (xy 204.3049 -37.488368) (xy 198.476362 -37.488368) (xy 198.469504 -37.53104)
			(xy 198.464845 -37.557222) (xy 198.449174 -37.608041) (xy 198.426582 -37.656184) (xy 198.397508 -37.700714)
			(xy 198.38035 -37.721032) (xy 198.371122 -37.732361) (xy 198.35896 -37.758916) (xy 198.354798 -37.787826)
			(xy 198.358975 -37.816733) (xy 198.37115 -37.843283) (xy 198.38035 -37.854636) (xy 198.39178 -37.868352)
			(xy 198.39776 -37.875299) (xy 198.413446 -37.884755) (xy 198.431456 -37.888082) (xy 198.449486 -37.884856)
			(xy 198.465225 -37.875488) (xy 198.471282 -37.868606) (xy 198.4895 -37.846809) (xy 198.531292 -37.808332)
			(xy 198.578328 -37.776478) (xy 198.629568 -37.751953) (xy 198.683878 -37.735298) (xy 198.740058 -37.726883)
			(xy 198.768462 -37.726366) (xy 198.795717 -37.726826) (xy 198.849674 -37.734579) (xy 198.901978 -37.749931)
			(xy 198.951564 -37.772571) (xy 198.997424 -37.802038) (xy 199.038624 -37.837731) (xy 199.074324 -37.878924)
			(xy 199.103798 -37.924779) (xy 199.126446 -37.974362) (xy 199.141808 -38.026664) (xy 199.149569 -38.080619)
			(xy 199.14997 -38.107874) (xy 199.149493 -38.135242) (xy 199.141659 -38.189415) (xy 199.126163 -38.241911)
			(xy 199.103323 -38.291655) (xy 199.073607 -38.337622) (xy 199.05599 -38.358572) (xy 199.04675 -38.3699)
			(xy 199.034567 -38.39646) (xy 199.030389 -38.42538) (xy 199.034556 -38.454303) (xy 199.046729 -38.480867)
			(xy 199.05599 -38.492176) (xy 199.073634 -38.513107) (xy 199.103363 -38.559072) (xy 199.12621 -38.608819)
			(xy 199.141704 -38.661323) (xy 199.149526 -38.715503) (xy 199.14997 -38.742874) (xy 199.149484 -38.770125)
			(xy 199.141728 -38.824073) (xy 199.126373 -38.876368) (xy 199.103731 -38.925945) (xy 199.074265 -38.971795)
			(xy 199.038574 -39.012986) (xy 198.997383 -39.048677) (xy 198.951533 -39.078143) (xy 198.901956 -39.100785)
			(xy 198.849661 -39.11614) (xy 198.795713 -39.123896) (xy 198.741211 -39.123896) (xy 198.687263 -39.11614)
			(xy 198.634968 -39.100785) (xy 198.585391 -39.078143) (xy 198.539541 -39.048677) (xy 198.49835 -39.012986)
			(xy 198.462659 -38.971795) (xy 198.433193 -38.925945) (xy 198.410551 -38.876368) (xy 198.395196 -38.824073)
			(xy 198.38744 -38.770125) (xy 198.386954 -38.742874) (xy 198.387428 -38.715505) (xy 198.395256 -38.661329)
			(xy 198.410747 -38.608829) (xy 198.433585 -38.559082) (xy 198.463298 -38.513111) (xy 198.480934 -38.492176)
			(xy 198.490164 -38.480848) (xy 198.502331 -38.454292) (xy 198.506495 -38.42538) (xy 198.502319 -38.39647)
			(xy 198.490143 -38.369919) (xy 198.480934 -38.358572) (xy 198.469504 -38.344856) (xy 198.463525 -38.337911)
			(xy 198.447841 -38.328459) (xy 198.429833 -38.325135) (xy 198.411809 -38.328365) (xy 198.396076 -38.337735)
			(xy 198.390002 -38.344602) (xy 198.371783 -38.366398) (xy 198.329991 -38.404872) (xy 198.282954 -38.436723)
			(xy 198.231714 -38.461246) (xy 198.177404 -38.477898) (xy 198.121225 -38.486311) (xy 198.092822 -38.486842)
			(xy 198.065569 -38.486358) (xy 198.011617 -38.478604) (xy 197.959318 -38.463251) (xy 197.909735 -38.440612)
			(xy 197.86388 -38.411147) (xy 197.822684 -38.375455) (xy 197.786987 -38.334265) (xy 197.757515 -38.288414)
			(xy 197.734869 -38.238835) (xy 197.719508 -38.186538) (xy 197.711746 -38.132587) (xy 197.711314 -38.105334)
			(xy 197.71179 -38.077966) (xy 197.719623 -38.023792) (xy 197.735118 -37.971294) (xy 197.757957 -37.92155)
			(xy 197.787671 -37.875581) (xy 197.805294 -37.854636) (xy 197.814536 -37.843309) (xy 197.826724 -37.816748)
			(xy 197.830905 -37.787826) (xy 197.826738 -37.758901) (xy 197.814564 -37.732335) (xy 197.805294 -37.721032)
			(xy 197.788172 -37.700688) (xy 197.75913 -37.656147) (xy 197.736539 -37.608013) (xy 197.720834 -37.557212)
			(xy 197.71614 -37.53104) (xy 197.709282 -37.488368) (xy 186.31662 -37.488368) (xy 184.19826 -39.606728)
			(xy 184.19826 -40.138604) (xy 195.560186 -40.138604) (xy 195.564257 -40.082982) (xy 195.576383 -40.028545)
			(xy 195.596306 -39.976454) (xy 195.623602 -39.927819) (xy 195.657688 -39.883676) (xy 195.697837 -39.844967)
			(xy 195.743195 -39.812516) (xy 195.792795 -39.787015) (xy 195.845579 -39.769008) (xy 195.900422 -39.758878)
			(xy 195.956156 -39.756841) (xy 196.011593 -39.762941) (xy 196.06555 -39.777047) (xy 196.116879 -39.798859)
			(xy 196.164485 -39.827913) (xy 196.207353 -39.863588) (xy 196.24457 -39.905125) (xy 196.275343 -39.951638)
			(xy 196.299015 -40.002135) (xy 196.315083 -40.055542) (xy 196.323203 -40.110718) (xy 196.323712 -40.138604)
			(xy 196.323203 -40.16649) (xy 196.315083 -40.221666) (xy 196.299015 -40.275073) (xy 196.275343 -40.32557)
			(xy 196.24457 -40.372083) (xy 196.207353 -40.41362) (xy 196.164485 -40.449295) (xy 196.116879 -40.478349)
			(xy 196.06555 -40.500161) (xy 196.011593 -40.514267) (xy 195.956156 -40.520367) (xy 195.900422 -40.51833)
			(xy 195.845579 -40.5082) (xy 195.792795 -40.490193) (xy 195.743195 -40.464692) (xy 195.697837 -40.432241)
			(xy 195.657688 -40.393532) (xy 195.623602 -40.349389) (xy 195.596306 -40.300754) (xy 195.576383 -40.248663)
			(xy 195.564257 -40.194226) (xy 195.560186 -40.138604) (xy 184.19826 -40.138604) (xy 184.19826 -41.552368)
			(xy 183.896 -41.854628) (xy 182.4609 -41.854628) (xy 182.15864 -41.552368) (xy 182.15864 -40.719248)
			(xy 182.139337 -40.699591) (xy 182.106015 -40.655718) (xy 182.07935 -40.607508) (xy 182.059897 -40.555965)
			(xy 182.04806 -40.502159) (xy 182.044086 -40.44721) (xy 182.048058 -40.392261) (xy 182.059891 -40.338454)
			(xy 182.079342 -40.28691) (xy 182.106004 -40.238699) (xy 182.139324 -40.194824) (xy 182.15864 -40.17518)
			(xy 182.15864 -36.299648) (xy 181.17566 -35.316668) (xy 174.29988 -35.316668) (xy 172.52188 -33.538668)
			(xy 172.52188 -28.946348) (xy 171.662852 -28.08732) (xy 171.651714 -28.076979) (xy 171.624869 -28.062767)
			(xy 171.595032 -28.057072) (xy 171.564839 -28.060397) (xy 171.536956 -28.072449) (xy 171.513847 -28.092163)
			(xy 171.497553 -28.117798) (xy 171.492926 -28.132278) (xy 171.485174 -28.158837) (xy 171.463063 -28.209553)
			(xy 171.433859 -28.256544) (xy 171.398174 -28.298825) (xy 171.356757 -28.335508) (xy 171.310477 -28.365826)
			(xy 171.260303 -28.389141) (xy 171.207288 -28.404966) (xy 171.152543 -28.412968) (xy 171.12488 -28.413456)
			(xy 171.097628 -28.412969) (xy 171.04368 -28.40521) (xy 170.991385 -28.389854) (xy 170.941807 -28.367212)
			(xy 170.895956 -28.337746) (xy 170.854764 -28.302055) (xy 170.819071 -28.260866) (xy 170.789601 -28.215017)
			(xy 170.766956 -28.165441) (xy 170.751596 -28.113147) (xy 170.743833 -28.0592) (xy 170.743372 -28.031948)
			(xy 170.743862 -28.004283) (xy 170.751849 -27.949532) (xy 170.767664 -27.896509) (xy 170.790974 -27.846328)
			(xy 170.82129 -27.800042) (xy 170.857975 -27.758621) (xy 170.900261 -27.722936) (xy 170.947258 -27.693735)
			(xy 170.997982 -27.671631) (xy 171.02455 -27.663902) (xy 171.039045 -27.659334) (xy 171.064673 -27.643029)
			(xy 171.084378 -27.619912) (xy 171.096419 -27.592025) (xy 171.099733 -27.561831) (xy 171.094028 -27.531997)
			(xy 171.079806 -27.505156) (xy 171.069508 -27.493976) (xy 170.70832 -27.132788) (xy 162.907726 -27.132788)
			(xy 162.892853 -27.133313) (xy 162.864372 -27.141902) (xy 162.839571 -27.158329) (xy 162.820553 -27.181203)
			(xy 162.808928 -27.208586) (xy 162.805683 -27.238156) (xy 162.811092 -27.267408) (xy 162.824696 -27.293862)
			(xy 162.834574 -27.305) (xy 162.854519 -27.326435) (xy 162.888261 -27.374284) (xy 162.914291 -27.426729)
			(xy 162.932 -27.482536) (xy 162.940969 -27.540394) (xy 162.941508 -27.569668) (xy 162.941047 -27.596922)
			(xy 162.933294 -27.650877) (xy 162.91794 -27.703178) (xy 162.8953 -27.752763) (xy 162.865833 -27.79862)
			(xy 162.830139 -27.839816) (xy 162.788945 -27.875513) (xy 162.743091 -27.904984) (xy 162.693508 -27.927629)
			(xy 162.641208 -27.942987) (xy 162.587254 -27.950745) (xy 162.56 -27.951176) (xy 162.529496 -27.950573)
			(xy 162.469265 -27.94087) (xy 162.440112 -27.931872) (xy 162.426861 -27.927958) (xy 162.399275 -27.926602)
			(xy 162.372336 -27.93269) (xy 162.348015 -27.945776) (xy 162.328092 -27.964904) (xy 162.314025 -27.988672)
			(xy 162.306846 -28.015341) (xy 162.306508 -28.029154) (xy 162.306508 -28.031948) (xy 162.306019 -28.059198)
			(xy 162.298256 -28.113144) (xy 162.282895 -28.165435) (xy 162.260249 -28.215009) (xy 162.230778 -28.260855)
			(xy 162.195083 -28.30204) (xy 162.15389 -28.337726) (xy 162.108038 -28.367187) (xy 162.05846 -28.389823)
			(xy 162.006166 -28.405173) (xy 161.952219 -28.412925) (xy 161.897718 -28.41292) (xy 161.843772 -28.405159)
			(xy 161.79148 -28.389801) (xy 161.741905 -28.367157) (xy 161.696058 -28.337688) (xy 161.654871 -28.301995)
			(xy 161.619183 -28.260803) (xy 161.58972 -28.214952) (xy 161.567083 -28.165375) (xy 161.55173 -28.113081)
			(xy 161.543977 -28.059135) (xy 161.543979 -28.004633) (xy 161.551737 -27.950687) (xy 161.567094 -27.898395)
			(xy 161.589736 -27.848819) (xy 161.619203 -27.802971) (xy 161.654894 -27.761783) (xy 161.696084 -27.726093)
			(xy 161.741934 -27.696628) (xy 161.79151 -27.673988) (xy 161.843803 -27.658634) (xy 161.897749 -27.650878)
			(xy 161.925 -27.65044) (xy 161.955504 -27.651043) (xy 162.015735 -27.660746) (xy 162.044888 -27.669744)
			(xy 162.05814 -27.673657) (xy 162.085726 -27.675013) (xy 162.112667 -27.668925) (xy 162.13699 -27.655839)
			(xy 162.156915 -27.636712) (xy 162.170984 -27.612944) (xy 162.178168 -27.586275) (xy 162.178492 -27.572462)
			(xy 162.178492 -27.569668) (xy 162.17905 -27.540397) (xy 162.188039 -27.482548) (xy 162.205755 -27.42675)
			(xy 162.231783 -27.374311) (xy 162.265512 -27.326461) (xy 162.285426 -27.305) (xy 162.295396 -27.29393)
			(xy 162.309027 -27.267454) (xy 162.31445 -27.238174) (xy 162.311203 -27.208573) (xy 162.299562 -27.181164)
			(xy 162.280516 -27.158273) (xy 162.25568 -27.141842) (xy 162.227163 -27.133267) (xy 162.212274 -27.132788)
			(xy 161.167318 -27.132788) (xy 161.152607 -27.133289) (xy 161.124409 -27.141687) (xy 161.099768 -27.157764)
			(xy 161.080723 -27.18019) (xy 161.068849 -27.20711) (xy 161.065129 -27.236296) (xy 161.066988 -27.250898)
			(xy 161.069367 -27.266345) (xy 161.07191 -27.297499) (xy 161.072068 -27.313128) (xy 161.071582 -27.340379)
			(xy 161.063826 -27.394327) (xy 161.048471 -27.446622) (xy 161.025829 -27.496199) (xy 160.996363 -27.542049)
			(xy 160.960672 -27.58324) (xy 160.919481 -27.618931) (xy 160.873631 -27.648397) (xy 160.824054 -27.671039)
			(xy 160.771759 -27.686394) (xy 160.717811 -27.69415) (xy 160.663309 -27.69415) (xy 160.609361 -27.686394)
			(xy 160.557066 -27.671039) (xy 160.507489 -27.648397) (xy 160.461639 -27.618931) (xy 160.420448 -27.58324)
			(xy 160.384757 -27.542049) (xy 160.355291 -27.496199) (xy 160.332649 -27.446622) (xy 160.317294 -27.394327)
			(xy 160.309538 -27.340379) (xy 160.309052 -27.313128) (xy 160.309198 -27.297499) (xy 160.31174 -27.266344)
			(xy 160.314132 -27.250898) (xy 160.316037 -27.236296) (xy 160.312337 -27.207094) (xy 160.300465 -27.18016)
			(xy 160.281405 -27.157729) (xy 160.256741 -27.141663) (xy 160.22852 -27.133297) (xy 160.213802 -27.132788)
			(xy 154.56916 -27.132788) (xy 153.093928 -25.657556) (xy 153.083952 -25.648196) (xy 153.060182 -25.634678)
			(xy 153.033674 -25.627961) (xy 153.006335 -25.628528) (xy 152.980129 -25.636338) (xy 152.95694 -25.650829)
			(xy 152.94737 -25.660604) (xy 152.929228 -25.679631) (xy 152.888622 -25.713024) (xy 152.843816 -25.740527)
			(xy 152.79566 -25.76162) (xy 152.745064 -25.775903) (xy 152.692987 -25.783105) (xy 152.6667 -25.78354)
			(xy 152.639448 -25.783054) (xy 152.585498 -25.775298) (xy 152.533202 -25.759943) (xy 152.483623 -25.737302)
			(xy 152.43777 -25.707837) (xy 152.396577 -25.672146) (xy 152.360883 -25.630956) (xy 152.331413 -25.585105)
			(xy 152.308768 -25.535528) (xy 152.293409 -25.483233) (xy 152.285648 -25.429284) (xy 152.285192 -25.402032)
			(xy 152.285734 -25.372699) (xy 152.294721 -25.314725) (xy 152.312472 -25.258809) (xy 152.338569 -25.206267)
			(xy 152.372398 -25.158337) (xy 152.39238 -25.136856) (xy 152.402331 -25.125745) (xy 152.415902 -25.0992)
			(xy 152.421244 -25.069869) (xy 152.417902 -25.040243) (xy 152.406161 -25.012839) (xy 152.387018 -24.989983)
			(xy 152.362097 -24.973618) (xy 152.34793 -24.968962) (xy 152.321964 -24.960773) (xy 152.27248 -24.938063)
			(xy 152.226725 -24.908555) (xy 152.185624 -24.872848) (xy 152.150012 -24.831664) (xy 152.12061 -24.78584)
			(xy 152.098015 -24.736304) (xy 152.082685 -24.684061) (xy 152.074931 -24.630171) (xy 152.074372 -24.602948)
			(xy 152.074832 -24.575692) (xy 152.082583 -24.521735) (xy 152.097935 -24.46943) (xy 152.120574 -24.419843)
			(xy 152.15004 -24.373982) (xy 152.185734 -24.332782) (xy 152.226928 -24.297081) (xy 152.272783 -24.267607)
			(xy 152.322366 -24.244958) (xy 152.374669 -24.229597) (xy 152.428624 -24.221836) (xy 152.45588 -24.22144)
			(xy 152.473056 -24.221605) (xy 152.507272 -24.224658) (xy 152.524206 -24.227536) (xy 152.538887 -24.229662)
			(xy 152.568349 -24.226314) (xy 152.59561 -24.214652) (xy 152.618376 -24.195655) (xy 152.634733 -24.170924)
			(xy 152.643303 -24.142538) (xy 152.64384 -24.127714) (xy 152.64384 -23.655528) (xy 153.39822 -22.901148)
			(xy 158.53664 -22.901148) (xy 160.5407 -20.897088) (xy 160.5407 -15.265908) (xy 159.71012 -14.435328)
			(xy 158.503874 -14.435328) (xy 158.489638 -14.435794) (xy 158.46227 -14.443644) (xy 158.438138 -14.458754)
			(xy 158.419123 -14.479944) (xy 158.406707 -14.505566) (xy 158.401856 -14.533621) (xy 158.404949 -14.561924)
			(xy 158.409894 -14.575282) (xy 158.418904 -14.5983) (xy 158.431579 -14.646077) (xy 158.43797 -14.695093)
			(xy 158.438342 -14.719808) (xy 158.437856 -14.747059) (xy 158.4301 -14.801007) (xy 158.414745 -14.853302)
			(xy 158.392103 -14.902879) (xy 158.362637 -14.948729) (xy 158.326946 -14.98992) (xy 158.285755 -15.025611)
			(xy 158.239905 -15.055077) (xy 158.190328 -15.077719) (xy 158.138033 -15.093074) (xy 158.084085 -15.10083)
			(xy 158.029583 -15.10083) (xy 157.975635 -15.093074) (xy 157.92334 -15.077719) (xy 157.873763 -15.055077)
			(xy 157.827913 -15.025611) (xy 157.786722 -14.98992) (xy 157.751031 -14.948729) (xy 157.721565 -14.902879)
			(xy 157.698923 -14.853302) (xy 157.683568 -14.801007) (xy 157.675812 -14.747059) (xy 157.675326 -14.719808)
			(xy 157.675717 -14.695093) (xy 157.6821 -14.646078) (xy 157.694761 -14.598298) (xy 157.703774 -14.575282)
			(xy 157.708711 -14.561926) (xy 157.711773 -14.53363) (xy 157.706906 -14.505587) (xy 157.694489 -14.479976)
			(xy 157.675486 -14.458787) (xy 157.651374 -14.443665) (xy 157.624025 -14.435784) (xy 157.609794 -14.435328)
			(xy 149.88286 -14.435328) (xy 149.230588 -15.0876) (xy 149.266402 -15.123414) (xy 149.28714 -15.145019)
			(xy 149.322304 -15.193492) (xy 149.349466 -15.246862) (xy 149.367957 -15.303819) (xy 149.377325 -15.362966)
			(xy 149.377908 -15.392908) (xy 149.377422 -15.420159) (xy 149.369664 -15.474106) (xy 149.354308 -15.5264)
			(xy 149.331667 -15.575976) (xy 149.3022 -15.621825) (xy 149.266509 -15.663014) (xy 149.225319 -15.698705)
			(xy 149.179469 -15.728171) (xy 149.129892 -15.750811) (xy 149.077598 -15.766166) (xy 149.023651 -15.773922)
			(xy 148.9964 -15.774416) (xy 148.96932 -15.773943) (xy 148.915705 -15.766288) (xy 148.863709 -15.751131)
			(xy 148.814379 -15.728777) (xy 148.768703 -15.699675) (xy 148.727599 -15.664408) (xy 148.70938 -15.644368)
			(xy 121.83745 -15.644368) (xy 121.824242 -15.675356) (xy 121.812928 -15.700894) (xy 121.783926 -15.748629)
			(xy 121.74827 -15.791623) (xy 121.706724 -15.828955) (xy 121.660176 -15.859827) (xy 121.609623 -15.883578)
			(xy 121.556145 -15.899701) (xy 121.500888 -15.907849) (xy 121.445032 -15.907849) (xy 121.389775 -15.899701)
			(xy 121.336297 -15.883578) (xy 121.285744 -15.859827) (xy 121.239196 -15.828955) (xy 121.19765 -15.791623)
			(xy 121.161994 -15.748629) (xy 121.132992 -15.700894) (xy 121.121678 -15.675356) (xy 121.10847 -15.644368)
			(xy 113.4872 -15.644368) (xy 112.221518 -16.91005) (xy 121.090942 -16.91005) (xy 121.095013 -16.854428)
			(xy 121.107139 -16.799991) (xy 121.127062 -16.7479) (xy 121.154358 -16.699265) (xy 121.188444 -16.655122)
			(xy 121.228593 -16.616413) (xy 121.273951 -16.583962) (xy 121.323551 -16.558461) (xy 121.376335 -16.540454)
			(xy 121.431178 -16.530324) (xy 121.486912 -16.528287) (xy 121.542349 -16.534387) (xy 121.596306 -16.548493)
			(xy 121.647635 -16.570305) (xy 121.695241 -16.599359) (xy 121.738109 -16.635034) (xy 121.775326 -16.676571)
			(xy 121.806099 -16.723084) (xy 121.829771 -16.773581) (xy 121.845839 -16.826988) (xy 121.853959 -16.882164)
			(xy 121.854468 -16.91005) (xy 121.853972 -16.937228) (xy 146.252182 -16.937228) (xy 146.256253 -16.881606)
			(xy 146.268379 -16.827169) (xy 146.288302 -16.775078) (xy 146.315598 -16.726443) (xy 146.349684 -16.6823)
			(xy 146.389833 -16.643591) (xy 146.435191 -16.61114) (xy 146.484791 -16.585639) (xy 146.537575 -16.567632)
			(xy 146.592418 -16.557502) (xy 146.648152 -16.555465) (xy 146.703589 -16.561565) (xy 146.757546 -16.575671)
			(xy 146.808875 -16.597483) (xy 146.856481 -16.626537) (xy 146.899349 -16.662212) (xy 146.936566 -16.703749)
			(xy 146.967339 -16.750262) (xy 146.991011 -16.800759) (xy 147.007079 -16.854166) (xy 147.015199 -16.909342)
			(xy 147.015708 -16.937228) (xy 147.015199 -16.965114) (xy 147.007079 -17.02029) (xy 146.991011 -17.073697)
			(xy 146.967339 -17.124194) (xy 146.936566 -17.170707) (xy 146.899349 -17.212244) (xy 146.856481 -17.247919)
			(xy 146.808875 -17.276973) (xy 146.757546 -17.298785) (xy 146.703589 -17.312891) (xy 146.648152 -17.318991)
			(xy 146.592418 -17.316954) (xy 146.537575 -17.306824) (xy 146.484791 -17.288817) (xy 146.435191 -17.263316)
			(xy 146.389833 -17.230865) (xy 146.349684 -17.192156) (xy 146.315598 -17.148013) (xy 146.288302 -17.099378)
			(xy 146.268379 -17.047287) (xy 146.256253 -16.99285) (xy 146.252182 -16.937228) (xy 121.853972 -16.937228)
			(xy 121.853959 -16.937936) (xy 121.845839 -16.993112) (xy 121.829771 -17.046519) (xy 121.806099 -17.097016)
			(xy 121.775326 -17.143529) (xy 121.738109 -17.185066) (xy 121.695241 -17.220741) (xy 121.647635 -17.249795)
			(xy 121.596306 -17.271607) (xy 121.542349 -17.285713) (xy 121.486912 -17.291813) (xy 121.431178 -17.289776)
			(xy 121.376335 -17.279646) (xy 121.323551 -17.261639) (xy 121.273951 -17.236138) (xy 121.228593 -17.203687)
			(xy 121.188444 -17.164978) (xy 121.154358 -17.120835) (xy 121.127062 -17.0722) (xy 121.107139 -17.020109)
			(xy 121.095013 -16.965672) (xy 121.090942 -16.91005) (xy 112.221518 -16.91005) (xy 111.89462 -17.236948)
			(xy 111.89462 -17.655032) (xy 129.364992 -17.655032) (xy 129.369063 -17.59941) (xy 129.381189 -17.544973)
			(xy 129.401112 -17.492882) (xy 129.428408 -17.444247) (xy 129.462494 -17.400104) (xy 129.502643 -17.361395)
			(xy 129.548001 -17.328944) (xy 129.597601 -17.303443) (xy 129.650385 -17.285436) (xy 129.705228 -17.275306)
			(xy 129.760962 -17.273269) (xy 129.816399 -17.279369) (xy 129.870356 -17.293475) (xy 129.921685 -17.315287)
			(xy 129.969291 -17.344341) (xy 130.012159 -17.380016) (xy 130.049376 -17.421553) (xy 130.080149 -17.468066)
			(xy 130.103821 -17.518563) (xy 130.119889 -17.57197) (xy 130.128009 -17.627146) (xy 130.128518 -17.655032)
			(xy 131.1656 -17.655032) (xy 131.166086 -17.627781) (xy 131.173842 -17.573833) (xy 131.189197 -17.521538)
			(xy 131.211839 -17.471961) (xy 131.241305 -17.426111) (xy 131.276996 -17.38492) (xy 131.318187 -17.349229)
			(xy 131.364037 -17.319763) (xy 131.413614 -17.297121) (xy 131.465909 -17.281766) (xy 131.519857 -17.27401)
			(xy 131.574359 -17.27401) (xy 131.628307 -17.281766) (xy 131.680602 -17.297121) (xy 131.730179 -17.319763)
			(xy 131.776029 -17.349229) (xy 131.81722 -17.38492) (xy 131.852911 -17.426111) (xy 131.882377 -17.471961)
			(xy 131.905019 -17.521538) (xy 131.920374 -17.573833) (xy 131.92813 -17.627781) (xy 131.928616 -17.655032)
			(xy 131.928516 -17.668092) (xy 131.926735 -17.69415) (xy 131.92506 -17.707102) (xy 131.924239 -17.716244)
			(xy 131.928239 -17.734137) (xy 131.938287 -17.749473) (xy 131.953093 -17.760287) (xy 131.970759 -17.765191)
			(xy 131.979924 -17.76476) (xy 132.014468 -17.763236) (xy 132.878068 -17.763236) (xy 132.913882 -17.76476)
			(xy 132.923052 -17.765218) (xy 132.940755 -17.76041) (xy 132.955627 -17.74967) (xy 132.965759 -17.734379)
			(xy 132.969851 -17.716497) (xy 132.969 -17.707356) (xy 132.967328 -17.69434) (xy 132.96555 -17.668155)
			(xy 132.965444 -17.655032) (xy 132.966008 -17.627784) (xy 132.973759 -17.573841) (xy 132.989107 -17.521551)
			(xy 133.011741 -17.471977) (xy 133.0412 -17.426129) (xy 133.076883 -17.38494) (xy 133.118065 -17.349248)
			(xy 133.163907 -17.31978) (xy 133.213476 -17.297135) (xy 133.265763 -17.281776) (xy 133.319704 -17.274014)
			(xy 133.346952 -17.273524) (xy 133.376679 -17.274097) (xy 133.435412 -17.283327) (xy 133.492003 -17.301554)
			(xy 133.545082 -17.328338) (xy 133.593364 -17.36303) (xy 133.614922 -17.383506) (xy 133.625863 -17.393527)
			(xy 133.652103 -17.407349) (xy 133.681202 -17.413071) (xy 133.710721 -17.410213) (xy 133.738183 -17.399016)
			(xy 133.75005 -17.39011) (xy 133.770498 -17.374097) (xy 133.814937 -17.347216) (xy 133.862615 -17.32662)
			(xy 133.912649 -17.312691) (xy 133.964111 -17.305688) (xy 133.99008 -17.305274) (xy 134.017333 -17.305772)
			(xy 134.071283 -17.313526) (xy 134.123581 -17.32888) (xy 134.173161 -17.35152) (xy 134.219015 -17.380986)
			(xy 134.260208 -17.416678) (xy 134.295902 -17.457869) (xy 134.32537 -17.503721) (xy 134.348013 -17.5533)
			(xy 134.36337 -17.605597) (xy 134.370478 -17.655032) (xy 134.765032 -17.655032) (xy 134.769103 -17.59941)
			(xy 134.781229 -17.544973) (xy 134.801152 -17.492882) (xy 134.828448 -17.444247) (xy 134.862534 -17.400104)
			(xy 134.902683 -17.361395) (xy 134.948041 -17.328944) (xy 134.997641 -17.303443) (xy 135.050425 -17.285436)
			(xy 135.105268 -17.275306) (xy 135.161002 -17.273269) (xy 135.216439 -17.279369) (xy 135.270396 -17.293475)
			(xy 135.321725 -17.315287) (xy 135.369331 -17.344341) (xy 135.412199 -17.380016) (xy 135.449416 -17.421553)
			(xy 135.480189 -17.468066) (xy 135.503861 -17.518563) (xy 135.519929 -17.57197) (xy 135.528049 -17.627146)
			(xy 135.528558 -17.655032) (xy 136.565386 -17.655032) (xy 136.565872 -17.627781) (xy 136.573628 -17.573833)
			(xy 136.588983 -17.521538) (xy 136.611625 -17.471961) (xy 136.641091 -17.426111) (xy 136.676782 -17.38492)
			(xy 136.717973 -17.349229) (xy 136.763823 -17.319763) (xy 136.8134 -17.297121) (xy 136.865695 -17.281766)
			(xy 136.919643 -17.27401) (xy 136.974145 -17.27401) (xy 137.028093 -17.281766) (xy 137.080388 -17.297121)
			(xy 137.129965 -17.319763) (xy 137.175815 -17.349229) (xy 137.217006 -17.38492) (xy 137.252697 -17.426111)
			(xy 137.282163 -17.471961) (xy 137.304805 -17.521538) (xy 137.32016 -17.573833) (xy 137.327916 -17.627781)
			(xy 137.328402 -17.655032) (xy 137.328303 -17.668092) (xy 137.326521 -17.69415) (xy 137.324846 -17.707102)
			(xy 137.324041 -17.716244) (xy 137.328039 -17.734134) (xy 137.338083 -17.749468) (xy 137.352885 -17.760281)
			(xy 137.370546 -17.765188) (xy 137.37971 -17.76476) (xy 137.414508 -17.763236) (xy 138.278108 -17.763236)
			(xy 138.313922 -17.76476) (xy 138.323091 -17.765255) (xy 138.340796 -17.760434) (xy 138.355668 -17.749686)
			(xy 138.365799 -17.734387) (xy 138.369891 -17.716499) (xy 138.36904 -17.707356) (xy 138.367368 -17.69434)
			(xy 138.36559 -17.668155) (xy 138.365484 -17.655032) (xy 138.36597 -17.627781) (xy 138.373726 -17.573833)
			(xy 138.389081 -17.521538) (xy 138.411723 -17.471961) (xy 138.441189 -17.426111) (xy 138.47688 -17.38492)
			(xy 138.518071 -17.349229) (xy 138.563921 -17.319763) (xy 138.613498 -17.297121) (xy 138.665793 -17.281766)
			(xy 138.719741 -17.27401) (xy 138.774243 -17.27401) (xy 138.828191 -17.281766) (xy 138.880486 -17.297121)
			(xy 138.930063 -17.319763) (xy 138.975913 -17.349229) (xy 139.017104 -17.38492) (xy 139.052795 -17.426111)
			(xy 139.082261 -17.471961) (xy 139.104903 -17.521538) (xy 139.120258 -17.573833) (xy 139.128014 -17.627781)
			(xy 139.1285 -17.655032) (xy 140.165582 -17.655032) (xy 140.166068 -17.627781) (xy 140.173824 -17.573833)
			(xy 140.189179 -17.521538) (xy 140.211821 -17.471961) (xy 140.241287 -17.426111) (xy 140.276978 -17.38492)
			(xy 140.318169 -17.349229) (xy 140.364019 -17.319763) (xy 140.413596 -17.297121) (xy 140.465891 -17.281766)
			(xy 140.519839 -17.27401) (xy 140.574341 -17.27401) (xy 140.628289 -17.281766) (xy 140.680584 -17.297121)
			(xy 140.730161 -17.319763) (xy 140.776011 -17.349229) (xy 140.817202 -17.38492) (xy 140.852893 -17.426111)
			(xy 140.882359 -17.471961) (xy 140.905001 -17.521538) (xy 140.920356 -17.573833) (xy 140.928112 -17.627781)
			(xy 140.928598 -17.655032) (xy 140.928499 -17.668092) (xy 140.926717 -17.69415) (xy 140.925042 -17.707102)
			(xy 140.924241 -17.716245) (xy 140.928239 -17.734133) (xy 140.938282 -17.749466) (xy 140.953082 -17.76028)
			(xy 140.970743 -17.765188) (xy 140.979906 -17.76476) (xy 141.01445 -17.763236) (xy 141.87805 -17.763236)
			(xy 141.913864 -17.76476) (xy 141.923035 -17.765201) (xy 141.940736 -17.760399) (xy 141.955609 -17.749664)
			(xy 141.965741 -17.734375) (xy 141.969834 -17.716496) (xy 141.968982 -17.707356) (xy 141.96731 -17.69434)
			(xy 141.965532 -17.668155) (xy 141.965426 -17.655032) (xy 141.965912 -17.627781) (xy 141.973668 -17.573833)
			(xy 141.989023 -17.521538) (xy 142.011665 -17.471961) (xy 142.041131 -17.426111) (xy 142.076822 -17.38492)
			(xy 142.118013 -17.349229) (xy 142.163863 -17.319763) (xy 142.21344 -17.297121) (xy 142.265735 -17.281766)
			(xy 142.319683 -17.27401) (xy 142.374185 -17.27401) (xy 142.428133 -17.281766) (xy 142.480428 -17.297121)
			(xy 142.530005 -17.319763) (xy 142.575855 -17.349229) (xy 142.617046 -17.38492) (xy 142.652737 -17.426111)
			(xy 142.682203 -17.471961) (xy 142.704845 -17.521538) (xy 142.7202 -17.573833) (xy 142.727956 -17.627781)
			(xy 142.728442 -17.655032) (xy 152.874978 -17.655032) (xy 152.879049 -17.59941) (xy 152.891175 -17.544973)
			(xy 152.911098 -17.492882) (xy 152.938394 -17.444247) (xy 152.97248 -17.400104) (xy 153.012629 -17.361395)
			(xy 153.057987 -17.328944) (xy 153.107587 -17.303443) (xy 153.160371 -17.285436) (xy 153.215214 -17.275306)
			(xy 153.270948 -17.273269) (xy 153.326385 -17.279369) (xy 153.380342 -17.293475) (xy 153.431671 -17.315287)
			(xy 153.479277 -17.344341) (xy 153.522145 -17.380016) (xy 153.559362 -17.421553) (xy 153.590135 -17.468066)
			(xy 153.613807 -17.518563) (xy 153.629875 -17.57197) (xy 153.637995 -17.627146) (xy 153.638504 -17.655032)
			(xy 155.874972 -17.655032) (xy 155.879043 -17.59941) (xy 155.891169 -17.544973) (xy 155.911092 -17.492882)
			(xy 155.938388 -17.444247) (xy 155.972474 -17.400104) (xy 156.012623 -17.361395) (xy 156.057981 -17.328944)
			(xy 156.107581 -17.303443) (xy 156.160365 -17.285436) (xy 156.215208 -17.275306) (xy 156.270942 -17.273269)
			(xy 156.326379 -17.279369) (xy 156.380336 -17.293475) (xy 156.431665 -17.315287) (xy 156.479271 -17.344341)
			(xy 156.522139 -17.380016) (xy 156.559356 -17.421553) (xy 156.590129 -17.468066) (xy 156.613801 -17.518563)
			(xy 156.629869 -17.57197) (xy 156.637989 -17.627146) (xy 156.638498 -17.655032) (xy 156.637989 -17.682918)
			(xy 156.629869 -17.738094) (xy 156.613801 -17.791501) (xy 156.590129 -17.841998) (xy 156.559356 -17.888511)
			(xy 156.522139 -17.930048) (xy 156.479271 -17.965723) (xy 156.431665 -17.994777) (xy 156.380336 -18.016589)
			(xy 156.326379 -18.030695) (xy 156.270942 -18.036795) (xy 156.215208 -18.034758) (xy 156.160365 -18.024628)
			(xy 156.107581 -18.006621) (xy 156.057981 -17.98112) (xy 156.012623 -17.948669) (xy 155.972474 -17.90996)
			(xy 155.938388 -17.865817) (xy 155.911092 -17.817182) (xy 155.891169 -17.765091) (xy 155.879043 -17.710654)
			(xy 155.874972 -17.655032) (xy 153.638504 -17.655032) (xy 153.637995 -17.682918) (xy 153.629875 -17.738094)
			(xy 153.613807 -17.791501) (xy 153.590135 -17.841998) (xy 153.559362 -17.888511) (xy 153.522145 -17.930048)
			(xy 153.479277 -17.965723) (xy 153.431671 -17.994777) (xy 153.380342 -18.016589) (xy 153.326385 -18.030695)
			(xy 153.270948 -18.036795) (xy 153.215214 -18.034758) (xy 153.160371 -18.024628) (xy 153.107587 -18.006621)
			(xy 153.057987 -17.98112) (xy 153.012629 -17.948669) (xy 152.97248 -17.90996) (xy 152.938394 -17.865817)
			(xy 152.911098 -17.817182) (xy 152.891175 -17.765091) (xy 152.879049 -17.710654) (xy 152.874978 -17.655032)
			(xy 142.728442 -17.655032) (xy 142.727992 -17.681771) (xy 142.720506 -17.734723) (xy 142.705699 -17.786111)
			(xy 142.683862 -17.834928) (xy 142.655421 -17.880217) (xy 142.620935 -17.921091) (xy 142.58108 -17.956749)
			(xy 142.536636 -17.986493) (xy 142.488473 -18.009738) (xy 142.437537 -18.026031) (xy 142.384825 -18.035051)
			(xy 142.35811 -18.036286) (xy 142.344935 -18.037112) (xy 142.319644 -18.044648) (xy 142.297131 -18.058415)
			(xy 142.278898 -18.077492) (xy 142.266164 -18.100606) (xy 142.25978 -18.126211) (xy 142.259558 -18.13941)
			(xy 142.259812 -18.144744) (xy 142.259385 -18.172009) (xy 142.251616 -18.225984) (xy 142.236242 -18.278302)
			(xy 142.225774 -18.301208) (xy 146.920202 -18.301208) (xy 146.924273 -18.245586) (xy 146.936399 -18.191149)
			(xy 146.956322 -18.139058) (xy 146.983618 -18.090423) (xy 147.017704 -18.04628) (xy 147.057853 -18.007571)
			(xy 147.103211 -17.97512) (xy 147.152811 -17.949619) (xy 147.205595 -17.931612) (xy 147.260438 -17.921482)
			(xy 147.316172 -17.919445) (xy 147.371609 -17.925545) (xy 147.425566 -17.939651) (xy 147.476895 -17.961463)
			(xy 147.524501 -17.990517) (xy 147.567369 -18.026192) (xy 147.604586 -18.067729) (xy 147.635359 -18.114242)
			(xy 147.659031 -18.164739) (xy 147.675099 -18.218146) (xy 147.683219 -18.273322) (xy 147.683728 -18.301208)
			(xy 147.683219 -18.329094) (xy 147.675099 -18.38427) (xy 147.659031 -18.437677) (xy 147.635359 -18.488174)
			(xy 147.604586 -18.534687) (xy 147.567369 -18.576224) (xy 147.524501 -18.611899) (xy 147.476895 -18.640953)
			(xy 147.425566 -18.662765) (xy 147.371609 -18.676871) (xy 147.316172 -18.682971) (xy 147.260438 -18.680934)
			(xy 147.205595 -18.670804) (xy 147.152811 -18.652797) (xy 147.103211 -18.627296) (xy 147.057853 -18.594845)
			(xy 147.017704 -18.556136) (xy 146.983618 -18.511993) (xy 146.956322 -18.463358) (xy 146.936399 -18.411267)
			(xy 146.924273 -18.35683) (xy 146.920202 -18.301208) (xy 142.225774 -18.301208) (xy 142.213576 -18.327899)
			(xy 142.18408 -18.373764) (xy 142.148355 -18.414963) (xy 142.107129 -18.450656) (xy 142.061241 -18.480117)
			(xy 142.011627 -18.502744) (xy 141.959296 -18.518078) (xy 141.905316 -18.525806) (xy 141.87805 -18.526252)
			(xy 141.01445 -18.526252) (xy 140.98719 -18.525823) (xy 140.933227 -18.518061) (xy 140.880916 -18.502701)
			(xy 140.831322 -18.480057) (xy 140.785453 -18.450589) (xy 140.744242 -18.414895) (xy 140.708528 -18.373703)
			(xy 140.679036 -18.327849) (xy 140.656367 -18.278266) (xy 140.640981 -18.225963) (xy 140.633191 -18.172003)
			(xy 140.632688 -18.144744) (xy 140.632942 -18.13941) (xy 140.632745 -18.126227) (xy 140.626396 -18.100646)
			(xy 140.613705 -18.077545) (xy 140.595519 -18.058468) (xy 140.573051 -18.044687) (xy 140.547803 -18.037124)
			(xy 140.534644 -18.036286) (xy 140.507985 -18.035007) (xy 140.455401 -18.025857) (xy 140.404607 -18.009466)
			(xy 140.356594 -17.986154) (xy 140.312299 -17.956376) (xy 140.272589 -17.920713) (xy 140.238239 -17.879862)
			(xy 140.209919 -17.834621) (xy 140.188183 -17.785874) (xy 140.173455 -17.734573) (xy 140.166024 -17.681719)
			(xy 140.165582 -17.655032) (xy 139.1285 -17.655032) (xy 139.127994 -17.681769) (xy 139.120509 -17.734716)
			(xy 139.105705 -17.786099) (xy 139.083872 -17.834912) (xy 139.055437 -17.880199) (xy 139.020957 -17.921072)
			(xy 138.981108 -17.95673) (xy 138.936671 -17.986474) (xy 138.888516 -18.009723) (xy 138.837586 -18.026021)
			(xy 138.78488 -18.035047) (xy 138.758168 -18.036286) (xy 138.74499 -18.037077) (xy 138.719698 -18.044622)
			(xy 138.697185 -18.058397) (xy 138.678954 -18.077481) (xy 138.666221 -18.100599) (xy 138.659837 -18.126209)
			(xy 138.659616 -18.13941) (xy 138.659616 -18.144744) (xy 138.659163 -18.171996) (xy 138.651401 -18.225944)
			(xy 138.636041 -18.278239) (xy 138.613395 -18.327816) (xy 138.583925 -18.373666) (xy 138.54823 -18.414855)
			(xy 138.507037 -18.450546) (xy 138.461185 -18.480012) (xy 138.411606 -18.502653) (xy 138.359309 -18.518009)
			(xy 138.30536 -18.525766) (xy 138.278108 -18.526252) (xy 137.414508 -18.526252) (xy 137.387259 -18.525715)
			(xy 137.333315 -18.517961) (xy 137.281024 -18.502609) (xy 137.23145 -18.479972) (xy 137.185602 -18.45051)
			(xy 137.144412 -18.414824) (xy 137.108721 -18.37364) (xy 137.079253 -18.327796) (xy 137.056609 -18.278225)
			(xy 137.04125 -18.225936) (xy 137.033489 -18.171993) (xy 137.033 -18.144744) (xy 137.033 -18.13941)
			(xy 137.032747 -18.12623) (xy 137.026403 -18.100658) (xy 137.013721 -18.077563) (xy 136.995546 -18.058488)
			(xy 136.973091 -18.044703) (xy 136.947855 -18.03713) (xy 136.934702 -18.036286) (xy 136.90803 -18.035028)
			(xy 136.855419 -18.025907) (xy 136.804593 -18.009537) (xy 136.756548 -17.986238) (xy 136.712222 -17.956466)
			(xy 136.672482 -17.920803) (xy 136.638104 -17.879945) (xy 136.609761 -17.834692) (xy 136.588007 -17.785928)
			(xy 136.573267 -17.734606) (xy 136.565829 -17.68173) (xy 136.565386 -17.655032) (xy 135.528558 -17.655032)
			(xy 135.528049 -17.682918) (xy 135.519929 -17.738094) (xy 135.503861 -17.791501) (xy 135.480189 -17.841998)
			(xy 135.449416 -17.888511) (xy 135.412199 -17.930048) (xy 135.369331 -17.965723) (xy 135.321725 -17.994777)
			(xy 135.270396 -18.016589) (xy 135.216439 -18.030695) (xy 135.161002 -18.036795) (xy 135.105268 -18.034758)
			(xy 135.050425 -18.024628) (xy 134.997641 -18.006621) (xy 134.948041 -17.98112) (xy 134.902683 -17.948669)
			(xy 134.862534 -17.90996) (xy 134.828448 -17.865817) (xy 134.801152 -17.817182) (xy 134.781229 -17.765091)
			(xy 134.769103 -17.710654) (xy 134.765032 -17.655032) (xy 134.370478 -17.655032) (xy 134.371127 -17.659548)
			(xy 134.371127 -17.714052) (xy 134.36337 -17.768003) (xy 134.348013 -17.8203) (xy 134.32537 -17.869879)
			(xy 134.295902 -17.915731) (xy 134.260208 -17.956922) (xy 134.219015 -17.992614) (xy 134.173161 -18.02208)
			(xy 134.123581 -18.04472) (xy 134.071283 -18.060074) (xy 134.017333 -18.067828) (xy 133.99008 -18.06829)
			(xy 133.960354 -18.067693) (xy 133.901622 -18.058469) (xy 133.845032 -18.040247) (xy 133.791952 -18.013469)
			(xy 133.743669 -17.978782) (xy 133.72211 -17.958308) (xy 133.711144 -17.948316) (xy 133.684913 -17.93449)
			(xy 133.655821 -17.928761) (xy 133.626307 -17.931612) (xy 133.598848 -17.942802) (xy 133.586982 -17.951704)
			(xy 133.562426 -17.970734) (xy 133.508413 -18.00142) (xy 133.450144 -18.022958) (xy 133.389158 -18.03478)
			(xy 133.358128 -18.036286) (xy 133.344954 -18.037127) (xy 133.319664 -18.044659) (xy 133.29715 -18.058422)
			(xy 133.278917 -18.077497) (xy 133.266182 -18.100608) (xy 133.259798 -18.126212) (xy 133.259576 -18.13941)
			(xy 133.259576 -18.144744) (xy 133.259163 -18.171998) (xy 133.2514 -18.22595) (xy 133.236037 -18.278248)
			(xy 133.213389 -18.327827) (xy 133.183915 -18.373679) (xy 133.148216 -18.41487) (xy 133.107018 -18.450561)
			(xy 133.061161 -18.480025) (xy 133.011577 -18.502664) (xy 132.959275 -18.518016) (xy 132.930238 -18.522188)
			(xy 133.879842 -18.522188) (xy 133.883913 -18.466566) (xy 133.896039 -18.412129) (xy 133.915962 -18.360038)
			(xy 133.943258 -18.311403) (xy 133.977344 -18.26726) (xy 134.017493 -18.228551) (xy 134.062851 -18.1961)
			(xy 134.112451 -18.170599) (xy 134.165235 -18.152592) (xy 134.220078 -18.142462) (xy 134.275812 -18.140425)
			(xy 134.331249 -18.146525) (xy 134.385206 -18.160631) (xy 134.436535 -18.182443) (xy 134.484141 -18.211497)
			(xy 134.527009 -18.247172) (xy 134.564226 -18.288709) (xy 134.594999 -18.335222) (xy 134.618671 -18.385719)
			(xy 134.634739 -18.439126) (xy 134.642859 -18.494302) (xy 134.643368 -18.522188) (xy 134.642859 -18.550074)
			(xy 134.634739 -18.60525) (xy 134.618671 -18.658657) (xy 134.594999 -18.709154) (xy 134.564226 -18.755667)
			(xy 134.527009 -18.797204) (xy 134.484141 -18.832879) (xy 134.436535 -18.861933) (xy 134.385206 -18.883745)
			(xy 134.331249 -18.897851) (xy 134.275812 -18.903951) (xy 134.220078 -18.901914) (xy 134.165235 -18.891784)
			(xy 134.112451 -18.873777) (xy 134.062851 -18.848276) (xy 134.017493 -18.815825) (xy 133.977344 -18.777116)
			(xy 133.943258 -18.732973) (xy 133.915962 -18.684338) (xy 133.896039 -18.632247) (xy 133.883913 -18.57781)
			(xy 133.879842 -18.522188) (xy 132.930238 -18.522188) (xy 132.905322 -18.525768) (xy 132.878068 -18.526252)
			(xy 132.014468 -18.526252) (xy 131.987218 -18.525752) (xy 131.933273 -18.517992) (xy 131.880981 -18.502635)
			(xy 131.831407 -18.479994) (xy 131.785559 -18.450528) (xy 131.74437 -18.414838) (xy 131.708679 -18.373651)
			(xy 131.679212 -18.327804) (xy 131.656569 -18.27823) (xy 131.64121 -18.225939) (xy 131.633449 -18.171994)
			(xy 131.63296 -18.144744) (xy 131.63296 -18.13941) (xy 131.632746 -18.126228) (xy 131.626399 -18.100649)
			(xy 131.61371 -18.077551) (xy 131.595527 -18.058474) (xy 131.573064 -18.044692) (xy 131.547819 -18.037126)
			(xy 131.534662 -18.036286) (xy 131.508004 -18.034991) (xy 131.455421 -18.025844) (xy 131.404626 -18.009455)
			(xy 131.356613 -17.986145) (xy 131.312319 -17.956368) (xy 131.272608 -17.920707) (xy 131.238258 -17.879857)
			(xy 131.209938 -17.834618) (xy 131.188201 -17.785872) (xy 131.173474 -17.734571) (xy 131.166042 -17.681718)
			(xy 131.1656 -17.655032) (xy 130.128518 -17.655032) (xy 130.128009 -17.682918) (xy 130.119889 -17.738094)
			(xy 130.103821 -17.791501) (xy 130.080149 -17.841998) (xy 130.049376 -17.888511) (xy 130.012159 -17.930048)
			(xy 129.969291 -17.965723) (xy 129.921685 -17.994777) (xy 129.870356 -18.016589) (xy 129.816399 -18.030695)
			(xy 129.760962 -18.036795) (xy 129.705228 -18.034758) (xy 129.650385 -18.024628) (xy 129.597601 -18.006621)
			(xy 129.548001 -17.98112) (xy 129.502643 -17.948669) (xy 129.462494 -17.90996) (xy 129.428408 -17.865817)
			(xy 129.401112 -17.817182) (xy 129.381189 -17.765091) (xy 129.369063 -17.710654) (xy 129.364992 -17.655032)
			(xy 111.89462 -17.655032) (xy 111.89462 -19.337528) (xy 124.009402 -19.337528) (xy 124.013473 -19.281906)
			(xy 124.025599 -19.227469) (xy 124.045522 -19.175378) (xy 124.072818 -19.126743) (xy 124.106904 -19.0826)
			(xy 124.147053 -19.043891) (xy 124.192411 -19.01144) (xy 124.242011 -18.985939) (xy 124.294795 -18.967932)
			(xy 124.349638 -18.957802) (xy 124.405372 -18.955765) (xy 124.460809 -18.961865) (xy 124.514766 -18.975971)
			(xy 124.566095 -18.997783) (xy 124.613701 -19.026837) (xy 124.656569 -19.062512) (xy 124.693786 -19.104049)
			(xy 124.724559 -19.150562) (xy 124.730047 -19.162268) (xy 146.399502 -19.162268) (xy 146.403573 -19.106646)
			(xy 146.415699 -19.052209) (xy 146.435622 -19.000118) (xy 146.462918 -18.951483) (xy 146.497004 -18.90734)
			(xy 146.537153 -18.868631) (xy 146.582511 -18.83618) (xy 146.632111 -18.810679) (xy 146.684895 -18.792672)
			(xy 146.739738 -18.782542) (xy 146.795472 -18.780505) (xy 146.850909 -18.786605) (xy 146.904866 -18.800711)
			(xy 146.956195 -18.822523) (xy 147.003801 -18.851577) (xy 147.046669 -18.887252) (xy 147.083886 -18.928789)
			(xy 147.114659 -18.975302) (xy 147.138331 -19.025799) (xy 147.154399 -19.079206) (xy 147.162519 -19.134382)
			(xy 147.163028 -19.162268) (xy 147.162519 -19.190154) (xy 147.154399 -19.24533) (xy 147.138331 -19.298737)
			(xy 147.114659 -19.349234) (xy 147.083886 -19.395747) (xy 147.046669 -19.437284) (xy 147.003801 -19.472959)
			(xy 146.956195 -19.502013) (xy 146.90693 -19.522948) (xy 152.328372 -19.522948) (xy 152.328898 -19.494031)
			(xy 152.337621 -19.436859) (xy 152.354876 -19.381659) (xy 152.380266 -19.329697) (xy 152.41321 -19.282163)
			(xy 152.452952 -19.240147) (xy 152.475438 -19.221958) (xy 152.4872 -19.212011) (xy 152.504727 -19.186703)
			(xy 152.513913 -19.157321) (xy 152.513921 -19.126537) (xy 152.504753 -19.09715) (xy 152.487241 -19.071832)
			(xy 152.475438 -19.061938) (xy 152.452981 -19.043716) (xy 152.413242 -19.001704) (xy 152.380299 -18.954176)
			(xy 152.354906 -18.90222) (xy 152.337644 -18.847028) (xy 152.32891 -18.789862) (xy 152.328372 -18.760948)
			(xy 152.328858 -18.733697) (xy 152.336614 -18.679749) (xy 152.351969 -18.627454) (xy 152.374611 -18.577877)
			(xy 152.404077 -18.532027) (xy 152.439768 -18.490836) (xy 152.480959 -18.455145) (xy 152.526809 -18.425679)
			(xy 152.576386 -18.403037) (xy 152.628681 -18.387682) (xy 152.682629 -18.379926) (xy 152.737131 -18.379926)
			(xy 152.791079 -18.387682) (xy 152.843374 -18.403037) (xy 152.892951 -18.425679) (xy 152.938801 -18.455145)
			(xy 152.979992 -18.490836) (xy 153.015683 -18.532027) (xy 153.045149 -18.577877) (xy 153.067791 -18.627454)
			(xy 153.083146 -18.679749) (xy 153.090902 -18.733697) (xy 153.091162 -18.748248) (xy 155.871672 -18.748248)
			(xy 155.872158 -18.720997) (xy 155.879914 -18.667049) (xy 155.895269 -18.614754) (xy 155.917911 -18.565177)
			(xy 155.947377 -18.519327) (xy 155.983068 -18.478136) (xy 156.024259 -18.442445) (xy 156.070109 -18.412979)
			(xy 156.119686 -18.390337) (xy 156.171981 -18.374982) (xy 156.225929 -18.367226) (xy 156.280431 -18.367226)
			(xy 156.334379 -18.374982) (xy 156.386674 -18.390337) (xy 156.436251 -18.412979) (xy 156.482101 -18.442445)
			(xy 156.523292 -18.478136) (xy 156.558983 -18.519327) (xy 156.588449 -18.565177) (xy 156.611091 -18.614754)
			(xy 156.626446 -18.667049) (xy 156.634202 -18.720997) (xy 156.634688 -18.748248) (xy 156.634151 -18.777331)
			(xy 156.625321 -18.834823) (xy 156.607873 -18.89031) (xy 156.58221 -18.942509) (xy 156.548926 -18.990211)
			(xy 156.508793 -19.032312) (xy 156.486098 -19.050508) (xy 156.475655 -19.059117) (xy 156.459305 -19.080669)
			(xy 156.449207 -19.105765) (xy 156.446071 -19.132635) (xy 156.45012 -19.159382) (xy 156.461068 -19.184119)
			(xy 156.478142 -19.205102) (xy 156.488892 -19.213322) (xy 156.509581 -19.228756) (xy 156.547007 -19.264302)
			(xy 156.579299 -19.304569) (xy 156.605869 -19.348822) (xy 156.626231 -19.396252) (xy 156.640013 -19.445994)
			(xy 156.646965 -19.49714) (xy 156.647388 -19.522948) (xy 156.646902 -19.550199) (xy 156.639146 -19.604147)
			(xy 156.623791 -19.656442) (xy 156.601149 -19.706019) (xy 156.571683 -19.751869) (xy 156.535992 -19.79306)
			(xy 156.494801 -19.828751) (xy 156.448951 -19.858217) (xy 156.399374 -19.880859) (xy 156.347079 -19.896214)
			(xy 156.293131 -19.90397) (xy 156.238629 -19.90397) (xy 156.184681 -19.896214) (xy 156.132386 -19.880859)
			(xy 156.082809 -19.858217) (xy 156.036959 -19.828751) (xy 155.995768 -19.79306) (xy 155.960077 -19.751869)
			(xy 155.930611 -19.706019) (xy 155.907969 -19.656442) (xy 155.892614 -19.604147) (xy 155.884858 -19.550199)
			(xy 155.884372 -19.522948) (xy 155.884922 -19.493866) (xy 155.893751 -19.436375) (xy 155.911198 -19.380889)
			(xy 155.936858 -19.328691) (xy 155.970139 -19.280988) (xy 156.010269 -19.238885) (xy 156.032962 -19.220688)
			(xy 156.043413 -19.212087) (xy 156.059769 -19.190535) (xy 156.069872 -19.165436) (xy 156.073009 -19.138563)
			(xy 156.068958 -19.111812) (xy 156.058004 -19.087073) (xy 156.040922 -19.066092) (xy 156.030168 -19.057874)
			(xy 156.009468 -19.042454) (xy 155.972045 -19.006904) (xy 155.939755 -18.966634) (xy 155.913187 -18.922379)
			(xy 155.892827 -18.874947) (xy 155.879046 -18.825204) (xy 155.872095 -18.774057) (xy 155.871672 -18.748248)
			(xy 153.091162 -18.748248) (xy 153.091388 -18.760948) (xy 153.090837 -18.789864) (xy 153.082115 -18.847034)
			(xy 153.064864 -18.902232) (xy 153.039479 -18.954194) (xy 153.006541 -19.001729) (xy 152.966805 -19.043747)
			(xy 152.944322 -19.061938) (xy 152.932468 -19.071782) (xy 152.914949 -19.09712) (xy 152.905778 -19.126527)
			(xy 152.905787 -19.157331) (xy 152.914976 -19.186733) (xy 152.932509 -19.212061) (xy 152.944322 -19.221958)
			(xy 152.96679 -19.240167) (xy 153.006525 -19.282184) (xy 153.039465 -19.329715) (xy 153.064856 -19.381673)
			(xy 153.082116 -19.436867) (xy 153.09085 -19.494033) (xy 153.091388 -19.522948) (xy 153.090902 -19.550199)
			(xy 153.083146 -19.604147) (xy 153.067791 -19.656442) (xy 153.045149 -19.706019) (xy 153.015683 -19.751869)
			(xy 152.979992 -19.79306) (xy 152.938801 -19.828751) (xy 152.892951 -19.858217) (xy 152.843374 -19.880859)
			(xy 152.791079 -19.896214) (xy 152.737131 -19.90397) (xy 152.682629 -19.90397) (xy 152.628681 -19.896214)
			(xy 152.576386 -19.880859) (xy 152.526809 -19.858217) (xy 152.480959 -19.828751) (xy 152.439768 -19.79306)
			(xy 152.404077 -19.751869) (xy 152.374611 -19.706019) (xy 152.351969 -19.656442) (xy 152.336614 -19.604147)
			(xy 152.328858 -19.550199) (xy 152.328372 -19.522948) (xy 146.90693 -19.522948) (xy 146.904866 -19.523825)
			(xy 146.850909 -19.537931) (xy 146.795472 -19.544031) (xy 146.739738 -19.541994) (xy 146.684895 -19.531864)
			(xy 146.632111 -19.513857) (xy 146.582511 -19.488356) (xy 146.537153 -19.455905) (xy 146.497004 -19.417196)
			(xy 146.462918 -19.373053) (xy 146.435622 -19.324418) (xy 146.415699 -19.272327) (xy 146.403573 -19.21789)
			(xy 146.399502 -19.162268) (xy 124.730047 -19.162268) (xy 124.748231 -19.201059) (xy 124.764299 -19.254466)
			(xy 124.772419 -19.309642) (xy 124.772928 -19.337528) (xy 124.772419 -19.365414) (xy 124.764299 -19.42059)
			(xy 124.748231 -19.473997) (xy 124.724559 -19.524494) (xy 124.693786 -19.571007) (xy 124.656569 -19.612544)
			(xy 124.613701 -19.648219) (xy 124.566095 -19.677273) (xy 124.514766 -19.699085) (xy 124.460809 -19.713191)
			(xy 124.405372 -19.719291) (xy 124.349638 -19.717254) (xy 124.294795 -19.707124) (xy 124.242011 -19.689117)
			(xy 124.192411 -19.663616) (xy 124.147053 -19.631165) (xy 124.106904 -19.592456) (xy 124.072818 -19.548313)
			(xy 124.045522 -19.499678) (xy 124.025599 -19.447587) (xy 124.013473 -19.39315) (xy 124.009402 -19.337528)
			(xy 111.89462 -19.337528) (xy 111.89462 -20.010628) (xy 115.078254 -20.010628) (xy 115.082325 -19.955006)
			(xy 115.094451 -19.900569) (xy 115.114374 -19.848478) (xy 115.14167 -19.799843) (xy 115.175756 -19.7557)
			(xy 115.215905 -19.716991) (xy 115.261263 -19.68454) (xy 115.310863 -19.659039) (xy 115.363647 -19.641032)
			(xy 115.41849 -19.630902) (xy 115.474224 -19.628865) (xy 115.529661 -19.634965) (xy 115.583618 -19.649071)
			(xy 115.634947 -19.670883) (xy 115.682553 -19.699937) (xy 115.725421 -19.735612) (xy 115.762638 -19.777149)
			(xy 115.793411 -19.823662) (xy 115.817083 -19.874159) (xy 115.829102 -19.914108) (xy 127.405382 -19.914108)
			(xy 127.409453 -19.858486) (xy 127.421579 -19.804049) (xy 127.441502 -19.751958) (xy 127.468798 -19.703323)
			(xy 127.502884 -19.65918) (xy 127.543033 -19.620471) (xy 127.588391 -19.58802) (xy 127.637991 -19.562519)
			(xy 127.690775 -19.544512) (xy 127.745618 -19.534382) (xy 127.801352 -19.532345) (xy 127.856789 -19.538445)
			(xy 127.910746 -19.552551) (xy 127.962075 -19.574363) (xy 128.009681 -19.603417) (xy 128.052549 -19.639092)
			(xy 128.089766 -19.680629) (xy 128.120539 -19.727142) (xy 128.144211 -19.777639) (xy 128.160279 -19.831046)
			(xy 128.168399 -19.886222) (xy 128.168908 -19.914108) (xy 128.168862 -19.916648) (xy 129.165602 -19.916648)
			(xy 129.169673 -19.861026) (xy 129.181799 -19.806589) (xy 129.201722 -19.754498) (xy 129.229018 -19.705863)
			(xy 129.263104 -19.66172) (xy 129.303253 -19.623011) (xy 129.348611 -19.59056) (xy 129.398211 -19.565059)
			(xy 129.450995 -19.547052) (xy 129.505838 -19.536922) (xy 129.561572 -19.534885) (xy 129.617009 -19.540985)
			(xy 129.670966 -19.555091) (xy 129.722295 -19.576903) (xy 129.769901 -19.605957) (xy 129.812769 -19.641632)
			(xy 129.838654 -19.670522) (xy 138.361928 -19.670522) (xy 138.362414 -19.643271) (xy 138.37017 -19.589323)
			(xy 138.385525 -19.537028) (xy 138.408167 -19.487451) (xy 138.437633 -19.441601) (xy 138.473324 -19.40041)
			(xy 138.514515 -19.364719) (xy 138.560365 -19.335253) (xy 138.609942 -19.312611) (xy 138.662237 -19.297256)
			(xy 138.716185 -19.2895) (xy 138.770687 -19.2895) (xy 138.824635 -19.297256) (xy 138.87693 -19.312611)
			(xy 138.926507 -19.335253) (xy 138.972357 -19.364719) (xy 139.013548 -19.40041) (xy 139.049239 -19.441601)
			(xy 139.078705 -19.487451) (xy 139.101347 -19.537028) (xy 139.116702 -19.589323) (xy 139.124458 -19.643271)
			(xy 139.124944 -19.670522) (xy 139.124848 -19.683645) (xy 139.123071 -19.709831) (xy 139.121388 -19.722846)
			(xy 139.120556 -19.731962) (xy 139.124615 -19.749796) (xy 139.134685 -19.765065) (xy 139.149479 -19.77582)
			(xy 139.167109 -19.780688) (xy 139.176252 -19.78025) (xy 139.20978 -19.77898) (xy 140.07338 -19.77898)
			(xy 140.11021 -19.780758) (xy 140.11941 -19.781185) (xy 140.137165 -19.776365) (xy 140.152068 -19.765576)
			(xy 140.16219 -19.750213) (xy 140.166225 -19.732263) (xy 140.165328 -19.7231) (xy 140.163652 -19.71002)
			(xy 140.161871 -19.683708) (xy 140.161772 -19.670522) (xy 140.162258 -19.643271) (xy 140.170014 -19.589323)
			(xy 140.185369 -19.537028) (xy 140.208011 -19.487451) (xy 140.237477 -19.441601) (xy 140.273168 -19.40041)
			(xy 140.314359 -19.364719) (xy 140.360209 -19.335253) (xy 140.409786 -19.312611) (xy 140.462081 -19.297256)
			(xy 140.516029 -19.2895) (xy 140.570531 -19.2895) (xy 140.624479 -19.297256) (xy 140.676774 -19.312611)
			(xy 140.726351 -19.335253) (xy 140.772201 -19.364719) (xy 140.813392 -19.40041) (xy 140.849083 -19.441601)
			(xy 140.878549 -19.487451) (xy 140.901191 -19.537028) (xy 140.916546 -19.589323) (xy 140.924302 -19.643271)
			(xy 140.924788 -19.670522) (xy 140.924353 -19.697294) (xy 140.916837 -19.75031) (xy 140.901984 -19.801754)
			(xy 140.880086 -19.850617) (xy 140.851572 -19.895939) (xy 140.817003 -19.93683) (xy 140.777057 -19.972487)
			(xy 140.732519 -20.00221) (xy 140.684264 -20.025416) (xy 140.633238 -20.041648) (xy 140.580444 -20.050588)
			(xy 140.553694 -20.051776) (xy 140.540498 -20.052601) (xy 140.515154 -20.060088) (xy 140.492583 -20.073832)
			(xy 140.474296 -20.09291) (xy 140.461521 -20.116044) (xy 140.455113 -20.141682) (xy 140.454888 -20.1549)
			(xy 140.454888 -20.160488) (xy 140.454433 -20.187741) (xy 140.446678 -20.241694) (xy 140.431322 -20.293993)
			(xy 140.40868 -20.343574) (xy 140.379211 -20.389429) (xy 140.343516 -20.430622) (xy 140.302322 -20.466316)
			(xy 140.256467 -20.495783) (xy 140.206885 -20.518425) (xy 140.154586 -20.533779) (xy 140.100633 -20.541534)
			(xy 140.07338 -20.541996) (xy 139.20978 -20.541996) (xy 139.182528 -20.541541) (xy 139.128578 -20.533781)
			(xy 139.076282 -20.518423) (xy 139.026704 -20.495779) (xy 138.980853 -20.466309) (xy 138.939663 -20.430614)
			(xy 138.903972 -20.389421) (xy 138.874506 -20.343568) (xy 138.851866 -20.293988) (xy 138.836512 -20.24169)
			(xy 138.828757 -20.18774) (xy 138.828272 -20.160488) (xy 138.828272 -20.1549) (xy 138.828067 -20.141738)
			(xy 138.821738 -20.116197) (xy 138.809088 -20.093124) (xy 138.790957 -20.074054) (xy 138.768552 -20.060255)
			(xy 138.743362 -20.052646) (xy 138.730228 -20.051776) (xy 138.703611 -20.050381) (xy 138.651118 -20.041144)
			(xy 138.600422 -20.024689) (xy 138.552511 -20.001338) (xy 138.508316 -19.971545) (xy 138.468699 -19.93589)
			(xy 138.434431 -19.895068) (xy 138.406179 -19.849872) (xy 138.384493 -19.801184) (xy 138.369796 -19.749951)
			(xy 138.362373 -19.697172) (xy 138.361928 -19.670522) (xy 129.838654 -19.670522) (xy 129.849986 -19.683169)
			(xy 129.880759 -19.729682) (xy 129.904431 -19.780179) (xy 129.920499 -19.833586) (xy 129.928619 -19.888762)
			(xy 129.929128 -19.916648) (xy 129.928619 -19.944534) (xy 129.920499 -19.99971) (xy 129.904431 -20.053117)
			(xy 129.880759 -20.103614) (xy 129.849986 -20.150127) (xy 129.812769 -20.191664) (xy 129.769901 -20.227339)
			(xy 129.722295 -20.256393) (xy 129.670966 -20.278205) (xy 129.617009 -20.292311) (xy 129.561572 -20.298411)
			(xy 129.505838 -20.296374) (xy 129.450995 -20.286244) (xy 129.398211 -20.268237) (xy 129.348611 -20.242736)
			(xy 129.303253 -20.210285) (xy 129.263104 -20.171576) (xy 129.229018 -20.127433) (xy 129.201722 -20.078798)
			(xy 129.181799 -20.026707) (xy 129.169673 -19.97227) (xy 129.165602 -19.916648) (xy 128.168862 -19.916648)
			(xy 128.168399 -19.941994) (xy 128.160279 -19.99717) (xy 128.144211 -20.050577) (xy 128.120539 -20.101074)
			(xy 128.089766 -20.147587) (xy 128.052549 -20.189124) (xy 128.009681 -20.224799) (xy 127.962075 -20.253853)
			(xy 127.910746 -20.275665) (xy 127.856789 -20.289771) (xy 127.801352 -20.295871) (xy 127.745618 -20.293834)
			(xy 127.690775 -20.283704) (xy 127.637991 -20.265697) (xy 127.588391 -20.240196) (xy 127.543033 -20.207745)
			(xy 127.502884 -20.169036) (xy 127.468798 -20.124893) (xy 127.441502 -20.076258) (xy 127.421579 -20.024167)
			(xy 127.409453 -19.96973) (xy 127.405382 -19.914108) (xy 115.829102 -19.914108) (xy 115.833151 -19.927566)
			(xy 115.841271 -19.982742) (xy 115.84178 -20.010628) (xy 115.841271 -20.038514) (xy 115.833151 -20.09369)
			(xy 115.817083 -20.147097) (xy 115.793411 -20.197594) (xy 115.762638 -20.244107) (xy 115.725421 -20.285644)
			(xy 115.682553 -20.321319) (xy 115.634947 -20.350373) (xy 115.583618 -20.372185) (xy 115.529661 -20.386291)
			(xy 115.474224 -20.392391) (xy 115.41849 -20.390354) (xy 115.363647 -20.380224) (xy 115.310863 -20.362217)
			(xy 115.261263 -20.336716) (xy 115.215905 -20.304265) (xy 115.175756 -20.265556) (xy 115.14167 -20.221413)
			(xy 115.114374 -20.172778) (xy 115.094451 -20.120687) (xy 115.082325 -20.06625) (xy 115.078254 -20.010628)
			(xy 111.89462 -20.010628) (xy 111.89462 -21.232114) (xy 149.650702 -21.232114) (xy 149.654773 -21.176492)
			(xy 149.666899 -21.122055) (xy 149.686822 -21.069964) (xy 149.714118 -21.021329) (xy 149.748204 -20.977186)
			(xy 149.788353 -20.938477) (xy 149.833711 -20.906026) (xy 149.883311 -20.880525) (xy 149.936095 -20.862518)
			(xy 149.990938 -20.852388) (xy 150.046672 -20.850351) (xy 150.102109 -20.856451) (xy 150.156066 -20.870557)
			(xy 150.207395 -20.892369) (xy 150.255001 -20.921423) (xy 150.297869 -20.957098) (xy 150.335086 -20.998635)
			(xy 150.365859 -21.045148) (xy 150.389531 -21.095645) (xy 150.405599 -21.149052) (xy 150.413719 -21.204228)
			(xy 150.414228 -21.232114) (xy 150.413719 -21.26) (xy 150.405599 -21.315176) (xy 150.389531 -21.368583)
			(xy 150.365859 -21.41908) (xy 150.335086 -21.465593) (xy 150.323299 -21.478748) (xy 153.547062 -21.478748)
			(xy 153.551133 -21.423126) (xy 153.563259 -21.368689) (xy 153.583182 -21.316598) (xy 153.610478 -21.267963)
			(xy 153.644564 -21.22382) (xy 153.684713 -21.185111) (xy 153.730071 -21.15266) (xy 153.779671 -21.127159)
			(xy 153.832455 -21.109152) (xy 153.887298 -21.099022) (xy 153.943032 -21.096985) (xy 153.998469 -21.103085)
			(xy 154.052426 -21.117191) (xy 154.103755 -21.139003) (xy 154.151361 -21.168057) (xy 154.194229 -21.203732)
			(xy 154.231446 -21.245269) (xy 154.262219 -21.291782) (xy 154.285891 -21.342279) (xy 154.301959 -21.395686)
			(xy 154.310079 -21.450862) (xy 154.310588 -21.478748) (xy 154.310079 -21.506634) (xy 154.301959 -21.56181)
			(xy 154.285891 -21.615217) (xy 154.262219 -21.665714) (xy 154.231446 -21.712227) (xy 154.194229 -21.753764)
			(xy 154.151361 -21.789439) (xy 154.103755 -21.818493) (xy 154.052426 -21.840305) (xy 153.998469 -21.854411)
			(xy 153.943032 -21.860511) (xy 153.887298 -21.858474) (xy 153.832455 -21.848344) (xy 153.779671 -21.830337)
			(xy 153.730071 -21.804836) (xy 153.684713 -21.772385) (xy 153.644564 -21.733676) (xy 153.610478 -21.689533)
			(xy 153.583182 -21.640898) (xy 153.563259 -21.588807) (xy 153.551133 -21.53437) (xy 153.547062 -21.478748)
			(xy 150.323299 -21.478748) (xy 150.297869 -21.50713) (xy 150.255001 -21.542805) (xy 150.207395 -21.571859)
			(xy 150.156066 -21.593671) (xy 150.102109 -21.607777) (xy 150.046672 -21.613877) (xy 149.990938 -21.61184)
			(xy 149.936095 -21.60171) (xy 149.883311 -21.583703) (xy 149.833711 -21.558202) (xy 149.788353 -21.525751)
			(xy 149.748204 -21.487042) (xy 149.714118 -21.442899) (xy 149.686822 -21.394264) (xy 149.666899 -21.342173)
			(xy 149.654773 -21.287736) (xy 149.650702 -21.232114) (xy 111.89462 -21.232114) (xy 111.89462 -22.394418)
			(xy 125.85649 -22.394418) (xy 125.860561 -22.338796) (xy 125.872687 -22.284359) (xy 125.89261 -22.232268)
			(xy 125.919906 -22.183633) (xy 125.953992 -22.13949) (xy 125.994141 -22.100781) (xy 126.039499 -22.06833)
			(xy 126.089099 -22.042829) (xy 126.141883 -22.024822) (xy 126.196726 -22.014692) (xy 126.25246 -22.012655)
			(xy 126.307897 -22.018755) (xy 126.361854 -22.032861) (xy 126.413183 -22.054673) (xy 126.460789 -22.083727)
			(xy 126.503657 -22.119402) (xy 126.540874 -22.160939) (xy 126.571647 -22.207452) (xy 126.595319 -22.257949)
			(xy 126.611387 -22.311356) (xy 126.619507 -22.366532) (xy 126.620016 -22.394418) (xy 126.619507 -22.422304)
			(xy 126.611387 -22.47748) (xy 126.595319 -22.530887) (xy 126.571647 -22.581384) (xy 126.540874 -22.627897)
			(xy 126.503657 -22.669434) (xy 126.460789 -22.705109) (xy 126.413183 -22.734163) (xy 126.361854 -22.755975)
			(xy 126.307897 -22.770081) (xy 126.25246 -22.776181) (xy 126.196726 -22.774144) (xy 126.141883 -22.764014)
			(xy 126.089099 -22.746007) (xy 126.039499 -22.720506) (xy 125.994141 -22.688055) (xy 125.953992 -22.649346)
			(xy 125.919906 -22.605203) (xy 125.89261 -22.556568) (xy 125.872687 -22.504477) (xy 125.860561 -22.45004)
			(xy 125.85649 -22.394418) (xy 111.89462 -22.394418) (xy 111.89462 -23.586948) (xy 111.901521 -23.593849)
			(xy 129.311406 -23.593849) (xy 129.311406 -23.539351) (xy 129.319162 -23.485407) (xy 129.334516 -23.433116)
			(xy 129.357156 -23.383543) (xy 129.38662 -23.337696) (xy 129.422309 -23.296509) (xy 129.463496 -23.26082)
			(xy 129.509343 -23.231356) (xy 129.558916 -23.208716) (xy 129.611207 -23.193362) (xy 129.665151 -23.185606)
			(xy 129.6924 -23.18512) (xy 129.721283 -23.185678) (xy 129.778387 -23.194398) (xy 129.833525 -23.211625)
			(xy 129.885438 -23.236964) (xy 129.932939 -23.269837) (xy 129.974943 -23.309492) (xy 129.993136 -23.331932)
			(xy 130.002985 -23.343667) (xy 130.028144 -23.361126) (xy 130.05734 -23.370367) (xy 130.087963 -23.370563)
			(xy 130.117275 -23.361697) (xy 130.142655 -23.344561) (xy 130.152648 -23.332948) (xy 130.170899 -23.311004)
			(xy 130.212749 -23.272199) (xy 130.259912 -23.240059) (xy 130.311336 -23.215304) (xy 130.365873 -23.198483)
			(xy 130.422308 -23.189974) (xy 130.450844 -23.189438) (xy 130.477201 -23.189864) (xy 130.529412 -23.197138)
			(xy 130.580126 -23.211527) (xy 130.628376 -23.232759) (xy 130.673246 -23.260429) (xy 130.713881 -23.294009)
			(xy 130.732022 -23.313136) (xy 130.741174 -23.322507) (xy 130.763202 -23.336663) (xy 130.788111 -23.344735)
			(xy 130.814254 -23.346191) (xy 130.839905 -23.340935) (xy 130.863369 -23.329313) (xy 130.8735 -23.32101)
			(xy 130.894416 -23.303406) (xy 130.940356 -23.273769) (xy 130.990056 -23.250995) (xy 131.042499 -23.23555)
			(xy 131.096609 -23.22775) (xy 131.123944 -23.227284) (xy 131.151193 -23.227789) (xy 131.205134 -23.23555)
			(xy 131.257423 -23.250909) (xy 131.306993 -23.273552) (xy 131.352837 -23.303019) (xy 131.394022 -23.33871)
			(xy 131.429708 -23.379898) (xy 131.459169 -23.425745) (xy 131.481807 -23.475318) (xy 131.497159 -23.527609)
			(xy 131.504914 -23.581551) (xy 131.504914 -23.636049) (xy 131.497159 -23.689991) (xy 131.481807 -23.742282)
			(xy 131.459169 -23.791855) (xy 131.429708 -23.837702) (xy 131.394022 -23.87889) (xy 131.352837 -23.914581)
			(xy 131.306993 -23.944048) (xy 131.257423 -23.966691) (xy 131.205134 -23.98205) (xy 131.151193 -23.989811)
			(xy 131.123944 -23.9903) (xy 131.097588 -23.989835) (xy 131.045378 -23.982572) (xy 130.994664 -23.968191)
			(xy 130.946413 -23.946967) (xy 130.901543 -23.919304) (xy 130.860907 -23.885727) (xy 130.842766 -23.866602)
			(xy 130.833626 -23.85722) (xy 130.811592 -23.843074) (xy 130.786681 -23.835007) (xy 130.760538 -23.833554)
			(xy 130.734886 -23.83881) (xy 130.711421 -23.850428) (xy 130.701288 -23.858728) (xy 130.680381 -23.876344)
			(xy 130.634439 -23.905978) (xy 130.584736 -23.928749) (xy 130.532291 -23.944192) (xy 130.478179 -23.951989)
			(xy 130.450844 -23.952454) (xy 130.421962 -23.951875) (xy 130.364858 -23.94316) (xy 130.30972 -23.925939)
			(xy 130.257807 -23.900604) (xy 130.210306 -23.867734) (xy 130.168301 -23.828081) (xy 130.150108 -23.805642)
			(xy 130.140214 -23.793944) (xy 130.115071 -23.776472) (xy 130.085884 -23.767219) (xy 130.055266 -23.767015)
			(xy 130.025959 -23.775877) (xy 130.000584 -23.793013) (xy 129.990596 -23.804626) (xy 129.972394 -23.826612)
			(xy 129.930532 -23.865411) (xy 129.883358 -23.897543) (xy 129.831925 -23.922291) (xy 129.777379 -23.939103)
			(xy 129.720939 -23.947604) (xy 129.6924 -23.948136) (xy 129.665151 -23.947594) (xy 129.611207 -23.939838)
			(xy 129.558916 -23.924484) (xy 129.509343 -23.901844) (xy 129.463496 -23.87238) (xy 129.422309 -23.836691)
			(xy 129.38662 -23.795504) (xy 129.357156 -23.749657) (xy 129.334516 -23.700084) (xy 129.319162 -23.647793)
			(xy 129.311406 -23.593849) (xy 111.901521 -23.593849) (xy 112.72012 -24.412448) (xy 126.193802 -24.412448)
			(xy 126.197873 -24.356826) (xy 126.209999 -24.302389) (xy 126.229922 -24.250298) (xy 126.257218 -24.201663)
			(xy 126.291304 -24.15752) (xy 126.331453 -24.118811) (xy 126.376811 -24.08636) (xy 126.426411 -24.060859)
			(xy 126.479195 -24.042852) (xy 126.534038 -24.032722) (xy 126.589772 -24.030685) (xy 126.645209 -24.036785)
			(xy 126.699166 -24.050891) (xy 126.750495 -24.072703) (xy 126.798101 -24.101757) (xy 126.840969 -24.137432)
			(xy 126.878186 -24.178969) (xy 126.908959 -24.225482) (xy 126.932631 -24.275979) (xy 126.948699 -24.329386)
			(xy 126.956819 -24.384562) (xy 126.957328 -24.412448) (xy 126.956819 -24.440334) (xy 126.948699 -24.49551)
			(xy 126.932631 -24.548917) (xy 126.908959 -24.599414) (xy 126.878186 -24.645927) (xy 126.840969 -24.687464)
			(xy 126.798101 -24.723139) (xy 126.750495 -24.752193) (xy 126.699166 -24.774005) (xy 126.645209 -24.788111)
			(xy 126.589772 -24.794211) (xy 126.534038 -24.792174) (xy 126.479195 -24.782044) (xy 126.426411 -24.764037)
			(xy 126.376811 -24.738536) (xy 126.331453 -24.706085) (xy 126.291304 -24.667376) (xy 126.257218 -24.623233)
			(xy 126.229922 -24.574598) (xy 126.209999 -24.522507) (xy 126.197873 -24.46807) (xy 126.193802 -24.412448)
			(xy 112.72012 -24.412448) (xy 113.23701 -24.929338) (xy 133.555232 -24.929338) (xy 133.555232 -24.065738)
			(xy 133.555759 -24.038481) (xy 133.563509 -23.984522) (xy 133.578856 -23.932214) (xy 133.601489 -23.882621)
			(xy 133.630947 -23.836752) (xy 133.66663 -23.795541) (xy 133.707814 -23.759825) (xy 133.753659 -23.730332)
			(xy 133.803234 -23.70766) (xy 133.85553 -23.692272) (xy 133.909484 -23.68448) (xy 133.93674 -23.683976)
			(xy 133.942328 -23.68423) (xy 133.955493 -23.68409) (xy 133.981042 -23.677751) (xy 134.004119 -23.665089)
			(xy 134.02319 -23.646945) (xy 134.036985 -23.624527) (xy 134.044587 -23.599325) (xy 134.045452 -23.586186)
			(xy 134.046871 -23.55957) (xy 134.056102 -23.507076) (xy 134.07255 -23.456379) (xy 134.095897 -23.408466)
			(xy 134.125687 -23.364269) (xy 134.16134 -23.324651) (xy 134.202161 -23.290382) (xy 134.247356 -23.262129)
			(xy 134.296044 -23.240444) (xy 134.347277 -23.225749) (xy 134.400057 -23.21833) (xy 134.426706 -23.217886)
			(xy 134.453957 -23.218384) (xy 134.507903 -23.226141) (xy 134.560196 -23.241497) (xy 134.609772 -23.264138)
			(xy 134.655621 -23.293604) (xy 134.696809 -23.329295) (xy 134.7325 -23.370484) (xy 134.761965 -23.416334)
			(xy 134.784605 -23.46591) (xy 134.79996 -23.518203) (xy 134.802321 -23.534624) (xy 143.855692 -23.534624)
			(xy 143.859763 -23.479002) (xy 143.871889 -23.424565) (xy 143.891812 -23.372474) (xy 143.919108 -23.323839)
			(xy 143.953194 -23.279696) (xy 143.993343 -23.240987) (xy 144.038701 -23.208536) (xy 144.088301 -23.183035)
			(xy 144.141085 -23.165028) (xy 144.195928 -23.154898) (xy 144.251662 -23.152861) (xy 144.307099 -23.158961)
			(xy 144.361056 -23.173067) (xy 144.412385 -23.194879) (xy 144.459991 -23.223933) (xy 144.502859 -23.259608)
			(xy 144.540076 -23.301145) (xy 144.570849 -23.347658) (xy 144.594521 -23.398155) (xy 144.610589 -23.451562)
			(xy 144.618709 -23.506738) (xy 144.619218 -23.534624) (xy 144.618709 -23.56251) (xy 144.610589 -23.617686)
			(xy 144.594521 -23.671093) (xy 144.570849 -23.72159) (xy 144.540076 -23.768103) (xy 144.502859 -23.80964)
			(xy 144.459991 -23.845315) (xy 144.412385 -23.874369) (xy 144.361056 -23.896181) (xy 144.307099 -23.910287)
			(xy 144.251662 -23.916387) (xy 144.195928 -23.91435) (xy 144.141085 -23.90422) (xy 144.088301 -23.886213)
			(xy 144.038701 -23.860712) (xy 143.993343 -23.828261) (xy 143.953194 -23.789552) (xy 143.919108 -23.745409)
			(xy 143.891812 -23.696774) (xy 143.871889 -23.644683) (xy 143.859763 -23.590246) (xy 143.855692 -23.534624)
			(xy 134.802321 -23.534624) (xy 134.807716 -23.572149) (xy 134.807716 -23.626651) (xy 134.79996 -23.680597)
			(xy 134.784605 -23.73289) (xy 134.761965 -23.782466) (xy 134.7325 -23.828316) (xy 134.696809 -23.869505)
			(xy 134.655621 -23.905196) (xy 134.609772 -23.934662) (xy 134.560196 -23.957303) (xy 134.507903 -23.972659)
			(xy 134.453957 -23.980416) (xy 134.426706 -23.980902) (xy 134.413583 -23.980813) (xy 134.387397 -23.979031)
			(xy 134.374382 -23.977346) (xy 134.365265 -23.976477) (xy 134.347419 -23.980533) (xy 134.332141 -23.99061)
			(xy 134.321387 -24.005417) (xy 134.31653 -24.023062) (xy 134.316978 -24.03221) (xy 134.318248 -24.065738)
			(xy 134.318248 -24.69388) (xy 150.676862 -24.69388) (xy 150.680933 -24.638258) (xy 150.693059 -24.583821)
			(xy 150.712982 -24.53173) (xy 150.740278 -24.483095) (xy 150.774364 -24.438952) (xy 150.814513 -24.400243)
			(xy 150.859871 -24.367792) (xy 150.909471 -24.342291) (xy 150.962255 -24.324284) (xy 151.017098 -24.314154)
			(xy 151.072832 -24.312117) (xy 151.128269 -24.318217) (xy 151.182226 -24.332323) (xy 151.233555 -24.354135)
			(xy 151.281161 -24.383189) (xy 151.324029 -24.418864) (xy 151.361246 -24.460401) (xy 151.392019 -24.506914)
			(xy 151.415691 -24.557411) (xy 151.431759 -24.610818) (xy 151.439879 -24.665994) (xy 151.440388 -24.69388)
			(xy 151.439879 -24.721766) (xy 151.431759 -24.776942) (xy 151.415691 -24.830349) (xy 151.392019 -24.880846)
			(xy 151.361246 -24.927359) (xy 151.324029 -24.968896) (xy 151.281161 -25.004571) (xy 151.233555 -25.033625)
			(xy 151.182226 -25.055437) (xy 151.128269 -25.069543) (xy 151.072832 -25.075643) (xy 151.017098 -25.073606)
			(xy 150.962255 -25.063476) (xy 150.909471 -25.045469) (xy 150.859871 -25.019968) (xy 150.814513 -24.987517)
			(xy 150.774364 -24.948808) (xy 150.740278 -24.904665) (xy 150.712982 -24.85603) (xy 150.693059 -24.803939)
			(xy 150.680933 -24.749502) (xy 150.676862 -24.69388) (xy 134.318248 -24.69388) (xy 134.318248 -24.929338)
			(xy 134.31647 -24.966168) (xy 134.315958 -24.975367) (xy 134.320799 -24.993133) (xy 134.331609 -25.008038)
			(xy 134.346991 -25.018159) (xy 134.364957 -25.022188) (xy 134.374128 -25.021286) (xy 134.387207 -25.019607)
			(xy 134.41352 -25.017828) (xy 134.426706 -25.01773) (xy 134.45396 -25.01814) (xy 134.507912 -25.025898)
			(xy 134.560211 -25.041255) (xy 134.609793 -25.063899) (xy 134.655647 -25.093369) (xy 134.675934 -25.110948)
			(xy 142.111982 -25.110948) (xy 142.116053 -25.055326) (xy 142.128179 -25.000889) (xy 142.148102 -24.948798)
			(xy 142.175398 -24.900163) (xy 142.209484 -24.85602) (xy 142.249633 -24.817311) (xy 142.294991 -24.78486)
			(xy 142.344591 -24.759359) (xy 142.397375 -24.741352) (xy 142.452218 -24.731222) (xy 142.507952 -24.729185)
			(xy 142.563389 -24.735285) (xy 142.617346 -24.749391) (xy 142.668675 -24.771203) (xy 142.716281 -24.800257)
			(xy 142.759149 -24.835932) (xy 142.796366 -24.877469) (xy 142.827139 -24.923982) (xy 142.850811 -24.974479)
			(xy 142.866879 -25.027886) (xy 142.874999 -25.083062) (xy 142.875508 -25.110948) (xy 142.874999 -25.138834)
			(xy 142.866879 -25.19401) (xy 142.850811 -25.247417) (xy 142.827139 -25.297914) (xy 142.796366 -25.344427)
			(xy 142.759149 -25.385964) (xy 142.716281 -25.421639) (xy 142.668675 -25.450693) (xy 142.617346 -25.472505)
			(xy 142.563389 -25.486611) (xy 142.507952 -25.492711) (xy 142.452218 -25.490674) (xy 142.397375 -25.480544)
			(xy 142.344591 -25.462537) (xy 142.294991 -25.437036) (xy 142.249633 -25.404585) (xy 142.209484 -25.365876)
			(xy 142.175398 -25.321733) (xy 142.148102 -25.273098) (xy 142.128179 -25.221007) (xy 142.116053 -25.16657)
			(xy 142.111982 -25.110948) (xy 134.675934 -25.110948) (xy 134.696841 -25.129064) (xy 134.732535 -25.170258)
			(xy 134.762004 -25.216113) (xy 134.784647 -25.265694) (xy 134.800003 -25.317994) (xy 134.80776 -25.371946)
			(xy 134.80776 -25.426454) (xy 134.800003 -25.480406) (xy 134.784647 -25.532706) (xy 134.762004 -25.582287)
			(xy 134.732535 -25.628142) (xy 134.696841 -25.669336) (xy 134.655647 -25.705031) (xy 134.609793 -25.734501)
			(xy 134.560211 -25.757145) (xy 134.507912 -25.772502) (xy 134.45396 -25.78026) (xy 134.426706 -25.780746)
			(xy 134.399932 -25.780326) (xy 134.346914 -25.772813) (xy 134.295468 -25.757961) (xy 134.246602 -25.736063)
			(xy 134.201278 -25.707549) (xy 134.160386 -25.672978) (xy 134.124728 -25.633029) (xy 134.095005 -25.588488)
			(xy 134.071802 -25.540229) (xy 134.055573 -25.4892) (xy 134.046637 -25.436403) (xy 134.045452 -25.409652)
			(xy 134.044635 -25.396457) (xy 134.03714 -25.371116) (xy 134.023393 -25.348547) (xy 134.004314 -25.330262)
			(xy 133.981182 -25.317486) (xy 133.955546 -25.311075) (xy 133.942328 -25.310846) (xy 133.93674 -25.3111)
			(xy 133.909476 -25.310607) (xy 133.855504 -25.302848) (xy 133.803185 -25.287484) (xy 133.753588 -25.264827)
			(xy 133.707722 -25.235339) (xy 133.666522 -25.199621) (xy 133.630828 -25.1584) (xy 133.601366 -25.112517)
			(xy 133.578738 -25.062906) (xy 133.563404 -25.010579) (xy 133.555677 -24.956602) (xy 133.555232 -24.929338)
			(xy 113.23701 -24.929338) (xy 114.15268 -25.845008) (xy 127.882902 -25.845008) (xy 127.886973 -25.789386)
			(xy 127.899099 -25.734949) (xy 127.919022 -25.682858) (xy 127.946318 -25.634223) (xy 127.980404 -25.59008)
			(xy 128.020553 -25.551371) (xy 128.065911 -25.51892) (xy 128.115511 -25.493419) (xy 128.168295 -25.475412)
			(xy 128.223138 -25.465282) (xy 128.278872 -25.463245) (xy 128.334309 -25.469345) (xy 128.388266 -25.483451)
			(xy 128.439595 -25.505263) (xy 128.487201 -25.534317) (xy 128.530069 -25.569992) (xy 128.567286 -25.611529)
			(xy 128.598059 -25.658042) (xy 128.621731 -25.708539) (xy 128.637799 -25.761946) (xy 128.645919 -25.817122)
			(xy 128.646428 -25.845008) (xy 128.645919 -25.872894) (xy 128.637799 -25.92807) (xy 128.621731 -25.981477)
			(xy 128.598059 -26.031974) (xy 128.567286 -26.078487) (xy 128.530069 -26.120024) (xy 128.487201 -26.155699)
			(xy 128.439595 -26.184753) (xy 128.388266 -26.206565) (xy 128.334309 -26.220671) (xy 128.278872 -26.226771)
			(xy 128.223138 -26.224734) (xy 128.168295 -26.214604) (xy 128.115511 -26.196597) (xy 128.065911 -26.171096)
			(xy 128.020553 -26.138645) (xy 127.980404 -26.099936) (xy 127.946318 -26.055793) (xy 127.919022 -26.007158)
			(xy 127.899099 -25.955067) (xy 127.886973 -25.90063) (xy 127.882902 -25.845008) (xy 114.15268 -25.845008)
			(xy 114.530632 -26.22296) (xy 114.540284 -26.227024) (xy 114.566257 -26.238148) (xy 114.614876 -26.266932)
			(xy 114.658719 -26.30257) (xy 114.696829 -26.344282) (xy 114.728373 -26.391158) (xy 114.752661 -26.442171)
			(xy 114.769162 -26.496208) (xy 114.777516 -26.552088) (xy 114.778028 -26.580338) (xy 114.777591 -26.606534)
			(xy 114.770413 -26.658432) (xy 114.756269 -26.708608) (xy 127.009142 -26.708608) (xy 127.013213 -26.652986)
			(xy 127.025339 -26.598549) (xy 127.045262 -26.546458) (xy 127.072558 -26.497823) (xy 127.106644 -26.45368)
			(xy 127.146793 -26.414971) (xy 127.192151 -26.38252) (xy 127.241751 -26.357019) (xy 127.294535 -26.339012)
			(xy 127.349378 -26.328882) (xy 127.405112 -26.326845) (xy 127.460549 -26.332945) (xy 127.514506 -26.347051)
			(xy 127.565835 -26.368863) (xy 127.613441 -26.397917) (xy 127.656309 -26.433592) (xy 127.693526 -26.475129)
			(xy 127.696754 -26.480008) (xy 131.010152 -26.480008) (xy 131.01069 -26.452939) (xy 131.018335 -26.399343)
			(xy 131.033486 -26.347368) (xy 131.055839 -26.29806) (xy 131.084944 -26.252411) (xy 131.120215 -26.211338)
			(xy 131.160942 -26.17567) (xy 131.206306 -26.146123) (xy 131.255395 -26.123292) (xy 131.28117 -26.11501)
			(xy 131.295031 -26.110207) (xy 131.319483 -26.094028) (xy 131.33834 -26.071577) (xy 131.350053 -26.044698)
			(xy 131.353659 -26.015601) (xy 131.348862 -25.986676) (xy 131.342892 -25.973278) (xy 131.330856 -25.947214)
			(xy 131.313863 -25.892378) (xy 131.305291 -25.835613) (xy 131.304792 -25.806908) (xy 131.305278 -25.779657)
			(xy 131.313034 -25.725709) (xy 131.328389 -25.673414) (xy 131.351031 -25.623837) (xy 131.380497 -25.577987)
			(xy 131.416188 -25.536796) (xy 131.457379 -25.501105) (xy 131.503229 -25.471639) (xy 131.552806 -25.448997)
			(xy 131.605101 -25.433642) (xy 131.659049 -25.425886) (xy 131.713551 -25.425886) (xy 131.767499 -25.433642)
			(xy 131.819794 -25.448997) (xy 131.869371 -25.471639) (xy 131.915221 -25.501105) (xy 131.956412 -25.536796)
			(xy 131.992103 -25.577987) (xy 132.021569 -25.623837) (xy 132.044211 -25.673414) (xy 132.059566 -25.725709)
			(xy 132.067322 -25.779657) (xy 132.067808 -25.806908) (xy 132.067312 -25.833979) (xy 132.059664 -25.887578)
			(xy 132.044509 -25.939555) (xy 132.022152 -25.988865) (xy 131.993042 -26.034515) (xy 131.957765 -26.075587)
			(xy 131.917032 -26.111254) (xy 131.871662 -26.140799) (xy 131.822568 -26.163626) (xy 131.79679 -26.171906)
			(xy 131.782915 -26.176671) (xy 131.758465 -26.192861) (xy 131.739611 -26.215321) (xy 131.727901 -26.242206)
			(xy 131.724298 -26.271309) (xy 131.729097 -26.300238) (xy 131.735068 -26.313638) (xy 131.747107 -26.339701)
			(xy 131.7641 -26.394538) (xy 131.77267 -26.451303) (xy 131.773049 -26.47315) (xy 133.831582 -26.47315)
			(xy 133.835653 -26.417528) (xy 133.847779 -26.363091) (xy 133.867702 -26.311) (xy 133.894998 -26.262365)
			(xy 133.929084 -26.218222) (xy 133.969233 -26.179513) (xy 134.014591 -26.147062) (xy 134.064191 -26.121561)
			(xy 134.116975 -26.103554) (xy 134.171818 -26.093424) (xy 134.227552 -26.091387) (xy 134.282989 -26.097487)
			(xy 134.336946 -26.111593) (xy 134.388275 -26.133405) (xy 134.435881 -26.162459) (xy 134.478749 -26.198134)
			(xy 134.515966 -26.239671) (xy 134.523731 -26.251408) (xy 137.443462 -26.251408) (xy 137.447533 -26.195786)
			(xy 137.459659 -26.141349) (xy 137.479582 -26.089258) (xy 137.506878 -26.040623) (xy 137.540964 -25.99648)
			(xy 137.581113 -25.957771) (xy 137.626471 -25.92532) (xy 137.676071 -25.899819) (xy 137.728855 -25.881812)
			(xy 137.783698 -25.871682) (xy 137.839432 -25.869645) (xy 137.894869 -25.875745) (xy 137.948826 -25.889851)
			(xy 138.000155 -25.911663) (xy 138.047761 -25.940717) (xy 138.090629 -25.976392) (xy 138.127846 -26.017929)
			(xy 138.158619 -26.064442) (xy 138.182291 -26.114939) (xy 138.185904 -26.126948) (xy 141.603982 -26.126948)
			(xy 141.608053 -26.071326) (xy 141.620179 -26.016889) (xy 141.640102 -25.964798) (xy 141.667398 -25.916163)
			(xy 141.701484 -25.87202) (xy 141.741633 -25.833311) (xy 141.786991 -25.80086) (xy 141.836591 -25.775359)
			(xy 141.889375 -25.757352) (xy 141.944218 -25.747222) (xy 141.999952 -25.745185) (xy 142.055389 -25.751285)
			(xy 142.109346 -25.765391) (xy 142.160675 -25.787203) (xy 142.208281 -25.816257) (xy 142.251149 -25.851932)
			(xy 142.288366 -25.893469) (xy 142.319139 -25.939982) (xy 142.342811 -25.990479) (xy 142.358879 -26.043886)
			(xy 142.366999 -26.099062) (xy 142.367508 -26.126948) (xy 144.436082 -26.126948) (xy 144.440153 -26.071326)
			(xy 144.452279 -26.016889) (xy 144.472202 -25.964798) (xy 144.499498 -25.916163) (xy 144.533584 -25.87202)
			(xy 144.573733 -25.833311) (xy 144.619091 -25.80086) (xy 144.668691 -25.775359) (xy 144.721475 -25.757352)
			(xy 144.776318 -25.747222) (xy 144.832052 -25.745185) (xy 144.887489 -25.751285) (xy 144.941446 -25.765391)
			(xy 144.992775 -25.787203) (xy 145.040381 -25.816257) (xy 145.083249 -25.851932) (xy 145.120466 -25.893469)
			(xy 145.151239 -25.939982) (xy 145.174911 -25.990479) (xy 145.190979 -26.043886) (xy 145.199099 -26.099062)
			(xy 145.199608 -26.126948) (xy 145.199099 -26.154834) (xy 145.190979 -26.21001) (xy 145.174911 -26.263417)
			(xy 145.151239 -26.313914) (xy 145.120466 -26.360427) (xy 145.083249 -26.401964) (xy 145.040381 -26.437639)
			(xy 144.992775 -26.466693) (xy 144.941446 -26.488505) (xy 144.887489 -26.502611) (xy 144.832052 -26.508711)
			(xy 144.776318 -26.506674) (xy 144.721475 -26.496544) (xy 144.668691 -26.478537) (xy 144.619091 -26.453036)
			(xy 144.573733 -26.420585) (xy 144.533584 -26.381876) (xy 144.499498 -26.337733) (xy 144.472202 -26.289098)
			(xy 144.452279 -26.237007) (xy 144.440153 -26.18257) (xy 144.436082 -26.126948) (xy 142.367508 -26.126948)
			(xy 142.366999 -26.154834) (xy 142.358879 -26.21001) (xy 142.342811 -26.263417) (xy 142.319139 -26.313914)
			(xy 142.288366 -26.360427) (xy 142.251149 -26.401964) (xy 142.208281 -26.437639) (xy 142.160675 -26.466693)
			(xy 142.109346 -26.488505) (xy 142.055389 -26.502611) (xy 141.999952 -26.508711) (xy 141.944218 -26.506674)
			(xy 141.889375 -26.496544) (xy 141.836591 -26.478537) (xy 141.786991 -26.453036) (xy 141.741633 -26.420585)
			(xy 141.701484 -26.381876) (xy 141.667398 -26.337733) (xy 141.640102 -26.289098) (xy 141.620179 -26.237007)
			(xy 141.608053 -26.18257) (xy 141.603982 -26.126948) (xy 138.185904 -26.126948) (xy 138.198359 -26.168346)
			(xy 138.206479 -26.223522) (xy 138.206988 -26.251408) (xy 138.206479 -26.279294) (xy 138.198359 -26.33447)
			(xy 138.182291 -26.387877) (xy 138.158619 -26.438374) (xy 138.127846 -26.484887) (xy 138.090629 -26.526424)
			(xy 138.047761 -26.562099) (xy 138.000155 -26.591153) (xy 137.948826 -26.612965) (xy 137.894869 -26.627071)
			(xy 137.839432 -26.633171) (xy 137.783698 -26.631134) (xy 137.728855 -26.621004) (xy 137.676071 -26.602997)
			(xy 137.626471 -26.577496) (xy 137.581113 -26.545045) (xy 137.540964 -26.506336) (xy 137.506878 -26.462193)
			(xy 137.479582 -26.413558) (xy 137.459659 -26.361467) (xy 137.447533 -26.30703) (xy 137.443462 -26.251408)
			(xy 134.523731 -26.251408) (xy 134.546739 -26.286184) (xy 134.570411 -26.336681) (xy 134.586479 -26.390088)
			(xy 134.594599 -26.445264) (xy 134.595108 -26.47315) (xy 134.594599 -26.501036) (xy 134.586479 -26.556212)
			(xy 134.570411 -26.609619) (xy 134.546739 -26.660116) (xy 134.515966 -26.706629) (xy 134.478749 -26.748166)
			(xy 134.435881 -26.783841) (xy 134.388275 -26.812895) (xy 134.336946 -26.834707) (xy 134.282989 -26.848813)
			(xy 134.227552 -26.854913) (xy 134.171818 -26.852876) (xy 134.116975 -26.842746) (xy 134.064191 -26.824739)
			(xy 134.014591 -26.799238) (xy 133.969233 -26.766787) (xy 133.929084 -26.728078) (xy 133.894998 -26.683935)
			(xy 133.867702 -26.6353) (xy 133.847779 -26.583209) (xy 133.835653 -26.528772) (xy 133.831582 -26.47315)
			(xy 131.773049 -26.47315) (xy 131.773168 -26.480008) (xy 131.772682 -26.507259) (xy 131.764926 -26.561207)
			(xy 131.749571 -26.613502) (xy 131.726929 -26.663079) (xy 131.697463 -26.708929) (xy 131.661772 -26.75012)
			(xy 131.620581 -26.785811) (xy 131.574731 -26.815277) (xy 131.525154 -26.837919) (xy 131.472859 -26.853274)
			(xy 131.418911 -26.86103) (xy 131.364409 -26.86103) (xy 131.310461 -26.853274) (xy 131.258166 -26.837919)
			(xy 131.208589 -26.815277) (xy 131.162739 -26.785811) (xy 131.121548 -26.75012) (xy 131.085857 -26.708929)
			(xy 131.056391 -26.663079) (xy 131.033749 -26.613502) (xy 131.018394 -26.561207) (xy 131.010638 -26.507259)
			(xy 131.010152 -26.480008) (xy 127.696754 -26.480008) (xy 127.724299 -26.521642) (xy 127.747971 -26.572139)
			(xy 127.764039 -26.625546) (xy 127.772159 -26.680722) (xy 127.772668 -26.708608) (xy 127.772159 -26.736494)
			(xy 127.764039 -26.79167) (xy 127.747971 -26.845077) (xy 127.724299 -26.895574) (xy 127.693526 -26.942087)
			(xy 127.656309 -26.983624) (xy 127.613441 -27.019299) (xy 127.565835 -27.048353) (xy 127.514506 -27.070165)
			(xy 127.460549 -27.084271) (xy 127.405112 -27.090371) (xy 127.349378 -27.088334) (xy 127.294535 -27.078204)
			(xy 127.241751 -27.060197) (xy 127.192151 -27.034696) (xy 127.146793 -27.002245) (xy 127.106644 -26.963536)
			(xy 127.072558 -26.919393) (xy 127.045262 -26.870758) (xy 127.025339 -26.818667) (xy 127.013213 -26.76423)
			(xy 127.009142 -26.708608) (xy 114.756269 -26.708608) (xy 114.756198 -26.708859) (xy 114.735213 -26.756865)
			(xy 114.707853 -26.801546) (xy 114.674634 -26.842061) (xy 114.636181 -26.877647) (xy 114.61496 -26.893012)
			(xy 114.61496 -28.270708) (xy 114.7826 -28.438348) (xy 129.386582 -28.438348) (xy 129.390653 -28.382726)
			(xy 129.402779 -28.328289) (xy 129.422702 -28.276198) (xy 129.449998 -28.227563) (xy 129.484084 -28.18342)
			(xy 129.524233 -28.144711) (xy 129.569591 -28.11226) (xy 129.619191 -28.086759) (xy 129.671975 -28.068752)
			(xy 129.726818 -28.058622) (xy 129.782552 -28.056585) (xy 129.837989 -28.062685) (xy 129.891946 -28.076791)
			(xy 129.943275 -28.098603) (xy 129.990881 -28.127657) (xy 130.033749 -28.163332) (xy 130.070966 -28.204869)
			(xy 130.101739 -28.251382) (xy 130.125411 -28.301879) (xy 130.141479 -28.355286) (xy 130.149599 -28.410462)
			(xy 130.150108 -28.438348) (xy 130.149599 -28.466234) (xy 130.141479 -28.52141) (xy 130.125411 -28.574817)
			(xy 130.101739 -28.625314) (xy 130.070966 -28.671827) (xy 130.033749 -28.713364) (xy 129.990881 -28.749039)
			(xy 129.943275 -28.778093) (xy 129.891946 -28.799905) (xy 129.837989 -28.814011) (xy 129.782552 -28.820111)
			(xy 129.726818 -28.818074) (xy 129.671975 -28.807944) (xy 129.619191 -28.789937) (xy 129.569591 -28.764436)
			(xy 129.524233 -28.731985) (xy 129.484084 -28.693276) (xy 129.449998 -28.649133) (xy 129.422702 -28.600498)
			(xy 129.402779 -28.548407) (xy 129.390653 -28.49397) (xy 129.386582 -28.438348) (xy 114.7826 -28.438348)
			(xy 115.370102 -29.02585) (xy 133.831582 -29.02585) (xy 133.835653 -28.970228) (xy 133.847779 -28.915791)
			(xy 133.867702 -28.8637) (xy 133.894998 -28.815065) (xy 133.929084 -28.770922) (xy 133.969233 -28.732213)
			(xy 134.014591 -28.699762) (xy 134.064191 -28.674261) (xy 134.116975 -28.656254) (xy 134.171818 -28.646124)
			(xy 134.227552 -28.644087) (xy 134.282989 -28.650187) (xy 134.336946 -28.664293) (xy 134.388275 -28.686105)
			(xy 134.435881 -28.715159) (xy 134.478749 -28.750834) (xy 134.515966 -28.792371) (xy 134.546739 -28.838884)
			(xy 134.570411 -28.889381) (xy 134.582201 -28.928568) (xy 162.170362 -28.928568) (xy 162.174433 -28.872946)
			(xy 162.186559 -28.818509) (xy 162.206482 -28.766418) (xy 162.233778 -28.717783) (xy 162.267864 -28.67364)
			(xy 162.308013 -28.634931) (xy 162.353371 -28.60248) (xy 162.402971 -28.576979) (xy 162.455755 -28.558972)
			(xy 162.510598 -28.548842) (xy 162.566332 -28.546805) (xy 162.621769 -28.552905) (xy 162.675726 -28.567011)
			(xy 162.727055 -28.588823) (xy 162.774661 -28.617877) (xy 162.817529 -28.653552) (xy 162.854746 -28.695089)
			(xy 162.885519 -28.741602) (xy 162.909191 -28.792099) (xy 162.925259 -28.845506) (xy 162.933379 -28.900682)
			(xy 162.933888 -28.928568) (xy 162.933379 -28.956454) (xy 162.925259 -29.01163) (xy 162.909191 -29.065037)
			(xy 162.885519 -29.115534) (xy 162.854746 -29.162047) (xy 162.817529 -29.203584) (xy 162.774661 -29.239259)
			(xy 162.727055 -29.268313) (xy 162.675726 -29.290125) (xy 162.621769 -29.304231) (xy 162.566332 -29.310331)
			(xy 162.510598 -29.308294) (xy 162.455755 -29.298164) (xy 162.402971 -29.280157) (xy 162.353371 -29.254656)
			(xy 162.308013 -29.222205) (xy 162.267864 -29.183496) (xy 162.233778 -29.139353) (xy 162.206482 -29.090718)
			(xy 162.186559 -29.038627) (xy 162.174433 -28.98419) (xy 162.170362 -28.928568) (xy 134.582201 -28.928568)
			(xy 134.586479 -28.942788) (xy 134.594599 -28.997964) (xy 134.595108 -29.02585) (xy 134.594599 -29.053736)
			(xy 134.586479 -29.108912) (xy 134.570411 -29.162319) (xy 134.546739 -29.212816) (xy 134.515966 -29.259329)
			(xy 134.478749 -29.300866) (xy 134.435881 -29.336541) (xy 134.388275 -29.365595) (xy 134.336946 -29.387407)
			(xy 134.282989 -29.401513) (xy 134.227552 -29.407613) (xy 134.171818 -29.405576) (xy 134.116975 -29.395446)
			(xy 134.064191 -29.377439) (xy 134.014591 -29.351938) (xy 133.969233 -29.319487) (xy 133.929084 -29.280778)
			(xy 133.894998 -29.236635) (xy 133.867702 -29.188) (xy 133.847779 -29.135909) (xy 133.835653 -29.081472)
			(xy 133.831582 -29.02585) (xy 115.370102 -29.02585) (xy 115.795044 -29.450792) (xy 117.047262 -29.450792)
			(xy 117.051333 -29.39517) (xy 117.063459 -29.340733) (xy 117.083382 -29.288642) (xy 117.110678 -29.240007)
			(xy 117.144764 -29.195864) (xy 117.184913 -29.157155) (xy 117.230271 -29.124704) (xy 117.279871 -29.099203)
			(xy 117.332655 -29.081196) (xy 117.387498 -29.071066) (xy 117.443232 -29.069029) (xy 117.498669 -29.075129)
			(xy 117.552626 -29.089235) (xy 117.603955 -29.111047) (xy 117.651561 -29.140101) (xy 117.694429 -29.175776)
			(xy 117.731646 -29.217313) (xy 117.762419 -29.263826) (xy 117.786091 -29.314323) (xy 117.802159 -29.36773)
			(xy 117.810279 -29.422906) (xy 117.810788 -29.450792) (xy 117.810279 -29.478678) (xy 117.802159 -29.533854)
			(xy 117.786091 -29.587261) (xy 117.762419 -29.637758) (xy 117.731646 -29.684271) (xy 117.694429 -29.725808)
			(xy 117.651561 -29.761483) (xy 117.603955 -29.790537) (xy 117.552626 -29.812349) (xy 117.498669 -29.826455)
			(xy 117.443232 -29.832555) (xy 117.387498 -29.830518) (xy 117.332655 -29.820388) (xy 117.279871 -29.802381)
			(xy 117.230271 -29.77688) (xy 117.184913 -29.744429) (xy 117.144764 -29.70572) (xy 117.110678 -29.661577)
			(xy 117.083382 -29.612942) (xy 117.063459 -29.560851) (xy 117.051333 -29.506414) (xy 117.047262 -29.450792)
			(xy 115.795044 -29.450792) (xy 116.2812 -29.936948) (xy 130.097782 -29.936948) (xy 130.101853 -29.881326)
			(xy 130.113979 -29.826889) (xy 130.133902 -29.774798) (xy 130.161198 -29.726163) (xy 130.195284 -29.68202)
			(xy 130.235433 -29.643311) (xy 130.280791 -29.61086) (xy 130.330391 -29.585359) (xy 130.383175 -29.567352)
			(xy 130.438018 -29.557222) (xy 130.493752 -29.555185) (xy 130.549189 -29.561285) (xy 130.603146 -29.575391)
			(xy 130.654475 -29.597203) (xy 130.702081 -29.626257) (xy 130.744949 -29.661932) (xy 130.782166 -29.703469)
			(xy 130.811945 -29.74848) (xy 171.210222 -29.74848) (xy 171.214293 -29.692858) (xy 171.226419 -29.638421)
			(xy 171.246342 -29.58633) (xy 171.273638 -29.537695) (xy 171.307724 -29.493552) (xy 171.347873 -29.454843)
			(xy 171.393231 -29.422392) (xy 171.442831 -29.396891) (xy 171.495615 -29.378884) (xy 171.550458 -29.368754)
			(xy 171.606192 -29.366717) (xy 171.661629 -29.372817) (xy 171.715586 -29.386923) (xy 171.766915 -29.408735)
			(xy 171.814521 -29.437789) (xy 171.857389 -29.473464) (xy 171.894606 -29.515001) (xy 171.925379 -29.561514)
			(xy 171.949051 -29.612011) (xy 171.965119 -29.665418) (xy 171.973239 -29.720594) (xy 171.973748 -29.74848)
			(xy 171.973239 -29.776366) (xy 171.965119 -29.831542) (xy 171.949051 -29.884949) (xy 171.925379 -29.935446)
			(xy 171.894606 -29.981959) (xy 171.857389 -30.023496) (xy 171.814521 -30.059171) (xy 171.766915 -30.088225)
			(xy 171.715586 -30.110037) (xy 171.661629 -30.124143) (xy 171.606192 -30.130243) (xy 171.550458 -30.128206)
			(xy 171.495615 -30.118076) (xy 171.442831 -30.100069) (xy 171.393231 -30.074568) (xy 171.347873 -30.042117)
			(xy 171.307724 -30.003408) (xy 171.273638 -29.959265) (xy 171.246342 -29.91063) (xy 171.226419 -29.858539)
			(xy 171.214293 -29.804102) (xy 171.210222 -29.74848) (xy 130.811945 -29.74848) (xy 130.812939 -29.749982)
			(xy 130.836611 -29.800479) (xy 130.852679 -29.853886) (xy 130.860799 -29.909062) (xy 130.861308 -29.936948)
			(xy 130.860799 -29.964834) (xy 130.852679 -30.02001) (xy 130.836611 -30.073417) (xy 130.812939 -30.123914)
			(xy 130.782166 -30.170427) (xy 130.744949 -30.211964) (xy 130.702081 -30.247639) (xy 130.654475 -30.276693)
			(xy 130.603146 -30.298505) (xy 130.549189 -30.312611) (xy 130.493752 -30.318711) (xy 130.438018 -30.316674)
			(xy 130.383175 -30.306544) (xy 130.330391 -30.288537) (xy 130.280791 -30.263036) (xy 130.235433 -30.230585)
			(xy 130.195284 -30.191876) (xy 130.161198 -30.147733) (xy 130.133902 -30.099098) (xy 130.113979 -30.047007)
			(xy 130.101853 -29.99257) (xy 130.097782 -29.936948) (xy 116.2812 -29.936948) (xy 116.95684 -30.612588)
			(xy 136.107422 -30.612588) (xy 136.111493 -30.556966) (xy 136.123619 -30.502529) (xy 136.143542 -30.450438)
			(xy 136.170838 -30.401803) (xy 136.204924 -30.35766) (xy 136.245073 -30.318951) (xy 136.290431 -30.2865)
			(xy 136.340031 -30.260999) (xy 136.392815 -30.242992) (xy 136.447658 -30.232862) (xy 136.503392 -30.230825)
			(xy 136.558829 -30.236925) (xy 136.612786 -30.251031) (xy 136.664115 -30.272843) (xy 136.711721 -30.301897)
			(xy 136.754589 -30.337572) (xy 136.791806 -30.379109) (xy 136.822579 -30.425622) (xy 136.846251 -30.476119)
			(xy 136.862319 -30.529526) (xy 136.870439 -30.584702) (xy 136.870948 -30.612588) (xy 136.870439 -30.640474)
			(xy 136.862319 -30.69565) (xy 136.846251 -30.749057) (xy 136.822579 -30.799554) (xy 136.791806 -30.846067)
			(xy 136.754589 -30.887604) (xy 136.711721 -30.923279) (xy 136.664115 -30.952333) (xy 136.612786 -30.974145)
			(xy 136.558829 -30.988251) (xy 136.503392 -30.994351) (xy 136.447658 -30.992314) (xy 136.392815 -30.982184)
			(xy 136.340031 -30.964177) (xy 136.290431 -30.938676) (xy 136.245073 -30.906225) (xy 136.204924 -30.867516)
			(xy 136.170838 -30.823373) (xy 136.143542 -30.774738) (xy 136.123619 -30.722647) (xy 136.111493 -30.66821)
			(xy 136.107422 -30.612588) (xy 116.95684 -30.612588) (xy 119.171974 -32.827722) (xy 133.517132 -32.827722)
			(xy 133.517618 -32.800471) (xy 133.525374 -32.746523) (xy 133.540729 -32.694228) (xy 133.563371 -32.644651)
			(xy 133.592837 -32.598801) (xy 133.628528 -32.55761) (xy 133.669719 -32.521919) (xy 133.715569 -32.492453)
			(xy 133.765146 -32.469811) (xy 133.817441 -32.454456) (xy 133.871389 -32.4467) (xy 133.925891 -32.4467)
			(xy 133.979839 -32.454456) (xy 134.032134 -32.469811) (xy 134.081711 -32.492453) (xy 134.127561 -32.521919)
			(xy 134.168752 -32.55761) (xy 134.204443 -32.598801) (xy 134.233909 -32.644651) (xy 134.256551 -32.694228)
			(xy 134.271906 -32.746523) (xy 134.279662 -32.800471) (xy 134.280148 -32.827722) (xy 134.279787 -32.8523)
			(xy 134.273461 -32.901047) (xy 134.260928 -32.948578) (xy 134.242397 -32.994107) (xy 134.230618 -33.015682)
			(xy 134.223454 -33.0296) (xy 134.217051 -33.060223) (xy 134.220204 -33.091349) (xy 134.232617 -33.120067)
			(xy 134.253129 -33.143689) (xy 134.266178 -33.152334) (xy 134.289654 -33.167327) (xy 134.332439 -33.20299)
			(xy 134.36958 -33.244498) (xy 134.400288 -33.290967) (xy 134.42391 -33.34141) (xy 134.439942 -33.394752)
			(xy 134.448044 -33.449858) (xy 134.44855 -33.477708) (xy 134.448064 -33.504959) (xy 134.440308 -33.558907)
			(xy 134.424953 -33.611202) (xy 134.402311 -33.660779) (xy 134.372845 -33.706629) (xy 134.337154 -33.74782)
			(xy 134.295963 -33.783511) (xy 134.250113 -33.812977) (xy 134.200536 -33.835619) (xy 134.148241 -33.850974)
			(xy 134.094293 -33.85873) (xy 134.039791 -33.85873) (xy 133.985843 -33.850974) (xy 133.933548 -33.835619)
			(xy 133.883971 -33.812977) (xy 133.838121 -33.783511) (xy 133.79693 -33.74782) (xy 133.761239 -33.706629)
			(xy 133.731773 -33.660779) (xy 133.709131 -33.611202) (xy 133.693776 -33.558907) (xy 133.68602 -33.504959)
			(xy 133.685534 -33.477708) (xy 133.68591 -33.453131) (xy 133.692232 -33.404384) (xy 133.70476 -33.356853)
			(xy 133.723287 -33.311323) (xy 133.735064 -33.289748) (xy 133.742202 -33.275817) (xy 133.748613 -33.2452)
			(xy 133.745467 -33.214077) (xy 133.73306 -33.185361) (xy 133.712552 -33.16174) (xy 133.699504 -33.153096)
			(xy 133.675993 -33.138157) (xy 133.633209 -33.102484) (xy 133.59607 -33.060967) (xy 133.565366 -33.014488)
			(xy 133.541751 -32.964037) (xy 133.525726 -32.910688) (xy 133.517633 -32.855574) (xy 133.517132 -32.827722)
			(xy 119.171974 -32.827722) (xy 120.5865 -34.242248) (xy 120.5865 -35.684968) (xy 126.270002 -35.684968)
			(xy 126.274073 -35.629346) (xy 126.286199 -35.574909) (xy 126.306122 -35.522818) (xy 126.333418 -35.474183)
			(xy 126.367504 -35.43004) (xy 126.407653 -35.391331) (xy 126.453011 -35.35888) (xy 126.502611 -35.333379)
			(xy 126.555395 -35.315372) (xy 126.610238 -35.305242) (xy 126.665972 -35.303205) (xy 126.721409 -35.309305)
			(xy 126.775366 -35.323411) (xy 126.826695 -35.345223) (xy 126.874301 -35.374277) (xy 126.917169 -35.409952)
			(xy 126.954386 -35.451489) (xy 126.985159 -35.498002) (xy 127.008831 -35.548499) (xy 127.024899 -35.601906)
			(xy 127.033019 -35.657082) (xy 127.033528 -35.684968) (xy 127.453642 -35.684968) (xy 127.457713 -35.629346)
			(xy 127.469839 -35.574909) (xy 127.489762 -35.522818) (xy 127.517058 -35.474183) (xy 127.551144 -35.43004)
			(xy 127.591293 -35.391331) (xy 127.636651 -35.35888) (xy 127.686251 -35.333379) (xy 127.739035 -35.315372)
			(xy 127.793878 -35.305242) (xy 127.849612 -35.303205) (xy 127.905049 -35.309305) (xy 127.959006 -35.323411)
			(xy 128.010335 -35.345223) (xy 128.057941 -35.374277) (xy 128.100809 -35.409952) (xy 128.138026 -35.451489)
			(xy 128.168799 -35.498002) (xy 128.192471 -35.548499) (xy 128.208539 -35.601906) (xy 128.216659 -35.657082)
			(xy 128.217168 -35.684968) (xy 128.487422 -35.684968) (xy 128.491493 -35.629346) (xy 128.503619 -35.574909)
			(xy 128.523542 -35.522818) (xy 128.550838 -35.474183) (xy 128.584924 -35.43004) (xy 128.625073 -35.391331)
			(xy 128.670431 -35.35888) (xy 128.720031 -35.333379) (xy 128.772815 -35.315372) (xy 128.827658 -35.305242)
			(xy 128.883392 -35.303205) (xy 128.938829 -35.309305) (xy 128.992786 -35.323411) (xy 129.044115 -35.345223)
			(xy 129.091721 -35.374277) (xy 129.134589 -35.409952) (xy 129.171806 -35.451489) (xy 129.202579 -35.498002)
			(xy 129.210329 -35.514534) (xy 131.237226 -35.514534) (xy 131.241297 -35.458912) (xy 131.253423 -35.404475)
			(xy 131.273346 -35.352384) (xy 131.300642 -35.303749) (xy 131.334728 -35.259606) (xy 131.374877 -35.220897)
			(xy 131.420235 -35.188446) (xy 131.469835 -35.162945) (xy 131.522619 -35.144938) (xy 131.577462 -35.134808)
			(xy 131.633196 -35.132771) (xy 131.688633 -35.138871) (xy 131.74259 -35.152977) (xy 131.793919 -35.174789)
			(xy 131.841525 -35.203843) (xy 131.884393 -35.239518) (xy 131.92161 -35.281055) (xy 131.952383 -35.327568)
			(xy 131.976055 -35.378065) (xy 131.992123 -35.431472) (xy 132.000243 -35.486648) (xy 132.000752 -35.514534)
			(xy 132.000243 -35.54242) (xy 131.992123 -35.597596) (xy 131.976055 -35.651003) (xy 131.952383 -35.7015)
			(xy 131.92161 -35.748013) (xy 131.884393 -35.78955) (xy 131.841525 -35.825225) (xy 131.793919 -35.854279)
			(xy 131.74259 -35.876091) (xy 131.688633 -35.890197) (xy 131.633196 -35.896297) (xy 131.577462 -35.89426)
			(xy 131.522619 -35.88413) (xy 131.469835 -35.866123) (xy 131.420235 -35.840622) (xy 131.374877 -35.808171)
			(xy 131.334728 -35.769462) (xy 131.300642 -35.725319) (xy 131.273346 -35.676684) (xy 131.253423 -35.624593)
			(xy 131.241297 -35.570156) (xy 131.237226 -35.514534) (xy 129.210329 -35.514534) (xy 129.226251 -35.548499)
			(xy 129.242319 -35.601906) (xy 129.250439 -35.657082) (xy 129.250948 -35.684968) (xy 129.250439 -35.712854)
			(xy 129.242319 -35.76803) (xy 129.226251 -35.821437) (xy 129.202579 -35.871934) (xy 129.171806 -35.918447)
			(xy 129.134589 -35.959984) (xy 129.091721 -35.995659) (xy 129.044115 -36.024713) (xy 128.992786 -36.046525)
			(xy 128.938829 -36.060631) (xy 128.883392 -36.066731) (xy 128.827658 -36.064694) (xy 128.772815 -36.054564)
			(xy 128.720031 -36.036557) (xy 128.670431 -36.011056) (xy 128.625073 -35.978605) (xy 128.584924 -35.939896)
			(xy 128.550838 -35.895753) (xy 128.523542 -35.847118) (xy 128.503619 -35.795027) (xy 128.491493 -35.74059)
			(xy 128.487422 -35.684968) (xy 128.217168 -35.684968) (xy 128.216659 -35.712854) (xy 128.208539 -35.76803)
			(xy 128.192471 -35.821437) (xy 128.168799 -35.871934) (xy 128.138026 -35.918447) (xy 128.100809 -35.959984)
			(xy 128.057941 -35.995659) (xy 128.010335 -36.024713) (xy 127.959006 -36.046525) (xy 127.905049 -36.060631)
			(xy 127.849612 -36.066731) (xy 127.793878 -36.064694) (xy 127.739035 -36.054564) (xy 127.686251 -36.036557)
			(xy 127.636651 -36.011056) (xy 127.591293 -35.978605) (xy 127.551144 -35.939896) (xy 127.517058 -35.895753)
			(xy 127.489762 -35.847118) (xy 127.469839 -35.795027) (xy 127.457713 -35.74059) (xy 127.453642 -35.684968)
			(xy 127.033528 -35.684968) (xy 127.033019 -35.712854) (xy 127.024899 -35.76803) (xy 127.008831 -35.821437)
			(xy 126.985159 -35.871934) (xy 126.954386 -35.918447) (xy 126.917169 -35.959984) (xy 126.874301 -35.995659)
			(xy 126.826695 -36.024713) (xy 126.775366 -36.046525) (xy 126.721409 -36.060631) (xy 126.665972 -36.066731)
			(xy 126.610238 -36.064694) (xy 126.555395 -36.054564) (xy 126.502611 -36.036557) (xy 126.453011 -36.011056)
			(xy 126.407653 -35.978605) (xy 126.367504 -35.939896) (xy 126.333418 -35.895753) (xy 126.306122 -35.847118)
			(xy 126.286199 -35.795027) (xy 126.274073 -35.74059) (xy 126.270002 -35.684968) (xy 120.5865 -35.684968)
			(xy 120.5865 -37.355526) (xy 122.015502 -37.355526) (xy 122.019573 -37.299904) (xy 122.031699 -37.245467)
			(xy 122.051622 -37.193376) (xy 122.078918 -37.144741) (xy 122.113004 -37.100598) (xy 122.153153 -37.061889)
			(xy 122.198511 -37.029438) (xy 122.248111 -37.003937) (xy 122.300895 -36.98593) (xy 122.355738 -36.9758)
			(xy 122.411472 -36.973763) (xy 122.466909 -36.979863) (xy 122.520866 -36.993969) (xy 122.572195 -37.015781)
			(xy 122.619801 -37.044835) (xy 122.662669 -37.08051) (xy 122.699886 -37.122047) (xy 122.730659 -37.16856)
			(xy 122.754331 -37.219057) (xy 122.770399 -37.272464) (xy 122.778519 -37.32764) (xy 122.779028 -37.355526)
			(xy 122.778519 -37.383412) (xy 122.770399 -37.438588) (xy 122.754331 -37.491995) (xy 122.730659 -37.542492)
			(xy 122.704753 -37.581649) (xy 130.604286 -37.581649) (xy 130.604286 -37.527151) (xy 130.612041 -37.473208)
			(xy 130.627394 -37.420918) (xy 130.650031 -37.371344) (xy 130.679493 -37.325497) (xy 130.71518 -37.284308)
			(xy 130.756364 -37.248617) (xy 130.802209 -37.219151) (xy 130.85178 -37.196508) (xy 130.904069 -37.181149)
			(xy 130.958011 -37.173388) (xy 130.98526 -37.1729) (xy 131.014681 -37.173474) (xy 131.072824 -37.182516)
			(xy 131.12889 -37.200377) (xy 131.181549 -37.226633) (xy 131.229554 -37.260661) (xy 131.271766 -37.301656)
			(xy 131.307184 -37.348645) (xy 131.321556 -37.374322) (xy 131.328264 -37.386031) (xy 131.34681 -37.405625)
			(xy 131.369837 -37.419682) (xy 131.395741 -37.427223) (xy 131.422715 -37.427722) (xy 131.44888 -37.421144)
			(xy 131.472411 -37.407947) (xy 131.491668 -37.389052) (xy 131.498848 -37.377624) (xy 131.513629 -37.353314)
			(xy 131.549255 -37.308956) (xy 131.591071 -37.270379) (xy 131.63815 -37.238436) (xy 131.68945 -37.213836)
			(xy 131.743833 -37.197124) (xy 131.800094 -37.18867) (xy 131.82854 -37.18814) (xy 131.855793 -37.188533)
			(xy 131.909743 -37.196295) (xy 131.96204 -37.211655) (xy 132.011618 -37.234302) (xy 132.057469 -37.263773)
			(xy 132.09866 -37.299469) (xy 132.134351 -37.340663) (xy 132.163818 -37.386517) (xy 132.186459 -37.436098)
			(xy 132.201814 -37.488396) (xy 132.20957 -37.542347) (xy 132.20957 -37.596853) (xy 132.201814 -37.650804)
			(xy 132.186459 -37.703102) (xy 132.163818 -37.752683) (xy 132.134351 -37.798537) (xy 132.09866 -37.839731)
			(xy 132.057469 -37.875427) (xy 132.011618 -37.904898) (xy 131.96204 -37.927545) (xy 131.909743 -37.942905)
			(xy 131.855793 -37.950667) (xy 131.82854 -37.951156) (xy 131.799118 -37.950605) (xy 131.740973 -37.941562)
			(xy 131.684905 -37.923699) (xy 131.632245 -37.89744) (xy 131.58424 -37.863407) (xy 131.54203 -37.822408)
			(xy 131.506614 -37.775414) (xy 131.492244 -37.749734) (xy 131.485534 -37.738028) (xy 131.466985 -37.718442)
			(xy 131.443958 -37.704391) (xy 131.418057 -37.696854) (xy 131.391087 -37.696356) (xy 131.364925 -37.702931)
			(xy 131.341395 -37.716121) (xy 131.322135 -37.735008) (xy 131.314952 -37.746432) (xy 131.300155 -37.770732)
			(xy 131.264533 -37.815092) (xy 131.222721 -37.853671) (xy 131.175644 -37.885616) (xy 131.124347 -37.910218)
			(xy 131.069966 -37.926931) (xy 131.013706 -37.935386) (xy 130.98526 -37.935916) (xy 130.958011 -37.935412)
			(xy 130.904069 -37.927651) (xy 130.85178 -37.912292) (xy 130.802209 -37.889649) (xy 130.756364 -37.860183)
			(xy 130.71518 -37.824492) (xy 130.679493 -37.783303) (xy 130.650031 -37.737456) (xy 130.627394 -37.687882)
			(xy 130.612041 -37.635592) (xy 130.604286 -37.581649) (xy 122.704753 -37.581649) (xy 122.699886 -37.589005)
			(xy 122.662669 -37.630542) (xy 122.619801 -37.666217) (xy 122.572195 -37.695271) (xy 122.520866 -37.717083)
			(xy 122.466909 -37.731189) (xy 122.411472 -37.737289) (xy 122.355738 -37.735252) (xy 122.300895 -37.725122)
			(xy 122.248111 -37.707115) (xy 122.198511 -37.681614) (xy 122.153153 -37.649163) (xy 122.113004 -37.610454)
			(xy 122.078918 -37.566311) (xy 122.051622 -37.517676) (xy 122.031699 -37.465585) (xy 122.019573 -37.411148)
			(xy 122.015502 -37.355526) (xy 120.5865 -37.355526) (xy 120.5865 -38.049708) (xy 133.685024 -38.049708)
			(xy 133.689095 -37.994086) (xy 133.701221 -37.939649) (xy 133.721144 -37.887558) (xy 133.74844 -37.838923)
			(xy 133.782526 -37.79478) (xy 133.822675 -37.756071) (xy 133.868033 -37.72362) (xy 133.917633 -37.698119)
			(xy 133.970417 -37.680112) (xy 134.02526 -37.669982) (xy 134.080994 -37.667945) (xy 134.136431 -37.674045)
			(xy 134.190388 -37.688151) (xy 134.241717 -37.709963) (xy 134.289323 -37.739017) (xy 134.332191 -37.774692)
			(xy 134.369408 -37.816229) (xy 134.400181 -37.862742) (xy 134.423853 -37.913239) (xy 134.439921 -37.966646)
			(xy 134.448041 -38.021822) (xy 134.44855 -38.049708) (xy 134.448041 -38.077594) (xy 134.439921 -38.13277)
			(xy 134.423853 -38.186177) (xy 134.400181 -38.236674) (xy 134.369408 -38.283187) (xy 134.332191 -38.324724)
			(xy 134.289323 -38.360399) (xy 134.241717 -38.389453) (xy 134.190388 -38.411265) (xy 134.136431 -38.425371)
			(xy 134.080994 -38.431471) (xy 134.02526 -38.429434) (xy 133.970417 -38.419304) (xy 133.917633 -38.401297)
			(xy 133.868033 -38.375796) (xy 133.822675 -38.343345) (xy 133.782526 -38.304636) (xy 133.74844 -38.260493)
			(xy 133.721144 -38.211858) (xy 133.701221 -38.159767) (xy 133.689095 -38.10533) (xy 133.685024 -38.049708)
			(xy 120.5865 -38.049708) (xy 120.5865 -39.9288) (xy 120.586996 -39.942575) (xy 120.594436 -39.969104)
			(xy 120.608693 -39.99268) (xy 120.628732 -40.01159) (xy 120.653095 -40.024459) (xy 120.68001 -40.03035)
			(xy 120.707521 -40.028835) (xy 120.733627 -40.020025) (xy 120.74525 -40.01262) (xy 120.76912 -39.997029)
			(xy 120.820509 -39.97234) (xy 120.874997 -39.955569) (xy 120.931374 -39.947087) (xy 120.95988 -39.94658)
			(xy 120.987135 -39.947042) (xy 121.04109 -39.954796) (xy 121.093391 -39.970151) (xy 121.142976 -39.992793)
			(xy 121.188833 -40.022262) (xy 121.230029 -40.057957) (xy 121.265726 -40.099151) (xy 121.295197 -40.145007)
			(xy 121.317842 -40.19459) (xy 121.333199 -40.246891) (xy 121.340957 -40.300845) (xy 121.340957 -40.355355)
			(xy 121.333199 -40.409309) (xy 121.317842 -40.46161) (xy 121.295197 -40.511193) (xy 121.265726 -40.557049)
			(xy 121.230029 -40.598243) (xy 121.188833 -40.633938) (xy 121.142976 -40.663407) (xy 121.093391 -40.686049)
			(xy 121.04109 -40.701404) (xy 120.987135 -40.709158) (xy 120.95988 -40.709596) (xy 120.931376 -40.709066)
			(xy 120.875001 -40.700586) (xy 120.820514 -40.683818) (xy 120.769126 -40.659135) (xy 120.74525 -40.643556)
			(xy 120.733599 -40.636185) (xy 120.707495 -40.627347) (xy 120.679978 -40.625811) (xy 120.653053 -40.631691)
			(xy 120.628681 -40.644556) (xy 120.608637 -40.663471) (xy 120.594381 -40.687058) (xy 120.586952 -40.713597)
			(xy 120.5865 -40.727376) (xy 120.5865 -40.986456) (xy 122.654566 -40.986456) (xy 122.658637 -40.930834)
			(xy 122.670763 -40.876397) (xy 122.690686 -40.824306) (xy 122.717982 -40.775671) (xy 122.752068 -40.731528)
			(xy 122.792217 -40.692819) (xy 122.837575 -40.660368) (xy 122.887175 -40.634867) (xy 122.939959 -40.61686)
			(xy 122.994802 -40.60673) (xy 123.050536 -40.604693) (xy 123.105973 -40.610793) (xy 123.15993 -40.624899)
			(xy 123.211259 -40.646711) (xy 123.258865 -40.675765) (xy 123.301733 -40.71144) (xy 123.33895 -40.752977)
			(xy 123.369723 -40.79949) (xy 123.393395 -40.849987) (xy 123.409463 -40.903394) (xy 123.417583 -40.95857)
			(xy 123.418083 -40.985948) (xy 133.456172 -40.985948) (xy 133.456658 -40.958697) (xy 133.464414 -40.904749)
			(xy 133.479769 -40.852454) (xy 133.502411 -40.802877) (xy 133.531877 -40.757027) (xy 133.567568 -40.715836)
			(xy 133.608759 -40.680145) (xy 133.654609 -40.650679) (xy 133.704186 -40.628037) (xy 133.756481 -40.612682)
			(xy 133.810429 -40.604926) (xy 133.864931 -40.604926) (xy 133.918879 -40.612682) (xy 133.971174 -40.628037)
			(xy 134.020751 -40.650679) (xy 134.066601 -40.680145) (xy 134.107792 -40.715836) (xy 134.143483 -40.757027)
			(xy 134.172949 -40.802877) (xy 134.195591 -40.852454) (xy 134.210946 -40.904749) (xy 134.211847 -40.911018)
			(xy 135.448292 -40.911018) (xy 135.452363 -40.855396) (xy 135.464489 -40.800959) (xy 135.484412 -40.748868)
			(xy 135.511708 -40.700233) (xy 135.545794 -40.65609) (xy 135.585943 -40.617381) (xy 135.631301 -40.58493)
			(xy 135.680901 -40.559429) (xy 135.733685 -40.541422) (xy 135.788528 -40.531292) (xy 135.844262 -40.529255)
			(xy 135.899699 -40.535355) (xy 135.953656 -40.549461) (xy 136.004985 -40.571273) (xy 136.052591 -40.600327)
			(xy 136.095459 -40.636002) (xy 136.132676 -40.677539) (xy 136.163449 -40.724052) (xy 136.187121 -40.774549)
			(xy 136.203189 -40.827956) (xy 136.211309 -40.883132) (xy 136.211818 -40.911018) (xy 136.211309 -40.938904)
			(xy 136.203189 -40.99408) (xy 136.187121 -41.047487) (xy 136.163449 -41.097984) (xy 136.132676 -41.144497)
			(xy 136.095459 -41.186034) (xy 136.052591 -41.221709) (xy 136.004985 -41.250763) (xy 135.953656 -41.272575)
			(xy 135.899699 -41.286681) (xy 135.844262 -41.292781) (xy 135.788528 -41.290744) (xy 135.733685 -41.280614)
			(xy 135.680901 -41.262607) (xy 135.631301 -41.237106) (xy 135.585943 -41.204655) (xy 135.545794 -41.165946)
			(xy 135.511708 -41.121803) (xy 135.484412 -41.073168) (xy 135.464489 -41.021077) (xy 135.452363 -40.96664)
			(xy 135.448292 -40.911018) (xy 134.211847 -40.911018) (xy 134.218702 -40.958697) (xy 134.219188 -40.985948)
			(xy 134.2187 -41.012945) (xy 134.211106 -41.0664) (xy 134.196048 -41.118251) (xy 134.173828 -41.167459)
			(xy 134.144888 -41.213041) (xy 134.109809 -41.254086) (xy 134.069292 -41.289773) (xy 134.046976 -41.304972)
			(xy 134.035596 -41.31302) (xy 134.017345 -41.334074) (xy 134.005466 -41.359277) (xy 134.000843 -41.386753)
			(xy 134.003819 -41.414456) (xy 134.014174 -41.440323) (xy 134.031135 -41.462428) (xy 134.053441 -41.479124)
			(xy 134.06628 -41.48455) (xy 134.09284 -41.495356) (xy 134.142612 -41.523827) (xy 134.187565 -41.559423)
			(xy 134.226687 -41.601345) (xy 134.259096 -41.648647) (xy 134.284063 -41.700266) (xy 134.301027 -41.755039)
			(xy 134.309605 -41.811734) (xy 134.31012 -41.840404) (xy 134.309634 -41.867655) (xy 134.301878 -41.921603)
			(xy 134.286523 -41.973898) (xy 134.263881 -42.023475) (xy 134.234415 -42.069325) (xy 134.198724 -42.110516)
			(xy 134.157533 -42.146207) (xy 134.111683 -42.175673) (xy 134.062106 -42.198315) (xy 134.009811 -42.21367)
			(xy 133.955863 -42.221426) (xy 133.901361 -42.221426) (xy 133.847413 -42.21367) (xy 133.795118 -42.198315)
			(xy 133.745541 -42.175673) (xy 133.699691 -42.146207) (xy 133.6585 -42.110516) (xy 133.622809 -42.069325)
			(xy 133.593343 -42.023475) (xy 133.570701 -41.973898) (xy 133.555346 -41.921603) (xy 133.54759 -41.867655)
			(xy 133.547104 -41.840404) (xy 133.547559 -41.813406) (xy 133.555159 -41.759949) (xy 133.570223 -41.708098)
			(xy 133.592449 -41.65889) (xy 133.621393 -41.613308) (xy 133.656477 -41.572264) (xy 133.696998 -41.536579)
			(xy 133.719316 -41.52138) (xy 133.730747 -41.513398) (xy 133.749001 -41.492332) (xy 133.76088 -41.467115)
			(xy 133.7655 -41.439626) (xy 133.762516 -41.411911) (xy 133.752151 -41.386036) (xy 133.735177 -41.363925)
			(xy 133.712857 -41.347227) (xy 133.700012 -41.341802) (xy 133.673469 -41.330957) (xy 133.623699 -41.30249)
			(xy 133.578747 -41.266899) (xy 133.539625 -41.224983) (xy 133.507214 -41.177686) (xy 133.482244 -41.126074)
			(xy 133.465275 -41.071306) (xy 133.456691 -41.014616) (xy 133.456172 -40.985948) (xy 123.418083 -40.985948)
			(xy 123.418092 -40.986456) (xy 123.417583 -41.014342) (xy 123.409463 -41.069518) (xy 123.393395 -41.122925)
			(xy 123.369723 -41.173422) (xy 123.33895 -41.219935) (xy 123.301733 -41.261472) (xy 123.258865 -41.297147)
			(xy 123.211259 -41.326201) (xy 123.15993 -41.348013) (xy 123.105973 -41.362119) (xy 123.050536 -41.368219)
			(xy 122.994802 -41.366182) (xy 122.939959 -41.356052) (xy 122.887175 -41.338045) (xy 122.837575 -41.312544)
			(xy 122.792217 -41.280093) (xy 122.752068 -41.241384) (xy 122.717982 -41.197241) (xy 122.690686 -41.148606)
			(xy 122.670763 -41.096515) (xy 122.658637 -41.042078) (xy 122.654566 -40.986456) (xy 120.5865 -40.986456)
			(xy 120.5865 -42.784522) (xy 130.389882 -42.784522) (xy 130.393953 -42.7289) (xy 130.406079 -42.674463)
			(xy 130.426002 -42.622372) (xy 130.453298 -42.573737) (xy 130.487384 -42.529594) (xy 130.527533 -42.490885)
			(xy 130.572891 -42.458434) (xy 130.622491 -42.432933) (xy 130.675275 -42.414926) (xy 130.730118 -42.404796)
			(xy 130.785852 -42.402759) (xy 130.841289 -42.408859) (xy 130.895246 -42.422965) (xy 130.946575 -42.444777)
			(xy 130.994181 -42.473831) (xy 131.037049 -42.509506) (xy 131.074266 -42.551043) (xy 131.105039 -42.597556)
			(xy 131.128711 -42.648053) (xy 131.144779 -42.70146) (xy 131.152899 -42.756636) (xy 131.153408 -42.784522)
			(xy 131.152899 -42.812408) (xy 131.144779 -42.867584) (xy 131.128711 -42.920991) (xy 131.105039 -42.971488)
			(xy 131.074266 -43.018001) (xy 131.037049 -43.059538) (xy 130.994181 -43.095213) (xy 130.946575 -43.124267)
			(xy 130.895246 -43.146079) (xy 130.841289 -43.160185) (xy 130.785852 -43.166285) (xy 130.730118 -43.164248)
			(xy 130.675275 -43.154118) (xy 130.622491 -43.136111) (xy 130.572891 -43.11061) (xy 130.527533 -43.078159)
			(xy 130.487384 -43.03945) (xy 130.453298 -42.995307) (xy 130.426002 -42.946672) (xy 130.406079 -42.894581)
			(xy 130.393953 -42.840144) (xy 130.389882 -42.784522) (xy 120.5865 -42.784522) (xy 120.5865 -43.271948)
			(xy 132.515862 -43.271948) (xy 132.519933 -43.216326) (xy 132.532059 -43.161889) (xy 132.551982 -43.109798)
			(xy 132.579278 -43.061163) (xy 132.613364 -43.01702) (xy 132.653513 -42.978311) (xy 132.698871 -42.94586)
			(xy 132.748471 -42.920359) (xy 132.801255 -42.902352) (xy 132.856098 -42.892222) (xy 132.911832 -42.890185)
			(xy 132.967269 -42.896285) (xy 133.021226 -42.910391) (xy 133.072555 -42.932203) (xy 133.120161 -42.961257)
			(xy 133.163029 -42.996932) (xy 133.200246 -43.038469) (xy 133.231019 -43.084982) (xy 133.254691 -43.135479)
			(xy 133.270759 -43.188886) (xy 133.278879 -43.244062) (xy 133.279388 -43.271948) (xy 133.278879 -43.299834)
			(xy 133.270759 -43.35501) (xy 133.254691 -43.408417) (xy 133.231019 -43.458914) (xy 133.200246 -43.505427)
			(xy 133.163029 -43.546964) (xy 133.120161 -43.582639) (xy 133.072555 -43.611693) (xy 133.021226 -43.633505)
			(xy 132.967269 -43.647611) (xy 132.911832 -43.653711) (xy 132.856098 -43.651674) (xy 132.801255 -43.641544)
			(xy 132.748471 -43.623537) (xy 132.698871 -43.598036) (xy 132.653513 -43.565585) (xy 132.613364 -43.526876)
			(xy 132.579278 -43.482733) (xy 132.551982 -43.434098) (xy 132.532059 -43.382007) (xy 132.519933 -43.32757)
			(xy 132.515862 -43.271948) (xy 120.5865 -43.271948) (xy 120.5865 -44.775628) (xy 122.60072 -46.789848)
			(xy 134.005574 -46.789848) (xy 134.02098 -46.789315) (xy 134.05039 -46.780129) (xy 134.075719 -46.762587)
			(xy 134.094661 -46.738286) (xy 134.105489 -46.70944) (xy 134.10692 -46.69409) (xy 134.108976 -46.666645)
			(xy 134.119986 -46.612722) (xy 134.138628 -46.56094) (xy 134.164515 -46.512373) (xy 134.19711 -46.468028)
			(xy 134.235737 -46.428825) (xy 134.279594 -46.395577) (xy 134.327773 -46.368974) (xy 134.379273 -46.349568)
			(xy 134.433027 -46.337761) (xy 134.48792 -46.333798) (xy 134.542813 -46.337761) (xy 134.596567 -46.349568)
			(xy 134.648067 -46.368974) (xy 134.696246 -46.395577) (xy 134.740103 -46.428825) (xy 134.77873 -46.468028)
			(xy 134.811325 -46.512373) (xy 134.837212 -46.56094) (xy 134.855854 -46.612722) (xy 134.866864 -46.666645)
			(xy 134.86892 -46.69409) (xy 134.870344 -46.709435) (xy 134.881203 -46.73826) (xy 134.900152 -46.762546)
			(xy 134.925471 -46.780088) (xy 134.954865 -46.789298) (xy 134.970266 -46.789848) (xy 136.45896 -46.789848)
			(xy 137.8204 -45.428408) (xy 137.8204 -37.532564) (xy 137.78992 -37.519356) (xy 137.764829 -37.50781)
			(xy 137.717983 -37.478553) (xy 137.675843 -37.442849) (xy 137.63929 -37.401444) (xy 137.609087 -37.355202)
			(xy 137.585866 -37.305089) (xy 137.570112 -37.252152) (xy 137.562153 -37.197497) (xy 137.562155 -37.142265)
			(xy 137.57012 -37.087611) (xy 137.58588 -37.034675) (xy 137.609106 -36.984564) (xy 137.639313 -36.938325)
			(xy 137.67587 -36.896923) (xy 137.718014 -36.861224) (xy 137.764863 -36.831972) (xy 137.78992 -36.820348)
			(xy 137.8204 -36.80714) (xy 137.8204 -31.295848) (xy 139.25804 -29.858208) (xy 141.44752 -29.858208)
			(xy 141.731492 -30.14218) (xy 143.124934 -30.14218) (xy 143.129005 -30.086558) (xy 143.141131 -30.032121)
			(xy 143.161054 -29.98003) (xy 143.18835 -29.931395) (xy 143.222436 -29.887252) (xy 143.262585 -29.848543)
			(xy 143.307943 -29.816092) (xy 143.357543 -29.790591) (xy 143.410327 -29.772584) (xy 143.46517 -29.762454)
			(xy 143.520904 -29.760417) (xy 143.576341 -29.766517) (xy 143.630298 -29.780623) (xy 143.681627 -29.802435)
			(xy 143.729233 -29.831489) (xy 143.772101 -29.867164) (xy 143.809318 -29.908701) (xy 143.840091 -29.955214)
			(xy 143.863763 -30.005711) (xy 143.879831 -30.059118) (xy 143.887951 -30.114294) (xy 143.88846 -30.14218)
			(xy 143.887951 -30.170066) (xy 143.879831 -30.225242) (xy 143.863763 -30.278649) (xy 143.840578 -30.328108)
			(xy 146.704302 -30.328108) (xy 146.708373 -30.272486) (xy 146.720499 -30.218049) (xy 146.740422 -30.165958)
			(xy 146.767718 -30.117323) (xy 146.801804 -30.07318) (xy 146.841953 -30.034471) (xy 146.887311 -30.00202)
			(xy 146.936911 -29.976519) (xy 146.989695 -29.958512) (xy 147.044538 -29.948382) (xy 147.100272 -29.946345)
			(xy 147.155709 -29.952445) (xy 147.209666 -29.966551) (xy 147.260995 -29.988363) (xy 147.308601 -30.017417)
			(xy 147.351469 -30.053092) (xy 147.388686 -30.094629) (xy 147.419459 -30.141142) (xy 147.443131 -30.191639)
			(xy 147.459199 -30.245046) (xy 147.467319 -30.300222) (xy 147.46755 -30.312868) (xy 154.584398 -30.312868)
			(xy 154.588469 -30.257246) (xy 154.600595 -30.202809) (xy 154.620518 -30.150718) (xy 154.647814 -30.102083)
			(xy 154.6819 -30.05794) (xy 154.722049 -30.019231) (xy 154.767407 -29.98678) (xy 154.817007 -29.961279)
			(xy 154.869791 -29.943272) (xy 154.924634 -29.933142) (xy 154.980368 -29.931105) (xy 155.035805 -29.937205)
			(xy 155.089762 -29.951311) (xy 155.141091 -29.973123) (xy 155.188697 -30.002177) (xy 155.231565 -30.037852)
			(xy 155.268782 -30.079389) (xy 155.299555 -30.125902) (xy 155.323227 -30.176399) (xy 155.339295 -30.229806)
			(xy 155.347415 -30.284982) (xy 155.347924 -30.312868) (xy 156.706822 -30.312868) (xy 156.710893 -30.257246)
			(xy 156.723019 -30.202809) (xy 156.742942 -30.150718) (xy 156.770238 -30.102083) (xy 156.804324 -30.05794)
			(xy 156.844473 -30.019231) (xy 156.889831 -29.98678) (xy 156.939431 -29.961279) (xy 156.992215 -29.943272)
			(xy 157.047058 -29.933142) (xy 157.102792 -29.931105) (xy 157.158229 -29.937205) (xy 157.212186 -29.951311)
			(xy 157.263515 -29.973123) (xy 157.311121 -30.002177) (xy 157.353989 -30.037852) (xy 157.391206 -30.079389)
			(xy 157.421979 -30.125902) (xy 157.445651 -30.176399) (xy 157.461719 -30.229806) (xy 157.467962 -30.272228)
			(xy 159.879536 -30.272228) (xy 159.883607 -30.216606) (xy 159.895733 -30.162169) (xy 159.915656 -30.110078)
			(xy 159.942952 -30.061443) (xy 159.977038 -30.0173) (xy 160.017187 -29.978591) (xy 160.062545 -29.94614)
			(xy 160.112145 -29.920639) (xy 160.164929 -29.902632) (xy 160.219772 -29.892502) (xy 160.275506 -29.890465)
			(xy 160.330943 -29.896565) (xy 160.3849 -29.910671) (xy 160.436229 -29.932483) (xy 160.483835 -29.961537)
			(xy 160.526703 -29.997212) (xy 160.56392 -30.038749) (xy 160.594693 -30.085262) (xy 160.618365 -30.135759)
			(xy 160.634433 -30.189166) (xy 160.642553 -30.244342) (xy 160.643062 -30.272228) (xy 160.642553 -30.300114)
			(xy 160.634433 -30.35529) (xy 160.618365 -30.408697) (xy 160.594693 -30.459194) (xy 160.56392 -30.505707)
			(xy 160.526703 -30.547244) (xy 160.483835 -30.582919) (xy 160.436229 -30.611973) (xy 160.3849 -30.633785)
			(xy 160.330943 -30.647891) (xy 160.275506 -30.653991) (xy 160.219772 -30.651954) (xy 160.164929 -30.641824)
			(xy 160.112145 -30.623817) (xy 160.062545 -30.598316) (xy 160.017187 -30.565865) (xy 159.977038 -30.527156)
			(xy 159.942952 -30.483013) (xy 159.915656 -30.434378) (xy 159.895733 -30.382287) (xy 159.883607 -30.32785)
			(xy 159.879536 -30.272228) (xy 157.467962 -30.272228) (xy 157.469839 -30.284982) (xy 157.470348 -30.312868)
			(xy 157.469839 -30.340754) (xy 157.461719 -30.39593) (xy 157.445651 -30.449337) (xy 157.421979 -30.499834)
			(xy 157.391206 -30.546347) (xy 157.353989 -30.587884) (xy 157.311121 -30.623559) (xy 157.263515 -30.652613)
			(xy 157.212186 -30.674425) (xy 157.158229 -30.688531) (xy 157.102792 -30.694631) (xy 157.047058 -30.692594)
			(xy 156.992215 -30.682464) (xy 156.939431 -30.664457) (xy 156.889831 -30.638956) (xy 156.844473 -30.606505)
			(xy 156.804324 -30.567796) (xy 156.770238 -30.523653) (xy 156.742942 -30.475018) (xy 156.723019 -30.422927)
			(xy 156.710893 -30.36849) (xy 156.706822 -30.312868) (xy 155.347924 -30.312868) (xy 155.347415 -30.340754)
			(xy 155.339295 -30.39593) (xy 155.323227 -30.449337) (xy 155.299555 -30.499834) (xy 155.268782 -30.546347)
			(xy 155.231565 -30.587884) (xy 155.188697 -30.623559) (xy 155.141091 -30.652613) (xy 155.089762 -30.674425)
			(xy 155.035805 -30.688531) (xy 154.980368 -30.694631) (xy 154.924634 -30.692594) (xy 154.869791 -30.682464)
			(xy 154.817007 -30.664457) (xy 154.767407 -30.638956) (xy 154.722049 -30.606505) (xy 154.6819 -30.567796)
			(xy 154.647814 -30.523653) (xy 154.620518 -30.475018) (xy 154.600595 -30.422927) (xy 154.588469 -30.36849)
			(xy 154.584398 -30.312868) (xy 147.46755 -30.312868) (xy 147.467828 -30.328108) (xy 147.467319 -30.355994)
			(xy 147.459199 -30.41117) (xy 147.443131 -30.464577) (xy 147.419459 -30.515074) (xy 147.388686 -30.561587)
			(xy 147.351469 -30.603124) (xy 147.308601 -30.638799) (xy 147.260995 -30.667853) (xy 147.209666 -30.689665)
			(xy 147.155709 -30.703771) (xy 147.100272 -30.709871) (xy 147.044538 -30.707834) (xy 146.989695 -30.697704)
			(xy 146.936911 -30.679697) (xy 146.887311 -30.654196) (xy 146.841953 -30.621745) (xy 146.801804 -30.583036)
			(xy 146.767718 -30.538893) (xy 146.740422 -30.490258) (xy 146.720499 -30.438167) (xy 146.708373 -30.38373)
			(xy 146.704302 -30.328108) (xy 143.840578 -30.328108) (xy 143.840091 -30.329146) (xy 143.809318 -30.375659)
			(xy 143.772101 -30.417196) (xy 143.729233 -30.452871) (xy 143.681627 -30.481925) (xy 143.630298 -30.503737)
			(xy 143.576341 -30.517843) (xy 143.520904 -30.523943) (xy 143.46517 -30.521906) (xy 143.410327 -30.511776)
			(xy 143.357543 -30.493769) (xy 143.307943 -30.468268) (xy 143.262585 -30.435817) (xy 143.222436 -30.397108)
			(xy 143.18835 -30.352965) (xy 143.161054 -30.30433) (xy 143.141131 -30.252239) (xy 143.129005 -30.197802)
			(xy 143.124934 -30.14218) (xy 141.731492 -30.14218) (xy 142.05204 -30.462728) (xy 142.05204 -31.774638)
			(xy 143.508982 -31.774638) (xy 143.513053 -31.719016) (xy 143.525179 -31.664579) (xy 143.545102 -31.612488)
			(xy 143.572398 -31.563853) (xy 143.606484 -31.51971) (xy 143.646633 -31.481001) (xy 143.691991 -31.44855)
			(xy 143.741591 -31.423049) (xy 143.794375 -31.405042) (xy 143.849218 -31.394912) (xy 143.904952 -31.392875)
			(xy 143.960389 -31.398975) (xy 144.014346 -31.413081) (xy 144.065675 -31.434893) (xy 144.113281 -31.463947)
			(xy 144.156149 -31.499622) (xy 144.193366 -31.541159) (xy 144.224139 -31.587672) (xy 144.247811 -31.638169)
			(xy 144.263879 -31.691576) (xy 144.271999 -31.746752) (xy 144.272508 -31.774638) (xy 144.271999 -31.802524)
			(xy 144.263879 -31.8577) (xy 144.247811 -31.911107) (xy 144.224139 -31.961604) (xy 144.193366 -32.008117)
			(xy 144.156149 -32.049654) (xy 144.113281 -32.085329) (xy 144.065675 -32.114383) (xy 144.014346 -32.136195)
			(xy 143.960389 -32.150301) (xy 143.904952 -32.156401) (xy 143.849218 -32.154364) (xy 143.794375 -32.144234)
			(xy 143.741591 -32.126227) (xy 143.691991 -32.100726) (xy 143.646633 -32.068275) (xy 143.606484 -32.029566)
			(xy 143.572398 -31.985423) (xy 143.545102 -31.936788) (xy 143.525179 -31.884697) (xy 143.513053 -31.83026)
			(xy 143.508982 -31.774638) (xy 142.05204 -31.774638) (xy 142.05204 -32.126428) (xy 141.97076 -32.207708)
			(xy 151.609552 -32.207708) (xy 151.609986 -32.18237) (xy 151.616693 -32.132141) (xy 151.629991 -32.083241)
			(xy 151.649646 -32.036532) (xy 151.67531 -31.992836) (xy 151.706534 -31.952923) (xy 151.72436 -31.934912)
			(xy 151.733671 -31.925279) (xy 151.747273 -31.902203) (xy 151.754411 -31.876386) (xy 151.754594 -31.849601)
			(xy 151.74781 -31.823688) (xy 151.734526 -31.800428) (xy 151.725376 -31.79064) (xy 151.704779 -31.769048)
			(xy 151.669842 -31.720677) (xy 151.642864 -31.667456) (xy 151.624504 -31.610682) (xy 151.61521 -31.551742)
			(xy 151.614632 -31.521908) (xy 151.615118 -31.494657) (xy 151.622874 -31.440709) (xy 151.638229 -31.388414)
			(xy 151.660871 -31.338837) (xy 151.690337 -31.292987) (xy 151.726028 -31.251796) (xy 151.767219 -31.216105)
			(xy 151.813069 -31.186639) (xy 151.862646 -31.163997) (xy 151.914941 -31.148642) (xy 151.968889 -31.140886)
			(xy 152.023391 -31.140886) (xy 152.077339 -31.148642) (xy 152.129634 -31.163997) (xy 152.179211 -31.186639)
			(xy 152.225061 -31.216105) (xy 152.266252 -31.251796) (xy 152.301943 -31.292987) (xy 152.328267 -31.333948)
			(xy 165.307262 -31.333948) (xy 165.311333 -31.278326) (xy 165.323459 -31.223889) (xy 165.343382 -31.171798)
			(xy 165.370678 -31.123163) (xy 165.404764 -31.07902) (xy 165.444913 -31.040311) (xy 165.490271 -31.00786)
			(xy 165.539871 -30.982359) (xy 165.592655 -30.964352) (xy 165.647498 -30.954222) (xy 165.703232 -30.952185)
			(xy 165.758669 -30.958285) (xy 165.812626 -30.972391) (xy 165.863955 -30.994203) (xy 165.911561 -31.023257)
			(xy 165.954429 -31.058932) (xy 165.991646 -31.100469) (xy 166.022419 -31.146982) (xy 166.046091 -31.197479)
			(xy 166.062159 -31.250886) (xy 166.070279 -31.306062) (xy 166.070788 -31.333948) (xy 166.070279 -31.361834)
			(xy 166.062159 -31.41701) (xy 166.046091 -31.470417) (xy 166.022419 -31.520914) (xy 165.991646 -31.567427)
			(xy 165.954429 -31.608964) (xy 165.911561 -31.644639) (xy 165.863955 -31.673693) (xy 165.812626 -31.695505)
			(xy 165.758669 -31.709611) (xy 165.703232 -31.715711) (xy 165.647498 -31.713674) (xy 165.592655 -31.703544)
			(xy 165.539871 -31.685537) (xy 165.490271 -31.660036) (xy 165.444913 -31.627585) (xy 165.404764 -31.588876)
			(xy 165.370678 -31.544733) (xy 165.343382 -31.496098) (xy 165.323459 -31.444007) (xy 165.311333 -31.38957)
			(xy 165.307262 -31.333948) (xy 152.328267 -31.333948) (xy 152.331409 -31.338837) (xy 152.354051 -31.388414)
			(xy 152.369406 -31.440709) (xy 152.377162 -31.494657) (xy 152.377648 -31.521908) (xy 152.377224 -31.547246)
			(xy 152.370515 -31.597476) (xy 152.357215 -31.646376) (xy 152.337559 -31.693085) (xy 152.311892 -31.73678)
			(xy 152.309498 -31.73984) (xy 167.892474 -31.73984) (xy 167.896545 -31.684218) (xy 167.908671 -31.629781)
			(xy 167.928594 -31.57769) (xy 167.95589 -31.529055) (xy 167.989976 -31.484912) (xy 168.030125 -31.446203)
			(xy 168.075483 -31.413752) (xy 168.125083 -31.388251) (xy 168.177867 -31.370244) (xy 168.23271 -31.360114)
			(xy 168.288444 -31.358077) (xy 168.343881 -31.364177) (xy 168.397838 -31.378283) (xy 168.449167 -31.400095)
			(xy 168.496773 -31.429149) (xy 168.539641 -31.464824) (xy 168.576858 -31.506361) (xy 168.607631 -31.552874)
			(xy 168.631303 -31.603371) (xy 168.647371 -31.656778) (xy 168.655491 -31.711954) (xy 168.656 -31.73984)
			(xy 168.655491 -31.767726) (xy 168.647371 -31.822902) (xy 168.631303 -31.876309) (xy 168.607631 -31.926806)
			(xy 168.576858 -31.973319) (xy 168.539641 -32.014856) (xy 168.496773 -32.050531) (xy 168.449167 -32.079585)
			(xy 168.397838 -32.101397) (xy 168.343881 -32.115503) (xy 168.288444 -32.121603) (xy 168.23271 -32.119566)
			(xy 168.177867 -32.109436) (xy 168.125083 -32.091429) (xy 168.075483 -32.065928) (xy 168.030125 -32.033477)
			(xy 167.989976 -31.994768) (xy 167.95589 -31.950625) (xy 167.928594 -31.90199) (xy 167.908671 -31.849899)
			(xy 167.896545 -31.795462) (xy 167.892474 -31.73984) (xy 152.309498 -31.73984) (xy 152.280667 -31.776694)
			(xy 152.26284 -31.794704) (xy 152.253513 -31.804323) (xy 152.239912 -31.827403) (xy 152.232777 -31.853224)
			(xy 152.232596 -31.880012) (xy 152.239384 -31.905927) (xy 152.252672 -31.929187) (xy 152.261824 -31.938976)
			(xy 152.282428 -31.960561) (xy 152.317365 -32.008933) (xy 152.344341 -32.062157) (xy 152.362699 -32.118932)
			(xy 152.371991 -32.177873) (xy 152.372568 -32.207708) (xy 152.372082 -32.234959) (xy 152.364326 -32.288907)
			(xy 152.348971 -32.341202) (xy 152.326329 -32.390779) (xy 152.296863 -32.436629) (xy 152.261172 -32.47782)
			(xy 152.219981 -32.513511) (xy 152.174131 -32.542977) (xy 152.124554 -32.565619) (xy 152.072259 -32.580974)
			(xy 152.018311 -32.58873) (xy 151.963809 -32.58873) (xy 151.909861 -32.580974) (xy 151.857566 -32.565619)
			(xy 151.807989 -32.542977) (xy 151.762139 -32.513511) (xy 151.720948 -32.47782) (xy 151.685257 -32.436629)
			(xy 151.655791 -32.390779) (xy 151.633149 -32.341202) (xy 151.617794 -32.288907) (xy 151.610038 -32.234959)
			(xy 151.609552 -32.207708) (xy 141.97076 -32.207708) (xy 141.40942 -32.769048) (xy 140.16228 -32.769048)
			(xy 140.16228 -33.157668) (xy 143.806924 -33.157668) (xy 143.810995 -33.102046) (xy 143.823121 -33.047609)
			(xy 143.843044 -32.995518) (xy 143.87034 -32.946883) (xy 143.904426 -32.90274) (xy 143.944575 -32.864031)
			(xy 143.989933 -32.83158) (xy 144.039533 -32.806079) (xy 144.092317 -32.788072) (xy 144.14716 -32.777942)
			(xy 144.202894 -32.775905) (xy 144.258331 -32.782005) (xy 144.312288 -32.796111) (xy 144.363617 -32.817923)
			(xy 144.411223 -32.846977) (xy 144.454091 -32.882652) (xy 144.491308 -32.924189) (xy 144.522081 -32.970702)
			(xy 144.545753 -33.021199) (xy 144.561821 -33.074606) (xy 144.569941 -33.129782) (xy 144.57045 -33.157668)
			(xy 144.569941 -33.185554) (xy 144.561821 -33.24073) (xy 144.545753 -33.294137) (xy 144.522081 -33.344634)
			(xy 144.491308 -33.391147) (xy 144.454091 -33.432684) (xy 144.411223 -33.468359) (xy 144.363617 -33.497413)
			(xy 144.312288 -33.519225) (xy 144.258331 -33.533331) (xy 144.202894 -33.539431) (xy 144.14716 -33.537394)
			(xy 144.092317 -33.527264) (xy 144.039533 -33.509257) (xy 143.989933 -33.483756) (xy 143.944575 -33.451305)
			(xy 143.904426 -33.412596) (xy 143.87034 -33.368453) (xy 143.843044 -33.319818) (xy 143.823121 -33.267727)
			(xy 143.810995 -33.21329) (xy 143.806924 -33.157668) (xy 140.16228 -33.157668) (xy 140.16228 -33.564068)
			(xy 149.832312 -33.564068) (xy 149.836383 -33.508446) (xy 149.848509 -33.454009) (xy 149.868432 -33.401918)
			(xy 149.895728 -33.353283) (xy 149.929814 -33.30914) (xy 149.969963 -33.270431) (xy 150.015321 -33.23798)
			(xy 150.064921 -33.212479) (xy 150.117705 -33.194472) (xy 150.172548 -33.184342) (xy 150.228282 -33.182305)
			(xy 150.283719 -33.188405) (xy 150.337676 -33.202511) (xy 150.389005 -33.224323) (xy 150.436611 -33.253377)
			(xy 150.479479 -33.289052) (xy 150.516696 -33.330589) (xy 150.547469 -33.377102) (xy 150.571141 -33.427599)
			(xy 150.587209 -33.481006) (xy 150.595329 -33.536182) (xy 150.595838 -33.564068) (xy 150.595329 -33.591954)
			(xy 150.587209 -33.64713) (xy 150.571141 -33.700537) (xy 150.547469 -33.751034) (xy 150.516696 -33.797547)
			(xy 150.479479 -33.839084) (xy 150.436611 -33.874759) (xy 150.389005 -33.903813) (xy 150.337676 -33.925625)
			(xy 150.283719 -33.939731) (xy 150.228282 -33.945831) (xy 150.172548 -33.943794) (xy 150.117705 -33.933664)
			(xy 150.064921 -33.915657) (xy 150.015321 -33.890156) (xy 149.969963 -33.857705) (xy 149.929814 -33.818996)
			(xy 149.895728 -33.774853) (xy 149.868432 -33.726218) (xy 149.848509 -33.674127) (xy 149.836383 -33.61969)
			(xy 149.832312 -33.564068) (xy 140.16228 -33.564068) (xy 140.16228 -34.12236) (xy 140.726412 -34.12236)
			(xy 140.730483 -34.066738) (xy 140.742609 -34.012301) (xy 140.762532 -33.96021) (xy 140.789828 -33.911575)
			(xy 140.823914 -33.867432) (xy 140.864063 -33.828723) (xy 140.909421 -33.796272) (xy 140.959021 -33.770771)
			(xy 141.011805 -33.752764) (xy 141.066648 -33.742634) (xy 141.122382 -33.740597) (xy 141.177819 -33.746697)
			(xy 141.231776 -33.760803) (xy 141.283105 -33.782615) (xy 141.330711 -33.811669) (xy 141.373579 -33.847344)
			(xy 141.410796 -33.888881) (xy 141.441569 -33.935394) (xy 141.465241 -33.985891) (xy 141.466714 -33.990788)
			(xy 165.220902 -33.990788) (xy 165.224973 -33.935166) (xy 165.237099 -33.880729) (xy 165.257022 -33.828638)
			(xy 165.284318 -33.780003) (xy 165.318404 -33.73586) (xy 165.358553 -33.697151) (xy 165.403911 -33.6647)
			(xy 165.453511 -33.639199) (xy 165.506295 -33.621192) (xy 165.561138 -33.611062) (xy 165.616872 -33.609025)
			(xy 165.672309 -33.615125) (xy 165.726266 -33.629231) (xy 165.727134 -33.6296) (xy 169.366182 -33.6296)
			(xy 169.370253 -33.573978) (xy 169.382379 -33.519541) (xy 169.402302 -33.46745) (xy 169.429598 -33.418815)
			(xy 169.463684 -33.374672) (xy 169.503833 -33.335963) (xy 169.549191 -33.303512) (xy 169.598791 -33.278011)
			(xy 169.651575 -33.260004) (xy 169.706418 -33.249874) (xy 169.762152 -33.247837) (xy 169.817589 -33.253937)
			(xy 169.871546 -33.268043) (xy 169.922875 -33.289855) (xy 169.970481 -33.318909) (xy 170.013349 -33.354584)
			(xy 170.050566 -33.396121) (xy 170.081339 -33.442634) (xy 170.105011 -33.493131) (xy 170.121079 -33.546538)
			(xy 170.129199 -33.601714) (xy 170.129708 -33.6296) (xy 170.129199 -33.657486) (xy 170.121079 -33.712662)
			(xy 170.105011 -33.766069) (xy 170.081339 -33.816566) (xy 170.050566 -33.863079) (xy 170.013349 -33.904616)
			(xy 169.970481 -33.940291) (xy 169.922875 -33.969345) (xy 169.871546 -33.991157) (xy 169.817589 -34.005263)
			(xy 169.762152 -34.011363) (xy 169.706418 -34.009326) (xy 169.651575 -33.999196) (xy 169.598791 -33.981189)
			(xy 169.549191 -33.955688) (xy 169.503833 -33.923237) (xy 169.463684 -33.884528) (xy 169.429598 -33.840385)
			(xy 169.402302 -33.79175) (xy 169.382379 -33.739659) (xy 169.370253 -33.685222) (xy 169.366182 -33.6296)
			(xy 165.727134 -33.6296) (xy 165.777595 -33.651043) (xy 165.825201 -33.680097) (xy 165.868069 -33.715772)
			(xy 165.905286 -33.757309) (xy 165.936059 -33.803822) (xy 165.959731 -33.854319) (xy 165.975799 -33.907726)
			(xy 165.983919 -33.962902) (xy 165.984428 -33.990788) (xy 165.983919 -34.018674) (xy 165.975799 -34.07385)
			(xy 165.959731 -34.127257) (xy 165.936059 -34.177754) (xy 165.905286 -34.224267) (xy 165.868069 -34.265804)
			(xy 165.825201 -34.301479) (xy 165.777595 -34.330533) (xy 165.726266 -34.352345) (xy 165.672309 -34.366451)
			(xy 165.616872 -34.372551) (xy 165.561138 -34.370514) (xy 165.506295 -34.360384) (xy 165.453511 -34.342377)
			(xy 165.403911 -34.316876) (xy 165.358553 -34.284425) (xy 165.318404 -34.245716) (xy 165.284318 -34.201573)
			(xy 165.257022 -34.152938) (xy 165.237099 -34.100847) (xy 165.224973 -34.04641) (xy 165.220902 -33.990788)
			(xy 141.466714 -33.990788) (xy 141.481309 -34.039298) (xy 141.489429 -34.094474) (xy 141.489938 -34.12236)
			(xy 141.489429 -34.150246) (xy 141.481309 -34.205422) (xy 141.465241 -34.258829) (xy 141.441569 -34.309326)
			(xy 141.410796 -34.355839) (xy 141.373579 -34.397376) (xy 141.330711 -34.433051) (xy 141.283105 -34.462105)
			(xy 141.231776 -34.483917) (xy 141.177819 -34.498023) (xy 141.122382 -34.504123) (xy 141.066648 -34.502086)
			(xy 141.011805 -34.491956) (xy 140.959021 -34.473949) (xy 140.909421 -34.448448) (xy 140.864063 -34.415997)
			(xy 140.823914 -34.377288) (xy 140.789828 -34.333145) (xy 140.762532 -34.28451) (xy 140.742609 -34.232419)
			(xy 140.730483 -34.177982) (xy 140.726412 -34.12236) (xy 140.16228 -34.12236) (xy 140.16228 -35.695128)
			(xy 145.251422 -35.695128) (xy 145.255493 -35.639506) (xy 145.267619 -35.585069) (xy 145.287542 -35.532978)
			(xy 145.314838 -35.484343) (xy 145.348924 -35.4402) (xy 145.389073 -35.401491) (xy 145.434431 -35.36904)
			(xy 145.484031 -35.343539) (xy 145.536815 -35.325532) (xy 145.591658 -35.315402) (xy 145.647392 -35.313365)
			(xy 145.702829 -35.319465) (xy 145.756786 -35.333571) (xy 145.808115 -35.355383) (xy 145.855721 -35.384437)
			(xy 145.898589 -35.420112) (xy 145.935806 -35.461649) (xy 145.966579 -35.508162) (xy 145.990251 -35.558659)
			(xy 146.006319 -35.612066) (xy 146.014439 -35.667242) (xy 146.014948 -35.695128) (xy 146.014439 -35.723014)
			(xy 146.006319 -35.77819) (xy 145.990251 -35.831597) (xy 145.966579 -35.882094) (xy 145.935806 -35.928607)
			(xy 145.898589 -35.970144) (xy 145.855721 -36.005819) (xy 145.808115 -36.034873) (xy 145.756786 -36.056685)
			(xy 145.702829 -36.070791) (xy 145.647392 -36.076891) (xy 145.591658 -36.074854) (xy 145.536815 -36.064724)
			(xy 145.484031 -36.046717) (xy 145.434431 -36.021216) (xy 145.389073 -35.988765) (xy 145.348924 -35.950056)
			(xy 145.314838 -35.905913) (xy 145.287542 -35.857278) (xy 145.267619 -35.805187) (xy 145.255493 -35.75075)
			(xy 145.251422 -35.695128) (xy 140.16228 -35.695128) (xy 140.16228 -36.111942) (xy 143.100552 -36.111942)
			(xy 143.101038 -36.084691) (xy 143.108794 -36.030743) (xy 143.124149 -35.978448) (xy 143.146791 -35.928871)
			(xy 143.176257 -35.883021) (xy 143.211948 -35.84183) (xy 143.253139 -35.806139) (xy 143.298989 -35.776673)
			(xy 143.348566 -35.754031) (xy 143.400861 -35.738676) (xy 143.454809 -35.73092) (xy 143.509311 -35.73092)
			(xy 143.563259 -35.738676) (xy 143.615554 -35.754031) (xy 143.665131 -35.776673) (xy 143.710981 -35.806139)
			(xy 143.752172 -35.84183) (xy 143.787863 -35.883021) (xy 143.817329 -35.928871) (xy 143.839971 -35.978448)
			(xy 143.855326 -36.030743) (xy 143.863082 -36.084691) (xy 143.863568 -36.111942) (xy 143.863014 -36.141526)
			(xy 143.853874 -36.199984) (xy 143.83582 -36.256331) (xy 143.809285 -36.309216) (xy 143.774905 -36.357371)
			(xy 143.754602 -36.378896) (xy 143.745115 -36.389321) (xy 143.731699 -36.414095) (xy 143.725559 -36.441591)
			(xy 143.727161 -36.469719) (xy 143.736383 -36.49634) (xy 143.752526 -36.519431) (xy 143.77436 -36.537235)
			(xy 143.787114 -36.543234) (xy 143.812508 -36.554623) (xy 143.859943 -36.583732) (xy 143.902647 -36.619422)
			(xy 143.939713 -36.660936) (xy 143.970356 -36.707394) (xy 143.993925 -36.757811) (xy 144.009921 -36.811117)
			(xy 144.018005 -36.866181) (xy 144.018508 -36.894008) (xy 144.018022 -36.921259) (xy 144.010266 -36.975207)
			(xy 143.994911 -37.027502) (xy 143.972269 -37.077079) (xy 143.942803 -37.122929) (xy 143.907112 -37.16412)
			(xy 143.865921 -37.199811) (xy 143.820071 -37.229277) (xy 143.770494 -37.251919) (xy 143.718199 -37.267274)
			(xy 143.664251 -37.27503) (xy 143.609749 -37.27503) (xy 143.555801 -37.267274) (xy 143.503506 -37.251919)
			(xy 143.453929 -37.229277) (xy 143.408079 -37.199811) (xy 143.366888 -37.16412) (xy 143.331197 -37.122929)
			(xy 143.301731 -37.077079) (xy 143.279089 -37.027502) (xy 143.263734 -36.975207) (xy 143.255978 -36.921259)
			(xy 143.255492 -36.894008) (xy 143.25606 -36.864424) (xy 143.265194 -36.805966) (xy 143.283243 -36.749618)
			(xy 143.309776 -36.696733) (xy 143.344155 -36.648579) (xy 143.364458 -36.627054) (xy 143.373983 -36.616665)
			(xy 143.387386 -36.59188) (xy 143.393514 -36.564377) (xy 143.391904 -36.536247) (xy 143.382677 -36.509623)
			(xy 143.366533 -36.48653) (xy 143.3447 -36.468719) (xy 143.331946 -36.462716) (xy 143.306562 -36.451306)
			(xy 143.25913 -36.422198) (xy 143.216428 -36.38651) (xy 143.179363 -36.344998) (xy 143.148719 -36.298543)
			(xy 143.125148 -36.24813) (xy 143.109148 -36.194828) (xy 143.101059 -36.139768) (xy 143.100552 -36.111942)
			(xy 140.16228 -36.111942) (xy 140.16228 -37.213032) (xy 140.175935 -37.235832) (xy 140.197493 -37.284407)
			(xy 140.212101 -37.335504) (xy 140.219475 -37.388135) (xy 140.219474 -37.441279) (xy 140.212098 -37.493909)
			(xy 140.197488 -37.545006) (xy 140.175929 -37.59358) (xy 140.16228 -37.616384) (xy 140.16228 -39.741348)
			(xy 140.726412 -39.741348) (xy 140.730483 -39.685726) (xy 140.742609 -39.631289) (xy 140.762532 -39.579198)
			(xy 140.789828 -39.530563) (xy 140.823914 -39.48642) (xy 140.864063 -39.447711) (xy 140.909421 -39.41526)
			(xy 140.959021 -39.389759) (xy 141.011805 -39.371752) (xy 141.066648 -39.361622) (xy 141.122382 -39.359585)
			(xy 141.177819 -39.365685) (xy 141.231776 -39.379791) (xy 141.245794 -39.385748) (xy 147.222462 -39.385748)
			(xy 147.226533 -39.330126) (xy 147.238659 -39.275689) (xy 147.258582 -39.223598) (xy 147.285878 -39.174963)
			(xy 147.319964 -39.13082) (xy 147.360113 -39.092111) (xy 147.405471 -39.05966) (xy 147.455071 -39.034159)
			(xy 147.507855 -39.016152) (xy 147.562698 -39.006022) (xy 147.618432 -39.003985) (xy 147.673869 -39.010085)
			(xy 147.727826 -39.024191) (xy 147.779155 -39.046003) (xy 147.826761 -39.075057) (xy 147.869629 -39.110732)
			(xy 147.906846 -39.152269) (xy 147.937619 -39.198782) (xy 147.961291 -39.249279) (xy 147.977359 -39.302686)
			(xy 147.985479 -39.357862) (xy 147.985779 -39.374318) (xy 148.487892 -39.374318) (xy 148.487892 -35.640518)
			(xy 148.86559 -35.26282) (xy 151.57577 -35.26282) (xy 151.968708 -35.655758) (xy 151.968708 -36.341558)
			(xy 152.604216 -36.341558) (xy 152.604702 -36.314307) (xy 152.612458 -36.260359) (xy 152.627813 -36.208064)
			(xy 152.650455 -36.158487) (xy 152.679921 -36.112637) (xy 152.715612 -36.071446) (xy 152.756803 -36.035755)
			(xy 152.802653 -36.006289) (xy 152.85223 -35.983647) (xy 152.904525 -35.968292) (xy 152.958473 -35.960536)
			(xy 153.012975 -35.960536) (xy 153.066923 -35.968292) (xy 153.119218 -35.983647) (xy 153.168795 -36.006289)
			(xy 153.214645 -36.035755) (xy 153.255836 -36.071446) (xy 153.291527 -36.112637) (xy 153.320993 -36.158487)
			(xy 153.343635 -36.208064) (xy 153.35899 -36.260359) (xy 153.366746 -36.314307) (xy 153.367232 -36.341558)
			(xy 153.36673 -36.369962) (xy 153.358311 -36.426143) (xy 153.341654 -36.480454) (xy 153.317126 -36.531693)
			(xy 153.286774 -36.576508) (xy 153.590242 -36.576508) (xy 153.594313 -36.520886) (xy 153.606439 -36.466449)
			(xy 153.626362 -36.414358) (xy 153.653658 -36.365723) (xy 153.687744 -36.32158) (xy 153.727893 -36.282871)
			(xy 153.773251 -36.25042) (xy 153.822851 -36.224919) (xy 153.875635 -36.206912) (xy 153.930478 -36.196782)
			(xy 153.986212 -36.194745) (xy 154.041649 -36.200845) (xy 154.095606 -36.214951) (xy 154.146935 -36.236763)
			(xy 154.194541 -36.265817) (xy 154.222985 -36.289488) (xy 155.236162 -36.289488) (xy 155.240233 -36.233866)
			(xy 155.252359 -36.179429) (xy 155.272282 -36.127338) (xy 155.299578 -36.078703) (xy 155.333664 -36.03456)
			(xy 155.373813 -35.995851) (xy 155.419171 -35.9634) (xy 155.468771 -35.937899) (xy 155.521555 -35.919892)
			(xy 155.576398 -35.909762) (xy 155.632132 -35.907725) (xy 155.687569 -35.913825) (xy 155.741526 -35.927931)
			(xy 155.792855 -35.949743) (xy 155.840461 -35.978797) (xy 155.883329 -36.014472) (xy 155.920546 -36.056009)
			(xy 155.951319 -36.102522) (xy 155.974991 -36.153019) (xy 155.991059 -36.206426) (xy 155.999179 -36.261602)
			(xy 155.999549 -36.281868) (xy 158.268922 -36.281868) (xy 158.272993 -36.226246) (xy 158.285119 -36.171809)
			(xy 158.305042 -36.119718) (xy 158.332338 -36.071083) (xy 158.366424 -36.02694) (xy 158.406573 -35.988231)
			(xy 158.451931 -35.95578) (xy 158.501531 -35.930279) (xy 158.554315 -35.912272) (xy 158.609158 -35.902142)
			(xy 158.664892 -35.900105) (xy 158.720329 -35.906205) (xy 158.774286 -35.920311) (xy 158.825615 -35.942123)
			(xy 158.873221 -35.971177) (xy 158.916089 -36.006852) (xy 158.953306 -36.048389) (xy 158.984079 -36.094902)
			(xy 159.007751 -36.145399) (xy 159.023819 -36.198806) (xy 159.031939 -36.253982) (xy 159.032448 -36.281868)
			(xy 159.031939 -36.309754) (xy 159.023819 -36.36493) (xy 159.007751 -36.418337) (xy 158.984079 -36.468834)
			(xy 158.953306 -36.515347) (xy 158.916089 -36.556884) (xy 158.873221 -36.592559) (xy 158.825615 -36.621613)
			(xy 158.774286 -36.643425) (xy 158.720329 -36.657531) (xy 158.664892 -36.663631) (xy 158.609158 -36.661594)
			(xy 158.554315 -36.651464) (xy 158.501531 -36.633457) (xy 158.451931 -36.607956) (xy 158.406573 -36.575505)
			(xy 158.366424 -36.536796) (xy 158.332338 -36.492653) (xy 158.305042 -36.444018) (xy 158.285119 -36.391927)
			(xy 158.272993 -36.33749) (xy 158.268922 -36.281868) (xy 155.999549 -36.281868) (xy 155.999688 -36.289488)
			(xy 155.999179 -36.317374) (xy 155.991059 -36.37255) (xy 155.974991 -36.425957) (xy 155.951319 -36.476454)
			(xy 155.920546 -36.522967) (xy 155.883329 -36.564504) (xy 155.840461 -36.600179) (xy 155.792855 -36.629233)
			(xy 155.741526 -36.651045) (xy 155.687569 -36.665151) (xy 155.632132 -36.671251) (xy 155.576398 -36.669214)
			(xy 155.521555 -36.659084) (xy 155.468771 -36.641077) (xy 155.419171 -36.615576) (xy 155.373813 -36.583125)
			(xy 155.333664 -36.544416) (xy 155.299578 -36.500273) (xy 155.272282 -36.451638) (xy 155.252359 -36.399547)
			(xy 155.240233 -36.34511) (xy 155.236162 -36.289488) (xy 154.222985 -36.289488) (xy 154.237409 -36.301492)
			(xy 154.274626 -36.343029) (xy 154.305399 -36.389542) (xy 154.329071 -36.440039) (xy 154.345139 -36.493446)
			(xy 154.353259 -36.548622) (xy 154.353768 -36.576508) (xy 154.353259 -36.604394) (xy 154.345139 -36.65957)
			(xy 154.329071 -36.712977) (xy 154.305399 -36.763474) (xy 154.274626 -36.809987) (xy 154.260791 -36.825428)
			(xy 164.918642 -36.825428) (xy 164.922713 -36.769806) (xy 164.934839 -36.715369) (xy 164.954762 -36.663278)
			(xy 164.982058 -36.614643) (xy 165.016144 -36.5705) (xy 165.056293 -36.531791) (xy 165.101651 -36.49934)
			(xy 165.151251 -36.473839) (xy 165.204035 -36.455832) (xy 165.258878 -36.445702) (xy 165.314612 -36.443665)
			(xy 165.370049 -36.449765) (xy 165.424006 -36.463871) (xy 165.475335 -36.485683) (xy 165.522941 -36.514737)
			(xy 165.565809 -36.550412) (xy 165.603026 -36.591949) (xy 165.633799 -36.638462) (xy 165.657471 -36.688959)
			(xy 165.673539 -36.742366) (xy 165.681659 -36.797542) (xy 165.682168 -36.825428) (xy 165.681659 -36.853314)
			(xy 165.673539 -36.90849) (xy 165.657471 -36.961897) (xy 165.633799 -37.012394) (xy 165.603026 -37.058907)
			(xy 165.565809 -37.100444) (xy 165.522941 -37.136119) (xy 165.475335 -37.165173) (xy 165.424006 -37.186985)
			(xy 165.370049 -37.201091) (xy 165.314612 -37.207191) (xy 165.258878 -37.205154) (xy 165.204035 -37.195024)
			(xy 165.151251 -37.177017) (xy 165.101651 -37.151516) (xy 165.056293 -37.119065) (xy 165.016144 -37.080356)
			(xy 164.982058 -37.036213) (xy 164.954762 -36.987578) (xy 164.934839 -36.935487) (xy 164.922713 -36.88105)
			(xy 164.918642 -36.825428) (xy 154.260791 -36.825428) (xy 154.237409 -36.851524) (xy 154.194541 -36.887199)
			(xy 154.146935 -36.916253) (xy 154.095606 -36.938065) (xy 154.041649 -36.952171) (xy 153.986212 -36.958271)
			(xy 153.930478 -36.956234) (xy 153.875635 -36.946104) (xy 153.822851 -36.928097) (xy 153.773251 -36.902596)
			(xy 153.727893 -36.870145) (xy 153.687744 -36.831436) (xy 153.653658 -36.787293) (xy 153.626362 -36.738658)
			(xy 153.606439 -36.686567) (xy 153.594313 -36.63213) (xy 153.590242 -36.576508) (xy 153.286774 -36.576508)
			(xy 153.28527 -36.578729) (xy 153.24679 -36.62052) (xy 153.224992 -36.638738) (xy 153.214322 -36.647901)
			(xy 153.198067 -36.670841) (xy 153.188678 -36.697343) (xy 153.186865 -36.7254) (xy 153.192765 -36.752889)
			(xy 153.205931 -36.777731) (xy 153.225368 -36.798046) (xy 153.249604 -36.812296) (xy 153.263092 -36.816284)
			(xy 153.289961 -36.823798) (xy 153.341324 -36.845581) (xy 153.388965 -36.874615) (xy 153.431869 -36.910278)
			(xy 153.46912 -36.951811) (xy 153.499923 -36.998328) (xy 153.523622 -37.048835) (xy 153.53971 -37.102256)
			(xy 153.547845 -37.157451) (xy 153.548334 -37.185346) (xy 153.547848 -37.212597) (xy 153.540092 -37.266545)
			(xy 153.524737 -37.31884) (xy 153.502095 -37.368417) (xy 153.472629 -37.414267) (xy 153.436938 -37.455458)
			(xy 153.395747 -37.491149) (xy 153.349897 -37.520615) (xy 153.30032 -37.543257) (xy 153.248025 -37.558612)
			(xy 153.194077 -37.566368) (xy 153.139575 -37.566368) (xy 153.085627 -37.558612) (xy 153.033332 -37.543257)
			(xy 152.983755 -37.520615) (xy 152.937905 -37.491149) (xy 152.896714 -37.455458) (xy 152.861023 -37.414267)
			(xy 152.831557 -37.368417) (xy 152.808915 -37.31884) (xy 152.79356 -37.266545) (xy 152.785804 -37.212597)
			(xy 152.785318 -37.185346) (xy 152.785804 -37.156941) (xy 152.794224 -37.100759) (xy 152.810883 -37.046447)
			(xy 152.835414 -36.995207) (xy 152.867274 -36.948172) (xy 152.905758 -36.906383) (xy 152.927558 -36.888166)
			(xy 152.938206 -36.878983) (xy 152.95445 -36.856045) (xy 152.963832 -36.82955) (xy 152.965644 -36.801501)
			(xy 152.959747 -36.774019) (xy 152.946589 -36.749182) (xy 152.927164 -36.728868) (xy 152.90294 -36.714613)
			(xy 152.889458 -36.71062) (xy 152.862581 -36.703135) (xy 152.811219 -36.681345) (xy 152.763579 -36.652307)
			(xy 152.720677 -36.616639) (xy 152.683428 -36.575102) (xy 152.652626 -36.528583) (xy 152.628928 -36.478073)
			(xy 152.61284 -36.42465) (xy 152.604705 -36.369454) (xy 152.604216 -36.341558) (xy 151.968708 -36.341558)
			(xy 151.968708 -39.080948) (xy 152.635712 -39.080948) (xy 152.636214 -39.052772) (xy 152.644503 -38.997033)
			(xy 152.660908 -38.943121) (xy 152.685072 -38.892212) (xy 152.716467 -38.845416) (xy 152.754409 -38.803751)
			(xy 152.77592 -38.785546) (xy 152.786587 -38.776269) (xy 152.802755 -38.753093) (xy 152.811955 -38.726373)
			(xy 152.813481 -38.698155) (xy 152.807217 -38.670599) (xy 152.793644 -38.645814) (xy 152.784048 -38.635432)
			(xy 152.763537 -38.613857) (xy 152.728758 -38.565549) (xy 152.701906 -38.512424) (xy 152.683634 -38.455773)
			(xy 152.674384 -38.396971) (xy 152.673812 -38.367208) (xy 152.674298 -38.339957) (xy 152.682054 -38.286009)
			(xy 152.697409 -38.233714) (xy 152.720051 -38.184137) (xy 152.749517 -38.138287) (xy 152.785208 -38.097096)
			(xy 152.826399 -38.061405) (xy 152.872249 -38.031939) (xy 152.921826 -38.009297) (xy 152.974121 -37.993942)
			(xy 153.028069 -37.986186) (xy 153.082571 -37.986186) (xy 153.136519 -37.993942) (xy 153.188814 -38.009297)
			(xy 153.238391 -38.031939) (xy 153.284241 -38.061405) (xy 153.302987 -38.077648) (xy 167.990012 -38.077648)
			(xy 167.99056 -38.048732) (xy 167.999282 -37.991562) (xy 168.016534 -37.936364) (xy 168.04192 -37.884402)
			(xy 168.074859 -37.836867) (xy 168.114595 -37.794849) (xy 168.137078 -37.776658) (xy 168.148836 -37.766709)
			(xy 168.166356 -37.7414) (xy 168.175538 -37.71202) (xy 168.175547 -37.681239) (xy 168.166382 -37.651854)
			(xy 168.148877 -37.626535) (xy 168.137078 -37.616638) (xy 168.114608 -37.598431) (xy 168.074873 -37.556414)
			(xy 168.041933 -37.508882) (xy 168.016543 -37.456924) (xy 167.999283 -37.40173) (xy 167.99055 -37.344563)
			(xy 167.990012 -37.315648) (xy 167.9905 -37.288395) (xy 167.998251 -37.234444) (xy 168.013602 -37.182146)
			(xy 168.03624 -37.132564) (xy 168.065705 -37.08671) (xy 168.101397 -37.045516) (xy 168.142588 -37.009822)
			(xy 168.18844 -36.980354) (xy 168.238019 -36.957712) (xy 168.290317 -36.942357) (xy 168.344267 -36.934602)
			(xy 168.37152 -36.93414) (xy 168.39853 -36.934621) (xy 168.452013 -36.942219) (xy 168.503889 -36.957289)
			(xy 168.553118 -36.979529) (xy 168.598717 -37.008494) (xy 168.639771 -37.043605) (xy 168.675459 -37.084157)
			(xy 168.68559 -37.099618) (xy 170.60087 -37.099618) (xy 170.60087 -37.00031) (xy 170.608861 -36.901323)
			(xy 170.624791 -36.8033) (xy 170.648557 -36.706877) (xy 170.680005 -36.612679) (xy 170.718931 -36.521316)
			(xy 170.765082 -36.433383) (xy 170.818159 -36.349448) (xy 170.877818 -36.270056) (xy 170.943672 -36.195722)
			(xy 171.015294 -36.126929) (xy 171.092219 -36.064121) (xy 171.173949 -36.007707) (xy 171.259953 -35.958053)
			(xy 171.349673 -35.91548) (xy 171.442529 -35.880264) (xy 171.537917 -35.852635) (xy 171.635219 -35.832771)
			(xy 171.733804 -35.8208) (xy 171.833032 -35.816802) (xy 171.93226 -35.8208) (xy 172.030845 -35.832771)
			(xy 172.128147 -35.852635) (xy 172.223535 -35.880264) (xy 172.316391 -35.91548) (xy 172.406111 -35.958053)
			(xy 172.492115 -36.007707) (xy 172.573845 -36.064121) (xy 172.65077 -36.126929) (xy 172.722392 -36.195722)
			(xy 172.788246 -36.270056) (xy 172.847905 -36.349448) (xy 172.900982 -36.433383) (xy 172.947133 -36.521316)
			(xy 172.986059 -36.612679) (xy 173.017507 -36.706877) (xy 173.041273 -36.8033) (xy 173.057203 -36.901323)
			(xy 173.065194 -37.00031) (xy 173.065694 -37.049964) (xy 173.065194 -37.099618) (xy 173.057203 -37.198605)
			(xy 173.041273 -37.296628) (xy 173.017507 -37.393051) (xy 172.986059 -37.487249) (xy 172.947133 -37.578612)
			(xy 172.900982 -37.666545) (xy 172.847905 -37.75048) (xy 172.788246 -37.829872) (xy 172.722392 -37.904206)
			(xy 172.65077 -37.972999) (xy 172.573845 -38.035807) (xy 172.492115 -38.092221) (xy 172.406111 -38.141875)
			(xy 172.316391 -38.184448) (xy 172.223535 -38.219664) (xy 172.128147 -38.247293) (xy 172.030845 -38.267157)
			(xy 171.93226 -38.279128) (xy 171.833032 -38.283127) (xy 171.733804 -38.279128) (xy 171.635219 -38.267157)
			(xy 171.537917 -38.247293) (xy 171.442529 -38.219664) (xy 171.349673 -38.184448) (xy 171.259953 -38.141875)
			(xy 171.173949 -38.092221) (xy 171.092219 -38.035807) (xy 171.015294 -37.972999) (xy 170.943672 -37.904206)
			(xy 170.877818 -37.829872) (xy 170.818159 -37.75048) (xy 170.765082 -37.666545) (xy 170.718931 -37.578612)
			(xy 170.680005 -37.487249) (xy 170.648557 -37.393051) (xy 170.624791 -37.296628) (xy 170.608861 -37.198605)
			(xy 170.60087 -37.099618) (xy 168.68559 -37.099618) (xy 168.705067 -37.129341) (xy 168.71696 -37.153596)
			(xy 168.723471 -37.16663) (xy 168.742722 -37.18849) (xy 168.767365 -37.20402) (xy 168.795391 -37.211957)
			(xy 168.824517 -37.211653) (xy 168.852372 -37.203133) (xy 168.864788 -37.195506) (xy 168.888303 -37.180559)
			(xy 168.938758 -37.15692) (xy 168.992116 -37.140876) (xy 169.047241 -37.132768) (xy 169.0751 -37.13226)
			(xy 169.102349 -37.13281) (xy 169.156292 -37.140566) (xy 169.208582 -37.15592) (xy 169.258155 -37.178559)
			(xy 169.304002 -37.208023) (xy 169.345189 -37.243711) (xy 169.380877 -37.284898) (xy 169.410341 -37.330745)
			(xy 169.43298 -37.380318) (xy 169.448334 -37.432608) (xy 169.45609 -37.486551) (xy 169.45609 -37.541049)
			(xy 169.448334 -37.594992) (xy 169.43298 -37.647282) (xy 169.410341 -37.696855) (xy 169.380877 -37.742702)
			(xy 169.345189 -37.783889) (xy 169.304002 -37.819577) (xy 169.258155 -37.849041) (xy 169.208582 -37.87168)
			(xy 169.156292 -37.887034) (xy 169.102349 -37.89479) (xy 169.0751 -37.895276) (xy 169.047912 -37.894866)
			(xy 168.994087 -37.887158) (xy 168.941901 -37.871885) (xy 168.892413 -37.849356) (xy 168.846626 -37.820027)
			(xy 168.805468 -37.784494) (xy 168.769773 -37.743476) (xy 168.740265 -37.697804) (xy 168.717541 -37.648405)
			(xy 168.70934 -37.62248) (xy 168.705921 -37.612805) (xy 168.692829 -37.597031) (xy 168.674616 -37.587624)
			(xy 168.654175 -37.58608) (xy 168.634755 -37.592644) (xy 168.62679 -37.599112) (xy 168.605962 -37.616638)
			(xy 168.594104 -37.62648) (xy 168.576579 -37.651817) (xy 168.567403 -37.681226) (xy 168.567412 -37.712033)
			(xy 168.576605 -37.741437) (xy 168.594145 -37.766763) (xy 168.605962 -37.776658) (xy 168.628417 -37.794882)
			(xy 168.668156 -37.836894) (xy 168.7011 -37.884422) (xy 168.726493 -37.936377) (xy 168.743755 -37.991569)
			(xy 168.75249 -38.048734) (xy 168.753028 -38.077648) (xy 168.752542 -38.104899) (xy 168.744786 -38.158847)
			(xy 168.729431 -38.211142) (xy 168.706789 -38.260719) (xy 168.677323 -38.306569) (xy 168.641632 -38.34776)
			(xy 168.600441 -38.383451) (xy 168.554591 -38.412917) (xy 168.505014 -38.435559) (xy 168.452719 -38.450914)
			(xy 168.398771 -38.45867) (xy 168.344269 -38.45867) (xy 168.290321 -38.450914) (xy 168.238026 -38.435559)
			(xy 168.188449 -38.412917) (xy 168.142599 -38.383451) (xy 168.101408 -38.34776) (xy 168.065717 -38.306569)
			(xy 168.036251 -38.260719) (xy 168.013609 -38.211142) (xy 167.998254 -38.158847) (xy 167.990498 -38.104899)
			(xy 167.990012 -38.077648) (xy 153.302987 -38.077648) (xy 153.325432 -38.097096) (xy 153.361123 -38.138287)
			(xy 153.390589 -38.184137) (xy 153.413231 -38.233714) (xy 153.428586 -38.286009) (xy 153.436342 -38.339957)
			(xy 153.436828 -38.367208) (xy 153.436281 -38.395382) (xy 153.427999 -38.451119) (xy 153.411602 -38.505029)
			(xy 153.387447 -38.555937) (xy 153.356061 -38.602735) (xy 153.318127 -38.644403) (xy 153.29662 -38.66261)
			(xy 153.285994 -38.671931) (xy 153.269818 -38.695094) (xy 153.260611 -38.721803) (xy 153.259076 -38.750013)
			(xy 153.265332 -38.777564) (xy 153.2789 -38.802344) (xy 153.288492 -38.812724) (xy 153.309019 -38.834284)
			(xy 153.343799 -38.882595) (xy 153.370649 -38.935723) (xy 153.382259 -38.971728) (xy 153.552142 -38.971728)
			(xy 153.556213 -38.916106) (xy 153.568339 -38.861669) (xy 153.588262 -38.809578) (xy 153.615558 -38.760943)
			(xy 153.649644 -38.7168) (xy 153.689793 -38.678091) (xy 153.735151 -38.64564) (xy 153.784751 -38.620139)
			(xy 153.837535 -38.602132) (xy 153.892378 -38.592002) (xy 153.948112 -38.589965) (xy 154.003549 -38.596065)
			(xy 154.057506 -38.610171) (xy 154.108835 -38.631983) (xy 154.156441 -38.661037) (xy 154.199309 -38.696712)
			(xy 154.236526 -38.738249) (xy 154.267299 -38.784762) (xy 154.290971 -38.835259) (xy 154.307039 -38.888666)
			(xy 154.315159 -38.943842) (xy 154.315668 -38.971728) (xy 154.315159 -38.999614) (xy 154.307039 -39.05479)
			(xy 154.290971 -39.108197) (xy 154.267299 -39.158694) (xy 154.236526 -39.205207) (xy 154.199309 -39.246744)
			(xy 154.156441 -39.282419) (xy 154.108835 -39.311473) (xy 154.083479 -39.322248) (xy 155.198062 -39.322248)
			(xy 155.202133 -39.266626) (xy 155.214259 -39.212189) (xy 155.234182 -39.160098) (xy 155.261478 -39.111463)
			(xy 155.295564 -39.06732) (xy 155.335713 -39.028611) (xy 155.381071 -38.99616) (xy 155.430671 -38.970659)
			(xy 155.483455 -38.952652) (xy 155.538298 -38.942522) (xy 155.594032 -38.940485) (xy 155.649469 -38.946585)
			(xy 155.703426 -38.960691) (xy 155.754755 -38.982503) (xy 155.802361 -39.011557) (xy 155.845229 -39.047232)
			(xy 155.882446 -39.088769) (xy 155.913219 -39.135282) (xy 155.936891 -39.185779) (xy 155.952959 -39.239186)
			(xy 155.958081 -39.273988) (xy 158.246062 -39.273988) (xy 158.250133 -39.218366) (xy 158.262259 -39.163929)
			(xy 158.282182 -39.111838) (xy 158.309478 -39.063203) (xy 158.343564 -39.01906) (xy 158.383713 -38.980351)
			(xy 158.429071 -38.9479) (xy 158.478671 -38.922399) (xy 158.531455 -38.904392) (xy 158.586298 -38.894262)
			(xy 158.642032 -38.892225) (xy 158.697469 -38.898325) (xy 158.751426 -38.912431) (xy 158.802755 -38.934243)
			(xy 158.850361 -38.963297) (xy 158.893229 -38.998972) (xy 158.930266 -39.040308) (xy 159.965642 -39.040308)
			(xy 159.969713 -38.984686) (xy 159.981839 -38.930249) (xy 160.001762 -38.878158) (xy 160.029058 -38.829523)
			(xy 160.063144 -38.78538) (xy 160.103293 -38.746671) (xy 160.148651 -38.71422) (xy 160.198251 -38.688719)
			(xy 160.251035 -38.670712) (xy 160.305878 -38.660582) (xy 160.361612 -38.658545) (xy 160.417049 -38.664645)
			(xy 160.471006 -38.678751) (xy 160.522335 -38.700563) (xy 160.569941 -38.729617) (xy 160.570916 -38.730428)
			(xy 173.486062 -38.730428) (xy 173.490133 -38.674806) (xy 173.502259 -38.620369) (xy 173.522182 -38.568278)
			(xy 173.549478 -38.519643) (xy 173.583564 -38.4755) (xy 173.623713 -38.436791) (xy 173.669071 -38.40434)
			(xy 173.718671 -38.378839) (xy 173.771455 -38.360832) (xy 173.826298 -38.350702) (xy 173.882032 -38.348665)
			(xy 173.937469 -38.354765) (xy 173.991426 -38.368871) (xy 174.042755 -38.390683) (xy 174.090361 -38.419737)
			(xy 174.133229 -38.455412) (xy 174.170446 -38.496949) (xy 174.201219 -38.543462) (xy 174.224891 -38.593959)
			(xy 174.240959 -38.647366) (xy 174.249079 -38.702542) (xy 174.249588 -38.730428) (xy 174.502062 -38.730428)
			(xy 174.506133 -38.674806) (xy 174.518259 -38.620369) (xy 174.538182 -38.568278) (xy 174.565478 -38.519643)
			(xy 174.599564 -38.4755) (xy 174.639713 -38.436791) (xy 174.685071 -38.40434) (xy 174.734671 -38.378839)
			(xy 174.787455 -38.360832) (xy 174.842298 -38.350702) (xy 174.898032 -38.348665) (xy 174.953469 -38.354765)
			(xy 175.007426 -38.368871) (xy 175.058755 -38.390683) (xy 175.106361 -38.419737) (xy 175.149229 -38.455412)
			(xy 175.186446 -38.496949) (xy 175.217219 -38.543462) (xy 175.240891 -38.593959) (xy 175.256959 -38.647366)
			(xy 175.265079 -38.702542) (xy 175.265588 -38.730428) (xy 175.518062 -38.730428) (xy 175.522133 -38.674806)
			(xy 175.534259 -38.620369) (xy 175.554182 -38.568278) (xy 175.581478 -38.519643) (xy 175.615564 -38.4755)
			(xy 175.655713 -38.436791) (xy 175.701071 -38.40434) (xy 175.750671 -38.378839) (xy 175.803455 -38.360832)
			(xy 175.858298 -38.350702) (xy 175.914032 -38.348665) (xy 175.969469 -38.354765) (xy 176.023426 -38.368871)
			(xy 176.074755 -38.390683) (xy 176.122361 -38.419737) (xy 176.165229 -38.455412) (xy 176.202446 -38.496949)
			(xy 176.233219 -38.543462) (xy 176.256891 -38.593959) (xy 176.272959 -38.647366) (xy 176.281079 -38.702542)
			(xy 176.281588 -38.730428) (xy 176.281079 -38.758314) (xy 176.272959 -38.81349) (xy 176.256891 -38.866897)
			(xy 176.233219 -38.917394) (xy 176.202446 -38.963907) (xy 176.165229 -39.005444) (xy 176.122361 -39.041119)
			(xy 176.074755 -39.070173) (xy 176.023426 -39.091985) (xy 175.969469 -39.106091) (xy 175.914032 -39.112191)
			(xy 175.858298 -39.110154) (xy 175.803455 -39.100024) (xy 175.750671 -39.082017) (xy 175.701071 -39.056516)
			(xy 175.655713 -39.024065) (xy 175.615564 -38.985356) (xy 175.581478 -38.941213) (xy 175.554182 -38.892578)
			(xy 175.534259 -38.840487) (xy 175.522133 -38.78605) (xy 175.518062 -38.730428) (xy 175.265588 -38.730428)
			(xy 175.265079 -38.758314) (xy 175.256959 -38.81349) (xy 175.240891 -38.866897) (xy 175.217219 -38.917394)
			(xy 175.186446 -38.963907) (xy 175.149229 -39.005444) (xy 175.106361 -39.041119) (xy 175.058755 -39.070173)
			(xy 175.007426 -39.091985) (xy 174.953469 -39.106091) (xy 174.898032 -39.112191) (xy 174.842298 -39.110154)
			(xy 174.787455 -39.100024) (xy 174.734671 -39.082017) (xy 174.685071 -39.056516) (xy 174.639713 -39.024065)
			(xy 174.599564 -38.985356) (xy 174.565478 -38.941213) (xy 174.538182 -38.892578) (xy 174.518259 -38.840487)
			(xy 174.506133 -38.78605) (xy 174.502062 -38.730428) (xy 174.249588 -38.730428) (xy 174.249079 -38.758314)
			(xy 174.240959 -38.81349) (xy 174.224891 -38.866897) (xy 174.201219 -38.917394) (xy 174.170446 -38.963907)
			(xy 174.133229 -39.005444) (xy 174.090361 -39.041119) (xy 174.042755 -39.070173) (xy 173.991426 -39.091985)
			(xy 173.937469 -39.106091) (xy 173.882032 -39.112191) (xy 173.826298 -39.110154) (xy 173.771455 -39.100024)
			(xy 173.718671 -39.082017) (xy 173.669071 -39.056516) (xy 173.623713 -39.024065) (xy 173.583564 -38.985356)
			(xy 173.549478 -38.941213) (xy 173.522182 -38.892578) (xy 173.502259 -38.840487) (xy 173.490133 -38.78605)
			(xy 173.486062 -38.730428) (xy 160.570916 -38.730428) (xy 160.612809 -38.765292) (xy 160.650026 -38.806829)
			(xy 160.680799 -38.853342) (xy 160.704471 -38.903839) (xy 160.720539 -38.957246) (xy 160.728659 -39.012422)
			(xy 160.729168 -39.040308) (xy 160.728659 -39.068194) (xy 160.720539 -39.12337) (xy 160.704471 -39.176777)
			(xy 160.680799 -39.227274) (xy 160.650026 -39.273787) (xy 160.612809 -39.315324) (xy 160.569941 -39.350999)
			(xy 160.522335 -39.380053) (xy 160.471006 -39.401865) (xy 160.417049 -39.415971) (xy 160.361612 -39.422071)
			(xy 160.305878 -39.420034) (xy 160.251035 -39.409904) (xy 160.198251 -39.391897) (xy 160.148651 -39.366396)
			(xy 160.103293 -39.333945) (xy 160.063144 -39.295236) (xy 160.029058 -39.251093) (xy 160.001762 -39.202458)
			(xy 159.981839 -39.150367) (xy 159.969713 -39.09593) (xy 159.965642 -39.040308) (xy 158.930266 -39.040308)
			(xy 158.930446 -39.040509) (xy 158.961219 -39.087022) (xy 158.984891 -39.137519) (xy 159.000959 -39.190926)
			(xy 159.009079 -39.246102) (xy 159.009588 -39.273988) (xy 159.009079 -39.301874) (xy 159.000959 -39.35705)
			(xy 158.984891 -39.410457) (xy 158.961219 -39.460954) (xy 158.930446 -39.507467) (xy 158.893229 -39.549004)
			(xy 158.850361 -39.584679) (xy 158.802755 -39.613733) (xy 158.751426 -39.635545) (xy 158.697469 -39.649651)
			(xy 158.642032 -39.655751) (xy 158.586298 -39.653714) (xy 158.531455 -39.643584) (xy 158.478671 -39.625577)
			(xy 158.429071 -39.600076) (xy 158.383713 -39.567625) (xy 158.343564 -39.528916) (xy 158.309478 -39.484773)
			(xy 158.282182 -39.436138) (xy 158.262259 -39.384047) (xy 158.250133 -39.32961) (xy 158.246062 -39.273988)
			(xy 155.958081 -39.273988) (xy 155.961079 -39.294362) (xy 155.961588 -39.322248) (xy 155.961079 -39.350134)
			(xy 155.952959 -39.40531) (xy 155.936891 -39.458717) (xy 155.913219 -39.509214) (xy 155.882446 -39.555727)
			(xy 155.845229 -39.597264) (xy 155.802361 -39.632939) (xy 155.754755 -39.661993) (xy 155.703426 -39.683805)
			(xy 155.649469 -39.697911) (xy 155.594032 -39.704011) (xy 155.538298 -39.701974) (xy 155.483455 -39.691844)
			(xy 155.430671 -39.673837) (xy 155.381071 -39.648336) (xy 155.335713 -39.615885) (xy 155.295564 -39.577176)
			(xy 155.261478 -39.533033) (xy 155.234182 -39.484398) (xy 155.214259 -39.432307) (xy 155.202133 -39.37787)
			(xy 155.198062 -39.322248) (xy 154.083479 -39.322248) (xy 154.057506 -39.333285) (xy 154.003549 -39.347391)
			(xy 153.948112 -39.353491) (xy 153.892378 -39.351454) (xy 153.837535 -39.341324) (xy 153.784751 -39.323317)
			(xy 153.735151 -39.297816) (xy 153.689793 -39.265365) (xy 153.649644 -39.226656) (xy 153.615558 -39.182513)
			(xy 153.588262 -39.133878) (xy 153.568339 -39.081787) (xy 153.556213 -39.02735) (xy 153.552142 -38.971728)
			(xy 153.382259 -38.971728) (xy 153.388917 -38.992378) (xy 153.39816 -39.051184) (xy 153.398728 -39.080948)
			(xy 153.398242 -39.108199) (xy 153.390486 -39.162147) (xy 153.375131 -39.214442) (xy 153.352489 -39.264019)
			(xy 153.323023 -39.309869) (xy 153.287332 -39.35106) (xy 153.246141 -39.386751) (xy 153.200291 -39.416217)
			(xy 153.150714 -39.438859) (xy 153.098419 -39.454214) (xy 153.044471 -39.46197) (xy 152.989969 -39.46197)
			(xy 152.936021 -39.454214) (xy 152.883726 -39.438859) (xy 152.834149 -39.416217) (xy 152.788299 -39.386751)
			(xy 152.747108 -39.35106) (xy 152.711417 -39.309869) (xy 152.681951 -39.264019) (xy 152.659309 -39.214442)
			(xy 152.643954 -39.162147) (xy 152.636198 -39.108199) (xy 152.635712 -39.080948) (xy 151.968708 -39.080948)
			(xy 151.968708 -39.450518) (xy 151.64689 -39.772336) (xy 150.9268 -39.772336) (xy 150.916894 -39.809928)
			(xy 150.909488 -39.83556) (xy 150.888561 -39.884637) (xy 150.861018 -39.93033) (xy 150.827393 -39.971754)
			(xy 150.808182 -39.990268) (xy 150.797912 -40.000414) (xy 150.783088 -40.025174) (xy 150.775787 -40.053094)
			(xy 150.776591 -40.081941) (xy 150.785437 -40.10941) (xy 150.801618 -40.133306) (xy 150.82384 -40.151718)
			(xy 150.836884 -40.157908) (xy 150.862075 -40.169448) (xy 150.909173 -40.19863) (xy 150.951556 -40.234316)
			(xy 150.988332 -40.275756) (xy 151.018729 -40.322079) (xy 151.042107 -40.372311) (xy 151.057975 -40.425396)
			(xy 151.065999 -40.480217) (xy 151.0665 -40.50792) (xy 151.066014 -40.535171) (xy 151.058258 -40.589119)
			(xy 151.042903 -40.641414) (xy 151.020261 -40.690991) (xy 150.990795 -40.736841) (xy 150.955104 -40.778032)
			(xy 150.913913 -40.813723) (xy 150.868063 -40.843189) (xy 150.818486 -40.865831) (xy 150.766191 -40.881186)
			(xy 150.712243 -40.888942) (xy 150.657741 -40.888942) (xy 150.603793 -40.881186) (xy 150.551498 -40.865831)
			(xy 150.501921 -40.843189) (xy 150.456071 -40.813723) (xy 150.41488 -40.778032) (xy 150.379189 -40.736841)
			(xy 150.349723 -40.690991) (xy 150.327081 -40.641414) (xy 150.311726 -40.589119) (xy 150.30397 -40.535171)
			(xy 150.303484 -40.50792) (xy 150.303944 -40.481787) (xy 150.311083 -40.430011) (xy 150.325215 -40.379693)
			(xy 150.346078 -40.331772) (xy 150.373281 -40.287143) (xy 150.406316 -40.246642) (xy 150.42515 -40.22852)
			(xy 150.435425 -40.21838) (xy 150.450242 -40.193617) (xy 150.457539 -40.165698) (xy 150.456732 -40.136851)
			(xy 150.447886 -40.109383) (xy 150.431708 -40.085487) (xy 150.40949 -40.067072) (xy 150.396448 -40.06088)
			(xy 150.370391 -40.049082) (xy 150.321893 -40.018756) (xy 150.278469 -39.981525) (xy 150.241094 -39.938224)
			(xy 150.210608 -39.889827) (xy 150.187694 -39.837417) (xy 150.179786 -39.809928) (xy 150.16988 -39.772336)
			(xy 148.88591 -39.772336) (xy 148.487892 -39.374318) (xy 147.985779 -39.374318) (xy 147.985988 -39.385748)
			(xy 147.985479 -39.413634) (xy 147.977359 -39.46881) (xy 147.961291 -39.522217) (xy 147.937619 -39.572714)
			(xy 147.906846 -39.619227) (xy 147.869629 -39.660764) (xy 147.826761 -39.696439) (xy 147.779155 -39.725493)
			(xy 147.727826 -39.747305) (xy 147.673869 -39.761411) (xy 147.618432 -39.767511) (xy 147.562698 -39.765474)
			(xy 147.507855 -39.755344) (xy 147.455071 -39.737337) (xy 147.405471 -39.711836) (xy 147.360113 -39.679385)
			(xy 147.319964 -39.640676) (xy 147.285878 -39.596533) (xy 147.258582 -39.547898) (xy 147.238659 -39.495807)
			(xy 147.226533 -39.44137) (xy 147.222462 -39.385748) (xy 141.245794 -39.385748) (xy 141.283105 -39.401603)
			(xy 141.330711 -39.430657) (xy 141.373579 -39.466332) (xy 141.410796 -39.507869) (xy 141.441569 -39.554382)
			(xy 141.465241 -39.604879) (xy 141.481309 -39.658286) (xy 141.489429 -39.713462) (xy 141.489938 -39.741348)
			(xy 141.489429 -39.769234) (xy 141.481309 -39.82441) (xy 141.465241 -39.877817) (xy 141.441569 -39.928314)
			(xy 141.410796 -39.974827) (xy 141.373579 -40.016364) (xy 141.330711 -40.052039) (xy 141.283105 -40.081093)
			(xy 141.231776 -40.102905) (xy 141.177819 -40.117011) (xy 141.122382 -40.123111) (xy 141.066648 -40.121074)
			(xy 141.011805 -40.110944) (xy 140.959021 -40.092937) (xy 140.909421 -40.067436) (xy 140.864063 -40.034985)
			(xy 140.823914 -39.996276) (xy 140.789828 -39.952133) (xy 140.762532 -39.903498) (xy 140.742609 -39.851407)
			(xy 140.730483 -39.79697) (xy 140.726412 -39.741348) (xy 140.16228 -39.741348) (xy 140.16228 -40.952928)
			(xy 144.389092 -40.952928) (xy 144.393163 -40.897306) (xy 144.405289 -40.842869) (xy 144.425212 -40.790778)
			(xy 144.452508 -40.742143) (xy 144.486594 -40.698) (xy 144.526743 -40.659291) (xy 144.572101 -40.62684)
			(xy 144.621701 -40.601339) (xy 144.674485 -40.583332) (xy 144.729328 -40.573202) (xy 144.785062 -40.571165)
			(xy 144.840499 -40.577265) (xy 144.894456 -40.591371) (xy 144.945785 -40.613183) (xy 144.993391 -40.642237)
			(xy 145.036259 -40.677912) (xy 145.073476 -40.719449) (xy 145.104249 -40.765962) (xy 145.127921 -40.816459)
			(xy 145.143989 -40.869866) (xy 145.152109 -40.925042) (xy 145.152618 -40.952928) (xy 145.152109 -40.980814)
			(xy 145.143989 -41.03599) (xy 145.13077 -41.079928) (xy 149.399242 -41.079928) (xy 149.403313 -41.024306)
			(xy 149.415439 -40.969869) (xy 149.435362 -40.917778) (xy 149.462658 -40.869143) (xy 149.496744 -40.825)
			(xy 149.536893 -40.786291) (xy 149.582251 -40.75384) (xy 149.631851 -40.728339) (xy 149.684635 -40.710332)
			(xy 149.739478 -40.700202) (xy 149.795212 -40.698165) (xy 149.850649 -40.704265) (xy 149.904606 -40.718371)
			(xy 149.955935 -40.740183) (xy 150.003541 -40.769237) (xy 150.046409 -40.804912) (xy 150.083626 -40.846449)
			(xy 150.114399 -40.892962) (xy 150.138071 -40.943459) (xy 150.154139 -40.996866) (xy 150.162259 -41.052042)
			(xy 150.162397 -41.059608) (xy 153.608022 -41.059608) (xy 153.612093 -41.003986) (xy 153.624219 -40.949549)
			(xy 153.644142 -40.897458) (xy 153.671438 -40.848823) (xy 153.705524 -40.80468) (xy 153.745673 -40.765971)
			(xy 153.791031 -40.73352) (xy 153.840631 -40.708019) (xy 153.893415 -40.690012) (xy 153.948258 -40.679882)
			(xy 154.003992 -40.677845) (xy 154.059429 -40.683945) (xy 154.113386 -40.698051) (xy 154.164715 -40.719863)
			(xy 154.212321 -40.748917) (xy 154.255189 -40.784592) (xy 154.292406 -40.826129) (xy 154.323179 -40.872642)
			(xy 154.346851 -40.923139) (xy 154.362919 -40.976546) (xy 154.370283 -41.026588) (xy 156.074362 -41.026588)
			(xy 156.078433 -40.970966) (xy 156.090559 -40.916529) (xy 156.110482 -40.864438) (xy 156.137778 -40.815803)
			(xy 156.171864 -40.77166) (xy 156.212013 -40.732951) (xy 156.257371 -40.7005) (xy 156.306971 -40.674999)
			(xy 156.359755 -40.656992) (xy 156.414598 -40.646862) (xy 156.470332 -40.644825) (xy 156.525769 -40.650925)
			(xy 156.579726 -40.665031) (xy 156.631055 -40.686843) (xy 156.678661 -40.715897) (xy 156.721529 -40.751572)
			(xy 156.758746 -40.793109) (xy 156.789519 -40.839622) (xy 156.813191 -40.890119) (xy 156.829259 -40.943526)
			(xy 156.837379 -40.998702) (xy 156.837888 -41.026588) (xy 156.837379 -41.054474) (xy 156.829259 -41.10965)
			(xy 156.813191 -41.163057) (xy 156.789519 -41.213554) (xy 156.758746 -41.260067) (xy 156.721529 -41.301604)
			(xy 156.678661 -41.337279) (xy 156.631055 -41.366333) (xy 156.579726 -41.388145) (xy 156.525769 -41.402251)
			(xy 156.470332 -41.408351) (xy 156.414598 -41.406314) (xy 156.359755 -41.396184) (xy 156.306971 -41.378177)
			(xy 156.257371 -41.352676) (xy 156.212013 -41.320225) (xy 156.171864 -41.281516) (xy 156.137778 -41.237373)
			(xy 156.110482 -41.188738) (xy 156.090559 -41.136647) (xy 156.078433 -41.08221) (xy 156.074362 -41.026588)
			(xy 154.370283 -41.026588) (xy 154.371039 -41.031722) (xy 154.371548 -41.059608) (xy 154.371039 -41.087494)
			(xy 154.362919 -41.14267) (xy 154.346851 -41.196077) (xy 154.323179 -41.246574) (xy 154.292406 -41.293087)
			(xy 154.255189 -41.334624) (xy 154.212321 -41.370299) (xy 154.164715 -41.399353) (xy 154.113386 -41.421165)
			(xy 154.059429 -41.435271) (xy 154.003992 -41.441371) (xy 153.948258 -41.439334) (xy 153.893415 -41.429204)
			(xy 153.840631 -41.411197) (xy 153.791031 -41.385696) (xy 153.745673 -41.353245) (xy 153.705524 -41.314536)
			(xy 153.671438 -41.270393) (xy 153.644142 -41.221758) (xy 153.624219 -41.169667) (xy 153.612093 -41.11523)
			(xy 153.608022 -41.059608) (xy 150.162397 -41.059608) (xy 150.162768 -41.079928) (xy 150.162259 -41.107814)
			(xy 150.154139 -41.16299) (xy 150.138071 -41.216397) (xy 150.114399 -41.266894) (xy 150.083626 -41.313407)
			(xy 150.046409 -41.354944) (xy 150.003541 -41.390619) (xy 149.955935 -41.419673) (xy 149.904606 -41.441485)
			(xy 149.850649 -41.455591) (xy 149.795212 -41.461691) (xy 149.739478 -41.459654) (xy 149.684635 -41.449524)
			(xy 149.631851 -41.431517) (xy 149.582251 -41.406016) (xy 149.536893 -41.373565) (xy 149.496744 -41.334856)
			(xy 149.462658 -41.290713) (xy 149.435362 -41.242078) (xy 149.415439 -41.189987) (xy 149.403313 -41.13555)
			(xy 149.399242 -41.079928) (xy 145.13077 -41.079928) (xy 145.127921 -41.089397) (xy 145.104249 -41.139894)
			(xy 145.073476 -41.186407) (xy 145.036259 -41.227944) (xy 144.993391 -41.263619) (xy 144.945785 -41.292673)
			(xy 144.894456 -41.314485) (xy 144.840499 -41.328591) (xy 144.785062 -41.334691) (xy 144.729328 -41.332654)
			(xy 144.674485 -41.322524) (xy 144.621701 -41.304517) (xy 144.572101 -41.279016) (xy 144.526743 -41.246565)
			(xy 144.486594 -41.207856) (xy 144.452508 -41.163713) (xy 144.425212 -41.115078) (xy 144.405289 -41.062987)
			(xy 144.393163 -41.00855) (xy 144.389092 -40.952928) (xy 140.16228 -40.952928) (xy 140.16228 -41.838118)
			(xy 147.236432 -41.838118) (xy 147.240503 -41.782496) (xy 147.252629 -41.728059) (xy 147.272552 -41.675968)
			(xy 147.299848 -41.627333) (xy 147.333934 -41.58319) (xy 147.374083 -41.544481) (xy 147.419441 -41.51203)
			(xy 147.469041 -41.486529) (xy 147.521825 -41.468522) (xy 147.576668 -41.458392) (xy 147.632402 -41.456355)
			(xy 147.687839 -41.462455) (xy 147.741796 -41.476561) (xy 147.793125 -41.498373) (xy 147.840731 -41.527427)
			(xy 147.883599 -41.563102) (xy 147.920816 -41.604639) (xy 147.951589 -41.651152) (xy 147.975261 -41.701649)
			(xy 147.991329 -41.755056) (xy 147.999449 -41.810232) (xy 147.999958 -41.838118) (xy 147.999449 -41.866004)
			(xy 147.991329 -41.92118) (xy 147.975261 -41.974587) (xy 147.951589 -42.025084) (xy 147.920816 -42.071597)
			(xy 147.883599 -42.113134) (xy 147.840731 -42.148809) (xy 147.793125 -42.177863) (xy 147.741796 -42.199675)
			(xy 147.687839 -42.213781) (xy 147.632402 -42.219881) (xy 147.576668 -42.217844) (xy 147.521825 -42.207714)
			(xy 147.469041 -42.189707) (xy 147.419441 -42.164206) (xy 147.374083 -42.131755) (xy 147.333934 -42.093046)
			(xy 147.299848 -42.048903) (xy 147.272552 -42.000268) (xy 147.252629 -41.948177) (xy 147.240503 -41.89374)
			(xy 147.236432 -41.838118) (xy 140.16228 -41.838118) (xy 140.16228 -42.655998) (xy 140.643862 -42.655998)
			(xy 140.647933 -42.600376) (xy 140.660059 -42.545939) (xy 140.679982 -42.493848) (xy 140.707278 -42.445213)
			(xy 140.741364 -42.40107) (xy 140.781513 -42.362361) (xy 140.826871 -42.32991) (xy 140.876471 -42.304409)
			(xy 140.929255 -42.286402) (xy 140.984098 -42.276272) (xy 141.039832 -42.274235) (xy 141.095269 -42.280335)
			(xy 141.149226 -42.294441) (xy 141.200555 -42.316253) (xy 141.248161 -42.345307) (xy 141.291029 -42.380982)
			(xy 141.328246 -42.422519) (xy 141.344077 -42.446448) (xy 143.952212 -42.446448) (xy 143.956283 -42.390826)
			(xy 143.968409 -42.336389) (xy 143.988332 -42.284298) (xy 144.015628 -42.235663) (xy 144.049714 -42.19152)
			(xy 144.089863 -42.152811) (xy 144.135221 -42.12036) (xy 144.184821 -42.094859) (xy 144.237605 -42.076852)
			(xy 144.292448 -42.066722) (xy 144.348182 -42.064685) (xy 144.403619 -42.070785) (xy 144.457576 -42.084891)
			(xy 144.508905 -42.106703) (xy 144.556511 -42.135757) (xy 144.599379 -42.171432) (xy 144.636596 -42.212969)
			(xy 144.665031 -42.255948) (xy 162.211002 -42.255948) (xy 162.215073 -42.200326) (xy 162.227199 -42.145889)
			(xy 162.247122 -42.093798) (xy 162.274418 -42.045163) (xy 162.308504 -42.00102) (xy 162.348653 -41.962311)
			(xy 162.394011 -41.92986) (xy 162.443611 -41.904359) (xy 162.496395 -41.886352) (xy 162.551238 -41.876222)
			(xy 162.606972 -41.874185) (xy 162.662409 -41.880285) (xy 162.716366 -41.894391) (xy 162.767695 -41.916203)
			(xy 162.815301 -41.945257) (xy 162.858169 -41.980932) (xy 162.895386 -42.022469) (xy 162.926159 -42.068982)
			(xy 162.949831 -42.119479) (xy 162.965899 -42.172886) (xy 162.974019 -42.228062) (xy 162.974528 -42.255948)
			(xy 162.974019 -42.283834) (xy 162.971656 -42.29989) (xy 177.907186 -42.29989) (xy 177.911257 -42.244268)
			(xy 177.923383 -42.189831) (xy 177.943306 -42.13774) (xy 177.970602 -42.089105) (xy 178.004688 -42.044962)
			(xy 178.044837 -42.006253) (xy 178.090195 -41.973802) (xy 178.139795 -41.948301) (xy 178.192579 -41.930294)
			(xy 178.247422 -41.920164) (xy 178.303156 -41.918127) (xy 178.358593 -41.924227) (xy 178.41255 -41.938333)
			(xy 178.463879 -41.960145) (xy 178.511485 -41.989199) (xy 178.554353 -42.024874) (xy 178.59157 -42.066411)
			(xy 178.622343 -42.112924) (xy 178.646015 -42.163421) (xy 178.662083 -42.216828) (xy 178.670203 -42.272004)
			(xy 178.670712 -42.29989) (xy 178.670203 -42.327776) (xy 178.662083 -42.382952) (xy 178.646015 -42.436359)
			(xy 178.622343 -42.486856) (xy 178.59157 -42.533369) (xy 178.554353 -42.574906) (xy 178.511485 -42.610581)
			(xy 178.463879 -42.639635) (xy 178.41255 -42.661447) (xy 178.358593 -42.675553) (xy 178.303156 -42.681653)
			(xy 178.247422 -42.679616) (xy 178.192579 -42.669486) (xy 178.139795 -42.651479) (xy 178.090195 -42.625978)
			(xy 178.044837 -42.593527) (xy 178.004688 -42.554818) (xy 177.970602 -42.510675) (xy 177.943306 -42.46204)
			(xy 177.923383 -42.409949) (xy 177.911257 -42.355512) (xy 177.907186 -42.29989) (xy 162.971656 -42.29989)
			(xy 162.965899 -42.33901) (xy 162.949831 -42.392417) (xy 162.926159 -42.442914) (xy 162.895386 -42.489427)
			(xy 162.858169 -42.530964) (xy 162.815301 -42.566639) (xy 162.767695 -42.595693) (xy 162.716366 -42.617505)
			(xy 162.662409 -42.631611) (xy 162.606972 -42.637711) (xy 162.551238 -42.635674) (xy 162.496395 -42.625544)
			(xy 162.443611 -42.607537) (xy 162.394011 -42.582036) (xy 162.348653 -42.549585) (xy 162.308504 -42.510876)
			(xy 162.274418 -42.466733) (xy 162.247122 -42.418098) (xy 162.227199 -42.366007) (xy 162.215073 -42.31157)
			(xy 162.211002 -42.255948) (xy 144.665031 -42.255948) (xy 144.667369 -42.259482) (xy 144.691041 -42.309979)
			(xy 144.707109 -42.363386) (xy 144.715229 -42.418562) (xy 144.715738 -42.446448) (xy 144.715229 -42.474334)
			(xy 144.707109 -42.52951) (xy 144.691041 -42.582917) (xy 144.667369 -42.633414) (xy 144.66335 -42.639488)
			(xy 159.968182 -42.639488) (xy 159.972253 -42.583866) (xy 159.984379 -42.529429) (xy 160.004302 -42.477338)
			(xy 160.031598 -42.428703) (xy 160.065684 -42.38456) (xy 160.105833 -42.345851) (xy 160.151191 -42.3134)
			(xy 160.200791 -42.287899) (xy 160.253575 -42.269892) (xy 160.308418 -42.259762) (xy 160.364152 -42.257725)
			(xy 160.419589 -42.263825) (xy 160.473546 -42.277931) (xy 160.524875 -42.299743) (xy 160.572481 -42.328797)
			(xy 160.615349 -42.364472) (xy 160.652566 -42.406009) (xy 160.683339 -42.452522) (xy 160.707011 -42.503019)
			(xy 160.723079 -42.556426) (xy 160.731199 -42.611602) (xy 160.731708 -42.639488) (xy 160.731199 -42.667374)
			(xy 160.723079 -42.72255) (xy 160.707011 -42.775957) (xy 160.683339 -42.826454) (xy 160.652566 -42.872967)
			(xy 160.615349 -42.914504) (xy 160.572481 -42.950179) (xy 160.524875 -42.979233) (xy 160.473546 -43.001045)
			(xy 160.419589 -43.015151) (xy 160.364152 -43.021251) (xy 160.308418 -43.019214) (xy 160.253575 -43.009084)
			(xy 160.200791 -42.991077) (xy 160.151191 -42.965576) (xy 160.105833 -42.933125) (xy 160.065684 -42.894416)
			(xy 160.031598 -42.850273) (xy 160.004302 -42.801638) (xy 159.984379 -42.749547) (xy 159.972253 -42.69511)
			(xy 159.968182 -42.639488) (xy 144.66335 -42.639488) (xy 144.636596 -42.679927) (xy 144.599379 -42.721464)
			(xy 144.556511 -42.757139) (xy 144.508905 -42.786193) (xy 144.457576 -42.808005) (xy 144.403619 -42.822111)
			(xy 144.348182 -42.828211) (xy 144.292448 -42.826174) (xy 144.237605 -42.816044) (xy 144.184821 -42.798037)
			(xy 144.135221 -42.772536) (xy 144.089863 -42.740085) (xy 144.049714 -42.701376) (xy 144.015628 -42.657233)
			(xy 143.988332 -42.608598) (xy 143.968409 -42.556507) (xy 143.956283 -42.50207) (xy 143.952212 -42.446448)
			(xy 141.344077 -42.446448) (xy 141.359019 -42.469032) (xy 141.382691 -42.519529) (xy 141.398759 -42.572936)
			(xy 141.406879 -42.628112) (xy 141.407388 -42.655998) (xy 141.406879 -42.683884) (xy 141.398759 -42.73906)
			(xy 141.382691 -42.792467) (xy 141.359019 -42.842964) (xy 141.328246 -42.889477) (xy 141.291029 -42.931014)
			(xy 141.248161 -42.966689) (xy 141.200555 -42.995743) (xy 141.149226 -43.017555) (xy 141.095269 -43.031661)
			(xy 141.039832 -43.037761) (xy 140.984098 -43.035724) (xy 140.929255 -43.025594) (xy 140.876471 -43.007587)
			(xy 140.826871 -42.982086) (xy 140.781513 -42.949635) (xy 140.741364 -42.910926) (xy 140.707278 -42.866783)
			(xy 140.679982 -42.818148) (xy 140.660059 -42.766057) (xy 140.647933 -42.71162) (xy 140.643862 -42.655998)
			(xy 140.16228 -42.655998) (xy 140.16228 -43.612308) (xy 144.263362 -43.612308) (xy 144.267433 -43.556686)
			(xy 144.279559 -43.502249) (xy 144.299482 -43.450158) (xy 144.326778 -43.401523) (xy 144.360864 -43.35738)
			(xy 144.401013 -43.318671) (xy 144.446371 -43.28622) (xy 144.495971 -43.260719) (xy 144.548755 -43.242712)
			(xy 144.603598 -43.232582) (xy 144.659332 -43.230545) (xy 144.714769 -43.236645) (xy 144.768726 -43.250751)
			(xy 144.820055 -43.272563) (xy 144.867661 -43.301617) (xy 144.910529 -43.337292) (xy 144.947746 -43.378829)
			(xy 144.978519 -43.425342) (xy 145.002191 -43.475839) (xy 145.018259 -43.529246) (xy 145.026379 -43.584422)
			(xy 145.026888 -43.612308) (xy 145.026379 -43.640194) (xy 145.024502 -43.652948) (xy 151.584912 -43.652948)
			(xy 151.588983 -43.597326) (xy 151.601109 -43.542889) (xy 151.621032 -43.490798) (xy 151.648328 -43.442163)
			(xy 151.682414 -43.39802) (xy 151.722563 -43.359311) (xy 151.767921 -43.32686) (xy 151.817521 -43.301359)
			(xy 151.870305 -43.283352) (xy 151.925148 -43.273222) (xy 151.980882 -43.271185) (xy 152.036319 -43.277285)
			(xy 152.090276 -43.291391) (xy 152.141605 -43.313203) (xy 152.189211 -43.342257) (xy 152.232079 -43.377932)
			(xy 152.269296 -43.419469) (xy 152.300069 -43.465982) (xy 152.323741 -43.516479) (xy 152.339809 -43.569886)
			(xy 152.347929 -43.625062) (xy 152.348438 -43.652948) (xy 152.347929 -43.680834) (xy 152.339809 -43.73601)
			(xy 152.323741 -43.789417) (xy 152.300069 -43.839914) (xy 152.269296 -43.886427) (xy 152.232079 -43.927964)
			(xy 152.189211 -43.963639) (xy 152.141605 -43.992693) (xy 152.090276 -44.014505) (xy 152.036319 -44.028611)
			(xy 151.980882 -44.034711) (xy 151.925148 -44.032674) (xy 151.870305 -44.022544) (xy 151.817521 -44.004537)
			(xy 151.767921 -43.979036) (xy 151.722563 -43.946585) (xy 151.682414 -43.907876) (xy 151.648328 -43.863733)
			(xy 151.621032 -43.815098) (xy 151.601109 -43.763007) (xy 151.588983 -43.70857) (xy 151.584912 -43.652948)
			(xy 145.024502 -43.652948) (xy 145.018259 -43.69537) (xy 145.002191 -43.748777) (xy 144.978519 -43.799274)
			(xy 144.947746 -43.845787) (xy 144.910529 -43.887324) (xy 144.867661 -43.922999) (xy 144.820055 -43.952053)
			(xy 144.768726 -43.973865) (xy 144.714769 -43.987971) (xy 144.659332 -43.994071) (xy 144.603598 -43.992034)
			(xy 144.548755 -43.981904) (xy 144.495971 -43.963897) (xy 144.446371 -43.938396) (xy 144.401013 -43.905945)
			(xy 144.360864 -43.867236) (xy 144.326778 -43.823093) (xy 144.299482 -43.774458) (xy 144.279559 -43.722367)
			(xy 144.267433 -43.66793) (xy 144.263362 -43.612308) (xy 140.16228 -43.612308) (xy 140.16228 -45.897292)
			(xy 149.549866 -45.897292) (xy 149.550295 -45.8709) (xy 149.557589 -45.818623) (xy 149.572023 -45.767851)
			(xy 149.593321 -45.719555) (xy 149.621076 -45.674658) (xy 149.654758 -45.634017) (xy 149.693722 -45.59841)
			(xy 149.71522 -45.583094) (xy 149.726311 -45.574847) (xy 149.744031 -45.553656) (xy 149.755428 -45.528494)
			(xy 149.75967 -45.501198) (xy 149.756445 -45.473763) (xy 149.74599 -45.448195) (xy 149.729069 -45.426361)
			(xy 149.718268 -45.41774) (xy 149.694763 -45.399646) (xy 149.653166 -45.357359) (xy 149.618619 -45.30914)
			(xy 149.591956 -45.256154) (xy 149.57382 -45.199678) (xy 149.564647 -45.141075) (xy 149.56409 -45.111416)
			(xy 149.564576 -45.084165) (xy 149.572332 -45.030217) (xy 149.587687 -44.977922) (xy 149.610329 -44.928345)
			(xy 149.639795 -44.882495) (xy 149.675486 -44.841304) (xy 149.716677 -44.805613) (xy 149.762527 -44.776147)
			(xy 149.812104 -44.753505) (xy 149.864399 -44.73815) (xy 149.918347 -44.730394) (xy 149.972849 -44.730394)
			(xy 150.026797 -44.73815) (xy 150.079092 -44.753505) (xy 150.128669 -44.776147) (xy 150.174519 -44.805613)
			(xy 150.21571 -44.841304) (xy 150.251401 -44.882495) (xy 150.280867 -44.928345) (xy 150.303509 -44.977922)
			(xy 150.318864 -45.030217) (xy 150.32662 -45.084165) (xy 150.327106 -45.111416) (xy 150.326695 -45.137808)
			(xy 150.319399 -45.190087) (xy 150.304963 -45.24086) (xy 150.283662 -45.289156) (xy 150.255904 -45.334054)
			(xy 150.222219 -45.374693) (xy 150.183252 -45.410299) (xy 150.161752 -45.425614) (xy 150.150656 -45.433852)
			(xy 150.13294 -45.455046) (xy 150.121546 -45.480211) (xy 150.117307 -45.507507) (xy 150.120532 -45.534941)
			(xy 150.12215 -45.538898) (xy 151.203912 -45.538898) (xy 151.207983 -45.483276) (xy 151.220109 -45.428839)
			(xy 151.240032 -45.376748) (xy 151.267328 -45.328113) (xy 151.301414 -45.28397) (xy 151.341563 -45.245261)
			(xy 151.386921 -45.21281) (xy 151.436521 -45.187309) (xy 151.489305 -45.169302) (xy 151.544148 -45.159172)
			(xy 151.599882 -45.157135) (xy 151.655319 -45.163235) (xy 151.709276 -45.177341) (xy 151.760605 -45.199153)
			(xy 151.808211 -45.228207) (xy 151.851079 -45.263882) (xy 151.888296 -45.305419) (xy 151.919069 -45.351932)
			(xy 151.942741 -45.402429) (xy 151.958809 -45.455836) (xy 151.966929 -45.511012) (xy 151.967438 -45.538898)
			(xy 151.966929 -45.566784) (xy 151.958809 -45.62196) (xy 151.94964 -45.652436) (xy 155.97378 -45.652436)
			(xy 155.97378 -44.816268) (xy 155.97378 -44.807124) (xy 155.97378 -44.788836) (xy 155.974353 -44.759098)
			(xy 155.983635 -44.700351) (xy 156.001919 -44.643755) (xy 156.028761 -44.59068) (xy 156.063511 -44.542412)
			(xy 156.084016 -44.520866) (xy 156.090615 -44.513439) (xy 156.098083 -44.49505) (xy 156.098015 -44.475203)
			(xy 156.09042 -44.456866) (xy 156.083762 -44.449492) (xy 156.063281 -44.427903) (xy 156.028558 -44.379581)
			(xy 156.00176 -44.326453) (xy 155.983538 -44.269808) (xy 155.974333 -44.21102) (xy 155.97378 -44.181268)
			(xy 155.974266 -44.154017) (xy 155.982022 -44.100069) (xy 155.997377 -44.047774) (xy 156.020019 -43.998197)
			(xy 156.049485 -43.952347) (xy 156.085176 -43.911156) (xy 156.126367 -43.875465) (xy 156.172217 -43.845999)
			(xy 156.221794 -43.823357) (xy 156.274089 -43.808002) (xy 156.328037 -43.800246) (xy 156.382539 -43.800246)
			(xy 156.436487 -43.808002) (xy 156.488782 -43.823357) (xy 156.538359 -43.845999) (xy 156.584209 -43.875465)
			(xy 156.6254 -43.911156) (xy 156.661091 -43.952347) (xy 156.690557 -43.998197) (xy 156.713199 -44.047774)
			(xy 156.728554 -44.100069) (xy 156.73631 -44.154017) (xy 156.736796 -44.181268) (xy 156.736227 -44.210995)
			(xy 156.726996 -44.269728) (xy 156.708767 -44.326319) (xy 156.681983 -44.379397) (xy 156.64729 -44.42768)
			(xy 156.626814 -44.449238) (xy 156.620207 -44.45666) (xy 156.612736 -44.475051) (xy 156.612805 -44.494902)
			(xy 156.620406 -44.51324) (xy 156.627068 -44.520612) (xy 156.647602 -44.542165) (xy 156.682378 -44.590479)
			(xy 156.709225 -44.64361) (xy 156.721653 -44.682156) (xy 159.179768 -44.682156) (xy 159.179768 -43.909488)
			(xy 159.179768 -43.900344) (xy 159.179768 -43.818556) (xy 159.180343 -43.788252) (xy 159.189932 -43.728407)
			(xy 159.208861 -43.670831) (xy 159.236654 -43.616971) (xy 159.272613 -43.568183) (xy 159.293814 -43.546522)
			(xy 159.272612 -43.524862) (xy 159.236652 -43.476075) (xy 159.208859 -43.422215) (xy 159.189933 -43.364638)
			(xy 159.18035 -43.304792) (xy 159.179768 -43.274488) (xy 159.180254 -43.247237) (xy 159.18801 -43.193289)
			(xy 159.203365 -43.140994) (xy 159.226007 -43.091417) (xy 159.255473 -43.045567) (xy 159.291164 -43.004376)
			(xy 159.332355 -42.968685) (xy 159.378205 -42.939219) (xy 159.427782 -42.916577) (xy 159.480077 -42.901222)
			(xy 159.534025 -42.893466) (xy 159.588527 -42.893466) (xy 159.642475 -42.901222) (xy 159.69477 -42.916577)
			(xy 159.744347 -42.939219) (xy 159.790197 -42.968685) (xy 159.831388 -43.004376) (xy 159.867079 -43.045567)
			(xy 159.896545 -43.091417) (xy 159.919187 -43.140994) (xy 159.934542 -43.193289) (xy 159.942298 -43.247237)
			(xy 159.942784 -43.274488) (xy 159.942221 -43.304756) (xy 159.93265 -43.364531) (xy 159.913761 -43.422046)
			(xy 159.898306 -43.452034) (xy 174.176434 -43.452034) (xy 174.180505 -43.396412) (xy 174.192631 -43.341975)
			(xy 174.212554 -43.289884) (xy 174.23985 -43.241249) (xy 174.273936 -43.197106) (xy 174.314085 -43.158397)
			(xy 174.359443 -43.125946) (xy 174.409043 -43.100445) (xy 174.461827 -43.082438) (xy 174.51667 -43.072308)
			(xy 174.572404 -43.070271) (xy 174.627841 -43.076371) (xy 174.681798 -43.090477) (xy 174.733127 -43.112289)
			(xy 174.780733 -43.141343) (xy 174.823601 -43.177018) (xy 174.860818 -43.218555) (xy 174.891591 -43.265068)
			(xy 174.915263 -43.315565) (xy 174.931331 -43.368972) (xy 174.939451 -43.424148) (xy 174.93996 -43.452034)
			(xy 174.939451 -43.47992) (xy 174.931331 -43.535096) (xy 174.915263 -43.588503) (xy 174.891591 -43.639)
			(xy 174.860818 -43.685513) (xy 174.823601 -43.72705) (xy 174.780733 -43.762725) (xy 174.733127 -43.791779)
			(xy 174.713748 -43.800014) (xy 177.907186 -43.800014) (xy 177.911257 -43.744392) (xy 177.923383 -43.689955)
			(xy 177.943306 -43.637864) (xy 177.970602 -43.589229) (xy 178.004688 -43.545086) (xy 178.044837 -43.506377)
			(xy 178.090195 -43.473926) (xy 178.139795 -43.448425) (xy 178.192579 -43.430418) (xy 178.247422 -43.420288)
			(xy 178.303156 -43.418251) (xy 178.358593 -43.424351) (xy 178.41255 -43.438457) (xy 178.463879 -43.460269)
			(xy 178.49908 -43.481752) (xy 178.891692 -43.481752) (xy 178.891692 -42.618152) (xy 178.892178 -42.590901)
			(xy 178.899934 -42.536953) (xy 178.915289 -42.484658) (xy 178.937931 -42.435081) (xy 178.967397 -42.389231)
			(xy 179.003088 -42.34804) (xy 179.044279 -42.312349) (xy 179.090129 -42.282883) (xy 179.139706 -42.260241)
			(xy 179.192001 -42.244886) (xy 179.245949 -42.23713) (xy 179.300451 -42.23713) (xy 179.354399 -42.244886)
			(xy 179.406694 -42.260241) (xy 179.456271 -42.282883) (xy 179.502121 -42.312349) (xy 179.543312 -42.34804)
			(xy 179.579003 -42.389231) (xy 179.608469 -42.435081) (xy 179.631111 -42.484658) (xy 179.646466 -42.536953)
			(xy 179.648974 -42.554398) (xy 189.032132 -42.554398) (xy 189.036203 -42.498776) (xy 189.048329 -42.444339)
			(xy 189.068252 -42.392248) (xy 189.095548 -42.343613) (xy 189.129634 -42.29947) (xy 189.169783 -42.260761)
			(xy 189.215141 -42.22831) (xy 189.264741 -42.202809) (xy 189.317525 -42.184802) (xy 189.372368 -42.174672)
			(xy 189.428102 -42.172635) (xy 189.483539 -42.178735) (xy 189.537496 -42.192841) (xy 189.588825 -42.214653)
			(xy 189.636431 -42.243707) (xy 189.679299 -42.279382) (xy 189.716516 -42.320919) (xy 189.747289 -42.367432)
			(xy 189.770961 -42.417929) (xy 189.787029 -42.471336) (xy 189.795149 -42.526512) (xy 189.79557 -42.549572)
			(xy 195.648578 -42.549572) (xy 195.652649 -42.49395) (xy 195.664775 -42.439513) (xy 195.684698 -42.387422)
			(xy 195.711994 -42.338787) (xy 195.74608 -42.294644) (xy 195.786229 -42.255935) (xy 195.831587 -42.223484)
			(xy 195.881187 -42.197983) (xy 195.933971 -42.179976) (xy 195.988814 -42.169846) (xy 196.044548 -42.167809)
			(xy 196.099985 -42.173909) (xy 196.153942 -42.188015) (xy 196.205271 -42.209827) (xy 196.252877 -42.238881)
			(xy 196.295745 -42.274556) (xy 196.332962 -42.316093) (xy 196.363735 -42.362606) (xy 196.387407 -42.413103)
			(xy 196.403475 -42.46651) (xy 196.411595 -42.521686) (xy 196.412104 -42.549572) (xy 196.411595 -42.577458)
			(xy 196.403475 -42.632634) (xy 196.387407 -42.686041) (xy 196.363735 -42.736538) (xy 196.332962 -42.783051)
			(xy 196.295745 -42.824588) (xy 196.252877 -42.860263) (xy 196.205271 -42.889317) (xy 196.153942 -42.911129)
			(xy 196.099985 -42.925235) (xy 196.044548 -42.931335) (xy 195.988814 -42.929298) (xy 195.933971 -42.919168)
			(xy 195.881187 -42.901161) (xy 195.831587 -42.87566) (xy 195.786229 -42.843209) (xy 195.74608 -42.8045)
			(xy 195.711994 -42.760357) (xy 195.684698 -42.711722) (xy 195.664775 -42.659631) (xy 195.652649 -42.605194)
			(xy 195.648578 -42.549572) (xy 189.79557 -42.549572) (xy 189.795658 -42.554398) (xy 189.795149 -42.582284)
			(xy 189.787029 -42.63746) (xy 189.770961 -42.690867) (xy 189.747289 -42.741364) (xy 189.716516 -42.787877)
			(xy 189.679299 -42.829414) (xy 189.636431 -42.865089) (xy 189.588825 -42.894143) (xy 189.537496 -42.915955)
			(xy 189.483539 -42.930061) (xy 189.428102 -42.936161) (xy 189.372368 -42.934124) (xy 189.317525 -42.923994)
			(xy 189.264741 -42.905987) (xy 189.215141 -42.880486) (xy 189.169783 -42.848035) (xy 189.129634 -42.809326)
			(xy 189.095548 -42.765183) (xy 189.068252 -42.716548) (xy 189.048329 -42.664457) (xy 189.036203 -42.61002)
			(xy 189.032132 -42.554398) (xy 179.648974 -42.554398) (xy 179.654222 -42.590901) (xy 179.654708 -42.618152)
			(xy 179.654708 -43.481752) (xy 179.654222 -43.509003) (xy 179.646466 -43.562951) (xy 179.631111 -43.615246)
			(xy 179.608469 -43.664823) (xy 179.579003 -43.710673) (xy 179.543312 -43.751864) (xy 179.502121 -43.787555)
			(xy 179.456271 -43.817021) (xy 179.406694 -43.839663) (xy 179.354399 -43.855018) (xy 179.300451 -43.862774)
			(xy 179.245949 -43.862774) (xy 179.192001 -43.855018) (xy 179.139706 -43.839663) (xy 179.090129 -43.817021)
			(xy 179.044279 -43.787555) (xy 179.003088 -43.751864) (xy 178.967397 -43.710673) (xy 178.937931 -43.664823)
			(xy 178.915289 -43.615246) (xy 178.899934 -43.562951) (xy 178.892178 -43.509003) (xy 178.891692 -43.481752)
			(xy 178.49908 -43.481752) (xy 178.511485 -43.489323) (xy 178.554353 -43.524998) (xy 178.59157 -43.566535)
			(xy 178.622343 -43.613048) (xy 178.646015 -43.663545) (xy 178.662083 -43.716952) (xy 178.670203 -43.772128)
			(xy 178.670712 -43.800014) (xy 178.670203 -43.8279) (xy 178.662083 -43.883076) (xy 178.646015 -43.936483)
			(xy 178.641481 -43.946154) (xy 181.026241 -43.946154) (xy 181.026241 -43.891646) (xy 181.033998 -43.837692)
			(xy 181.049355 -43.785392) (xy 181.071999 -43.735809) (xy 181.101469 -43.689954) (xy 181.137165 -43.648759)
			(xy 181.17836 -43.613064) (xy 181.224216 -43.583595) (xy 181.273799 -43.560953) (xy 181.3261 -43.545597)
			(xy 181.380054 -43.53784) (xy 181.407308 -43.537378) (xy 181.436196 -43.537913) (xy 181.493314 -43.546613)
			(xy 181.548466 -43.563829) (xy 181.60039 -43.589166) (xy 181.6479 -43.622044) (xy 181.689906 -43.661712)
			(xy 181.72545 -43.707262) (xy 181.740048 -43.732196) (xy 181.748059 -43.745409) (xy 181.770486 -43.766644)
			(xy 181.798235 -43.780205) (xy 181.828768 -43.784854) (xy 181.859294 -43.780165) (xy 181.873398 -43.773852)
			(xy 181.899668 -43.761568) (xy 181.954986 -43.744167) (xy 182.012298 -43.735319) (xy 182.041292 -43.734736)
			(xy 182.070289 -43.735304) (xy 182.127606 -43.744133) (xy 182.182925 -43.761544) (xy 182.209186 -43.773852)
			(xy 182.223293 -43.780159) (xy 182.25382 -43.784852) (xy 182.284354 -43.780207) (xy 182.312105 -43.766648)
			(xy 182.334534 -43.745415) (xy 182.342536 -43.732196) (xy 182.357132 -43.707262) (xy 182.392684 -43.661721)
			(xy 182.434695 -43.62206) (xy 182.482204 -43.589184) (xy 182.534126 -43.563846) (xy 182.589275 -43.546624)
			(xy 182.646389 -43.537912) (xy 182.675276 -43.537378) (xy 182.702529 -43.537868) (xy 182.756481 -43.545622)
			(xy 182.808779 -43.560975) (xy 182.858361 -43.583615) (xy 182.904215 -43.613082) (xy 182.945409 -43.648774)
			(xy 182.981104 -43.689966) (xy 183.010573 -43.735818) (xy 183.033217 -43.785398) (xy 183.048573 -43.837696)
			(xy 183.050277 -43.849544) (xy 192.177922 -43.849544) (xy 192.181993 -43.793922) (xy 192.194119 -43.739485)
			(xy 192.214042 -43.687394) (xy 192.241338 -43.638759) (xy 192.275424 -43.594616) (xy 192.315573 -43.555907)
			(xy 192.360931 -43.523456) (xy 192.410531 -43.497955) (xy 192.463315 -43.479948) (xy 192.518158 -43.469818)
			(xy 192.573892 -43.467781) (xy 192.629329 -43.473881) (xy 192.683286 -43.487987) (xy 192.734615 -43.509799)
			(xy 192.782221 -43.538853) (xy 192.825089 -43.574528) (xy 192.862306 -43.616065) (xy 192.893079 -43.662578)
			(xy 192.916751 -43.713075) (xy 192.932819 -43.766482) (xy 192.940939 -43.821658) (xy 192.941448 -43.849544)
			(xy 192.940939 -43.87743) (xy 192.932819 -43.932606) (xy 192.916751 -43.986013) (xy 192.893079 -44.03651)
			(xy 192.862306 -44.083023) (xy 192.825089 -44.12456) (xy 192.782221 -44.160235) (xy 192.734615 -44.189289)
			(xy 192.683286 -44.211101) (xy 192.629329 -44.225207) (xy 192.573892 -44.231307) (xy 192.518158 -44.22927)
			(xy 192.463315 -44.21914) (xy 192.410531 -44.201133) (xy 192.360931 -44.175632) (xy 192.315573 -44.143181)
			(xy 192.275424 -44.104472) (xy 192.241338 -44.060329) (xy 192.214042 -44.011694) (xy 192.194119 -43.959603)
			(xy 192.181993 -43.905166) (xy 192.177922 -43.849544) (xy 183.050277 -43.849544) (xy 183.056331 -43.891647)
			(xy 183.056331 -43.946153) (xy 183.048573 -44.000104) (xy 183.033217 -44.052402) (xy 183.010573 -44.101982)
			(xy 182.981104 -44.147834) (xy 182.945409 -44.189026) (xy 182.904215 -44.224718) (xy 182.858361 -44.254185)
			(xy 182.808779 -44.276825) (xy 182.756481 -44.292178) (xy 182.702529 -44.299932) (xy 182.675276 -44.300394)
			(xy 182.64497 -44.299835) (xy 182.585121 -44.290257) (xy 182.55615 -44.281344) (xy 182.542958 -44.277524)
			(xy 182.515539 -44.276208) (xy 182.488761 -44.282246) (xy 182.464561 -44.295201) (xy 182.444687 -44.314137)
			(xy 182.430578 -44.337684) (xy 182.423254 -44.364139) (xy 182.4228 -44.377864) (xy 182.4228 -44.478448)
			(xy 212.297262 -44.478448) (xy 212.301333 -44.422826) (xy 212.313459 -44.368389) (xy 212.333382 -44.316298)
			(xy 212.360678 -44.267663) (xy 212.394764 -44.22352) (xy 212.434913 -44.184811) (xy 212.480271 -44.15236)
			(xy 212.529871 -44.126859) (xy 212.582655 -44.108852) (xy 212.637498 -44.098722) (xy 212.693232 -44.096685)
			(xy 212.748669 -44.102785) (xy 212.802626 -44.116891) (xy 212.853955 -44.138703) (xy 212.901561 -44.167757)
			(xy 212.944429 -44.203432) (xy 212.981646 -44.244969) (xy 213.012419 -44.291482) (xy 213.036091 -44.341979)
			(xy 213.052159 -44.395386) (xy 213.060279 -44.450562) (xy 213.060788 -44.478448) (xy 213.060279 -44.506334)
			(xy 213.052159 -44.56151) (xy 213.036091 -44.614917) (xy 213.012419 -44.665414) (xy 212.981646 -44.711927)
			(xy 212.944429 -44.753464) (xy 212.902536 -44.788328) (xy 218.943934 -44.788328) (xy 218.948005 -44.732706)
			(xy 218.960131 -44.678269) (xy 218.980054 -44.626178) (xy 219.00735 -44.577543) (xy 219.041436 -44.5334)
			(xy 219.081585 -44.494691) (xy 219.126943 -44.46224) (xy 219.176543 -44.436739) (xy 219.229327 -44.418732)
			(xy 219.28417 -44.408602) (xy 219.339904 -44.406565) (xy 219.395341 -44.412665) (xy 219.449298 -44.426771)
			(xy 219.500627 -44.448583) (xy 219.548233 -44.477637) (xy 219.591101 -44.513312) (xy 219.628318 -44.554849)
			(xy 219.659091 -44.601362) (xy 219.682763 -44.651859) (xy 219.698831 -44.705266) (xy 219.706951 -44.760442)
			(xy 219.70746 -44.788328) (xy 219.706951 -44.816214) (xy 219.698831 -44.87139) (xy 219.683319 -44.922948)
			(xy 222.298512 -44.922948) (xy 222.302583 -44.867326) (xy 222.314709 -44.812889) (xy 222.334632 -44.760798)
			(xy 222.361928 -44.712163) (xy 222.396014 -44.66802) (xy 222.436163 -44.629311) (xy 222.481521 -44.59686)
			(xy 222.531121 -44.571359) (xy 222.583905 -44.553352) (xy 222.638748 -44.543222) (xy 222.694482 -44.541185)
			(xy 222.749919 -44.547285) (xy 222.803876 -44.561391) (xy 222.855205 -44.583203) (xy 222.902811 -44.612257)
			(xy 222.945679 -44.647932) (xy 222.982896 -44.689469) (xy 223.013669 -44.735982) (xy 223.037341 -44.786479)
			(xy 223.053409 -44.839886) (xy 223.061529 -44.895062) (xy 223.062038 -44.922948) (xy 223.061529 -44.950834)
			(xy 223.053409 -45.00601) (xy 223.037341 -45.059417) (xy 223.013669 -45.109914) (xy 222.982896 -45.156427)
			(xy 222.945679 -45.197964) (xy 222.902811 -45.233639) (xy 222.855205 -45.262693) (xy 222.803876 -45.284505)
			(xy 222.749919 -45.298611) (xy 222.694482 -45.304711) (xy 222.638748 -45.302674) (xy 222.583905 -45.292544)
			(xy 222.531121 -45.274537) (xy 222.481521 -45.249036) (xy 222.436163 -45.216585) (xy 222.396014 -45.177876)
			(xy 222.361928 -45.133733) (xy 222.334632 -45.085098) (xy 222.314709 -45.033007) (xy 222.302583 -44.97857)
			(xy 222.298512 -44.922948) (xy 219.683319 -44.922948) (xy 219.682763 -44.924797) (xy 219.659091 -44.975294)
			(xy 219.628318 -45.021807) (xy 219.591101 -45.063344) (xy 219.548233 -45.099019) (xy 219.500627 -45.128073)
			(xy 219.449298 -45.149885) (xy 219.395341 -45.163991) (xy 219.339904 -45.170091) (xy 219.28417 -45.168054)
			(xy 219.229327 -45.157924) (xy 219.176543 -45.139917) (xy 219.126943 -45.114416) (xy 219.081585 -45.081965)
			(xy 219.041436 -45.043256) (xy 219.00735 -44.999113) (xy 218.980054 -44.950478) (xy 218.960131 -44.898387)
			(xy 218.948005 -44.84395) (xy 218.943934 -44.788328) (xy 212.902536 -44.788328) (xy 212.901561 -44.789139)
			(xy 212.853955 -44.818193) (xy 212.802626 -44.840005) (xy 212.748669 -44.854111) (xy 212.693232 -44.860211)
			(xy 212.637498 -44.858174) (xy 212.582655 -44.848044) (xy 212.529871 -44.830037) (xy 212.480271 -44.804536)
			(xy 212.434913 -44.772085) (xy 212.394764 -44.733376) (xy 212.360678 -44.689233) (xy 212.333382 -44.640598)
			(xy 212.313459 -44.588507) (xy 212.301333 -44.53407) (xy 212.297262 -44.478448) (xy 182.4228 -44.478448)
			(xy 182.4228 -44.718732) (xy 182.423215 -44.732463) (xy 182.430542 -44.758929) (xy 182.444656 -44.782486)
			(xy 182.464537 -44.801429) (xy 182.488747 -44.81439) (xy 182.515536 -44.820431) (xy 182.542966 -44.819114)
			(xy 182.55615 -44.815252) (xy 182.585122 -44.806347) (xy 182.644972 -44.796783) (xy 182.675276 -44.796202)
			(xy 182.702531 -44.796643) (xy 182.756486 -44.804398) (xy 182.808788 -44.819752) (xy 182.858372 -44.842394)
			(xy 182.90423 -44.871862) (xy 182.945426 -44.907557) (xy 182.981124 -44.948751) (xy 183.010595 -44.994607)
			(xy 183.03324 -45.04419) (xy 183.048597 -45.096491) (xy 183.056355 -45.150445) (xy 183.056355 -45.204955)
			(xy 183.048597 -45.258909) (xy 183.03324 -45.31121) (xy 183.010595 -45.360793) (xy 182.981124 -45.406649)
			(xy 182.945426 -45.447843) (xy 182.90423 -45.483538) (xy 182.858372 -45.513006) (xy 182.808788 -45.535648)
			(xy 182.756486 -45.551002) (xy 182.702531 -45.558757) (xy 182.675276 -45.559218) (xy 182.646387 -45.558698)
			(xy 182.589269 -45.549995) (xy 182.534116 -45.532777) (xy 182.482192 -45.507438) (xy 182.434683 -45.474557)
			(xy 182.392676 -45.434887) (xy 182.357134 -45.389335) (xy 182.342536 -45.3644) (xy 182.334543 -45.351175)
			(xy 182.31211 -45.32994) (xy 182.284357 -45.316381) (xy 182.25382 -45.311735) (xy 182.22329 -45.316428)
			(xy 182.209186 -45.322744) (xy 182.182918 -45.335033) (xy 182.127599 -45.352432) (xy 182.070287 -45.361278)
			(xy 182.041292 -45.36186) (xy 182.012295 -45.361299) (xy 181.954977 -45.352467) (xy 181.899658 -45.335054)
			(xy 181.873398 -45.322744) (xy 181.859298 -45.316421) (xy 181.828767 -45.311732) (xy 181.798231 -45.316381)
			(xy 181.77048 -45.329943) (xy 181.74805 -45.351179) (xy 181.740048 -45.3644) (xy 181.725462 -45.38934)
			(xy 181.689908 -45.434881) (xy 181.647896 -45.474542) (xy 181.600385 -45.507417) (xy 181.548461 -45.532754)
			(xy 181.493311 -45.549975) (xy 181.436196 -45.558686) (xy 181.407308 -45.559218) (xy 181.380055 -45.558735)
			(xy 181.326105 -45.550979) (xy 181.273808 -45.535624) (xy 181.224228 -45.512983) (xy 181.178375 -45.483516)
			(xy 181.137182 -45.447823) (xy 181.101489 -45.406631) (xy 181.072021 -45.360779) (xy 181.049378 -45.3112)
			(xy 181.034022 -45.258903) (xy 181.026265 -45.204953) (xy 181.026265 -45.150447) (xy 181.034022 -45.096497)
			(xy 181.049378 -45.0442) (xy 181.072021 -44.994621) (xy 181.101489 -44.948769) (xy 181.137182 -44.907577)
			(xy 181.178375 -44.871884) (xy 181.224228 -44.842417) (xy 181.273808 -44.819776) (xy 181.326105 -44.804421)
			(xy 181.380055 -44.796665) (xy 181.407308 -44.796202) (xy 181.437614 -44.796764) (xy 181.497463 -44.80634)
			(xy 181.526434 -44.815252) (xy 181.53963 -44.819058) (xy 181.567047 -44.820377) (xy 181.593824 -44.814342)
			(xy 181.618025 -44.801389) (xy 181.637898 -44.782456) (xy 181.652007 -44.75891) (xy 181.65933 -44.732456)
			(xy 181.659784 -44.718732) (xy 181.659784 -44.377864) (xy 181.659393 -44.364132) (xy 181.652064 -44.337662)
			(xy 181.637946 -44.314103) (xy 181.618061 -44.295158) (xy 181.593846 -44.282198) (xy 181.567053 -44.276159)
			(xy 181.539619 -44.277479) (xy 181.526434 -44.281344) (xy 181.497457 -44.29023) (xy 181.437611 -44.299807)
			(xy 181.407308 -44.300394) (xy 181.380054 -44.29996) (xy 181.3261 -44.292203) (xy 181.273799 -44.276847)
			(xy 181.224216 -44.254205) (xy 181.17836 -44.224736) (xy 181.137165 -44.189041) (xy 181.101469 -44.147846)
			(xy 181.071999 -44.101991) (xy 181.049355 -44.052408) (xy 181.033998 -44.000108) (xy 181.026241 -43.946154)
			(xy 178.641481 -43.946154) (xy 178.622343 -43.98698) (xy 178.59157 -44.033493) (xy 178.554353 -44.07503)
			(xy 178.511485 -44.110705) (xy 178.463879 -44.139759) (xy 178.41255 -44.161571) (xy 178.358593 -44.175677)
			(xy 178.303156 -44.181777) (xy 178.247422 -44.17974) (xy 178.192579 -44.16961) (xy 178.139795 -44.151603)
			(xy 178.090195 -44.126102) (xy 178.044837 -44.093651) (xy 178.004688 -44.054942) (xy 177.970602 -44.010799)
			(xy 177.943306 -43.962164) (xy 177.923383 -43.910073) (xy 177.911257 -43.855636) (xy 177.907186 -43.800014)
			(xy 174.713748 -43.800014) (xy 174.681798 -43.813591) (xy 174.627841 -43.827697) (xy 174.572404 -43.833797)
			(xy 174.51667 -43.83176) (xy 174.461827 -43.82163) (xy 174.409043 -43.803623) (xy 174.359443 -43.778122)
			(xy 174.314085 -43.745671) (xy 174.273936 -43.706962) (xy 174.23985 -43.662819) (xy 174.212554 -43.614184)
			(xy 174.192631 -43.562093) (xy 174.180505 -43.507656) (xy 174.176434 -43.452034) (xy 159.898306 -43.452034)
			(xy 159.886029 -43.475857) (xy 159.850149 -43.524614) (xy 159.828992 -43.546268) (xy 159.850267 -43.567908)
			(xy 159.886301 -43.616735) (xy 159.91415 -43.67065) (xy 159.933112 -43.728295) (xy 159.94271 -43.788214)
			(xy 159.943292 -43.818556) (xy 159.943292 -44.682156) (xy 159.942795 -44.709559) (xy 159.934944 -44.7638)
			(xy 159.919412 -44.816359) (xy 159.896517 -44.866154) (xy 159.866732 -44.912161) (xy 159.849058 -44.933108)
			(xy 159.839935 -44.944469) (xy 159.827844 -44.970962) (xy 159.8237 -44.999787) (xy 159.825431 -45.011848)
			(xy 165.157402 -45.011848) (xy 165.161473 -44.956226) (xy 165.173599 -44.901789) (xy 165.193522 -44.849698)
			(xy 165.220818 -44.801063) (xy 165.254904 -44.75692) (xy 165.295053 -44.718211) (xy 165.340411 -44.68576)
			(xy 165.390011 -44.660259) (xy 165.442795 -44.642252) (xy 165.497638 -44.632122) (xy 165.553372 -44.630085)
			(xy 165.608809 -44.636185) (xy 165.662766 -44.650291) (xy 165.714095 -44.672103) (xy 165.761701 -44.701157)
			(xy 165.804569 -44.736832) (xy 165.841786 -44.778369) (xy 165.872559 -44.824882) (xy 165.896231 -44.875379)
			(xy 165.912299 -44.928786) (xy 165.920419 -44.983962) (xy 165.920928 -45.011848) (xy 165.920419 -45.039734)
			(xy 165.912299 -45.09491) (xy 165.896231 -45.148317) (xy 165.872559 -45.198814) (xy 165.841786 -45.245327)
			(xy 165.804569 -45.286864) (xy 165.761701 -45.322539) (xy 165.754139 -45.327154) (xy 177.908139 -45.327154)
			(xy 177.908139 -45.272646) (xy 177.915896 -45.218692) (xy 177.931253 -45.166392) (xy 177.953897 -45.116809)
			(xy 177.983367 -45.070954) (xy 178.019062 -45.029759) (xy 178.060257 -44.994064) (xy 178.106113 -44.964595)
			(xy 178.155696 -44.941952) (xy 178.207996 -44.926595) (xy 178.26195 -44.918839) (xy 178.289204 -44.918376)
			(xy 178.318278 -44.918876) (xy 178.375749 -44.927714) (xy 178.431215 -44.945169) (xy 178.48339 -44.970838)
			(xy 178.531067 -45.004125) (xy 178.573141 -45.044261) (xy 178.608639 -45.090316) (xy 178.636738 -45.141223)
			(xy 178.656788 -45.195805) (xy 178.663092 -45.224192) (xy 178.666395 -45.237688) (xy 178.679068 -45.262397)
			(xy 178.697931 -45.282775) (xy 178.721589 -45.297314) (xy 178.74829 -45.304938) (xy 178.776058 -45.305082)
			(xy 178.802837 -45.297736) (xy 178.814984 -45.290994) (xy 178.837338 -45.278048) (xy 178.884797 -45.25765)
			(xy 178.934571 -45.243828) (xy 178.985752 -45.236831) (xy 179.01158 -45.236384) (xy 179.038844 -45.236875)
			(xy 179.092815 -45.244635) (xy 179.145133 -45.260001) (xy 179.194729 -45.282659) (xy 179.240594 -45.312148)
			(xy 179.281793 -45.347867) (xy 179.317488 -45.389087) (xy 179.346949 -45.43497) (xy 179.369578 -45.484579)
			(xy 179.384913 -45.536906) (xy 179.392641 -45.590882) (xy 179.393088 -45.618146) (xy 179.393088 -46.092647)
			(xy 213.669918 -46.092647) (xy 213.669918 -46.038153) (xy 213.677673 -45.984212) (xy 213.693026 -45.931925)
			(xy 213.715663 -45.882354) (xy 213.745124 -45.836509) (xy 213.78081 -45.795324) (xy 213.821993 -45.759636)
			(xy 213.867836 -45.730173) (xy 213.917406 -45.707533) (xy 213.969693 -45.692178) (xy 214.023633 -45.68442)
			(xy 214.05088 -45.683932) (xy 214.079797 -45.684453) (xy 214.136969 -45.693179) (xy 214.192168 -45.710436)
			(xy 214.24413 -45.735827) (xy 214.291664 -45.768771) (xy 214.33368 -45.808512) (xy 214.35187 -45.830998)
			(xy 214.361749 -45.842859) (xy 214.387082 -45.860472) (xy 214.416516 -45.869725) (xy 214.447371 -45.869772)
			(xy 214.476834 -45.860611) (xy 214.502221 -45.843076) (xy 214.512144 -45.831252) (xy 214.530303 -45.808781)
			(xy 214.572304 -45.76911) (xy 214.619808 -45.736228) (xy 214.671729 -45.710888) (xy 214.726878 -45.69367)
			(xy 214.783993 -45.684967) (xy 214.81288 -45.68444) (xy 214.840472 -45.684886) (xy 214.895077 -45.69286)
			(xy 214.947964 -45.708617) (xy 214.99803 -45.731826) (xy 215.04423 -45.762005) (xy 215.085603 -45.798524)
			(xy 215.121283 -45.840621) (xy 215.150528 -45.887419) (xy 215.172728 -45.937941) (xy 215.187419 -45.991134)
			(xy 215.19134 -46.01845) (xy 215.193476 -46.031756) (xy 215.203679 -46.056684) (xy 215.220048 -46.078075)
			(xy 215.241444 -46.094437) (xy 215.266375 -46.104633) (xy 215.293106 -46.10795) (xy 215.319773 -46.104159)
			(xy 215.33231 -46.099222) (xy 215.356267 -46.089343) (xy 215.406186 -46.075431) (xy 215.457529 -46.068413)
			(xy 215.48344 -46.06798) (xy 215.510688 -46.068493) (xy 215.56463 -46.076254) (xy 215.616918 -46.091612)
			(xy 215.666489 -46.114255) (xy 215.712333 -46.143721) (xy 215.753517 -46.179411) (xy 215.789203 -46.220599)
			(xy 215.818665 -46.266446) (xy 215.841302 -46.316019) (xy 215.856655 -46.368309) (xy 215.86441 -46.422251)
			(xy 215.86441 -46.476749) (xy 215.857484 -46.524926) (xy 222.71304 -46.524926) (xy 222.717111 -46.469304)
			(xy 222.729237 -46.414867) (xy 222.74916 -46.362776) (xy 222.776456 -46.314141) (xy 222.810542 -46.269998)
			(xy 222.850691 -46.231289) (xy 222.896049 -46.198838) (xy 222.945649 -46.173337) (xy 222.998433 -46.15533)
			(xy 223.053276 -46.1452) (xy 223.10901 -46.143163) (xy 223.164447 -46.149263) (xy 223.218404 -46.163369)
			(xy 223.269733 -46.185181) (xy 223.317339 -46.214235) (xy 223.360207 -46.24991) (xy 223.397424 -46.291447)
			(xy 223.428197 -46.33796) (xy 223.451869 -46.388457) (xy 223.467937 -46.441864) (xy 223.476057 -46.49704)
			(xy 223.476566 -46.524926) (xy 223.476057 -46.552812) (xy 223.467937 -46.607988) (xy 223.451869 -46.661395)
			(xy 223.428197 -46.711892) (xy 223.397424 -46.758405) (xy 223.360207 -46.799942) (xy 223.317339 -46.835617)
			(xy 223.269733 -46.864671) (xy 223.218404 -46.886483) (xy 223.164447 -46.900589) (xy 223.10901 -46.906689)
			(xy 223.053276 -46.904652) (xy 222.998433 -46.894522) (xy 222.945649 -46.876515) (xy 222.896049 -46.851014)
			(xy 222.850691 -46.818563) (xy 222.810542 -46.779854) (xy 222.776456 -46.735711) (xy 222.74916 -46.687076)
			(xy 222.729237 -46.634985) (xy 222.717111 -46.580548) (xy 222.71304 -46.524926) (xy 215.857484 -46.524926)
			(xy 215.856655 -46.530691) (xy 215.841302 -46.582981) (xy 215.818665 -46.632554) (xy 215.789203 -46.678401)
			(xy 215.753517 -46.719589) (xy 215.712333 -46.755279) (xy 215.666489 -46.784745) (xy 215.616918 -46.807388)
			(xy 215.56463 -46.822746) (xy 215.510688 -46.830507) (xy 215.48344 -46.830996) (xy 215.45585 -46.8305)
			(xy 215.401249 -46.82253) (xy 215.348365 -46.806778) (xy 215.298301 -46.783573) (xy 215.252101 -46.7534)
			(xy 215.210729 -46.716887) (xy 215.175048 -46.674795) (xy 215.145801 -46.628004) (xy 215.123599 -46.577487)
			(xy 215.108904 -46.5243) (xy 215.10498 -46.496986) (xy 215.10286 -46.483679) (xy 215.092646 -46.458757)
			(xy 215.076271 -46.437373) (xy 215.054874 -46.421014) (xy 215.029944 -46.41082) (xy 215.003215 -46.407499)
			(xy 214.976548 -46.411282) (xy 214.96401 -46.416214) (xy 214.940051 -46.426088) (xy 214.890133 -46.440001)
			(xy 214.83879 -46.447021) (xy 214.81288 -46.447456) (xy 214.783964 -46.446897) (xy 214.726794 -46.438178)
			(xy 214.671596 -46.42093) (xy 214.619633 -46.395546) (xy 214.572099 -46.362609) (xy 214.530081 -46.322873)
			(xy 214.51189 -46.30039) (xy 214.502054 -46.28849) (xy 214.476709 -46.270879) (xy 214.447264 -46.261633)
			(xy 214.416401 -46.261592) (xy 214.386931 -46.270762) (xy 214.36154 -46.288306) (xy 214.351616 -46.300136)
			(xy 214.33342 -46.322576) (xy 214.291427 -46.36225) (xy 214.243931 -46.395135) (xy 214.192017 -46.420481)
			(xy 214.136875 -46.437706) (xy 214.079765 -46.446417) (xy 214.05088 -46.446948) (xy 214.023633 -46.44638)
			(xy 213.969693 -46.438622) (xy 213.917406 -46.423267) (xy 213.867836 -46.400627) (xy 213.821993 -46.371164)
			(xy 213.78081 -46.335476) (xy 213.745124 -46.294291) (xy 213.715663 -46.248446) (xy 213.693026 -46.198875)
			(xy 213.677673 -46.146588) (xy 213.669918 -46.092647) (xy 179.393088 -46.092647) (xy 179.393088 -46.481746)
			(xy 179.392619 -46.509004) (xy 179.384859 -46.562964) (xy 179.369502 -46.615272) (xy 179.346861 -46.664864)
			(xy 179.317396 -46.710731) (xy 179.281707 -46.751941) (xy 179.240519 -46.787655) (xy 179.19467 -46.817148)
			(xy 179.145092 -46.83982) (xy 179.092793 -46.855209) (xy 179.038837 -46.863003) (xy 179.01158 -46.863508)
			(xy 178.98575 -46.863083) (xy 178.934563 -46.856104) (xy 178.884787 -46.842276) (xy 178.837335 -46.821852)
			(xy 178.814984 -46.808898) (xy 178.802863 -46.802095) (xy 178.776066 -46.794745) (xy 178.74828 -46.79489)
			(xy 178.721561 -46.802518) (xy 178.697887 -46.817066) (xy 178.67901 -46.837457) (xy 178.666328 -46.862181)
			(xy 178.663092 -46.8757) (xy 178.656753 -46.904078) (xy 178.636713 -46.958659) (xy 178.617126 -46.994154)
			(xy 181.026241 -46.994154) (xy 181.026241 -46.939646) (xy 181.033998 -46.885692) (xy 181.049355 -46.833392)
			(xy 181.071999 -46.783809) (xy 181.101469 -46.737954) (xy 181.137165 -46.696759) (xy 181.17836 -46.661064)
			(xy 181.224216 -46.631595) (xy 181.273799 -46.608953) (xy 181.3261 -46.593597) (xy 181.380054 -46.58584)
			(xy 181.407308 -46.585378) (xy 181.436196 -46.585913) (xy 181.493314 -46.594613) (xy 181.548466 -46.611829)
			(xy 181.60039 -46.637166) (xy 181.6479 -46.670044) (xy 181.689906 -46.709712) (xy 181.72545 -46.755262)
			(xy 181.740048 -46.780196) (xy 181.748059 -46.793409) (xy 181.770486 -46.814644) (xy 181.798235 -46.828205)
			(xy 181.828768 -46.832854) (xy 181.859294 -46.828165) (xy 181.873398 -46.821852) (xy 181.899668 -46.809568)
			(xy 181.954986 -46.792167) (xy 182.012298 -46.783319) (xy 182.041292 -46.782736) (xy 182.070289 -46.783304)
			(xy 182.127606 -46.792133) (xy 182.182925 -46.809544) (xy 182.209186 -46.821852) (xy 182.223293 -46.828159)
			(xy 182.25382 -46.832852) (xy 182.284354 -46.828207) (xy 182.312105 -46.814648) (xy 182.334534 -46.793415)
			(xy 182.342536 -46.780196) (xy 182.357132 -46.755262) (xy 182.392684 -46.709721) (xy 182.434695 -46.67006)
			(xy 182.482204 -46.637184) (xy 182.534126 -46.611846) (xy 182.589275 -46.594624) (xy 182.646389 -46.585912)
			(xy 182.675276 -46.585378) (xy 182.702529 -46.585868) (xy 182.756481 -46.593622) (xy 182.808779 -46.608975)
			(xy 182.858361 -46.631615) (xy 182.904215 -46.661082) (xy 182.945409 -46.696774) (xy 182.981104 -46.737966)
			(xy 183.010573 -46.783818) (xy 183.033217 -46.833398) (xy 183.048573 -46.885696) (xy 183.056331 -46.939647)
			(xy 183.056331 -46.994153) (xy 183.048573 -47.048104) (xy 183.033217 -47.100402) (xy 183.010573 -47.149982)
			(xy 182.981104 -47.195834) (xy 182.945409 -47.237026) (xy 182.904215 -47.272718) (xy 182.858361 -47.302185)
			(xy 182.808779 -47.324825) (xy 182.756481 -47.340178) (xy 182.702529 -47.347932) (xy 182.675276 -47.348394)
			(xy 182.64497 -47.347835) (xy 182.585121 -47.338257) (xy 182.55615 -47.329344) (xy 182.542958 -47.325524)
			(xy 182.515539 -47.324208) (xy 182.488761 -47.330246) (xy 182.464561 -47.343201) (xy 182.444687 -47.362137)
			(xy 182.430578 -47.385684) (xy 182.423254 -47.412139) (xy 182.4228 -47.425864) (xy 182.4228 -47.766732)
			(xy 182.423215 -47.780463) (xy 182.430542 -47.806929) (xy 182.444656 -47.830486) (xy 182.464537 -47.849429)
			(xy 182.488747 -47.86239) (xy 182.515536 -47.868431) (xy 182.542966 -47.867114) (xy 182.55615 -47.863252)
			(xy 182.585122 -47.854347) (xy 182.644972 -47.844783) (xy 182.675276 -47.844202) (xy 182.702531 -47.844643)
			(xy 182.756486 -47.852398) (xy 182.808788 -47.867752) (xy 182.858372 -47.890394) (xy 182.90423 -47.919862)
			(xy 182.945426 -47.955557) (xy 182.981124 -47.996751) (xy 183.010595 -48.042607) (xy 183.03324 -48.09219)
			(xy 183.048597 -48.144491) (xy 183.056355 -48.198445) (xy 183.056355 -48.252955) (xy 183.048597 -48.306909)
			(xy 183.03324 -48.35921) (xy 183.010595 -48.408793) (xy 182.981124 -48.454649) (xy 182.945426 -48.495843)
			(xy 182.90423 -48.531538) (xy 182.858372 -48.561006) (xy 182.808788 -48.583648) (xy 182.756486 -48.599002)
			(xy 182.702531 -48.606757) (xy 182.675276 -48.607218) (xy 182.646387 -48.606698) (xy 182.589269 -48.597995)
			(xy 182.534116 -48.580777) (xy 182.482192 -48.555438) (xy 182.434683 -48.522557) (xy 182.392676 -48.482887)
			(xy 182.357134 -48.437335) (xy 182.342536 -48.4124) (xy 182.334543 -48.399175) (xy 182.31211 -48.37794)
			(xy 182.284357 -48.364381) (xy 182.25382 -48.359735) (xy 182.22329 -48.364428) (xy 182.209186 -48.370744)
			(xy 182.182918 -48.383033) (xy 182.127599 -48.400432) (xy 182.070287 -48.409278) (xy 182.041292 -48.40986)
			(xy 182.012295 -48.409299) (xy 181.954977 -48.400467) (xy 181.899658 -48.383054) (xy 181.873398 -48.370744)
			(xy 181.859298 -48.364421) (xy 181.828767 -48.359732) (xy 181.798231 -48.364381) (xy 181.77048 -48.377943)
			(xy 181.74805 -48.399179) (xy 181.740048 -48.4124) (xy 181.725462 -48.43734) (xy 181.689908 -48.482881)
			(xy 181.647896 -48.522542) (xy 181.600385 -48.555417) (xy 181.548461 -48.580754) (xy 181.493311 -48.597975)
			(xy 181.436196 -48.606686) (xy 181.407308 -48.607218) (xy 181.380055 -48.606735) (xy 181.326105 -48.598979)
			(xy 181.273808 -48.583624) (xy 181.224228 -48.560983) (xy 181.178375 -48.531516) (xy 181.137182 -48.495823)
			(xy 181.101489 -48.454631) (xy 181.072021 -48.408779) (xy 181.049378 -48.3592) (xy 181.034022 -48.306903)
			(xy 181.026265 -48.252953) (xy 181.026265 -48.198447) (xy 181.034022 -48.144497) (xy 181.049378 -48.0922)
			(xy 181.072021 -48.042621) (xy 181.101489 -47.996769) (xy 181.137182 -47.955577) (xy 181.178375 -47.919884)
			(xy 181.224228 -47.890417) (xy 181.273808 -47.867776) (xy 181.326105 -47.852421) (xy 181.380055 -47.844665)
			(xy 181.407308 -47.844202) (xy 181.437614 -47.844764) (xy 181.497463 -47.85434) (xy 181.526434 -47.863252)
			(xy 181.53963 -47.867058) (xy 181.567047 -47.868377) (xy 181.593824 -47.862342) (xy 181.618025 -47.849389)
			(xy 181.637898 -47.830456) (xy 181.652007 -47.80691) (xy 181.65933 -47.780456) (xy 181.659784 -47.766732)
			(xy 181.659784 -47.425864) (xy 181.659393 -47.412132) (xy 181.652064 -47.385662) (xy 181.637946 -47.362103)
			(xy 181.618061 -47.343158) (xy 181.593846 -47.330198) (xy 181.567053 -47.324159) (xy 181.539619 -47.325479)
			(xy 181.526434 -47.329344) (xy 181.497457 -47.33823) (xy 181.437611 -47.347807) (xy 181.407308 -47.348394)
			(xy 181.380054 -47.34796) (xy 181.3261 -47.340203) (xy 181.273799 -47.324847) (xy 181.224216 -47.302205)
			(xy 181.17836 -47.272736) (xy 181.137165 -47.237041) (xy 181.101469 -47.195846) (xy 181.071999 -47.149991)
			(xy 181.049355 -47.100408) (xy 181.033998 -47.048108) (xy 181.026241 -46.994154) (xy 178.617126 -46.994154)
			(xy 178.608622 -47.009566) (xy 178.57313 -47.05562) (xy 178.531059 -47.095753) (xy 178.483384 -47.129036)
			(xy 178.43121 -47.154698) (xy 178.375745 -47.172143) (xy 178.318276 -47.180969) (xy 178.289204 -47.181516)
			(xy 178.261952 -47.181037) (xy 178.208001 -47.173281) (xy 178.155704 -47.157925) (xy 178.106124 -47.135283)
			(xy 178.060272 -47.105816) (xy 178.01908 -47.070123) (xy 177.983386 -47.028931) (xy 177.953918 -46.983079)
			(xy 177.931276 -46.9335) (xy 177.91592 -46.881203) (xy 177.908163 -46.827252) (xy 177.908163 -46.772748)
			(xy 177.91592 -46.718797) (xy 177.931276 -46.6665) (xy 177.953918 -46.616921) (xy 177.983386 -46.571069)
			(xy 178.01908 -46.529877) (xy 178.060272 -46.494184) (xy 178.106124 -46.464717) (xy 178.155704 -46.442075)
			(xy 178.208001 -46.426719) (xy 178.261952 -46.418963) (xy 178.289204 -46.4185) (xy 178.313924 -46.418898)
			(xy 178.362953 -46.425271) (xy 178.410747 -46.437923) (xy 178.456507 -46.456642) (xy 178.47818 -46.468538)
			(xy 178.491675 -46.475523) (xy 178.521322 -46.482101) (xy 178.551594 -46.479681) (xy 178.579819 -46.468476)
			(xy 178.603509 -46.449475) (xy 178.620573 -46.424354) (xy 178.629505 -46.39533) (xy 178.630072 -46.380146)
			(xy 178.630072 -45.719746) (xy 178.629543 -45.704548) (xy 178.620642 -45.675485) (xy 178.603584 -45.650328)
			(xy 178.57988 -45.631303) (xy 178.551627 -45.620094) (xy 178.521326 -45.617694) (xy 178.491661 -45.624315)
			(xy 178.47818 -45.631354) (xy 178.456511 -45.643258) (xy 178.410748 -45.661971) (xy 178.362953 -45.674622)
			(xy 178.313925 -45.681002) (xy 178.289204 -45.681392) (xy 178.26195 -45.680961) (xy 178.207996 -45.673205)
			(xy 178.155696 -45.657848) (xy 178.106113 -45.635205) (xy 178.060257 -45.605736) (xy 178.019062 -45.570041)
			(xy 177.983367 -45.528846) (xy 177.953897 -45.482991) (xy 177.931253 -45.433408) (xy 177.915896 -45.381108)
			(xy 177.908139 -45.327154) (xy 165.754139 -45.327154) (xy 165.714095 -45.351593) (xy 165.662766 -45.373405)
			(xy 165.608809 -45.387511) (xy 165.553372 -45.393611) (xy 165.497638 -45.391574) (xy 165.442795 -45.381444)
			(xy 165.390011 -45.363437) (xy 165.340411 -45.337936) (xy 165.295053 -45.305485) (xy 165.254904 -45.266776)
			(xy 165.220818 -45.222633) (xy 165.193522 -45.173998) (xy 165.173599 -45.121907) (xy 165.161473 -45.06747)
			(xy 165.157402 -45.011848) (xy 159.825431 -45.011848) (xy 159.827837 -45.028613) (xy 159.839921 -45.055109)
			(xy 159.849058 -45.066458) (xy 159.866684 -45.0874) (xy 159.8964 -45.13337) (xy 159.919239 -45.183115)
			(xy 159.934733 -45.235613) (xy 159.942563 -45.289787) (xy 159.943038 -45.317156) (xy 159.942552 -45.344407)
			(xy 159.934796 -45.398355) (xy 159.919441 -45.45065) (xy 159.896799 -45.500227) (xy 159.867333 -45.546077)
			(xy 159.831642 -45.587268) (xy 159.790451 -45.622959) (xy 159.744601 -45.652425) (xy 159.695024 -45.675067)
			(xy 159.642729 -45.690422) (xy 159.588781 -45.698178) (xy 159.534279 -45.698178) (xy 159.480331 -45.690422)
			(xy 159.428036 -45.675067) (xy 159.378459 -45.652425) (xy 159.332609 -45.622959) (xy 159.291418 -45.587268)
			(xy 159.255727 -45.546077) (xy 159.226261 -45.500227) (xy 159.203619 -45.45065) (xy 159.188264 -45.398355)
			(xy 159.180508 -45.344407) (xy 159.180022 -45.317156) (xy 159.180516 -45.289787) (xy 159.188326 -45.235609)
			(xy 159.203808 -45.183106) (xy 159.226644 -45.133358) (xy 159.256363 -45.08739) (xy 159.274002 -45.066458)
			(xy 159.28325 -45.05517) (xy 159.29542 -45.028659) (xy 159.299588 -44.999787) (xy 159.295413 -44.970916)
			(xy 159.283236 -44.944409) (xy 159.274002 -44.933108) (xy 159.256354 -44.912142) (xy 159.226583 -44.866131)
			(xy 159.203689 -44.81634) (xy 159.188144 -44.763789) (xy 159.180265 -44.709557) (xy 159.179768 -44.682156)
			(xy 156.721653 -44.682156) (xy 156.727492 -44.700266) (xy 156.736735 -44.759072) (xy 156.737304 -44.788836)
			(xy 156.737304 -45.652436) (xy 156.736786 -45.680012) (xy 156.728782 -45.73458) (xy 156.713018 -45.787432)
			(xy 156.689821 -45.837469) (xy 156.659674 -45.883653) (xy 156.6418 -45.904658) (xy 156.636006 -45.911836)
			(xy 156.629518 -45.929092) (xy 156.629521 -45.947527) (xy 156.636016 -45.964781) (xy 156.6418 -45.971968)
			(xy 156.659652 -45.992948) (xy 156.689739 -46.039093) (xy 156.712878 -46.089085) (xy 156.72859 -46.141884)
			(xy 156.736548 -46.196393) (xy 156.736856 -46.213268) (xy 164.684962 -46.213268) (xy 164.689033 -46.157646)
			(xy 164.701159 -46.103209) (xy 164.721082 -46.051118) (xy 164.748378 -46.002483) (xy 164.782464 -45.95834)
			(xy 164.822613 -45.919631) (xy 164.867971 -45.88718) (xy 164.917571 -45.861679) (xy 164.970355 -45.843672)
			(xy 165.025198 -45.833542) (xy 165.080932 -45.831505) (xy 165.136369 -45.837605) (xy 165.190326 -45.851711)
			(xy 165.241655 -45.873523) (xy 165.289261 -45.902577) (xy 165.332129 -45.938252) (xy 165.369346 -45.979789)
			(xy 165.400119 -46.026302) (xy 165.423791 -46.076799) (xy 165.439859 -46.130206) (xy 165.447979 -46.185382)
			(xy 165.448488 -46.213268) (xy 165.447979 -46.241154) (xy 165.439859 -46.29633) (xy 165.423791 -46.349737)
			(xy 165.400119 -46.400234) (xy 165.369346 -46.446747) (xy 165.332129 -46.488284) (xy 165.289261 -46.523959)
			(xy 165.241655 -46.553013) (xy 165.190326 -46.574825) (xy 165.136369 -46.588931) (xy 165.080932 -46.595031)
			(xy 165.025198 -46.592994) (xy 164.970355 -46.582864) (xy 164.917571 -46.564857) (xy 164.867971 -46.539356)
			(xy 164.822613 -46.506905) (xy 164.782464 -46.468196) (xy 164.748378 -46.424053) (xy 164.721082 -46.375418)
			(xy 164.701159 -46.323327) (xy 164.689033 -46.26889) (xy 164.684962 -46.213268) (xy 156.736856 -46.213268)
			(xy 156.73705 -46.223936) (xy 156.736564 -46.251187) (xy 156.728808 -46.305135) (xy 156.713453 -46.35743)
			(xy 156.690811 -46.407007) (xy 156.661345 -46.452857) (xy 156.625654 -46.494048) (xy 156.584463 -46.529739)
			(xy 156.538613 -46.559205) (xy 156.489036 -46.581847) (xy 156.436741 -46.597202) (xy 156.382793 -46.604958)
			(xy 156.328291 -46.604958) (xy 156.274343 -46.597202) (xy 156.222048 -46.581847) (xy 156.172471 -46.559205)
			(xy 156.126621 -46.529739) (xy 156.08543 -46.494048) (xy 156.049739 -46.452857) (xy 156.020273 -46.407007)
			(xy 155.997631 -46.35743) (xy 155.982276 -46.305135) (xy 155.97452 -46.251187) (xy 155.974034 -46.223936)
			(xy 155.97454 -46.196393) (xy 155.982489 -46.141882) (xy 155.998199 -46.089083) (xy 156.021342 -46.039093)
			(xy 156.051437 -45.992953) (xy 156.069284 -45.971968) (xy 156.075111 -45.964795) (xy 156.081685 -45.947541)
			(xy 156.081688 -45.929078) (xy 156.075121 -45.911822) (xy 156.069284 -45.904658) (xy 156.051381 -45.883673)
			(xy 156.021205 -45.8375) (xy 155.997999 -45.787459) (xy 155.982247 -45.734597) (xy 155.974277 -45.680016)
			(xy 155.97378 -45.652436) (xy 151.94964 -45.652436) (xy 151.942741 -45.675367) (xy 151.919069 -45.725864)
			(xy 151.888296 -45.772377) (xy 151.851079 -45.813914) (xy 151.808211 -45.849589) (xy 151.760605 -45.878643)
			(xy 151.709276 -45.900455) (xy 151.655319 -45.914561) (xy 151.599882 -45.920661) (xy 151.544148 -45.918624)
			(xy 151.489305 -45.908494) (xy 151.436521 -45.890487) (xy 151.386921 -45.864986) (xy 151.341563 -45.832535)
			(xy 151.301414 -45.793826) (xy 151.267328 -45.749683) (xy 151.240032 -45.701048) (xy 151.220109 -45.648957)
			(xy 151.207983 -45.59452) (xy 151.203912 -45.538898) (xy 150.12215 -45.538898) (xy 150.130986 -45.56051)
			(xy 150.147905 -45.582346) (xy 150.158704 -45.590968) (xy 150.182207 -45.609065) (xy 150.223805 -45.651351)
			(xy 150.258353 -45.699568) (xy 150.285017 -45.752554) (xy 150.303153 -45.80903) (xy 150.312325 -45.867634)
			(xy 150.312882 -45.897292) (xy 150.312396 -45.924543) (xy 150.30464 -45.978491) (xy 150.289285 -46.030786)
			(xy 150.266643 -46.080363) (xy 150.237177 -46.126213) (xy 150.201486 -46.167404) (xy 150.160295 -46.203095)
			(xy 150.114445 -46.232561) (xy 150.064868 -46.255203) (xy 150.012573 -46.270558) (xy 149.958625 -46.278314)
			(xy 149.904123 -46.278314) (xy 149.850175 -46.270558) (xy 149.79788 -46.255203) (xy 149.748303 -46.232561)
			(xy 149.702453 -46.203095) (xy 149.661262 -46.167404) (xy 149.625571 -46.126213) (xy 149.596105 -46.080363)
			(xy 149.573463 -46.030786) (xy 149.558108 -45.978491) (xy 149.550352 -45.924543) (xy 149.549866 -45.897292)
			(xy 140.16228 -45.897292) (xy 140.16228 -46.98855) (xy 150.296876 -46.98855) (xy 150.296876 -46.93405)
			(xy 150.304632 -46.880103) (xy 150.319986 -46.82781) (xy 150.342626 -46.778234) (xy 150.37209 -46.732384)
			(xy 150.40778 -46.691194) (xy 150.448968 -46.655502) (xy 150.494816 -46.626035) (xy 150.544391 -46.603393)
			(xy 150.596684 -46.588036) (xy 150.65063 -46.580277) (xy 150.67788 -46.57979) (xy 150.70711 -46.58037)
			(xy 150.764884 -46.589312) (xy 150.820618 -46.606958) (xy 150.87301 -46.632898) (xy 150.920833 -46.666523)
			(xy 150.96297 -46.707047) (xy 150.998435 -46.753523) (xy 151.012906 -46.778926) (xy 151.019939 -46.790804)
			(xy 151.039095 -46.810657) (xy 151.062873 -46.824646) (xy 151.089531 -46.831748) (xy 151.117117 -46.831441)
			(xy 151.143611 -46.823748) (xy 151.167071 -46.809233) (xy 151.18578 -46.788958) (xy 151.192484 -46.776894)
			(xy 151.204804 -46.753859) (xy 151.234839 -46.711116) (xy 151.270427 -46.672873) (xy 151.310902 -46.639845)
			(xy 151.355506 -46.612651) (xy 151.403405 -46.5918) (xy 151.453701 -46.577682) (xy 151.505454 -46.570562)
			(xy 151.531574 -46.570138) (xy 151.558375 -46.570591) (xy 151.611451 -46.578079) (xy 151.662955 -46.592926)
			(xy 151.711873 -46.614839) (xy 151.757241 -46.643386) (xy 151.798164 -46.678004) (xy 151.833836 -46.718012)
			(xy 151.849074 -46.740064) (xy 151.857302 -46.751532) (xy 151.878792 -46.769811) (xy 151.904463 -46.781515)
			(xy 151.932357 -46.78575) (xy 151.960345 -46.782195) (xy 151.986293 -46.77112) (xy 152.008222 -46.753369)
			(xy 152.016714 -46.742096) (xy 152.03207 -46.720948) (xy 152.067655 -46.682668) (xy 152.108133 -46.649606)
			(xy 152.152746 -46.622381) (xy 152.200659 -46.601501) (xy 152.250973 -46.58736) (xy 152.302748 -46.580221)
			(xy 152.32888 -46.57979) (xy 152.356134 -46.580256) (xy 152.410086 -46.588011) (xy 152.462386 -46.603365)
			(xy 152.511969 -46.626006) (xy 152.557824 -46.655473) (xy 152.599019 -46.691167) (xy 152.634715 -46.73236)
			(xy 152.664184 -46.778214) (xy 152.686828 -46.827795) (xy 152.702185 -46.880094) (xy 152.709943 -46.934046)
			(xy 152.709943 -46.954948) (xy 162.807902 -46.954948) (xy 162.811973 -46.899326) (xy 162.824099 -46.844889)
			(xy 162.844022 -46.792798) (xy 162.871318 -46.744163) (xy 162.905404 -46.70002) (xy 162.945553 -46.661311)
			(xy 162.990911 -46.62886) (xy 163.040511 -46.603359) (xy 163.093295 -46.585352) (xy 163.148138 -46.575222)
			(xy 163.203872 -46.573185) (xy 163.259309 -46.579285) (xy 163.313266 -46.593391) (xy 163.364595 -46.615203)
			(xy 163.412201 -46.644257) (xy 163.455069 -46.679932) (xy 163.492286 -46.721469) (xy 163.523059 -46.767982)
			(xy 163.546731 -46.818479) (xy 163.562799 -46.871886) (xy 163.570919 -46.927062) (xy 163.571428 -46.954948)
			(xy 163.570919 -46.982834) (xy 163.562799 -47.03801) (xy 163.546731 -47.091417) (xy 163.523059 -47.141914)
			(xy 163.492286 -47.188427) (xy 163.455069 -47.229964) (xy 163.412201 -47.265639) (xy 163.364595 -47.294693)
			(xy 163.313266 -47.316505) (xy 163.259309 -47.330611) (xy 163.203872 -47.336711) (xy 163.148138 -47.334674)
			(xy 163.093295 -47.324544) (xy 163.040511 -47.306537) (xy 162.990911 -47.281036) (xy 162.945553 -47.248585)
			(xy 162.905404 -47.209876) (xy 162.871318 -47.165733) (xy 162.844022 -47.117098) (xy 162.824099 -47.065007)
			(xy 162.811973 -47.01057) (xy 162.807902 -46.954948) (xy 152.709943 -46.954948) (xy 152.709943 -46.988554)
			(xy 152.702185 -47.042506) (xy 152.686828 -47.094805) (xy 152.664184 -47.144386) (xy 152.634715 -47.19024)
			(xy 152.599019 -47.231433) (xy 152.557824 -47.267127) (xy 152.511969 -47.296594) (xy 152.462386 -47.319235)
			(xy 152.410086 -47.334589) (xy 152.356134 -47.342344) (xy 152.32888 -47.342806) (xy 152.302079 -47.342368)
			(xy 152.249003 -47.334875) (xy 152.197499 -47.320024) (xy 152.148582 -47.298108) (xy 152.103215 -47.269559)
			(xy 152.062291 -47.23494) (xy 152.026618 -47.194932) (xy 152.01138 -47.17288) (xy 152.003207 -47.161372)
			(xy 151.981701 -47.143101) (xy 151.956019 -47.131407) (xy 151.928118 -47.127179) (xy 151.900124 -47.130741)
			(xy 151.874171 -47.14182) (xy 151.852235 -47.159573) (xy 151.84374 -47.170848) (xy 151.828363 -47.191981)
			(xy 151.792781 -47.230258) (xy 151.752306 -47.26332) (xy 151.707696 -47.290547) (xy 151.659787 -47.311429)
			(xy 151.609476 -47.325575) (xy 151.557705 -47.332719) (xy 151.531574 -47.333154) (xy 151.502344 -47.33256)
			(xy 151.44457 -47.323625) (xy 151.388834 -47.305983) (xy 151.336441 -47.280046) (xy 151.288617 -47.246423)
			(xy 151.246481 -47.205898) (xy 151.211018 -47.159422) (xy 151.196548 -47.134018) (xy 151.189576 -47.122104)
			(xy 151.170405 -47.102258) (xy 151.146616 -47.088276) (xy 151.11995 -47.081182) (xy 151.092358 -47.081495)
			(xy 151.06586 -47.089192) (xy 151.042394 -47.103709) (xy 151.023678 -47.123985) (xy 151.01697 -47.13605)
			(xy 151.004628 -47.159073) (xy 150.974594 -47.201813) (xy 150.939008 -47.240055) (xy 150.898536 -47.273082)
			(xy 150.853935 -47.300277) (xy 150.806041 -47.32113) (xy 150.755748 -47.335252) (xy 150.703999 -47.342379)
			(xy 150.67788 -47.342806) (xy 150.65063 -47.342323) (xy 150.596684 -47.334564) (xy 150.544391 -47.319207)
			(xy 150.494816 -47.296565) (xy 150.448968 -47.267098) (xy 150.40778 -47.231406) (xy 150.37209 -47.190216)
			(xy 150.342626 -47.144366) (xy 150.319986 -47.09479) (xy 150.304632 -47.042497) (xy 150.296876 -46.98855)
			(xy 140.16228 -46.98855) (xy 140.16228 -47.873755) (xy 154.820543 -47.873755) (xy 154.820543 -47.819245)
			(xy 154.828301 -47.765291) (xy 154.843658 -47.71299) (xy 154.866303 -47.663407) (xy 154.895774 -47.617551)
			(xy 154.931471 -47.576357) (xy 154.972667 -47.540662) (xy 155.018524 -47.511193) (xy 155.068109 -47.488551)
			(xy 155.12041 -47.473196) (xy 155.174365 -47.465442) (xy 155.20162 -47.46498) (xy 155.22947 -47.465478)
			(xy 155.284575 -47.473592) (xy 155.337915 -47.489631) (xy 155.388357 -47.513253) (xy 155.43483 -47.543957)
			(xy 155.476346 -47.58109) (xy 155.512023 -47.623863) (xy 155.526994 -47.647352) (xy 155.53543 -47.659949)
			(xy 155.558111 -47.680031) (xy 155.585687 -47.692574) (xy 155.615729 -47.696472) (xy 155.645593 -47.691383)
			(xy 155.672648 -47.677754) (xy 155.683966 -47.667672) (xy 155.705441 -47.647858) (xy 155.753291 -47.614329)
			(xy 155.80569 -47.58848) (xy 155.861415 -47.570914) (xy 155.919166 -47.562042) (xy 155.94838 -47.5615)
			(xy 156.81198 -47.5615) (xy 156.841986 -47.562037) (xy 156.90126 -47.571409) (xy 156.958338 -47.58994)
			(xy 157.011813 -47.617174) (xy 157.060368 -47.65244) (xy 157.081982 -47.67326) (xy 157.091603 -47.68218)
			(xy 157.114286 -47.695339) (xy 157.139571 -47.702293) (xy 157.165793 -47.702582) (xy 157.191225 -47.696188)
			(xy 157.214193 -47.683532) (xy 157.223968 -47.674784) (xy 157.245395 -47.655059) (xy 157.293135 -47.621706)
			(xy 157.345387 -47.59599) (xy 157.400939 -47.578509) (xy 157.458501 -47.569667) (xy 157.48762 -47.56912)
			(xy 157.514872 -47.569551) (xy 157.568822 -47.577311) (xy 157.621118 -47.592669) (xy 157.670696 -47.615313)
			(xy 157.716548 -47.644782) (xy 157.757738 -47.680476) (xy 157.79343 -47.721668) (xy 157.822897 -47.767521)
			(xy 157.845538 -47.817101) (xy 157.860894 -47.869398) (xy 157.86865 -47.923348) (xy 157.86865 -47.977852)
			(xy 157.860894 -48.031802) (xy 157.845538 -48.084099) (xy 157.822897 -48.133679) (xy 157.79343 -48.179532)
			(xy 157.757738 -48.220724) (xy 157.716548 -48.256418) (xy 157.670696 -48.285887) (xy 157.621118 -48.308531)
			(xy 157.568822 -48.323889) (xy 157.514872 -48.331649) (xy 157.48762 -48.332136) (xy 157.457643 -48.331535)
			(xy 157.398428 -48.322147) (xy 157.34141 -48.303615) (xy 157.287991 -48.276395) (xy 157.239486 -48.241156)
			(xy 157.217872 -48.220376) (xy 157.208291 -48.211408) (xy 157.185598 -48.198248) (xy 157.160301 -48.191298)
			(xy 157.134069 -48.191017) (xy 157.10863 -48.197423) (xy 157.08566 -48.210095) (xy 157.075886 -48.218852)
			(xy 157.054411 -48.23856) (xy 157.006628 -48.271931) (xy 156.95433 -48.297657) (xy 156.898731 -48.315141)
			(xy 156.841122 -48.323976) (xy 156.81198 -48.324516) (xy 155.94838 -48.324516) (xy 155.920519 -48.323951)
			(xy 155.865389 -48.315841) (xy 155.812022 -48.299811) (xy 155.761548 -48.2762) (xy 155.715039 -48.24551)
			(xy 155.67348 -48.20839) (xy 155.637752 -48.165629) (xy 155.622752 -48.142144) (xy 155.614363 -48.129505)
			(xy 155.591683 -48.10939) (xy 155.564093 -48.096829) (xy 155.534029 -48.092933) (xy 155.504148 -48.098046)
			(xy 155.47709 -48.111717) (xy 155.46578 -48.121824) (xy 155.444316 -48.141613) (xy 155.396518 -48.175128)
			(xy 155.344174 -48.200974) (xy 155.288505 -48.218548) (xy 155.230809 -48.22744) (xy 155.20162 -48.227996)
			(xy 155.174365 -48.227558) (xy 155.12041 -48.219804) (xy 155.068109 -48.204449) (xy 155.018524 -48.181807)
			(xy 154.972667 -48.152338) (xy 154.931471 -48.116643) (xy 154.895774 -48.075449) (xy 154.866303 -48.029593)
			(xy 154.843658 -47.98001) (xy 154.828301 -47.927709) (xy 154.820543 -47.873755) (xy 140.16228 -47.873755)
			(xy 140.16228 -48.576992) (xy 158.58744 -48.576992) (xy 158.587994 -48.548105) (xy 158.596694 -48.490989)
			(xy 158.613907 -48.435838) (xy 158.639241 -48.383914) (xy 158.672116 -48.336405) (xy 158.71178 -48.294397)
			(xy 158.757326 -48.258852) (xy 158.782258 -48.244252) (xy 158.795481 -48.236257) (xy 158.816707 -48.213821)
			(xy 158.830263 -48.186069) (xy 158.83491 -48.155535) (xy 158.830224 -48.125007) (xy 158.823914 -48.110902)
			(xy 158.81163 -48.08464) (xy 158.794302 -48.029312) (xy 158.785566 -47.971997) (xy 158.785052 -47.943008)
			(xy 158.785585 -47.915759) (xy 158.793339 -47.861815) (xy 158.808692 -47.809523) (xy 158.831329 -47.759949)
			(xy 158.860791 -47.7141) (xy 158.896477 -47.672911) (xy 158.937662 -47.637219) (xy 158.983507 -47.607752)
			(xy 159.033078 -47.585108) (xy 159.085368 -47.56975) (xy 159.139311 -47.561989) (xy 159.16656 -47.5615)
			(xy 160.03016 -47.5615) (xy 160.057412 -47.561993) (xy 160.111363 -47.569744) (xy 160.16366 -47.585096)
			(xy 160.213241 -47.607734) (xy 160.259095 -47.637199) (xy 160.300288 -47.672889) (xy 160.335982 -47.71408)
			(xy 160.365451 -47.759931) (xy 160.388093 -47.80951) (xy 160.403449 -47.861806) (xy 160.411205 -47.915756)
			(xy 160.411668 -47.943008) (xy 160.411135 -47.971994) (xy 160.40237 -48.0293) (xy 160.385057 -48.084627)
			(xy 160.372806 -48.110902) (xy 160.3665 -48.125008) (xy 160.361813 -48.155534) (xy 160.366461 -48.186067)
			(xy 160.380017 -48.213816) (xy 160.401246 -48.236248) (xy 160.414462 -48.244252) (xy 160.439394 -48.258852)
			(xy 160.484936 -48.294402) (xy 160.51586 -48.327155) (xy 177.908133 -48.327155) (xy 177.908133 -48.272645)
			(xy 177.91589 -48.218691) (xy 177.931248 -48.16639) (xy 177.953892 -48.116806) (xy 177.983362 -48.07095)
			(xy 178.019058 -48.029755) (xy 178.060254 -47.994059) (xy 178.10611 -47.96459) (xy 178.155693 -47.941946)
			(xy 178.207995 -47.92659) (xy 178.261949 -47.918833) (xy 178.289204 -47.91837) (xy 178.318277 -47.918875)
			(xy 178.375749 -47.927713) (xy 178.431214 -47.945168) (xy 178.483389 -47.970836) (xy 178.531065 -48.004123)
			(xy 178.57314 -48.044258) (xy 178.608638 -48.090312) (xy 178.636737 -48.141218) (xy 178.656788 -48.195799)
			(xy 178.663092 -48.224186) (xy 178.666399 -48.237682) (xy 178.67907 -48.26239) (xy 178.697932 -48.282769)
			(xy 178.72159 -48.297308) (xy 178.748291 -48.304932) (xy 178.776059 -48.305077) (xy 178.802838 -48.29773)
			(xy 178.814984 -48.290988) (xy 178.837349 -48.278078) (xy 178.884814 -48.257738) (xy 178.934587 -48.243977)
			(xy 178.98576 -48.237046) (xy 179.01158 -48.236632) (xy 179.038834 -48.237074) (xy 179.092788 -48.244829)
			(xy 179.145089 -48.260185) (xy 179.194671 -48.282828) (xy 179.240527 -48.312298) (xy 179.28172 -48.347994)
			(xy 179.317414 -48.38919) (xy 179.346882 -48.435046) (xy 179.369522 -48.48463) (xy 179.384875 -48.536932)
			(xy 179.392627 -48.590886) (xy 179.393088 -48.61814) (xy 179.393088 -49.48174) (xy 179.392659 -49.508993)
			(xy 179.384897 -49.562944) (xy 179.369536 -49.615241) (xy 179.346888 -49.66482) (xy 179.317416 -49.710671)
			(xy 179.281719 -49.751861) (xy 179.240523 -49.787552) (xy 179.194667 -49.817017) (xy 179.145085 -49.839657)
			(xy 179.092785 -49.85501) (xy 179.038833 -49.862764) (xy 179.01158 -49.863248) (xy 178.985758 -49.862839)
			(xy 178.93458 -49.855929) (xy 178.884805 -49.842169) (xy 178.837344 -49.821813) (xy 178.814984 -49.808892)
			(xy 178.802862 -49.802093) (xy 178.776065 -49.794744) (xy 178.74828 -49.794888) (xy 178.721562 -49.802517)
			(xy 178.697888 -49.817064) (xy 178.679012 -49.837453) (xy 178.666329 -49.862175) (xy 178.663092 -49.875694)
			(xy 178.656748 -49.904071) (xy 178.652679 -49.915154) (xy 181.026241 -49.915154) (xy 181.026241 -49.860646)
			(xy 181.033998 -49.806692) (xy 181.049355 -49.754392) (xy 181.071999 -49.704809) (xy 181.101469 -49.658954)
			(xy 181.137165 -49.617759) (xy 181.17836 -49.582064) (xy 181.224216 -49.552595) (xy 181.273799 -49.529953)
			(xy 181.3261 -49.514597) (xy 181.380054 -49.50684) (xy 181.407308 -49.506378) (xy 181.436196 -49.506913)
			(xy 181.493314 -49.515613) (xy 181.548466 -49.532829) (xy 181.60039 -49.558166) (xy 181.6479 -49.591044)
			(xy 181.689906 -49.630712) (xy 181.72545 -49.676262) (xy 181.740048 -49.701196) (xy 181.748059 -49.714409)
			(xy 181.770486 -49.735644) (xy 181.798235 -49.749205) (xy 181.828768 -49.753854) (xy 181.859294 -49.749165)
			(xy 181.873398 -49.742852) (xy 181.899668 -49.730568) (xy 181.954986 -49.713167) (xy 182.012298 -49.704319)
			(xy 182.041292 -49.703736) (xy 182.070289 -49.704304) (xy 182.127606 -49.713133) (xy 182.182925 -49.730544)
			(xy 182.209186 -49.742852) (xy 182.223293 -49.749159) (xy 182.25382 -49.753852) (xy 182.284354 -49.749207)
			(xy 182.312105 -49.735648) (xy 182.334534 -49.714415) (xy 182.342536 -49.701196) (xy 182.357132 -49.676262)
			(xy 182.392684 -49.630721) (xy 182.434695 -49.59106) (xy 182.482204 -49.558184) (xy 182.534126 -49.532846)
			(xy 182.589275 -49.515624) (xy 182.646389 -49.506912) (xy 182.675276 -49.506378) (xy 182.702529 -49.506868)
			(xy 182.756481 -49.514622) (xy 182.808779 -49.529975) (xy 182.858361 -49.552615) (xy 182.904215 -49.582082)
			(xy 182.945409 -49.617774) (xy 182.981104 -49.658966) (xy 183.010573 -49.704818) (xy 183.033217 -49.754398)
			(xy 183.048573 -49.806696) (xy 183.056331 -49.860647) (xy 183.056331 -49.915153) (xy 183.048573 -49.969104)
			(xy 183.033217 -50.021402) (xy 183.010573 -50.070982) (xy 182.981104 -50.116834) (xy 182.945409 -50.158026)
			(xy 182.904215 -50.193718) (xy 182.858361 -50.223185) (xy 182.808779 -50.245825) (xy 182.756481 -50.261178)
			(xy 182.702529 -50.268932) (xy 182.675276 -50.269394) (xy 182.64497 -50.268835) (xy 182.585121 -50.259257)
			(xy 182.55615 -50.250344) (xy 182.542958 -50.246524) (xy 182.515539 -50.245208) (xy 182.488761 -50.251246)
			(xy 182.464561 -50.264201) (xy 182.444687 -50.283137) (xy 182.430578 -50.306684) (xy 182.423254 -50.333139)
			(xy 182.4228 -50.346864) (xy 182.4228 -50.687732) (xy 182.423215 -50.701463) (xy 182.430542 -50.727929)
			(xy 182.444656 -50.751486) (xy 182.464537 -50.770429) (xy 182.488747 -50.78339) (xy 182.515536 -50.789431)
			(xy 182.542966 -50.788114) (xy 182.55615 -50.784252) (xy 182.585122 -50.775347) (xy 182.644972 -50.765783)
			(xy 182.675276 -50.765202) (xy 182.702531 -50.765643) (xy 182.756486 -50.773398) (xy 182.808788 -50.788752)
			(xy 182.858372 -50.811394) (xy 182.90423 -50.840862) (xy 182.945426 -50.876557) (xy 182.981124 -50.917751)
			(xy 183.010595 -50.963607) (xy 183.03324 -51.01319) (xy 183.048597 -51.065491) (xy 183.056355 -51.119445)
			(xy 183.056355 -51.173955) (xy 183.048597 -51.227909) (xy 183.03324 -51.28021) (xy 183.010595 -51.329793)
			(xy 182.981124 -51.375649) (xy 182.945426 -51.416843) (xy 182.90423 -51.452538) (xy 182.858372 -51.482006)
			(xy 182.808788 -51.504648) (xy 182.756486 -51.520002) (xy 182.702531 -51.527757) (xy 182.675276 -51.528218)
			(xy 182.646387 -51.527698) (xy 182.589269 -51.518995) (xy 182.534116 -51.501777) (xy 182.482192 -51.476438)
			(xy 182.434683 -51.443557) (xy 182.392676 -51.403887) (xy 182.357134 -51.358335) (xy 182.342536 -51.3334)
			(xy 182.334543 -51.320175) (xy 182.31211 -51.29894) (xy 182.284357 -51.285381) (xy 182.25382 -51.280735)
			(xy 182.22329 -51.285428) (xy 182.209186 -51.291744) (xy 182.182918 -51.304033) (xy 182.127599 -51.321432)
			(xy 182.070287 -51.330278) (xy 182.041292 -51.33086) (xy 182.012295 -51.330299) (xy 181.954977 -51.321467)
			(xy 181.899658 -51.304054) (xy 181.873398 -51.291744) (xy 181.859298 -51.285421) (xy 181.828767 -51.280732)
			(xy 181.798231 -51.285381) (xy 181.77048 -51.298943) (xy 181.74805 -51.320179) (xy 181.740048 -51.3334)
			(xy 181.725462 -51.35834) (xy 181.689908 -51.403881) (xy 181.647896 -51.443542) (xy 181.600385 -51.476417)
			(xy 181.548461 -51.501754) (xy 181.493311 -51.518975) (xy 181.436196 -51.527686) (xy 181.407308 -51.528218)
			(xy 181.380055 -51.527735) (xy 181.326105 -51.519979) (xy 181.273808 -51.504624) (xy 181.224228 -51.481983)
			(xy 181.178375 -51.452516) (xy 181.137182 -51.416823) (xy 181.101489 -51.375631) (xy 181.072021 -51.329779)
			(xy 181.049378 -51.2802) (xy 181.034022 -51.227903) (xy 181.026265 -51.173953) (xy 181.026265 -51.119447)
			(xy 181.034022 -51.065497) (xy 181.049378 -51.0132) (xy 181.072021 -50.963621) (xy 181.101489 -50.917769)
			(xy 181.137182 -50.876577) (xy 181.178375 -50.840884) (xy 181.224228 -50.811417) (xy 181.273808 -50.788776)
			(xy 181.326105 -50.773421) (xy 181.380055 -50.765665) (xy 181.407308 -50.765202) (xy 181.437614 -50.765764)
			(xy 181.497463 -50.77534) (xy 181.526434 -50.784252) (xy 181.53963 -50.788058) (xy 181.567047 -50.789377)
			(xy 181.593824 -50.783342) (xy 181.618025 -50.770389) (xy 181.637898 -50.751456) (xy 181.652007 -50.72791)
			(xy 181.65933 -50.701456) (xy 181.659784 -50.687732) (xy 181.659784 -50.346864) (xy 181.659393 -50.333132)
			(xy 181.652064 -50.306662) (xy 181.637946 -50.283103) (xy 181.618061 -50.264158) (xy 181.593846 -50.251198)
			(xy 181.567053 -50.245159) (xy 181.539619 -50.246479) (xy 181.526434 -50.250344) (xy 181.497457 -50.25923)
			(xy 181.437611 -50.268807) (xy 181.407308 -50.269394) (xy 181.380054 -50.26896) (xy 181.3261 -50.261203)
			(xy 181.273799 -50.245847) (xy 181.224216 -50.223205) (xy 181.17836 -50.193736) (xy 181.137165 -50.158041)
			(xy 181.101469 -50.116846) (xy 181.071999 -50.070991) (xy 181.049355 -50.021408) (xy 181.033998 -49.969108)
			(xy 181.026241 -49.915154) (xy 178.652679 -49.915154) (xy 178.63671 -49.958652) (xy 178.608619 -50.009559)
			(xy 178.573128 -50.055613) (xy 178.531057 -50.095747) (xy 178.483383 -50.12903) (xy 178.431209 -50.154692)
			(xy 178.375745 -50.172137) (xy 178.318276 -50.180963) (xy 178.289204 -50.18151) (xy 178.261951 -50.181043)
			(xy 178.208 -50.173286) (xy 178.155702 -50.157931) (xy 178.106122 -50.135289) (xy 178.060268 -50.105821)
			(xy 178.019075 -50.070128) (xy 177.983381 -50.028935) (xy 177.953913 -49.983082) (xy 177.931271 -49.933502)
			(xy 177.915914 -49.881204) (xy 177.908157 -49.827253) (xy 177.908157 -49.772747) (xy 177.915914 -49.718796)
			(xy 177.931271 -49.666498) (xy 177.953913 -49.616918) (xy 177.983381 -49.571065) (xy 178.019075 -49.529872)
			(xy 178.060268 -49.494179) (xy 178.106122 -49.464711) (xy 178.155702 -49.442069) (xy 178.208 -49.426714)
			(xy 178.261951 -49.418957) (xy 178.289204 -49.418494) (xy 178.313924 -49.418892) (xy 178.362952 -49.425265)
			(xy 178.410747 -49.437917) (xy 178.456507 -49.456636) (xy 178.47818 -49.468532) (xy 178.491673 -49.475522)
			(xy 178.521321 -49.482101) (xy 178.551594 -49.479681) (xy 178.579821 -49.468475) (xy 178.603511 -49.449473)
			(xy 178.620574 -49.424351) (xy 178.629506 -49.395324) (xy 178.630072 -49.38014) (xy 178.630072 -48.71974)
			(xy 178.629548 -48.704542) (xy 178.620645 -48.675479) (xy 178.603586 -48.650322) (xy 178.579881 -48.631297)
			(xy 178.551628 -48.620089) (xy 178.521327 -48.617689) (xy 178.491661 -48.624309) (xy 178.47818 -48.631348)
			(xy 178.456511 -48.643251) (xy 178.410748 -48.661964) (xy 178.362953 -48.674616) (xy 178.313925 -48.680996)
			(xy 178.289204 -48.681386) (xy 178.261949 -48.680967) (xy 178.207995 -48.67321) (xy 178.155693 -48.657854)
			(xy 178.10611 -48.63521) (xy 178.060254 -48.605741) (xy 178.019058 -48.570045) (xy 177.983362 -48.52885)
			(xy 177.953892 -48.482994) (xy 177.931248 -48.43341) (xy 177.91589 -48.381109) (xy 177.908133 -48.327155)
			(xy 160.51586 -48.327155) (xy 160.524599 -48.336411) (xy 160.557476 -48.38392) (xy 160.582815 -48.435842)
			(xy 160.600036 -48.49099) (xy 160.608747 -48.548105) (xy 160.60928 -48.576992) (xy 160.608794 -48.604243)
			(xy 160.601038 -48.658191) (xy 160.585683 -48.710486) (xy 160.563041 -48.760063) (xy 160.533575 -48.805913)
			(xy 160.497884 -48.847104) (xy 160.456693 -48.882795) (xy 160.410843 -48.912261) (xy 160.361266 -48.934903)
			(xy 160.308971 -48.950258) (xy 160.255023 -48.958014) (xy 160.200521 -48.958014) (xy 160.146573 -48.950258)
			(xy 160.094278 -48.934903) (xy 160.044701 -48.912261) (xy 159.998851 -48.882795) (xy 159.95766 -48.847104)
			(xy 159.921969 -48.805913) (xy 159.892503 -48.760063) (xy 159.869861 -48.710486) (xy 159.854506 -48.658191)
			(xy 159.84675 -48.604243) (xy 159.846264 -48.576992) (xy 159.846828 -48.546687) (xy 159.856403 -48.486837)
			(xy 159.865314 -48.457866) (xy 159.869156 -48.444678) (xy 159.870477 -48.417254) (xy 159.86444 -48.39047)
			(xy 159.851482 -48.366265) (xy 159.83254 -48.346389) (xy 159.808985 -48.332283) (xy 159.782522 -48.324965)
			(xy 159.768794 -48.324516) (xy 159.427926 -48.324516) (xy 159.414195 -48.324959) (xy 159.387727 -48.332273)
			(xy 159.364166 -48.346379) (xy 159.345219 -48.366257) (xy 159.332257 -48.390466) (xy 159.326218 -48.417254)
			(xy 159.32754 -48.444683) (xy 159.331406 -48.457866) (xy 159.340293 -48.486843) (xy 159.349869 -48.546689)
			(xy 159.350456 -48.576992) (xy 159.34997 -48.604243) (xy 159.342214 -48.658191) (xy 159.326859 -48.710486)
			(xy 159.304217 -48.760063) (xy 159.274751 -48.805913) (xy 159.23906 -48.847104) (xy 159.197869 -48.882795)
			(xy 159.152019 -48.912261) (xy 159.102442 -48.934903) (xy 159.050147 -48.950258) (xy 158.996199 -48.958014)
			(xy 158.941697 -48.958014) (xy 158.887749 -48.950258) (xy 158.835454 -48.934903) (xy 158.785877 -48.912261)
			(xy 158.740027 -48.882795) (xy 158.698836 -48.847104) (xy 158.663145 -48.805913) (xy 158.633679 -48.760063)
			(xy 158.611037 -48.710486) (xy 158.595682 -48.658191) (xy 158.587926 -48.604243) (xy 158.58744 -48.576992)
			(xy 140.16228 -48.576992) (xy 140.16228 -48.924464) (xy 140.162725 -48.938182) (xy 140.170028 -48.964626)
			(xy 140.184115 -48.988168) (xy 140.203967 -49.007104) (xy 140.228148 -49.020063) (xy 140.254908 -49.026109)
			(xy 140.282312 -49.024803) (xy 140.308376 -49.016241) (xy 140.331215 -49.001041) (xy 140.340588 -48.991012)
			(xy 140.358786 -48.97073) (xy 140.399978 -48.935058) (xy 140.445828 -48.905614) (xy 140.495403 -48.882996)
			(xy 140.547693 -48.867665) (xy 140.601632 -48.859934) (xy 140.628878 -48.85944) (xy 140.656131 -48.859902)
			(xy 140.710081 -48.867657) (xy 140.762379 -48.883011) (xy 140.811959 -48.905653) (xy 140.857811 -48.935121)
			(xy 140.899003 -48.970816) (xy 140.934694 -49.012009) (xy 140.964159 -49.057864) (xy 140.986798 -49.107445)
			(xy 141.002149 -49.159744) (xy 141.0099 -49.213695) (xy 141.010386 -49.240948) (xy 141.010031 -49.265158)
			(xy 141.003935 -49.313194) (xy 140.991798 -49.360068) (xy 140.98702 -49.372012) (xy 146.806156 -49.372012)
			(xy 146.810227 -49.31639) (xy 146.822353 -49.261953) (xy 146.842276 -49.209862) (xy 146.869572 -49.161227)
			(xy 146.903658 -49.117084) (xy 146.943807 -49.078375) (xy 146.989165 -49.045924) (xy 147.038765 -49.020423)
			(xy 147.091549 -49.002416) (xy 147.146392 -48.992286) (xy 147.202126 -48.990249) (xy 147.257563 -48.996349)
			(xy 147.31152 -49.010455) (xy 147.362849 -49.032267) (xy 147.410455 -49.061321) (xy 147.453323 -49.096996)
			(xy 147.49054 -49.138533) (xy 147.521313 -49.185046) (xy 147.544985 -49.235543) (xy 147.561053 -49.28895)
			(xy 147.569173 -49.344126) (xy 147.569682 -49.372012) (xy 147.569173 -49.399898) (xy 147.561053 -49.455074)
			(xy 147.544985 -49.508481) (xy 147.521313 -49.558978) (xy 147.49054 -49.605491) (xy 147.453323 -49.647028)
			(xy 147.410455 -49.682703) (xy 147.362849 -49.711757) (xy 147.31152 -49.733569) (xy 147.257563 -49.747675)
			(xy 147.202126 -49.753775) (xy 147.146392 -49.751738) (xy 147.091549 -49.741608) (xy 147.038765 -49.723601)
			(xy 146.989165 -49.6981) (xy 146.943807 -49.665649) (xy 146.903658 -49.62694) (xy 146.869572 -49.582797)
			(xy 146.842276 -49.534162) (xy 146.822353 -49.482071) (xy 146.810227 -49.427634) (xy 146.806156 -49.372012)
			(xy 140.98702 -49.372012) (xy 140.973814 -49.405025) (xy 140.96238 -49.426368) (xy 140.956248 -49.438257)
			(xy 140.949794 -49.46421) (xy 140.95029 -49.490949) (xy 140.957702 -49.516645) (xy 140.971523 -49.53954)
			(xy 140.990808 -49.558068) (xy 141.014238 -49.570962) (xy 141.02715 -49.57445) (xy 141.054518 -49.581594)
			(xy 141.106931 -49.602855) (xy 141.155631 -49.631621) (xy 141.19955 -49.667262) (xy 141.237727 -49.708996)
			(xy 141.269323 -49.755909) (xy 141.293647 -49.806973) (xy 141.310167 -49.861068) (xy 141.318518 -49.917009)
			(xy 141.318996 -49.94529) (xy 141.318658 -49.967923) (xy 141.313309 -50.012871) (xy 141.308328 -50.034952)
			(xy 141.305291 -50.049856) (xy 141.307136 -50.080199) (xy 141.317832 -50.108655) (xy 141.336431 -50.1327)
			(xy 141.361285 -50.150205) (xy 141.39019 -50.159617) (xy 141.420586 -50.160102) (xy 141.435328 -50.156364)
			(xy 141.461181 -50.149365) (xy 141.514212 -50.141847) (xy 141.540992 -50.141378) (xy 141.568244 -50.141863)
			(xy 141.622193 -50.149619) (xy 141.67449 -50.164973) (xy 141.724069 -50.187614) (xy 141.769921 -50.217079)
			(xy 141.811114 -50.252771) (xy 141.846807 -50.293961) (xy 141.876276 -50.339812) (xy 141.898919 -50.38939)
			(xy 141.914277 -50.441685) (xy 141.922035 -50.495634) (xy 141.9225 -50.522886) (xy 141.922265 -50.541679)
			(xy 141.918573 -50.579084) (xy 141.915134 -50.597562) (xy 141.912793 -50.611334) (xy 141.914882 -50.639182)
			(xy 141.924444 -50.66542) (xy 141.940764 -50.688081) (xy 141.962617 -50.705467) (xy 141.988367 -50.716275)
			(xy 142.016082 -50.719695) (xy 142.029942 -50.717958) (xy 142.04427 -50.715926) (xy 142.073129 -50.713761)
			(xy 142.0876 -50.71364) (xy 142.114847 -50.714126) (xy 142.168787 -50.721881) (xy 142.221073 -50.737234)
			(xy 142.270643 -50.759871) (xy 142.316487 -50.789332) (xy 142.357672 -50.825017) (xy 142.393359 -50.8662)
			(xy 142.412519 -50.896012) (xy 155.708856 -50.896012) (xy 155.712927 -50.84039) (xy 155.725053 -50.785953)
			(xy 155.744976 -50.733862) (xy 155.772272 -50.685227) (xy 155.806358 -50.641084) (xy 155.846507 -50.602375)
			(xy 155.891865 -50.569924) (xy 155.941465 -50.544423) (xy 155.994249 -50.526416) (xy 156.049092 -50.516286)
			(xy 156.104826 -50.514249) (xy 156.160263 -50.520349) (xy 156.21422 -50.534455) (xy 156.265549 -50.556267)
			(xy 156.313155 -50.585321) (xy 156.356023 -50.620996) (xy 156.39324 -50.662533) (xy 156.424013 -50.709046)
			(xy 156.447685 -50.759543) (xy 156.463753 -50.81295) (xy 156.471873 -50.868126) (xy 156.472382 -50.896012)
			(xy 156.471873 -50.923898) (xy 156.464987 -50.970688) (xy 170.735242 -50.970688) (xy 170.739313 -50.915066)
			(xy 170.751439 -50.860629) (xy 170.771362 -50.808538) (xy 170.798658 -50.759903) (xy 170.832744 -50.71576)
			(xy 170.872893 -50.677051) (xy 170.918251 -50.6446) (xy 170.967851 -50.619099) (xy 171.020635 -50.601092)
			(xy 171.075478 -50.590962) (xy 171.131212 -50.588925) (xy 171.186649 -50.595025) (xy 171.240606 -50.609131)
			(xy 171.291935 -50.630943) (xy 171.339541 -50.659997) (xy 171.382409 -50.695672) (xy 171.419626 -50.737209)
			(xy 171.450399 -50.783722) (xy 171.474071 -50.834219) (xy 171.490139 -50.887626) (xy 171.498259 -50.942802)
			(xy 171.498768 -50.970688) (xy 171.498259 -50.998574) (xy 171.490139 -51.05375) (xy 171.474071 -51.107157)
			(xy 171.450399 -51.157654) (xy 171.419626 -51.204167) (xy 171.382409 -51.245704) (xy 171.339541 -51.281379)
			(xy 171.291935 -51.310433) (xy 171.252584 -51.327155) (xy 177.908127 -51.327155) (xy 177.908127 -51.272645)
			(xy 177.915885 -51.21869) (xy 177.931242 -51.166388) (xy 177.953886 -51.116803) (xy 177.983357 -51.070947)
			(xy 178.019054 -51.029751) (xy 178.06025 -50.994055) (xy 178.106107 -50.964585) (xy 178.155691 -50.941941)
			(xy 178.207994 -50.926584) (xy 178.261949 -50.918827) (xy 178.289204 -50.918364) (xy 178.318277 -50.918874)
			(xy 178.375748 -50.927711) (xy 178.431213 -50.945166) (xy 178.483388 -50.970834) (xy 178.531064 -51.00412)
			(xy 178.573138 -51.044254) (xy 178.608636 -51.090308) (xy 178.636736 -51.141213) (xy 178.656788 -51.195793)
			(xy 178.663092 -51.22418) (xy 178.666402 -51.237675) (xy 178.679072 -51.262384) (xy 178.697933 -51.282763)
			(xy 178.721591 -51.297303) (xy 178.748292 -51.304927) (xy 178.776059 -51.305071) (xy 178.802838 -51.297725)
			(xy 178.814984 -51.290982) (xy 178.837337 -51.278035) (xy 178.884797 -51.257638) (xy 178.93457 -51.243815)
			(xy 178.985752 -51.236819) (xy 179.01158 -51.236372) (xy 179.038843 -51.236875) (xy 179.092814 -51.244635)
			(xy 179.14513 -51.26) (xy 179.194726 -51.282658) (xy 179.24059 -51.312145) (xy 179.281789 -51.347862)
			(xy 179.317483 -51.389081) (xy 179.346945 -51.434962) (xy 179.369575 -51.484571) (xy 179.384911 -51.536896)
			(xy 179.392641 -51.590871) (xy 179.393088 -51.618134) (xy 179.393088 -52.481734) (xy 179.392608 -52.508992)
			(xy 179.384849 -52.562952) (xy 179.369494 -52.615259) (xy 179.346854 -52.664851) (xy 179.31739 -52.710718)
			(xy 179.281702 -52.751928) (xy 179.240515 -52.787643) (xy 179.194667 -52.817136) (xy 179.14509 -52.839807)
			(xy 179.092792 -52.855197) (xy 179.038837 -52.862991) (xy 179.01158 -52.863496) (xy 178.98575 -52.863073)
			(xy 178.934563 -52.856093) (xy 178.884787 -52.842265) (xy 178.837335 -52.821841) (xy 178.814984 -52.808886)
			(xy 178.80286 -52.802091) (xy 178.776064 -52.794742) (xy 178.74828 -52.794887) (xy 178.721563 -52.802515)
			(xy 178.69789 -52.817061) (xy 178.679013 -52.837449) (xy 178.66633 -52.86217) (xy 178.663092 -52.875688)
			(xy 178.656744 -52.904064) (xy 178.636706 -52.958645) (xy 178.608617 -53.009552) (xy 178.573126 -53.055606)
			(xy 178.531056 -53.09574) (xy 178.483382 -53.129024) (xy 178.431208 -53.154686) (xy 178.375745 -53.172131)
			(xy 178.318275 -53.180957) (xy 178.289204 -53.181504) (xy 178.261951 -53.181049) (xy 178.207999 -53.173292)
			(xy 178.1557 -53.157936) (xy 178.106119 -53.135294) (xy 178.060265 -53.105826) (xy 178.019071 -53.070132)
			(xy 177.983377 -53.028939) (xy 177.953908 -52.983085) (xy 177.931265 -52.933504) (xy 177.915909 -52.881205)
			(xy 177.908151 -52.827253) (xy 177.908151 -52.772747) (xy 177.915909 -52.718795) (xy 177.931265 -52.666496)
			(xy 177.953908 -52.616915) (xy 177.983377 -52.571061) (xy 178.019071 -52.529868) (xy 178.060265 -52.494174)
			(xy 178.106119 -52.464706) (xy 178.1557 -52.442064) (xy 178.207999 -52.426708) (xy 178.261951 -52.418951)
			(xy 178.289204 -52.418488) (xy 178.313924 -52.418887) (xy 178.362952 -52.42526) (xy 178.410747 -52.437912)
			(xy 178.456507 -52.45663) (xy 178.47818 -52.468526) (xy 178.491671 -52.475521) (xy 178.52132 -52.482101)
			(xy 178.551594 -52.47968) (xy 178.579822 -52.468474) (xy 178.603513 -52.449471) (xy 178.620576 -52.424347)
			(xy 178.629507 -52.395319) (xy 178.630072 -52.380134) (xy 178.630072 -51.719734) (xy 178.629552 -51.704535)
			(xy 178.620648 -51.675473) (xy 178.603588 -51.650316) (xy 178.579882 -51.631292) (xy 178.551629 -51.620083)
			(xy 178.521328 -51.617683) (xy 178.491661 -51.624303) (xy 178.47818 -51.631342) (xy 178.45651 -51.643245)
			(xy 178.410747 -51.661958) (xy 178.362952 -51.67461) (xy 178.313925 -51.68099) (xy 178.289204 -51.68138)
			(xy 178.261949 -51.680973) (xy 178.207994 -51.673216) (xy 178.155691 -51.657859) (xy 178.106107 -51.635215)
			(xy 178.06025 -51.605745) (xy 178.019054 -51.570049) (xy 177.983357 -51.528853) (xy 177.953886 -51.482997)
			(xy 177.931242 -51.433412) (xy 177.915885 -51.38111) (xy 177.908127 -51.327155) (xy 171.252584 -51.327155)
			(xy 171.240606 -51.332245) (xy 171.186649 -51.346351) (xy 171.131212 -51.352451) (xy 171.075478 -51.350414)
			(xy 171.020635 -51.340284) (xy 170.967851 -51.322277) (xy 170.918251 -51.296776) (xy 170.872893 -51.264325)
			(xy 170.832744 -51.225616) (xy 170.798658 -51.181473) (xy 170.771362 -51.132838) (xy 170.751439 -51.080747)
			(xy 170.739313 -51.02631) (xy 170.735242 -50.970688) (xy 156.464987 -50.970688) (xy 156.463753 -50.979074)
			(xy 156.447685 -51.032481) (xy 156.424013 -51.082978) (xy 156.39324 -51.129491) (xy 156.356023 -51.171028)
			(xy 156.313155 -51.206703) (xy 156.265549 -51.235757) (xy 156.21422 -51.257569) (xy 156.160263 -51.271675)
			(xy 156.104826 -51.277775) (xy 156.049092 -51.275738) (xy 155.994249 -51.265608) (xy 155.941465 -51.247601)
			(xy 155.891865 -51.2221) (xy 155.846507 -51.189649) (xy 155.806358 -51.15094) (xy 155.772272 -51.106797)
			(xy 155.744976 -51.058162) (xy 155.725053 -51.006071) (xy 155.712927 -50.951634) (xy 155.708856 -50.896012)
			(xy 142.412519 -50.896012) (xy 142.422822 -50.912043) (xy 142.445461 -50.961612) (xy 142.460815 -51.013898)
			(xy 142.468573 -51.067837) (xy 142.468575 -51.122331) (xy 142.460822 -51.176271) (xy 142.445472 -51.228558)
			(xy 142.422837 -51.278129) (xy 142.393378 -51.323974) (xy 142.357694 -51.36516) (xy 142.316513 -51.400849)
			(xy 142.270671 -51.430314) (xy 142.221103 -51.452955) (xy 142.168818 -51.468312) (xy 142.114879 -51.476072)
			(xy 142.060385 -51.476076) (xy 142.006445 -51.468326) (xy 141.954157 -51.452978) (xy 141.904585 -51.430345)
			(xy 141.858739 -51.400887) (xy 141.817551 -51.365206) (xy 141.781861 -51.324026) (xy 141.752394 -51.278185)
			(xy 141.72975 -51.228618) (xy 141.714391 -51.176333) (xy 141.70663 -51.122395) (xy 141.706092 -51.095148)
			(xy 141.706325 -51.076354) (xy 141.710014 -51.038949) (xy 141.713458 -51.020472) (xy 141.71579 -51.006706)
			(xy 141.713687 -50.978874) (xy 141.704118 -50.952655) (xy 141.6878 -50.930012) (xy 141.665954 -50.912641)
			(xy 141.640216 -50.901842) (xy 141.612515 -50.898426) (xy 141.59865 -50.900076) (xy 141.584322 -50.902108)
			(xy 141.555462 -50.904272) (xy 141.540992 -50.904394) (xy 141.51374 -50.90393) (xy 141.459791 -50.896172)
			(xy 141.407495 -50.880815) (xy 141.357916 -50.858172) (xy 141.312065 -50.828704) (xy 141.270875 -50.79301)
			(xy 141.235183 -50.751817) (xy 141.205717 -50.705964) (xy 141.183077 -50.656385) (xy 141.167723 -50.604088)
			(xy 141.159968 -50.550138) (xy 141.159484 -50.522886) (xy 141.159823 -50.500253) (xy 141.165174 -50.455305)
			(xy 141.170152 -50.433224) (xy 141.173185 -50.418324) (xy 141.171336 -50.387989) (xy 141.160638 -50.359543)
			(xy 141.14204 -50.335507) (xy 141.117191 -50.318011) (xy 141.088292 -50.308606) (xy 141.057905 -50.308124)
			(xy 141.043152 -50.311812) (xy 141.017298 -50.31881) (xy 140.964268 -50.326326) (xy 140.937488 -50.326798)
			(xy 140.910238 -50.326311) (xy 140.856292 -50.318553) (xy 140.803999 -50.303197) (xy 140.754424 -50.280555)
			(xy 140.708576 -50.251088) (xy 140.667388 -50.215396) (xy 140.631699 -50.174206) (xy 140.602235 -50.128357)
			(xy 140.579596 -50.07878) (xy 140.564242 -50.026487) (xy 140.556488 -49.97254) (xy 140.55598 -49.94529)
			(xy 140.556333 -49.921079) (xy 140.562424 -49.873042) (xy 140.574556 -49.826165) (xy 140.592534 -49.781204)
			(xy 140.603986 -49.75987) (xy 140.61011 -49.747984) (xy 140.616551 -49.722043) (xy 140.616045 -49.695319)
			(xy 140.608626 -49.66964) (xy 140.594802 -49.646763) (xy 140.575519 -49.628254) (xy 140.552096 -49.615377)
			(xy 140.539216 -49.611788) (xy 140.510623 -49.604301) (xy 140.456006 -49.581716) (xy 140.405522 -49.550984)
			(xy 140.360376 -49.512839) (xy 140.340588 -49.490884) (xy 140.331258 -49.480826) (xy 140.30841 -49.465659)
			(xy 140.282349 -49.457123) (xy 140.254955 -49.455834) (xy 140.228207 -49.461886) (xy 140.204037 -49.474842)
			(xy 140.184188 -49.493766) (xy 140.170096 -49.517292) (xy 140.162776 -49.54372) (xy 140.16228 -49.557432)
			(xy 140.16228 -51.476148) (xy 143.026382 -51.476148) (xy 143.030453 -51.420526) (xy 143.042579 -51.366089)
			(xy 143.062502 -51.313998) (xy 143.089798 -51.265363) (xy 143.123884 -51.22122) (xy 143.164033 -51.182511)
			(xy 143.209391 -51.15006) (xy 143.258991 -51.124559) (xy 143.311775 -51.106552) (xy 143.366618 -51.096422)
			(xy 143.422352 -51.094385) (xy 143.477789 -51.100485) (xy 143.531746 -51.114591) (xy 143.583075 -51.136403)
			(xy 143.630681 -51.165457) (xy 143.673549 -51.201132) (xy 143.710766 -51.242669) (xy 143.741539 -51.289182)
			(xy 143.765211 -51.339679) (xy 143.781279 -51.393086) (xy 143.782887 -51.404012) (xy 146.806156 -51.404012)
			(xy 146.810227 -51.34839) (xy 146.822353 -51.293953) (xy 146.842276 -51.241862) (xy 146.869572 -51.193227)
			(xy 146.903658 -51.149084) (xy 146.943807 -51.110375) (xy 146.989165 -51.077924) (xy 147.038765 -51.052423)
			(xy 147.091549 -51.034416) (xy 147.146392 -51.024286) (xy 147.202126 -51.022249) (xy 147.257563 -51.028349)
			(xy 147.31152 -51.042455) (xy 147.362849 -51.064267) (xy 147.410455 -51.093321) (xy 147.453323 -51.128996)
			(xy 147.49054 -51.170533) (xy 147.521313 -51.217046) (xy 147.544985 -51.267543) (xy 147.561053 -51.32095)
			(xy 147.569173 -51.376126) (xy 147.569682 -51.404012) (xy 147.569173 -51.431898) (xy 147.561053 -51.487074)
			(xy 147.544985 -51.540481) (xy 147.521313 -51.590978) (xy 147.49054 -51.637491) (xy 147.453323 -51.679028)
			(xy 147.410455 -51.714703) (xy 147.364338 -51.742848) (xy 151.703022 -51.742848) (xy 151.707093 -51.687226)
			(xy 151.719219 -51.632789) (xy 151.739142 -51.580698) (xy 151.766438 -51.532063) (xy 151.800524 -51.48792)
			(xy 151.840673 -51.449211) (xy 151.886031 -51.41676) (xy 151.935631 -51.391259) (xy 151.988415 -51.373252)
			(xy 152.043258 -51.363122) (xy 152.098992 -51.361085) (xy 152.154429 -51.367185) (xy 152.208386 -51.381291)
			(xy 152.259715 -51.403103) (xy 152.307321 -51.432157) (xy 152.350189 -51.467832) (xy 152.387406 -51.509369)
			(xy 152.418179 -51.555882) (xy 152.441851 -51.606379) (xy 152.457919 -51.659786) (xy 152.466039 -51.714962)
			(xy 152.466548 -51.742848) (xy 152.466039 -51.770734) (xy 152.457919 -51.82591) (xy 152.441851 -51.879317)
			(xy 152.418179 -51.929814) (xy 152.387406 -51.976327) (xy 152.350189 -52.017864) (xy 152.307321 -52.053539)
			(xy 152.282846 -52.068476) (xy 154.419806 -52.068476) (xy 154.423877 -52.012854) (xy 154.436003 -51.958417)
			(xy 154.455926 -51.906326) (xy 154.483222 -51.857691) (xy 154.517308 -51.813548) (xy 154.557457 -51.774839)
			(xy 154.602815 -51.742388) (xy 154.652415 -51.716887) (xy 154.705199 -51.69888) (xy 154.760042 -51.68875)
			(xy 154.815776 -51.686713) (xy 154.871213 -51.692813) (xy 154.92517 -51.706919) (xy 154.976499 -51.728731)
			(xy 155.024105 -51.757785) (xy 155.066973 -51.79346) (xy 155.10419 -51.834997) (xy 155.134963 -51.88151)
			(xy 155.158635 -51.932007) (xy 155.174703 -51.985414) (xy 155.182823 -52.04059) (xy 155.183332 -52.068476)
			(xy 155.182823 -52.096362) (xy 155.174703 -52.151538) (xy 155.158635 -52.204945) (xy 155.134963 -52.255442)
			(xy 155.10419 -52.301955) (xy 155.066973 -52.343492) (xy 155.024105 -52.379167) (xy 154.976499 -52.408221)
			(xy 154.92517 -52.430033) (xy 154.871213 -52.444139) (xy 154.815776 -52.450239) (xy 154.760042 -52.448202)
			(xy 154.705199 -52.438072) (xy 154.652415 -52.420065) (xy 154.602815 -52.394564) (xy 154.557457 -52.362113)
			(xy 154.517308 -52.323404) (xy 154.483222 -52.279261) (xy 154.455926 -52.230626) (xy 154.436003 -52.178535)
			(xy 154.423877 -52.124098) (xy 154.419806 -52.068476) (xy 152.282846 -52.068476) (xy 152.259715 -52.082593)
			(xy 152.208386 -52.104405) (xy 152.154429 -52.118511) (xy 152.098992 -52.124611) (xy 152.043258 -52.122574)
			(xy 151.988415 -52.112444) (xy 151.935631 -52.094437) (xy 151.886031 -52.068936) (xy 151.840673 -52.036485)
			(xy 151.800524 -51.997776) (xy 151.766438 -51.953633) (xy 151.739142 -51.904998) (xy 151.719219 -51.852907)
			(xy 151.707093 -51.79847) (xy 151.703022 -51.742848) (xy 147.364338 -51.742848) (xy 147.362849 -51.743757)
			(xy 147.31152 -51.765569) (xy 147.257563 -51.779675) (xy 147.202126 -51.785775) (xy 147.146392 -51.783738)
			(xy 147.091549 -51.773608) (xy 147.038765 -51.755601) (xy 146.989165 -51.7301) (xy 146.943807 -51.697649)
			(xy 146.903658 -51.65894) (xy 146.869572 -51.614797) (xy 146.842276 -51.566162) (xy 146.822353 -51.514071)
			(xy 146.810227 -51.459634) (xy 146.806156 -51.404012) (xy 143.782887 -51.404012) (xy 143.789399 -51.448262)
			(xy 143.789908 -51.476148) (xy 143.789399 -51.504034) (xy 143.781279 -51.55921) (xy 143.765211 -51.612617)
			(xy 143.741539 -51.663114) (xy 143.710766 -51.709627) (xy 143.673549 -51.751164) (xy 143.630681 -51.786839)
			(xy 143.583075 -51.815893) (xy 143.531746 -51.837705) (xy 143.477789 -51.851811) (xy 143.422352 -51.857911)
			(xy 143.366618 -51.855874) (xy 143.311775 -51.845744) (xy 143.258991 -51.827737) (xy 143.209391 -51.802236)
			(xy 143.164033 -51.769785) (xy 143.123884 -51.731076) (xy 143.089798 -51.686933) (xy 143.062502 -51.638298)
			(xy 143.042579 -51.586207) (xy 143.030453 -51.53177) (xy 143.026382 -51.476148) (xy 140.16228 -51.476148)
			(xy 140.16228 -51.727608) (xy 141.30274 -52.868068) (xy 152.866342 -52.868068) (xy 152.870413 -52.812446)
			(xy 152.882539 -52.758009) (xy 152.902462 -52.705918) (xy 152.929758 -52.657283) (xy 152.963844 -52.61314)
			(xy 153.003993 -52.574431) (xy 153.049351 -52.54198) (xy 153.098951 -52.516479) (xy 153.151735 -52.498472)
			(xy 153.206578 -52.488342) (xy 153.262312 -52.486305) (xy 153.317749 -52.492405) (xy 153.371706 -52.506511)
			(xy 153.423035 -52.528323) (xy 153.470641 -52.557377) (xy 153.513509 -52.593052) (xy 153.550726 -52.634589)
			(xy 153.581499 -52.681102) (xy 153.605171 -52.731599) (xy 153.621239 -52.785006) (xy 153.629359 -52.840182)
			(xy 153.629868 -52.868068) (xy 153.629359 -52.895954) (xy 153.621239 -52.95113) (xy 153.605171 -53.004537)
			(xy 153.581499 -53.055034) (xy 153.550726 -53.101547) (xy 153.513509 -53.143084) (xy 153.470641 -53.178759)
			(xy 153.423035 -53.207813) (xy 153.371706 -53.229625) (xy 153.317749 -53.243731) (xy 153.262312 -53.249831)
			(xy 153.206578 -53.247794) (xy 153.151735 -53.237664) (xy 153.098951 -53.219657) (xy 153.049351 -53.194156)
			(xy 153.003993 -53.161705) (xy 152.963844 -53.122996) (xy 152.929758 -53.078853) (xy 152.902462 -53.030218)
			(xy 152.882539 -52.978127) (xy 152.870413 -52.92369) (xy 152.866342 -52.868068) (xy 141.30274 -52.868068)
			(xy 141.870684 -53.436012) (xy 146.806156 -53.436012) (xy 146.810227 -53.38039) (xy 146.822353 -53.325953)
			(xy 146.842276 -53.273862) (xy 146.869572 -53.225227) (xy 146.903658 -53.181084) (xy 146.943807 -53.142375)
			(xy 146.989165 -53.109924) (xy 147.038765 -53.084423) (xy 147.091549 -53.066416) (xy 147.146392 -53.056286)
			(xy 147.202126 -53.054249) (xy 147.257563 -53.060349) (xy 147.31152 -53.074455) (xy 147.362849 -53.096267)
			(xy 147.410455 -53.125321) (xy 147.453323 -53.160996) (xy 147.49054 -53.202533) (xy 147.521313 -53.249046)
			(xy 147.544985 -53.299543) (xy 147.556028 -53.336249) (xy 154.90979 -53.336249) (xy 154.90979 -53.281751)
			(xy 154.917546 -53.227807) (xy 154.932899 -53.175516) (xy 154.955538 -53.125942) (xy 154.985 -53.080095)
			(xy 155.020688 -53.038906) (xy 155.061874 -53.003216) (xy 155.107719 -52.97375) (xy 155.157292 -52.951108)
			(xy 155.209582 -52.935751) (xy 155.263525 -52.927992) (xy 155.290774 -52.927504) (xy 155.317377 -52.927971)
			(xy 155.37007 -52.935349) (xy 155.421225 -52.94998) (xy 155.46985 -52.97158) (xy 155.515001 -52.999728)
			(xy 155.5558 -53.03388) (xy 155.591457 -53.073371) (xy 155.60675 -53.095144) (xy 155.615084 -53.106624)
			(xy 155.636828 -53.124828) (xy 155.662741 -53.136346) (xy 155.690824 -53.140286) (xy 155.718907 -53.136346)
			(xy 155.74482 -53.124828) (xy 155.766564 -53.106624) (xy 155.774898 -53.095144) (xy 155.790183 -53.073367)
			(xy 155.825851 -53.033888) (xy 155.866656 -52.999745) (xy 155.911808 -52.9716) (xy 155.960431 -52.949999)
			(xy 156.011582 -52.93536) (xy 156.064271 -52.927967) (xy 156.090874 -52.927504) (xy 156.118129 -52.927941)
			(xy 156.172084 -52.935695) (xy 156.224387 -52.95105) (xy 156.273972 -52.973691) (xy 156.31983 -53.00316)
			(xy 156.361027 -53.038854) (xy 156.396725 -53.080049) (xy 156.426196 -53.125905) (xy 156.448841 -53.175488)
			(xy 156.464199 -53.22779) (xy 156.471957 -53.281745) (xy 156.471957 -53.336255) (xy 156.464199 -53.39021)
			(xy 156.448841 -53.442512) (xy 156.426196 -53.492095) (xy 156.396725 -53.537951) (xy 156.361027 -53.579146)
			(xy 156.31983 -53.61484) (xy 156.273972 -53.644309) (xy 156.224387 -53.66695) (xy 156.172084 -53.682305)
			(xy 156.118129 -53.690059) (xy 156.090874 -53.69052) (xy 156.06427 -53.690082) (xy 156.011577 -53.682697)
			(xy 155.960421 -53.66806) (xy 155.911796 -53.646456) (xy 155.866646 -53.618303) (xy 155.825847 -53.584148)
			(xy 155.790191 -53.544654) (xy 155.774898 -53.52288) (xy 155.766564 -53.5114) (xy 155.74482 -53.493196)
			(xy 155.718907 -53.481678) (xy 155.690824 -53.477738) (xy 155.662741 -53.481678) (xy 155.636828 -53.493196)
			(xy 155.615084 -53.5114) (xy 155.60675 -53.52288) (xy 155.591442 -53.54464) (xy 155.555777 -53.584119)
			(xy 155.514975 -53.618262) (xy 155.469828 -53.646408) (xy 155.421209 -53.668012) (xy 155.370061 -53.682656)
			(xy 155.317375 -53.690054) (xy 155.290774 -53.69052) (xy 155.263525 -53.690008) (xy 155.209582 -53.682249)
			(xy 155.157292 -53.666892) (xy 155.107719 -53.64425) (xy 155.061874 -53.614784) (xy 155.020688 -53.579094)
			(xy 154.985 -53.537905) (xy 154.955538 -53.492058) (xy 154.932899 -53.442484) (xy 154.917546 -53.390193)
			(xy 154.90979 -53.336249) (xy 147.556028 -53.336249) (xy 147.561053 -53.35295) (xy 147.569173 -53.408126)
			(xy 147.569682 -53.436012) (xy 147.569173 -53.463898) (xy 147.561053 -53.519074) (xy 147.544985 -53.572481)
			(xy 147.521313 -53.622978) (xy 147.49054 -53.669491) (xy 147.453323 -53.711028) (xy 147.410455 -53.746703)
			(xy 147.362849 -53.775757) (xy 147.31152 -53.797569) (xy 147.257563 -53.811675) (xy 147.202126 -53.817775)
			(xy 147.146392 -53.815738) (xy 147.091549 -53.805608) (xy 147.038765 -53.787601) (xy 146.989165 -53.7621)
			(xy 146.943807 -53.729649) (xy 146.903658 -53.69094) (xy 146.869572 -53.646797) (xy 146.842276 -53.598162)
			(xy 146.822353 -53.546071) (xy 146.810227 -53.491634) (xy 146.806156 -53.436012) (xy 141.870684 -53.436012)
			(xy 143.26743 -54.832758) (xy 147.11883 -54.832758) (xy 147.122901 -54.777136) (xy 147.135027 -54.722699)
			(xy 147.15495 -54.670608) (xy 147.182246 -54.621973) (xy 147.216332 -54.57783) (xy 147.256481 -54.539121)
			(xy 147.301839 -54.50667) (xy 147.351439 -54.481169) (xy 147.404223 -54.463162) (xy 147.459066 -54.453032)
			(xy 147.5148 -54.450995) (xy 147.570237 -54.457095) (xy 147.624194 -54.471201) (xy 147.675523 -54.493013)
			(xy 147.723129 -54.522067) (xy 147.765997 -54.557742) (xy 147.803214 -54.599279) (xy 147.833987 -54.645792)
			(xy 147.857659 -54.696289) (xy 147.873727 -54.749696) (xy 147.881847 -54.804872) (xy 147.882356 -54.832758)
			(xy 147.881847 -54.860644) (xy 147.873727 -54.91582) (xy 147.857659 -54.969227) (xy 147.838004 -55.011155)
			(xy 159.316343 -55.011155) (xy 159.316343 -54.956645) (xy 159.324101 -54.902691) (xy 159.339458 -54.85039)
			(xy 159.362103 -54.800807) (xy 159.391574 -54.754951) (xy 159.427271 -54.713757) (xy 159.468467 -54.678062)
			(xy 159.514324 -54.648593) (xy 159.563909 -54.625951) (xy 159.61621 -54.610596) (xy 159.670165 -54.602842)
			(xy 159.69742 -54.60238) (xy 159.726336 -54.602926) (xy 159.783508 -54.611645) (xy 159.838707 -54.628895)
			(xy 159.89067 -54.654282) (xy 159.938204 -54.687222) (xy 159.98022 -54.726961) (xy 159.99841 -54.749446)
			(xy 160.008307 -54.761251) (xy 160.033631 -54.77877) (xy 160.063024 -54.787946) (xy 160.093816 -54.787946)
			(xy 160.123209 -54.77877) (xy 160.148533 -54.761251) (xy 160.15843 -54.749446) (xy 160.17659 -54.726937)
			(xy 160.218618 -54.687206) (xy 160.26616 -54.654271) (xy 160.318127 -54.628888) (xy 160.373329 -54.611637)
			(xy 160.430502 -54.602913) (xy 160.45942 -54.60238) (xy 160.486669 -54.602892) (xy 160.540613 -54.61065)
			(xy 160.592904 -54.626007) (xy 160.642477 -54.648648) (xy 160.688323 -54.678114) (xy 160.72951 -54.713804)
			(xy 160.765198 -54.754993) (xy 160.794662 -54.800841) (xy 160.8173 -54.850415) (xy 160.832654 -54.902706)
			(xy 160.84041 -54.956651) (xy 160.84041 -55.011149) (xy 160.832654 -55.065094) (xy 160.8173 -55.117385)
			(xy 160.794662 -55.166959) (xy 160.765198 -55.212807) (xy 160.72951 -55.253996) (xy 160.688323 -55.289686)
			(xy 160.642477 -55.319152) (xy 160.592904 -55.341793) (xy 160.540613 -55.35715) (xy 160.486669 -55.364908)
			(xy 160.45942 -55.365396) (xy 160.430504 -55.364865) (xy 160.373333 -55.356139) (xy 160.318134 -55.338883)
			(xy 160.266173 -55.313494) (xy 160.218638 -55.280553) (xy 160.176621 -55.240814) (xy 160.15843 -55.21833)
			(xy 160.148533 -55.206525) (xy 160.123209 -55.189006) (xy 160.093816 -55.17983) (xy 160.063024 -55.17983)
			(xy 160.033631 -55.189006) (xy 160.008307 -55.206525) (xy 159.99841 -55.21833) (xy 159.980221 -55.240815)
			(xy 159.9382 -55.280549) (xy 159.890664 -55.313487) (xy 159.838703 -55.338874) (xy 159.783505 -55.356131)
			(xy 159.726336 -55.36486) (xy 159.69742 -55.365396) (xy 159.670165 -55.364958) (xy 159.61621 -55.357204)
			(xy 159.563909 -55.341849) (xy 159.514324 -55.319207) (xy 159.468467 -55.289738) (xy 159.427271 -55.254043)
			(xy 159.391574 -55.212849) (xy 159.362103 -55.166993) (xy 159.339458 -55.11741) (xy 159.324101 -55.065109)
			(xy 159.316343 -55.011155) (xy 147.838004 -55.011155) (xy 147.833987 -55.019724) (xy 147.803214 -55.066237)
			(xy 147.765997 -55.107774) (xy 147.723129 -55.143449) (xy 147.675523 -55.172503) (xy 147.624194 -55.194315)
			(xy 147.570237 -55.208421) (xy 147.5148 -55.214521) (xy 147.459066 -55.212484) (xy 147.404223 -55.202354)
			(xy 147.351439 -55.184347) (xy 147.301839 -55.158846) (xy 147.256481 -55.126395) (xy 147.216332 -55.087686)
			(xy 147.182246 -55.043543) (xy 147.15495 -54.994908) (xy 147.135027 -54.942817) (xy 147.122901 -54.88838)
			(xy 147.11883 -54.832758) (xy 143.26743 -54.832758) (xy 143.764 -55.329328) (xy 143.77404 -55.338735)
			(xy 143.797971 -55.35229) (xy 143.824654 -55.358956) (xy 143.852148 -55.358248) (xy 143.878452 -55.350218)
			(xy 143.901653 -55.335449) (xy 143.920064 -55.315018) (xy 143.932344 -55.290409) (xy 143.93545 -55.277004)
			(xy 143.94095 -55.25131) (xy 143.95807 -55.201634) (xy 143.981846 -55.154777) (xy 144.01183 -55.111627)
			(xy 144.047452 -55.073002) (xy 144.088039 -55.039632) (xy 144.132823 -55.012149) (xy 144.180955 -54.991073)
			(xy 144.231524 -54.976804) (xy 144.283574 -54.969612) (xy 144.309846 -54.969156) (xy 144.337098 -54.969645)
			(xy 144.391046 -54.977408) (xy 144.44334 -54.992768) (xy 144.492916 -55.015414) (xy 144.538765 -55.044884)
			(xy 144.579953 -55.080579) (xy 144.615643 -55.121772) (xy 144.645108 -55.167625) (xy 144.667748 -55.217203)
			(xy 144.683102 -55.269499) (xy 144.690858 -55.323448) (xy 144.690858 -55.377952) (xy 144.683102 -55.4319)
			(xy 144.667748 -55.484197) (xy 144.653797 -55.514748) (xy 146.544792 -55.514748) (xy 146.545278 -55.487497)
			(xy 146.553034 -55.433549) (xy 146.568389 -55.381254) (xy 146.591031 -55.331677) (xy 146.620497 -55.285827)
			(xy 146.656188 -55.244636) (xy 146.697379 -55.208945) (xy 146.743229 -55.179479) (xy 146.792806 -55.156837)
			(xy 146.845101 -55.141482) (xy 146.899049 -55.133726) (xy 146.953551 -55.133726) (xy 147.007499 -55.141482)
			(xy 147.059794 -55.156837) (xy 147.109371 -55.179479) (xy 147.155221 -55.208945) (xy 147.196412 -55.244636)
			(xy 147.232103 -55.285827) (xy 147.261569 -55.331677) (xy 147.284211 -55.381254) (xy 147.299566 -55.433549)
			(xy 147.307322 -55.487497) (xy 147.307808 -55.514748) (xy 147.307279 -55.543108) (xy 147.298865 -55.5992)
			(xy 147.282232 -55.653425) (xy 147.257744 -55.704587) (xy 147.242276 -55.728362) (xy 147.234399 -55.740895)
			(xy 147.225489 -55.769108) (xy 147.225419 -55.773828) (xy 149.810722 -55.773828) (xy 149.814793 -55.718206)
			(xy 149.826919 -55.663769) (xy 149.846842 -55.611678) (xy 149.874138 -55.563043) (xy 149.908224 -55.5189)
			(xy 149.948373 -55.480191) (xy 149.993731 -55.44774) (xy 150.043331 -55.422239) (xy 150.096115 -55.404232)
			(xy 150.150958 -55.394102) (xy 150.206692 -55.392065) (xy 150.262129 -55.398165) (xy 150.316086 -55.412271)
			(xy 150.367415 -55.434083) (xy 150.415021 -55.463137) (xy 150.457889 -55.498812) (xy 150.495106 -55.540349)
			(xy 150.525879 -55.586862) (xy 150.549551 -55.637359) (xy 150.565619 -55.690766) (xy 150.573739 -55.745942)
			(xy 150.574248 -55.773828) (xy 150.573739 -55.801714) (xy 150.565619 -55.85689) (xy 150.549551 -55.910297)
			(xy 150.525879 -55.960794) (xy 150.495106 -56.007307) (xy 150.477322 -56.027155) (xy 159.316343 -56.027155)
			(xy 159.316343 -55.972645) (xy 159.324101 -55.918691) (xy 159.339458 -55.86639) (xy 159.362103 -55.816807)
			(xy 159.391574 -55.770951) (xy 159.427271 -55.729757) (xy 159.468467 -55.694062) (xy 159.514324 -55.664593)
			(xy 159.563909 -55.641951) (xy 159.61621 -55.626596) (xy 159.670165 -55.618842) (xy 159.69742 -55.61838)
			(xy 159.726336 -55.618926) (xy 159.783508 -55.627645) (xy 159.838707 -55.644895) (xy 159.89067 -55.670282)
			(xy 159.938204 -55.703222) (xy 159.98022 -55.742961) (xy 159.99841 -55.765446) (xy 160.008307 -55.777251)
			(xy 160.033631 -55.79477) (xy 160.063024 -55.803946) (xy 160.093816 -55.803946) (xy 160.123209 -55.79477)
			(xy 160.148533 -55.777251) (xy 160.15843 -55.765446) (xy 160.17659 -55.742937) (xy 160.218618 -55.703206)
			(xy 160.26616 -55.670271) (xy 160.318127 -55.644888) (xy 160.373329 -55.627637) (xy 160.430502 -55.618913)
			(xy 160.45942 -55.61838) (xy 160.486669 -55.618892) (xy 160.540613 -55.62665) (xy 160.592904 -55.642007)
			(xy 160.642477 -55.664648) (xy 160.688323 -55.694114) (xy 160.72951 -55.729804) (xy 160.765198 -55.770993)
			(xy 160.794662 -55.816841) (xy 160.8173 -55.866415) (xy 160.832654 -55.918706) (xy 160.84041 -55.972651)
			(xy 160.84041 -56.027149) (xy 160.832654 -56.081094) (xy 160.8173 -56.133385) (xy 160.794662 -56.182959)
			(xy 160.765198 -56.228807) (xy 160.72951 -56.269996) (xy 160.688323 -56.305686) (xy 160.642477 -56.335152)
			(xy 160.592904 -56.357793) (xy 160.540613 -56.37315) (xy 160.486669 -56.380908) (xy 160.45942 -56.381396)
			(xy 160.430504 -56.380865) (xy 160.373333 -56.372139) (xy 160.318134 -56.354883) (xy 160.266173 -56.329494)
			(xy 160.218638 -56.296553) (xy 160.176621 -56.256814) (xy 160.15843 -56.23433) (xy 160.148533 -56.222525)
			(xy 160.123209 -56.205006) (xy 160.093816 -56.19583) (xy 160.063024 -56.19583) (xy 160.033631 -56.205006)
			(xy 160.008307 -56.222525) (xy 159.99841 -56.23433) (xy 159.980221 -56.256815) (xy 159.9382 -56.296549)
			(xy 159.890664 -56.329487) (xy 159.838703 -56.354874) (xy 159.783505 -56.372131) (xy 159.726336 -56.38086)
			(xy 159.69742 -56.381396) (xy 159.670165 -56.380958) (xy 159.61621 -56.373204) (xy 159.563909 -56.357849)
			(xy 159.514324 -56.335207) (xy 159.468467 -56.305738) (xy 159.427271 -56.270043) (xy 159.391574 -56.228849)
			(xy 159.362103 -56.182993) (xy 159.339458 -56.13341) (xy 159.324101 -56.081109) (xy 159.316343 -56.027155)
			(xy 150.477322 -56.027155) (xy 150.457889 -56.048844) (xy 150.415021 -56.084519) (xy 150.367415 -56.113573)
			(xy 150.316086 -56.135385) (xy 150.262129 -56.149491) (xy 150.206692 -56.155591) (xy 150.150958 -56.153554)
			(xy 150.096115 -56.143424) (xy 150.043331 -56.125417) (xy 149.993731 -56.099916) (xy 149.948373 -56.067465)
			(xy 149.908224 -56.028756) (xy 149.874138 -55.984613) (xy 149.846842 -55.935978) (xy 149.826919 -55.883887)
			(xy 149.814793 -55.82945) (xy 149.810722 -55.773828) (xy 147.225419 -55.773828) (xy 147.225049 -55.798692)
			(xy 147.233117 -55.827158) (xy 147.249014 -55.852112) (xy 147.271402 -55.871454) (xy 147.284694 -55.877968)
			(xy 147.30948 -55.889639) (xy 147.355712 -55.919031) (xy 147.397267 -55.954732) (xy 147.43329 -55.996007)
			(xy 147.46304 -56.04201) (xy 147.485907 -56.091794) (xy 147.501421 -56.144336) (xy 147.509262 -56.198556)
			(xy 147.509738 -56.225948) (xy 147.509252 -56.253199) (xy 147.501496 -56.307147) (xy 147.486141 -56.359442)
			(xy 147.463499 -56.409019) (xy 147.434033 -56.454869) (xy 147.398342 -56.49606) (xy 147.357151 -56.531751)
			(xy 147.311301 -56.561217) (xy 147.261724 -56.583859) (xy 147.209429 -56.599214) (xy 147.155481 -56.60697)
			(xy 147.100979 -56.60697) (xy 147.047031 -56.599214) (xy 146.994736 -56.583859) (xy 146.945159 -56.561217)
			(xy 146.899309 -56.531751) (xy 146.858118 -56.49606) (xy 146.822427 -56.454869) (xy 146.792961 -56.409019)
			(xy 146.770319 -56.359442) (xy 146.754964 -56.307147) (xy 146.747208 -56.253199) (xy 146.746722 -56.225948)
			(xy 146.747244 -56.197588) (xy 146.755659 -56.141496) (xy 146.772295 -56.08727) (xy 146.796784 -56.036109)
			(xy 146.812254 -56.012334) (xy 146.820123 -55.999797) (xy 146.829028 -55.971585) (xy 146.829466 -55.942005)
			(xy 146.8214 -55.913542) (xy 146.805508 -55.888589) (xy 146.783125 -55.869244) (xy 146.769836 -55.862728)
			(xy 146.745055 -55.851046) (xy 146.698822 -55.821657) (xy 146.657266 -55.785959) (xy 146.621242 -55.744685)
			(xy 146.59149 -55.698684) (xy 146.568623 -55.648901) (xy 146.553109 -55.59636) (xy 146.545268 -55.54214)
			(xy 146.544792 -55.514748) (xy 144.653797 -55.514748) (xy 144.645108 -55.533775) (xy 144.615643 -55.579628)
			(xy 144.579953 -55.620821) (xy 144.538765 -55.656516) (xy 144.492916 -55.685986) (xy 144.44334 -55.708632)
			(xy 144.391046 -55.723992) (xy 144.337098 -55.731755) (xy 144.309846 -55.732172) (xy 144.291304 -55.731664)
			(xy 144.268952 -55.730648) (xy 144.217136 -55.782464) (xy 144.28851 -55.853838) (xy 144.301718 -55.857394)
			(xy 144.329227 -55.865263) (xy 144.381686 -55.888105) (xy 144.430144 -55.918526) (xy 144.473514 -55.955845)
			(xy 144.510823 -55.999223) (xy 144.541234 -56.047688) (xy 144.564064 -56.100152) (xy 144.571974 -56.12765)
			(xy 144.57553 -56.140858) (xy 145.95348 -57.518808) (xy 146.460972 -57.518808) (xy 146.475069 -57.518315)
			(xy 146.50217 -57.510533) (xy 146.52611 -57.495636) (xy 146.545064 -57.474762) (xy 146.557589 -57.4495)
			(xy 146.562728 -57.421776) (xy 146.560091 -57.393703) (xy 146.55546 -57.380378) (xy 146.547239 -57.358237)
			(xy 146.535701 -57.312437) (xy 146.529904 -57.265564) (xy 146.529552 -57.241948) (xy 146.530038 -57.214697)
			(xy 146.537794 -57.160749) (xy 146.553149 -57.108454) (xy 146.575791 -57.058877) (xy 146.605257 -57.013027)
			(xy 146.640948 -56.971836) (xy 146.682139 -56.936145) (xy 146.727989 -56.906679) (xy 146.777566 -56.884037)
			(xy 146.829861 -56.868682) (xy 146.883809 -56.860926) (xy 146.938311 -56.860926) (xy 146.992259 -56.868682)
			(xy 147.044554 -56.884037) (xy 147.094131 -56.906679) (xy 147.139981 -56.936145) (xy 147.181172 -56.971836)
			(xy 147.216863 -57.013027) (xy 147.246329 -57.058877) (xy 147.268971 -57.108454) (xy 147.284326 -57.160749)
			(xy 147.292082 -57.214697) (xy 147.292568 -57.241948) (xy 147.292229 -57.265564) (xy 147.286428 -57.312438)
			(xy 147.274882 -57.358237) (xy 147.26666 -57.380378) (xy 147.261972 -57.393686) (xy 147.259329 -57.421765)
			(xy 147.264471 -57.449496) (xy 147.277005 -57.474761) (xy 147.295975 -57.495632) (xy 147.319932 -57.510514)
			(xy 147.347047 -57.518273) (xy 147.361148 -57.518808) (xy 159.85998 -57.518808) (xy 159.993076 -57.385712)
			(xy 159.928814 -57.321704) (xy 159.894778 -57.342278) (xy 159.872361 -57.355343) (xy 159.824743 -57.375952)
			(xy 159.774769 -57.389908) (xy 159.723363 -57.396952) (xy 159.69742 -57.397396) (xy 159.670167 -57.396934)
			(xy 159.616216 -57.38918) (xy 159.563917 -57.373826) (xy 159.514336 -57.351185) (xy 159.468482 -57.321719)
			(xy 159.427288 -57.286026) (xy 159.391593 -57.244834) (xy 159.362124 -57.198982) (xy 159.339481 -57.149402)
			(xy 159.324125 -57.097104) (xy 159.316367 -57.043153) (xy 159.316367 -56.988647) (xy 159.324125 -56.934696)
			(xy 159.339481 -56.882398) (xy 159.362124 -56.832818) (xy 159.391593 -56.786966) (xy 159.427288 -56.745774)
			(xy 159.468482 -56.710081) (xy 159.514336 -56.680615) (xy 159.563917 -56.657974) (xy 159.616216 -56.64262)
			(xy 159.670167 -56.634866) (xy 159.69742 -56.63438) (xy 159.726336 -56.634916) (xy 159.783506 -56.643645)
			(xy 159.838704 -56.6609) (xy 159.890667 -56.686287) (xy 159.938204 -56.719224) (xy 159.980227 -56.758956)
			(xy 159.99841 -56.781446) (xy 160.008307 -56.793251) (xy 160.033631 -56.81077) (xy 160.063024 -56.819946)
			(xy 160.093816 -56.819946) (xy 160.123209 -56.81077) (xy 160.148533 -56.793251) (xy 160.15843 -56.781446)
			(xy 160.176618 -56.758958) (xy 160.218633 -56.719212) (xy 160.266166 -56.686264) (xy 160.318128 -56.660869)
			(xy 160.373329 -56.64361) (xy 160.430502 -56.634882) (xy 160.45942 -56.63438) (xy 160.483598 -56.634751)
			(xy 160.531567 -56.640864) (xy 160.578375 -56.653002) (xy 160.623269 -56.670969) (xy 160.644586 -56.682386)
			(xy 160.67786 -56.700928) (xy 163.41344 -53.965348) (xy 167.256968 -53.965348) (xy 167.271746 -53.964851)
			(xy 167.300066 -53.956396) (xy 167.324779 -53.940185) (xy 167.343815 -53.917576) (xy 167.355579 -53.890463)
			(xy 167.359086 -53.861116) (xy 167.354042 -53.831994) (xy 167.34087 -53.805536) (xy 167.331136 -53.794406)
			(xy 167.311862 -53.77308) (xy 167.27929 -53.72572) (xy 167.254191 -53.674008) (xy 167.237133 -53.619117)
			(xy 167.228503 -53.562288) (xy 167.228012 -53.533548) (xy 167.228487 -53.506179) (xy 167.236318 -53.452005)
			(xy 167.251811 -53.399506) (xy 167.274649 -53.34976) (xy 167.304362 -53.303789) (xy 167.321992 -53.28285)
			(xy 167.331236 -53.271523) (xy 167.343428 -53.244961) (xy 167.347612 -53.216036) (xy 167.343448 -53.187109)
			(xy 167.331276 -53.160538) (xy 167.321992 -53.149246) (xy 167.304349 -53.128312) (xy 167.27462 -53.082343)
			(xy 167.251771 -53.032595) (xy 167.23627 -52.98009) (xy 167.228436 -52.925909) (xy 167.228431 -52.871164)
			(xy 167.236254 -52.816981) (xy 167.251745 -52.764473) (xy 167.274586 -52.714721) (xy 167.304306 -52.668745)
			(xy 167.321992 -52.64785) (xy 167.331236 -52.636523) (xy 167.343428 -52.609961) (xy 167.347612 -52.581036)
			(xy 167.343448 -52.552109) (xy 167.331276 -52.525538) (xy 167.321992 -52.514246) (xy 167.304353 -52.493314)
			(xy 167.274634 -52.447346) (xy 167.251799 -52.397598) (xy 167.236316 -52.345095) (xy 167.228506 -52.290917)
			(xy 167.228012 -52.263548) (xy 167.228472 -52.236293) (xy 167.236224 -52.182338) (xy 167.251576 -52.130036)
			(xy 167.274216 -52.080451) (xy 167.303683 -52.034593) (xy 167.339377 -51.993397) (xy 167.380571 -51.9577)
			(xy 167.426426 -51.928229) (xy 167.47601 -51.905585) (xy 167.528311 -51.89023) (xy 167.582265 -51.882474)
			(xy 167.60952 -51.88204) (xy 167.637808 -51.882555) (xy 167.693762 -51.890914) (xy 167.747868 -51.907446)
			(xy 167.798939 -51.931787) (xy 167.845854 -51.963405) (xy 167.867076 -51.982116) (xy 167.878422 -51.991793)
			(xy 167.905281 -52.004713) (xy 167.934726 -52.009339) (xy 167.964253 -52.005275) (xy 167.991354 -51.992869)
			(xy 168.013725 -51.973174) (xy 168.022016 -51.96078) (xy 168.037034 -51.937525) (xy 168.072719 -51.895205)
			(xy 168.114143 -51.858484) (xy 168.160437 -51.828132) (xy 168.21063 -51.804786) (xy 168.263669 -51.788935)
			(xy 168.318442 -51.780913) (xy 168.34612 -51.78044) (xy 168.373371 -51.780905) (xy 168.427317 -51.788664)
			(xy 168.47961 -51.804023) (xy 168.529184 -51.826667) (xy 168.575031 -51.856136) (xy 168.616218 -51.89183)
			(xy 168.651905 -51.933023) (xy 168.681366 -51.978876) (xy 168.704001 -52.028454) (xy 168.71935 -52.08075)
			(xy 168.7271 -52.134697) (xy 168.727628 -52.161948) (xy 168.727153 -52.189316) (xy 168.719322 -52.24349)
			(xy 168.703827 -52.295988) (xy 168.680987 -52.345732) (xy 168.651271 -52.391701) (xy 168.633648 -52.412646)
			(xy 168.624422 -52.423975) (xy 168.612264 -52.450529) (xy 168.608105 -52.479436) (xy 168.612285 -52.508341)
			(xy 168.624462 -52.534886) (xy 168.633648 -52.54625) (xy 168.651286 -52.567182) (xy 168.681006 -52.613148)
			(xy 168.703846 -52.662893) (xy 168.719338 -52.715392) (xy 168.727161 -52.769567) (xy 168.727156 -52.824305)
			(xy 168.719322 -52.878479) (xy 168.703821 -52.930975) (xy 168.680971 -52.980715) (xy 168.651243 -53.026676)
			(xy 168.633648 -53.047646) (xy 168.624422 -53.058975) (xy 168.612264 -53.085529) (xy 168.608105 -53.114436)
			(xy 168.612285 -53.143341) (xy 168.624462 -53.169886) (xy 168.633648 -53.18125) (xy 168.651289 -53.202181)
			(xy 168.681013 -53.248148) (xy 168.703853 -53.297895) (xy 168.719339 -53.350399) (xy 168.727151 -53.404578)
			(xy 168.727628 -53.431948) (xy 168.727139 -53.459198) (xy 168.719377 -53.513141) (xy 168.704018 -53.565431)
			(xy 168.681374 -53.615004) (xy 168.651907 -53.66085) (xy 168.616216 -53.702036) (xy 168.575027 -53.737724)
			(xy 168.529179 -53.767188) (xy 168.479605 -53.789828) (xy 168.427314 -53.805183) (xy 168.37337 -53.812941)
			(xy 168.34612 -53.813456) (xy 168.317831 -53.812944) (xy 168.261874 -53.80459) (xy 168.207765 -53.788063)
			(xy 168.15669 -53.763724) (xy 168.109771 -53.732109) (xy 168.088564 -53.71338) (xy 168.07722 -53.703713)
			(xy 168.050367 -53.69081) (xy 168.020935 -53.686198) (xy 167.991423 -53.690271) (xy 167.964339 -53.702681)
			(xy 167.941984 -53.722373) (xy 167.933624 -53.734716) (xy 167.923517 -53.750608) (xy 167.900618 -53.780512)
			(xy 167.887904 -53.794406) (xy 167.878176 -53.805541) (xy 167.865011 -53.832002) (xy 167.859971 -53.861125)
			(xy 167.863479 -53.890471) (xy 167.87524 -53.917585) (xy 167.894271 -53.940198) (xy 167.918978 -53.956417)
			(xy 167.947295 -53.964885) (xy 167.962072 -53.965348) (xy 170.572176 -53.965348) (xy 170.586456 -53.964882)
			(xy 170.613904 -53.956996) (xy 170.638088 -53.941808) (xy 170.657113 -53.920509) (xy 170.669485 -53.89477)
			(xy 170.674234 -53.866609) (xy 170.670987 -53.838236) (xy 170.665902 -53.824886) (xy 170.656655 -53.801572)
			(xy 170.643654 -53.753131) (xy 170.637095 -53.703406) (xy 170.636692 -53.678328) (xy 170.637178 -53.651077)
			(xy 170.644934 -53.597129) (xy 170.660289 -53.544834) (xy 170.682931 -53.495257) (xy 170.712397 -53.449407)
			(xy 170.748088 -53.408216) (xy 170.789279 -53.372525) (xy 170.835129 -53.343059) (xy 170.884706 -53.320417)
			(xy 170.937001 -53.305062) (xy 170.990949 -53.297306) (xy 171.045451 -53.297306) (xy 171.099399 -53.305062)
			(xy 171.151694 -53.320417) (xy 171.201271 -53.343059) (xy 171.247121 -53.372525) (xy 171.288312 -53.408216)
			(xy 171.324003 -53.449407) (xy 171.353469 -53.495257) (xy 171.376111 -53.544834) (xy 171.391466 -53.597129)
			(xy 171.399222 -53.651077) (xy 171.399708 -53.678328) (xy 171.399332 -53.703408) (xy 171.39279 -53.753139)
			(xy 171.379771 -53.80158) (xy 171.370498 -53.824886) (xy 171.365493 -53.838246) (xy 171.362311 -53.866586)
			(xy 171.367089 -53.894701) (xy 171.379454 -53.920398) (xy 171.398442 -53.941675) (xy 171.422574 -53.956872)
			(xy 171.449966 -53.964805) (xy 171.464224 -53.965348) (xy 178.105308 -53.965348) (xy 178.11623 -53.95976)
			(xy 178.143165 -53.946681) (xy 178.200121 -53.92822) (xy 178.259266 -53.918906) (xy 178.289204 -53.918358)
			(xy 178.319137 -53.918946) (xy 178.37827 -53.928288) (xy 178.435225 -53.946727) (xy 178.462178 -53.95976)
			(xy 178.4731 -53.965348) (xy 181.074822 -53.965348) (xy 181.089434 -53.940465) (xy 181.124985 -53.895016)
			(xy 181.166976 -53.855441) (xy 181.21445 -53.822643) (xy 181.266323 -53.797371) (xy 181.321411 -53.780201)
			(xy 181.378457 -53.771525) (xy 181.407308 -53.771038) (xy 181.437611 -53.771625) (xy 181.497457 -53.7812)
			(xy 181.526434 -53.790088) (xy 181.539616 -53.793954) (xy 181.567045 -53.795276) (xy 181.593833 -53.789237)
			(xy 181.618042 -53.776275) (xy 181.637918 -53.757328) (xy 181.652024 -53.733767) (xy 181.659337 -53.707298)
			(xy 181.659784 -53.693568) (xy 181.659784 -53.3527) (xy 181.659334 -53.338973) (xy 181.652016 -53.312511)
			(xy 181.637909 -53.288958) (xy 181.618034 -53.270017) (xy 181.593829 -53.257059) (xy 181.567046 -53.251023)
			(xy 181.539623 -53.252343) (xy 181.526434 -53.25618) (xy 181.497463 -53.265091) (xy 181.437613 -53.274666)
			(xy 181.407308 -53.27523) (xy 181.380053 -53.274768) (xy 181.326098 -53.267011) (xy 181.273796 -53.251655)
			(xy 181.224212 -53.229012) (xy 181.178355 -53.199542) (xy 181.137159 -53.163846) (xy 181.101463 -53.122651)
			(xy 181.071992 -53.076795) (xy 181.049348 -53.027211) (xy 181.033991 -52.97491) (xy 181.026233 -52.920955)
			(xy 181.026233 -52.866445) (xy 181.033991 -52.81249) (xy 181.049348 -52.760189) (xy 181.071992 -52.710605)
			(xy 181.101463 -52.664749) (xy 181.137159 -52.623554) (xy 181.178355 -52.587858) (xy 181.224212 -52.558388)
			(xy 181.273796 -52.535745) (xy 181.326098 -52.520389) (xy 181.380053 -52.512632) (xy 181.407308 -52.512214)
			(xy 181.436195 -52.512747) (xy 181.49331 -52.521457) (xy 181.548459 -52.538679) (xy 181.600381 -52.564017)
			(xy 181.64789 -52.596894) (xy 181.689899 -52.636556) (xy 181.72545 -52.682099) (xy 181.740048 -52.707032)
			(xy 181.748052 -52.720249) (xy 181.770483 -52.741479) (xy 181.798233 -52.755036) (xy 181.828766 -52.759684)
			(xy 181.859293 -52.754997) (xy 181.873398 -52.748688) (xy 181.899659 -52.73638) (xy 181.954978 -52.71897)
			(xy 182.012296 -52.71014) (xy 182.041292 -52.709572) (xy 182.070287 -52.710154) (xy 182.127599 -52.719)
			(xy 182.182917 -52.736401) (xy 182.209186 -52.748688) (xy 182.223291 -52.755002) (xy 182.253822 -52.759694)
			(xy 182.284359 -52.755049) (xy 182.312114 -52.741492) (xy 182.334551 -52.720262) (xy 182.342536 -52.707032)
			(xy 182.357132 -52.682095) (xy 182.392673 -52.63654) (xy 182.434679 -52.596867) (xy 182.482188 -52.563983)
			(xy 182.534113 -52.538641) (xy 182.589266 -52.521422) (xy 182.646386 -52.512718) (xy 182.675276 -52.512214)
			(xy 182.702528 -52.512676) (xy 182.756479 -52.520429) (xy 182.808777 -52.535782) (xy 182.858357 -52.558422)
			(xy 182.90421 -52.587888) (xy 182.945403 -52.62358) (xy 182.981098 -52.66477) (xy 183.010566 -52.710622)
			(xy 183.033209 -52.760201) (xy 183.048565 -52.812498) (xy 183.056323 -52.866448) (xy 183.056323 -52.920952)
			(xy 183.048565 -52.974902) (xy 183.033209 -53.027199) (xy 183.010566 -53.076778) (xy 182.981098 -53.12263)
			(xy 182.945403 -53.16382) (xy 182.90421 -53.199512) (xy 182.858357 -53.228978) (xy 182.808777 -53.251618)
			(xy 182.756479 -53.266971) (xy 182.702528 -53.274724) (xy 182.675276 -53.27523) (xy 182.644972 -53.274649)
			(xy 182.585122 -53.265086) (xy 182.55615 -53.25618) (xy 182.542967 -53.252317) (xy 182.51554 -53.251)
			(xy 182.488753 -53.25704) (xy 182.464546 -53.270002) (xy 182.444669 -53.288947) (xy 182.430561 -53.312505)
			(xy 182.423242 -53.33897) (xy 182.4228 -53.3527) (xy 182.4228 -53.693568) (xy 182.423246 -53.7073)
			(xy 182.430559 -53.733771) (xy 182.444665 -53.757335) (xy 182.464542 -53.776285) (xy 182.488751 -53.78925)
			(xy 182.515542 -53.795292) (xy 182.542973 -53.793974) (xy 182.55615 -53.790088) (xy 182.585121 -53.781174)
			(xy 182.64497 -53.771595) (xy 182.675276 -53.771038) (xy 182.704121 -53.771572) (xy 182.761154 -53.780266)
			(xy 182.816228 -53.797445) (xy 182.868089 -53.822717) (xy 182.915556 -53.855507) (xy 182.957547 -53.895067)
			(xy 182.993106 -53.940496) (xy 183.007762 -53.965348) (xy 197.19798 -53.965348) (xy 198.40956 -52.753768)
			(xy 198.40956 -49.126648) (xy 200.8632 -46.673008) (xy 207.74406 -46.673008) (xy 208.089754 -47.018702)
			(xy 221.910908 -47.018702) (xy 221.914979 -46.96308) (xy 221.927105 -46.908643) (xy 221.947028 -46.856552)
			(xy 221.974324 -46.807917) (xy 222.00841 -46.763774) (xy 222.048559 -46.725065) (xy 222.093917 -46.692614)
			(xy 222.143517 -46.667113) (xy 222.196301 -46.649106) (xy 222.251144 -46.638976) (xy 222.306878 -46.636939)
			(xy 222.362315 -46.643039) (xy 222.416272 -46.657145) (xy 222.467601 -46.678957) (xy 222.515207 -46.708011)
			(xy 222.558075 -46.743686) (xy 222.595292 -46.785223) (xy 222.626065 -46.831736) (xy 222.649737 -46.882233)
			(xy 222.665805 -46.93564) (xy 222.673925 -46.990816) (xy 222.674434 -47.018702) (xy 222.673925 -47.046588)
			(xy 222.665805 -47.101764) (xy 222.649737 -47.155171) (xy 222.626065 -47.205668) (xy 222.595292 -47.252181)
			(xy 222.558075 -47.293718) (xy 222.515207 -47.329393) (xy 222.467601 -47.358447) (xy 222.416272 -47.380259)
			(xy 222.362315 -47.394365) (xy 222.306878 -47.400465) (xy 222.251144 -47.398428) (xy 222.196301 -47.388298)
			(xy 222.143517 -47.370291) (xy 222.093917 -47.34479) (xy 222.048559 -47.312339) (xy 222.00841 -47.27363)
			(xy 221.974324 -47.229487) (xy 221.947028 -47.180852) (xy 221.927105 -47.128761) (xy 221.914979 -47.074324)
			(xy 221.910908 -47.018702) (xy 208.089754 -47.018702) (xy 208.683098 -47.612046) (xy 222.685862 -47.612046)
			(xy 222.689933 -47.556424) (xy 222.702059 -47.501987) (xy 222.721982 -47.449896) (xy 222.749278 -47.401261)
			(xy 222.783364 -47.357118) (xy 222.823513 -47.318409) (xy 222.868871 -47.285958) (xy 222.918471 -47.260457)
			(xy 222.971255 -47.24245) (xy 223.026098 -47.23232) (xy 223.081832 -47.230283) (xy 223.137269 -47.236383)
			(xy 223.191226 -47.250489) (xy 223.242555 -47.272301) (xy 223.290161 -47.301355) (xy 223.333029 -47.33703)
			(xy 223.370246 -47.378567) (xy 223.401019 -47.42508) (xy 223.424691 -47.475577) (xy 223.440759 -47.528984)
			(xy 223.448879 -47.58416) (xy 223.449388 -47.612046) (xy 223.448879 -47.639932) (xy 223.440759 -47.695108)
			(xy 223.424691 -47.748515) (xy 223.401019 -47.799012) (xy 223.370246 -47.845525) (xy 223.333029 -47.887062)
			(xy 223.290161 -47.922737) (xy 223.242555 -47.951791) (xy 223.191226 -47.973603) (xy 223.137269 -47.987709)
			(xy 223.081832 -47.993809) (xy 223.026098 -47.991772) (xy 222.971255 -47.981642) (xy 222.918471 -47.963635)
			(xy 222.868871 -47.938134) (xy 222.823513 -47.905683) (xy 222.783364 -47.866974) (xy 222.749278 -47.822831)
			(xy 222.721982 -47.774196) (xy 222.702059 -47.722105) (xy 222.689933 -47.667668) (xy 222.685862 -47.612046)
			(xy 208.683098 -47.612046) (xy 209.853022 -48.78197) (xy 222.685862 -48.78197) (xy 222.689933 -48.726348)
			(xy 222.702059 -48.671911) (xy 222.721982 -48.61982) (xy 222.749278 -48.571185) (xy 222.783364 -48.527042)
			(xy 222.823513 -48.488333) (xy 222.868871 -48.455882) (xy 222.918471 -48.430381) (xy 222.971255 -48.412374)
			(xy 223.026098 -48.402244) (xy 223.081832 -48.400207) (xy 223.137269 -48.406307) (xy 223.191226 -48.420413)
			(xy 223.242555 -48.442225) (xy 223.290161 -48.471279) (xy 223.333029 -48.506954) (xy 223.370246 -48.548491)
			(xy 223.401019 -48.595004) (xy 223.424691 -48.645501) (xy 223.440759 -48.698908) (xy 223.448879 -48.754084)
			(xy 223.449388 -48.78197) (xy 223.448879 -48.809856) (xy 223.440759 -48.865032) (xy 223.424691 -48.918439)
			(xy 223.401019 -48.968936) (xy 223.370246 -49.015449) (xy 223.333029 -49.056986) (xy 223.290161 -49.092661)
			(xy 223.242555 -49.121715) (xy 223.191226 -49.143527) (xy 223.137269 -49.157633) (xy 223.081832 -49.163733)
			(xy 223.026098 -49.161696) (xy 222.971255 -49.151566) (xy 222.918471 -49.133559) (xy 222.868871 -49.108058)
			(xy 222.823513 -49.075607) (xy 222.783364 -49.036898) (xy 222.749278 -48.992755) (xy 222.721982 -48.94412)
			(xy 222.702059 -48.892029) (xy 222.689933 -48.837592) (xy 222.685862 -48.78197) (xy 209.853022 -48.78197)
			(xy 209.89798 -48.826928) (xy 209.89798 -49.97196) (xy 221.078552 -49.97196) (xy 221.079088 -49.944079)
			(xy 221.087211 -49.888912) (xy 221.103278 -49.835515) (xy 221.126948 -49.785025) (xy 221.157715 -49.73852)
			(xy 221.194924 -49.696988) (xy 221.237783 -49.661315) (xy 221.285378 -49.632262) (xy 221.336695 -49.610446)
			(xy 221.36354 -49.602898) (xy 221.377001 -49.598878) (xy 221.401177 -49.584592) (xy 221.420551 -49.564264)
			(xy 221.43366 -49.53943) (xy 221.439514 -49.511965) (xy 221.43767 -49.483944) (xy 221.43339 -49.470564)
			(xy 221.42308 -49.439569) (xy 221.411963 -49.375206) (xy 221.411292 -49.342548) (xy 221.411778 -49.315297)
			(xy 221.419534 -49.261349) (xy 221.434889 -49.209054) (xy 221.457531 -49.159477) (xy 221.486997 -49.113627)
			(xy 221.522688 -49.072436) (xy 221.563879 -49.036745) (xy 221.609729 -49.007279) (xy 221.659306 -48.984637)
			(xy 221.711601 -48.969282) (xy 221.765549 -48.961526) (xy 221.820051 -48.961526) (xy 221.873999 -48.969282)
			(xy 221.926294 -48.984637) (xy 221.975871 -49.007279) (xy 222.021721 -49.036745) (xy 222.062912 -49.072436)
			(xy 222.098603 -49.113627) (xy 222.128069 -49.159477) (xy 222.150711 -49.209054) (xy 222.166066 -49.261349)
			(xy 222.173822 -49.315297) (xy 222.174308 -49.342548) (xy 222.173809 -49.370431) (xy 222.165684 -49.425601)
			(xy 222.149613 -49.479) (xy 222.12594 -49.529491) (xy 222.095168 -49.575998) (xy 222.057954 -49.61753)
			(xy 222.01509 -49.653201) (xy 221.96749 -49.682252) (xy 221.916167 -49.704064) (xy 221.88932 -49.71161)
			(xy 221.87585 -49.715599) (xy 221.851675 -49.729895) (xy 221.832303 -49.75023) (xy 221.819197 -49.775069)
			(xy 221.813345 -49.802538) (xy 221.81519 -49.830562) (xy 221.81947 -49.843944) (xy 221.829784 -49.874938)
			(xy 221.840898 -49.939302) (xy 221.841109 -49.949608) (xy 222.622616 -49.949608) (xy 222.626687 -49.893986)
			(xy 222.638813 -49.839549) (xy 222.658736 -49.787458) (xy 222.686032 -49.738823) (xy 222.720118 -49.69468)
			(xy 222.760267 -49.655971) (xy 222.805625 -49.62352) (xy 222.855225 -49.598019) (xy 222.908009 -49.580012)
			(xy 222.962852 -49.569882) (xy 223.018586 -49.567845) (xy 223.074023 -49.573945) (xy 223.12798 -49.588051)
			(xy 223.179309 -49.609863) (xy 223.226915 -49.638917) (xy 223.269783 -49.674592) (xy 223.307 -49.716129)
			(xy 223.337773 -49.762642) (xy 223.361445 -49.813139) (xy 223.377513 -49.866546) (xy 223.385633 -49.921722)
			(xy 223.386142 -49.949608) (xy 223.385633 -49.977494) (xy 223.377513 -50.03267) (xy 223.361445 -50.086077)
			(xy 223.337773 -50.136574) (xy 223.307 -50.183087) (xy 223.269783 -50.224624) (xy 223.226915 -50.260299)
			(xy 223.179309 -50.289353) (xy 223.12798 -50.311165) (xy 223.074023 -50.325271) (xy 223.018586 -50.331371)
			(xy 222.962852 -50.329334) (xy 222.908009 -50.319204) (xy 222.855225 -50.301197) (xy 222.805625 -50.275696)
			(xy 222.760267 -50.243245) (xy 222.720118 -50.204536) (xy 222.686032 -50.160393) (xy 222.658736 -50.111758)
			(xy 222.638813 -50.059667) (xy 222.626687 -50.00523) (xy 222.622616 -49.949608) (xy 221.841109 -49.949608)
			(xy 221.841568 -49.97196) (xy 221.840968 -50.001721) (xy 221.831718 -50.060521) (xy 221.813451 -50.117172)
			(xy 221.786611 -50.170299) (xy 221.751848 -50.218616) (xy 221.731332 -50.240184) (xy 221.721981 -50.25033)
			(xy 221.708547 -50.274416) (xy 221.702042 -50.301216) (xy 221.702941 -50.32878) (xy 221.711177 -50.355101)
			(xy 221.72615 -50.37826) (xy 221.736158 -50.387758) (xy 221.75596 -50.405923) (xy 221.790752 -50.446874)
			(xy 221.81945 -50.492304) (xy 221.841487 -50.541312) (xy 221.856425 -50.592929) (xy 221.863969 -50.646132)
			(xy 221.864428 -50.673) (xy 221.863942 -50.700251) (xy 221.856186 -50.754199) (xy 221.840831 -50.806494)
			(xy 221.818189 -50.856071) (xy 221.788723 -50.901921) (xy 221.753032 -50.943112) (xy 221.711841 -50.978803)
			(xy 221.665991 -51.008269) (xy 221.656512 -51.012598) (xy 222.559878 -51.012598) (xy 222.563949 -50.956976)
			(xy 222.576075 -50.902539) (xy 222.595998 -50.850448) (xy 222.623294 -50.801813) (xy 222.65738 -50.75767)
			(xy 222.697529 -50.718961) (xy 222.742887 -50.68651) (xy 222.792487 -50.661009) (xy 222.845271 -50.643002)
			(xy 222.900114 -50.632872) (xy 222.955848 -50.630835) (xy 223.011285 -50.636935) (xy 223.065242 -50.651041)
			(xy 223.116571 -50.672853) (xy 223.164177 -50.701907) (xy 223.207045 -50.737582) (xy 223.244262 -50.779119)
			(xy 223.275035 -50.825632) (xy 223.298707 -50.876129) (xy 223.314775 -50.929536) (xy 223.322895 -50.984712)
			(xy 223.323404 -51.012598) (xy 223.322895 -51.040484) (xy 223.314775 -51.09566) (xy 223.298707 -51.149067)
			(xy 223.275035 -51.199564) (xy 223.244262 -51.246077) (xy 223.207045 -51.287614) (xy 223.164177 -51.323289)
			(xy 223.116571 -51.352343) (xy 223.065242 -51.374155) (xy 223.011285 -51.388261) (xy 222.955848 -51.394361)
			(xy 222.900114 -51.392324) (xy 222.845271 -51.382194) (xy 222.792487 -51.364187) (xy 222.742887 -51.338686)
			(xy 222.697529 -51.306235) (xy 222.65738 -51.267526) (xy 222.623294 -51.223383) (xy 222.595998 -51.174748)
			(xy 222.576075 -51.122657) (xy 222.563949 -51.06822) (xy 222.559878 -51.012598) (xy 221.656512 -51.012598)
			(xy 221.616414 -51.030911) (xy 221.564119 -51.046266) (xy 221.510171 -51.054022) (xy 221.455669 -51.054022)
			(xy 221.401721 -51.046266) (xy 221.349426 -51.030911) (xy 221.299849 -51.008269) (xy 221.253999 -50.978803)
			(xy 221.212808 -50.943112) (xy 221.177117 -50.901921) (xy 221.147651 -50.856071) (xy 221.125009 -50.806494)
			(xy 221.109654 -50.754199) (xy 221.101898 -50.700251) (xy 221.101412 -50.673) (xy 221.101964 -50.643236)
			(xy 221.111222 -50.584434) (xy 221.129499 -50.527782) (xy 221.156351 -50.474654) (xy 221.191126 -50.426341)
			(xy 221.211648 -50.404776) (xy 221.221031 -50.39466) (xy 221.234451 -50.370563) (xy 221.240945 -50.343757)
			(xy 221.240039 -50.31619) (xy 221.231801 -50.289867) (xy 221.216828 -50.266703) (xy 221.206822 -50.257202)
			(xy 221.187045 -50.239011) (xy 221.152252 -50.198065) (xy 221.123551 -50.152641) (xy 221.10151 -50.103637)
			(xy 221.086566 -50.052025) (xy 221.079016 -49.998826) (xy 221.078552 -49.97196) (xy 209.89798 -49.97196)
			(xy 209.89798 -51.559714) (xy 209.898234 -51.561746) (xy 209.906729 -51.671084) (xy 209.91575 -51.89023)
			(xy 209.916268 -51.999896) (xy 209.91598 -52.061872) (xy 214.127586 -52.061872) (xy 214.131657 -52.00625)
			(xy 214.143783 -51.951813) (xy 214.163706 -51.899722) (xy 214.191002 -51.851087) (xy 214.225088 -51.806944)
			(xy 214.265237 -51.768235) (xy 214.310595 -51.735784) (xy 214.360195 -51.710283) (xy 214.412979 -51.692276)
			(xy 214.467822 -51.682146) (xy 214.523556 -51.680109) (xy 214.578993 -51.686209) (xy 214.63295 -51.700315)
			(xy 214.684279 -51.722127) (xy 214.731885 -51.751181) (xy 214.774753 -51.786856) (xy 214.81197 -51.828393)
			(xy 214.842743 -51.874906) (xy 214.866415 -51.925403) (xy 214.882483 -51.97881) (xy 214.890603 -52.033986)
			(xy 214.891112 -52.061872) (xy 214.890603 -52.089758) (xy 214.882483 -52.144934) (xy 214.866415 -52.198341)
			(xy 214.842743 -52.248838) (xy 214.81197 -52.295351) (xy 214.774753 -52.336888) (xy 214.731885 -52.372563)
			(xy 214.684279 -52.401617) (xy 214.63295 -52.423429) (xy 214.578993 -52.437535) (xy 214.523556 -52.443635)
			(xy 214.467822 -52.441598) (xy 214.412979 -52.431468) (xy 214.360195 -52.413461) (xy 214.310595 -52.38796)
			(xy 214.265237 -52.355509) (xy 214.225088 -52.3168) (xy 214.191002 -52.272657) (xy 214.163706 -52.224022)
			(xy 214.143783 -52.171931) (xy 214.131657 -52.117494) (xy 214.127586 -52.061872) (xy 209.91598 -52.061872)
			(xy 209.915759 -52.109562) (xy 209.90674 -52.328709) (xy 209.898234 -52.438046) (xy 209.89798 -52.440078)
			(xy 209.89798 -54.154578) (xy 212.257132 -54.154578) (xy 212.2576 -54.127522) (xy 212.265274 -54.073955)
			(xy 212.280436 -54.02201) (xy 212.302784 -53.972727) (xy 212.331867 -53.927094) (xy 212.367105 -53.886026)
			(xy 212.407789 -53.850347) (xy 212.453105 -53.820771) (xy 212.502144 -53.797893) (xy 212.527896 -53.78958)
			(xy 212.54199 -53.784783) (xy 212.566789 -53.768334) (xy 212.585798 -53.745438) (xy 212.597405 -53.718036)
			(xy 212.600626 -53.688452) (xy 212.595188 -53.659195) (xy 212.581553 -53.632744) (xy 212.571584 -53.621686)
			(xy 212.551557 -53.600197) (xy 212.517648 -53.552236) (xy 212.491488 -53.499645) (xy 212.473694 -53.443668)
			(xy 212.464686 -53.385625) (xy 212.464142 -53.356256) (xy 212.464622 -53.328478) (xy 212.472699 -53.273511)
			(xy 212.488662 -53.220297) (xy 212.512173 -53.16996) (xy 212.542734 -53.123565) (xy 212.579701 -53.082092)
			(xy 212.622292 -53.046418) (xy 212.669605 -53.017297) (xy 212.720641 -52.995345) (xy 212.747352 -52.987702)
			(xy 212.761967 -52.983203) (xy 212.787831 -52.966921) (xy 212.80772 -52.943716) (xy 212.819853 -52.915665)
			(xy 212.823144 -52.88528) (xy 212.817297 -52.855282) (xy 212.802837 -52.828357) (xy 212.79231 -52.817268)
			(xy 212.771154 -52.795627) (xy 212.735331 -52.746851) (xy 212.70766 -52.693029) (xy 212.688834 -52.635514)
			(xy 212.679327 -52.575747) (xy 212.678772 -52.545488) (xy 212.679258 -52.518237) (xy 212.687014 -52.464289)
			(xy 212.702369 -52.411994) (xy 212.725011 -52.362417) (xy 212.754477 -52.316567) (xy 212.790168 -52.275376)
			(xy 212.831359 -52.239685) (xy 212.877209 -52.210219) (xy 212.926786 -52.187577) (xy 212.979081 -52.172222)
			(xy 213.033029 -52.164466) (xy 213.087531 -52.164466) (xy 213.141479 -52.172222) (xy 213.193774 -52.187577)
			(xy 213.243351 -52.210219) (xy 213.289201 -52.239685) (xy 213.330392 -52.275376) (xy 213.366083 -52.316567)
			(xy 213.395549 -52.362417) (xy 213.418191 -52.411994) (xy 213.433546 -52.464289) (xy 213.441302 -52.518237)
			(xy 213.441788 -52.545488) (xy 213.441326 -52.573266) (xy 213.433243 -52.628233) (xy 213.417276 -52.681446)
			(xy 213.393762 -52.731782) (xy 213.363197 -52.778176) (xy 213.326229 -52.819649) (xy 213.283638 -52.855323)
			(xy 213.236325 -52.884444) (xy 213.185289 -52.906398) (xy 213.158578 -52.914042) (xy 213.143934 -52.918452)
			(xy 213.118072 -52.934756) (xy 213.098188 -52.957979) (xy 213.086061 -52.986044) (xy 213.082776 -53.016439)
			(xy 213.088627 -53.046447) (xy 213.103091 -53.073382) (xy 213.11362 -53.084476) (xy 213.134737 -53.106154)
			(xy 213.170568 -53.154919) (xy 213.198248 -53.20873) (xy 213.217082 -53.266238) (xy 213.226599 -53.325999)
			(xy 213.227158 -53.356256) (xy 213.226639 -53.383311) (xy 213.218974 -53.436875) (xy 213.203819 -53.48882)
			(xy 213.181479 -53.538103) (xy 213.152402 -53.583736) (xy 213.117171 -53.624805) (xy 213.076491 -53.660485)
			(xy 213.03118 -53.690062) (xy 212.982145 -53.712941) (xy 212.956394 -53.721254) (xy 212.942279 -53.725997)
			(xy 212.917476 -53.742456) (xy 212.898466 -53.765362) (xy 212.88686 -53.792774) (xy 212.883644 -53.822367)
			(xy 212.889088 -53.851632) (xy 212.895337 -53.863748) (xy 215.444322 -53.863748) (xy 215.448393 -53.808126)
			(xy 215.460519 -53.753689) (xy 215.480442 -53.701598) (xy 215.507738 -53.652963) (xy 215.541824 -53.60882)
			(xy 215.581973 -53.570111) (xy 215.627331 -53.53766) (xy 215.676931 -53.512159) (xy 215.729715 -53.494152)
			(xy 215.784558 -53.484022) (xy 215.840292 -53.481985) (xy 215.895729 -53.488085) (xy 215.949686 -53.502191)
			(xy 216.001015 -53.524003) (xy 216.048621 -53.553057) (xy 216.091489 -53.588732) (xy 216.128706 -53.630269)
			(xy 216.159479 -53.676782) (xy 216.183151 -53.727279) (xy 216.199219 -53.780686) (xy 216.207339 -53.835862)
			(xy 216.207848 -53.863748) (xy 216.207339 -53.891634) (xy 216.199219 -53.94681) (xy 216.183151 -54.000217)
			(xy 216.159479 -54.050714) (xy 216.128706 -54.097227) (xy 216.091489 -54.138764) (xy 216.048621 -54.174439)
			(xy 216.001015 -54.203493) (xy 215.949686 -54.225305) (xy 215.895729 -54.239411) (xy 215.840292 -54.245511)
			(xy 215.784558 -54.243474) (xy 215.729715 -54.233344) (xy 215.676931 -54.215337) (xy 215.627331 -54.189836)
			(xy 215.581973 -54.157385) (xy 215.541824 -54.118676) (xy 215.507738 -54.074533) (xy 215.480442 -54.025898)
			(xy 215.460519 -53.973807) (xy 215.448393 -53.91937) (xy 215.444322 -53.863748) (xy 212.895337 -53.863748)
			(xy 212.902733 -53.878088) (xy 212.912706 -53.889148) (xy 212.932747 -53.910624) (xy 212.966655 -53.958589)
			(xy 212.992812 -54.011182) (xy 213.010603 -54.067163) (xy 213.019606 -54.125208) (xy 213.020148 -54.154578)
			(xy 213.019662 -54.181829) (xy 213.011906 -54.235777) (xy 212.996551 -54.288072) (xy 212.973909 -54.337649)
			(xy 212.944443 -54.383499) (xy 212.908752 -54.42469) (xy 212.867561 -54.460381) (xy 212.821711 -54.489847)
			(xy 212.772134 -54.512489) (xy 212.719839 -54.527844) (xy 212.665891 -54.5356) (xy 212.611389 -54.5356)
			(xy 212.557441 -54.527844) (xy 212.505146 -54.512489) (xy 212.455569 -54.489847) (xy 212.409719 -54.460381)
			(xy 212.368528 -54.42469) (xy 212.332837 -54.383499) (xy 212.303371 -54.337649) (xy 212.280729 -54.288072)
			(xy 212.265374 -54.235777) (xy 212.257618 -54.181829) (xy 212.257132 -54.154578) (xy 209.89798 -54.154578)
			(xy 209.89798 -54.999128) (xy 214.303862 -54.999128) (xy 214.307933 -54.943506) (xy 214.320059 -54.889069)
			(xy 214.339982 -54.836978) (xy 214.367278 -54.788343) (xy 214.401364 -54.7442) (xy 214.441513 -54.705491)
			(xy 214.486871 -54.67304) (xy 214.536471 -54.647539) (xy 214.589255 -54.629532) (xy 214.644098 -54.619402)
			(xy 214.699832 -54.617365) (xy 214.755269 -54.623465) (xy 214.809226 -54.637571) (xy 214.860555 -54.659383)
			(xy 214.908161 -54.688437) (xy 214.928364 -54.70525) (xy 217.024964 -54.70525) (xy 217.029035 -54.649628)
			(xy 217.041161 -54.595191) (xy 217.061084 -54.5431) (xy 217.08838 -54.494465) (xy 217.122466 -54.450322)
			(xy 217.162615 -54.411613) (xy 217.207973 -54.379162) (xy 217.257573 -54.353661) (xy 217.310357 -54.335654)
			(xy 217.3652 -54.325524) (xy 217.420934 -54.323487) (xy 217.476371 -54.329587) (xy 217.530328 -54.343693)
			(xy 217.581657 -54.365505) (xy 217.629263 -54.394559) (xy 217.672131 -54.430234) (xy 217.709348 -54.471771)
			(xy 217.740121 -54.518284) (xy 217.763793 -54.568781) (xy 217.779861 -54.622188) (xy 217.787981 -54.677364)
			(xy 217.788189 -54.68874) (xy 218.070682 -54.68874) (xy 218.074753 -54.633118) (xy 218.086879 -54.578681)
			(xy 218.106802 -54.52659) (xy 218.134098 -54.477955) (xy 218.168184 -54.433812) (xy 218.208333 -54.395103)
			(xy 218.253691 -54.362652) (xy 218.303291 -54.337151) (xy 218.356075 -54.319144) (xy 218.410918 -54.309014)
			(xy 218.466652 -54.306977) (xy 218.522089 -54.313077) (xy 218.576046 -54.327183) (xy 218.627375 -54.348995)
			(xy 218.674981 -54.378049) (xy 218.717849 -54.413724) (xy 218.755066 -54.455261) (xy 218.785839 -54.501774)
			(xy 218.809511 -54.552271) (xy 218.825579 -54.605678) (xy 218.833699 -54.660854) (xy 218.834208 -54.68874)
			(xy 218.833699 -54.716626) (xy 218.825579 -54.771802) (xy 218.809511 -54.825209) (xy 218.785839 -54.875706)
			(xy 218.755066 -54.922219) (xy 218.717849 -54.963756) (xy 218.674981 -54.999431) (xy 218.627375 -55.028485)
			(xy 218.576046 -55.050297) (xy 218.522089 -55.064403) (xy 218.466652 -55.070503) (xy 218.410918 -55.068466)
			(xy 218.356075 -55.058336) (xy 218.303291 -55.040329) (xy 218.253691 -55.014828) (xy 218.208333 -54.982377)
			(xy 218.168184 -54.943668) (xy 218.134098 -54.899525) (xy 218.106802 -54.85089) (xy 218.086879 -54.798799)
			(xy 218.074753 -54.744362) (xy 218.070682 -54.68874) (xy 217.788189 -54.68874) (xy 217.78849 -54.70525)
			(xy 217.787981 -54.733136) (xy 217.779861 -54.788312) (xy 217.763793 -54.841719) (xy 217.740121 -54.892216)
			(xy 217.709348 -54.938729) (xy 217.672131 -54.980266) (xy 217.629263 -55.015941) (xy 217.581657 -55.044995)
			(xy 217.530328 -55.066807) (xy 217.476371 -55.080913) (xy 217.420934 -55.087013) (xy 217.3652 -55.084976)
			(xy 217.310357 -55.074846) (xy 217.257573 -55.056839) (xy 217.207973 -55.031338) (xy 217.162615 -54.998887)
			(xy 217.122466 -54.960178) (xy 217.08838 -54.916035) (xy 217.061084 -54.8674) (xy 217.041161 -54.815309)
			(xy 217.029035 -54.760872) (xy 217.024964 -54.70525) (xy 214.928364 -54.70525) (xy 214.951029 -54.724112)
			(xy 214.988246 -54.765649) (xy 215.019019 -54.812162) (xy 215.042691 -54.862659) (xy 215.058759 -54.916066)
			(xy 215.066879 -54.971242) (xy 215.067388 -54.999128) (xy 215.066879 -55.027014) (xy 215.058759 -55.08219)
			(xy 215.042691 -55.135597) (xy 215.019019 -55.186094) (xy 214.988246 -55.232607) (xy 214.951029 -55.274144)
			(xy 214.908161 -55.309819) (xy 214.860555 -55.338873) (xy 214.809226 -55.360685) (xy 214.755269 -55.374791)
			(xy 214.699832 -55.380891) (xy 214.644098 -55.378854) (xy 214.589255 -55.368724) (xy 214.536471 -55.350717)
			(xy 214.486871 -55.325216) (xy 214.441513 -55.292765) (xy 214.401364 -55.254056) (xy 214.367278 -55.209913)
			(xy 214.339982 -55.161278) (xy 214.320059 -55.109187) (xy 214.307933 -55.05475) (xy 214.303862 -54.999128)
			(xy 209.89798 -54.999128) (xy 209.89798 -55.425848) (xy 212.256622 -55.425848) (xy 212.260693 -55.370226)
			(xy 212.272819 -55.315789) (xy 212.292742 -55.263698) (xy 212.320038 -55.215063) (xy 212.354124 -55.17092)
			(xy 212.394273 -55.132211) (xy 212.439631 -55.09976) (xy 212.489231 -55.074259) (xy 212.542015 -55.056252)
			(xy 212.596858 -55.046122) (xy 212.652592 -55.044085) (xy 212.708029 -55.050185) (xy 212.761986 -55.064291)
			(xy 212.813315 -55.086103) (xy 212.860921 -55.115157) (xy 212.903789 -55.150832) (xy 212.941006 -55.192369)
			(xy 212.971779 -55.238882) (xy 212.995451 -55.289379) (xy 213.011519 -55.342786) (xy 213.019639 -55.397962)
			(xy 213.020148 -55.425848) (xy 213.019639 -55.453734) (xy 213.011519 -55.50891) (xy 212.995451 -55.562317)
			(xy 212.971779 -55.612814) (xy 212.941006 -55.659327) (xy 212.903789 -55.700864) (xy 212.860921 -55.736539)
			(xy 212.813315 -55.765593) (xy 212.761986 -55.787405) (xy 212.708029 -55.801511) (xy 212.652592 -55.807611)
			(xy 212.596858 -55.805574) (xy 212.542015 -55.795444) (xy 212.489231 -55.777437) (xy 212.439631 -55.751936)
			(xy 212.394273 -55.719485) (xy 212.354124 -55.680776) (xy 212.320038 -55.636633) (xy 212.292742 -55.587998)
			(xy 212.272819 -55.535907) (xy 212.260693 -55.48147) (xy 212.256622 -55.425848) (xy 209.89798 -55.425848)
			(xy 209.89798 -57.948322) (xy 210.524088 -57.948322) (xy 210.528159 -57.8927) (xy 210.540285 -57.838263)
			(xy 210.560208 -57.786172) (xy 210.587504 -57.737537) (xy 210.62159 -57.693394) (xy 210.661739 -57.654685)
			(xy 210.707097 -57.622234) (xy 210.756697 -57.596733) (xy 210.809481 -57.578726) (xy 210.864324 -57.568596)
			(xy 210.920058 -57.566559) (xy 210.975495 -57.572659) (xy 211.029452 -57.586765) (xy 211.080781 -57.608577)
			(xy 211.128387 -57.637631) (xy 211.171255 -57.673306) (xy 211.208472 -57.714843) (xy 211.239245 -57.761356)
			(xy 211.262917 -57.811853) (xy 211.278985 -57.86526) (xy 211.287105 -57.920436) (xy 211.287614 -57.948322)
			(xy 211.287105 -57.976208) (xy 211.278985 -58.031384) (xy 211.262917 -58.084791) (xy 211.239245 -58.135288)
			(xy 211.208472 -58.181801) (xy 211.171255 -58.223338) (xy 211.128387 -58.259013) (xy 211.080781 -58.288067)
			(xy 211.029452 -58.309879) (xy 210.975495 -58.323985) (xy 210.920058 -58.330085) (xy 210.864324 -58.328048)
			(xy 210.809481 -58.317918) (xy 210.756697 -58.299911) (xy 210.707097 -58.27441) (xy 210.661739 -58.241959)
			(xy 210.62159 -58.20325) (xy 210.587504 -58.159107) (xy 210.560208 -58.110472) (xy 210.540285 -58.058381)
			(xy 210.528159 -58.003944) (xy 210.524088 -57.948322) (xy 209.89798 -57.948322) (xy 209.89798 -58.416253)
			(xy 216.079267 -58.416253) (xy 216.079267 -58.361747) (xy 216.087025 -58.307796) (xy 216.102381 -58.255497)
			(xy 216.125025 -58.205917) (xy 216.154494 -58.160064) (xy 216.190189 -58.118872) (xy 216.231384 -58.08318)
			(xy 216.277238 -58.053714) (xy 216.32682 -58.031073) (xy 216.379119 -58.01572) (xy 216.433071 -58.007966)
			(xy 216.460324 -58.007504) (xy 216.487695 -58.007955) (xy 216.541875 -58.015776) (xy 216.594378 -58.031269)
			(xy 216.644124 -58.054114) (xy 216.690091 -58.083841) (xy 216.711022 -58.101484) (xy 216.72235 -58.11072)
			(xy 216.748907 -58.122896) (xy 216.777824 -58.127069) (xy 216.806741 -58.122896) (xy 216.833298 -58.11072)
			(xy 216.844626 -58.101484) (xy 216.865573 -58.083864) (xy 216.911542 -58.05415) (xy 216.961286 -58.03131)
			(xy 217.013783 -58.015815) (xy 217.067956 -58.007981) (xy 217.095324 -58.007504) (xy 217.122575 -58.007967)
			(xy 217.176522 -58.015727) (xy 217.228815 -58.031085) (xy 217.278391 -58.053728) (xy 217.32424 -58.083196)
			(xy 217.365429 -58.118888) (xy 217.401119 -58.160079) (xy 217.430584 -58.20593) (xy 217.453224 -58.255507)
			(xy 217.468578 -58.307802) (xy 217.476334 -58.361749) (xy 217.476334 -58.416251) (xy 217.468578 -58.470198)
			(xy 217.453224 -58.522493) (xy 217.430584 -58.57207) (xy 217.401119 -58.617921) (xy 217.365429 -58.659112)
			(xy 217.32424 -58.694804) (xy 217.278391 -58.724272) (xy 217.228815 -58.746915) (xy 217.176522 -58.762273)
			(xy 217.122575 -58.770033) (xy 217.095324 -58.77052) (xy 217.067953 -58.770059) (xy 217.013773 -58.762243)
			(xy 216.961269 -58.746754) (xy 216.911522 -58.72391) (xy 216.865557 -58.694183) (xy 216.844626 -58.67654)
			(xy 216.833298 -58.667304) (xy 216.806741 -58.655128) (xy 216.777824 -58.650955) (xy 216.748907 -58.655128)
			(xy 216.72235 -58.667304) (xy 216.711022 -58.67654) (xy 216.690098 -58.694189) (xy 216.644122 -58.723898)
			(xy 216.594373 -58.746731) (xy 216.541871 -58.762221) (xy 216.487694 -58.770047) (xy 216.460324 -58.77052)
			(xy 216.433071 -58.770034) (xy 216.379119 -58.76228) (xy 216.32682 -58.746927) (xy 216.277238 -58.724286)
			(xy 216.231384 -58.69482) (xy 216.190189 -58.659128) (xy 216.154494 -58.617936) (xy 216.125025 -58.572083)
			(xy 216.102381 -58.522503) (xy 216.087025 -58.470204) (xy 216.079267 -58.416253) (xy 209.89798 -58.416253)
			(xy 209.89798 -58.984388) (xy 214.903302 -58.984388) (xy 214.907373 -58.928766) (xy 214.919499 -58.874329)
			(xy 214.939422 -58.822238) (xy 214.966718 -58.773603) (xy 215.000804 -58.72946) (xy 215.040953 -58.690751)
			(xy 215.086311 -58.6583) (xy 215.135911 -58.632799) (xy 215.188695 -58.614792) (xy 215.243538 -58.604662)
			(xy 215.299272 -58.602625) (xy 215.354709 -58.608725) (xy 215.408666 -58.622831) (xy 215.459995 -58.644643)
			(xy 215.507601 -58.673697) (xy 215.550469 -58.709372) (xy 215.587686 -58.750909) (xy 215.618459 -58.797422)
			(xy 215.642131 -58.847919) (xy 215.650023 -58.874152) (xy 219.970094 -58.874152) (xy 219.974165 -58.81853)
			(xy 219.986291 -58.764093) (xy 220.006214 -58.712002) (xy 220.03351 -58.663367) (xy 220.067596 -58.619224)
			(xy 220.107745 -58.580515) (xy 220.153103 -58.548064) (xy 220.202703 -58.522563) (xy 220.255487 -58.504556)
			(xy 220.31033 -58.494426) (xy 220.366064 -58.492389) (xy 220.421501 -58.498489) (xy 220.475458 -58.512595)
			(xy 220.526787 -58.534407) (xy 220.574393 -58.563461) (xy 220.617261 -58.599136) (xy 220.654478 -58.640673)
			(xy 220.685251 -58.687186) (xy 220.708923 -58.737683) (xy 220.724991 -58.79109) (xy 220.733111 -58.846266)
			(xy 220.73362 -58.874152) (xy 220.733111 -58.902038) (xy 220.724991 -58.957214) (xy 220.708923 -59.010621)
			(xy 220.685251 -59.061118) (xy 220.654478 -59.107631) (xy 220.617261 -59.149168) (xy 220.574393 -59.184843)
			(xy 220.526787 -59.213897) (xy 220.475458 -59.235709) (xy 220.421501 -59.249815) (xy 220.366064 -59.255915)
			(xy 220.31033 -59.253878) (xy 220.255487 -59.243748) (xy 220.202703 -59.225741) (xy 220.153103 -59.20024)
			(xy 220.107745 -59.167789) (xy 220.067596 -59.12908) (xy 220.03351 -59.084937) (xy 220.006214 -59.036302)
			(xy 219.986291 -58.984211) (xy 219.974165 -58.929774) (xy 219.970094 -58.874152) (xy 215.650023 -58.874152)
			(xy 215.658199 -58.901326) (xy 215.666319 -58.956502) (xy 215.666828 -58.984388) (xy 215.666319 -59.012274)
			(xy 215.658199 -59.06745) (xy 215.642131 -59.120857) (xy 215.618459 -59.171354) (xy 215.587686 -59.217867)
			(xy 215.550469 -59.259404) (xy 215.507601 -59.295079) (xy 215.459995 -59.324133) (xy 215.408666 -59.345945)
			(xy 215.354709 -59.360051) (xy 215.299272 -59.366151) (xy 215.243538 -59.364114) (xy 215.188695 -59.353984)
			(xy 215.135911 -59.335977) (xy 215.086311 -59.310476) (xy 215.040953 -59.278025) (xy 215.000804 -59.239316)
			(xy 214.966718 -59.195173) (xy 214.939422 -59.146538) (xy 214.919499 -59.094447) (xy 214.907373 -59.04001)
			(xy 214.903302 -58.984388) (xy 209.89798 -58.984388) (xy 209.89798 -59.106308) (xy 212.1662 -61.374528)
			(xy 222.44558 -61.374528)
		)
		(stroke
			(width 0)
			(type solid)
		)
		(fill yes)
		(layer "In11.Cu")
		(net "P3V3_AUX")
	)
	(gr_poly
		(pts
			(xy 84.847938 -332.37551) (xy 84.847938 -331.67447) (xy 84.830158 -331.65669) (xy 84.830158 -330.941172)
			(xy 84.830588 -330.931105) (xy 84.838316 -330.912514) (xy 84.845144 -330.905104) (xy 86.392512 -329.357736)
			(xy 86.399909 -329.350888) (xy 86.418508 -329.343152) (xy 86.42858 -329.34275) (xy 92.023438 -329.34275)
			(xy 95.295212 -326.070976) (xy 95.302608 -326.064123) (xy 95.321206 -326.056381) (xy 95.33128 -326.05599)
			(xy 123.505976 -326.05599) (xy 123.51604 -326.056427) (xy 123.534626 -326.064159) (xy 123.542044 -326.070976)
			(xy 127.199898 -329.72883) (xy 128.830578 -329.72883) (xy 128.850898 -329.70851) (xy 131.730496 -329.70851)
			(xy 131.740566 -329.708933) (xy 131.759171 -329.716647) (xy 131.766564 -329.723496) (xy 133.431788 -331.38872)
			(xy 145.771108 -331.38872) (xy 146.6596 -330.500228) (xy 146.6596 -324.195948) (xy 125.2474 -302.783748)
			(xy 125.2474 -297.068748) (xy 123.235974 -295.057322) (xy 123.225897 -295.047892) (xy 123.20188 -295.034319)
			(xy 123.175106 -295.027669) (xy 123.14753 -295.028427) (xy 123.121162 -295.036539) (xy 123.097928 -295.051412)
			(xy 123.079522 -295.071961) (xy 123.067288 -295.096687) (xy 123.06427 -295.110154) (xy 123.058912 -295.13599)
			(xy 123.04202 -295.185977) (xy 123.018393 -295.233156) (xy 122.988486 -295.276626) (xy 122.952868 -295.315554)
			(xy 122.912221 -295.349198) (xy 122.867322 -295.376913) (xy 122.819029 -295.39817) (xy 122.768266 -295.412563)
			(xy 122.716002 -295.419816) (xy 122.68962 -295.420288) (xy 122.662367 -295.419826) (xy 122.608415 -295.412071)
			(xy 122.556116 -295.396717) (xy 122.506534 -295.374075) (xy 122.46068 -295.344607) (xy 122.419487 -295.308913)
			(xy 122.383793 -295.26772) (xy 122.354325 -295.221866) (xy 122.331683 -295.172284) (xy 122.316329 -295.119985)
			(xy 122.308574 -295.066033) (xy 122.308112 -295.03878) (xy 122.308576 -295.012991) (xy 122.315591 -294.96189)
			(xy 122.322082 -294.936926) (xy 122.32528 -294.923922) (xy 122.325501 -294.897151) (xy 122.318755 -294.871244)
			(xy 122.305504 -294.847982) (xy 122.286661 -294.828966) (xy 122.263521 -294.815502) (xy 122.237677 -294.808518)
			(xy 122.224292 -294.808148) (xy 121.666 -294.808148) (xy 120.65 -293.792148) (xy 120.65 -292.979348)
			(xy 120.1674 -292.496748) (xy 118.8466 -292.496748) (xy 117.6274 -291.277548) (xy 117.6274 -289.153092)
			(xy 117.60898 -289.134318) (xy 117.577733 -289.092015) (xy 117.55358 -289.045296) (xy 117.53713 -288.995343)
			(xy 117.528798 -288.943414) (xy 117.528795 -288.890822) (xy 117.537121 -288.838893) (xy 117.553566 -288.788937)
			(xy 117.577714 -288.742216) (xy 117.608956 -288.699909) (xy 117.6274 -288.68116) (xy 117.6274 -287.525206)
			(xy 117.608979 -287.506432) (xy 117.57773 -287.464128) (xy 117.553574 -287.417409) (xy 117.537122 -287.367455)
			(xy 117.528789 -287.315525) (xy 117.528784 -287.262931) (xy 117.537109 -287.211) (xy 117.553553 -287.161042)
			(xy 117.5777 -287.114319) (xy 117.608942 -287.07201) (xy 117.6274 -287.053274) (xy 117.6274 -286.603948)
			(xy 118.1354 -286.095948) (xy 118.1354 -285.115254) (xy 118.114578 -285.099619) (xy 118.077668 -285.062895)
			(xy 118.046978 -285.020835) (xy 118.023269 -284.974479) (xy 118.007127 -284.924977) (xy 117.998953 -284.873556)
			(xy 117.998949 -284.821489) (xy 118.007116 -284.770066) (xy 118.023251 -284.720562) (xy 118.046955 -284.674203)
			(xy 118.077639 -284.632138) (xy 118.114545 -284.59541) (xy 118.1354 -284.579822) (xy 118.1354 -283.487622)
			(xy 118.114581 -283.471987) (xy 118.077676 -283.435264) (xy 118.046991 -283.393205) (xy 118.023285 -283.346852)
			(xy 118.007148 -283.297353) (xy 117.998977 -283.245935) (xy 117.998977 -283.193872) (xy 118.007146 -283.142454)
			(xy 118.023283 -283.092955) (xy 118.046987 -283.046601) (xy 118.077671 -283.004541) (xy 118.114576 -282.967817)
			(xy 118.1354 -282.95219) (xy 118.1354 -282.800806) (xy 118.134857 -282.786373) (xy 118.126705 -282.758678)
			(xy 118.111136 -282.734367) (xy 118.08939 -282.715378) (xy 118.063202 -282.703226) (xy 118.034661 -282.698881)
			(xy 118.006044 -282.702689) (xy 117.992652 -282.708096) (xy 117.971517 -282.717004) (xy 117.927404 -282.729561)
			(xy 117.88198 -282.735904) (xy 117.859048 -282.73629) (xy 117.833075 -282.735811) (xy 117.781768 -282.727692)
			(xy 117.732363 -282.711647) (xy 117.686076 -282.68807) (xy 117.644047 -282.657543) (xy 117.607312 -282.620817)
			(xy 117.576774 -282.578796) (xy 117.553185 -282.532515) (xy 117.537128 -282.483114) (xy 117.528996 -282.431809)
			(xy 117.528594 -282.405836) (xy 117.52918 -282.377723) (xy 117.538731 -282.322313) (xy 117.557514 -282.269316)
			(xy 117.584988 -282.220257) (xy 117.602254 -282.198064) (xy 117.630956 -282.162504) (xy 117.391434 -281.922982)
			(xy 117.37213 -281.921966) (xy 117.345234 -281.920048) (xy 117.292552 -281.908573) (xy 117.242431 -281.888695)
			(xy 117.196204 -281.860944) (xy 117.155096 -281.826055) (xy 117.120198 -281.784954) (xy 117.092436 -281.738733)
			(xy 117.072548 -281.688617) (xy 117.061061 -281.635937) (xy 117.059202 -281.609038) (xy 117.058186 -281.589734)
			(xy 116.6368 -281.168348) (xy 116.6368 -280.950162) (xy 116.63045 -280.938732) (xy 116.619176 -280.917587)
			(xy 116.602177 -280.872785) (xy 116.591832 -280.825996) (xy 116.588359 -280.778204) (xy 116.591831 -280.730411)
			(xy 116.602175 -280.683622) (xy 116.619173 -280.63882) (xy 116.63045 -280.617676) (xy 116.6368 -280.606246)
			(xy 116.6368 -280.3906) (xy 116.53139 -280.28519) (xy 116.505482 -280.289762) (xy 116.491559 -280.292027)
			(xy 116.463453 -280.29444) (xy 116.449348 -280.294588) (xy 116.423375 -280.294109) (xy 116.372068 -280.28599)
			(xy 116.322663 -280.269945) (xy 116.276376 -280.246368) (xy 116.234348 -280.215841) (xy 116.197612 -280.179115)
			(xy 116.167075 -280.137094) (xy 116.143487 -280.090813) (xy 116.127429 -280.041412) (xy 116.119298 -279.990107)
			(xy 116.118894 -279.964134) (xy 116.119057 -279.95003) (xy 116.121472 -279.921925) (xy 116.12372 -279.908)
			(xy 116.128292 -279.882092) (xy 115.504214 -279.258014) (xy 115.493983 -279.248396) (xy 115.469493 -279.234679)
			(xy 115.442194 -279.228147) (xy 115.414147 -279.229292) (xy 115.387472 -279.23803) (xy 115.364183 -279.253699)
			(xy 115.346039 -279.275117) (xy 115.339876 -279.287732) (xy 115.328172 -279.31203) (xy 115.298069 -279.356777)
			(xy 115.261103 -279.396044) (xy 115.218252 -279.428789) (xy 115.170654 -279.454144) (xy 115.119571 -279.471436)
			(xy 115.066359 -279.480206) (xy 115.039394 -279.480772) (xy 115.013427 -279.480262) (xy 114.962131 -279.472137)
			(xy 114.912738 -279.456088) (xy 114.866464 -279.432511) (xy 114.824447 -279.401985) (xy 114.787723 -279.365262)
			(xy 114.757196 -279.323246) (xy 114.733616 -279.276973) (xy 114.717565 -279.22758) (xy 114.709439 -279.176285)
			(xy 114.70894 -279.150318) (xy 114.709418 -279.125063) (xy 114.717104 -279.07514) (xy 114.732301 -279.026969)
			(xy 114.754653 -278.981673) (xy 114.783639 -278.940308) (xy 114.818585 -278.903837) (xy 114.858676 -278.873111)
			(xy 114.902976 -278.848845) (xy 114.950454 -278.831607) (xy 114.975132 -278.826214) (xy 115.016026 -278.818086)
			(xy 115.016026 -277.854664) (xy 114.975132 -277.846536) (xy 114.950452 -277.841154) (xy 114.902977 -277.823904)
			(xy 114.858681 -277.79963) (xy 114.818595 -277.768897) (xy 114.783653 -277.732422) (xy 114.754669 -277.691054)
			(xy 114.732318 -277.645756) (xy 114.717122 -277.597585) (xy 114.709434 -277.547662) (xy 114.709433 -277.497151)
			(xy 114.717119 -277.447227) (xy 114.732314 -277.399055) (xy 114.754662 -277.353757) (xy 114.783645 -277.312388)
			(xy 114.818585 -277.275911) (xy 114.85867 -277.245177) (xy 114.902966 -277.220901) (xy 114.95044 -277.203649)
			(xy 114.975132 -277.198328) (xy 115.016026 -277.1902) (xy 115.016026 -276.227032) (xy 114.975132 -276.218904)
			(xy 114.950454 -276.213522) (xy 114.902984 -276.196273) (xy 114.858693 -276.172) (xy 114.818611 -276.14127)
			(xy 114.783673 -276.104797) (xy 114.754692 -276.063432) (xy 114.732345 -276.018139) (xy 114.717151 -275.969972)
			(xy 114.709464 -275.920053) (xy 114.709464 -275.869547) (xy 114.717151 -275.819628) (xy 114.732345 -275.771461)
			(xy 114.754692 -275.726168) (xy 114.783673 -275.684803) (xy 114.818611 -275.64833) (xy 114.858693 -275.6176)
			(xy 114.902984 -275.593327) (xy 114.950454 -275.576078) (xy 114.975132 -275.570696) (xy 115.016026 -275.562568)
			(xy 115.016026 -275.14042) (xy 114.945668 -275.070062) (xy 114.89817 -275.11756) (xy 114.895376 -275.133562)
			(xy 114.890736 -275.159049) (xy 114.874576 -275.208264) (xy 114.850936 -275.254357) (xy 114.820396 -275.296197)
			(xy 114.783702 -275.332761) (xy 114.741753 -275.363153) (xy 114.695577 -275.386628) (xy 114.646304 -275.402613)
			(xy 114.59514 -275.410716) (xy 114.56924 -275.411184) (xy 114.543268 -275.410704) (xy 114.491962 -275.402584)
			(xy 114.442558 -275.386538) (xy 114.396273 -275.362961) (xy 114.354246 -275.332434) (xy 114.317512 -275.295708)
			(xy 114.286975 -275.253687) (xy 114.263388 -275.207407) (xy 114.247332 -275.158006) (xy 114.239201 -275.106702)
			(xy 114.238786 -275.08073) (xy 114.239251 -275.056035) (xy 114.246613 -275.007197) (xy 114.261163 -274.959999)
			(xy 114.282576 -274.915493) (xy 114.310376 -274.87467) (xy 114.343943 -274.838439) (xy 114.382528 -274.807609)
			(xy 114.425273 -274.782866) (xy 114.448082 -274.77339) (xy 114.461281 -274.767634) (xy 114.484028 -274.75)
			(xy 114.500953 -274.726719) (xy 114.51071 -274.699642) (xy 114.512526 -274.670917) (xy 114.506256 -274.642826)
			(xy 114.492398 -274.6176) (xy 114.482626 -274.60702) (xy 114.356134 -274.480528) (xy 114.32032 -274.512786)
			(xy 114.302048 -274.528638) (xy 114.261736 -274.555374) (xy 114.217953 -274.57594) (xy 114.171637 -274.589894)
			(xy 114.12378 -274.59694) (xy 114.099594 -274.597368) (xy 114.073627 -274.596858) (xy 114.022332 -274.588733)
			(xy 113.972939 -274.572684) (xy 113.926665 -274.549107) (xy 113.884649 -274.51858) (xy 113.847925 -274.481857)
			(xy 113.817398 -274.439842) (xy 113.793819 -274.393569) (xy 113.777769 -274.344176) (xy 113.769642 -274.292881)
			(xy 113.76914 -274.266914) (xy 113.769568 -274.24273) (xy 113.776634 -274.194881) (xy 113.790601 -274.148573)
			(xy 113.811171 -274.104796) (xy 113.837904 -274.064487) (xy 113.853722 -274.046188) (xy 113.85988 -274.038722)
			(xy 113.866583 -274.020584) (xy 113.866091 -274.001254) (xy 113.858474 -273.98348) (xy 113.851944 -273.976338)
			(xy 113.65865 -273.783044) (xy 113.636806 -273.783552) (xy 113.629694 -273.783552) (xy 113.603727 -273.783042)
			(xy 113.552433 -273.774917) (xy 113.503041 -273.758868) (xy 113.456768 -273.73529) (xy 113.414754 -273.704764)
			(xy 113.378031 -273.66804) (xy 113.347506 -273.626025) (xy 113.323929 -273.579751) (xy 113.307881 -273.530359)
			(xy 113.299757 -273.479065) (xy 113.29924 -273.453098) (xy 113.299684 -273.428519) (xy 113.306956 -273.379902)
			(xy 113.321354 -273.3329) (xy 113.34256 -273.288551) (xy 113.370106 -273.247836) (xy 113.403382 -273.211653)
			(xy 113.441654 -273.180803) (xy 113.484075 -273.155966) (xy 113.52971 -273.137691) (xy 113.57755 -273.126383)
			(xy 113.602008 -273.123914) (xy 113.617049 -273.122123) (xy 113.645171 -273.110909) (xy 113.66877 -273.091944)
			(xy 113.685771 -273.066893) (xy 113.694682 -273.037959) (xy 113.695226 -273.022822) (xy 113.695226 -272.255488)
			(xy 113.69463 -272.240364) (xy 113.685693 -272.211462) (xy 113.668695 -272.186437) (xy 113.645121 -272.167478)
			(xy 113.617032 -272.156242) (xy 113.602008 -272.154396) (xy 113.57756 -272.151882) (xy 113.52974 -272.140545)
			(xy 113.484126 -272.122254) (xy 113.441722 -272.097411) (xy 113.403464 -272.066563) (xy 113.370195 -272.030392)
			(xy 113.342647 -271.989693) (xy 113.321428 -271.945365) (xy 113.307006 -271.898383) (xy 113.299699 -271.849784)
			(xy 113.29924 -271.825212) (xy 113.299705 -271.799695) (xy 113.307534 -271.749267) (xy 113.323022 -271.700641)
			(xy 113.345801 -271.654974) (xy 113.375329 -271.613352) (xy 113.410906 -271.576764) (xy 113.451684 -271.54608)
			(xy 113.496694 -271.52203) (xy 113.544867 -271.505186) (xy 113.595057 -271.495947) (xy 113.62055 -271.494758)
			(xy 113.67008 -271.444212) (xy 113.67008 -270.57858) (xy 113.62055 -270.528034) (xy 113.595064 -270.526839)
			(xy 113.544894 -270.517578) (xy 113.496742 -270.500719) (xy 113.451751 -270.476661) (xy 113.410992 -270.445977)
			(xy 113.37543 -270.409395) (xy 113.345911 -270.367784) (xy 113.323136 -270.322131) (xy 113.307645 -270.273521)
			(xy 113.299807 -270.223109) (xy 113.299807 -270.17209) (xy 113.307646 -270.121678) (xy 113.323136 -270.073068)
			(xy 113.345912 -270.027415) (xy 113.375431 -269.985804) (xy 113.410992 -269.949222) (xy 113.451752 -269.918538)
			(xy 113.496743 -269.894481) (xy 113.544895 -269.877621) (xy 113.595066 -269.86836) (xy 113.62055 -269.867126)
			(xy 113.67008 -269.81658) (xy 113.67008 -268.950694) (xy 113.62055 -268.900148) (xy 113.595063 -268.898953)
			(xy 113.54489 -268.889692) (xy 113.496736 -268.872832) (xy 113.451744 -268.848773) (xy 113.410983 -268.818088)
			(xy 113.37542 -268.781504) (xy 113.345899 -268.739891) (xy 113.323123 -268.694237) (xy 113.307632 -268.645625)
			(xy 113.299793 -268.59521) (xy 113.299793 -268.54419) (xy 113.307632 -268.493775) (xy 113.323123 -268.445163)
			(xy 113.3459 -268.399508) (xy 113.37542 -268.357895) (xy 113.410983 -268.321312) (xy 113.451744 -268.290627)
			(xy 113.496737 -268.266568) (xy 113.544891 -268.249708) (xy 113.595064 -268.240447) (xy 113.62055 -268.23924)
			(xy 113.67008 -268.188694) (xy 113.67008 -267.322808) (xy 113.62055 -267.272262) (xy 113.595062 -267.271067)
			(xy 113.544887 -267.261805) (xy 113.496731 -267.244945) (xy 113.451737 -267.220885) (xy 113.410974 -267.190199)
			(xy 113.375409 -267.153614) (xy 113.345888 -267.111999) (xy 113.32311 -267.066342) (xy 113.307618 -267.017728)
			(xy 113.299779 -266.967312) (xy 113.299779 -266.916289) (xy 113.307618 -266.865872) (xy 113.32311 -266.817258)
			(xy 113.345887 -266.771602) (xy 113.375409 -266.729987) (xy 113.410973 -266.693402) (xy 113.451737 -266.662715)
			(xy 113.496731 -266.638656) (xy 113.544887 -266.621795) (xy 113.595062 -266.612533) (xy 113.62055 -266.611354)
			(xy 113.67008 -266.560808) (xy 113.67008 -264.067544) (xy 113.62055 -264.016998) (xy 113.59504 -264.015846)
			(xy 113.54481 -264.006653) (xy 113.496593 -263.98984) (xy 113.451537 -263.965808) (xy 113.410718 -263.935127)
			(xy 113.375105 -263.898531) (xy 113.345549 -263.856889) (xy 113.322754 -263.811196) (xy 113.307262 -263.762538)
			(xy 113.299443 -263.712076) (xy 113.298986 -263.686544) (xy 113.299466 -263.660574) (xy 113.307585 -263.609271)
			(xy 113.323632 -263.559872) (xy 113.34721 -263.513591) (xy 113.377738 -263.471569) (xy 113.414466 -263.434841)
			(xy 113.456487 -263.404312) (xy 113.502768 -263.380733) (xy 113.552168 -263.364686) (xy 113.60347 -263.356566)
			(xy 113.62944 -263.35609) (xy 113.655777 -263.356628) (xy 113.707779 -263.365031) (xy 113.75779 -263.381572)
			(xy 113.804548 -263.405831) (xy 113.846868 -263.437196) (xy 113.86566 -263.455658) (xy 113.875342 -263.46496)
			(xy 113.89847 -263.47858) (xy 113.924346 -263.485707) (xy 113.951186 -263.485848) (xy 113.977136 -263.478994)
			(xy 114.000406 -263.465619) (xy 114.010186 -263.45642) (xy 115.930426 -261.53618) (xy 115.958874 -261.53618)
			(xy 115.974286 -261.535604) (xy 116.003689 -261.526343) (xy 116.028998 -261.508744) (xy 116.047917 -261.484405)
			(xy 116.058728 -261.455536) (xy 116.060449 -261.424757) (xy 116.057172 -261.409688) (xy 116.052559 -261.390007)
			(xy 116.047592 -261.34989) (xy 116.047266 -261.329678) (xy 116.047266 -261.32917) (xy 116.047778 -261.303205)
			(xy 116.055906 -261.251915) (xy 116.071957 -261.202527) (xy 116.095537 -261.156259) (xy 116.126064 -261.114249)
			(xy 116.162787 -261.077532) (xy 116.204802 -261.047011) (xy 116.251074 -261.023438) (xy 116.300463 -261.007394)
			(xy 116.351755 -260.999274) (xy 116.37772 -260.998716) (xy 116.405017 -260.99928) (xy 116.458867 -261.008261)
			(xy 116.510507 -261.025975) (xy 116.558531 -261.051941) (xy 116.601632 -261.08545) (xy 116.620544 -261.105142)
			(xy 116.630377 -261.115122) (xy 116.654261 -261.129748) (xy 116.681217 -261.137347) (xy 116.709223 -261.137347)
			(xy 116.736179 -261.129748) (xy 116.760063 -261.115122) (xy 116.769896 -261.105142) (xy 116.787041 -261.087197)
			(xy 116.825757 -261.056145) (xy 116.868684 -261.031237) (xy 116.914855 -261.013034) (xy 116.96323 -261.001945)
			(xy 117.01272 -260.998221) (xy 117.06221 -261.001945) (xy 117.110585 -261.013034) (xy 117.156756 -261.031237)
			(xy 117.199683 -261.056145) (xy 117.238399 -261.087197) (xy 117.255544 -261.105142) (xy 117.265377 -261.115122)
			(xy 117.289261 -261.129748) (xy 117.316217 -261.137347) (xy 117.344223 -261.137347) (xy 117.371179 -261.129748)
			(xy 117.395063 -261.115122) (xy 117.404896 -261.105142) (xy 117.422041 -261.087197) (xy 117.460757 -261.056145)
			(xy 117.503684 -261.031237) (xy 117.549855 -261.013034) (xy 117.59823 -261.001945) (xy 117.64772 -260.998221)
			(xy 117.69721 -261.001945) (xy 117.745585 -261.013034) (xy 117.791756 -261.031237) (xy 117.834683 -261.056145)
			(xy 117.873399 -261.087197) (xy 117.890544 -261.105142) (xy 117.900377 -261.115122) (xy 117.924261 -261.129748)
			(xy 117.951217 -261.137347) (xy 117.979223 -261.137347) (xy 118.006179 -261.129748) (xy 118.030063 -261.115122)
			(xy 118.039896 -261.105142) (xy 118.058808 -261.08545) (xy 118.101906 -261.051936) (xy 118.14993 -261.025968)
			(xy 118.201571 -261.008254) (xy 118.255423 -260.999277) (xy 118.28272 -260.998716) (xy 118.301298 -260.998982)
			(xy 118.338217 -261.003185) (xy 118.35638 -261.007098) (xy 118.383812 -261.013194) (xy 120.727724 -258.669282)
			(xy 120.712373 -258.651123) (xy 120.686502 -258.611228) (xy 120.666619 -258.568036) (xy 120.653136 -258.522438)
			(xy 120.646331 -258.475379) (xy 120.645936 -258.451604) (xy 120.646445 -258.425636) (xy 120.654569 -258.37434)
			(xy 120.670617 -258.324946) (xy 120.694194 -258.278671) (xy 120.72472 -258.236654) (xy 120.761443 -258.199929)
			(xy 120.803459 -258.169402) (xy 120.849733 -258.145822) (xy 120.899127 -258.129772) (xy 120.950422 -258.121646)
			(xy 120.97639 -258.12115) (xy 120.976898 -258.12115) (xy 121.001369 -258.121614) (xy 121.04977 -258.128872)
			(xy 121.096572 -258.143186) (xy 121.140753 -258.164242) (xy 121.161302 -258.177538) (xy 121.195846 -258.20116)
			(xy 121.303288 -258.093718) (xy 121.296684 -258.066032) (xy 121.292419 -258.047078) (xy 121.287839 -258.008496)
			(xy 121.28754 -257.98907) (xy 121.287932 -257.9658) (xy 121.29445 -257.919719) (xy 121.307367 -257.875008)
			(xy 121.326428 -257.832551) (xy 121.351255 -257.793187) (xy 121.366026 -257.775202) (xy 121.366026 -257.504692)
			(xy 121.361962 -257.49504) (xy 121.350278 -257.464814) (xy 121.302272 -257.43027) (xy 121.258838 -257.454654)
			(xy 121.245912 -257.475127) (xy 121.215014 -257.512405) (xy 121.179009 -257.544776) (xy 121.138666 -257.571548)
			(xy 121.09485 -257.592149) (xy 121.048497 -257.606137) (xy 121.000599 -257.613213) (xy 120.97639 -257.613658)
			(xy 120.950423 -257.613148) (xy 120.899129 -257.605022) (xy 120.849738 -257.588973) (xy 120.803465 -257.565395)
			(xy 120.76145 -257.534868) (xy 120.724728 -257.498145) (xy 120.694202 -257.45613) (xy 120.670625 -257.409857)
			(xy 120.654576 -257.360465) (xy 120.646452 -257.309171) (xy 120.645936 -257.283204) (xy 120.646452 -257.256803)
			(xy 120.654845 -257.204673) (xy 120.671418 -257.15454) (xy 120.69575 -257.107679) (xy 120.727221 -257.065282)
			(xy 120.745758 -257.046476) (xy 120.755106 -257.036782) (xy 120.768793 -257.013598) (xy 120.775935 -256.987641)
			(xy 120.776037 -256.960719) (xy 120.769089 -256.934709) (xy 120.755578 -256.911423) (xy 120.746266 -256.901696)
			(xy 120.728068 -256.882961) (xy 120.697222 -256.840815) (xy 120.673394 -256.794339) (xy 120.657176 -256.744694)
			(xy 120.648973 -256.693114) (xy 120.648476 -256.667) (xy 120.648959 -256.641032) (xy 120.657084 -256.589734)
			(xy 120.673134 -256.54034) (xy 120.696714 -256.494064) (xy 120.727244 -256.452047) (xy 120.76397 -256.415324)
			(xy 120.80599 -256.384799) (xy 120.852267 -256.361223) (xy 120.901663 -256.345177) (xy 120.952962 -256.337057)
			(xy 120.97893 -256.336546) (xy 121.007325 -256.337138) (xy 121.063277 -256.346854) (xy 121.116744 -256.365995)
			(xy 121.141744 -256.379472) (xy 121.154118 -256.385919) (xy 121.181227 -256.392483) (xy 121.2091 -256.391474)
			(xy 121.235663 -256.382966) (xy 121.258937 -256.367594) (xy 121.277187 -256.346502) (xy 121.289056 -256.321261)
			(xy 121.291858 -256.30759) (xy 121.297328 -256.278308) (xy 121.3174 -256.222229) (xy 121.34721 -256.170663)
			(xy 121.366026 -256.14757) (xy 121.366026 -255.852676) (xy 121.365542 -255.83803) (xy 121.357226 -255.809944)
			(xy 121.341286 -255.78537) (xy 121.31903 -255.766326) (xy 121.292286 -255.754378) (xy 121.263251 -255.750506)
			(xy 121.234311 -255.75503) (xy 121.207843 -255.767576) (xy 121.196608 -255.776984) (xy 121.178337 -255.792726)
			(xy 121.13809 -255.819296) (xy 121.094407 -255.839733) (xy 121.048218 -255.853603) (xy 121.000503 -255.860612)
			(xy 120.97639 -255.861058) (xy 120.950423 -255.860548) (xy 120.899129 -255.852422) (xy 120.849738 -255.836373)
			(xy 120.803465 -255.812795) (xy 120.76145 -255.782268) (xy 120.724728 -255.745545) (xy 120.694202 -255.70353)
			(xy 120.670625 -255.657257) (xy 120.654576 -255.607865) (xy 120.646452 -255.556571) (xy 120.645936 -255.530604)
			(xy 120.645936 -255.53035) (xy 120.64638 -255.505822) (xy 120.653629 -255.457304) (xy 120.667975 -255.410392)
			(xy 120.689103 -255.366118) (xy 120.716547 -255.325456) (xy 120.732804 -255.307084) (xy 120.742606 -255.295594)
			(xy 120.755617 -255.268356) (xy 120.760085 -255.238503) (xy 120.755618 -255.20865) (xy 120.742609 -255.181411)
			(xy 120.732804 -255.169924) (xy 120.716561 -255.15154) (xy 120.689125 -255.110876) (xy 120.667996 -255.066605)
			(xy 120.653639 -255.019698) (xy 120.64637 -254.971185) (xy 120.645936 -254.946658) (xy 120.645936 -254.946404)
			(xy 120.646445 -254.920436) (xy 120.654569 -254.86914) (xy 120.670617 -254.819746) (xy 120.694194 -254.773471)
			(xy 120.72472 -254.731454) (xy 120.761443 -254.694729) (xy 120.803459 -254.664202) (xy 120.849733 -254.640622)
			(xy 120.899127 -254.624572) (xy 120.950422 -254.616446) (xy 120.97639 -254.61595) (xy 120.976644 -254.61595)
			(xy 121.000502 -254.616367) (xy 121.047723 -254.623233) (xy 121.093462 -254.636828) (xy 121.136765 -254.656871)
			(xy 121.156984 -254.669544) (xy 121.170029 -254.67748) (xy 121.199361 -254.685918) (xy 121.229877 -254.685308)
			(xy 121.258848 -254.675703) (xy 121.283684 -254.657963) (xy 121.302166 -254.633673) (xy 121.30786 -254.619506)
			(xy 121.318438 -254.592439) (xy 121.347691 -254.542231) (xy 121.366026 -254.519684) (xy 121.366026 -253.515876)
			(xy 121.365542 -253.50123) (xy 121.357226 -253.473144) (xy 121.341286 -253.44857) (xy 121.31903 -253.429526)
			(xy 121.292286 -253.417578) (xy 121.263251 -253.413706) (xy 121.234311 -253.41823) (xy 121.207843 -253.430776)
			(xy 121.196608 -253.440184) (xy 121.178337 -253.455926) (xy 121.13809 -253.482496) (xy 121.094407 -253.502933)
			(xy 121.048218 -253.516803) (xy 121.000503 -253.523812) (xy 120.97639 -253.524258) (xy 120.950423 -253.523748)
			(xy 120.899129 -253.515622) (xy 120.849738 -253.499573) (xy 120.803465 -253.475995) (xy 120.76145 -253.445468)
			(xy 120.724728 -253.408745) (xy 120.694202 -253.36673) (xy 120.670625 -253.320457) (xy 120.654576 -253.271065)
			(xy 120.646452 -253.219771) (xy 120.645936 -253.193804) (xy 120.645936 -253.19355) (xy 120.64638 -253.169022)
			(xy 120.653629 -253.120504) (xy 120.667975 -253.073592) (xy 120.689103 -253.029318) (xy 120.716547 -252.988656)
			(xy 120.732804 -252.970284) (xy 120.742606 -252.958794) (xy 120.755617 -252.931556) (xy 120.760085 -252.901703)
			(xy 120.755618 -252.87185) (xy 120.742609 -252.844611) (xy 120.732804 -252.833124) (xy 120.716561 -252.81474)
			(xy 120.689125 -252.774076) (xy 120.667996 -252.729805) (xy 120.653639 -252.682898) (xy 120.64637 -252.634385)
			(xy 120.645936 -252.609858) (xy 120.645936 -252.609604) (xy 120.646445 -252.583636) (xy 120.654569 -252.53234)
			(xy 120.670617 -252.482946) (xy 120.694194 -252.436671) (xy 120.72472 -252.394654) (xy 120.761443 -252.357929)
			(xy 120.803459 -252.327402) (xy 120.849733 -252.303822) (xy 120.899127 -252.287772) (xy 120.950422 -252.279646)
			(xy 120.97639 -252.27915) (xy 121.000504 -252.279587) (xy 121.04822 -252.286596) (xy 121.09441 -252.300467)
			(xy 121.138093 -252.320905) (xy 121.178342 -252.347476) (xy 121.196608 -252.363224) (xy 121.207835 -252.372641)
			(xy 121.234299 -252.385199) (xy 121.263239 -252.389728) (xy 121.292274 -252.385858) (xy 121.319016 -252.373905)
			(xy 121.341266 -252.354854) (xy 121.357194 -252.330271) (xy 121.365489 -252.302178) (xy 121.366026 -252.287532)
			(xy 121.366026 -251.763276) (xy 121.365542 -251.74863) (xy 121.357226 -251.720544) (xy 121.341286 -251.69597)
			(xy 121.31903 -251.676926) (xy 121.292286 -251.664978) (xy 121.263251 -251.661106) (xy 121.234311 -251.66563)
			(xy 121.207843 -251.678176) (xy 121.196608 -251.687584) (xy 121.178337 -251.703326) (xy 121.13809 -251.729896)
			(xy 121.094407 -251.750333) (xy 121.048218 -251.764203) (xy 121.000503 -251.771212) (xy 120.97639 -251.771658)
			(xy 120.950423 -251.771148) (xy 120.899129 -251.763022) (xy 120.849738 -251.746973) (xy 120.803465 -251.723395)
			(xy 120.76145 -251.692868) (xy 120.724728 -251.656145) (xy 120.694202 -251.61413) (xy 120.670625 -251.567857)
			(xy 120.654576 -251.518465) (xy 120.646452 -251.467171) (xy 120.645936 -251.441204) (xy 120.645936 -251.44095)
			(xy 120.64638 -251.416422) (xy 120.653629 -251.367904) (xy 120.667975 -251.320992) (xy 120.689103 -251.276718)
			(xy 120.716547 -251.236056) (xy 120.732804 -251.217684) (xy 120.742606 -251.206194) (xy 120.755617 -251.178956)
			(xy 120.760085 -251.149103) (xy 120.755618 -251.11925) (xy 120.742609 -251.092011) (xy 120.732804 -251.080524)
			(xy 120.716561 -251.06214) (xy 120.689125 -251.021476) (xy 120.667996 -250.977205) (xy 120.653639 -250.930298)
			(xy 120.64637 -250.881785) (xy 120.645936 -250.857258) (xy 120.645936 -250.857004) (xy 120.646445 -250.831036)
			(xy 120.654569 -250.77974) (xy 120.670617 -250.730346) (xy 120.694194 -250.684071) (xy 120.72472 -250.642054)
			(xy 120.761443 -250.605329) (xy 120.803459 -250.574802) (xy 120.849733 -250.551222) (xy 120.899127 -250.535172)
			(xy 120.950422 -250.527046) (xy 120.97639 -250.52655) (xy 121.000504 -250.526987) (xy 121.04822 -250.533996)
			(xy 121.09441 -250.547867) (xy 121.138093 -250.568305) (xy 121.178342 -250.594876) (xy 121.196608 -250.610624)
			(xy 121.207835 -250.620041) (xy 121.234299 -250.632599) (xy 121.263239 -250.637128) (xy 121.292274 -250.633258)
			(xy 121.319016 -250.621305) (xy 121.341266 -250.602254) (xy 121.357194 -250.577671) (xy 121.365489 -250.549578)
			(xy 121.366026 -250.534932) (xy 121.366026 -249.918474) (xy 121.34222 -249.906562) (xy 121.298434 -249.876293)
			(xy 121.260068 -249.839395) (xy 121.228115 -249.796823) (xy 121.2034 -249.749679) (xy 121.186564 -249.699182)
			(xy 121.178042 -249.646639) (xy 121.177558 -249.620024) (xy 121.177816 -249.602357) (xy 121.181636 -249.56723)
			(xy 121.185178 -249.54992) (xy 121.187823 -249.53551) (xy 121.185684 -249.506303) (xy 121.175355 -249.478899)
			(xy 121.157684 -249.455545) (xy 121.13412 -249.438157) (xy 121.106594 -249.428159) (xy 121.077363 -249.426372)
			(xy 121.063004 -249.42927) (xy 121.044777 -249.433188) (xy 121.007731 -249.437386) (xy 120.98909 -249.437652)
			(xy 120.963123 -249.437142) (xy 120.91183 -249.429016) (xy 120.862439 -249.412967) (xy 120.816167 -249.389389)
			(xy 120.774153 -249.358863) (xy 120.737431 -249.32214) (xy 120.706906 -249.280125) (xy 120.683329 -249.233852)
			(xy 120.667281 -249.18446) (xy 120.659157 -249.133167) (xy 120.659157 -249.081233) (xy 120.667281 -249.02994)
			(xy 120.683329 -248.980548) (xy 120.706906 -248.934275) (xy 120.737431 -248.89226) (xy 120.774153 -248.855537)
			(xy 120.816167 -248.825011) (xy 120.862439 -248.801433) (xy 120.91183 -248.785384) (xy 120.963123 -248.777258)
			(xy 120.98909 -248.776744) (xy 121.017642 -248.777344) (xy 121.073899 -248.787146) (xy 121.127637 -248.80646)
			(xy 121.177262 -248.834713) (xy 121.199656 -248.852436) (xy 121.211053 -248.861223) (xy 121.237452 -248.872652)
			(xy 121.265991 -248.876261) (xy 121.294403 -248.871764) (xy 121.320433 -248.859519) (xy 121.342012 -248.840497)
			(xy 121.357427 -248.81621) (xy 121.365454 -248.788587) (xy 121.366026 -248.774204) (xy 121.366026 -248.627392)
			(xy 121.365488 -248.612274) (xy 121.35666 -248.583358) (xy 121.33975 -248.558295) (xy 121.316242 -248.539283)
			(xy 121.288197 -248.527988) (xy 121.258074 -248.525403) (xy 121.228514 -248.531753) (xy 121.20211 -248.546481)
			(xy 121.191274 -248.557034) (xy 121.172443 -248.575908) (xy 121.129823 -248.607936) (xy 121.082617 -248.632711)
			(xy 121.032047 -248.649592) (xy 120.979424 -248.65814) (xy 120.952768 -248.658634) (xy 120.926804 -248.658122)
			(xy 120.875516 -248.649995) (xy 120.826131 -248.633944) (xy 120.779864 -248.610366) (xy 120.737855 -248.579841)
			(xy 120.701138 -248.543121) (xy 120.670617 -248.501109) (xy 120.647044 -248.45484) (xy 120.630998 -248.405453)
			(xy 120.622875 -248.354164) (xy 120.622875 -248.302236) (xy 120.630998 -248.250947) (xy 120.647044 -248.20156)
			(xy 120.670617 -248.155291) (xy 120.701138 -248.113279) (xy 120.737855 -248.076559) (xy 120.779864 -248.046034)
			(xy 120.826131 -248.022456) (xy 120.875516 -248.006405) (xy 120.926804 -247.998278) (xy 120.952768 -247.997726)
			(xy 120.953022 -247.997726) (xy 120.978186 -247.998223) (xy 121.02793 -248.005884) (xy 121.052082 -248.012966)
			(xy 121.065973 -248.016799) (xy 121.09477 -248.017405) (xy 121.122594 -248.009954) (xy 121.147235 -247.99504)
			(xy 121.166739 -247.973844) (xy 121.179557 -247.94805) (xy 121.182638 -247.933972) (xy 121.187735 -247.908291)
			(xy 121.204957 -247.85885) (xy 121.229761 -247.812744) (xy 121.261525 -247.771126) (xy 121.299455 -247.735039)
			(xy 121.342601 -247.705384) (xy 121.366026 -247.693688) (xy 121.366026 -247.475756) (xy 121.284238 -247.475756)
			(xy 121.270014 -247.503188) (xy 121.257736 -247.525943) (xy 121.227196 -247.567661) (xy 121.190526 -247.604109)
			(xy 121.148622 -247.634393) (xy 121.102509 -247.657775) (xy 121.053314 -247.673682) (xy 121.002241 -247.681725)
			(xy 120.97639 -247.682258) (xy 120.950423 -247.681748) (xy 120.899129 -247.673622) (xy 120.849738 -247.657573)
			(xy 120.803465 -247.633995) (xy 120.76145 -247.603468) (xy 120.724728 -247.566745) (xy 120.694202 -247.52473)
			(xy 120.670625 -247.478457) (xy 120.654576 -247.429065) (xy 120.646452 -247.377771) (xy 120.645936 -247.351804)
			(xy 120.645936 -247.35155) (xy 120.64638 -247.327022) (xy 120.653629 -247.278504) (xy 120.667975 -247.231592)
			(xy 120.689103 -247.187318) (xy 120.716547 -247.146656) (xy 120.732804 -247.128284) (xy 120.742606 -247.116794)
			(xy 120.755617 -247.089556) (xy 120.760085 -247.059703) (xy 120.755618 -247.02985) (xy 120.742609 -247.002611)
			(xy 120.732804 -246.991124) (xy 120.725084 -246.982554) (xy 120.710718 -246.964505) (xy 120.704102 -246.955056)
			(xy 120.69618 -246.944205) (xy 120.675753 -246.926766) (xy 120.651484 -246.915261) (xy 120.625053 -246.91049)
			(xy 120.598293 -246.912781) (xy 120.573057 -246.921976) (xy 120.561862 -246.929402) (xy 120.540872 -246.943646)
			(xy 120.495443 -246.966213) (xy 120.4471 -246.981575) (xy 120.396978 -246.989372) (xy 120.371616 -246.989854)
			(xy 120.344318 -246.989293) (xy 120.290465 -246.980316) (xy 120.238822 -246.962605) (xy 120.190795 -246.936641)
			(xy 120.147693 -246.903131) (xy 120.128792 -246.883428) (xy 120.118959 -246.873448) (xy 120.095075 -246.858822)
			(xy 120.068119 -246.851223) (xy 120.040113 -246.851223) (xy 120.013157 -246.858822) (xy 119.989273 -246.873448)
			(xy 119.97944 -246.883428) (xy 119.962295 -246.901373) (xy 119.923579 -246.932425) (xy 119.880652 -246.957333)
			(xy 119.834481 -246.975536) (xy 119.786106 -246.986625) (xy 119.736616 -246.990349) (xy 119.687126 -246.986625)
			(xy 119.638751 -246.975536) (xy 119.59258 -246.957333) (xy 119.549653 -246.932425) (xy 119.510937 -246.901373)
			(xy 119.493792 -246.883428) (xy 119.483959 -246.873448) (xy 119.460075 -246.858822) (xy 119.433119 -246.851223)
			(xy 119.405113 -246.851223) (xy 119.378157 -246.858822) (xy 119.354273 -246.873448) (xy 119.34444 -246.883428)
			(xy 119.325529 -246.903124) (xy 119.282434 -246.936645) (xy 119.23441 -246.962621) (xy 119.182769 -246.980342)
			(xy 119.128915 -246.989326) (xy 119.101616 -246.989854) (xy 119.077233 -246.989412) (xy 119.028999 -246.982238)
			(xy 118.982341 -246.968056) (xy 118.938272 -246.947176) (xy 118.897748 -246.920049) (xy 118.861647 -246.887265)
			(xy 118.845838 -246.868696) (xy 118.835917 -246.857461) (xy 118.811 -246.840831) (xy 118.782331 -246.832143)
			(xy 118.752373 -246.832143) (xy 118.723704 -246.840831) (xy 118.698787 -246.857461) (xy 118.688866 -246.868696)
			(xy 118.673089 -246.887297) (xy 118.636994 -246.9201) (xy 118.596467 -246.947239) (xy 118.55239 -246.968122)
			(xy 118.505721 -246.982296) (xy 118.457475 -246.989453) (xy 118.433088 -246.989854) (xy 118.407766 -246.98937)
			(xy 118.357715 -246.981648) (xy 118.309426 -246.966387) (xy 118.264028 -246.943942) (xy 118.222582 -246.914839)
			(xy 118.20398 -246.897652) (xy 118.194115 -246.888775) (xy 118.170891 -246.87595) (xy 118.14515 -246.869533)
			(xy 118.118624 -246.869955) (xy 118.0931 -246.877188) (xy 118.070296 -246.890745) (xy 118.060724 -246.899938)
			(xy 118.041943 -246.918519) (xy 117.999565 -246.95006) (xy 117.952706 -246.974452) (xy 117.902561 -246.991073)
			(xy 117.85041 -246.999499) (xy 117.823996 -247.000014) (xy 117.798032 -246.999505) (xy 117.746744 -246.991381)
			(xy 117.697358 -246.975334) (xy 117.65109 -246.951759) (xy 117.60908 -246.921236) (xy 117.572361 -246.884517)
			(xy 117.541839 -246.842507) (xy 117.518265 -246.796239) (xy 117.502218 -246.746852) (xy 117.494095 -246.695564)
			(xy 117.494095 -246.643636) (xy 117.502218 -246.592348) (xy 117.518265 -246.542961) (xy 117.541839 -246.496693)
			(xy 117.572361 -246.454683) (xy 117.60908 -246.417964) (xy 117.65109 -246.387441) (xy 117.697358 -246.363866)
			(xy 117.746744 -246.347819) (xy 117.798032 -246.339695) (xy 117.823996 -246.339106) (xy 117.849318 -246.339588)
			(xy 117.899372 -246.347308) (xy 117.947663 -246.362566) (xy 117.993065 -246.385007) (xy 118.034515 -246.414107)
			(xy 118.053104 -246.431308) (xy 118.062968 -246.44019) (xy 118.086192 -246.453024) (xy 118.111937 -246.459448)
			(xy 118.138468 -246.459028) (xy 118.163996 -246.451794) (xy 118.186803 -246.438233) (xy 118.19636 -246.429022)
			(xy 118.215139 -246.410437) (xy 118.257515 -246.378888) (xy 118.304373 -246.354489) (xy 118.354519 -246.337863)
			(xy 118.406673 -246.329433) (xy 118.433088 -246.328946) (xy 118.45747 -246.329388) (xy 118.505705 -246.336563)
			(xy 118.552362 -246.350745) (xy 118.596431 -246.371626) (xy 118.636954 -246.398753) (xy 118.673054 -246.431537)
			(xy 118.688866 -246.450104) (xy 118.698787 -246.461339) (xy 118.723704 -246.477969) (xy 118.752373 -246.486657)
			(xy 118.782331 -246.486657) (xy 118.811 -246.477969) (xy 118.835917 -246.461339) (xy 118.845838 -246.450104)
			(xy 118.861616 -246.431503) (xy 118.89771 -246.3987) (xy 118.938237 -246.371562) (xy 118.982314 -246.350679)
			(xy 119.028983 -246.336506) (xy 119.077229 -246.32935) (xy 119.101616 -246.328946) (xy 119.128913 -246.329509)
			(xy 119.182763 -246.338491) (xy 119.234402 -246.356206) (xy 119.282425 -246.382173) (xy 119.325524 -246.415684)
			(xy 119.34444 -246.435372) (xy 119.354273 -246.445352) (xy 119.378157 -246.459978) (xy 119.405113 -246.467577)
			(xy 119.433119 -246.467577) (xy 119.460075 -246.459978) (xy 119.483959 -246.445352) (xy 119.493792 -246.435372)
			(xy 119.510937 -246.417427) (xy 119.549653 -246.386375) (xy 119.59258 -246.361467) (xy 119.638751 -246.343264)
			(xy 119.687126 -246.332175) (xy 119.736616 -246.328451) (xy 119.786106 -246.332175) (xy 119.834481 -246.343264)
			(xy 119.880652 -246.361467) (xy 119.923579 -246.386375) (xy 119.962295 -246.417427) (xy 119.97944 -246.435372)
			(xy 119.989273 -246.445352) (xy 120.013157 -246.459978) (xy 120.040113 -246.467577) (xy 120.068119 -246.467577)
			(xy 120.095075 -246.459978) (xy 120.118959 -246.445352) (xy 120.128792 -246.435372) (xy 120.147703 -246.415678)
			(xy 120.1908 -246.382161) (xy 120.238824 -246.35619) (xy 120.290465 -246.338474) (xy 120.344318 -246.329495)
			(xy 120.371616 -246.328946) (xy 120.398289 -246.329456) (xy 120.450943 -246.33802) (xy 120.50154 -246.354923)
			(xy 120.548769 -246.379727) (xy 120.591405 -246.41179) (xy 120.628342 -246.450279) (xy 120.643904 -246.471948)
			(xy 120.651827 -246.482798) (xy 120.672253 -246.500235) (xy 120.696522 -246.511737) (xy 120.722952 -246.516508)
			(xy 120.74971 -246.514216) (xy 120.774944 -246.50502) (xy 120.786144 -246.497602) (xy 120.807134 -246.483359)
			(xy 120.852563 -246.460792) (xy 120.900906 -246.44543) (xy 120.951028 -246.437634) (xy 120.97639 -246.43715)
			(xy 121.000504 -246.437587) (xy 121.04822 -246.444596) (xy 121.09441 -246.458467) (xy 121.138093 -246.478905)
			(xy 121.178342 -246.505476) (xy 121.196608 -246.521224) (xy 121.21007 -246.507762) (xy 121.199801 -246.485292)
			(xy 121.185302 -246.438066) (xy 121.177993 -246.389207) (xy 121.177558 -246.364506) (xy 121.178098 -246.337897)
			(xy 121.186637 -246.285368) (xy 121.20348 -246.234885) (xy 121.228191 -246.187752) (xy 121.260133 -246.145185)
			(xy 121.29848 -246.108284) (xy 121.342243 -246.078002) (xy 121.366026 -246.066056) (xy 121.366026 -245.921276)
			(xy 121.365542 -245.90663) (xy 121.357226 -245.878544) (xy 121.341286 -245.85397) (xy 121.31903 -245.834926)
			(xy 121.292286 -245.822978) (xy 121.263251 -245.819106) (xy 121.234311 -245.82363) (xy 121.207843 -245.836176)
			(xy 121.196608 -245.845584) (xy 121.178337 -245.861326) (xy 121.13809 -245.887896) (xy 121.094407 -245.908333)
			(xy 121.048218 -245.922203) (xy 121.000503 -245.929212) (xy 120.97639 -245.929658) (xy 120.950423 -245.929148)
			(xy 120.899129 -245.921022) (xy 120.849738 -245.904973) (xy 120.803465 -245.881395) (xy 120.76145 -245.850868)
			(xy 120.724728 -245.814145) (xy 120.694202 -245.77213) (xy 120.670625 -245.725857) (xy 120.654576 -245.676465)
			(xy 120.646452 -245.625171) (xy 120.645936 -245.599204) (xy 120.645936 -245.59895) (xy 120.64638 -245.574422)
			(xy 120.653629 -245.525904) (xy 120.667975 -245.478992) (xy 120.689103 -245.434718) (xy 120.716547 -245.394056)
			(xy 120.732804 -245.375684) (xy 120.742606 -245.364194) (xy 120.755617 -245.336956) (xy 120.760085 -245.307103)
			(xy 120.755618 -245.27725) (xy 120.742609 -245.250011) (xy 120.732804 -245.238524) (xy 120.716546 -245.22012)
			(xy 120.689087 -245.17941) (xy 120.66795 -245.135086) (xy 120.6536 -245.088124) (xy 120.646353 -245.039557)
			(xy 120.645936 -245.015004) (xy 120.646363 -244.99045) (xy 120.65359 -244.941877) (xy 120.667929 -244.89491)
			(xy 120.689065 -244.850584) (xy 120.716532 -244.809876) (xy 120.732804 -244.791484) (xy 120.742606 -244.779994)
			(xy 120.755617 -244.752756) (xy 120.760085 -244.722903) (xy 120.755618 -244.69305) (xy 120.742609 -244.665811)
			(xy 120.732804 -244.654324) (xy 120.716546 -244.63592) (xy 120.689087 -244.59521) (xy 120.66795 -244.550886)
			(xy 120.6536 -244.503924) (xy 120.646353 -244.455357) (xy 120.645936 -244.430804) (xy 120.646363 -244.40625)
			(xy 120.65359 -244.357677) (xy 120.667929 -244.31071) (xy 120.689065 -244.266384) (xy 120.716532 -244.225676)
			(xy 120.732804 -244.207284) (xy 120.742606 -244.195794) (xy 120.755617 -244.168556) (xy 120.760085 -244.138703)
			(xy 120.755618 -244.10885) (xy 120.742609 -244.081611) (xy 120.732804 -244.070124) (xy 120.716561 -244.05174)
			(xy 120.689125 -244.011076) (xy 120.667996 -243.966805) (xy 120.653639 -243.919898) (xy 120.64637 -243.871385)
			(xy 120.645936 -243.846858) (xy 120.645936 -243.846604) (xy 120.646445 -243.820636) (xy 120.654569 -243.76934)
			(xy 120.670617 -243.719946) (xy 120.694194 -243.673671) (xy 120.72472 -243.631654) (xy 120.761443 -243.594929)
			(xy 120.803459 -243.564402) (xy 120.849733 -243.540822) (xy 120.899127 -243.524772) (xy 120.950422 -243.516646)
			(xy 120.97639 -243.51615) (xy 121.000504 -243.516587) (xy 121.04822 -243.523596) (xy 121.09441 -243.537467)
			(xy 121.138093 -243.557905) (xy 121.178342 -243.584476) (xy 121.196608 -243.600224) (xy 121.207835 -243.609641)
			(xy 121.234299 -243.622199) (xy 121.263239 -243.626728) (xy 121.292274 -243.622858) (xy 121.319016 -243.610905)
			(xy 121.341266 -243.591854) (xy 121.357194 -243.567271) (xy 121.365489 -243.539178) (xy 121.366026 -243.524532)
			(xy 121.366026 -243.407438) (xy 121.342223 -243.395523) (xy 121.298444 -243.365249) (xy 121.260083 -243.32835)
			(xy 121.228132 -243.28578) (xy 121.203417 -243.23864) (xy 121.186576 -243.188147) (xy 121.178046 -243.135608)
			(xy 121.178047 -243.082381) (xy 121.186579 -243.029843) (xy 121.203421 -242.979351) (xy 121.228137 -242.932211)
			(xy 121.26009 -242.889642) (xy 121.298452 -242.852744) (xy 121.342232 -242.822472) (xy 121.366026 -242.810538)
			(xy 121.366026 -241.779552) (xy 121.342222 -241.767637) (xy 121.298441 -241.737363) (xy 121.260078 -241.700463)
			(xy 121.228124 -241.657892) (xy 121.203407 -241.61075) (xy 121.186566 -241.560256) (xy 121.178034 -241.507715)
			(xy 121.178034 -241.454486) (xy 121.186565 -241.401946) (xy 121.203407 -241.351452) (xy 121.228124 -241.304309)
			(xy 121.260076 -241.261738) (xy 121.298439 -241.224838) (xy 121.34222 -241.194564) (xy 121.366026 -241.182652)
			(xy 121.366026 -241.00028) (xy 121.365618 -240.986786) (xy 121.358561 -240.960738) (xy 121.34492 -240.937452)
			(xy 121.32565 -240.918558) (xy 121.3021 -240.905379) (xy 121.275918 -240.898837) (xy 121.248936 -240.899391)
			(xy 121.223044 -240.907001) (xy 121.200054 -240.921134) (xy 121.190512 -240.930684) (xy 121.171636 -240.949989)
			(xy 121.12876 -240.982801) (xy 121.081121 -241.008206) (xy 121.029986 -241.025529) (xy 120.976715 -241.034309)
			(xy 120.94972 -241.034824) (xy 120.923751 -241.034343) (xy 120.872451 -241.02622) (xy 120.823053 -241.010171)
			(xy 120.776775 -240.986592) (xy 120.734756 -240.956063) (xy 120.69803 -240.919337) (xy 120.667502 -240.877316)
			(xy 120.643925 -240.831037) (xy 120.627878 -240.78164) (xy 120.619757 -240.730339) (xy 120.619266 -240.70437)
			(xy 120.619266 -240.704116) (xy 120.619713 -240.679589) (xy 120.626967 -240.631074) (xy 120.641318 -240.584166)
			(xy 120.66245 -240.539896) (xy 120.689898 -240.49924) (xy 120.706134 -240.48085) (xy 120.715937 -240.469363)
			(xy 120.728947 -240.442128) (xy 120.73341 -240.412278) (xy 120.728934 -240.382429) (xy 120.715912 -240.3552)
			(xy 120.706134 -240.34369) (xy 120.689892 -240.325306) (xy 120.662457 -240.284642) (xy 120.641331 -240.24037)
			(xy 120.626978 -240.193463) (xy 120.619712 -240.144951) (xy 120.619266 -240.120424) (xy 120.619266 -240.12017)
			(xy 120.619778 -240.094205) (xy 120.627906 -240.042915) (xy 120.643957 -239.993527) (xy 120.667537 -239.947259)
			(xy 120.698064 -239.905249) (xy 120.734787 -239.868532) (xy 120.776802 -239.838011) (xy 120.823074 -239.814438)
			(xy 120.872463 -239.798394) (xy 120.923755 -239.790274) (xy 120.94972 -239.789716) (xy 120.978852 -239.790335)
			(xy 121.036212 -239.800559) (xy 121.063766 -239.810036) (xy 121.076621 -239.814304) (xy 121.103598 -239.816628)
			(xy 121.130237 -239.811783) (xy 121.154668 -239.800108) (xy 121.175172 -239.782424) (xy 121.19031 -239.759974)
			(xy 121.195084 -239.747298) (xy 121.204072 -239.722408) (xy 121.228818 -239.675636) (xy 121.260685 -239.633392)
			(xy 121.298863 -239.596751) (xy 121.342379 -239.566645) (xy 121.366026 -239.554766) (xy 121.366026 -238.524034)
			(xy 121.342223 -238.512119) (xy 121.298445 -238.481845) (xy 121.260085 -238.444947) (xy 121.228134 -238.402377)
			(xy 121.203419 -238.355237) (xy 121.186579 -238.304745) (xy 121.17805 -238.252206) (xy 121.178051 -238.19898)
			(xy 121.186583 -238.146442) (xy 121.203425 -238.095951) (xy 121.228141 -238.048811) (xy 121.260094 -238.006243)
			(xy 121.298456 -237.969346) (xy 121.342235 -237.939074) (xy 121.366026 -237.927134) (xy 121.366026 -237.76178)
			(xy 121.26976 -237.665514) (xy 121.262569 -237.658985) (xy 121.244703 -237.651403) (xy 121.2253 -237.65098)
			(xy 121.207121 -237.657776) (xy 121.199656 -237.66399) (xy 121.181271 -237.680229) (xy 121.140605 -237.707658)
			(xy 121.096333 -237.728778) (xy 121.049427 -237.743125) (xy 121.000916 -237.750385) (xy 120.97639 -237.750858)
			(xy 120.950423 -237.750348) (xy 120.899129 -237.742222) (xy 120.849738 -237.726173) (xy 120.803465 -237.702595)
			(xy 120.76145 -237.672068) (xy 120.724728 -237.635345) (xy 120.694202 -237.59333) (xy 120.670625 -237.547057)
			(xy 120.654576 -237.497665) (xy 120.646452 -237.446371) (xy 120.645936 -237.420404) (xy 120.646383 -237.395877)
			(xy 120.653639 -237.347362) (xy 120.66799 -237.300454) (xy 120.689122 -237.256185) (xy 120.716569 -237.215529)
			(xy 120.732804 -237.197138) (xy 120.76557 -237.161324) (xy 120.565926 -236.96168) (xy 115.76558 -236.96168)
			(xy 115.750547 -236.962221) (xy 115.721783 -236.970976) (xy 115.696813 -236.987723) (xy 115.677796 -237.011011)
			(xy 115.66638 -237.038826) (xy 115.663552 -237.068759) (xy 115.666012 -237.0836) (xy 115.66911 -237.09987)
			(xy 115.672416 -237.132825) (xy 115.672616 -237.149386) (xy 115.672107 -237.175353) (xy 115.663982 -237.226648)
			(xy 115.647934 -237.276041) (xy 115.624356 -237.322315) (xy 115.59383 -237.364331) (xy 115.557107 -237.401054)
			(xy 115.515091 -237.43158) (xy 115.468817 -237.455158) (xy 115.419424 -237.471206) (xy 115.368129 -237.479331)
			(xy 115.316195 -237.479331) (xy 115.2649 -237.471206) (xy 115.215507 -237.455158) (xy 115.169233 -237.43158)
			(xy 115.127217 -237.401054) (xy 115.090494 -237.364331) (xy 115.059968 -237.322315) (xy 115.03639 -237.276041)
			(xy 115.020342 -237.226648) (xy 115.012217 -237.175353) (xy 115.011708 -237.149386) (xy 115.011909 -237.132825)
			(xy 115.015214 -237.099869) (xy 115.018312 -237.0836) (xy 115.020789 -237.068764) (xy 115.017961 -237.038833)
			(xy 115.006541 -237.011022) (xy 114.987519 -236.987741) (xy 114.962543 -236.971006) (xy 114.933776 -236.962269)
			(xy 114.918744 -236.96168) (xy 103.598726 -236.96168) (xy 103.122671 -237.437735) (xy 109.431075 -237.437735)
			(xy 109.431075 -237.385801) (xy 109.4392 -237.334506) (xy 109.455248 -237.285113) (xy 109.478826 -237.238839)
			(xy 109.509352 -237.196823) (xy 109.546075 -237.1601) (xy 109.588091 -237.129574) (xy 109.634365 -237.105996)
			(xy 109.683758 -237.089948) (xy 109.735053 -237.081823) (xy 109.786987 -237.081823) (xy 109.838282 -237.089948)
			(xy 109.887675 -237.105996) (xy 109.933949 -237.129574) (xy 109.975965 -237.1601) (xy 110.012688 -237.196823)
			(xy 110.043214 -237.238839) (xy 110.066792 -237.285113) (xy 110.08284 -237.334506) (xy 110.090965 -237.385801)
			(xy 110.091474 -237.411768) (xy 110.090965 -237.437735) (xy 110.370875 -237.437735) (xy 110.370875 -237.385801)
			(xy 110.379 -237.334506) (xy 110.395048 -237.285113) (xy 110.418626 -237.238839) (xy 110.449152 -237.196823)
			(xy 110.485875 -237.1601) (xy 110.527891 -237.129574) (xy 110.574165 -237.105996) (xy 110.623558 -237.089948)
			(xy 110.674853 -237.081823) (xy 110.726787 -237.081823) (xy 110.778082 -237.089948) (xy 110.827475 -237.105996)
			(xy 110.873749 -237.129574) (xy 110.915765 -237.1601) (xy 110.952488 -237.196823) (xy 110.983014 -237.238839)
			(xy 111.006592 -237.285113) (xy 111.02264 -237.334506) (xy 111.030765 -237.385801) (xy 111.031274 -237.411768)
			(xy 111.030765 -237.437735) (xy 111.310675 -237.437735) (xy 111.310675 -237.385801) (xy 111.3188 -237.334506)
			(xy 111.334848 -237.285113) (xy 111.358426 -237.238839) (xy 111.388952 -237.196823) (xy 111.425675 -237.1601)
			(xy 111.467691 -237.129574) (xy 111.513965 -237.105996) (xy 111.563358 -237.089948) (xy 111.614653 -237.081823)
			(xy 111.666587 -237.081823) (xy 111.717882 -237.089948) (xy 111.767275 -237.105996) (xy 111.813549 -237.129574)
			(xy 111.855565 -237.1601) (xy 111.892288 -237.196823) (xy 111.922814 -237.238839) (xy 111.946392 -237.285113)
			(xy 111.96244 -237.334506) (xy 111.970565 -237.385801) (xy 111.971074 -237.411768) (xy 111.970565 -237.437735)
			(xy 112.250475 -237.437735) (xy 112.250475 -237.385801) (xy 112.2586 -237.334506) (xy 112.274648 -237.285113)
			(xy 112.298226 -237.238839) (xy 112.328752 -237.196823) (xy 112.365475 -237.1601) (xy 112.407491 -237.129574)
			(xy 112.453765 -237.105996) (xy 112.503158 -237.089948) (xy 112.554453 -237.081823) (xy 112.606387 -237.081823)
			(xy 112.657682 -237.089948) (xy 112.707075 -237.105996) (xy 112.753349 -237.129574) (xy 112.795365 -237.1601)
			(xy 112.832088 -237.196823) (xy 112.862614 -237.238839) (xy 112.886192 -237.285113) (xy 112.90224 -237.334506)
			(xy 112.910365 -237.385801) (xy 112.910874 -237.411768) (xy 112.910365 -237.437735) (xy 113.190275 -237.437735)
			(xy 113.190275 -237.385801) (xy 113.1984 -237.334506) (xy 113.214448 -237.285113) (xy 113.238026 -237.238839)
			(xy 113.268552 -237.196823) (xy 113.305275 -237.1601) (xy 113.347291 -237.129574) (xy 113.393565 -237.105996)
			(xy 113.442958 -237.089948) (xy 113.494253 -237.081823) (xy 113.546187 -237.081823) (xy 113.597482 -237.089948)
			(xy 113.646875 -237.105996) (xy 113.693149 -237.129574) (xy 113.735165 -237.1601) (xy 113.771888 -237.196823)
			(xy 113.802414 -237.238839) (xy 113.825992 -237.285113) (xy 113.84204 -237.334506) (xy 113.850165 -237.385801)
			(xy 113.850674 -237.411768) (xy 113.850165 -237.437735) (xy 113.84204 -237.48903) (xy 113.825992 -237.538423)
			(xy 113.802414 -237.584697) (xy 113.771888 -237.626713) (xy 113.735165 -237.663436) (xy 113.693149 -237.693962)
			(xy 113.646875 -237.71754) (xy 113.597482 -237.733588) (xy 113.546187 -237.741713) (xy 113.494253 -237.741713)
			(xy 113.442958 -237.733588) (xy 113.393565 -237.71754) (xy 113.347291 -237.693962) (xy 113.305275 -237.663436)
			(xy 113.268552 -237.626713) (xy 113.238026 -237.584697) (xy 113.214448 -237.538423) (xy 113.1984 -237.48903)
			(xy 113.190275 -237.437735) (xy 112.910365 -237.437735) (xy 112.90224 -237.48903) (xy 112.886192 -237.538423)
			(xy 112.862614 -237.584697) (xy 112.832088 -237.626713) (xy 112.795365 -237.663436) (xy 112.753349 -237.693962)
			(xy 112.707075 -237.71754) (xy 112.657682 -237.733588) (xy 112.606387 -237.741713) (xy 112.554453 -237.741713)
			(xy 112.503158 -237.733588) (xy 112.453765 -237.71754) (xy 112.407491 -237.693962) (xy 112.365475 -237.663436)
			(xy 112.328752 -237.626713) (xy 112.298226 -237.584697) (xy 112.274648 -237.538423) (xy 112.2586 -237.48903)
			(xy 112.250475 -237.437735) (xy 111.970565 -237.437735) (xy 111.96244 -237.48903) (xy 111.946392 -237.538423)
			(xy 111.922814 -237.584697) (xy 111.892288 -237.626713) (xy 111.855565 -237.663436) (xy 111.813549 -237.693962)
			(xy 111.767275 -237.71754) (xy 111.717882 -237.733588) (xy 111.666587 -237.741713) (xy 111.614653 -237.741713)
			(xy 111.563358 -237.733588) (xy 111.513965 -237.71754) (xy 111.467691 -237.693962) (xy 111.425675 -237.663436)
			(xy 111.388952 -237.626713) (xy 111.358426 -237.584697) (xy 111.334848 -237.538423) (xy 111.3188 -237.48903)
			(xy 111.310675 -237.437735) (xy 111.030765 -237.437735) (xy 111.02264 -237.48903) (xy 111.006592 -237.538423)
			(xy 110.983014 -237.584697) (xy 110.952488 -237.626713) (xy 110.915765 -237.663436) (xy 110.873749 -237.693962)
			(xy 110.827475 -237.71754) (xy 110.778082 -237.733588) (xy 110.726787 -237.741713) (xy 110.674853 -237.741713)
			(xy 110.623558 -237.733588) (xy 110.574165 -237.71754) (xy 110.527891 -237.693962) (xy 110.485875 -237.663436)
			(xy 110.449152 -237.626713) (xy 110.418626 -237.584697) (xy 110.395048 -237.538423) (xy 110.379 -237.48903)
			(xy 110.370875 -237.437735) (xy 110.090965 -237.437735) (xy 110.08284 -237.48903) (xy 110.066792 -237.538423)
			(xy 110.043214 -237.584697) (xy 110.012688 -237.626713) (xy 109.975965 -237.663436) (xy 109.933949 -237.693962)
			(xy 109.887675 -237.71754) (xy 109.838282 -237.733588) (xy 109.786987 -237.741713) (xy 109.735053 -237.741713)
			(xy 109.683758 -237.733588) (xy 109.634365 -237.71754) (xy 109.588091 -237.693962) (xy 109.546075 -237.663436)
			(xy 109.509352 -237.626713) (xy 109.478826 -237.584697) (xy 109.455248 -237.538423) (xy 109.4392 -237.48903)
			(xy 109.431075 -237.437735) (xy 103.122671 -237.437735) (xy 103.117396 -237.44301) (xy 103.14432 -237.478316)
			(xy 103.160372 -237.5001) (xy 103.185898 -237.54781) (xy 103.2033 -237.599043) (xy 103.212112 -237.65243)
			(xy 103.212646 -237.679484) (xy 103.212646 -237.679738) (xy 103.212203 -237.704267) (xy 103.204955 -237.752785)
			(xy 103.190609 -237.799698) (xy 103.169482 -237.843972) (xy 103.142037 -237.884634) (xy 103.137849 -237.889366)
			(xy 108.350335 -237.889366) (xy 108.350335 -237.837434) (xy 108.358458 -237.78614) (xy 108.374505 -237.736749)
			(xy 108.39808 -237.690476) (xy 108.428602 -237.64846) (xy 108.465321 -237.611735) (xy 108.507333 -237.581206)
			(xy 108.553603 -237.557624) (xy 108.602992 -237.54157) (xy 108.654284 -237.533439) (xy 108.68025 -237.532926)
			(xy 108.705052 -237.53337) (xy 108.754102 -237.540764) (xy 108.801495 -237.555408) (xy 108.846166 -237.576973)
			(xy 108.887111 -237.604974) (xy 108.923409 -237.638783) (xy 108.954245 -237.677638) (xy 108.978925 -237.720666)
			(xy 108.996895 -237.766901) (xy 109.00775 -237.815303) (xy 109.009942 -237.840012) (xy 109.011363 -237.853971)
			(xy 109.020864 -237.880362) (xy 109.037185 -237.903174) (xy 109.059097 -237.920685) (xy 109.084946 -237.931575)
			(xy 109.112782 -237.935023) (xy 109.140507 -237.930769) (xy 109.153452 -237.925356) (xy 109.175111 -237.91589)
			(xy 109.22045 -237.90253) (xy 109.267233 -237.895786) (xy 109.290866 -237.895384) (xy 109.31684 -237.895788)
			(xy 109.368149 -237.90391) (xy 109.417556 -237.919959) (xy 109.463844 -237.943539) (xy 109.505872 -237.974071)
			(xy 109.542607 -238.010802) (xy 109.573143 -238.052827) (xy 109.596728 -238.099113) (xy 109.612782 -238.148518)
			(xy 109.620909 -238.199826) (xy 109.620909 -238.251774) (xy 109.620904 -238.251805) (xy 109.900721 -238.251805)
			(xy 109.900721 -238.199871) (xy 109.908846 -238.148576) (xy 109.924894 -238.099183) (xy 109.948472 -238.052909)
			(xy 109.978998 -238.010893) (xy 110.015721 -237.97417) (xy 110.057737 -237.943644) (xy 110.104011 -237.920066)
			(xy 110.153404 -237.904018) (xy 110.204699 -237.895893) (xy 110.256633 -237.895893) (xy 110.307928 -237.904018)
			(xy 110.357321 -237.920066) (xy 110.403595 -237.943644) (xy 110.445611 -237.97417) (xy 110.482334 -238.010893)
			(xy 110.51286 -238.052909) (xy 110.536438 -238.099183) (xy 110.552486 -238.148576) (xy 110.560611 -238.199871)
			(xy 110.56112 -238.225838) (xy 110.560611 -238.251805) (xy 110.840521 -238.251805) (xy 110.840521 -238.199871)
			(xy 110.848646 -238.148576) (xy 110.864694 -238.099183) (xy 110.888272 -238.052909) (xy 110.918798 -238.010893)
			(xy 110.955521 -237.97417) (xy 110.997537 -237.943644) (xy 111.043811 -237.920066) (xy 111.093204 -237.904018)
			(xy 111.144499 -237.895893) (xy 111.196433 -237.895893) (xy 111.247728 -237.904018) (xy 111.297121 -237.920066)
			(xy 111.343395 -237.943644) (xy 111.385411 -237.97417) (xy 111.422134 -238.010893) (xy 111.45266 -238.052909)
			(xy 111.476238 -238.099183) (xy 111.492286 -238.148576) (xy 111.500411 -238.199871) (xy 111.50092 -238.225838)
			(xy 111.500411 -238.251805) (xy 111.780321 -238.251805) (xy 111.780321 -238.199871) (xy 111.788446 -238.148576)
			(xy 111.804494 -238.099183) (xy 111.828072 -238.052909) (xy 111.858598 -238.010893) (xy 111.895321 -237.97417)
			(xy 111.937337 -237.943644) (xy 111.983611 -237.920066) (xy 112.033004 -237.904018) (xy 112.084299 -237.895893)
			(xy 112.136233 -237.895893) (xy 112.187528 -237.904018) (xy 112.236921 -237.920066) (xy 112.283195 -237.943644)
			(xy 112.325211 -237.97417) (xy 112.361934 -238.010893) (xy 112.39246 -238.052909) (xy 112.416038 -238.099183)
			(xy 112.432086 -238.148576) (xy 112.440211 -238.199871) (xy 112.44072 -238.225838) (xy 112.440211 -238.251805)
			(xy 112.720121 -238.251805) (xy 112.720121 -238.199871) (xy 112.728246 -238.148576) (xy 112.744294 -238.099183)
			(xy 112.767872 -238.052909) (xy 112.798398 -238.010893) (xy 112.835121 -237.97417) (xy 112.877137 -237.943644)
			(xy 112.923411 -237.920066) (xy 112.972804 -237.904018) (xy 113.024099 -237.895893) (xy 113.076033 -237.895893)
			(xy 113.127328 -237.904018) (xy 113.176721 -237.920066) (xy 113.222995 -237.943644) (xy 113.265011 -237.97417)
			(xy 113.301734 -238.010893) (xy 113.33226 -238.052909) (xy 113.355838 -238.099183) (xy 113.371886 -238.148576)
			(xy 113.380011 -238.199871) (xy 113.38052 -238.225838) (xy 113.380011 -238.251805) (xy 113.659921 -238.251805)
			(xy 113.659921 -238.199871) (xy 113.668046 -238.148576) (xy 113.684094 -238.099183) (xy 113.707672 -238.052909)
			(xy 113.738198 -238.010893) (xy 113.774921 -237.97417) (xy 113.816937 -237.943644) (xy 113.863211 -237.920066)
			(xy 113.912604 -237.904018) (xy 113.963899 -237.895893) (xy 114.015833 -237.895893) (xy 114.067128 -237.904018)
			(xy 114.116521 -237.920066) (xy 114.162795 -237.943644) (xy 114.204811 -237.97417) (xy 114.241534 -238.010893)
			(xy 114.27206 -238.052909) (xy 114.295638 -238.099183) (xy 114.311686 -238.148576) (xy 114.319811 -238.199871)
			(xy 114.32032 -238.225838) (xy 114.319811 -238.251805) (xy 114.311686 -238.3031) (xy 114.295638 -238.352493)
			(xy 114.27206 -238.398767) (xy 114.241534 -238.440783) (xy 114.204811 -238.477506) (xy 114.162795 -238.508032)
			(xy 114.116521 -238.53161) (xy 114.067128 -238.547658) (xy 114.015833 -238.555783) (xy 113.963899 -238.555783)
			(xy 113.912604 -238.547658) (xy 113.863211 -238.53161) (xy 113.816937 -238.508032) (xy 113.774921 -238.477506)
			(xy 113.738198 -238.440783) (xy 113.707672 -238.398767) (xy 113.684094 -238.352493) (xy 113.668046 -238.3031)
			(xy 113.659921 -238.251805) (xy 113.380011 -238.251805) (xy 113.371886 -238.3031) (xy 113.355838 -238.352493)
			(xy 113.33226 -238.398767) (xy 113.301734 -238.440783) (xy 113.265011 -238.477506) (xy 113.222995 -238.508032)
			(xy 113.176721 -238.53161) (xy 113.127328 -238.547658) (xy 113.076033 -238.555783) (xy 113.024099 -238.555783)
			(xy 112.972804 -238.547658) (xy 112.923411 -238.53161) (xy 112.877137 -238.508032) (xy 112.835121 -238.477506)
			(xy 112.798398 -238.440783) (xy 112.767872 -238.398767) (xy 112.744294 -238.352493) (xy 112.728246 -238.3031)
			(xy 112.720121 -238.251805) (xy 112.440211 -238.251805) (xy 112.432086 -238.3031) (xy 112.416038 -238.352493)
			(xy 112.39246 -238.398767) (xy 112.361934 -238.440783) (xy 112.325211 -238.477506) (xy 112.283195 -238.508032)
			(xy 112.236921 -238.53161) (xy 112.187528 -238.547658) (xy 112.136233 -238.555783) (xy 112.084299 -238.555783)
			(xy 112.033004 -238.547658) (xy 111.983611 -238.53161) (xy 111.937337 -238.508032) (xy 111.895321 -238.477506)
			(xy 111.858598 -238.440783) (xy 111.828072 -238.398767) (xy 111.804494 -238.352493) (xy 111.788446 -238.3031)
			(xy 111.780321 -238.251805) (xy 111.500411 -238.251805) (xy 111.492286 -238.3031) (xy 111.476238 -238.352493)
			(xy 111.45266 -238.398767) (xy 111.422134 -238.440783) (xy 111.385411 -238.477506) (xy 111.343395 -238.508032)
			(xy 111.297121 -238.53161) (xy 111.247728 -238.547658) (xy 111.196433 -238.555783) (xy 111.144499 -238.555783)
			(xy 111.093204 -238.547658) (xy 111.043811 -238.53161) (xy 110.997537 -238.508032) (xy 110.955521 -238.477506)
			(xy 110.918798 -238.440783) (xy 110.888272 -238.398767) (xy 110.864694 -238.352493) (xy 110.848646 -238.3031)
			(xy 110.840521 -238.251805) (xy 110.560611 -238.251805) (xy 110.552486 -238.3031) (xy 110.536438 -238.352493)
			(xy 110.51286 -238.398767) (xy 110.482334 -238.440783) (xy 110.445611 -238.477506) (xy 110.403595 -238.508032)
			(xy 110.357321 -238.53161) (xy 110.307928 -238.547658) (xy 110.256633 -238.555783) (xy 110.204699 -238.555783)
			(xy 110.153404 -238.547658) (xy 110.104011 -238.53161) (xy 110.057737 -238.508032) (xy 110.015721 -238.477506)
			(xy 109.978998 -238.440783) (xy 109.948472 -238.398767) (xy 109.924894 -238.352493) (xy 109.908846 -238.3031)
			(xy 109.900721 -238.251805) (xy 109.620904 -238.251805) (xy 109.612782 -238.303082) (xy 109.596728 -238.352487)
			(xy 109.573143 -238.398773) (xy 109.542607 -238.440798) (xy 109.505872 -238.477529) (xy 109.463844 -238.508061)
			(xy 109.417556 -238.531641) (xy 109.368149 -238.54769) (xy 109.31684 -238.555812) (xy 109.290866 -238.556292)
			(xy 109.266065 -238.555817) (xy 109.217017 -238.548426) (xy 109.169626 -238.533785) (xy 109.124956 -238.512223)
			(xy 109.084012 -238.484225) (xy 109.047713 -238.45042) (xy 109.016877 -238.411569) (xy 108.992196 -238.368544)
			(xy 108.974225 -238.322312) (xy 108.963367 -238.273914) (xy 108.961174 -238.249206) (xy 108.959718 -238.235251)
			(xy 108.950223 -238.208863) (xy 108.933908 -238.186053) (xy 108.912003 -238.168542) (xy 108.88616 -238.15765)
			(xy 108.858328 -238.1542) (xy 108.830608 -238.158451) (xy 108.817664 -238.163862) (xy 108.796017 -238.173356)
			(xy 108.750672 -238.186705) (xy 108.703885 -238.193438) (xy 108.68025 -238.193834) (xy 108.654284 -238.193361)
			(xy 108.602992 -238.18523) (xy 108.553603 -238.169176) (xy 108.507333 -238.145594) (xy 108.465321 -238.115065)
			(xy 108.428602 -238.07834) (xy 108.39808 -238.036324) (xy 108.374505 -237.990051) (xy 108.358458 -237.94066)
			(xy 108.350335 -237.889366) (xy 103.137849 -237.889366) (xy 103.125778 -237.903004) (xy 103.115976 -237.914495)
			(xy 103.102964 -237.941734) (xy 103.098493 -237.971588) (xy 103.102957 -238.001444) (xy 103.115962 -238.028686)
			(xy 103.125778 -238.040164) (xy 103.142016 -238.058549) (xy 103.169444 -238.099215) (xy 103.190562 -238.143487)
			(xy 103.204907 -238.190394) (xy 103.212164 -238.238905) (xy 103.212646 -238.26343) (xy 103.212646 -238.263684)
			(xy 103.212164 -238.289654) (xy 103.204041 -238.340954) (xy 103.187993 -238.390353) (xy 103.164414 -238.436632)
			(xy 103.133885 -238.478653) (xy 103.097159 -238.51538) (xy 103.055139 -238.54591) (xy 103.00886 -238.56949)
			(xy 102.959462 -238.585539) (xy 102.908162 -238.593664) (xy 102.882192 -238.594138) (xy 102.881938 -238.594138)
			(xy 102.850695 -238.593387) (xy 102.789323 -238.581628) (xy 102.760018 -238.57077) (xy 102.746682 -238.565958)
			(xy 102.718486 -238.563105) (xy 102.690591 -238.568108) (xy 102.665143 -238.580582) (xy 102.644101 -238.599566)
			(xy 102.629083 -238.6236) (xy 102.621245 -238.650835) (xy 102.620826 -238.665004) (xy 102.620826 -238.938562)
			(xy 102.6214 -238.953874) (xy 102.630569 -238.983097) (xy 102.647978 -239.008296) (xy 102.672066 -239.027213)
			(xy 102.700674 -239.038153) (xy 102.731237 -239.040134) (xy 102.761018 -239.03298) (xy 102.774496 -239.025684)
			(xy 102.800241 -239.011117) (xy 102.855634 -238.990384) (xy 102.913833 -238.979841) (xy 102.943406 -238.979202)
			(xy 102.94366 -238.979202) (xy 102.968188 -238.979647) (xy 103.016706 -238.986897) (xy 103.063618 -239.001243)
			(xy 103.107892 -239.02237) (xy 103.148554 -239.049813) (xy 103.166926 -239.06607) (xy 103.178415 -239.075873)
			(xy 103.205652 -239.088887) (xy 103.235506 -239.093355) (xy 103.26536 -239.088887) (xy 103.292597 -239.075873)
			(xy 103.304086 -239.06607) (xy 103.322489 -239.049809) (xy 103.363198 -239.022346) (xy 103.407521 -239.001207)
			(xy 103.454484 -238.986855) (xy 103.503053 -238.979607) (xy 103.527606 -238.979202) (xy 103.55216 -238.97963)
			(xy 103.600732 -238.986857) (xy 103.647699 -239.001197) (xy 103.692026 -239.022332) (xy 103.732734 -239.049797)
			(xy 103.751126 -239.06607) (xy 103.762615 -239.075873) (xy 103.789852 -239.088887) (xy 103.819706 -239.093355)
			(xy 103.84956 -239.088887) (xy 103.876797 -239.075873) (xy 103.888286 -239.06607) (xy 103.906669 -239.049825)
			(xy 103.947332 -239.022384) (xy 103.991603 -239.001253) (xy 104.03851 -238.986894) (xy 104.087024 -238.979624)
			(xy 104.111552 -238.979202) (xy 104.111806 -238.979202) (xy 104.137776 -238.979712) (xy 104.189077 -238.987838)
			(xy 104.238476 -239.003889) (xy 104.284755 -239.02747) (xy 104.326776 -239.058001) (xy 104.363503 -239.094729)
			(xy 104.394033 -239.13675) (xy 104.417613 -239.18303) (xy 104.433663 -239.232428) (xy 104.441789 -239.28373)
			(xy 104.441789 -239.318871) (xy 104.849621 -239.318871) (xy 104.849621 -239.266929) (xy 104.857747 -239.215626)
			(xy 104.873798 -239.166227) (xy 104.897381 -239.119947) (xy 104.927912 -239.077925) (xy 104.964642 -239.041198)
			(xy 105.006665 -239.010669) (xy 105.052947 -238.98709) (xy 105.102348 -238.971042) (xy 105.153651 -238.962919)
			(xy 105.179622 -238.962438) (xy 105.204173 -238.962903) (xy 105.252738 -238.970139) (xy 105.2997 -238.984477)
			(xy 105.344024 -239.005603) (xy 105.384737 -239.033052) (xy 105.403142 -239.049306) (xy 105.414631 -239.059109)
			(xy 105.441868 -239.072123) (xy 105.471722 -239.076591) (xy 105.501576 -239.072123) (xy 105.528813 -239.059109)
			(xy 105.540302 -239.049306) (xy 105.558687 -239.033025) (xy 105.599397 -239.00556) (xy 105.643725 -238.984426)
			(xy 105.690694 -238.970088) (xy 105.739267 -238.962864) (xy 105.763822 -238.962438) (xy 105.788373 -238.962903)
			(xy 105.836938 -238.970139) (xy 105.8839 -238.984477) (xy 105.928224 -239.005603) (xy 105.968937 -239.033052)
			(xy 105.987342 -239.049306) (xy 105.998831 -239.059109) (xy 106.026068 -239.072123) (xy 106.055922 -239.076591)
			(xy 106.085776 -239.072123) (xy 106.113013 -239.059109) (xy 106.124502 -239.049306) (xy 106.142887 -239.033025)
			(xy 106.183597 -239.00556) (xy 106.227925 -238.984426) (xy 106.274894 -238.970088) (xy 106.323467 -238.962864)
			(xy 106.348022 -238.962438) (xy 106.373987 -238.962965) (xy 106.425279 -238.971092) (xy 106.474667 -238.987142)
			(xy 106.520937 -239.01072) (xy 106.562949 -239.041246) (xy 106.587322 -239.065621) (xy 113.190021 -239.065621)
			(xy 113.190021 -239.013687) (xy 113.198146 -238.962392) (xy 113.214194 -238.912999) (xy 113.237772 -238.866725)
			(xy 113.268298 -238.824709) (xy 113.305021 -238.787986) (xy 113.347037 -238.75746) (xy 113.393311 -238.733882)
			(xy 113.442704 -238.717834) (xy 113.493999 -238.709709) (xy 113.545933 -238.709709) (xy 113.597228 -238.717834)
			(xy 113.646621 -238.733882) (xy 113.692895 -238.75746) (xy 113.734911 -238.787986) (xy 113.771634 -238.824709)
			(xy 113.80216 -238.866725) (xy 113.825738 -238.912999) (xy 113.841786 -238.962392) (xy 113.849911 -239.013687)
			(xy 113.85042 -239.039654) (xy 113.849911 -239.065621) (xy 113.841786 -239.116916) (xy 113.825738 -239.166309)
			(xy 113.80216 -239.212583) (xy 113.771634 -239.254599) (xy 113.734911 -239.291322) (xy 113.692895 -239.321848)
			(xy 113.67186 -239.332566) (xy 117.084363 -239.332566) (xy 117.084363 -239.280634) (xy 117.092487 -239.22934)
			(xy 117.108535 -239.17995) (xy 117.132112 -239.133677) (xy 117.162637 -239.091663) (xy 117.199358 -239.05494)
			(xy 117.241372 -239.024415) (xy 117.287644 -239.000837) (xy 117.337035 -238.984789) (xy 117.388328 -238.976664)
			(xy 117.414294 -238.976154) (xy 117.414548 -238.976154) (xy 117.439075 -238.976589) (xy 117.487588 -238.983858)
			(xy 117.534495 -238.998214) (xy 117.578766 -239.019342) (xy 117.61943 -239.046779) (xy 117.637814 -239.063022)
			(xy 117.649303 -239.072825) (xy 117.67654 -239.085839) (xy 117.706394 -239.090307) (xy 117.736248 -239.085839)
			(xy 117.763485 -239.072825) (xy 117.774974 -239.063022) (xy 117.793373 -239.046757) (xy 117.834079 -239.019289)
			(xy 117.878403 -238.998151) (xy 117.925369 -238.98381) (xy 117.97394 -238.976582) (xy 117.998494 -238.976154)
			(xy 118.023047 -238.976572) (xy 118.071615 -238.983818) (xy 118.118577 -238.998168) (xy 118.1629 -239.019304)
			(xy 118.20361 -239.046763) (xy 118.222014 -239.063022) (xy 118.233503 -239.072825) (xy 118.26074 -239.085839)
			(xy 118.290594 -239.090307) (xy 118.320448 -239.085839) (xy 118.347685 -239.072825) (xy 118.359174 -239.063022)
			(xy 118.377553 -239.046773) (xy 118.418212 -239.019327) (xy 118.462484 -238.998198) (xy 118.509395 -238.98385)
			(xy 118.557912 -238.976599) (xy 118.58244 -238.976154) (xy 118.582694 -238.976154) (xy 118.609772 -238.976723)
			(xy 118.663199 -238.985575) (xy 118.714466 -239.003025) (xy 118.762199 -239.028607) (xy 118.805119 -239.061634)
			(xy 118.823994 -239.081056) (xy 118.83334 -239.090417) (xy 118.85576 -239.104432) (xy 118.881028 -239.112218)
			(xy 118.907449 -239.113253) (xy 118.933248 -239.107467) (xy 118.956696 -239.095249) (xy 118.966742 -239.086644)
			(xy 118.985098 -239.070422) (xy 119.02573 -239.04306) (xy 119.069957 -239.021997) (xy 119.11681 -239.007697)
			(xy 119.165261 -239.000471) (xy 119.189754 -239.00003) (xy 119.212959 -239.000479) (xy 119.258909 -239.007009)
			(xy 119.303497 -239.019891) (xy 119.34585 -239.038873) (xy 119.385137 -239.063583) (xy 119.403114 -239.078262)
			(xy 119.415014 -239.087632) (xy 119.442867 -239.099501) (xy 119.472974 -239.102697) (xy 119.502698 -239.09694)
			(xy 119.529434 -239.082735) (xy 119.540528 -239.07242) (xy 119.559233 -239.054504) (xy 119.601192 -239.024141)
			(xy 119.647373 -239.000693) (xy 119.696645 -238.984735) (xy 119.747804 -238.976657) (xy 119.7737 -238.976154)
			(xy 119.799632 -238.976673) (xy 119.850861 -238.984763) (xy 119.900196 -239.00076) (xy 119.946425 -239.02427)
			(xy 119.988411 -239.054716) (xy 120.007126 -239.072674) (xy 120.018254 -239.082959) (xy 120.044994 -239.097169)
			(xy 120.074729 -239.102891) (xy 120.104833 -239.099621) (xy 120.132645 -239.087646) (xy 120.14454 -239.078262)
			(xy 120.162547 -239.063576) (xy 120.201871 -239.038825) (xy 120.244272 -239.01982) (xy 120.288915 -239.006936)
			(xy 120.334922 -239.000427) (xy 120.358154 -239.00003) (xy 120.384124 -239.000541) (xy 120.435427 -239.00866)
			(xy 120.484827 -239.024705) (xy 120.531109 -239.048281) (xy 120.573132 -239.078808) (xy 120.609862 -239.115533)
			(xy 120.640395 -239.157552) (xy 120.663977 -239.203831) (xy 120.680029 -239.253229) (xy 120.688155 -239.30453)
			(xy 120.688155 -239.35647) (xy 120.680029 -239.407771) (xy 120.663977 -239.457169) (xy 120.640395 -239.503448)
			(xy 120.609862 -239.545467) (xy 120.573132 -239.582192) (xy 120.531109 -239.612719) (xy 120.484827 -239.636295)
			(xy 120.435427 -239.65234) (xy 120.384124 -239.660459) (xy 120.358154 -239.660938) (xy 120.332221 -239.660451)
			(xy 120.28099 -239.652353) (xy 120.231655 -239.63635) (xy 120.185426 -239.612832) (xy 120.143441 -239.582379)
			(xy 120.124728 -239.564418) (xy 120.113637 -239.55409) (xy 120.086884 -239.539885) (xy 120.057138 -239.534171)
			(xy 120.027027 -239.537453) (xy 119.999209 -239.549439) (xy 119.987314 -239.55883) (xy 119.969323 -239.573536)
			(xy 119.929995 -239.598285) (xy 119.88759 -239.617286) (xy 119.842943 -239.630165) (xy 119.796934 -239.636669)
			(xy 119.7737 -239.637062) (xy 119.750494 -239.636642) (xy 119.704542 -239.630105) (xy 119.659954 -239.617216)
			(xy 119.617602 -239.598228) (xy 119.578317 -239.573512) (xy 119.56034 -239.55883) (xy 119.5484 -239.549516)
			(xy 119.520562 -239.537641) (xy 119.490468 -239.534434) (xy 119.460753 -239.540177) (xy 119.43402 -239.554366)
			(xy 119.422926 -239.564672) (xy 119.404212 -239.582578) (xy 119.362254 -239.612939) (xy 119.316075 -239.636387)
			(xy 119.266805 -239.652347) (xy 119.215649 -239.660431) (xy 119.189754 -239.660938) (xy 119.162675 -239.660405)
			(xy 119.109245 -239.651545) (xy 119.057978 -239.634086) (xy 119.010245 -239.608497) (xy 118.967328 -239.575462)
			(xy 118.948454 -239.556036) (xy 118.939155 -239.546626) (xy 118.916721 -239.532614) (xy 118.891441 -239.524835)
			(xy 118.865011 -239.523809) (xy 118.839204 -239.529606) (xy 118.815752 -239.541837) (xy 118.805706 -239.550448)
			(xy 118.78733 -239.566646) (xy 118.746703 -239.594012) (xy 118.702481 -239.615079) (xy 118.655633 -239.629386)
			(xy 118.607186 -239.636618) (xy 118.582694 -239.637062) (xy 118.58244 -239.637062) (xy 118.557915 -239.63657)
			(xy 118.509405 -239.629315) (xy 118.462499 -239.614972) (xy 118.418226 -239.593856) (xy 118.37756 -239.566431)
			(xy 118.359174 -239.550194) (xy 118.347685 -239.540391) (xy 118.320448 -239.527377) (xy 118.290594 -239.522909)
			(xy 118.26074 -239.527377) (xy 118.233503 -239.540391) (xy 118.222014 -239.550194) (xy 118.203622 -239.566467)
			(xy 118.162914 -239.593933) (xy 118.118588 -239.615069) (xy 118.071621 -239.629409) (xy 118.023048 -239.636635)
			(xy 117.998494 -239.637062) (xy 117.973943 -239.636587) (xy 117.925378 -239.629354) (xy 117.878417 -239.615018)
			(xy 117.834093 -239.593894) (xy 117.79338 -239.566447) (xy 117.774974 -239.550194) (xy 117.763485 -239.540391)
			(xy 117.736248 -239.527377) (xy 117.706394 -239.522909) (xy 117.67654 -239.527377) (xy 117.649303 -239.540391)
			(xy 117.637814 -239.550194) (xy 117.619442 -239.566451) (xy 117.57878 -239.593895) (xy 117.534507 -239.615023)
			(xy 117.487594 -239.629369) (xy 117.439076 -239.636618) (xy 117.414548 -239.637062) (xy 117.414294 -239.637062)
			(xy 117.388328 -239.636536) (xy 117.337035 -239.628411) (xy 117.287644 -239.612363) (xy 117.241372 -239.588785)
			(xy 117.199358 -239.55826) (xy 117.162637 -239.521537) (xy 117.132112 -239.479523) (xy 117.108535 -239.43325)
			(xy 117.092487 -239.38386) (xy 117.084363 -239.332566) (xy 113.67186 -239.332566) (xy 113.646621 -239.345426)
			(xy 113.597228 -239.361474) (xy 113.545933 -239.369599) (xy 113.493999 -239.369599) (xy 113.442704 -239.361474)
			(xy 113.393311 -239.345426) (xy 113.347037 -239.321848) (xy 113.305021 -239.291322) (xy 113.268298 -239.254599)
			(xy 113.237772 -239.212583) (xy 113.214194 -239.166309) (xy 113.198146 -239.116916) (xy 113.190021 -239.065621)
			(xy 106.587322 -239.065621) (xy 106.599668 -239.077968) (xy 106.630191 -239.119982) (xy 106.653767 -239.166253)
			(xy 106.669813 -239.215643) (xy 106.677937 -239.266935) (xy 106.677937 -239.318865) (xy 106.669813 -239.370157)
			(xy 106.653767 -239.419547) (xy 106.630191 -239.465818) (xy 106.599668 -239.507832) (xy 106.562949 -239.544554)
			(xy 106.520937 -239.57508) (xy 106.474667 -239.598658) (xy 106.425279 -239.614708) (xy 106.373987 -239.622835)
			(xy 106.348022 -239.623346) (xy 106.32347 -239.622919) (xy 106.274902 -239.615674) (xy 106.22794 -239.601327)
			(xy 106.183617 -239.580193) (xy 106.142906 -239.552736) (xy 106.124502 -239.536478) (xy 106.113013 -239.526675)
			(xy 106.085776 -239.513661) (xy 106.055922 -239.509193) (xy 106.026068 -239.513661) (xy 105.998831 -239.526675)
			(xy 105.987342 -239.536478) (xy 105.968937 -239.552735) (xy 105.928233 -239.580204) (xy 105.88391 -239.601344)
			(xy 105.836946 -239.615686) (xy 105.788375 -239.622917) (xy 105.763822 -239.623346) (xy 105.73927 -239.622919)
			(xy 105.690702 -239.615674) (xy 105.64374 -239.601327) (xy 105.599417 -239.580193) (xy 105.558706 -239.552736)
			(xy 105.540302 -239.536478) (xy 105.528813 -239.526675) (xy 105.501576 -239.513661) (xy 105.471722 -239.509193)
			(xy 105.441868 -239.513661) (xy 105.414631 -239.526675) (xy 105.403142 -239.536478) (xy 105.384737 -239.552735)
			(xy 105.344033 -239.580204) (xy 105.29971 -239.601344) (xy 105.252746 -239.615686) (xy 105.204175 -239.622917)
			(xy 105.179622 -239.623346) (xy 105.153651 -239.622881) (xy 105.102348 -239.614758) (xy 105.052947 -239.59871)
			(xy 105.006665 -239.575131) (xy 104.964642 -239.544602) (xy 104.927912 -239.507875) (xy 104.897381 -239.465853)
			(xy 104.873798 -239.419573) (xy 104.857747 -239.370174) (xy 104.849621 -239.318871) (xy 104.441789 -239.318871)
			(xy 104.441789 -239.33567) (xy 104.433663 -239.386972) (xy 104.417613 -239.43637) (xy 104.394033 -239.48265)
			(xy 104.363503 -239.524671) (xy 104.326776 -239.561399) (xy 104.284755 -239.59193) (xy 104.238476 -239.615511)
			(xy 104.189077 -239.631562) (xy 104.137776 -239.639688) (xy 104.111806 -239.64011) (xy 104.111552 -239.64011)
			(xy 104.087024 -239.639666) (xy 104.038507 -239.632416) (xy 103.991596 -239.618068) (xy 103.947324 -239.596938)
			(xy 103.906665 -239.569491) (xy 103.888286 -239.553242) (xy 103.876797 -239.543439) (xy 103.84956 -239.530425)
			(xy 103.819706 -239.525957) (xy 103.789852 -239.530425) (xy 103.762615 -239.543439) (xy 103.751126 -239.553242)
			(xy 103.732722 -239.569497) (xy 103.69201 -239.596948) (xy 103.647685 -239.618075) (xy 103.600723 -239.632414)
			(xy 103.552157 -239.639649) (xy 103.527606 -239.64011) (xy 103.503052 -239.639683) (xy 103.45448 -239.632455)
			(xy 103.407514 -239.618114) (xy 103.36319 -239.596976) (xy 103.322485 -239.569507) (xy 103.304086 -239.553242)
			(xy 103.292597 -239.543439) (xy 103.26536 -239.530425) (xy 103.235506 -239.525957) (xy 103.205652 -239.530425)
			(xy 103.178415 -239.543439) (xy 103.166926 -239.553242) (xy 103.148541 -239.569481) (xy 103.107876 -239.59691)
			(xy 103.063604 -239.618029) (xy 103.016697 -239.632375) (xy 102.968186 -239.639632) (xy 102.94366 -239.64011)
			(xy 102.943406 -239.64011) (xy 102.913834 -239.639453) (xy 102.855634 -239.628921) (xy 102.800241 -239.608193)
			(xy 102.774496 -239.593628) (xy 102.762772 -239.587103) (xy 102.736954 -239.579826) (xy 102.710132 -239.579523)
			(xy 102.684157 -239.586215) (xy 102.660821 -239.59944) (xy 102.641733 -239.618285) (xy 102.628211 -239.641451)
			(xy 102.621188 -239.667339) (xy 102.620826 -239.68075) (xy 102.620826 -239.879437) (xy 109.900975 -239.879437)
			(xy 109.900975 -239.827503) (xy 109.9091 -239.776208) (xy 109.925148 -239.726815) (xy 109.948726 -239.680541)
			(xy 109.979252 -239.638525) (xy 110.015975 -239.601802) (xy 110.057991 -239.571276) (xy 110.104265 -239.547698)
			(xy 110.153658 -239.53165) (xy 110.204953 -239.523525) (xy 110.256887 -239.523525) (xy 110.308182 -239.53165)
			(xy 110.357575 -239.547698) (xy 110.403849 -239.571276) (xy 110.445865 -239.601802) (xy 110.482588 -239.638525)
			(xy 110.513114 -239.680541) (xy 110.536692 -239.726815) (xy 110.55274 -239.776208) (xy 110.560865 -239.827503)
			(xy 110.561374 -239.85347) (xy 110.560865 -239.879437) (xy 110.55274 -239.930732) (xy 110.536692 -239.980125)
			(xy 110.513114 -240.026399) (xy 110.482588 -240.068415) (xy 110.445865 -240.105138) (xy 110.403849 -240.135664)
			(xy 110.357575 -240.159242) (xy 110.308182 -240.17529) (xy 110.256887 -240.183415) (xy 110.204953 -240.183415)
			(xy 110.153658 -240.17529) (xy 110.104265 -240.159242) (xy 110.057991 -240.135664) (xy 110.015975 -240.105138)
			(xy 109.979252 -240.068415) (xy 109.948726 -240.026399) (xy 109.925148 -239.980125) (xy 109.9091 -239.930732)
			(xy 109.900975 -239.879437) (xy 102.620826 -239.879437) (xy 102.620826 -239.954054) (xy 102.621301 -239.968691)
			(xy 102.629599 -239.996763) (xy 102.645525 -240.021324) (xy 102.667768 -240.040354) (xy 102.694498 -240.052287)
			(xy 102.723516 -240.05614) (xy 102.752434 -240.051596) (xy 102.76586 -240.045748) (xy 102.787974 -240.035814)
			(xy 102.834382 -240.021797) (xy 102.882337 -240.014696) (xy 102.906576 -240.014252) (xy 102.90683 -240.014252)
			(xy 102.932795 -240.014763) (xy 102.984087 -240.022892) (xy 103.033475 -240.038943) (xy 103.079744 -240.062522)
			(xy 103.121755 -240.093049) (xy 103.158474 -240.129772) (xy 103.188996 -240.171787) (xy 103.212571 -240.218059)
			(xy 103.228617 -240.267449) (xy 103.236739 -240.31874) (xy 103.237284 -240.344706) (xy 103.237284 -240.34496)
			(xy 103.236839 -240.369488) (xy 103.229589 -240.418006) (xy 103.215242 -240.464917) (xy 103.194115 -240.509191)
			(xy 103.166671 -240.549852) (xy 103.150416 -240.568226) (xy 103.140614 -240.579715) (xy 103.127603 -240.606952)
			(xy 103.123137 -240.636804) (xy 103.127606 -240.666656) (xy 103.140619 -240.693892) (xy 103.150416 -240.705386)
			(xy 103.166662 -240.723768) (xy 103.194104 -240.764431) (xy 103.215236 -240.808702) (xy 103.229595 -240.85561)
			(xy 103.236865 -240.904124) (xy 103.237284 -240.928652) (xy 103.237284 -240.928906) (xy 103.236774 -240.954874)
			(xy 103.228649 -241.00617) (xy 103.212601 -241.055564) (xy 103.189023 -241.101839) (xy 103.158497 -241.143856)
			(xy 103.12961 -241.172746) (xy 108.095796 -241.172746) (xy 108.096227 -241.148194) (xy 108.103469 -241.099626)
			(xy 108.117814 -241.052664) (xy 108.138948 -241.00834) (xy 108.166406 -240.967629) (xy 108.182664 -240.949226)
			(xy 108.192424 -240.937702) (xy 108.205444 -240.910478) (xy 108.209922 -240.880634) (xy 108.205464 -240.850787)
			(xy 108.192462 -240.823554) (xy 108.182664 -240.812066) (xy 108.166425 -240.793645) (xy 108.138952 -240.752946)
			(xy 108.117808 -240.708627) (xy 108.103461 -240.661666) (xy 108.096227 -240.613098) (xy 108.095796 -240.588546)
			(xy 108.096305 -240.562579) (xy 108.10443 -240.511284) (xy 108.120478 -240.461891) (xy 108.144056 -240.415617)
			(xy 108.174582 -240.373601) (xy 108.211305 -240.336878) (xy 108.253321 -240.306352) (xy 108.299595 -240.282774)
			(xy 108.348988 -240.266726) (xy 108.400283 -240.258601) (xy 108.452217 -240.258601) (xy 108.503512 -240.266726)
			(xy 108.552905 -240.282774) (xy 108.599179 -240.306352) (xy 108.641195 -240.336878) (xy 108.677918 -240.373601)
			(xy 108.708444 -240.415617) (xy 108.732022 -240.461891) (xy 108.74807 -240.511284) (xy 108.756195 -240.562579)
			(xy 108.756704 -240.588546) (xy 108.756268 -240.613098) (xy 108.749028 -240.661666) (xy 108.739302 -240.693507)
			(xy 113.190275 -240.693507) (xy 113.190275 -240.641573) (xy 113.1984 -240.590278) (xy 113.214448 -240.540885)
			(xy 113.238026 -240.494611) (xy 113.268552 -240.452595) (xy 113.305275 -240.415872) (xy 113.347291 -240.385346)
			(xy 113.393565 -240.361768) (xy 113.442958 -240.34572) (xy 113.494253 -240.337595) (xy 113.546187 -240.337595)
			(xy 113.597482 -240.34572) (xy 113.646875 -240.361768) (xy 113.693149 -240.385346) (xy 113.735165 -240.415872)
			(xy 113.771888 -240.452595) (xy 113.802414 -240.494611) (xy 113.825992 -240.540885) (xy 113.84204 -240.590278)
			(xy 113.850165 -240.641573) (xy 113.850674 -240.66754) (xy 113.850165 -240.693507) (xy 113.84204 -240.744802)
			(xy 113.825992 -240.794195) (xy 113.802414 -240.840469) (xy 113.771888 -240.882485) (xy 113.735165 -240.919208)
			(xy 113.693149 -240.949734) (xy 113.646875 -240.973312) (xy 113.597482 -240.98936) (xy 113.546187 -240.997485)
			(xy 113.494253 -240.997485) (xy 113.442958 -240.98936) (xy 113.393565 -240.973312) (xy 113.347291 -240.949734)
			(xy 113.305275 -240.919208) (xy 113.268552 -240.882485) (xy 113.238026 -240.840469) (xy 113.214448 -240.794195)
			(xy 113.1984 -240.744802) (xy 113.190275 -240.693507) (xy 108.739302 -240.693507) (xy 108.734683 -240.708628)
			(xy 108.71355 -240.752952) (xy 108.686094 -240.793662) (xy 108.669836 -240.812066) (xy 108.659987 -240.823519)
			(xy 108.646977 -240.850769) (xy 108.642516 -240.880634) (xy 108.646997 -240.910496) (xy 108.660025 -240.937737)
			(xy 108.669836 -240.949226) (xy 108.686071 -240.96765) (xy 108.713545 -241.008348) (xy 108.734689 -241.052666)
			(xy 108.749037 -241.099627) (xy 108.756273 -241.148194) (xy 108.756704 -241.172746) (xy 108.756195 -241.198713)
			(xy 108.74807 -241.250008) (xy 108.732022 -241.299401) (xy 108.708444 -241.345675) (xy 108.677918 -241.387691)
			(xy 108.641195 -241.424414) (xy 108.599179 -241.45494) (xy 108.552905 -241.478518) (xy 108.503512 -241.494566)
			(xy 108.452217 -241.502691) (xy 108.400283 -241.502691) (xy 108.348988 -241.494566) (xy 108.299595 -241.478518)
			(xy 108.253321 -241.45494) (xy 108.211305 -241.424414) (xy 108.174582 -241.387691) (xy 108.144056 -241.345675)
			(xy 108.120478 -241.299401) (xy 108.10443 -241.250008) (xy 108.096305 -241.198713) (xy 108.095796 -241.172746)
			(xy 103.12961 -241.172746) (xy 103.121775 -241.180582) (xy 103.079759 -241.211111) (xy 103.033486 -241.234691)
			(xy 102.984093 -241.250744) (xy 102.932798 -241.258872) (xy 102.90683 -241.25936) (xy 102.906576 -241.25936)
			(xy 102.882335 -241.258937) (xy 102.834374 -241.25185) (xy 102.787968 -241.237816) (xy 102.76586 -241.227864)
			(xy 102.752432 -241.222039) (xy 102.723523 -241.217532) (xy 102.694522 -241.221402) (xy 102.667807 -241.233333)
			(xy 102.645568 -241.252346) (xy 102.62963 -241.276882) (xy 102.621299 -241.30493) (xy 102.620826 -241.319558)
			(xy 102.620826 -241.507323) (xy 109.900975 -241.507323) (xy 109.900975 -241.455389) (xy 109.9091 -241.404094)
			(xy 109.925148 -241.354701) (xy 109.948726 -241.308427) (xy 109.979252 -241.266411) (xy 110.015975 -241.229688)
			(xy 110.057991 -241.199162) (xy 110.104265 -241.175584) (xy 110.153658 -241.159536) (xy 110.204953 -241.151411)
			(xy 110.256887 -241.151411) (xy 110.308182 -241.159536) (xy 110.357575 -241.175584) (xy 110.403849 -241.199162)
			(xy 110.445865 -241.229688) (xy 110.482588 -241.266411) (xy 110.513114 -241.308427) (xy 110.536692 -241.354701)
			(xy 110.55274 -241.404094) (xy 110.560865 -241.455389) (xy 110.561374 -241.481356) (xy 110.560865 -241.507323)
			(xy 110.55274 -241.558618) (xy 110.536692 -241.608011) (xy 110.513114 -241.654285) (xy 110.504962 -241.665506)
			(xy 115.092988 -241.665506) (xy 115.092988 -241.665252) (xy 115.093414 -241.640724) (xy 115.100684 -241.592211)
			(xy 115.115041 -241.545303) (xy 115.136172 -241.501032) (xy 115.163612 -241.460369) (xy 115.179856 -241.441986)
			(xy 115.189655 -241.430493) (xy 115.202672 -241.403258) (xy 115.207143 -241.373404) (xy 115.202675 -241.343551)
			(xy 115.18966 -241.316314) (xy 115.179856 -241.304826) (xy 115.163613 -241.286442) (xy 115.136165 -241.245785)
			(xy 115.115033 -241.201514) (xy 115.100684 -241.154604) (xy 115.093433 -241.106088) (xy 115.092988 -241.08156)
			(xy 115.092988 -241.081306) (xy 115.093497 -241.055339) (xy 115.101622 -241.004044) (xy 115.11767 -240.954651)
			(xy 115.141248 -240.908377) (xy 115.171774 -240.866361) (xy 115.208497 -240.829638) (xy 115.250513 -240.799112)
			(xy 115.296787 -240.775534) (xy 115.34618 -240.759486) (xy 115.397475 -240.751361) (xy 115.449409 -240.751361)
			(xy 115.500704 -240.759486) (xy 115.550097 -240.775534) (xy 115.596371 -240.799112) (xy 115.638387 -240.829638)
			(xy 115.67511 -240.866361) (xy 115.705636 -240.908377) (xy 115.729214 -240.954651) (xy 115.745262 -241.004044)
			(xy 115.753387 -241.055339) (xy 115.753896 -241.081306) (xy 115.753896 -241.08156) (xy 115.753421 -241.106086)
			(xy 115.746164 -241.154598) (xy 115.731818 -241.201505) (xy 115.710698 -241.245777) (xy 115.683268 -241.286442)
			(xy 115.667028 -241.304826) (xy 115.657218 -241.31631) (xy 115.644205 -241.343549) (xy 115.639737 -241.373404)
			(xy 115.644208 -241.403259) (xy 115.657223 -241.430497) (xy 115.667028 -241.441986) (xy 115.683291 -241.460353)
			(xy 115.710733 -241.501017) (xy 115.731859 -241.545292) (xy 115.746204 -241.592205) (xy 115.753452 -241.640723)
			(xy 115.753896 -241.665252) (xy 115.753896 -241.665506) (xy 115.753387 -241.691473) (xy 115.745262 -241.742768)
			(xy 115.729214 -241.792161) (xy 115.705636 -241.838435) (xy 115.67511 -241.880451) (xy 115.638387 -241.917174)
			(xy 115.596371 -241.9477) (xy 115.550097 -241.971278) (xy 115.500704 -241.987326) (xy 115.449409 -241.995451)
			(xy 115.397475 -241.995451) (xy 115.34618 -241.987326) (xy 115.296787 -241.971278) (xy 115.250513 -241.9477)
			(xy 115.208497 -241.917174) (xy 115.171774 -241.880451) (xy 115.141248 -241.838435) (xy 115.11767 -241.792161)
			(xy 115.101622 -241.742768) (xy 115.093497 -241.691473) (xy 115.092988 -241.665506) (xy 110.504962 -241.665506)
			(xy 110.482588 -241.696301) (xy 110.445865 -241.733024) (xy 110.403849 -241.76355) (xy 110.357575 -241.787128)
			(xy 110.308182 -241.803176) (xy 110.256887 -241.811301) (xy 110.204953 -241.811301) (xy 110.153658 -241.803176)
			(xy 110.104265 -241.787128) (xy 110.057991 -241.76355) (xy 110.015975 -241.733024) (xy 109.979252 -241.696301)
			(xy 109.948726 -241.654285) (xy 109.925148 -241.608011) (xy 109.9091 -241.558618) (xy 109.900975 -241.507323)
			(xy 102.620826 -241.507323) (xy 102.620826 -242.321139) (xy 113.190275 -242.321139) (xy 113.190275 -242.269205)
			(xy 113.1984 -242.21791) (xy 113.214448 -242.168517) (xy 113.238026 -242.122243) (xy 113.268552 -242.080227)
			(xy 113.305275 -242.043504) (xy 113.347291 -242.012978) (xy 113.393565 -241.9894) (xy 113.442958 -241.973352)
			(xy 113.494253 -241.965227) (xy 113.546187 -241.965227) (xy 113.597482 -241.973352) (xy 113.646875 -241.9894)
			(xy 113.693149 -242.012978) (xy 113.735165 -242.043504) (xy 113.771888 -242.080227) (xy 113.802414 -242.122243)
			(xy 113.825992 -242.168517) (xy 113.84204 -242.21791) (xy 113.850165 -242.269205) (xy 113.850674 -242.295172)
			(xy 113.850165 -242.321139) (xy 113.84204 -242.372434) (xy 113.825992 -242.421827) (xy 113.802414 -242.468101)
			(xy 113.771888 -242.510117) (xy 113.735165 -242.54684) (xy 113.693149 -242.577366) (xy 113.646875 -242.600944)
			(xy 113.597482 -242.616992) (xy 113.546187 -242.625117) (xy 113.494253 -242.625117) (xy 113.442958 -242.616992)
			(xy 113.393565 -242.600944) (xy 113.347291 -242.577366) (xy 113.305275 -242.54684) (xy 113.268552 -242.510117)
			(xy 113.238026 -242.468101) (xy 113.214448 -242.421827) (xy 113.1984 -242.372434) (xy 113.190275 -242.321139)
			(xy 102.620826 -242.321139) (xy 102.620826 -243.135209) (xy 109.900975 -243.135209) (xy 109.900975 -243.083275)
			(xy 109.9091 -243.03198) (xy 109.925148 -242.982587) (xy 109.948726 -242.936313) (xy 109.979252 -242.894297)
			(xy 110.015975 -242.857574) (xy 110.057991 -242.827048) (xy 110.104265 -242.80347) (xy 110.153658 -242.787422)
			(xy 110.204953 -242.779297) (xy 110.256887 -242.779297) (xy 110.308182 -242.787422) (xy 110.357575 -242.80347)
			(xy 110.403849 -242.827048) (xy 110.445865 -242.857574) (xy 110.482588 -242.894297) (xy 110.513114 -242.936313)
			(xy 110.536692 -242.982587) (xy 110.538181 -242.98717) (xy 117.494015 -242.98717) (xy 117.494015 -242.93523)
			(xy 117.502141 -242.883929) (xy 117.518191 -242.834531) (xy 117.541771 -242.788252) (xy 117.572301 -242.746231)
			(xy 117.609028 -242.709503) (xy 117.651048 -242.678973) (xy 117.697327 -242.655392) (xy 117.746725 -242.639341)
			(xy 117.798026 -242.631216) (xy 117.823996 -242.630706) (xy 117.849857 -242.631205) (xy 117.900949 -242.639252)
			(xy 117.950163 -242.655163) (xy 117.996294 -242.678552) (xy 118.038216 -242.708845) (xy 118.056914 -242.726718)
			(xy 118.066629 -242.735763) (xy 118.089638 -242.748975) (xy 118.115275 -242.755812) (xy 118.141809 -242.755812)
			(xy 118.167446 -242.748975) (xy 118.190455 -242.735763) (xy 118.20017 -242.726718) (xy 118.218865 -242.708844)
			(xy 118.260794 -242.678561) (xy 118.306927 -242.655178) (xy 118.356138 -242.639264) (xy 118.407228 -242.631207)
			(xy 118.433088 -242.630706) (xy 118.459055 -242.631268) (xy 118.510349 -242.63939) (xy 118.559741 -242.655437)
			(xy 118.606015 -242.679013) (xy 118.648031 -242.709538) (xy 118.684754 -242.74626) (xy 118.71528 -242.788275)
			(xy 118.738858 -242.834548) (xy 118.754907 -242.883939) (xy 118.763031 -242.935233) (xy 118.763031 -242.987167)
			(xy 118.754907 -243.038461) (xy 118.738858 -243.087852) (xy 118.71528 -243.134125) (xy 118.684754 -243.17614)
			(xy 118.648031 -243.212862) (xy 118.606015 -243.243387) (xy 118.559741 -243.266963) (xy 118.510349 -243.28301)
			(xy 118.459055 -243.291132) (xy 118.433088 -243.291614) (xy 118.407227 -243.291119) (xy 118.356135 -243.283071)
			(xy 118.306921 -243.267158) (xy 118.26079 -243.243768) (xy 118.218868 -243.213475) (xy 118.20017 -243.195602)
			(xy 118.190455 -243.186557) (xy 118.167446 -243.173345) (xy 118.141809 -243.166508) (xy 118.115275 -243.166508)
			(xy 118.089638 -243.173345) (xy 118.066629 -243.186557) (xy 118.056914 -243.195602) (xy 118.038229 -243.213487)
			(xy 117.996297 -243.243767) (xy 117.950162 -243.267149) (xy 117.900948 -243.28306) (xy 117.849857 -243.291114)
			(xy 117.823996 -243.291614) (xy 117.798026 -243.291184) (xy 117.746725 -243.283059) (xy 117.697327 -243.267008)
			(xy 117.651048 -243.243427) (xy 117.609028 -243.212897) (xy 117.572301 -243.176169) (xy 117.541771 -243.134148)
			(xy 117.518191 -243.087869) (xy 117.502141 -243.038471) (xy 117.494015 -242.98717) (xy 110.538181 -242.98717)
			(xy 110.55274 -243.03198) (xy 110.560865 -243.083275) (xy 110.561374 -243.109242) (xy 110.560865 -243.135209)
			(xy 110.55274 -243.186504) (xy 110.536692 -243.235897) (xy 110.513114 -243.282171) (xy 110.482588 -243.324187)
			(xy 110.445865 -243.36091) (xy 110.403849 -243.391436) (xy 110.357575 -243.415014) (xy 110.308182 -243.431062)
			(xy 110.256887 -243.439187) (xy 110.204953 -243.439187) (xy 110.153658 -243.431062) (xy 110.104265 -243.415014)
			(xy 110.057991 -243.391436) (xy 110.015975 -243.36091) (xy 109.979252 -243.324187) (xy 109.948726 -243.282171)
			(xy 109.925148 -243.235897) (xy 109.9091 -243.186504) (xy 109.900975 -243.135209) (xy 102.620826 -243.135209)
			(xy 102.620826 -243.949025) (xy 113.190275 -243.949025) (xy 113.190275 -243.897091) (xy 113.1984 -243.845796)
			(xy 113.214448 -243.796403) (xy 113.238026 -243.750129) (xy 113.268552 -243.708113) (xy 113.305275 -243.67139)
			(xy 113.347291 -243.640864) (xy 113.393565 -243.617286) (xy 113.442958 -243.601238) (xy 113.494253 -243.593113)
			(xy 113.546187 -243.593113) (xy 113.597482 -243.601238) (xy 113.646875 -243.617286) (xy 113.693149 -243.640864)
			(xy 113.735165 -243.67139) (xy 113.771888 -243.708113) (xy 113.802414 -243.750129) (xy 113.825992 -243.796403)
			(xy 113.84204 -243.845796) (xy 113.850165 -243.897091) (xy 113.850674 -243.923058) (xy 113.850165 -243.949025)
			(xy 113.84204 -244.00032) (xy 113.825992 -244.049713) (xy 113.802414 -244.095987) (xy 113.771888 -244.138003)
			(xy 113.735165 -244.174726) (xy 113.693149 -244.205252) (xy 113.646875 -244.22883) (xy 113.597482 -244.244878)
			(xy 113.546187 -244.253003) (xy 113.494253 -244.253003) (xy 113.442958 -244.244878) (xy 113.393565 -244.22883)
			(xy 113.347291 -244.205252) (xy 113.305275 -244.174726) (xy 113.268552 -244.138003) (xy 113.238026 -244.095987)
			(xy 113.214448 -244.049713) (xy 113.1984 -244.00032) (xy 113.190275 -243.949025) (xy 102.620826 -243.949025)
			(xy 102.620826 -244.359938) (xy 102.621333 -244.374448) (xy 102.629488 -244.402298) (xy 102.645157 -244.426723)
			(xy 102.66707 -244.445748) (xy 102.693454 -244.457831) (xy 102.722173 -244.461995) (xy 102.750902 -244.457903)
			(xy 102.764336 -244.452394) (xy 102.78582 -244.443108) (xy 102.83075 -244.430003) (xy 102.877079 -244.423368)
			(xy 102.90048 -244.42293) (xy 102.900988 -244.42293) (xy 102.926956 -244.423438) (xy 102.978254 -244.431561)
			(xy 103.027649 -244.447608) (xy 103.073926 -244.471185) (xy 103.115944 -244.501711) (xy 103.152671 -244.538434)
			(xy 103.1832 -244.58045) (xy 103.206781 -244.626725) (xy 103.222832 -244.676119) (xy 103.230959 -244.727416)
			(xy 103.231442 -244.753384) (xy 103.231442 -244.753638) (xy 103.230999 -244.778167) (xy 103.223751 -244.826685)
			(xy 103.209405 -244.873597) (xy 103.188277 -244.917872) (xy 103.160833 -244.958533) (xy 103.144574 -244.976904)
			(xy 103.134764 -244.988391) (xy 103.121739 -245.01563) (xy 103.117265 -245.045488) (xy 103.121732 -245.075348)
			(xy 103.134751 -245.102589) (xy 103.144574 -245.114064) (xy 103.160813 -245.132449) (xy 103.18824 -245.173115)
			(xy 103.209358 -245.217387) (xy 103.223704 -245.264293) (xy 103.230961 -245.312805) (xy 103.231442 -245.33733)
			(xy 103.231442 -245.337584) (xy 103.231258 -245.34749) (xy 108.103416 -245.34749) (xy 108.103868 -245.322938)
			(xy 108.111104 -245.274371) (xy 108.125444 -245.227409) (xy 108.146574 -245.183085) (xy 108.174028 -245.142374)
			(xy 108.190284 -245.12397) (xy 108.200096 -245.112488) (xy 108.213108 -245.085248) (xy 108.217574 -245.055393)
			(xy 108.213104 -245.025538) (xy 108.200088 -244.9983) (xy 108.190284 -244.98681) (xy 108.174005 -244.968423)
			(xy 108.146541 -244.927713) (xy 108.125406 -244.883386) (xy 108.111068 -244.836418) (xy 108.103843 -244.787844)
			(xy 108.103416 -244.76329) (xy 108.103925 -244.737323) (xy 108.11205 -244.686028) (xy 108.128098 -244.636635)
			(xy 108.151676 -244.590361) (xy 108.182202 -244.548345) (xy 108.218925 -244.511622) (xy 108.260941 -244.481096)
			(xy 108.307215 -244.457518) (xy 108.356608 -244.44147) (xy 108.407903 -244.433345) (xy 108.459837 -244.433345)
			(xy 108.511132 -244.44147) (xy 108.560525 -244.457518) (xy 108.606799 -244.481096) (xy 108.648815 -244.511622)
			(xy 108.685538 -244.548345) (xy 108.716064 -244.590361) (xy 108.739642 -244.636635) (xy 108.75569 -244.686028)
			(xy 108.763815 -244.737323) (xy 108.764315 -244.762841) (xy 109.900975 -244.762841) (xy 109.900975 -244.710907)
			(xy 109.9091 -244.659612) (xy 109.925148 -244.610219) (xy 109.948726 -244.563945) (xy 109.979252 -244.521929)
			(xy 110.015975 -244.485206) (xy 110.057991 -244.45468) (xy 110.104265 -244.431102) (xy 110.153658 -244.415054)
			(xy 110.204953 -244.406929) (xy 110.256887 -244.406929) (xy 110.308182 -244.415054) (xy 110.357575 -244.431102)
			(xy 110.403849 -244.45468) (xy 110.445865 -244.485206) (xy 110.482588 -244.521929) (xy 110.513114 -244.563945)
			(xy 110.536692 -244.610219) (xy 110.55274 -244.659612) (xy 110.560865 -244.710907) (xy 110.561374 -244.736874)
			(xy 110.560865 -244.762841) (xy 110.55274 -244.814136) (xy 110.536692 -244.863529) (xy 110.513114 -244.909803)
			(xy 110.482588 -244.951819) (xy 110.445865 -244.988542) (xy 110.403849 -245.019068) (xy 110.357575 -245.042646)
			(xy 110.308182 -245.058694) (xy 110.256887 -245.066819) (xy 110.204953 -245.066819) (xy 110.153658 -245.058694)
			(xy 110.104265 -245.042646) (xy 110.057991 -245.019068) (xy 110.015975 -244.988542) (xy 109.979252 -244.951819)
			(xy 109.948726 -244.909803) (xy 109.925148 -244.863529) (xy 109.9091 -244.814136) (xy 109.900975 -244.762841)
			(xy 108.764315 -244.762841) (xy 108.764324 -244.76329) (xy 108.763909 -244.787843) (xy 108.756663 -244.836411)
			(xy 108.742313 -244.883373) (xy 108.721176 -244.927697) (xy 108.693715 -244.968407) (xy 108.677456 -244.98681)
			(xy 108.66766 -244.998306) (xy 108.654641 -245.02554) (xy 108.650169 -245.055393) (xy 108.654636 -245.085246)
			(xy 108.667651 -245.112482) (xy 108.677456 -245.12397) (xy 108.693715 -245.142374) (xy 108.721185 -245.183078)
			(xy 108.742324 -245.227401) (xy 108.756666 -245.274366) (xy 108.763896 -245.322937) (xy 108.764324 -245.34749)
			(xy 108.763815 -245.373457) (xy 108.75569 -245.424752) (xy 108.739642 -245.474145) (xy 108.716064 -245.520419)
			(xy 108.685538 -245.562435) (xy 108.671062 -245.576911) (xy 113.190275 -245.576911) (xy 113.190275 -245.524977)
			(xy 113.1984 -245.473682) (xy 113.214448 -245.424289) (xy 113.238026 -245.378015) (xy 113.268552 -245.335999)
			(xy 113.305275 -245.299276) (xy 113.347291 -245.26875) (xy 113.393565 -245.245172) (xy 113.442958 -245.229124)
			(xy 113.494253 -245.220999) (xy 113.546187 -245.220999) (xy 113.597482 -245.229124) (xy 113.646875 -245.245172)
			(xy 113.693149 -245.26875) (xy 113.735165 -245.299276) (xy 113.771888 -245.335999) (xy 113.802414 -245.378015)
			(xy 113.811968 -245.396766) (xy 115.085368 -245.396766) (xy 115.085368 -245.396512) (xy 115.085835 -245.371986)
			(xy 115.093096 -245.323474) (xy 115.107444 -245.276568) (xy 115.128565 -245.232296) (xy 115.155996 -245.19163)
			(xy 115.172236 -245.173246) (xy 115.182076 -245.161784) (xy 115.195091 -245.134538) (xy 115.199555 -245.104675)
			(xy 115.195076 -245.074814) (xy 115.182048 -245.047574) (xy 115.172236 -245.036086) (xy 115.15597 -245.017721)
			(xy 115.128526 -244.977058) (xy 115.1074 -244.932782) (xy 115.093056 -244.885869) (xy 115.08581 -244.837349)
			(xy 115.085368 -244.81282) (xy 115.085368 -244.812566) (xy 115.085877 -244.786599) (xy 115.094002 -244.735304)
			(xy 115.11005 -244.685911) (xy 115.133628 -244.639637) (xy 115.164154 -244.597621) (xy 115.200877 -244.560898)
			(xy 115.242893 -244.530372) (xy 115.289167 -244.506794) (xy 115.33856 -244.490746) (xy 115.389855 -244.482621)
			(xy 115.441789 -244.482621) (xy 115.493084 -244.490746) (xy 115.542477 -244.506794) (xy 115.588751 -244.530372)
			(xy 115.630767 -244.560898) (xy 115.66749 -244.597621) (xy 115.698016 -244.639637) (xy 115.721594 -244.685911)
			(xy 115.737642 -244.735304) (xy 115.745767 -244.786599) (xy 115.746276 -244.812566) (xy 115.746276 -244.81282)
			(xy 115.745817 -244.837346) (xy 115.738553 -244.885858) (xy 115.724202 -244.932764) (xy 115.703079 -244.977036)
			(xy 115.675648 -245.017701) (xy 115.659408 -245.036086) (xy 115.649639 -245.047602) (xy 115.636624 -245.07483)
			(xy 115.63215 -245.104675) (xy 115.636609 -245.134522) (xy 115.649611 -245.161757) (xy 115.659408 -245.173246)
			(xy 115.675649 -245.191632) (xy 115.703095 -245.23229) (xy 115.724225 -245.27656) (xy 115.738575 -245.323469)
			(xy 115.745829 -245.371985) (xy 115.746276 -245.396512) (xy 115.746276 -245.396766) (xy 115.745767 -245.422733)
			(xy 115.737642 -245.474028) (xy 115.721594 -245.523421) (xy 115.698016 -245.569695) (xy 115.66749 -245.611711)
			(xy 115.630767 -245.648434) (xy 115.588751 -245.67896) (xy 115.542477 -245.702538) (xy 115.493084 -245.718586)
			(xy 115.441789 -245.726711) (xy 115.389855 -245.726711) (xy 115.33856 -245.718586) (xy 115.289167 -245.702538)
			(xy 115.242893 -245.67896) (xy 115.200877 -245.648434) (xy 115.164154 -245.611711) (xy 115.133628 -245.569695)
			(xy 115.11005 -245.523421) (xy 115.094002 -245.474028) (xy 115.085877 -245.422733) (xy 115.085368 -245.396766)
			(xy 113.811968 -245.396766) (xy 113.825992 -245.424289) (xy 113.84204 -245.473682) (xy 113.850165 -245.524977)
			(xy 113.850674 -245.550944) (xy 113.850165 -245.576911) (xy 113.84204 -245.628206) (xy 113.825992 -245.677599)
			(xy 113.802414 -245.723873) (xy 113.771888 -245.765889) (xy 113.735165 -245.802612) (xy 113.693149 -245.833138)
			(xy 113.646875 -245.856716) (xy 113.597482 -245.872764) (xy 113.546187 -245.880889) (xy 113.494253 -245.880889)
			(xy 113.442958 -245.872764) (xy 113.393565 -245.856716) (xy 113.347291 -245.833138) (xy 113.305275 -245.802612)
			(xy 113.268552 -245.765889) (xy 113.238026 -245.723873) (xy 113.214448 -245.677599) (xy 113.1984 -245.628206)
			(xy 113.190275 -245.576911) (xy 108.671062 -245.576911) (xy 108.648815 -245.599158) (xy 108.606799 -245.629684)
			(xy 108.560525 -245.653262) (xy 108.511132 -245.66931) (xy 108.459837 -245.677435) (xy 108.407903 -245.677435)
			(xy 108.356608 -245.66931) (xy 108.307215 -245.653262) (xy 108.260941 -245.629684) (xy 108.218925 -245.599158)
			(xy 108.182202 -245.562435) (xy 108.151676 -245.520419) (xy 108.128098 -245.474145) (xy 108.11205 -245.424752)
			(xy 108.103925 -245.373457) (xy 108.103416 -245.34749) (xy 103.231258 -245.34749) (xy 103.23096 -245.363554)
			(xy 103.222837 -245.414854) (xy 103.206789 -245.464252) (xy 103.18321 -245.510531) (xy 103.152681 -245.552551)
			(xy 103.115954 -245.589278) (xy 103.073934 -245.619808) (xy 103.027656 -245.643387) (xy 102.978258 -245.659436)
			(xy 102.926958 -245.66756) (xy 102.900988 -245.668038) (xy 102.90048 -245.668038) (xy 102.877078 -245.667616)
			(xy 102.830746 -245.66098) (xy 102.785815 -245.647874) (xy 102.764336 -245.638574) (xy 102.750912 -245.633053)
			(xy 102.722186 -245.628992) (xy 102.693477 -245.633174) (xy 102.667103 -245.645261) (xy 102.645193 -245.664278)
			(xy 102.629516 -245.688689) (xy 102.621337 -245.716524) (xy 102.620826 -245.73103) (xy 102.620826 -246.237506)
			(xy 102.621373 -246.252667) (xy 102.630264 -246.281655) (xy 102.647287 -246.306745) (xy 102.670936 -246.32572)
			(xy 102.69912 -246.3369) (xy 102.729346 -246.339296) (xy 102.74427 -246.336566) (xy 102.761828 -246.332966)
			(xy 102.797468 -246.32915) (xy 102.81539 -246.328946) (xy 102.839944 -246.329373) (xy 102.888517 -246.336599)
			(xy 102.935484 -246.350938) (xy 102.979811 -246.372074) (xy 103.020519 -246.39954) (xy 103.03891 -246.415814)
			(xy 103.050399 -246.425617) (xy 103.077636 -246.438631) (xy 103.10749 -246.443099) (xy 103.137344 -246.438631)
			(xy 103.164581 -246.425617) (xy 103.17607 -246.415814) (xy 103.194475 -246.399561) (xy 103.235188 -246.372113)
			(xy 103.279513 -246.350988) (xy 103.326474 -246.336651) (xy 103.375039 -246.329416) (xy 103.39959 -246.328946)
			(xy 103.424144 -246.329373) (xy 103.472717 -246.336599) (xy 103.519684 -246.350938) (xy 103.564011 -246.372074)
			(xy 103.604719 -246.39954) (xy 103.62311 -246.415814) (xy 103.634599 -246.425617) (xy 103.661836 -246.438631)
			(xy 103.69169 -246.443099) (xy 103.721544 -246.438631) (xy 103.748781 -246.425617) (xy 103.76027 -246.415814)
			(xy 103.778675 -246.399561) (xy 103.819388 -246.372113) (xy 103.863713 -246.350988) (xy 103.910674 -246.336651)
			(xy 103.959239 -246.329416) (xy 103.98379 -246.328946) (xy 104.008344 -246.329373) (xy 104.056917 -246.336599)
			(xy 104.103884 -246.350938) (xy 104.148211 -246.372074) (xy 104.188919 -246.39954) (xy 104.20731 -246.415814)
			(xy 104.218799 -246.425617) (xy 104.246036 -246.438631) (xy 104.27589 -246.443099) (xy 104.305744 -246.438631)
			(xy 104.332981 -246.425617) (xy 104.34447 -246.415814) (xy 104.362855 -246.399576) (xy 104.403522 -246.37215)
			(xy 104.447794 -246.351034) (xy 104.4947 -246.33669) (xy 104.543211 -246.329433) (xy 104.567736 -246.328946)
			(xy 104.56799 -246.328946) (xy 104.593401 -246.329411) (xy 104.643623 -246.33719) (xy 104.692062 -246.352567)
			(xy 104.737576 -246.375179) (xy 104.779091 -246.404492) (xy 104.81563 -246.439815) (xy 104.831388 -246.459756)
			(xy 104.841095 -246.471726) (xy 104.866139 -246.489659) (xy 104.895391 -246.49931) (xy 104.92619 -246.499801)
			(xy 104.955735 -246.491087) (xy 104.981338 -246.473961) (xy 104.991408 -246.462296) (xy 105.007177 -246.443417)
			(xy 105.043355 -246.410091) (xy 105.084078 -246.382503) (xy 105.128443 -246.361263) (xy 105.17547 -246.346842)
			(xy 105.224116 -246.339559) (xy 105.24871 -246.339106) (xy 105.274463 -246.339599) (xy 105.325345 -246.347588)
			(xy 105.374373 -246.363372) (xy 105.420359 -246.386568) (xy 105.462192 -246.416616) (xy 105.480866 -246.434356)
			(xy 105.490556 -246.443349) (xy 105.513488 -246.456481) (xy 105.539027 -246.463276) (xy 105.565453 -246.463276)
			(xy 105.590992 -246.456481) (xy 105.613924 -246.443349) (xy 105.623614 -246.434356) (xy 105.642287 -246.416612)
			(xy 105.684113 -246.386549) (xy 105.730098 -246.363342) (xy 105.779129 -246.347555) (xy 105.830015 -246.339571)
			(xy 105.85577 -246.339106) (xy 105.881744 -246.339587) (xy 105.933053 -246.347709) (xy 105.982459 -246.363758)
			(xy 106.028747 -246.387339) (xy 106.033411 -246.390727) (xy 109.900975 -246.390727) (xy 109.900975 -246.338793)
			(xy 109.9091 -246.287498) (xy 109.925148 -246.238105) (xy 109.948726 -246.191831) (xy 109.979252 -246.149815)
			(xy 110.015975 -246.113092) (xy 110.057991 -246.082566) (xy 110.104265 -246.058988) (xy 110.153658 -246.04294)
			(xy 110.204953 -246.034815) (xy 110.256887 -246.034815) (xy 110.308182 -246.04294) (xy 110.357575 -246.058988)
			(xy 110.403849 -246.082566) (xy 110.445865 -246.113092) (xy 110.482588 -246.149815) (xy 110.513114 -246.191831)
			(xy 110.536692 -246.238105) (xy 110.55274 -246.287498) (xy 110.560865 -246.338793) (xy 110.561374 -246.36476)
			(xy 110.560865 -246.390727) (xy 110.55274 -246.442022) (xy 110.536692 -246.491415) (xy 110.513114 -246.537689)
			(xy 110.482588 -246.579705) (xy 110.445865 -246.616428) (xy 110.403849 -246.646954) (xy 110.357575 -246.670532)
			(xy 110.308182 -246.68658) (xy 110.256887 -246.694705) (xy 110.204953 -246.694705) (xy 110.153658 -246.68658)
			(xy 110.104265 -246.670532) (xy 110.057991 -246.646954) (xy 110.015975 -246.616428) (xy 109.979252 -246.579705)
			(xy 109.948726 -246.537689) (xy 109.925148 -246.491415) (xy 109.9091 -246.442022) (xy 109.900975 -246.390727)
			(xy 106.033411 -246.390727) (xy 106.070775 -246.417871) (xy 106.10751 -246.454602) (xy 106.138045 -246.496628)
			(xy 106.16163 -246.542913) (xy 106.177684 -246.592318) (xy 106.185811 -246.643626) (xy 106.185811 -246.695574)
			(xy 106.177684 -246.746882) (xy 106.16163 -246.796287) (xy 106.138045 -246.842572) (xy 106.10751 -246.884598)
			(xy 106.070775 -246.921329) (xy 106.028747 -246.951861) (xy 105.982459 -246.975442) (xy 105.933053 -246.991491)
			(xy 105.881744 -246.999613) (xy 105.85577 -247.000014) (xy 105.830018 -246.99952) (xy 105.779137 -246.991528)
			(xy 105.73011 -246.975743) (xy 105.684125 -246.952546) (xy 105.642294 -246.922498) (xy 105.623614 -246.904764)
			(xy 105.613924 -246.895771) (xy 105.590992 -246.882639) (xy 105.565453 -246.875844) (xy 105.539027 -246.875844)
			(xy 105.513488 -246.882639) (xy 105.490556 -246.895771) (xy 105.480866 -246.904764) (xy 105.462192 -246.922506)
			(xy 105.420365 -246.952565) (xy 105.374379 -246.975767) (xy 105.325349 -246.99155) (xy 105.274464 -246.999531)
			(xy 105.24871 -247.000014) (xy 105.223299 -246.999549) (xy 105.173075 -246.991771) (xy 105.124634 -246.976396)
			(xy 105.079117 -246.953787) (xy 105.037598 -246.924477) (xy 105.001055 -246.889157) (xy 104.985312 -246.869204)
			(xy 104.975603 -246.857238) (xy 104.950558 -246.839312) (xy 104.921307 -246.829665) (xy 104.890511 -246.829174)
			(xy 104.860968 -246.837884) (xy 104.835364 -246.855003) (xy 104.825292 -246.866664) (xy 104.809524 -246.885545)
			(xy 104.773348 -246.918875) (xy 104.732626 -246.946466) (xy 104.68826 -246.967709) (xy 104.641232 -246.982132)
			(xy 104.592585 -246.989416) (xy 104.56799 -246.989854) (xy 104.567736 -246.989854) (xy 104.543208 -246.989409)
			(xy 104.494691 -246.982158) (xy 104.447781 -246.96781) (xy 104.403509 -246.94668) (xy 104.36285 -246.919234)
			(xy 104.34447 -246.902986) (xy 104.332981 -246.893183) (xy 104.305744 -246.880169) (xy 104.27589 -246.875701)
			(xy 104.246036 -246.880169) (xy 104.218799 -246.893183) (xy 104.20731 -246.902986) (xy 104.188906 -246.919244)
			(xy 104.148196 -246.946702) (xy 104.103872 -246.967838) (xy 104.05691 -246.982186) (xy 104.008343 -246.989432)
			(xy 103.98379 -246.989854) (xy 103.959236 -246.989426) (xy 103.910665 -246.982197) (xy 103.863699 -246.967856)
			(xy 103.819375 -246.946718) (xy 103.778669 -246.91925) (xy 103.76027 -246.902986) (xy 103.748781 -246.893183)
			(xy 103.721544 -246.880169) (xy 103.69169 -246.875701) (xy 103.661836 -246.880169) (xy 103.634599 -246.893183)
			(xy 103.62311 -246.902986) (xy 103.604706 -246.919244) (xy 103.563996 -246.946702) (xy 103.519672 -246.967838)
			(xy 103.47271 -246.982186) (xy 103.424143 -246.989432) (xy 103.39959 -246.989854) (xy 103.375036 -246.989426)
			(xy 103.326465 -246.982197) (xy 103.279499 -246.967856) (xy 103.235175 -246.946718) (xy 103.194469 -246.91925)
			(xy 103.17607 -246.902986) (xy 103.164581 -246.893183) (xy 103.137344 -246.880169) (xy 103.10749 -246.875701)
			(xy 103.077636 -246.880169) (xy 103.050399 -246.893183) (xy 103.03891 -246.902986) (xy 103.020506 -246.919244)
			(xy 102.979796 -246.946702) (xy 102.935472 -246.967838) (xy 102.88851 -246.982186) (xy 102.839943 -246.989432)
			(xy 102.81539 -246.989854) (xy 102.797468 -246.98964) (xy 102.761829 -246.985825) (xy 102.74427 -246.982234)
			(xy 102.72936 -246.979531) (xy 102.699174 -246.981999) (xy 102.671036 -246.993204) (xy 102.647419 -247.012164)
			(xy 102.630395 -247.037213) (xy 102.62146 -247.066152) (xy 102.620826 -247.081294) (xy 102.620826 -247.204543)
			(xy 113.190275 -247.204543) (xy 113.190275 -247.152609) (xy 113.1984 -247.101314) (xy 113.214448 -247.051921)
			(xy 113.238026 -247.005647) (xy 113.268552 -246.963631) (xy 113.305275 -246.926908) (xy 113.347291 -246.896382)
			(xy 113.393565 -246.872804) (xy 113.442958 -246.856756) (xy 113.494253 -246.848631) (xy 113.546187 -246.848631)
			(xy 113.597482 -246.856756) (xy 113.646875 -246.872804) (xy 113.693149 -246.896382) (xy 113.735165 -246.926908)
			(xy 113.771888 -246.963631) (xy 113.802414 -247.005647) (xy 113.825992 -247.051921) (xy 113.84204 -247.101314)
			(xy 113.850165 -247.152609) (xy 113.850674 -247.178576) (xy 113.850165 -247.204543) (xy 113.84204 -247.255838)
			(xy 113.825992 -247.305231) (xy 113.802414 -247.351505) (xy 113.771888 -247.393521) (xy 113.735165 -247.430244)
			(xy 113.693149 -247.46077) (xy 113.646875 -247.484348) (xy 113.597482 -247.500396) (xy 113.546187 -247.508521)
			(xy 113.494253 -247.508521) (xy 113.442958 -247.500396) (xy 113.393565 -247.484348) (xy 113.347291 -247.46077)
			(xy 113.305275 -247.430244) (xy 113.268552 -247.393521) (xy 113.238026 -247.351505) (xy 113.214448 -247.305231)
			(xy 113.1984 -247.255838) (xy 113.190275 -247.204543) (xy 102.620826 -247.204543) (xy 102.620826 -248.018359)
			(xy 109.900975 -248.018359) (xy 109.900975 -247.966425) (xy 109.9091 -247.91513) (xy 109.925148 -247.865737)
			(xy 109.948726 -247.819463) (xy 109.979252 -247.777447) (xy 110.015975 -247.740724) (xy 110.057991 -247.710198)
			(xy 110.104265 -247.68662) (xy 110.153658 -247.670572) (xy 110.204953 -247.662447) (xy 110.256887 -247.662447)
			(xy 110.308182 -247.670572) (xy 110.357575 -247.68662) (xy 110.403849 -247.710198) (xy 110.445865 -247.740724)
			(xy 110.482588 -247.777447) (xy 110.513114 -247.819463) (xy 110.536692 -247.865737) (xy 110.55274 -247.91513)
			(xy 110.560865 -247.966425) (xy 110.561374 -247.992392) (xy 110.560865 -248.018359) (xy 110.55274 -248.069654)
			(xy 110.536692 -248.119047) (xy 110.513114 -248.165321) (xy 110.482588 -248.207337) (xy 110.445865 -248.24406)
			(xy 110.403849 -248.274586) (xy 110.357575 -248.298164) (xy 110.308182 -248.314212) (xy 110.256887 -248.322337)
			(xy 110.204953 -248.322337) (xy 110.153658 -248.314212) (xy 110.104265 -248.298164) (xy 110.057991 -248.274586)
			(xy 110.015975 -248.24406) (xy 109.979252 -248.207337) (xy 109.948726 -248.165321) (xy 109.925148 -248.119047)
			(xy 109.9091 -248.069654) (xy 109.900975 -248.018359) (xy 102.620826 -248.018359) (xy 102.620826 -248.241058)
			(xy 102.621218 -248.254394) (xy 102.628119 -248.280158) (xy 102.641459 -248.303254) (xy 102.660329 -248.322104)
			(xy 102.683438 -248.335421) (xy 102.709209 -248.342295) (xy 102.735881 -248.342257) (xy 102.748842 -248.339102)
			(xy 102.769905 -248.333775) (xy 102.812971 -248.328042) (xy 102.834694 -248.327672) (xy 102.860663 -248.328154)
			(xy 102.911961 -248.336279) (xy 102.961357 -248.352329) (xy 103.007633 -248.375908) (xy 103.049651 -248.406437)
			(xy 103.086376 -248.443164) (xy 103.116902 -248.485184) (xy 103.140479 -248.531462) (xy 103.156526 -248.580858)
			(xy 103.164647 -248.632157) (xy 103.165148 -248.658126) (xy 103.165148 -248.65838) (xy 103.164702 -248.682907)
			(xy 103.157448 -248.731423) (xy 103.143098 -248.778332) (xy 103.121967 -248.822602) (xy 103.09452 -248.863259)
			(xy 103.07828 -248.881646) (xy 103.068484 -248.893137) (xy 103.055484 -248.920372) (xy 103.051024 -248.950219)
			(xy 103.055495 -248.980065) (xy 103.067574 -249.005344) (xy 108.103416 -249.005344) (xy 108.103841 -248.980791)
			(xy 108.111083 -248.932223) (xy 108.12543 -248.885261) (xy 108.146565 -248.840937) (xy 108.174025 -248.800227)
			(xy 108.190284 -248.781824) (xy 108.200044 -248.770301) (xy 108.213061 -248.743076) (xy 108.217538 -248.713233)
			(xy 108.21308 -248.683386) (xy 108.20008 -248.656153) (xy 108.190284 -248.644664) (xy 108.174031 -248.626255)
			(xy 108.146563 -248.585552) (xy 108.125423 -248.54123) (xy 108.111079 -248.494266) (xy 108.103847 -248.445697)
			(xy 108.103416 -248.421144) (xy 108.103925 -248.395177) (xy 108.11205 -248.343882) (xy 108.128098 -248.294489)
			(xy 108.151676 -248.248215) (xy 108.182202 -248.206199) (xy 108.218925 -248.169476) (xy 108.260941 -248.13895)
			(xy 108.307215 -248.115372) (xy 108.356608 -248.099324) (xy 108.407903 -248.091199) (xy 108.459837 -248.091199)
			(xy 108.511132 -248.099324) (xy 108.560525 -248.115372) (xy 108.606799 -248.13895) (xy 108.648815 -248.169476)
			(xy 108.685538 -248.206199) (xy 108.716064 -248.248215) (xy 108.739642 -248.294489) (xy 108.75569 -248.343882)
			(xy 108.763815 -248.395177) (xy 108.764324 -248.421144) (xy 108.763882 -248.445696) (xy 108.756642 -248.494263)
			(xy 108.742299 -248.541225) (xy 108.721167 -248.585549) (xy 108.693713 -248.62626) (xy 108.677456 -248.644664)
			(xy 108.667607 -248.656118) (xy 108.654594 -248.683367) (xy 108.650132 -248.713233) (xy 108.654613 -248.743095)
			(xy 108.667643 -248.770336) (xy 108.677456 -248.781824) (xy 108.693694 -248.800246) (xy 108.715418 -248.832429)
			(xy 113.190275 -248.832429) (xy 113.190275 -248.780495) (xy 113.1984 -248.7292) (xy 113.214448 -248.679807)
			(xy 113.238026 -248.633533) (xy 113.268552 -248.591517) (xy 113.305275 -248.554794) (xy 113.347291 -248.524268)
			(xy 113.393565 -248.50069) (xy 113.442958 -248.484642) (xy 113.494253 -248.476517) (xy 113.546187 -248.476517)
			(xy 113.597482 -248.484642) (xy 113.646875 -248.50069) (xy 113.693149 -248.524268) (xy 113.735165 -248.554794)
			(xy 113.771888 -248.591517) (xy 113.802414 -248.633533) (xy 113.825992 -248.679807) (xy 113.84204 -248.7292)
			(xy 113.850165 -248.780495) (xy 113.850674 -248.806462) (xy 113.850165 -248.832429) (xy 113.84204 -248.883724)
			(xy 113.825992 -248.933117) (xy 113.802414 -248.979391) (xy 113.771888 -249.021407) (xy 113.735165 -249.05813)
			(xy 113.693149 -249.088656) (xy 113.646875 -249.112234) (xy 113.597482 -249.128282) (xy 113.546187 -249.136407)
			(xy 113.494253 -249.136407) (xy 113.442958 -249.128282) (xy 113.393565 -249.112234) (xy 113.347291 -249.088656)
			(xy 113.305275 -249.05813) (xy 113.268552 -249.021407) (xy 113.238026 -248.979391) (xy 113.214448 -248.933117)
			(xy 113.1984 -248.883724) (xy 113.190275 -248.832429) (xy 108.715418 -248.832429) (xy 108.721166 -248.840945)
			(xy 108.74231 -248.885264) (xy 108.756657 -248.932224) (xy 108.763892 -248.980792) (xy 108.764324 -249.005344)
			(xy 108.763815 -249.031311) (xy 108.75569 -249.082606) (xy 108.739642 -249.131999) (xy 108.716064 -249.178273)
			(xy 108.685538 -249.220289) (xy 108.678741 -249.227086) (xy 115.052348 -249.227086) (xy 115.052348 -249.226832)
			(xy 115.052832 -249.202307) (xy 115.060089 -249.153796) (xy 115.074434 -249.10689) (xy 115.095551 -249.062618)
			(xy 115.122978 -249.021951) (xy 115.139216 -249.003566) (xy 115.14903 -248.992086) (xy 115.162037 -248.964845)
			(xy 115.166501 -248.93499) (xy 115.162031 -248.905135) (xy 115.149018 -248.877896) (xy 115.139216 -248.866406)
			(xy 115.122957 -248.848036) (xy 115.095512 -248.807374) (xy 115.074385 -248.7631) (xy 115.060039 -248.716187)
			(xy 115.052791 -248.667669) (xy 115.052348 -248.64314) (xy 115.052348 -248.642886) (xy 115.052857 -248.616919)
			(xy 115.060982 -248.565624) (xy 115.07703 -248.516231) (xy 115.100608 -248.469957) (xy 115.131134 -248.427941)
			(xy 115.167857 -248.391218) (xy 115.209873 -248.360692) (xy 115.256147 -248.337114) (xy 115.30554 -248.321066)
			(xy 115.356835 -248.312941) (xy 115.408769 -248.312941) (xy 115.460064 -248.321066) (xy 115.509457 -248.337114)
			(xy 115.555731 -248.360692) (xy 115.597747 -248.391218) (xy 115.63447 -248.427941) (xy 115.664996 -248.469957)
			(xy 115.688574 -248.516231) (xy 115.704622 -248.565624) (xy 115.712747 -248.616919) (xy 115.713256 -248.642886)
			(xy 115.713256 -248.64314) (xy 115.712814 -248.667667) (xy 115.705546 -248.716179) (xy 115.691192 -248.763086)
			(xy 115.670065 -248.807357) (xy 115.64263 -248.848022) (xy 115.626388 -248.866406) (xy 115.616601 -248.877907)
			(xy 115.603591 -248.905141) (xy 115.599121 -248.93499) (xy 115.603585 -248.964839) (xy 115.61659 -248.992076)
			(xy 115.626388 -249.003566) (xy 115.642635 -249.021947) (xy 115.670081 -249.062606) (xy 115.69121 -249.106878)
			(xy 115.705559 -249.153788) (xy 115.712811 -249.202304) (xy 115.713256 -249.226832) (xy 115.713256 -249.227086)
			(xy 115.712747 -249.253053) (xy 115.704622 -249.304348) (xy 115.688574 -249.353741) (xy 115.664996 -249.400015)
			(xy 115.63447 -249.442031) (xy 115.597747 -249.478754) (xy 115.555731 -249.50928) (xy 115.509457 -249.532858)
			(xy 115.460064 -249.548906) (xy 115.408769 -249.557031) (xy 115.356835 -249.557031) (xy 115.30554 -249.548906)
			(xy 115.256147 -249.532858) (xy 115.209873 -249.50928) (xy 115.167857 -249.478754) (xy 115.131134 -249.442031)
			(xy 115.100608 -249.400015) (xy 115.07703 -249.353741) (xy 115.060982 -249.304348) (xy 115.052857 -249.253053)
			(xy 115.052348 -249.227086) (xy 108.678741 -249.227086) (xy 108.648815 -249.257012) (xy 108.606799 -249.287538)
			(xy 108.560525 -249.311116) (xy 108.511132 -249.327164) (xy 108.459837 -249.335289) (xy 108.407903 -249.335289)
			(xy 108.356608 -249.327164) (xy 108.307215 -249.311116) (xy 108.260941 -249.287538) (xy 108.218925 -249.257012)
			(xy 108.182202 -249.220289) (xy 108.151676 -249.178273) (xy 108.128098 -249.131999) (xy 108.11205 -249.082606)
			(xy 108.103925 -249.031311) (xy 108.103416 -249.005344) (xy 103.067574 -249.005344) (xy 103.068506 -249.007295)
			(xy 103.07828 -249.018806) (xy 103.094522 -249.03719) (xy 103.121956 -249.077855) (xy 103.143082 -249.122126)
			(xy 103.157435 -249.169033) (xy 103.164701 -249.217545) (xy 103.165148 -249.242072) (xy 103.165148 -249.242326)
			(xy 103.164637 -249.268292) (xy 103.156509 -249.319583) (xy 103.140458 -249.368972) (xy 103.116879 -249.415242)
			(xy 103.086352 -249.457254) (xy 103.049629 -249.493973) (xy 103.007615 -249.524496) (xy 102.961342 -249.54807)
			(xy 102.911952 -249.564117) (xy 102.86066 -249.572239) (xy 102.834694 -249.57278) (xy 102.812971 -249.57242)
			(xy 102.769904 -249.566684) (xy 102.748842 -249.56135) (xy 102.735865 -249.558264) (xy 102.7092 -249.558229)
			(xy 102.683435 -249.565098) (xy 102.660326 -249.578402) (xy 102.641449 -249.597235) (xy 102.62809 -249.620313)
			(xy 102.621161 -249.646062) (xy 102.621156 -249.646245) (xy 109.900975 -249.646245) (xy 109.900975 -249.594311)
			(xy 109.9091 -249.543016) (xy 109.925148 -249.493623) (xy 109.948726 -249.447349) (xy 109.979252 -249.405333)
			(xy 110.015975 -249.36861) (xy 110.057991 -249.338084) (xy 110.104265 -249.314506) (xy 110.153658 -249.298458)
			(xy 110.204953 -249.290333) (xy 110.256887 -249.290333) (xy 110.308182 -249.298458) (xy 110.357575 -249.314506)
			(xy 110.403849 -249.338084) (xy 110.445865 -249.36861) (xy 110.482588 -249.405333) (xy 110.513114 -249.447349)
			(xy 110.536692 -249.493623) (xy 110.55274 -249.543016) (xy 110.560865 -249.594311) (xy 110.561374 -249.620278)
			(xy 110.560865 -249.646245) (xy 110.55274 -249.69754) (xy 110.536692 -249.746933) (xy 110.513114 -249.793207)
			(xy 110.482588 -249.835223) (xy 110.445865 -249.871946) (xy 110.403849 -249.902472) (xy 110.357575 -249.92605)
			(xy 110.308182 -249.942098) (xy 110.256887 -249.950223) (xy 110.204953 -249.950223) (xy 110.153658 -249.942098)
			(xy 110.104265 -249.92605) (xy 110.057991 -249.902472) (xy 110.015975 -249.871946) (xy 109.979252 -249.835223)
			(xy 109.948726 -249.793207) (xy 109.925148 -249.746933) (xy 109.9091 -249.69754) (xy 109.900975 -249.646245)
			(xy 102.621156 -249.646245) (xy 102.620826 -249.659394) (xy 102.620826 -250.133866) (xy 102.621219 -250.147201)
			(xy 102.628121 -250.172963) (xy 102.641462 -250.196057) (xy 102.660331 -250.214906) (xy 102.683439 -250.228222)
			(xy 102.709209 -250.235095) (xy 102.735879 -250.235057) (xy 102.748842 -250.23191) (xy 102.769905 -250.226583)
			(xy 102.812971 -250.22085) (xy 102.834694 -250.22048) (xy 102.860663 -250.220962) (xy 102.91196 -250.229087)
			(xy 102.961356 -250.245137) (xy 103.007632 -250.268717) (xy 103.049649 -250.299246) (xy 103.086372 -250.335972)
			(xy 103.106199 -250.363265) (xy 105.127075 -250.363265) (xy 105.127075 -250.311335) (xy 105.135199 -250.260044)
			(xy 105.151246 -250.210655) (xy 105.174821 -250.164385) (xy 105.205345 -250.122372) (xy 105.242064 -250.085651)
			(xy 105.284076 -250.055126) (xy 105.330346 -250.03155) (xy 105.379734 -250.015501) (xy 105.431025 -250.007376)
			(xy 105.45699 -250.006866) (xy 105.482743 -250.007367) (xy 105.533628 -250.015345) (xy 105.582657 -250.031124)
			(xy 105.628643 -250.054321) (xy 105.670471 -250.084376) (xy 105.689146 -250.102116) (xy 105.698836 -250.111109)
			(xy 105.721768 -250.124241) (xy 105.747307 -250.131036) (xy 105.773733 -250.131036) (xy 105.799272 -250.124241)
			(xy 105.822204 -250.111109) (xy 105.831894 -250.102116) (xy 105.850579 -250.084388) (xy 105.89241 -250.05434)
			(xy 105.938394 -250.031143) (xy 105.987418 -250.015356) (xy 106.038298 -250.007362) (xy 106.06405 -250.006866)
			(xy 106.090023 -250.007305) (xy 106.141332 -250.015424) (xy 106.190738 -250.031471) (xy 106.237025 -250.055049)
			(xy 106.279054 -250.085579) (xy 106.315788 -250.122308) (xy 106.346325 -250.164332) (xy 106.36991 -250.210616)
			(xy 106.385964 -250.26002) (xy 106.394091 -250.311327) (xy 106.394091 -250.363265) (xy 117.494075 -250.363265)
			(xy 117.494075 -250.311335) (xy 117.502199 -250.260043) (xy 117.518246 -250.210654) (xy 117.541822 -250.164383)
			(xy 117.572346 -250.12237) (xy 117.609067 -250.085649) (xy 117.651079 -250.055124) (xy 117.69735 -250.031548)
			(xy 117.746739 -250.0155) (xy 117.798031 -250.007375) (xy 117.823996 -250.006866) (xy 117.849856 -250.007377)
			(xy 117.900948 -250.015422) (xy 117.95016 -250.031332) (xy 117.996292 -250.054717) (xy 118.038215 -250.085007)
			(xy 118.056914 -250.102878) (xy 118.066629 -250.111923) (xy 118.089638 -250.125135) (xy 118.115275 -250.131972)
			(xy 118.141809 -250.131972) (xy 118.167446 -250.125135) (xy 118.190455 -250.111923) (xy 118.20017 -250.102878)
			(xy 118.218859 -250.084997) (xy 118.26079 -250.054717) (xy 118.306925 -250.031335) (xy 118.356137 -250.015423)
			(xy 118.407227 -250.007367) (xy 118.433088 -250.006866) (xy 118.459059 -250.007308) (xy 118.510363 -250.015432)
			(xy 118.559764 -250.031482) (xy 118.606046 -250.055062) (xy 118.64807 -250.085593) (xy 118.6848 -250.122321)
			(xy 118.715332 -250.164343) (xy 118.738914 -250.210625) (xy 118.754965 -250.260025) (xy 118.763091 -250.311329)
			(xy 118.763091 -250.363271) (xy 118.754965 -250.414575) (xy 118.738914 -250.463975) (xy 118.715332 -250.510257)
			(xy 118.6848 -250.552279) (xy 118.64807 -250.589007) (xy 118.606046 -250.619538) (xy 118.559764 -250.643118)
			(xy 118.510363 -250.659168) (xy 118.459059 -250.667292) (xy 118.433088 -250.667774) (xy 118.407228 -250.667262)
			(xy 118.356137 -250.659216) (xy 118.306925 -250.643306) (xy 118.260793 -250.619921) (xy 118.218869 -250.589632)
			(xy 118.20017 -250.571762) (xy 118.190455 -250.562717) (xy 118.167446 -250.549505) (xy 118.141809 -250.542668)
			(xy 118.115275 -250.542668) (xy 118.089638 -250.549505) (xy 118.066629 -250.562717) (xy 118.056914 -250.571762)
			(xy 118.038222 -250.58964) (xy 117.996293 -250.619923) (xy 117.95016 -250.643306) (xy 117.900947 -250.659219)
			(xy 117.849857 -250.667274) (xy 117.823996 -250.667774) (xy 117.798031 -250.667225) (xy 117.746739 -250.6591)
			(xy 117.69735 -250.643052) (xy 117.651079 -250.619476) (xy 117.609067 -250.588951) (xy 117.572346 -250.55223)
			(xy 117.541822 -250.510217) (xy 117.518246 -250.463946) (xy 117.502199 -250.414557) (xy 117.494075 -250.363265)
			(xy 106.394091 -250.363265) (xy 106.394091 -250.363273) (xy 106.385964 -250.41458) (xy 106.36991 -250.463984)
			(xy 106.346325 -250.510268) (xy 106.315788 -250.552292) (xy 106.279054 -250.589021) (xy 106.237025 -250.619551)
			(xy 106.190738 -250.643129) (xy 106.141332 -250.659176) (xy 106.090023 -250.667295) (xy 106.06405 -250.667774)
			(xy 106.038295 -250.667328) (xy 105.987407 -250.659339) (xy 105.938376 -250.643548) (xy 105.892391 -250.620338)
			(xy 105.850566 -250.590271) (xy 105.831894 -250.572524) (xy 105.822204 -250.563531) (xy 105.799272 -250.550399)
			(xy 105.773733 -250.543604) (xy 105.747307 -250.543604) (xy 105.721768 -250.550399) (xy 105.698836 -250.563531)
			(xy 105.689146 -250.572524) (xy 105.670494 -250.590288) (xy 105.628654 -250.620329) (xy 105.582661 -250.64352)
			(xy 105.533629 -250.659298) (xy 105.482744 -250.667283) (xy 105.45699 -250.667774) (xy 105.431025 -250.667224)
			(xy 105.379734 -250.659099) (xy 105.330346 -250.64305) (xy 105.284076 -250.619474) (xy 105.242064 -250.588949)
			(xy 105.205345 -250.552228) (xy 105.174821 -250.510215) (xy 105.151246 -250.463945) (xy 105.135199 -250.414556)
			(xy 105.127075 -250.363265) (xy 103.106199 -250.363265) (xy 103.116898 -250.377992) (xy 103.140474 -250.42427)
			(xy 103.15652 -250.473667) (xy 103.16464 -250.524965) (xy 103.165148 -250.550934) (xy 103.165148 -250.551188)
			(xy 103.164701 -250.575715) (xy 103.157447 -250.62423) (xy 103.143096 -250.671138) (xy 103.121964 -250.715408)
			(xy 103.094516 -250.756064) (xy 103.07828 -250.774454) (xy 103.068485 -250.785945) (xy 103.055487 -250.813179)
			(xy 103.051029 -250.843025) (xy 103.055502 -250.872869) (xy 103.068513 -250.900097) (xy 103.07828 -250.911614)
			(xy 103.094521 -250.929998) (xy 103.121954 -250.970663) (xy 103.143079 -251.014935) (xy 103.157431 -251.061841)
			(xy 103.164696 -251.110354) (xy 103.165148 -251.13488) (xy 103.165148 -251.135134) (xy 103.164636 -251.161099)
			(xy 103.156508 -251.21239) (xy 103.140456 -251.261778) (xy 103.116876 -251.308046) (xy 103.086349 -251.350057)
			(xy 103.049627 -251.386775) (xy 103.007612 -251.417297) (xy 102.96134 -251.440871) (xy 102.911951 -251.456917)
			(xy 102.860659 -251.465039) (xy 102.834694 -251.465588) (xy 102.812971 -251.465228) (xy 102.769904 -251.459492)
			(xy 102.748842 -251.454158) (xy 102.735866 -251.451072) (xy 102.709201 -251.451037) (xy 102.683437 -251.457906)
			(xy 102.660328 -251.47121) (xy 102.641452 -251.490043) (xy 102.628095 -251.513121) (xy 102.621167 -251.53887)
			(xy 102.620826 -251.552202) (xy 102.620826 -251.818902) (xy 102.621315 -251.833319) (xy 102.629356 -251.861007)
			(xy 102.644825 -251.885338) (xy 102.666485 -251.904368) (xy 102.692604 -251.916577) (xy 102.721097 -251.920988)
			(xy 102.749686 -251.91725) (xy 102.763066 -251.911866) (xy 102.78402 -251.903121) (xy 102.827722 -251.890803)
			(xy 102.872698 -251.884572) (xy 102.8954 -251.88418) (xy 102.895654 -251.88418) (xy 102.921625 -251.884659)
			(xy 102.972927 -251.892779) (xy 103.022328 -251.908825) (xy 103.068609 -251.932403) (xy 103.110632 -251.962931)
			(xy 103.147361 -251.999659) (xy 103.177891 -252.04168) (xy 103.20147 -252.087961) (xy 103.217518 -252.137361)
			(xy 103.22564 -252.188663) (xy 103.226108 -252.214634) (xy 103.226108 -252.214888) (xy 103.225661 -252.239415)
			(xy 103.218406 -252.287929) (xy 103.204053 -252.334836) (xy 103.18292 -252.379104) (xy 103.15547 -252.419758)
			(xy 103.13924 -252.438154) (xy 103.12944 -252.449642) (xy 103.116434 -252.476876) (xy 103.111973 -252.506725)
			(xy 103.116449 -252.536572) (xy 103.129468 -252.563799) (xy 103.13924 -252.575314) (xy 103.155483 -252.593697)
			(xy 103.182919 -252.634361) (xy 103.194863 -252.659388) (xy 108.103416 -252.659388) (xy 108.103867 -252.634836)
			(xy 108.111103 -252.586269) (xy 108.125444 -252.539307) (xy 108.146573 -252.494983) (xy 108.174027 -252.454272)
			(xy 108.190284 -252.435868) (xy 108.200098 -252.424388) (xy 108.21311 -252.397147) (xy 108.217575 -252.367291)
			(xy 108.213104 -252.337436) (xy 108.200088 -252.310198) (xy 108.190284 -252.298708) (xy 108.174004 -252.280322)
			(xy 108.14654 -252.239612) (xy 108.125406 -252.195284) (xy 108.111068 -252.148316) (xy 108.103842 -252.099742)
			(xy 108.103416 -252.075188) (xy 108.103925 -252.049221) (xy 108.11205 -251.997926) (xy 108.128098 -251.948533)
			(xy 108.151676 -251.902259) (xy 108.182202 -251.860243) (xy 108.218925 -251.82352) (xy 108.260941 -251.792994)
			(xy 108.307215 -251.769416) (xy 108.356608 -251.753368) (xy 108.407903 -251.745243) (xy 108.459837 -251.745243)
			(xy 108.511132 -251.753368) (xy 108.560525 -251.769416) (xy 108.606799 -251.792994) (xy 108.648815 -251.82352)
			(xy 108.685538 -251.860243) (xy 108.716064 -251.902259) (xy 108.739642 -251.948533) (xy 108.75569 -251.997926)
			(xy 108.763815 -252.049221) (xy 108.764324 -252.075188) (xy 108.763908 -252.099741) (xy 108.756662 -252.148309)
			(xy 108.742313 -252.195271) (xy 108.721175 -252.239595) (xy 108.693715 -252.280305) (xy 108.677456 -252.298708)
			(xy 108.667662 -252.310205) (xy 108.654642 -252.337439) (xy 108.65017 -252.367291) (xy 108.654637 -252.397144)
			(xy 108.667652 -252.42438) (xy 108.677456 -252.435868) (xy 108.693714 -252.454272) (xy 108.721184 -252.494976)
			(xy 108.742324 -252.539299) (xy 108.756666 -252.586264) (xy 108.763896 -252.634835) (xy 108.764324 -252.659388)
			(xy 108.763815 -252.685355) (xy 108.75569 -252.73665) (xy 108.739642 -252.786043) (xy 108.729501 -252.805946)
			(xy 115.103148 -252.805946) (xy 115.103148 -252.805692) (xy 115.103608 -252.781166) (xy 115.110871 -252.732654)
			(xy 115.125221 -252.685747) (xy 115.146344 -252.641476) (xy 115.173776 -252.600811) (xy 115.190016 -252.582426)
			(xy 115.199771 -252.5709) (xy 115.212785 -252.543675) (xy 115.21726 -252.513834) (xy 115.212805 -252.48399)
			(xy 115.199809 -252.456756) (xy 115.190016 -252.445266) (xy 115.173785 -252.426872) (xy 115.146337 -252.386216)
			(xy 115.125204 -252.341948) (xy 115.110852 -252.295041) (xy 115.103596 -252.246527) (xy 115.103148 -252.222)
			(xy 115.103148 -252.221746) (xy 115.103657 -252.195779) (xy 115.111782 -252.144484) (xy 115.12783 -252.095091)
			(xy 115.151408 -252.048817) (xy 115.181934 -252.006801) (xy 115.218657 -251.970078) (xy 115.260673 -251.939552)
			(xy 115.306947 -251.915974) (xy 115.35634 -251.899926) (xy 115.407635 -251.891801) (xy 115.459569 -251.891801)
			(xy 115.510864 -251.899926) (xy 115.560257 -251.915974) (xy 115.606531 -251.939552) (xy 115.648547 -251.970078)
			(xy 115.68527 -252.006801) (xy 115.715796 -252.048817) (xy 115.739374 -252.095091) (xy 115.755422 -252.144484)
			(xy 115.763547 -252.195779) (xy 115.764056 -252.221746) (xy 115.764056 -252.222) (xy 115.76359 -252.246526)
			(xy 115.756328 -252.295037) (xy 115.741979 -252.341944) (xy 115.720858 -252.386216) (xy 115.693428 -252.426881)
			(xy 115.677188 -252.445266) (xy 115.667342 -252.456721) (xy 115.654339 -252.483971) (xy 115.64988 -252.513834)
			(xy 115.654358 -252.543694) (xy 115.667381 -252.570935) (xy 115.677188 -252.582426) (xy 115.693416 -252.600823)
			(xy 115.720865 -252.641478) (xy 115.741998 -252.685745) (xy 115.756351 -252.732652) (xy 115.763608 -252.781165)
			(xy 115.764056 -252.805692) (xy 115.764056 -252.805946) (xy 115.763547 -252.831913) (xy 115.755422 -252.883208)
			(xy 115.739374 -252.932601) (xy 115.715796 -252.978875) (xy 115.68527 -253.020891) (xy 115.648547 -253.057614)
			(xy 115.606531 -253.08814) (xy 115.560257 -253.111718) (xy 115.510864 -253.127766) (xy 115.459569 -253.135891)
			(xy 115.407635 -253.135891) (xy 115.35634 -253.127766) (xy 115.306947 -253.111718) (xy 115.260673 -253.08814)
			(xy 115.218657 -253.057614) (xy 115.181934 -253.020891) (xy 115.151408 -252.978875) (xy 115.12783 -252.932601)
			(xy 115.111782 -252.883208) (xy 115.103657 -252.831913) (xy 115.103148 -252.805946) (xy 108.729501 -252.805946)
			(xy 108.716064 -252.832317) (xy 108.685538 -252.874333) (xy 108.648815 -252.911056) (xy 108.606799 -252.941582)
			(xy 108.560525 -252.96516) (xy 108.511132 -252.981208) (xy 108.459837 -252.989333) (xy 108.407903 -252.989333)
			(xy 108.356608 -252.981208) (xy 108.307215 -252.96516) (xy 108.260941 -252.941582) (xy 108.218925 -252.911056)
			(xy 108.182202 -252.874333) (xy 108.151676 -252.832317) (xy 108.128098 -252.786043) (xy 108.11205 -252.73665)
			(xy 108.103925 -252.685355) (xy 108.103416 -252.659388) (xy 103.194863 -252.659388) (xy 103.204047 -252.678633)
			(xy 103.218401 -252.72554) (xy 103.225666 -252.774053) (xy 103.226108 -252.79858) (xy 103.226108 -252.798834)
			(xy 103.225623 -252.8248) (xy 103.217493 -252.876093) (xy 103.20144 -252.925482) (xy 103.177857 -252.971751)
			(xy 103.147327 -253.013762) (xy 103.110601 -253.050479) (xy 103.068583 -253.080999) (xy 103.022308 -253.10457)
			(xy 102.972915 -253.120612) (xy 102.92162 -253.128729) (xy 102.895654 -253.129288) (xy 102.8954 -253.129288)
			(xy 102.872696 -253.128916) (xy 102.827715 -253.1227) (xy 102.784012 -253.110371) (xy 102.763066 -253.101602)
			(xy 102.749667 -253.096293) (xy 102.7211 -253.092594) (xy 102.692635 -253.09702) (xy 102.666539 -253.109219)
			(xy 102.644889 -253.128221) (xy 102.629407 -253.152514) (xy 102.621325 -253.180163) (xy 102.620826 -253.194566)
			(xy 102.620826 -253.72695) (xy 102.635429 -253.748116) (xy 102.65859 -253.794025) (xy 102.674346 -253.842972)
			(xy 102.682314 -253.893772) (xy 102.682802 -253.919482) (xy 102.682802 -253.919736) (xy 102.682366 -253.943786)
			(xy 102.675384 -253.991376) (xy 102.661573 -254.037451) (xy 102.659925 -254.041164) (xy 105.127095 -254.041164)
			(xy 105.127095 -253.989236) (xy 105.135218 -253.937949) (xy 105.151264 -253.888563) (xy 105.174838 -253.842295)
			(xy 105.20536 -253.800285) (xy 105.242077 -253.763566) (xy 105.284087 -253.733043) (xy 105.330354 -253.709468)
			(xy 105.379739 -253.69342) (xy 105.431026 -253.685296) (xy 105.45699 -253.684786) (xy 105.482743 -253.685281)
			(xy 105.533628 -253.693259) (xy 105.582658 -253.709039) (xy 105.628644 -253.732239) (xy 105.670472 -253.762295)
			(xy 105.689146 -253.780036) (xy 105.698836 -253.789029) (xy 105.721768 -253.802161) (xy 105.747307 -253.808956)
			(xy 105.773733 -253.808956) (xy 105.799272 -253.802161) (xy 105.822204 -253.789029) (xy 105.831894 -253.780036)
			(xy 105.850582 -253.762311) (xy 105.892412 -253.732263) (xy 105.938395 -253.709064) (xy 105.987419 -253.693276)
			(xy 106.038298 -253.685282) (xy 106.06405 -253.684786) (xy 106.090025 -253.685185) (xy 106.141336 -253.693305)
			(xy 106.190746 -253.709352) (xy 106.237036 -253.732932) (xy 106.279067 -253.763464) (xy 106.315804 -253.800195)
			(xy 106.346342 -253.842222) (xy 106.369928 -253.888508) (xy 106.385983 -253.937915) (xy 106.387257 -253.945957)
			(xy 113.300003 -253.945957) (xy 113.300003 -253.894023) (xy 113.308128 -253.842728) (xy 113.324176 -253.793335)
			(xy 113.347754 -253.747061) (xy 113.37828 -253.705045) (xy 113.415003 -253.668322) (xy 113.457019 -253.637796)
			(xy 113.503293 -253.614218) (xy 113.552686 -253.59817) (xy 113.603981 -253.590045) (xy 113.655915 -253.590045)
			(xy 113.70721 -253.59817) (xy 113.756603 -253.614218) (xy 113.802877 -253.637796) (xy 113.844893 -253.668322)
			(xy 113.881616 -253.705045) (xy 113.912142 -253.747061) (xy 113.93572 -253.793335) (xy 113.951768 -253.842728)
			(xy 113.959893 -253.894023) (xy 113.960402 -253.91999) (xy 113.959893 -253.945957) (xy 113.951768 -253.997252)
			(xy 113.937501 -254.041164) (xy 117.494095 -254.041164) (xy 117.494095 -253.989236) (xy 117.502218 -253.937948)
			(xy 117.518265 -253.888561) (xy 117.541839 -253.842293) (xy 117.572361 -253.800283) (xy 117.60908 -253.763564)
			(xy 117.65109 -253.733041) (xy 117.697358 -253.709466) (xy 117.746744 -253.693419) (xy 117.798032 -253.685295)
			(xy 117.823996 -253.684786) (xy 117.849857 -253.685291) (xy 117.900948 -253.693337) (xy 117.950162 -253.709247)
			(xy 117.996293 -253.732635) (xy 118.038216 -253.762926) (xy 118.056914 -253.780798) (xy 118.066629 -253.789843)
			(xy 118.089638 -253.803055) (xy 118.115275 -253.809892) (xy 118.141809 -253.809892) (xy 118.167446 -253.803055)
			(xy 118.190455 -253.789843) (xy 118.20017 -253.780798) (xy 118.218862 -253.762921) (xy 118.260792 -253.732639)
			(xy 118.306926 -253.709257) (xy 118.356138 -253.693343) (xy 118.407228 -253.685287) (xy 118.433088 -253.684786)
			(xy 118.459061 -253.685188) (xy 118.510368 -253.693313) (xy 118.559772 -253.709363) (xy 118.606057 -253.732945)
			(xy 118.648083 -253.763477) (xy 118.684815 -253.800208) (xy 118.715349 -253.842233) (xy 118.738932 -253.888517)
			(xy 118.754985 -253.93792) (xy 118.763111 -253.989227) (xy 118.763111 -254.041173) (xy 118.754985 -254.09248)
			(xy 118.738932 -254.141883) (xy 118.715349 -254.188167) (xy 118.684815 -254.230192) (xy 118.648083 -254.266923)
			(xy 118.606057 -254.297455) (xy 118.559772 -254.321037) (xy 118.510368 -254.337087) (xy 118.459061 -254.345212)
			(xy 118.433088 -254.345694) (xy 118.407227 -254.345205) (xy 118.356134 -254.337156) (xy 118.30692 -254.321242)
			(xy 118.260789 -254.297851) (xy 118.218867 -254.267556) (xy 118.20017 -254.249682) (xy 118.190455 -254.240637)
			(xy 118.167446 -254.227425) (xy 118.141809 -254.220588) (xy 118.115275 -254.220588) (xy 118.089638 -254.227425)
			(xy 118.066629 -254.240637) (xy 118.056914 -254.249682) (xy 118.038226 -254.267564) (xy 117.996295 -254.297845)
			(xy 117.950161 -254.321227) (xy 117.900948 -254.33714) (xy 117.849857 -254.345194) (xy 117.823996 -254.345694)
			(xy 117.798032 -254.345105) (xy 117.746744 -254.336981) (xy 117.697358 -254.320934) (xy 117.65109 -254.297359)
			(xy 117.60908 -254.266836) (xy 117.572361 -254.230117) (xy 117.541839 -254.188107) (xy 117.518265 -254.141839)
			(xy 117.502218 -254.092452) (xy 117.494095 -254.041164) (xy 113.937501 -254.041164) (xy 113.93572 -254.046645)
			(xy 113.912142 -254.092919) (xy 113.881616 -254.134935) (xy 113.844893 -254.171658) (xy 113.802877 -254.202184)
			(xy 113.756603 -254.225762) (xy 113.70721 -254.24181) (xy 113.655915 -254.249935) (xy 113.603981 -254.249935)
			(xy 113.552686 -254.24181) (xy 113.503293 -254.225762) (xy 113.457019 -254.202184) (xy 113.415003 -254.171658)
			(xy 113.37828 -254.134935) (xy 113.347754 -254.092919) (xy 113.324176 -254.046645) (xy 113.308128 -253.997252)
			(xy 113.300003 -253.945957) (xy 106.387257 -253.945957) (xy 106.394111 -253.989225) (xy 106.394111 -254.041175)
			(xy 106.385983 -254.092485) (xy 106.369928 -254.141892) (xy 106.346342 -254.188178) (xy 106.315804 -254.230205)
			(xy 106.279067 -254.266936) (xy 106.237036 -254.297468) (xy 106.190746 -254.321048) (xy 106.141336 -254.337095)
			(xy 106.090025 -254.345215) (xy 106.06405 -254.345694) (xy 106.038295 -254.345242) (xy 105.987408 -254.337254)
			(xy 105.938377 -254.321464) (xy 105.892392 -254.298255) (xy 105.850567 -254.26819) (xy 105.831894 -254.250444)
			(xy 105.822204 -254.241451) (xy 105.799272 -254.228319) (xy 105.773733 -254.221524) (xy 105.747307 -254.221524)
			(xy 105.721768 -254.228319) (xy 105.698836 -254.241451) (xy 105.689146 -254.250444) (xy 105.670481 -254.268194)
			(xy 105.628645 -254.29824) (xy 105.582657 -254.321435) (xy 105.533627 -254.337216) (xy 105.482743 -254.345203)
			(xy 105.45699 -254.345694) (xy 105.431026 -254.345104) (xy 105.379739 -254.33698) (xy 105.330354 -254.320932)
			(xy 105.284087 -254.297357) (xy 105.242077 -254.266834) (xy 105.20536 -254.230115) (xy 105.174838 -254.188105)
			(xy 105.151264 -254.141837) (xy 105.135218 -254.092451) (xy 105.127095 -254.041164) (xy 102.659925 -254.041164)
			(xy 102.651814 -254.059436) (xy 102.647496 -254.068834) (xy 102.630117 -254.759773) (xy 110.010703 -254.759773)
			(xy 110.010703 -254.707839) (xy 110.018828 -254.656544) (xy 110.034876 -254.607151) (xy 110.058454 -254.560877)
			(xy 110.08898 -254.518861) (xy 110.125703 -254.482138) (xy 110.167719 -254.451612) (xy 110.213993 -254.428034)
			(xy 110.263386 -254.411986) (xy 110.314681 -254.403861) (xy 110.366615 -254.403861) (xy 110.41791 -254.411986)
			(xy 110.467303 -254.428034) (xy 110.513577 -254.451612) (xy 110.555593 -254.482138) (xy 110.592316 -254.518861)
			(xy 110.622842 -254.560877) (xy 110.64642 -254.607151) (xy 110.662468 -254.656544) (xy 110.670593 -254.707839)
			(xy 110.671102 -254.733806) (xy 110.670593 -254.759773) (xy 110.662468 -254.811068) (xy 110.64642 -254.860461)
			(xy 110.622842 -254.906735) (xy 110.592316 -254.948751) (xy 110.555593 -254.985474) (xy 110.513577 -255.016)
			(xy 110.467303 -255.039578) (xy 110.41791 -255.055626) (xy 110.366615 -255.063751) (xy 110.314681 -255.063751)
			(xy 110.263386 -255.055626) (xy 110.213993 -255.039578) (xy 110.167719 -255.016) (xy 110.125703 -254.985474)
			(xy 110.08898 -254.948751) (xy 110.058454 -254.906735) (xy 110.034876 -254.860461) (xy 110.018828 -254.811068)
			(xy 110.010703 -254.759773) (xy 102.630117 -254.759773) (xy 102.6287 -254.816102) (xy 102.628182 -254.830057)
			(xy 102.624877 -254.857789) (xy 102.622096 -254.871474) (xy 102.620826 -254.876808) (xy 102.620826 -254.94996)
			(xy 102.621359 -254.959931) (xy 102.629066 -254.97833) (xy 102.64321 -254.992395) (xy 102.661652 -254.999998)
			(xy 102.671626 -255.000506) (xy 102.705916 -254.987298) (xy 102.724278 -254.971137) (xy 102.764874 -254.943848)
			(xy 102.809048 -254.922841) (xy 102.855837 -254.908575) (xy 102.904217 -254.901361) (xy 102.928674 -254.900938)
			(xy 102.954645 -254.901419) (xy 103.005948 -254.909541) (xy 103.055348 -254.925588) (xy 103.10163 -254.949166)
			(xy 103.143653 -254.979694) (xy 103.180384 -255.016421) (xy 103.210916 -255.058441) (xy 103.234499 -255.10472)
			(xy 103.250551 -255.154119) (xy 103.258678 -255.205421) (xy 103.259128 -255.231392) (xy 103.258641 -255.256092)
			(xy 103.251239 -255.304935) (xy 103.236659 -255.352135) (xy 103.215225 -255.396643) (xy 103.187412 -255.43747)
			(xy 103.17099 -255.455928) (xy 103.161069 -255.467442) (xy 103.147868 -255.4948) (xy 103.143299 -255.524831)
			(xy 103.147768 -255.554877) (xy 103.16088 -255.582279) (xy 103.170736 -255.59385) (xy 103.187075 -255.612245)
			(xy 103.214683 -255.652968) (xy 103.235941 -255.697337) (xy 103.250379 -255.74437) (xy 103.257677 -255.793024)
			(xy 103.258112 -255.817624) (xy 103.257627 -255.843591) (xy 103.249499 -255.894885) (xy 103.233447 -255.944275)
			(xy 103.209865 -255.990547) (xy 103.179335 -256.032559) (xy 103.142609 -256.069278) (xy 103.10059 -256.0998)
			(xy 103.054314 -256.123372) (xy 103.00492 -256.139415) (xy 102.953625 -256.147533) (xy 102.927658 -256.148078)
			(xy 102.900383 -256.147517) (xy 102.846574 -256.13856) (xy 102.794964 -256.120896) (xy 102.770686 -256.108454)
			(xy 102.757209 -256.101788) (xy 102.727755 -256.095819) (xy 102.697839 -256.098673) (xy 102.670046 -256.110104)
			(xy 102.646777 -256.129123) (xy 102.630045 -256.154086) (xy 102.621295 -256.182836) (xy 102.620826 -256.197862)
			(xy 102.620826 -256.31775) (xy 102.633526 -256.33045) (xy 108.103416 -256.33045) (xy 108.103844 -256.305897)
			(xy 108.111086 -256.257329) (xy 108.125432 -256.210367) (xy 108.146567 -256.166043) (xy 108.174025 -256.125333)
			(xy 108.190284 -256.10693) (xy 108.200038 -256.095402) (xy 108.213056 -256.068179) (xy 108.217534 -256.038337)
			(xy 108.213078 -256.008492) (xy 108.200079 -255.981259) (xy 108.190284 -255.96977) (xy 108.174034 -255.951359)
			(xy 108.146565 -255.910656) (xy 108.125425 -255.866334) (xy 108.11108 -255.819372) (xy 108.103847 -255.770803)
			(xy 108.103416 -255.74625) (xy 108.103925 -255.720283) (xy 108.11205 -255.668988) (xy 108.128098 -255.619595)
			(xy 108.151676 -255.573321) (xy 108.182202 -255.531305) (xy 108.218925 -255.494582) (xy 108.260941 -255.464056)
			(xy 108.307215 -255.440478) (xy 108.356608 -255.42443) (xy 108.407903 -255.416305) (xy 108.459837 -255.416305)
			(xy 108.511132 -255.42443) (xy 108.560525 -255.440478) (xy 108.606799 -255.464056) (xy 108.648815 -255.494582)
			(xy 108.685538 -255.531305) (xy 108.716064 -255.573321) (xy 108.71633 -255.573843) (xy 113.300003 -255.573843)
			(xy 113.300003 -255.521909) (xy 113.308128 -255.470614) (xy 113.324176 -255.421221) (xy 113.347754 -255.374947)
			(xy 113.37828 -255.332931) (xy 113.415003 -255.296208) (xy 113.457019 -255.265682) (xy 113.503293 -255.242104)
			(xy 113.552686 -255.226056) (xy 113.603981 -255.217931) (xy 113.655915 -255.217931) (xy 113.70721 -255.226056)
			(xy 113.756603 -255.242104) (xy 113.802877 -255.265682) (xy 113.844893 -255.296208) (xy 113.881616 -255.332931)
			(xy 113.912142 -255.374947) (xy 113.93572 -255.421221) (xy 113.951768 -255.470614) (xy 113.959893 -255.521909)
			(xy 113.960402 -255.547876) (xy 113.959893 -255.573843) (xy 113.951768 -255.625138) (xy 113.93572 -255.674531)
			(xy 113.912142 -255.720805) (xy 113.881616 -255.762821) (xy 113.844893 -255.799544) (xy 113.802877 -255.83007)
			(xy 113.756603 -255.853648) (xy 113.70721 -255.869696) (xy 113.655915 -255.877821) (xy 113.603981 -255.877821)
			(xy 113.552686 -255.869696) (xy 113.503293 -255.853648) (xy 113.457019 -255.83007) (xy 113.415003 -255.799544)
			(xy 113.37828 -255.762821) (xy 113.347754 -255.720805) (xy 113.324176 -255.674531) (xy 113.308128 -255.625138)
			(xy 113.300003 -255.573843) (xy 108.71633 -255.573843) (xy 108.739642 -255.619595) (xy 108.75569 -255.668988)
			(xy 108.763815 -255.720283) (xy 108.764324 -255.74625) (xy 108.763885 -255.770802) (xy 108.756645 -255.819369)
			(xy 108.742301 -255.866331) (xy 108.721168 -255.910655) (xy 108.693713 -255.951366) (xy 108.677456 -255.96977)
			(xy 108.667601 -255.98122) (xy 108.654589 -256.00847) (xy 108.650128 -256.038337) (xy 108.654611 -256.068201)
			(xy 108.667643 -256.095442) (xy 108.677456 -256.10693) (xy 108.693696 -256.12535) (xy 108.721169 -256.166049)
			(xy 108.742312 -256.210368) (xy 108.756658 -256.25733) (xy 108.763893 -256.305898) (xy 108.764324 -256.33045)
			(xy 108.763815 -256.356417) (xy 108.758866 -256.387659) (xy 110.010449 -256.387659) (xy 110.010449 -256.335725)
			(xy 110.018574 -256.28443) (xy 110.034622 -256.235037) (xy 110.0582 -256.188763) (xy 110.088726 -256.146747)
			(xy 110.125449 -256.110024) (xy 110.167465 -256.079498) (xy 110.213739 -256.05592) (xy 110.263132 -256.039872)
			(xy 110.314427 -256.031747) (xy 110.366361 -256.031747) (xy 110.417656 -256.039872) (xy 110.467049 -256.05592)
			(xy 110.513323 -256.079498) (xy 110.555339 -256.110024) (xy 110.592062 -256.146747) (xy 110.622588 -256.188763)
			(xy 110.646166 -256.235037) (xy 110.662214 -256.28443) (xy 110.670339 -256.335725) (xy 110.670848 -256.361692)
			(xy 110.670339 -256.387659) (xy 110.669986 -256.389886) (xy 115.098068 -256.389886) (xy 115.09853 -256.365335)
			(xy 115.105765 -256.316769) (xy 115.120104 -256.269807) (xy 115.141231 -256.225483) (xy 115.168681 -256.184771)
			(xy 115.184936 -256.166366) (xy 115.194756 -256.154889) (xy 115.207774 -256.127648) (xy 115.212241 -256.09779)
			(xy 115.207768 -256.067932) (xy 115.194745 -256.040694) (xy 115.184936 -256.029206) (xy 115.168664 -256.010813)
			(xy 115.141196 -255.970106) (xy 115.12006 -255.92578) (xy 115.10572 -255.878813) (xy 115.098494 -255.83024)
			(xy 115.098068 -255.805686) (xy 115.098577 -255.779719) (xy 115.106702 -255.728424) (xy 115.12275 -255.679031)
			(xy 115.146328 -255.632757) (xy 115.176854 -255.590741) (xy 115.213577 -255.554018) (xy 115.255593 -255.523492)
			(xy 115.301867 -255.499914) (xy 115.35126 -255.483866) (xy 115.402555 -255.475741) (xy 115.454489 -255.475741)
			(xy 115.505784 -255.483866) (xy 115.555177 -255.499914) (xy 115.601451 -255.523492) (xy 115.643467 -255.554018)
			(xy 115.68019 -255.590741) (xy 115.710716 -255.632757) (xy 115.734294 -255.679031) (xy 115.750342 -255.728424)
			(xy 115.758467 -255.779719) (xy 115.758976 -255.805686) (xy 115.758546 -255.830238) (xy 115.751301 -255.878805)
			(xy 115.736954 -255.925767) (xy 115.71582 -255.97009) (xy 115.688365 -256.010802) (xy 115.672108 -256.029206)
			(xy 115.66232 -256.040706) (xy 115.649307 -256.06794) (xy 115.644836 -256.09779) (xy 115.6493 -256.12764)
			(xy 115.662308 -256.154876) (xy 115.672108 -256.166366) (xy 115.688374 -256.184764) (xy 115.715841 -256.22547)
			(xy 115.736978 -256.269795) (xy 115.751319 -256.316761) (xy 115.758548 -256.365332) (xy 115.758976 -256.389886)
			(xy 115.758467 -256.415853) (xy 115.750342 -256.467148) (xy 115.734294 -256.516541) (xy 115.710716 -256.562815)
			(xy 115.68019 -256.604831) (xy 115.643467 -256.641554) (xy 115.601451 -256.67208) (xy 115.555177 -256.695658)
			(xy 115.505784 -256.711706) (xy 115.454489 -256.719831) (xy 115.402555 -256.719831) (xy 115.35126 -256.711706)
			(xy 115.301867 -256.695658) (xy 115.255593 -256.67208) (xy 115.213577 -256.641554) (xy 115.176854 -256.604831)
			(xy 115.146328 -256.562815) (xy 115.12275 -256.516541) (xy 115.106702 -256.467148) (xy 115.098577 -256.415853)
			(xy 115.098068 -256.389886) (xy 110.669986 -256.389886) (xy 110.662214 -256.438954) (xy 110.646166 -256.488347)
			(xy 110.622588 -256.534621) (xy 110.592062 -256.576637) (xy 110.555339 -256.61336) (xy 110.513323 -256.643886)
			(xy 110.467049 -256.667464) (xy 110.417656 -256.683512) (xy 110.366361 -256.691637) (xy 110.314427 -256.691637)
			(xy 110.263132 -256.683512) (xy 110.213739 -256.667464) (xy 110.167465 -256.643886) (xy 110.125449 -256.61336)
			(xy 110.088726 -256.576637) (xy 110.0582 -256.534621) (xy 110.034622 -256.488347) (xy 110.018574 -256.438954)
			(xy 110.010449 -256.387659) (xy 108.758866 -256.387659) (xy 108.75569 -256.407712) (xy 108.739642 -256.457105)
			(xy 108.716064 -256.503379) (xy 108.685538 -256.545395) (xy 108.648815 -256.582118) (xy 108.606799 -256.612644)
			(xy 108.560525 -256.636222) (xy 108.511132 -256.65227) (xy 108.459837 -256.660395) (xy 108.407903 -256.660395)
			(xy 108.356608 -256.65227) (xy 108.307215 -256.636222) (xy 108.260941 -256.612644) (xy 108.218925 -256.582118)
			(xy 108.182202 -256.545395) (xy 108.151676 -256.503379) (xy 108.128098 -256.457105) (xy 108.11205 -256.407712)
			(xy 108.103925 -256.356417) (xy 108.103416 -256.33045) (xy 102.633526 -256.33045) (xy 102.857046 -256.55397)
			(xy 104.743758 -256.55397) (xy 105.294938 -257.10515) (xy 105.294938 -257.201475) (xy 113.300003 -257.201475)
			(xy 113.300003 -257.149541) (xy 113.308128 -257.098246) (xy 113.324176 -257.048853) (xy 113.347754 -257.002579)
			(xy 113.37828 -256.960563) (xy 113.415003 -256.92384) (xy 113.457019 -256.893314) (xy 113.503293 -256.869736)
			(xy 113.552686 -256.853688) (xy 113.603981 -256.845563) (xy 113.655915 -256.845563) (xy 113.70721 -256.853688)
			(xy 113.756603 -256.869736) (xy 113.802877 -256.893314) (xy 113.844893 -256.92384) (xy 113.881616 -256.960563)
			(xy 113.912142 -257.002579) (xy 113.93572 -257.048853) (xy 113.951768 -257.098246) (xy 113.959893 -257.149541)
			(xy 113.960402 -257.175508) (xy 113.959893 -257.201475) (xy 113.951768 -257.25277) (xy 113.93572 -257.302163)
			(xy 113.912142 -257.348437) (xy 113.881616 -257.390453) (xy 113.844893 -257.427176) (xy 113.802877 -257.457702)
			(xy 113.756603 -257.48128) (xy 113.70721 -257.497328) (xy 113.655915 -257.505453) (xy 113.603981 -257.505453)
			(xy 113.552686 -257.497328) (xy 113.503293 -257.48128) (xy 113.457019 -257.457702) (xy 113.415003 -257.427176)
			(xy 113.37828 -257.390453) (xy 113.347754 -257.348437) (xy 113.324176 -257.302163) (xy 113.308128 -257.25277)
			(xy 113.300003 -257.201475) (xy 105.294938 -257.201475) (xy 105.294938 -257.265424) (xy 105.295456 -257.279933)
			(xy 105.303628 -257.307778) (xy 105.319304 -257.332198) (xy 105.341219 -257.35122) (xy 105.3676 -257.363308)
			(xy 105.396317 -257.367484) (xy 105.410762 -257.366008) (xy 105.422258 -257.36448) (xy 105.445393 -257.362828)
			(xy 105.45699 -257.362706) (xy 105.482743 -257.363197) (xy 105.533627 -257.371184) (xy 105.582657 -257.386965)
			(xy 105.628645 -257.41016) (xy 105.670481 -257.440206) (xy 105.689146 -257.457956) (xy 105.698836 -257.466949)
			(xy 105.721768 -257.480081) (xy 105.747307 -257.486876) (xy 105.773733 -257.486876) (xy 105.799272 -257.480081)
			(xy 105.822204 -257.466949) (xy 105.831894 -257.457956) (xy 105.850567 -257.44021) (xy 105.892392 -257.410145)
			(xy 105.938377 -257.386936) (xy 105.987408 -257.371146) (xy 106.038295 -257.363158) (xy 106.06405 -257.362706)
			(xy 106.090025 -257.363185) (xy 106.141336 -257.371305) (xy 106.190746 -257.387352) (xy 106.237036 -257.410932)
			(xy 106.279067 -257.441464) (xy 106.315804 -257.478195) (xy 106.346342 -257.520222) (xy 106.369928 -257.566508)
			(xy 106.385983 -257.615915) (xy 106.394111 -257.667225) (xy 106.394111 -257.719175) (xy 106.385983 -257.770485)
			(xy 106.369928 -257.819892) (xy 106.346342 -257.866178) (xy 106.315804 -257.908205) (xy 106.279067 -257.944936)
			(xy 106.237036 -257.975468) (xy 106.190746 -257.999048) (xy 106.141336 -258.015095) (xy 106.140097 -258.015291)
			(xy 110.010703 -258.015291) (xy 110.010703 -257.963357) (xy 110.018828 -257.912062) (xy 110.034876 -257.862669)
			(xy 110.058454 -257.816395) (xy 110.08898 -257.774379) (xy 110.125703 -257.737656) (xy 110.167719 -257.70713)
			(xy 110.213993 -257.683552) (xy 110.263386 -257.667504) (xy 110.314681 -257.659379) (xy 110.366615 -257.659379)
			(xy 110.41791 -257.667504) (xy 110.467303 -257.683552) (xy 110.513577 -257.70713) (xy 110.530149 -257.71917)
			(xy 117.494015 -257.71917) (xy 117.494015 -257.66723) (xy 117.502141 -257.615929) (xy 117.518191 -257.566531)
			(xy 117.541771 -257.520252) (xy 117.572301 -257.478231) (xy 117.609028 -257.441503) (xy 117.651048 -257.410973)
			(xy 117.697327 -257.387392) (xy 117.746725 -257.371341) (xy 117.798026 -257.363216) (xy 117.823996 -257.362706)
			(xy 117.849857 -257.363205) (xy 117.900949 -257.371252) (xy 117.950163 -257.387163) (xy 117.996294 -257.410552)
			(xy 118.038216 -257.440845) (xy 118.056914 -257.458718) (xy 118.066629 -257.467763) (xy 118.089638 -257.480975)
			(xy 118.115275 -257.487812) (xy 118.141809 -257.487812) (xy 118.167446 -257.480975) (xy 118.190455 -257.467763)
			(xy 118.20017 -257.458718) (xy 118.218865 -257.440844) (xy 118.260794 -257.410561) (xy 118.306927 -257.387178)
			(xy 118.356138 -257.371264) (xy 118.407228 -257.363207) (xy 118.433088 -257.362706) (xy 118.457443 -257.363121)
			(xy 118.505625 -257.370271) (xy 118.552235 -257.384417) (xy 118.596263 -257.405252) (xy 118.636756 -257.432326)
			(xy 118.672834 -257.465052) (xy 118.688612 -257.48361) (xy 118.698497 -257.494826) (xy 118.723299 -257.511488)
			(xy 118.75186 -257.520268) (xy 118.781739 -257.520416) (xy 118.810385 -257.511919) (xy 118.835351 -257.495503)
			(xy 118.84533 -257.484372) (xy 118.861106 -257.466072) (xy 118.897076 -257.433814) (xy 118.937363 -257.407142)
			(xy 118.981106 -257.386625) (xy 119.027371 -257.3727) (xy 119.075172 -257.365664) (xy 119.09933 -257.365246)
			(xy 119.123857 -257.365694) (xy 119.172369 -257.37296) (xy 119.219276 -257.387313) (xy 119.263547 -257.408438)
			(xy 119.304212 -257.435873) (xy 119.322596 -257.452114) (xy 119.334153 -257.46199) (xy 119.361623 -257.474979)
			(xy 119.391698 -257.47932) (xy 119.42172 -257.474628) (xy 119.449036 -257.461318) (xy 119.460518 -257.451352)
			(xy 119.47897 -257.434774) (xy 119.519914 -257.406776) (xy 119.564581 -257.385209) (xy 119.61197 -257.370556)
			(xy 119.661015 -257.363149) (xy 119.685816 -257.362706) (xy 119.711779 -257.363296) (xy 119.763066 -257.371422)
			(xy 119.812451 -257.38747) (xy 119.858717 -257.411045) (xy 119.900725 -257.441568) (xy 119.937442 -257.478287)
			(xy 119.967963 -257.520297) (xy 119.991536 -257.566564) (xy 120.007582 -257.615949) (xy 120.015705 -257.667237)
			(xy 120.015705 -257.719163) (xy 120.007582 -257.770451) (xy 119.991536 -257.819836) (xy 119.967963 -257.866103)
			(xy 119.937442 -257.908113) (xy 119.900725 -257.944832) (xy 119.858717 -257.975355) (xy 119.812451 -257.99893)
			(xy 119.763066 -258.014978) (xy 119.711779 -258.023104) (xy 119.685816 -258.023614) (xy 119.66129 -258.023149)
			(xy 119.612778 -258.015889) (xy 119.565871 -258.00154) (xy 119.521599 -257.980418) (xy 119.480934 -257.952987)
			(xy 119.46255 -257.936746) (xy 119.450956 -257.926919) (xy 119.423499 -257.91393) (xy 119.393436 -257.909582)
			(xy 119.363424 -257.914261) (xy 119.336111 -257.927552) (xy 119.324628 -257.937508) (xy 119.306193 -257.954105)
			(xy 119.265245 -257.982102) (xy 119.220573 -258.003666) (xy 119.173181 -258.018314) (xy 119.124132 -258.025715)
			(xy 119.09933 -258.026154) (xy 119.074977 -258.025705) (xy 119.026797 -258.018559) (xy 118.980188 -258.004419)
			(xy 118.93616 -257.983589) (xy 118.895667 -257.956523) (xy 118.859585 -257.923805) (xy 118.843806 -257.90525)
			(xy 118.833901 -257.894056) (xy 118.809102 -257.8774) (xy 118.780548 -257.868621) (xy 118.750676 -257.86847)
			(xy 118.722034 -257.876959) (xy 118.697069 -257.893363) (xy 118.687088 -257.904488) (xy 118.671293 -257.922772)
			(xy 118.635328 -257.955032) (xy 118.595045 -257.981707) (xy 118.551306 -258.002228) (xy 118.505043 -258.016156)
			(xy 118.457245 -258.023194) (xy 118.433088 -258.023614) (xy 118.407227 -258.023119) (xy 118.356135 -258.015071)
			(xy 118.306921 -257.999158) (xy 118.26079 -257.975768) (xy 118.218868 -257.945475) (xy 118.20017 -257.927602)
			(xy 118.190455 -257.918557) (xy 118.167446 -257.905345) (xy 118.141809 -257.898508) (xy 118.115275 -257.898508)
			(xy 118.089638 -257.905345) (xy 118.066629 -257.918557) (xy 118.056914 -257.927602) (xy 118.038229 -257.945487)
			(xy 117.996297 -257.975767) (xy 117.950162 -257.999149) (xy 117.900948 -258.01506) (xy 117.849857 -258.023114)
			(xy 117.823996 -258.023614) (xy 117.798026 -258.023184) (xy 117.746725 -258.015059) (xy 117.697327 -257.999008)
			(xy 117.651048 -257.975427) (xy 117.609028 -257.944897) (xy 117.572301 -257.908169) (xy 117.541771 -257.866148)
			(xy 117.518191 -257.819869) (xy 117.502141 -257.770471) (xy 117.494015 -257.71917) (xy 110.530149 -257.71917)
			(xy 110.555593 -257.737656) (xy 110.592316 -257.774379) (xy 110.622842 -257.816395) (xy 110.64642 -257.862669)
			(xy 110.662468 -257.912062) (xy 110.670593 -257.963357) (xy 110.671102 -257.989324) (xy 110.670593 -258.015291)
			(xy 110.662468 -258.066586) (xy 110.64642 -258.115979) (xy 110.622842 -258.162253) (xy 110.592316 -258.204269)
			(xy 110.555593 -258.240992) (xy 110.513577 -258.271518) (xy 110.467303 -258.295096) (xy 110.41791 -258.311144)
			(xy 110.366615 -258.319269) (xy 110.314681 -258.319269) (xy 110.263386 -258.311144) (xy 110.213993 -258.295096)
			(xy 110.167719 -258.271518) (xy 110.125703 -258.240992) (xy 110.08898 -258.204269) (xy 110.058454 -258.162253)
			(xy 110.034876 -258.115979) (xy 110.018828 -258.066586) (xy 110.010703 -258.015291) (xy 106.140097 -258.015291)
			(xy 106.090025 -258.023215) (xy 106.06405 -258.023614) (xy 106.038298 -258.023118) (xy 105.987419 -258.015124)
			(xy 105.938395 -257.999336) (xy 105.892412 -257.976137) (xy 105.850582 -257.946089) (xy 105.831894 -257.928364)
			(xy 105.822204 -257.919371) (xy 105.799272 -257.906239) (xy 105.773733 -257.899444) (xy 105.747307 -257.899444)
			(xy 105.721768 -257.906239) (xy 105.698836 -257.919371) (xy 105.689146 -257.928364) (xy 105.670472 -257.946105)
			(xy 105.628644 -257.976161) (xy 105.582658 -257.999361) (xy 105.533628 -258.015141) (xy 105.482743 -258.023119)
			(xy 105.45699 -258.023614) (xy 105.445393 -258.023508) (xy 105.422257 -258.021857) (xy 105.410762 -258.020312)
			(xy 105.396318 -258.018784) (xy 105.367588 -258.022962) (xy 105.341195 -258.035056) (xy 105.319273 -258.054089)
			(xy 105.303592 -258.078522) (xy 105.295421 -258.10638) (xy 105.294938 -258.120896) (xy 105.294938 -259.578602)
			(xy 108.103416 -259.578602) (xy 108.103815 -259.554048) (xy 108.111064 -259.505479) (xy 108.125417 -259.458516)
			(xy 108.146558 -259.414193) (xy 108.174022 -259.373484) (xy 108.190284 -259.355082) (xy 108.200085 -259.343591)
			(xy 108.213098 -259.316354) (xy 108.217566 -259.286501) (xy 108.213098 -259.256648) (xy 108.200086 -259.229411)
			(xy 108.190284 -259.217922) (xy 108.174011 -259.19953) (xy 108.146546 -259.158822) (xy 108.12541 -259.114496)
			(xy 108.111071 -259.067529) (xy 108.103843 -259.018956) (xy 108.103416 -258.994402) (xy 108.103925 -258.968435)
			(xy 108.11205 -258.91714) (xy 108.128098 -258.867747) (xy 108.151676 -258.821473) (xy 108.182202 -258.779457)
			(xy 108.218925 -258.742734) (xy 108.260941 -258.712208) (xy 108.307215 -258.68863) (xy 108.356608 -258.672582)
			(xy 108.407903 -258.664457) (xy 108.459837 -258.664457) (xy 108.511132 -258.672582) (xy 108.560525 -258.68863)
			(xy 108.606799 -258.712208) (xy 108.648815 -258.742734) (xy 108.685538 -258.779457) (xy 108.716064 -258.821473)
			(xy 108.720083 -258.829361) (xy 113.300003 -258.829361) (xy 113.300003 -258.777427) (xy 113.308128 -258.726132)
			(xy 113.324176 -258.676739) (xy 113.347754 -258.630465) (xy 113.37828 -258.588449) (xy 113.415003 -258.551726)
			(xy 113.457019 -258.5212) (xy 113.503293 -258.497622) (xy 113.552686 -258.481574) (xy 113.603981 -258.473449)
			(xy 113.655915 -258.473449) (xy 113.70721 -258.481574) (xy 113.756603 -258.497622) (xy 113.802877 -258.5212)
			(xy 113.844893 -258.551726) (xy 113.881616 -258.588449) (xy 113.912142 -258.630465) (xy 113.93572 -258.676739)
			(xy 113.951768 -258.726132) (xy 113.959893 -258.777427) (xy 113.960402 -258.803394) (xy 113.959893 -258.829361)
			(xy 113.951768 -258.880656) (xy 113.93572 -258.930049) (xy 113.912142 -258.976323) (xy 113.881616 -259.018339)
			(xy 113.844893 -259.055062) (xy 113.802877 -259.085588) (xy 113.756603 -259.109166) (xy 113.70721 -259.125214)
			(xy 113.655915 -259.133339) (xy 113.603981 -259.133339) (xy 113.552686 -259.125214) (xy 113.503293 -259.109166)
			(xy 113.457019 -259.085588) (xy 113.415003 -259.055062) (xy 113.37828 -259.018339) (xy 113.347754 -258.976323)
			(xy 113.324176 -258.930049) (xy 113.308128 -258.880656) (xy 113.300003 -258.829361) (xy 108.720083 -258.829361)
			(xy 108.739642 -258.867747) (xy 108.75569 -258.91714) (xy 108.763815 -258.968435) (xy 108.764324 -258.994402)
			(xy 108.763917 -259.018955) (xy 108.756669 -259.067524) (xy 108.742317 -259.114486) (xy 108.721178 -259.158809)
			(xy 108.693716 -259.199519) (xy 108.677456 -259.217922) (xy 108.667648 -259.229408) (xy 108.65463 -259.256646)
			(xy 108.650161 -259.286501) (xy 108.654631 -259.316357) (xy 108.66765 -259.343594) (xy 108.677456 -259.355082)
			(xy 108.693721 -259.373481) (xy 108.72119 -259.414186) (xy 108.742328 -259.458511) (xy 108.756669 -259.505476)
			(xy 108.763897 -259.554048) (xy 108.764324 -259.578602) (xy 108.763815 -259.604569) (xy 108.7577 -259.643177)
			(xy 110.010449 -259.643177) (xy 110.010449 -259.591243) (xy 110.018574 -259.539948) (xy 110.034622 -259.490555)
			(xy 110.0582 -259.444281) (xy 110.088726 -259.402265) (xy 110.125449 -259.365542) (xy 110.167465 -259.335016)
			(xy 110.213739 -259.311438) (xy 110.263132 -259.29539) (xy 110.314427 -259.287265) (xy 110.366361 -259.287265)
			(xy 110.417656 -259.29539) (xy 110.467049 -259.311438) (xy 110.513323 -259.335016) (xy 110.555339 -259.365542)
			(xy 110.592062 -259.402265) (xy 110.622588 -259.444281) (xy 110.646166 -259.490555) (xy 110.662214 -259.539948)
			(xy 110.670339 -259.591243) (xy 110.670848 -259.61721) (xy 110.670495 -259.635244) (xy 115.095782 -259.635244)
			(xy 115.096215 -259.610692) (xy 115.103457 -259.562124) (xy 115.117802 -259.515162) (xy 115.138936 -259.470838)
			(xy 115.166392 -259.430128) (xy 115.18265 -259.411724) (xy 115.192413 -259.400202) (xy 115.205435 -259.372977)
			(xy 115.209913 -259.343133) (xy 115.205454 -259.313285) (xy 115.192449 -259.286052) (xy 115.18265 -259.274564)
			(xy 115.166408 -259.256146) (xy 115.138935 -259.215446) (xy 115.117793 -259.171126) (xy 115.103447 -259.124165)
			(xy 115.096213 -259.075596) (xy 115.095782 -259.051044) (xy 115.096291 -259.025077) (xy 115.104416 -258.973782)
			(xy 115.120464 -258.924389) (xy 115.144042 -258.878115) (xy 115.174568 -258.836099) (xy 115.211291 -258.799376)
			(xy 115.253307 -258.76885) (xy 115.299581 -258.745272) (xy 115.348974 -258.729224) (xy 115.400269 -258.721099)
			(xy 115.452203 -258.721099) (xy 115.503498 -258.729224) (xy 115.552891 -258.745272) (xy 115.599165 -258.76885)
			(xy 115.641181 -258.799376) (xy 115.677904 -258.836099) (xy 115.70843 -258.878115) (xy 115.732008 -258.924389)
			(xy 115.748056 -258.973782) (xy 115.756181 -259.025077) (xy 115.75669 -259.051044) (xy 115.756257 -259.075596)
			(xy 115.749016 -259.124164) (xy 115.734671 -259.171126) (xy 115.713538 -259.21545) (xy 115.68608 -259.256161)
			(xy 115.669822 -259.274564) (xy 115.659975 -259.286019) (xy 115.646967 -259.313269) (xy 115.642507 -259.343133)
			(xy 115.646986 -259.372994) (xy 115.660012 -259.400235) (xy 115.669822 -259.411724) (xy 115.68607 -259.430137)
			(xy 115.713539 -259.470839) (xy 115.734679 -259.51516) (xy 115.749024 -259.562123) (xy 115.756259 -259.610691)
			(xy 115.75669 -259.635244) (xy 115.756181 -259.661211) (xy 115.748056 -259.712506) (xy 115.732008 -259.761899)
			(xy 115.70843 -259.808173) (xy 115.677904 -259.850189) (xy 115.641181 -259.886912) (xy 115.599165 -259.917438)
			(xy 115.552891 -259.941016) (xy 115.503498 -259.957064) (xy 115.452203 -259.965189) (xy 115.400269 -259.965189)
			(xy 115.348974 -259.957064) (xy 115.299581 -259.941016) (xy 115.253307 -259.917438) (xy 115.211291 -259.886912)
			(xy 115.174568 -259.850189) (xy 115.144042 -259.808173) (xy 115.120464 -259.761899) (xy 115.104416 -259.712506)
			(xy 115.096291 -259.661211) (xy 115.095782 -259.635244) (xy 110.670495 -259.635244) (xy 110.670339 -259.643177)
			(xy 110.662214 -259.694472) (xy 110.646166 -259.743865) (xy 110.622588 -259.790139) (xy 110.592062 -259.832155)
			(xy 110.555339 -259.868878) (xy 110.513323 -259.899404) (xy 110.467049 -259.922982) (xy 110.417656 -259.93903)
			(xy 110.366361 -259.947155) (xy 110.314427 -259.947155) (xy 110.263132 -259.93903) (xy 110.213739 -259.922982)
			(xy 110.167465 -259.899404) (xy 110.125449 -259.868878) (xy 110.088726 -259.832155) (xy 110.0582 -259.790139)
			(xy 110.034622 -259.743865) (xy 110.018574 -259.694472) (xy 110.010449 -259.643177) (xy 108.7577 -259.643177)
			(xy 108.75569 -259.655864) (xy 108.739642 -259.705257) (xy 108.716064 -259.751531) (xy 108.685538 -259.793547)
			(xy 108.648815 -259.83027) (xy 108.606799 -259.860796) (xy 108.560525 -259.884374) (xy 108.511132 -259.900422)
			(xy 108.459837 -259.908547) (xy 108.407903 -259.908547) (xy 108.356608 -259.900422) (xy 108.307215 -259.884374)
			(xy 108.260941 -259.860796) (xy 108.218925 -259.83027) (xy 108.182202 -259.793547) (xy 108.151676 -259.751531)
			(xy 108.128098 -259.705257) (xy 108.11205 -259.655864) (xy 108.103925 -259.604569) (xy 108.103416 -259.578602)
			(xy 105.294938 -259.578602) (xy 105.294938 -260.456993) (xy 113.300003 -260.456993) (xy 113.300003 -260.405059)
			(xy 113.308128 -260.353764) (xy 113.324176 -260.304371) (xy 113.347754 -260.258097) (xy 113.37828 -260.216081)
			(xy 113.415003 -260.179358) (xy 113.457019 -260.148832) (xy 113.503293 -260.125254) (xy 113.552686 -260.109206)
			(xy 113.603981 -260.101081) (xy 113.655915 -260.101081) (xy 113.70721 -260.109206) (xy 113.756603 -260.125254)
			(xy 113.802877 -260.148832) (xy 113.844893 -260.179358) (xy 113.881616 -260.216081) (xy 113.912142 -260.258097)
			(xy 113.93572 -260.304371) (xy 113.951768 -260.353764) (xy 113.959893 -260.405059) (xy 113.960402 -260.431026)
			(xy 113.959893 -260.456993) (xy 113.951768 -260.508288) (xy 113.93572 -260.557681) (xy 113.912142 -260.603955)
			(xy 113.881616 -260.645971) (xy 113.844893 -260.682694) (xy 113.802877 -260.71322) (xy 113.756603 -260.736798)
			(xy 113.70721 -260.752846) (xy 113.655915 -260.760971) (xy 113.603981 -260.760971) (xy 113.552686 -260.752846)
			(xy 113.503293 -260.736798) (xy 113.457019 -260.71322) (xy 113.415003 -260.682694) (xy 113.37828 -260.645971)
			(xy 113.347754 -260.603955) (xy 113.324176 -260.557681) (xy 113.308128 -260.508288) (xy 113.300003 -260.456993)
			(xy 105.294938 -260.456993) (xy 105.294938 -260.996684) (xy 105.336086 -261.004812) (xy 105.361703 -261.010296)
			(xy 105.410905 -261.028275) (xy 105.456649 -261.053802) (xy 105.497786 -261.086233) (xy 105.515918 -261.105142)
			(xy 105.525751 -261.115122) (xy 105.549635 -261.129748) (xy 105.576591 -261.137347) (xy 105.604597 -261.137347)
			(xy 105.631553 -261.129748) (xy 105.655437 -261.115122) (xy 105.66527 -261.105142) (xy 105.682415 -261.087197)
			(xy 105.721131 -261.056145) (xy 105.764058 -261.031237) (xy 105.810229 -261.013034) (xy 105.858604 -261.001945)
			(xy 105.908094 -260.998221) (xy 105.957584 -261.001945) (xy 106.005959 -261.013034) (xy 106.05213 -261.031237)
			(xy 106.095057 -261.056145) (xy 106.133773 -261.087197) (xy 106.150918 -261.105142) (xy 106.160751 -261.115122)
			(xy 106.184635 -261.129748) (xy 106.211591 -261.137347) (xy 106.239597 -261.137347) (xy 106.266553 -261.129748)
			(xy 106.290437 -261.115122) (xy 106.30027 -261.105142) (xy 106.317415 -261.087197) (xy 106.356131 -261.056145)
			(xy 106.399058 -261.031237) (xy 106.445229 -261.013034) (xy 106.493604 -261.001945) (xy 106.543094 -260.998221)
			(xy 106.592584 -261.001945) (xy 106.640959 -261.013034) (xy 106.68713 -261.031237) (xy 106.730057 -261.056145)
			(xy 106.768773 -261.087197) (xy 106.785918 -261.105142) (xy 106.795751 -261.115122) (xy 106.819635 -261.129748)
			(xy 106.846591 -261.137347) (xy 106.874597 -261.137347) (xy 106.901553 -261.129748) (xy 106.925437 -261.115122)
			(xy 106.93527 -261.105142) (xy 106.954182 -261.085448) (xy 106.997279 -261.051931) (xy 107.045302 -261.02596)
			(xy 107.096943 -261.008242) (xy 107.150796 -260.99926) (xy 107.178094 -260.998716) (xy 107.204066 -260.999198)
			(xy 107.25537 -261.007323) (xy 107.304772 -261.023374) (xy 107.351055 -261.046956) (xy 107.393079 -261.077487)
			(xy 107.429809 -261.114217) (xy 107.460341 -261.15624) (xy 107.483923 -261.202522) (xy 107.499975 -261.251924)
			(xy 107.503006 -261.271063) (xy 110.010449 -261.271063) (xy 110.010449 -261.219129) (xy 110.018574 -261.167834)
			(xy 110.034622 -261.118441) (xy 110.0582 -261.072167) (xy 110.088726 -261.030151) (xy 110.125449 -260.993428)
			(xy 110.167465 -260.962902) (xy 110.213739 -260.939324) (xy 110.263132 -260.923276) (xy 110.314427 -260.915151)
			(xy 110.366361 -260.915151) (xy 110.417656 -260.923276) (xy 110.467049 -260.939324) (xy 110.513323 -260.962902)
			(xy 110.555339 -260.993428) (xy 110.592062 -261.030151) (xy 110.622588 -261.072167) (xy 110.646166 -261.118441)
			(xy 110.662214 -261.167834) (xy 110.670339 -261.219129) (xy 110.670848 -261.245096) (xy 110.670339 -261.271063)
			(xy 110.662214 -261.322358) (xy 110.646166 -261.371751) (xy 110.622588 -261.418025) (xy 110.592062 -261.460041)
			(xy 110.555339 -261.496764) (xy 110.513323 -261.52729) (xy 110.467049 -261.550868) (xy 110.417656 -261.566916)
			(xy 110.366361 -261.575041) (xy 110.314427 -261.575041) (xy 110.263132 -261.566916) (xy 110.213739 -261.550868)
			(xy 110.167465 -261.52729) (xy 110.125449 -261.496764) (xy 110.088726 -261.460041) (xy 110.0582 -261.418025)
			(xy 110.034622 -261.371751) (xy 110.018574 -261.322358) (xy 110.010449 -261.271063) (xy 107.503006 -261.271063)
			(xy 107.508101 -261.303228) (xy 107.508101 -261.355172) (xy 107.499975 -261.406476) (xy 107.483923 -261.455878)
			(xy 107.460341 -261.50216) (xy 107.429809 -261.544183) (xy 107.393079 -261.580913) (xy 107.351055 -261.611444)
			(xy 107.304772 -261.635026) (xy 107.25537 -261.651077) (xy 107.204066 -261.659202) (xy 107.178094 -261.659624)
			(xy 107.150797 -261.659061) (xy 107.096947 -261.650081) (xy 107.045307 -261.632366) (xy 106.997285 -261.606398)
			(xy 106.954187 -261.572885) (xy 106.93527 -261.553198) (xy 106.925437 -261.543218) (xy 106.901553 -261.528592)
			(xy 106.874597 -261.520993) (xy 106.846591 -261.520993) (xy 106.819635 -261.528592) (xy 106.795751 -261.543218)
			(xy 106.785918 -261.553198) (xy 106.768773 -261.571143) (xy 106.730057 -261.602195) (xy 106.68713 -261.627103)
			(xy 106.640959 -261.645306) (xy 106.592584 -261.656395) (xy 106.543094 -261.660119) (xy 106.493604 -261.656395)
			(xy 106.445229 -261.645306) (xy 106.399058 -261.627103) (xy 106.356131 -261.602195) (xy 106.317415 -261.571143)
			(xy 106.30027 -261.553198) (xy 106.290437 -261.543218) (xy 106.266553 -261.528592) (xy 106.239597 -261.520993)
			(xy 106.211591 -261.520993) (xy 106.184635 -261.528592) (xy 106.160751 -261.543218) (xy 106.150918 -261.553198)
			(xy 106.133773 -261.571143) (xy 106.095057 -261.602195) (xy 106.05213 -261.627103) (xy 106.005959 -261.645306)
			(xy 105.957584 -261.656395) (xy 105.908094 -261.660119) (xy 105.858604 -261.656395) (xy 105.810229 -261.645306)
			(xy 105.764058 -261.627103) (xy 105.721131 -261.602195) (xy 105.682415 -261.571143) (xy 105.66527 -261.553198)
			(xy 105.655437 -261.543218) (xy 105.631553 -261.528592) (xy 105.604597 -261.520993) (xy 105.576591 -261.520993)
			(xy 105.549635 -261.528592) (xy 105.525751 -261.543218) (xy 105.515918 -261.553198) (xy 105.497788 -261.572106)
			(xy 105.456637 -261.604516) (xy 105.410892 -261.630034) (xy 105.361696 -261.648022) (xy 105.336086 -261.653528)
			(xy 105.294938 -261.661656) (xy 105.294938 -262.084879) (xy 113.300003 -262.084879) (xy 113.300003 -262.032945)
			(xy 113.308128 -261.98165) (xy 113.324176 -261.932257) (xy 113.347754 -261.885983) (xy 113.37828 -261.843967)
			(xy 113.415003 -261.807244) (xy 113.457019 -261.776718) (xy 113.503293 -261.75314) (xy 113.552686 -261.737092)
			(xy 113.603981 -261.728967) (xy 113.655915 -261.728967) (xy 113.70721 -261.737092) (xy 113.756603 -261.75314)
			(xy 113.802877 -261.776718) (xy 113.844893 -261.807244) (xy 113.881616 -261.843967) (xy 113.912142 -261.885983)
			(xy 113.93572 -261.932257) (xy 113.951768 -261.98165) (xy 113.959893 -262.032945) (xy 113.960402 -262.058912)
			(xy 113.959893 -262.084879) (xy 113.951768 -262.136174) (xy 113.93572 -262.185567) (xy 113.912142 -262.231841)
			(xy 113.881616 -262.273857) (xy 113.844893 -262.31058) (xy 113.802877 -262.341106) (xy 113.756603 -262.364684)
			(xy 113.70721 -262.380732) (xy 113.655915 -262.388857) (xy 113.603981 -262.388857) (xy 113.552686 -262.380732)
			(xy 113.503293 -262.364684) (xy 113.457019 -262.341106) (xy 113.415003 -262.31058) (xy 113.37828 -262.273857)
			(xy 113.347754 -262.231841) (xy 113.324176 -262.185567) (xy 113.308128 -262.136174) (xy 113.300003 -262.084879)
			(xy 105.294938 -262.084879) (xy 105.294938 -262.898695) (xy 110.010703 -262.898695) (xy 110.010703 -262.846761)
			(xy 110.018828 -262.795466) (xy 110.034876 -262.746073) (xy 110.058454 -262.699799) (xy 110.08898 -262.657783)
			(xy 110.125703 -262.62106) (xy 110.167719 -262.590534) (xy 110.213993 -262.566956) (xy 110.263386 -262.550908)
			(xy 110.314681 -262.542783) (xy 110.366615 -262.542783) (xy 110.41791 -262.550908) (xy 110.467303 -262.566956)
			(xy 110.513577 -262.590534) (xy 110.555593 -262.62106) (xy 110.592316 -262.657783) (xy 110.622842 -262.699799)
			(xy 110.64642 -262.746073) (xy 110.662468 -262.795466) (xy 110.670593 -262.846761) (xy 110.671102 -262.872728)
			(xy 110.670593 -262.898695) (xy 110.662468 -262.94999) (xy 110.64642 -262.999383) (xy 110.622842 -263.045657)
			(xy 110.592316 -263.087673) (xy 110.555593 -263.124396) (xy 110.513577 -263.154922) (xy 110.467303 -263.1785)
			(xy 110.41791 -263.194548) (xy 110.366615 -263.202673) (xy 110.314681 -263.202673) (xy 110.263386 -263.194548)
			(xy 110.213993 -263.1785) (xy 110.167719 -263.154922) (xy 110.125703 -263.124396) (xy 110.08898 -263.087673)
			(xy 110.058454 -263.045657) (xy 110.034876 -262.999383) (xy 110.018828 -262.94999) (xy 110.010703 -262.898695)
			(xy 105.294938 -262.898695) (xy 105.294938 -263.41451) (xy 104.706166 -264.003282) (xy 104.696694 -264.013416)
			(xy 104.683082 -264.037573) (xy 104.676465 -264.064499) (xy 104.677329 -264.092213) (xy 104.685611 -264.118674)
			(xy 104.700702 -264.141936) (xy 104.721489 -264.160285) (xy 104.746444 -264.17237) (xy 104.760014 -264.17524)
			(xy 104.785115 -264.180218) (xy 104.833493 -264.19689) (xy 104.87872 -264.220829) (xy 104.91971 -264.251459)
			(xy 104.955484 -264.288047) (xy 104.985183 -264.329717) (xy 105.008096 -264.375471) (xy 105.023676 -264.424213)
			(xy 105.031547 -264.474774) (xy 105.032048 -264.50036) (xy 105.031568 -264.526327) (xy 105.311449 -264.526327)
			(xy 105.311449 -264.474393) (xy 105.319574 -264.423098) (xy 105.335622 -264.373705) (xy 105.3592 -264.327431)
			(xy 105.389726 -264.285415) (xy 105.426449 -264.248692) (xy 105.468465 -264.218166) (xy 105.514739 -264.194588)
			(xy 105.564132 -264.17854) (xy 105.615427 -264.170415) (xy 105.667361 -264.170415) (xy 105.718656 -264.17854)
			(xy 105.768049 -264.194588) (xy 105.814323 -264.218166) (xy 105.856339 -264.248692) (xy 105.893062 -264.285415)
			(xy 105.923588 -264.327431) (xy 105.947166 -264.373705) (xy 105.963214 -264.423098) (xy 105.971339 -264.474393)
			(xy 105.971848 -264.50036) (xy 105.971339 -264.526327) (xy 106.251249 -264.526327) (xy 106.251249 -264.474393)
			(xy 106.259374 -264.423098) (xy 106.275422 -264.373705) (xy 106.299 -264.327431) (xy 106.329526 -264.285415)
			(xy 106.366249 -264.248692) (xy 106.408265 -264.218166) (xy 106.454539 -264.194588) (xy 106.503932 -264.17854)
			(xy 106.555227 -264.170415) (xy 106.607161 -264.170415) (xy 106.658456 -264.17854) (xy 106.707849 -264.194588)
			(xy 106.754123 -264.218166) (xy 106.796139 -264.248692) (xy 106.832862 -264.285415) (xy 106.863388 -264.327431)
			(xy 106.886966 -264.373705) (xy 106.903014 -264.423098) (xy 106.911139 -264.474393) (xy 106.911648 -264.50036)
			(xy 106.911139 -264.526327) (xy 107.191303 -264.526327) (xy 107.191303 -264.474393) (xy 107.199428 -264.423098)
			(xy 107.215476 -264.373705) (xy 107.239054 -264.327431) (xy 107.26958 -264.285415) (xy 107.306303 -264.248692)
			(xy 107.348319 -264.218166) (xy 107.394593 -264.194588) (xy 107.443986 -264.17854) (xy 107.495281 -264.170415)
			(xy 107.547215 -264.170415) (xy 107.59851 -264.17854) (xy 107.647903 -264.194588) (xy 107.694177 -264.218166)
			(xy 107.736193 -264.248692) (xy 107.772916 -264.285415) (xy 107.803442 -264.327431) (xy 107.82702 -264.373705)
			(xy 107.843068 -264.423098) (xy 107.851193 -264.474393) (xy 107.851702 -264.50036) (xy 107.851193 -264.526327)
			(xy 108.131103 -264.526327) (xy 108.131103 -264.474393) (xy 108.139228 -264.423098) (xy 108.155276 -264.373705)
			(xy 108.178854 -264.327431) (xy 108.20938 -264.285415) (xy 108.246103 -264.248692) (xy 108.288119 -264.218166)
			(xy 108.334393 -264.194588) (xy 108.383786 -264.17854) (xy 108.435081 -264.170415) (xy 108.487015 -264.170415)
			(xy 108.53831 -264.17854) (xy 108.587703 -264.194588) (xy 108.633977 -264.218166) (xy 108.675993 -264.248692)
			(xy 108.712716 -264.285415) (xy 108.743242 -264.327431) (xy 108.76682 -264.373705) (xy 108.782868 -264.423098)
			(xy 108.790993 -264.474393) (xy 108.791502 -264.50036) (xy 108.790993 -264.526327) (xy 108.782868 -264.577622)
			(xy 108.76682 -264.627015) (xy 108.743242 -264.673289) (xy 108.712716 -264.715305) (xy 108.675993 -264.752028)
			(xy 108.633977 -264.782554) (xy 108.587703 -264.806132) (xy 108.53831 -264.82218) (xy 108.487015 -264.830305)
			(xy 108.435081 -264.830305) (xy 108.383786 -264.82218) (xy 108.334393 -264.806132) (xy 108.288119 -264.782554)
			(xy 108.246103 -264.752028) (xy 108.20938 -264.715305) (xy 108.178854 -264.673289) (xy 108.155276 -264.627015)
			(xy 108.139228 -264.577622) (xy 108.131103 -264.526327) (xy 107.851193 -264.526327) (xy 107.843068 -264.577622)
			(xy 107.82702 -264.627015) (xy 107.803442 -264.673289) (xy 107.772916 -264.715305) (xy 107.736193 -264.752028)
			(xy 107.694177 -264.782554) (xy 107.647903 -264.806132) (xy 107.59851 -264.82218) (xy 107.547215 -264.830305)
			(xy 107.495281 -264.830305) (xy 107.443986 -264.82218) (xy 107.394593 -264.806132) (xy 107.348319 -264.782554)
			(xy 107.306303 -264.752028) (xy 107.26958 -264.715305) (xy 107.239054 -264.673289) (xy 107.215476 -264.627015)
			(xy 107.199428 -264.577622) (xy 107.191303 -264.526327) (xy 106.911139 -264.526327) (xy 106.903014 -264.577622)
			(xy 106.886966 -264.627015) (xy 106.863388 -264.673289) (xy 106.832862 -264.715305) (xy 106.796139 -264.752028)
			(xy 106.754123 -264.782554) (xy 106.707849 -264.806132) (xy 106.658456 -264.82218) (xy 106.607161 -264.830305)
			(xy 106.555227 -264.830305) (xy 106.503932 -264.82218) (xy 106.454539 -264.806132) (xy 106.408265 -264.782554)
			(xy 106.366249 -264.752028) (xy 106.329526 -264.715305) (xy 106.299 -264.673289) (xy 106.275422 -264.627015)
			(xy 106.259374 -264.577622) (xy 106.251249 -264.526327) (xy 105.971339 -264.526327) (xy 105.963214 -264.577622)
			(xy 105.947166 -264.627015) (xy 105.923588 -264.673289) (xy 105.893062 -264.715305) (xy 105.856339 -264.752028)
			(xy 105.814323 -264.782554) (xy 105.768049 -264.806132) (xy 105.718656 -264.82218) (xy 105.667361 -264.830305)
			(xy 105.615427 -264.830305) (xy 105.564132 -264.82218) (xy 105.514739 -264.806132) (xy 105.468465 -264.782554)
			(xy 105.426449 -264.752028) (xy 105.389726 -264.715305) (xy 105.3592 -264.673289) (xy 105.335622 -264.627015)
			(xy 105.319574 -264.577622) (xy 105.311449 -264.526327) (xy 105.031568 -264.526327) (xy 105.031568 -264.526331)
			(xy 105.023448 -264.577635) (xy 105.007402 -264.627036) (xy 104.983824 -264.673319) (xy 104.953296 -264.715343)
			(xy 104.916569 -264.752074) (xy 104.874548 -264.782606) (xy 104.828268 -264.806189) (xy 104.778868 -264.82224)
			(xy 104.727565 -264.830365) (xy 104.701594 -264.830814) (xy 104.676012 -264.830327) (xy 104.625463 -264.822424)
			(xy 104.576735 -264.806823) (xy 104.530995 -264.783898) (xy 104.489336 -264.754197) (xy 104.452752 -264.718428)
			(xy 104.42212 -264.677448) (xy 104.39817 -264.632236) (xy 104.381476 -264.583873) (xy 104.376474 -264.55878)
			(xy 104.373557 -264.545217) (xy 104.361485 -264.520254) (xy 104.343145 -264.499456) (xy 104.319887 -264.484356)
			(xy 104.293425 -264.476067) (xy 104.265709 -264.475199) (xy 104.238781 -264.481817) (xy 104.214624 -264.495432)
			(xy 104.204516 -264.504932) (xy 104.053386 -264.656062) (xy 104.04983 -264.662158) (xy 104.038437 -264.681688)
			(xy 104.011128 -264.717723) (xy 103.979158 -264.749697) (xy 103.943127 -264.777012) (xy 103.923592 -264.788396)
			(xy 103.917496 -264.791952) (xy 103.573072 -265.136376) (xy 103.589074 -265.168888) (xy 103.599629 -265.191549)
			(xy 103.614548 -265.23926) (xy 103.622111 -265.288674) (xy 103.622602 -265.313668) (xy 103.622602 -265.314176)
			(xy 103.622095 -265.340143) (xy 103.902003 -265.340143) (xy 103.902003 -265.288209) (xy 103.910128 -265.236914)
			(xy 103.926176 -265.187521) (xy 103.949754 -265.141247) (xy 103.98028 -265.099231) (xy 104.017003 -265.062508)
			(xy 104.059019 -265.031982) (xy 104.105293 -265.008404) (xy 104.154686 -264.992356) (xy 104.205981 -264.984231)
			(xy 104.257915 -264.984231) (xy 104.30921 -264.992356) (xy 104.358603 -265.008404) (xy 104.404877 -265.031982)
			(xy 104.446893 -265.062508) (xy 104.483616 -265.099231) (xy 104.514142 -265.141247) (xy 104.53772 -265.187521)
			(xy 104.553768 -265.236914) (xy 104.561893 -265.288209) (xy 104.562402 -265.314176) (xy 104.561893 -265.340143)
			(xy 104.841803 -265.340143) (xy 104.841803 -265.288209) (xy 104.849928 -265.236914) (xy 104.865976 -265.187521)
			(xy 104.889554 -265.141247) (xy 104.92008 -265.099231) (xy 104.956803 -265.062508) (xy 104.998819 -265.031982)
			(xy 105.045093 -265.008404) (xy 105.094486 -264.992356) (xy 105.145781 -264.984231) (xy 105.197715 -264.984231)
			(xy 105.24901 -264.992356) (xy 105.298403 -265.008404) (xy 105.344677 -265.031982) (xy 105.386693 -265.062508)
			(xy 105.423416 -265.099231) (xy 105.453942 -265.141247) (xy 105.47752 -265.187521) (xy 105.493568 -265.236914)
			(xy 105.501693 -265.288209) (xy 105.502202 -265.314176) (xy 105.501693 -265.340143) (xy 105.781603 -265.340143)
			(xy 105.781603 -265.288209) (xy 105.789728 -265.236914) (xy 105.805776 -265.187521) (xy 105.829354 -265.141247)
			(xy 105.85988 -265.099231) (xy 105.896603 -265.062508) (xy 105.938619 -265.031982) (xy 105.984893 -265.008404)
			(xy 106.034286 -264.992356) (xy 106.085581 -264.984231) (xy 106.137515 -264.984231) (xy 106.18881 -264.992356)
			(xy 106.238203 -265.008404) (xy 106.284477 -265.031982) (xy 106.326493 -265.062508) (xy 106.363216 -265.099231)
			(xy 106.393742 -265.141247) (xy 106.41732 -265.187521) (xy 106.433368 -265.236914) (xy 106.441493 -265.288209)
			(xy 106.442002 -265.314176) (xy 106.441493 -265.340143) (xy 106.721403 -265.340143) (xy 106.721403 -265.288209)
			(xy 106.729528 -265.236914) (xy 106.745576 -265.187521) (xy 106.769154 -265.141247) (xy 106.79968 -265.099231)
			(xy 106.836403 -265.062508) (xy 106.878419 -265.031982) (xy 106.924693 -265.008404) (xy 106.974086 -264.992356)
			(xy 107.025381 -264.984231) (xy 107.077315 -264.984231) (xy 107.12861 -264.992356) (xy 107.178003 -265.008404)
			(xy 107.224277 -265.031982) (xy 107.266293 -265.062508) (xy 107.303016 -265.099231) (xy 107.333542 -265.141247)
			(xy 107.35712 -265.187521) (xy 107.373168 -265.236914) (xy 107.381293 -265.288209) (xy 107.381802 -265.314176)
			(xy 107.381293 -265.340143) (xy 107.661203 -265.340143) (xy 107.661203 -265.288209) (xy 107.669328 -265.236914)
			(xy 107.685376 -265.187521) (xy 107.708954 -265.141247) (xy 107.73948 -265.099231) (xy 107.776203 -265.062508)
			(xy 107.818219 -265.031982) (xy 107.864493 -265.008404) (xy 107.913886 -264.992356) (xy 107.965181 -264.984231)
			(xy 108.017115 -264.984231) (xy 108.06841 -264.992356) (xy 108.117803 -265.008404) (xy 108.164077 -265.031982)
			(xy 108.206093 -265.062508) (xy 108.242816 -265.099231) (xy 108.273342 -265.141247) (xy 108.29692 -265.187521)
			(xy 108.312968 -265.236914) (xy 108.321093 -265.288209) (xy 108.321602 -265.314176) (xy 108.321093 -265.340143)
			(xy 108.601003 -265.340143) (xy 108.601003 -265.288209) (xy 108.609128 -265.236914) (xy 108.625176 -265.187521)
			(xy 108.648754 -265.141247) (xy 108.67928 -265.099231) (xy 108.716003 -265.062508) (xy 108.758019 -265.031982)
			(xy 108.804293 -265.008404) (xy 108.853686 -264.992356) (xy 108.904981 -264.984231) (xy 108.956915 -264.984231)
			(xy 109.00821 -264.992356) (xy 109.057603 -265.008404) (xy 109.103877 -265.031982) (xy 109.145893 -265.062508)
			(xy 109.182616 -265.099231) (xy 109.213142 -265.141247) (xy 109.23672 -265.187521) (xy 109.252768 -265.236914)
			(xy 109.260893 -265.288209) (xy 109.261402 -265.314176) (xy 109.260893 -265.340143) (xy 109.252768 -265.391438)
			(xy 109.23672 -265.440831) (xy 109.213142 -265.487105) (xy 109.182616 -265.529121) (xy 109.145893 -265.565844)
			(xy 109.103877 -265.59637) (xy 109.057603 -265.619948) (xy 109.00821 -265.635996) (xy 108.956915 -265.644121)
			(xy 108.904981 -265.644121) (xy 108.853686 -265.635996) (xy 108.804293 -265.619948) (xy 108.758019 -265.59637)
			(xy 108.716003 -265.565844) (xy 108.67928 -265.529121) (xy 108.648754 -265.487105) (xy 108.625176 -265.440831)
			(xy 108.609128 -265.391438) (xy 108.601003 -265.340143) (xy 108.321093 -265.340143) (xy 108.312968 -265.391438)
			(xy 108.29692 -265.440831) (xy 108.273342 -265.487105) (xy 108.242816 -265.529121) (xy 108.206093 -265.565844)
			(xy 108.164077 -265.59637) (xy 108.117803 -265.619948) (xy 108.06841 -265.635996) (xy 108.017115 -265.644121)
			(xy 107.965181 -265.644121) (xy 107.913886 -265.635996) (xy 107.864493 -265.619948) (xy 107.818219 -265.59637)
			(xy 107.776203 -265.565844) (xy 107.73948 -265.529121) (xy 107.708954 -265.487105) (xy 107.685376 -265.440831)
			(xy 107.669328 -265.391438) (xy 107.661203 -265.340143) (xy 107.381293 -265.340143) (xy 107.373168 -265.391438)
			(xy 107.35712 -265.440831) (xy 107.333542 -265.487105) (xy 107.303016 -265.529121) (xy 107.266293 -265.565844)
			(xy 107.224277 -265.59637) (xy 107.178003 -265.619948) (xy 107.12861 -265.635996) (xy 107.077315 -265.644121)
			(xy 107.025381 -265.644121) (xy 106.974086 -265.635996) (xy 106.924693 -265.619948) (xy 106.878419 -265.59637)
			(xy 106.836403 -265.565844) (xy 106.79968 -265.529121) (xy 106.769154 -265.487105) (xy 106.745576 -265.440831)
			(xy 106.729528 -265.391438) (xy 106.721403 -265.340143) (xy 106.441493 -265.340143) (xy 106.433368 -265.391438)
			(xy 106.41732 -265.440831) (xy 106.393742 -265.487105) (xy 106.363216 -265.529121) (xy 106.326493 -265.565844)
			(xy 106.284477 -265.59637) (xy 106.238203 -265.619948) (xy 106.18881 -265.635996) (xy 106.137515 -265.644121)
			(xy 106.085581 -265.644121) (xy 106.034286 -265.635996) (xy 105.984893 -265.619948) (xy 105.938619 -265.59637)
			(xy 105.896603 -265.565844) (xy 105.85988 -265.529121) (xy 105.829354 -265.487105) (xy 105.805776 -265.440831)
			(xy 105.789728 -265.391438) (xy 105.781603 -265.340143) (xy 105.501693 -265.340143) (xy 105.493568 -265.391438)
			(xy 105.47752 -265.440831) (xy 105.453942 -265.487105) (xy 105.423416 -265.529121) (xy 105.386693 -265.565844)
			(xy 105.344677 -265.59637) (xy 105.298403 -265.619948) (xy 105.24901 -265.635996) (xy 105.197715 -265.644121)
			(xy 105.145781 -265.644121) (xy 105.094486 -265.635996) (xy 105.045093 -265.619948) (xy 104.998819 -265.59637)
			(xy 104.956803 -265.565844) (xy 104.92008 -265.529121) (xy 104.889554 -265.487105) (xy 104.865976 -265.440831)
			(xy 104.849928 -265.391438) (xy 104.841803 -265.340143) (xy 104.561893 -265.340143) (xy 104.553768 -265.391438)
			(xy 104.53772 -265.440831) (xy 104.514142 -265.487105) (xy 104.483616 -265.529121) (xy 104.446893 -265.565844)
			(xy 104.404877 -265.59637) (xy 104.358603 -265.619948) (xy 104.30921 -265.635996) (xy 104.257915 -265.644121)
			(xy 104.205981 -265.644121) (xy 104.154686 -265.635996) (xy 104.105293 -265.619948) (xy 104.059019 -265.59637)
			(xy 104.017003 -265.565844) (xy 103.98028 -265.529121) (xy 103.949754 -265.487105) (xy 103.926176 -265.440831)
			(xy 103.910128 -265.391438) (xy 103.902003 -265.340143) (xy 103.622095 -265.340143) (xy 103.622095 -265.340146)
			(xy 103.613974 -265.391447) (xy 103.597928 -265.440845) (xy 103.574352 -265.487126) (xy 103.543827 -265.529149)
			(xy 103.507104 -265.56588) (xy 103.465088 -265.596414) (xy 103.418812 -265.62) (xy 103.369417 -265.636057)
			(xy 103.318118 -265.644189) (xy 103.292148 -265.64463) (xy 103.29164 -265.64463) (xy 103.266645 -265.644151)
			(xy 103.217232 -265.636582) (xy 103.169522 -265.621656) (xy 103.14686 -265.611102) (xy 103.114348 -265.5951)
			(xy 103.003096 -265.706352) (xy 102.993041 -265.717078) (xy 102.979017 -265.742903) (xy 102.97293 -265.771653)
			(xy 102.975286 -265.800946) (xy 102.98589 -265.828353) (xy 103.003862 -265.851604) (xy 103.015542 -265.86053)
			(xy 103.036361 -265.876164) (xy 103.073266 -265.912885) (xy 103.10395 -265.954944) (xy 103.127653 -266.001298)
			(xy 103.143786 -266.050797) (xy 103.15195 -266.102215) (xy 103.152448 -266.128246) (xy 103.151935 -266.154211)
			(xy 103.151935 -266.154213) (xy 103.431849 -266.154213) (xy 103.431849 -266.102279) (xy 103.439974 -266.050984)
			(xy 103.456022 -266.001591) (xy 103.4796 -265.955317) (xy 103.510126 -265.913301) (xy 103.546849 -265.876578)
			(xy 103.588865 -265.846052) (xy 103.635139 -265.822474) (xy 103.684532 -265.806426) (xy 103.735827 -265.798301)
			(xy 103.787761 -265.798301) (xy 103.839056 -265.806426) (xy 103.888449 -265.822474) (xy 103.934723 -265.846052)
			(xy 103.976739 -265.876578) (xy 104.013462 -265.913301) (xy 104.043988 -265.955317) (xy 104.067566 -266.001591)
			(xy 104.083614 -266.050984) (xy 104.091739 -266.102279) (xy 104.092248 -266.128246) (xy 104.091739 -266.154213)
			(xy 104.371649 -266.154213) (xy 104.371649 -266.102279) (xy 104.379774 -266.050984) (xy 104.395822 -266.001591)
			(xy 104.4194 -265.955317) (xy 104.449926 -265.913301) (xy 104.486649 -265.876578) (xy 104.528665 -265.846052)
			(xy 104.574939 -265.822474) (xy 104.624332 -265.806426) (xy 104.675627 -265.798301) (xy 104.727561 -265.798301)
			(xy 104.778856 -265.806426) (xy 104.828249 -265.822474) (xy 104.874523 -265.846052) (xy 104.916539 -265.876578)
			(xy 104.953262 -265.913301) (xy 104.983788 -265.955317) (xy 105.007366 -266.001591) (xy 105.023414 -266.050984)
			(xy 105.031539 -266.102279) (xy 105.032048 -266.128246) (xy 105.031539 -266.154213) (xy 105.311449 -266.154213)
			(xy 105.311449 -266.102279) (xy 105.319574 -266.050984) (xy 105.335622 -266.001591) (xy 105.3592 -265.955317)
			(xy 105.389726 -265.913301) (xy 105.426449 -265.876578) (xy 105.468465 -265.846052) (xy 105.514739 -265.822474)
			(xy 105.564132 -265.806426) (xy 105.615427 -265.798301) (xy 105.667361 -265.798301) (xy 105.718656 -265.806426)
			(xy 105.768049 -265.822474) (xy 105.814323 -265.846052) (xy 105.856339 -265.876578) (xy 105.893062 -265.913301)
			(xy 105.923588 -265.955317) (xy 105.947166 -266.001591) (xy 105.963214 -266.050984) (xy 105.971339 -266.102279)
			(xy 105.971848 -266.128246) (xy 105.971339 -266.154213) (xy 106.251249 -266.154213) (xy 106.251249 -266.102279)
			(xy 106.259374 -266.050984) (xy 106.275422 -266.001591) (xy 106.299 -265.955317) (xy 106.329526 -265.913301)
			(xy 106.366249 -265.876578) (xy 106.408265 -265.846052) (xy 106.454539 -265.822474) (xy 106.503932 -265.806426)
			(xy 106.555227 -265.798301) (xy 106.607161 -265.798301) (xy 106.658456 -265.806426) (xy 106.707849 -265.822474)
			(xy 106.754123 -265.846052) (xy 106.796139 -265.876578) (xy 106.832862 -265.913301) (xy 106.863388 -265.955317)
			(xy 106.886966 -266.001591) (xy 106.903014 -266.050984) (xy 106.911139 -266.102279) (xy 106.911648 -266.128246)
			(xy 106.911139 -266.154213) (xy 107.191049 -266.154213) (xy 107.191049 -266.102279) (xy 107.199174 -266.050984)
			(xy 107.215222 -266.001591) (xy 107.2388 -265.955317) (xy 107.269326 -265.913301) (xy 107.306049 -265.876578)
			(xy 107.348065 -265.846052) (xy 107.394339 -265.822474) (xy 107.443732 -265.806426) (xy 107.495027 -265.798301)
			(xy 107.546961 -265.798301) (xy 107.598256 -265.806426) (xy 107.647649 -265.822474) (xy 107.693923 -265.846052)
			(xy 107.735939 -265.876578) (xy 107.772662 -265.913301) (xy 107.803188 -265.955317) (xy 107.826766 -266.001591)
			(xy 107.842814 -266.050984) (xy 107.850939 -266.102279) (xy 107.851448 -266.128246) (xy 107.850939 -266.154213)
			(xy 108.130849 -266.154213) (xy 108.130849 -266.102279) (xy 108.138974 -266.050984) (xy 108.155022 -266.001591)
			(xy 108.1786 -265.955317) (xy 108.209126 -265.913301) (xy 108.245849 -265.876578) (xy 108.287865 -265.846052)
			(xy 108.334139 -265.822474) (xy 108.383532 -265.806426) (xy 108.434827 -265.798301) (xy 108.486761 -265.798301)
			(xy 108.538056 -265.806426) (xy 108.587449 -265.822474) (xy 108.633723 -265.846052) (xy 108.675739 -265.876578)
			(xy 108.712462 -265.913301) (xy 108.742988 -265.955317) (xy 108.766566 -266.001591) (xy 108.782614 -266.050984)
			(xy 108.790739 -266.102279) (xy 108.791248 -266.128246) (xy 108.790739 -266.154213) (xy 109.070903 -266.154213)
			(xy 109.070903 -266.102279) (xy 109.079028 -266.050984) (xy 109.095076 -266.001591) (xy 109.118654 -265.955317)
			(xy 109.14918 -265.913301) (xy 109.185903 -265.876578) (xy 109.227919 -265.846052) (xy 109.274193 -265.822474)
			(xy 109.323586 -265.806426) (xy 109.374881 -265.798301) (xy 109.426815 -265.798301) (xy 109.47811 -265.806426)
			(xy 109.527503 -265.822474) (xy 109.573777 -265.846052) (xy 109.615793 -265.876578) (xy 109.652516 -265.913301)
			(xy 109.683042 -265.955317) (xy 109.70662 -266.001591) (xy 109.722668 -266.050984) (xy 109.730793 -266.102279)
			(xy 109.731302 -266.128246) (xy 109.730793 -266.154213) (xy 109.722668 -266.205508) (xy 109.70662 -266.254901)
			(xy 109.683042 -266.301175) (xy 109.652516 -266.343191) (xy 109.615793 -266.379914) (xy 109.573777 -266.41044)
			(xy 109.527503 -266.434018) (xy 109.47811 -266.450066) (xy 109.426815 -266.458191) (xy 109.374881 -266.458191)
			(xy 109.323586 -266.450066) (xy 109.274193 -266.434018) (xy 109.227919 -266.41044) (xy 109.185903 -266.379914)
			(xy 109.14918 -266.343191) (xy 109.118654 -266.301175) (xy 109.095076 -266.254901) (xy 109.079028 -266.205508)
			(xy 109.070903 -266.154213) (xy 108.790739 -266.154213) (xy 108.782614 -266.205508) (xy 108.766566 -266.254901)
			(xy 108.742988 -266.301175) (xy 108.712462 -266.343191) (xy 108.675739 -266.379914) (xy 108.633723 -266.41044)
			(xy 108.587449 -266.434018) (xy 108.538056 -266.450066) (xy 108.486761 -266.458191) (xy 108.434827 -266.458191)
			(xy 108.383532 -266.450066) (xy 108.334139 -266.434018) (xy 108.287865 -266.41044) (xy 108.245849 -266.379914)
			(xy 108.209126 -266.343191) (xy 108.1786 -266.301175) (xy 108.155022 -266.254901) (xy 108.138974 -266.205508)
			(xy 108.130849 -266.154213) (xy 107.850939 -266.154213) (xy 107.842814 -266.205508) (xy 107.826766 -266.254901)
			(xy 107.803188 -266.301175) (xy 107.772662 -266.343191) (xy 107.735939 -266.379914) (xy 107.693923 -266.41044)
			(xy 107.647649 -266.434018) (xy 107.598256 -266.450066) (xy 107.546961 -266.458191) (xy 107.495027 -266.458191)
			(xy 107.443732 -266.450066) (xy 107.394339 -266.434018) (xy 107.348065 -266.41044) (xy 107.306049 -266.379914)
			(xy 107.269326 -266.343191) (xy 107.2388 -266.301175) (xy 107.215222 -266.254901) (xy 107.199174 -266.205508)
			(xy 107.191049 -266.154213) (xy 106.911139 -266.154213) (xy 106.903014 -266.205508) (xy 106.886966 -266.254901)
			(xy 106.863388 -266.301175) (xy 106.832862 -266.343191) (xy 106.796139 -266.379914) (xy 106.754123 -266.41044)
			(xy 106.707849 -266.434018) (xy 106.658456 -266.450066) (xy 106.607161 -266.458191) (xy 106.555227 -266.458191)
			(xy 106.503932 -266.450066) (xy 106.454539 -266.434018) (xy 106.408265 -266.41044) (xy 106.366249 -266.379914)
			(xy 106.329526 -266.343191) (xy 106.299 -266.301175) (xy 106.275422 -266.254901) (xy 106.259374 -266.205508)
			(xy 106.251249 -266.154213) (xy 105.971339 -266.154213) (xy 105.963214 -266.205508) (xy 105.947166 -266.254901)
			(xy 105.923588 -266.301175) (xy 105.893062 -266.343191) (xy 105.856339 -266.379914) (xy 105.814323 -266.41044)
			(xy 105.768049 -266.434018) (xy 105.718656 -266.450066) (xy 105.667361 -266.458191) (xy 105.615427 -266.458191)
			(xy 105.564132 -266.450066) (xy 105.514739 -266.434018) (xy 105.468465 -266.41044) (xy 105.426449 -266.379914)
			(xy 105.389726 -266.343191) (xy 105.3592 -266.301175) (xy 105.335622 -266.254901) (xy 105.319574 -266.205508)
			(xy 105.311449 -266.154213) (xy 105.031539 -266.154213) (xy 105.023414 -266.205508) (xy 105.007366 -266.254901)
			(xy 104.983788 -266.301175) (xy 104.953262 -266.343191) (xy 104.916539 -266.379914) (xy 104.874523 -266.41044)
			(xy 104.828249 -266.434018) (xy 104.778856 -266.450066) (xy 104.727561 -266.458191) (xy 104.675627 -266.458191)
			(xy 104.624332 -266.450066) (xy 104.574939 -266.434018) (xy 104.528665 -266.41044) (xy 104.486649 -266.379914)
			(xy 104.449926 -266.343191) (xy 104.4194 -266.301175) (xy 104.395822 -266.254901) (xy 104.379774 -266.205508)
			(xy 104.371649 -266.154213) (xy 104.091739 -266.154213) (xy 104.083614 -266.205508) (xy 104.067566 -266.254901)
			(xy 104.043988 -266.301175) (xy 104.013462 -266.343191) (xy 103.976739 -266.379914) (xy 103.934723 -266.41044)
			(xy 103.888449 -266.434018) (xy 103.839056 -266.450066) (xy 103.787761 -266.458191) (xy 103.735827 -266.458191)
			(xy 103.684532 -266.450066) (xy 103.635139 -266.434018) (xy 103.588865 -266.41044) (xy 103.546849 -266.379914)
			(xy 103.510126 -266.343191) (xy 103.4796 -266.301175) (xy 103.456022 -266.254901) (xy 103.439974 -266.205508)
			(xy 103.431849 -266.154213) (xy 103.151935 -266.154213) (xy 103.143805 -266.2055) (xy 103.127752 -266.254886)
			(xy 103.104172 -266.301153) (xy 103.073645 -266.343162) (xy 103.036922 -266.379879) (xy 102.994909 -266.410399)
			(xy 102.948638 -266.433972) (xy 102.899249 -266.450017) (xy 102.847959 -266.458139) (xy 102.821994 -266.4587)
			(xy 102.82174 -266.4587) (xy 102.802576 -266.458406) (xy 102.764509 -266.453945) (xy 102.745794 -266.44981)
			(xy 102.730786 -266.446792) (xy 102.700258 -266.448873) (xy 102.671713 -266.459894) (xy 102.647706 -266.478868)
			(xy 102.630389 -266.504095) (xy 102.621311 -266.533317) (xy 102.620826 -266.548616) (xy 102.620826 -266.749022)
			(xy 102.635448 -266.770215) (xy 102.658632 -266.816184) (xy 102.674393 -266.865198) (xy 102.682345 -266.916065)
			(xy 102.682802 -266.941808) (xy 102.682306 -266.967547) (xy 102.68227 -266.967775) (xy 102.962203 -266.967775)
			(xy 102.962203 -266.915841) (xy 102.970328 -266.864546) (xy 102.986376 -266.815153) (xy 103.009954 -266.768879)
			(xy 103.04048 -266.726863) (xy 103.077203 -266.69014) (xy 103.119219 -266.659614) (xy 103.165493 -266.636036)
			(xy 103.214886 -266.619988) (xy 103.266181 -266.611863) (xy 103.318115 -266.611863) (xy 103.36941 -266.619988)
			(xy 103.418803 -266.636036) (xy 103.465077 -266.659614) (xy 103.507093 -266.69014) (xy 103.543816 -266.726863)
			(xy 103.574342 -266.768879) (xy 103.59792 -266.815153) (xy 103.613968 -266.864546) (xy 103.622093 -266.915841)
			(xy 103.622602 -266.941808) (xy 103.622093 -266.967775) (xy 103.901749 -266.967775) (xy 103.901749 -266.915841)
			(xy 103.909874 -266.864546) (xy 103.925922 -266.815153) (xy 103.9495 -266.768879) (xy 103.980026 -266.726863)
			(xy 104.016749 -266.69014) (xy 104.058765 -266.659614) (xy 104.105039 -266.636036) (xy 104.154432 -266.619988)
			(xy 104.205727 -266.611863) (xy 104.257661 -266.611863) (xy 104.308956 -266.619988) (xy 104.358349 -266.636036)
			(xy 104.404623 -266.659614) (xy 104.446639 -266.69014) (xy 104.483362 -266.726863) (xy 104.513888 -266.768879)
			(xy 104.537466 -266.815153) (xy 104.553514 -266.864546) (xy 104.561639 -266.915841) (xy 104.562148 -266.941808)
			(xy 104.561639 -266.967775) (xy 104.841295 -266.967775) (xy 104.841295 -266.915841) (xy 104.84942 -266.864546)
			(xy 104.865468 -266.815153) (xy 104.889046 -266.768879) (xy 104.919572 -266.726863) (xy 104.956295 -266.69014)
			(xy 104.998311 -266.659614) (xy 105.044585 -266.636036) (xy 105.093978 -266.619988) (xy 105.145273 -266.611863)
			(xy 105.197207 -266.611863) (xy 105.248502 -266.619988) (xy 105.297895 -266.636036) (xy 105.344169 -266.659614)
			(xy 105.386185 -266.69014) (xy 105.422908 -266.726863) (xy 105.453434 -266.768879) (xy 105.477012 -266.815153)
			(xy 105.49306 -266.864546) (xy 105.501185 -266.915841) (xy 105.501694 -266.941808) (xy 105.501185 -266.967775)
			(xy 105.781349 -266.967775) (xy 105.781349 -266.915841) (xy 105.789474 -266.864546) (xy 105.805522 -266.815153)
			(xy 105.8291 -266.768879) (xy 105.859626 -266.726863) (xy 105.896349 -266.69014) (xy 105.938365 -266.659614)
			(xy 105.984639 -266.636036) (xy 106.034032 -266.619988) (xy 106.085327 -266.611863) (xy 106.137261 -266.611863)
			(xy 106.188556 -266.619988) (xy 106.237949 -266.636036) (xy 106.284223 -266.659614) (xy 106.326239 -266.69014)
			(xy 106.362962 -266.726863) (xy 106.393488 -266.768879) (xy 106.417066 -266.815153) (xy 106.433114 -266.864546)
			(xy 106.441239 -266.915841) (xy 106.441748 -266.941808) (xy 106.441239 -266.967775) (xy 106.721403 -266.967775)
			(xy 106.721403 -266.915841) (xy 106.729528 -266.864546) (xy 106.745576 -266.815153) (xy 106.769154 -266.768879)
			(xy 106.79968 -266.726863) (xy 106.836403 -266.69014) (xy 106.878419 -266.659614) (xy 106.924693 -266.636036)
			(xy 106.974086 -266.619988) (xy 107.025381 -266.611863) (xy 107.077315 -266.611863) (xy 107.12861 -266.619988)
			(xy 107.178003 -266.636036) (xy 107.224277 -266.659614) (xy 107.266293 -266.69014) (xy 107.303016 -266.726863)
			(xy 107.333542 -266.768879) (xy 107.35712 -266.815153) (xy 107.373168 -266.864546) (xy 107.381293 -266.915841)
			(xy 107.381802 -266.941808) (xy 107.381293 -266.967775) (xy 107.661203 -266.967775) (xy 107.661203 -266.915841)
			(xy 107.669328 -266.864546) (xy 107.685376 -266.815153) (xy 107.708954 -266.768879) (xy 107.73948 -266.726863)
			(xy 107.776203 -266.69014) (xy 107.818219 -266.659614) (xy 107.864493 -266.636036) (xy 107.913886 -266.619988)
			(xy 107.965181 -266.611863) (xy 108.017115 -266.611863) (xy 108.06841 -266.619988) (xy 108.117803 -266.636036)
			(xy 108.164077 -266.659614) (xy 108.206093 -266.69014) (xy 108.242816 -266.726863) (xy 108.273342 -266.768879)
			(xy 108.29692 -266.815153) (xy 108.312968 -266.864546) (xy 108.321093 -266.915841) (xy 108.321602 -266.941808)
			(xy 108.321093 -266.967775) (xy 108.601003 -266.967775) (xy 108.601003 -266.915841) (xy 108.609128 -266.864546)
			(xy 108.625176 -266.815153) (xy 108.648754 -266.768879) (xy 108.67928 -266.726863) (xy 108.716003 -266.69014)
			(xy 108.758019 -266.659614) (xy 108.804293 -266.636036) (xy 108.853686 -266.619988) (xy 108.904981 -266.611863)
			(xy 108.956915 -266.611863) (xy 109.00821 -266.619988) (xy 109.057603 -266.636036) (xy 109.103877 -266.659614)
			(xy 109.145893 -266.69014) (xy 109.182616 -266.726863) (xy 109.213142 -266.768879) (xy 109.23672 -266.815153)
			(xy 109.252768 -266.864546) (xy 109.260893 -266.915841) (xy 109.261402 -266.941808) (xy 109.260893 -266.967775)
			(xy 109.540549 -266.967775) (xy 109.540549 -266.915841) (xy 109.548674 -266.864546) (xy 109.564722 -266.815153)
			(xy 109.5883 -266.768879) (xy 109.618826 -266.726863) (xy 109.655549 -266.69014) (xy 109.697565 -266.659614)
			(xy 109.743839 -266.636036) (xy 109.793232 -266.619988) (xy 109.844527 -266.611863) (xy 109.896461 -266.611863)
			(xy 109.947756 -266.619988) (xy 109.997149 -266.636036) (xy 110.043423 -266.659614) (xy 110.085439 -266.69014)
			(xy 110.122162 -266.726863) (xy 110.152688 -266.768879) (xy 110.176266 -266.815153) (xy 110.192314 -266.864546)
			(xy 110.200439 -266.915841) (xy 110.200948 -266.941808) (xy 110.200439 -266.967775) (xy 110.192314 -267.01907)
			(xy 110.176266 -267.068463) (xy 110.152688 -267.114737) (xy 110.122162 -267.156753) (xy 110.085439 -267.193476)
			(xy 110.043423 -267.224002) (xy 109.997149 -267.24758) (xy 109.947756 -267.263628) (xy 109.896461 -267.271753)
			(xy 109.844527 -267.271753) (xy 109.793232 -267.263628) (xy 109.743839 -267.24758) (xy 109.697565 -267.224002)
			(xy 109.655549 -267.193476) (xy 109.618826 -267.156753) (xy 109.5883 -267.114737) (xy 109.564722 -267.068463)
			(xy 109.548674 -267.01907) (xy 109.540549 -266.967775) (xy 109.260893 -266.967775) (xy 109.252768 -267.01907)
			(xy 109.23672 -267.068463) (xy 109.213142 -267.114737) (xy 109.182616 -267.156753) (xy 109.145893 -267.193476)
			(xy 109.103877 -267.224002) (xy 109.057603 -267.24758) (xy 109.00821 -267.263628) (xy 108.956915 -267.271753)
			(xy 108.904981 -267.271753) (xy 108.853686 -267.263628) (xy 108.804293 -267.24758) (xy 108.758019 -267.224002)
			(xy 108.716003 -267.193476) (xy 108.67928 -267.156753) (xy 108.648754 -267.114737) (xy 108.625176 -267.068463)
			(xy 108.609128 -267.01907) (xy 108.601003 -266.967775) (xy 108.321093 -266.967775) (xy 108.312968 -267.01907)
			(xy 108.29692 -267.068463) (xy 108.273342 -267.114737) (xy 108.242816 -267.156753) (xy 108.206093 -267.193476)
			(xy 108.164077 -267.224002) (xy 108.117803 -267.24758) (xy 108.06841 -267.263628) (xy 108.017115 -267.271753)
			(xy 107.965181 -267.271753) (xy 107.913886 -267.263628) (xy 107.864493 -267.24758) (xy 107.818219 -267.224002)
			(xy 107.776203 -267.193476) (xy 107.73948 -267.156753) (xy 107.708954 -267.114737) (xy 107.685376 -267.068463)
			(xy 107.669328 -267.01907) (xy 107.661203 -266.967775) (xy 107.381293 -266.967775) (xy 107.373168 -267.01907)
			(xy 107.35712 -267.068463) (xy 107.333542 -267.114737) (xy 107.303016 -267.156753) (xy 107.266293 -267.193476)
			(xy 107.224277 -267.224002) (xy 107.178003 -267.24758) (xy 107.12861 -267.263628) (xy 107.077315 -267.271753)
			(xy 107.025381 -267.271753) (xy 106.974086 -267.263628) (xy 106.924693 -267.24758) (xy 106.878419 -267.224002)
			(xy 106.836403 -267.193476) (xy 106.79968 -267.156753) (xy 106.769154 -267.114737) (xy 106.745576 -267.068463)
			(xy 106.729528 -267.01907) (xy 106.721403 -266.967775) (xy 106.441239 -266.967775) (xy 106.433114 -267.01907)
			(xy 106.417066 -267.068463) (xy 106.393488 -267.114737) (xy 106.362962 -267.156753) (xy 106.326239 -267.193476)
			(xy 106.284223 -267.224002) (xy 106.237949 -267.24758) (xy 106.188556 -267.263628) (xy 106.137261 -267.271753)
			(xy 106.085327 -267.271753) (xy 106.034032 -267.263628) (xy 105.984639 -267.24758) (xy 105.938365 -267.224002)
			(xy 105.896349 -267.193476) (xy 105.859626 -267.156753) (xy 105.8291 -267.114737) (xy 105.805522 -267.068463)
			(xy 105.789474 -267.01907) (xy 105.781349 -266.967775) (xy 105.501185 -266.967775) (xy 105.49306 -267.01907)
			(xy 105.477012 -267.068463) (xy 105.453434 -267.114737) (xy 105.422908 -267.156753) (xy 105.386185 -267.193476)
			(xy 105.344169 -267.224002) (xy 105.297895 -267.24758) (xy 105.248502 -267.263628) (xy 105.197207 -267.271753)
			(xy 105.145273 -267.271753) (xy 105.093978 -267.263628) (xy 105.044585 -267.24758) (xy 104.998311 -267.224002)
			(xy 104.956295 -267.193476) (xy 104.919572 -267.156753) (xy 104.889046 -267.114737) (xy 104.865468 -267.068463)
			(xy 104.84942 -267.01907) (xy 104.841295 -266.967775) (xy 104.561639 -266.967775) (xy 104.553514 -267.01907)
			(xy 104.537466 -267.068463) (xy 104.513888 -267.114737) (xy 104.483362 -267.156753) (xy 104.446639 -267.193476)
			(xy 104.404623 -267.224002) (xy 104.358349 -267.24758) (xy 104.308956 -267.263628) (xy 104.257661 -267.271753)
			(xy 104.205727 -267.271753) (xy 104.154432 -267.263628) (xy 104.105039 -267.24758) (xy 104.058765 -267.224002)
			(xy 104.016749 -267.193476) (xy 103.980026 -267.156753) (xy 103.9495 -267.114737) (xy 103.925922 -267.068463)
			(xy 103.909874 -267.01907) (xy 103.901749 -266.967775) (xy 103.622093 -266.967775) (xy 103.613968 -267.01907)
			(xy 103.59792 -267.068463) (xy 103.574342 -267.114737) (xy 103.543816 -267.156753) (xy 103.507093 -267.193476)
			(xy 103.465077 -267.224002) (xy 103.418803 -267.24758) (xy 103.36941 -267.263628) (xy 103.318115 -267.271753)
			(xy 103.266181 -267.271753) (xy 103.214886 -267.263628) (xy 103.165493 -267.24758) (xy 103.119219 -267.224002)
			(xy 103.077203 -267.193476) (xy 103.04048 -267.156753) (xy 103.009954 -267.114737) (xy 102.986376 -267.068463)
			(xy 102.970328 -267.01907) (xy 102.962203 -266.967775) (xy 102.68227 -266.967775) (xy 102.674324 -267.018402)
			(xy 102.658571 -267.06741) (xy 102.635425 -267.11339) (xy 102.620826 -267.134594) (xy 102.620826 -267.335508)
			(xy 102.621333 -267.350812) (xy 102.630378 -267.380053) (xy 102.647682 -267.405299) (xy 102.671691 -267.424282)
			(xy 102.700248 -267.435297) (xy 102.730786 -267.437353) (xy 102.745794 -267.434314) (xy 102.764504 -267.430151)
			(xy 102.802575 -267.425694) (xy 102.82174 -267.425424) (xy 102.821994 -267.425424) (xy 102.847965 -267.425906)
			(xy 102.899269 -267.434031) (xy 102.948669 -267.450082) (xy 102.994951 -267.473663) (xy 103.036974 -267.504193)
			(xy 103.073703 -267.540922) (xy 103.104234 -267.582944) (xy 103.127816 -267.629225) (xy 103.143867 -267.678626)
			(xy 103.151993 -267.729929) (xy 103.151993 -267.781845) (xy 103.431849 -267.781845) (xy 103.431849 -267.729911)
			(xy 103.439974 -267.678616) (xy 103.456022 -267.629223) (xy 103.4796 -267.582949) (xy 103.510126 -267.540933)
			(xy 103.546849 -267.50421) (xy 103.588865 -267.473684) (xy 103.635139 -267.450106) (xy 103.684532 -267.434058)
			(xy 103.735827 -267.425933) (xy 103.787761 -267.425933) (xy 103.839056 -267.434058) (xy 103.888449 -267.450106)
			(xy 103.934723 -267.473684) (xy 103.976739 -267.50421) (xy 104.013462 -267.540933) (xy 104.043988 -267.582949)
			(xy 104.067566 -267.629223) (xy 104.083614 -267.678616) (xy 104.091739 -267.729911) (xy 104.092248 -267.755878)
			(xy 104.091739 -267.781845) (xy 104.371649 -267.781845) (xy 104.371649 -267.729911) (xy 104.379774 -267.678616)
			(xy 104.395822 -267.629223) (xy 104.4194 -267.582949) (xy 104.449926 -267.540933) (xy 104.486649 -267.50421)
			(xy 104.528665 -267.473684) (xy 104.574939 -267.450106) (xy 104.624332 -267.434058) (xy 104.675627 -267.425933)
			(xy 104.727561 -267.425933) (xy 104.778856 -267.434058) (xy 104.828249 -267.450106) (xy 104.874523 -267.473684)
			(xy 104.916539 -267.50421) (xy 104.953262 -267.540933) (xy 104.983788 -267.582949) (xy 105.007366 -267.629223)
			(xy 105.023414 -267.678616) (xy 105.031539 -267.729911) (xy 105.032048 -267.755878) (xy 105.031539 -267.781845)
			(xy 105.311449 -267.781845) (xy 105.311449 -267.729911) (xy 105.319574 -267.678616) (xy 105.335622 -267.629223)
			(xy 105.3592 -267.582949) (xy 105.389726 -267.540933) (xy 105.426449 -267.50421) (xy 105.468465 -267.473684)
			(xy 105.514739 -267.450106) (xy 105.564132 -267.434058) (xy 105.615427 -267.425933) (xy 105.667361 -267.425933)
			(xy 105.718656 -267.434058) (xy 105.768049 -267.450106) (xy 105.814323 -267.473684) (xy 105.856339 -267.50421)
			(xy 105.893062 -267.540933) (xy 105.923588 -267.582949) (xy 105.947166 -267.629223) (xy 105.963214 -267.678616)
			(xy 105.971339 -267.729911) (xy 105.971848 -267.755878) (xy 105.971339 -267.781845) (xy 106.251249 -267.781845)
			(xy 106.251249 -267.729911) (xy 106.259374 -267.678616) (xy 106.275422 -267.629223) (xy 106.299 -267.582949)
			(xy 106.329526 -267.540933) (xy 106.366249 -267.50421) (xy 106.408265 -267.473684) (xy 106.454539 -267.450106)
			(xy 106.503932 -267.434058) (xy 106.555227 -267.425933) (xy 106.607161 -267.425933) (xy 106.658456 -267.434058)
			(xy 106.707849 -267.450106) (xy 106.754123 -267.473684) (xy 106.796139 -267.50421) (xy 106.832862 -267.540933)
			(xy 106.863388 -267.582949) (xy 106.886966 -267.629223) (xy 106.903014 -267.678616) (xy 106.911139 -267.729911)
			(xy 106.911648 -267.755878) (xy 106.911139 -267.781845) (xy 107.191049 -267.781845) (xy 107.191049 -267.729911)
			(xy 107.199174 -267.678616) (xy 107.215222 -267.629223) (xy 107.2388 -267.582949) (xy 107.269326 -267.540933)
			(xy 107.306049 -267.50421) (xy 107.348065 -267.473684) (xy 107.394339 -267.450106) (xy 107.443732 -267.434058)
			(xy 107.495027 -267.425933) (xy 107.546961 -267.425933) (xy 107.598256 -267.434058) (xy 107.647649 -267.450106)
			(xy 107.693923 -267.473684) (xy 107.735939 -267.50421) (xy 107.772662 -267.540933) (xy 107.803188 -267.582949)
			(xy 107.826766 -267.629223) (xy 107.842814 -267.678616) (xy 107.850939 -267.729911) (xy 107.851448 -267.755878)
			(xy 107.850939 -267.781845) (xy 108.130849 -267.781845) (xy 108.130849 -267.729911) (xy 108.138974 -267.678616)
			(xy 108.155022 -267.629223) (xy 108.1786 -267.582949) (xy 108.209126 -267.540933) (xy 108.245849 -267.50421)
			(xy 108.287865 -267.473684) (xy 108.334139 -267.450106) (xy 108.383532 -267.434058) (xy 108.434827 -267.425933)
			(xy 108.486761 -267.425933) (xy 108.538056 -267.434058) (xy 108.587449 -267.450106) (xy 108.633723 -267.473684)
			(xy 108.675739 -267.50421) (xy 108.712462 -267.540933) (xy 108.742988 -267.582949) (xy 108.766566 -267.629223)
			(xy 108.782614 -267.678616) (xy 108.790739 -267.729911) (xy 108.791248 -267.755878) (xy 108.790739 -267.781845)
			(xy 109.070649 -267.781845) (xy 109.070649 -267.729911) (xy 109.078774 -267.678616) (xy 109.094822 -267.629223)
			(xy 109.1184 -267.582949) (xy 109.148926 -267.540933) (xy 109.185649 -267.50421) (xy 109.227665 -267.473684)
			(xy 109.273939 -267.450106) (xy 109.323332 -267.434058) (xy 109.374627 -267.425933) (xy 109.426561 -267.425933)
			(xy 109.477856 -267.434058) (xy 109.527249 -267.450106) (xy 109.573523 -267.473684) (xy 109.615539 -267.50421)
			(xy 109.652262 -267.540933) (xy 109.682788 -267.582949) (xy 109.706366 -267.629223) (xy 109.722414 -267.678616)
			(xy 109.730539 -267.729911) (xy 109.731048 -267.755878) (xy 109.730539 -267.781845) (xy 110.010449 -267.781845)
			(xy 110.010449 -267.729911) (xy 110.018574 -267.678616) (xy 110.034622 -267.629223) (xy 110.0582 -267.582949)
			(xy 110.088726 -267.540933) (xy 110.125449 -267.50421) (xy 110.167465 -267.473684) (xy 110.213739 -267.450106)
			(xy 110.263132 -267.434058) (xy 110.314427 -267.425933) (xy 110.366361 -267.425933) (xy 110.417656 -267.434058)
			(xy 110.467049 -267.450106) (xy 110.513323 -267.473684) (xy 110.555339 -267.50421) (xy 110.592062 -267.540933)
			(xy 110.622588 -267.582949) (xy 110.646166 -267.629223) (xy 110.662214 -267.678616) (xy 110.670339 -267.729911)
			(xy 110.670848 -267.755878) (xy 110.670339 -267.781845) (xy 110.662214 -267.83314) (xy 110.646166 -267.882533)
			(xy 110.622588 -267.928807) (xy 110.592062 -267.970823) (xy 110.555339 -268.007546) (xy 110.513323 -268.038072)
			(xy 110.467049 -268.06165) (xy 110.417656 -268.077698) (xy 110.366361 -268.085823) (xy 110.314427 -268.085823)
			(xy 110.263132 -268.077698) (xy 110.213739 -268.06165) (xy 110.167465 -268.038072) (xy 110.125449 -268.007546)
			(xy 110.088726 -267.970823) (xy 110.0582 -267.928807) (xy 110.034622 -267.882533) (xy 110.018574 -267.83314)
			(xy 110.010449 -267.781845) (xy 109.730539 -267.781845) (xy 109.722414 -267.83314) (xy 109.706366 -267.882533)
			(xy 109.682788 -267.928807) (xy 109.652262 -267.970823) (xy 109.615539 -268.007546) (xy 109.573523 -268.038072)
			(xy 109.527249 -268.06165) (xy 109.477856 -268.077698) (xy 109.426561 -268.085823) (xy 109.374627 -268.085823)
			(xy 109.323332 -268.077698) (xy 109.273939 -268.06165) (xy 109.227665 -268.038072) (xy 109.185649 -268.007546)
			(xy 109.148926 -267.970823) (xy 109.1184 -267.928807) (xy 109.094822 -267.882533) (xy 109.078774 -267.83314)
			(xy 109.070649 -267.781845) (xy 108.790739 -267.781845) (xy 108.782614 -267.83314) (xy 108.766566 -267.882533)
			(xy 108.742988 -267.928807) (xy 108.712462 -267.970823) (xy 108.675739 -268.007546) (xy 108.633723 -268.038072)
			(xy 108.587449 -268.06165) (xy 108.538056 -268.077698) (xy 108.486761 -268.085823) (xy 108.434827 -268.085823)
			(xy 108.383532 -268.077698) (xy 108.334139 -268.06165) (xy 108.287865 -268.038072) (xy 108.245849 -268.007546)
			(xy 108.209126 -267.970823) (xy 108.1786 -267.928807) (xy 108.155022 -267.882533) (xy 108.138974 -267.83314)
			(xy 108.130849 -267.781845) (xy 107.850939 -267.781845) (xy 107.842814 -267.83314) (xy 107.826766 -267.882533)
			(xy 107.803188 -267.928807) (xy 107.772662 -267.970823) (xy 107.735939 -268.007546) (xy 107.693923 -268.038072)
			(xy 107.647649 -268.06165) (xy 107.598256 -268.077698) (xy 107.546961 -268.085823) (xy 107.495027 -268.085823)
			(xy 107.443732 -268.077698) (xy 107.394339 -268.06165) (xy 107.348065 -268.038072) (xy 107.306049 -268.007546)
			(xy 107.269326 -267.970823) (xy 107.2388 -267.928807) (xy 107.215222 -267.882533) (xy 107.199174 -267.83314)
			(xy 107.191049 -267.781845) (xy 106.911139 -267.781845) (xy 106.903014 -267.83314) (xy 106.886966 -267.882533)
			(xy 106.863388 -267.928807) (xy 106.832862 -267.970823) (xy 106.796139 -268.007546) (xy 106.754123 -268.038072)
			(xy 106.707849 -268.06165) (xy 106.658456 -268.077698) (xy 106.607161 -268.085823) (xy 106.555227 -268.085823)
			(xy 106.503932 -268.077698) (xy 106.454539 -268.06165) (xy 106.408265 -268.038072) (xy 106.366249 -268.007546)
			(xy 106.329526 -267.970823) (xy 106.299 -267.928807) (xy 106.275422 -267.882533) (xy 106.259374 -267.83314)
			(xy 106.251249 -267.781845) (xy 105.971339 -267.781845) (xy 105.963214 -267.83314) (xy 105.947166 -267.882533)
			(xy 105.923588 -267.928807) (xy 105.893062 -267.970823) (xy 105.856339 -268.007546) (xy 105.814323 -268.038072)
			(xy 105.768049 -268.06165) (xy 105.718656 -268.077698) (xy 105.667361 -268.085823) (xy 105.615427 -268.085823)
			(xy 105.564132 -268.077698) (xy 105.514739 -268.06165) (xy 105.468465 -268.038072) (xy 105.426449 -268.007546)
			(xy 105.389726 -267.970823) (xy 105.3592 -267.928807) (xy 105.335622 -267.882533) (xy 105.319574 -267.83314)
			(xy 105.311449 -267.781845) (xy 105.031539 -267.781845) (xy 105.023414 -267.83314) (xy 105.007366 -267.882533)
			(xy 104.983788 -267.928807) (xy 104.953262 -267.970823) (xy 104.916539 -268.007546) (xy 104.874523 -268.038072)
			(xy 104.828249 -268.06165) (xy 104.778856 -268.077698) (xy 104.727561 -268.085823) (xy 104.675627 -268.085823)
			(xy 104.624332 -268.077698) (xy 104.574939 -268.06165) (xy 104.528665 -268.038072) (xy 104.486649 -268.007546)
			(xy 104.449926 -267.970823) (xy 104.4194 -267.928807) (xy 104.395822 -267.882533) (xy 104.379774 -267.83314)
			(xy 104.371649 -267.781845) (xy 104.091739 -267.781845) (xy 104.083614 -267.83314) (xy 104.067566 -267.882533)
			(xy 104.043988 -267.928807) (xy 104.013462 -267.970823) (xy 103.976739 -268.007546) (xy 103.934723 -268.038072)
			(xy 103.888449 -268.06165) (xy 103.839056 -268.077698) (xy 103.787761 -268.085823) (xy 103.735827 -268.085823)
			(xy 103.684532 -268.077698) (xy 103.635139 -268.06165) (xy 103.588865 -268.038072) (xy 103.546849 -268.007546)
			(xy 103.510126 -267.970823) (xy 103.4796 -267.928807) (xy 103.456022 -267.882533) (xy 103.439974 -267.83314)
			(xy 103.431849 -267.781845) (xy 103.151993 -267.781845) (xy 103.151993 -267.781871) (xy 103.143867 -267.833174)
			(xy 103.127816 -267.882575) (xy 103.104234 -267.928856) (xy 103.073703 -267.970878) (xy 103.036974 -268.007607)
			(xy 102.994951 -268.038137) (xy 102.948669 -268.061718) (xy 102.899269 -268.077769) (xy 102.847965 -268.085894)
			(xy 102.821994 -268.086332) (xy 102.82174 -268.086332) (xy 102.802576 -268.086038) (xy 102.764509 -268.081577)
			(xy 102.745794 -268.077442) (xy 102.730788 -268.074423) (xy 102.700262 -268.076505) (xy 102.67172 -268.087526)
			(xy 102.647719 -268.106501) (xy 102.630407 -268.131729) (xy 102.621338 -268.16095) (xy 102.620826 -268.176248)
			(xy 102.620826 -268.376908) (xy 102.635448 -268.398101) (xy 102.658635 -268.44407) (xy 102.674398 -268.493083)
			(xy 102.682352 -268.543951) (xy 102.682802 -268.569694) (xy 102.682307 -268.595433) (xy 102.682271 -268.595661)
			(xy 102.962203 -268.595661) (xy 102.962203 -268.543727) (xy 102.970328 -268.492432) (xy 102.986376 -268.443039)
			(xy 103.009954 -268.396765) (xy 103.04048 -268.354749) (xy 103.077203 -268.318026) (xy 103.119219 -268.2875)
			(xy 103.165493 -268.263922) (xy 103.214886 -268.247874) (xy 103.266181 -268.239749) (xy 103.318115 -268.239749)
			(xy 103.36941 -268.247874) (xy 103.418803 -268.263922) (xy 103.465077 -268.2875) (xy 103.507093 -268.318026)
			(xy 103.543816 -268.354749) (xy 103.574342 -268.396765) (xy 103.59792 -268.443039) (xy 103.613968 -268.492432)
			(xy 103.622093 -268.543727) (xy 103.622602 -268.569694) (xy 103.622093 -268.595661) (xy 103.902003 -268.595661)
			(xy 103.902003 -268.543727) (xy 103.910128 -268.492432) (xy 103.926176 -268.443039) (xy 103.949754 -268.396765)
			(xy 103.98028 -268.354749) (xy 104.017003 -268.318026) (xy 104.059019 -268.2875) (xy 104.105293 -268.263922)
			(xy 104.154686 -268.247874) (xy 104.205981 -268.239749) (xy 104.257915 -268.239749) (xy 104.30921 -268.247874)
			(xy 104.358603 -268.263922) (xy 104.404877 -268.2875) (xy 104.446893 -268.318026) (xy 104.483616 -268.354749)
			(xy 104.514142 -268.396765) (xy 104.53772 -268.443039) (xy 104.553768 -268.492432) (xy 104.561893 -268.543727)
			(xy 104.562402 -268.569694) (xy 104.561893 -268.595661) (xy 104.841803 -268.595661) (xy 104.841803 -268.543727)
			(xy 104.849928 -268.492432) (xy 104.865976 -268.443039) (xy 104.889554 -268.396765) (xy 104.92008 -268.354749)
			(xy 104.956803 -268.318026) (xy 104.998819 -268.2875) (xy 105.045093 -268.263922) (xy 105.094486 -268.247874)
			(xy 105.145781 -268.239749) (xy 105.197715 -268.239749) (xy 105.24901 -268.247874) (xy 105.298403 -268.263922)
			(xy 105.344677 -268.2875) (xy 105.386693 -268.318026) (xy 105.423416 -268.354749) (xy 105.453942 -268.396765)
			(xy 105.47752 -268.443039) (xy 105.493568 -268.492432) (xy 105.501693 -268.543727) (xy 105.502202 -268.569694)
			(xy 105.501693 -268.595661) (xy 105.781603 -268.595661) (xy 105.781603 -268.543727) (xy 105.789728 -268.492432)
			(xy 105.805776 -268.443039) (xy 105.829354 -268.396765) (xy 105.85988 -268.354749) (xy 105.896603 -268.318026)
			(xy 105.938619 -268.2875) (xy 105.984893 -268.263922) (xy 106.034286 -268.247874) (xy 106.085581 -268.239749)
			(xy 106.137515 -268.239749) (xy 106.18881 -268.247874) (xy 106.238203 -268.263922) (xy 106.284477 -268.2875)
			(xy 106.326493 -268.318026) (xy 106.363216 -268.354749) (xy 106.393742 -268.396765) (xy 106.41732 -268.443039)
			(xy 106.433368 -268.492432) (xy 106.441493 -268.543727) (xy 106.442002 -268.569694) (xy 106.441493 -268.595661)
			(xy 106.721403 -268.595661) (xy 106.721403 -268.543727) (xy 106.729528 -268.492432) (xy 106.745576 -268.443039)
			(xy 106.769154 -268.396765) (xy 106.79968 -268.354749) (xy 106.836403 -268.318026) (xy 106.878419 -268.2875)
			(xy 106.924693 -268.263922) (xy 106.974086 -268.247874) (xy 107.025381 -268.239749) (xy 107.077315 -268.239749)
			(xy 107.12861 -268.247874) (xy 107.178003 -268.263922) (xy 107.224277 -268.2875) (xy 107.266293 -268.318026)
			(xy 107.303016 -268.354749) (xy 107.333542 -268.396765) (xy 107.35712 -268.443039) (xy 107.373168 -268.492432)
			(xy 107.381293 -268.543727) (xy 107.381802 -268.569694) (xy 107.381293 -268.595661) (xy 107.661203 -268.595661)
			(xy 107.661203 -268.543727) (xy 107.669328 -268.492432) (xy 107.685376 -268.443039) (xy 107.708954 -268.396765)
			(xy 107.73948 -268.354749) (xy 107.776203 -268.318026) (xy 107.818219 -268.2875) (xy 107.864493 -268.263922)
			(xy 107.913886 -268.247874) (xy 107.965181 -268.239749) (xy 108.017115 -268.239749) (xy 108.06841 -268.247874)
			(xy 108.117803 -268.263922) (xy 108.164077 -268.2875) (xy 108.206093 -268.318026) (xy 108.242816 -268.354749)
			(xy 108.273342 -268.396765) (xy 108.29692 -268.443039) (xy 108.312968 -268.492432) (xy 108.321093 -268.543727)
			(xy 108.321602 -268.569694) (xy 108.321093 -268.595661) (xy 108.600749 -268.595661) (xy 108.600749 -268.543727)
			(xy 108.608874 -268.492432) (xy 108.624922 -268.443039) (xy 108.6485 -268.396765) (xy 108.679026 -268.354749)
			(xy 108.715749 -268.318026) (xy 108.757765 -268.2875) (xy 108.804039 -268.263922) (xy 108.853432 -268.247874)
			(xy 108.904727 -268.239749) (xy 108.956661 -268.239749) (xy 109.007956 -268.247874) (xy 109.057349 -268.263922)
			(xy 109.103623 -268.2875) (xy 109.145639 -268.318026) (xy 109.182362 -268.354749) (xy 109.212888 -268.396765)
			(xy 109.236466 -268.443039) (xy 109.252514 -268.492432) (xy 109.260639 -268.543727) (xy 109.261148 -268.569694)
			(xy 109.260639 -268.595661) (xy 109.540549 -268.595661) (xy 109.540549 -268.543727) (xy 109.548674 -268.492432)
			(xy 109.564722 -268.443039) (xy 109.5883 -268.396765) (xy 109.618826 -268.354749) (xy 109.655549 -268.318026)
			(xy 109.697565 -268.2875) (xy 109.743839 -268.263922) (xy 109.793232 -268.247874) (xy 109.844527 -268.239749)
			(xy 109.896461 -268.239749) (xy 109.947756 -268.247874) (xy 109.997149 -268.263922) (xy 110.043423 -268.2875)
			(xy 110.085439 -268.318026) (xy 110.122162 -268.354749) (xy 110.152688 -268.396765) (xy 110.176266 -268.443039)
			(xy 110.192314 -268.492432) (xy 110.200439 -268.543727) (xy 110.200948 -268.569694) (xy 110.200439 -268.595661)
			(xy 110.192314 -268.646956) (xy 110.176266 -268.696349) (xy 110.152688 -268.742623) (xy 110.122162 -268.784639)
			(xy 110.085439 -268.821362) (xy 110.043423 -268.851888) (xy 109.997149 -268.875466) (xy 109.947756 -268.891514)
			(xy 109.896461 -268.899639) (xy 109.844527 -268.899639) (xy 109.793232 -268.891514) (xy 109.743839 -268.875466)
			(xy 109.697565 -268.851888) (xy 109.655549 -268.821362) (xy 109.618826 -268.784639) (xy 109.5883 -268.742623)
			(xy 109.564722 -268.696349) (xy 109.548674 -268.646956) (xy 109.540549 -268.595661) (xy 109.260639 -268.595661)
			(xy 109.252514 -268.646956) (xy 109.236466 -268.696349) (xy 109.212888 -268.742623) (xy 109.182362 -268.784639)
			(xy 109.145639 -268.821362) (xy 109.103623 -268.851888) (xy 109.057349 -268.875466) (xy 109.007956 -268.891514)
			(xy 108.956661 -268.899639) (xy 108.904727 -268.899639) (xy 108.853432 -268.891514) (xy 108.804039 -268.875466)
			(xy 108.757765 -268.851888) (xy 108.715749 -268.821362) (xy 108.679026 -268.784639) (xy 108.6485 -268.742623)
			(xy 108.624922 -268.696349) (xy 108.608874 -268.646956) (xy 108.600749 -268.595661) (xy 108.321093 -268.595661)
			(xy 108.312968 -268.646956) (xy 108.29692 -268.696349) (xy 108.273342 -268.742623) (xy 108.242816 -268.784639)
			(xy 108.206093 -268.821362) (xy 108.164077 -268.851888) (xy 108.117803 -268.875466) (xy 108.06841 -268.891514)
			(xy 108.017115 -268.899639) (xy 107.965181 -268.899639) (xy 107.913886 -268.891514) (xy 107.864493 -268.875466)
			(xy 107.818219 -268.851888) (xy 107.776203 -268.821362) (xy 107.73948 -268.784639) (xy 107.708954 -268.742623)
			(xy 107.685376 -268.696349) (xy 107.669328 -268.646956) (xy 107.661203 -268.595661) (xy 107.381293 -268.595661)
			(xy 107.373168 -268.646956) (xy 107.35712 -268.696349) (xy 107.333542 -268.742623) (xy 107.303016 -268.784639)
			(xy 107.266293 -268.821362) (xy 107.224277 -268.851888) (xy 107.178003 -268.875466) (xy 107.12861 -268.891514)
			(xy 107.077315 -268.899639) (xy 107.025381 -268.899639) (xy 106.974086 -268.891514) (xy 106.924693 -268.875466)
			(xy 106.878419 -268.851888) (xy 106.836403 -268.821362) (xy 106.79968 -268.784639) (xy 106.769154 -268.742623)
			(xy 106.745576 -268.696349) (xy 106.729528 -268.646956) (xy 106.721403 -268.595661) (xy 106.441493 -268.595661)
			(xy 106.433368 -268.646956) (xy 106.41732 -268.696349) (xy 106.393742 -268.742623) (xy 106.363216 -268.784639)
			(xy 106.326493 -268.821362) (xy 106.284477 -268.851888) (xy 106.238203 -268.875466) (xy 106.18881 -268.891514)
			(xy 106.137515 -268.899639) (xy 106.085581 -268.899639) (xy 106.034286 -268.891514) (xy 105.984893 -268.875466)
			(xy 105.938619 -268.851888) (xy 105.896603 -268.821362) (xy 105.85988 -268.784639) (xy 105.829354 -268.742623)
			(xy 105.805776 -268.696349) (xy 105.789728 -268.646956) (xy 105.781603 -268.595661) (xy 105.501693 -268.595661)
			(xy 105.493568 -268.646956) (xy 105.47752 -268.696349) (xy 105.453942 -268.742623) (xy 105.423416 -268.784639)
			(xy 105.386693 -268.821362) (xy 105.344677 -268.851888) (xy 105.298403 -268.875466) (xy 105.24901 -268.891514)
			(xy 105.197715 -268.899639) (xy 105.145781 -268.899639) (xy 105.094486 -268.891514) (xy 105.045093 -268.875466)
			(xy 104.998819 -268.851888) (xy 104.956803 -268.821362) (xy 104.92008 -268.784639) (xy 104.889554 -268.742623)
			(xy 104.865976 -268.696349) (xy 104.849928 -268.646956) (xy 104.841803 -268.595661) (xy 104.561893 -268.595661)
			(xy 104.553768 -268.646956) (xy 104.53772 -268.696349) (xy 104.514142 -268.742623) (xy 104.483616 -268.784639)
			(xy 104.446893 -268.821362) (xy 104.404877 -268.851888) (xy 104.358603 -268.875466) (xy 104.30921 -268.891514)
			(xy 104.257915 -268.899639) (xy 104.205981 -268.899639) (xy 104.154686 -268.891514) (xy 104.105293 -268.875466)
			(xy 104.059019 -268.851888) (xy 104.017003 -268.821362) (xy 103.98028 -268.784639) (xy 103.949754 -268.742623)
			(xy 103.926176 -268.696349) (xy 103.910128 -268.646956) (xy 103.902003 -268.595661) (xy 103.622093 -268.595661)
			(xy 103.613968 -268.646956) (xy 103.59792 -268.696349) (xy 103.574342 -268.742623) (xy 103.543816 -268.784639)
			(xy 103.507093 -268.821362) (xy 103.465077 -268.851888) (xy 103.418803 -268.875466) (xy 103.36941 -268.891514)
			(xy 103.318115 -268.899639) (xy 103.266181 -268.899639) (xy 103.214886 -268.891514) (xy 103.165493 -268.875466)
			(xy 103.119219 -268.851888) (xy 103.077203 -268.821362) (xy 103.04048 -268.784639) (xy 103.009954 -268.742623)
			(xy 102.986376 -268.696349) (xy 102.970328 -268.646956) (xy 102.962203 -268.595661) (xy 102.682271 -268.595661)
			(xy 102.674327 -268.646289) (xy 102.658576 -268.695298) (xy 102.635431 -268.74128) (xy 102.620826 -268.76248)
			(xy 102.620826 -268.96314) (xy 102.621337 -268.978441) (xy 102.630387 -269.007673) (xy 102.647693 -269.03291)
			(xy 102.671699 -269.051887) (xy 102.70025 -269.062897) (xy 102.730782 -269.064954) (xy 102.745794 -269.061946)
			(xy 102.764504 -269.057783) (xy 102.802575 -269.053325) (xy 102.82174 -269.053056) (xy 102.821994 -269.053056)
			(xy 102.847963 -269.053538) (xy 102.899261 -269.061662) (xy 102.948657 -269.077711) (xy 102.994934 -269.10129)
			(xy 103.036953 -269.131818) (xy 103.073679 -269.168543) (xy 103.104207 -269.210561) (xy 103.127786 -269.256837)
			(xy 103.143836 -269.306233) (xy 103.151961 -269.357531) (xy 103.151961 -269.409469) (xy 103.15196 -269.409477)
			(xy 103.431849 -269.409477) (xy 103.431849 -269.357543) (xy 103.439974 -269.306248) (xy 103.456022 -269.256855)
			(xy 103.4796 -269.210581) (xy 103.510126 -269.168565) (xy 103.546849 -269.131842) (xy 103.588865 -269.101316)
			(xy 103.635139 -269.077738) (xy 103.684532 -269.06169) (xy 103.735827 -269.053565) (xy 103.787761 -269.053565)
			(xy 103.839056 -269.06169) (xy 103.888449 -269.077738) (xy 103.934723 -269.101316) (xy 103.976739 -269.131842)
			(xy 104.013462 -269.168565) (xy 104.043988 -269.210581) (xy 104.067566 -269.256855) (xy 104.083614 -269.306248)
			(xy 104.091739 -269.357543) (xy 104.092248 -269.38351) (xy 104.091739 -269.409477) (xy 104.371649 -269.409477)
			(xy 104.371649 -269.357543) (xy 104.379774 -269.306248) (xy 104.395822 -269.256855) (xy 104.4194 -269.210581)
			(xy 104.449926 -269.168565) (xy 104.486649 -269.131842) (xy 104.528665 -269.101316) (xy 104.574939 -269.077738)
			(xy 104.624332 -269.06169) (xy 104.675627 -269.053565) (xy 104.727561 -269.053565) (xy 104.778856 -269.06169)
			(xy 104.828249 -269.077738) (xy 104.874523 -269.101316) (xy 104.916539 -269.131842) (xy 104.953262 -269.168565)
			(xy 104.983788 -269.210581) (xy 105.007366 -269.256855) (xy 105.023414 -269.306248) (xy 105.031539 -269.357543)
			(xy 105.032048 -269.38351) (xy 105.031539 -269.409477) (xy 105.311449 -269.409477) (xy 105.311449 -269.357543)
			(xy 105.319574 -269.306248) (xy 105.335622 -269.256855) (xy 105.3592 -269.210581) (xy 105.389726 -269.168565)
			(xy 105.426449 -269.131842) (xy 105.468465 -269.101316) (xy 105.514739 -269.077738) (xy 105.564132 -269.06169)
			(xy 105.615427 -269.053565) (xy 105.667361 -269.053565) (xy 105.718656 -269.06169) (xy 105.768049 -269.077738)
			(xy 105.814323 -269.101316) (xy 105.856339 -269.131842) (xy 105.893062 -269.168565) (xy 105.923588 -269.210581)
			(xy 105.947166 -269.256855) (xy 105.963214 -269.306248) (xy 105.971339 -269.357543) (xy 105.971848 -269.38351)
			(xy 105.971339 -269.409477) (xy 106.251249 -269.409477) (xy 106.251249 -269.357543) (xy 106.259374 -269.306248)
			(xy 106.275422 -269.256855) (xy 106.299 -269.210581) (xy 106.329526 -269.168565) (xy 106.366249 -269.131842)
			(xy 106.408265 -269.101316) (xy 106.454539 -269.077738) (xy 106.503932 -269.06169) (xy 106.555227 -269.053565)
			(xy 106.607161 -269.053565) (xy 106.658456 -269.06169) (xy 106.707849 -269.077738) (xy 106.754123 -269.101316)
			(xy 106.796139 -269.131842) (xy 106.832862 -269.168565) (xy 106.863388 -269.210581) (xy 106.886966 -269.256855)
			(xy 106.903014 -269.306248) (xy 106.911139 -269.357543) (xy 106.911648 -269.38351) (xy 106.911139 -269.409477)
			(xy 107.191049 -269.409477) (xy 107.191049 -269.357543) (xy 107.199174 -269.306248) (xy 107.215222 -269.256855)
			(xy 107.2388 -269.210581) (xy 107.269326 -269.168565) (xy 107.306049 -269.131842) (xy 107.348065 -269.101316)
			(xy 107.394339 -269.077738) (xy 107.443732 -269.06169) (xy 107.495027 -269.053565) (xy 107.546961 -269.053565)
			(xy 107.598256 -269.06169) (xy 107.647649 -269.077738) (xy 107.693923 -269.101316) (xy 107.735939 -269.131842)
			(xy 107.772662 -269.168565) (xy 107.803188 -269.210581) (xy 107.826766 -269.256855) (xy 107.842814 -269.306248)
			(xy 107.850939 -269.357543) (xy 107.851448 -269.38351) (xy 107.850939 -269.409477) (xy 108.130849 -269.409477)
			(xy 108.130849 -269.357543) (xy 108.138974 -269.306248) (xy 108.155022 -269.256855) (xy 108.1786 -269.210581)
			(xy 108.209126 -269.168565) (xy 108.245849 -269.131842) (xy 108.287865 -269.101316) (xy 108.334139 -269.077738)
			(xy 108.383532 -269.06169) (xy 108.434827 -269.053565) (xy 108.486761 -269.053565) (xy 108.538056 -269.06169)
			(xy 108.587449 -269.077738) (xy 108.633723 -269.101316) (xy 108.675739 -269.131842) (xy 108.712462 -269.168565)
			(xy 108.742988 -269.210581) (xy 108.766566 -269.256855) (xy 108.782614 -269.306248) (xy 108.790739 -269.357543)
			(xy 108.791248 -269.38351) (xy 108.790739 -269.409477) (xy 109.070649 -269.409477) (xy 109.070649 -269.357543)
			(xy 109.078774 -269.306248) (xy 109.094822 -269.256855) (xy 109.1184 -269.210581) (xy 109.148926 -269.168565)
			(xy 109.185649 -269.131842) (xy 109.227665 -269.101316) (xy 109.273939 -269.077738) (xy 109.323332 -269.06169)
			(xy 109.374627 -269.053565) (xy 109.426561 -269.053565) (xy 109.477856 -269.06169) (xy 109.527249 -269.077738)
			(xy 109.573523 -269.101316) (xy 109.615539 -269.131842) (xy 109.652262 -269.168565) (xy 109.682788 -269.210581)
			(xy 109.706366 -269.256855) (xy 109.722414 -269.306248) (xy 109.730539 -269.357543) (xy 109.731048 -269.38351)
			(xy 109.730539 -269.409477) (xy 110.010449 -269.409477) (xy 110.010449 -269.357543) (xy 110.018574 -269.306248)
			(xy 110.034622 -269.256855) (xy 110.0582 -269.210581) (xy 110.088726 -269.168565) (xy 110.125449 -269.131842)
			(xy 110.167465 -269.101316) (xy 110.213739 -269.077738) (xy 110.263132 -269.06169) (xy 110.314427 -269.053565)
			(xy 110.366361 -269.053565) (xy 110.417656 -269.06169) (xy 110.467049 -269.077738) (xy 110.513323 -269.101316)
			(xy 110.555339 -269.131842) (xy 110.592062 -269.168565) (xy 110.622588 -269.210581) (xy 110.646166 -269.256855)
			(xy 110.662214 -269.306248) (xy 110.670339 -269.357543) (xy 110.670848 -269.38351) (xy 110.670339 -269.409477)
			(xy 110.662214 -269.460772) (xy 110.646166 -269.510165) (xy 110.622588 -269.556439) (xy 110.592062 -269.598455)
			(xy 110.555339 -269.635178) (xy 110.513323 -269.665704) (xy 110.467049 -269.689282) (xy 110.417656 -269.70533)
			(xy 110.366361 -269.713455) (xy 110.314427 -269.713455) (xy 110.263132 -269.70533) (xy 110.213739 -269.689282)
			(xy 110.167465 -269.665704) (xy 110.125449 -269.635178) (xy 110.088726 -269.598455) (xy 110.0582 -269.556439)
			(xy 110.034622 -269.510165) (xy 110.018574 -269.460772) (xy 110.010449 -269.409477) (xy 109.730539 -269.409477)
			(xy 109.722414 -269.460772) (xy 109.706366 -269.510165) (xy 109.682788 -269.556439) (xy 109.652262 -269.598455)
			(xy 109.615539 -269.635178) (xy 109.573523 -269.665704) (xy 109.527249 -269.689282) (xy 109.477856 -269.70533)
			(xy 109.426561 -269.713455) (xy 109.374627 -269.713455) (xy 109.323332 -269.70533) (xy 109.273939 -269.689282)
			(xy 109.227665 -269.665704) (xy 109.185649 -269.635178) (xy 109.148926 -269.598455) (xy 109.1184 -269.556439)
			(xy 109.094822 -269.510165) (xy 109.078774 -269.460772) (xy 109.070649 -269.409477) (xy 108.790739 -269.409477)
			(xy 108.782614 -269.460772) (xy 108.766566 -269.510165) (xy 108.742988 -269.556439) (xy 108.712462 -269.598455)
			(xy 108.675739 -269.635178) (xy 108.633723 -269.665704) (xy 108.587449 -269.689282) (xy 108.538056 -269.70533)
			(xy 108.486761 -269.713455) (xy 108.434827 -269.713455) (xy 108.383532 -269.70533) (xy 108.334139 -269.689282)
			(xy 108.287865 -269.665704) (xy 108.245849 -269.635178) (xy 108.209126 -269.598455) (xy 108.1786 -269.556439)
			(xy 108.155022 -269.510165) (xy 108.138974 -269.460772) (xy 108.130849 -269.409477) (xy 107.850939 -269.409477)
			(xy 107.842814 -269.460772) (xy 107.826766 -269.510165) (xy 107.803188 -269.556439) (xy 107.772662 -269.598455)
			(xy 107.735939 -269.635178) (xy 107.693923 -269.665704) (xy 107.647649 -269.689282) (xy 107.598256 -269.70533)
			(xy 107.546961 -269.713455) (xy 107.495027 -269.713455) (xy 107.443732 -269.70533) (xy 107.394339 -269.689282)
			(xy 107.348065 -269.665704) (xy 107.306049 -269.635178) (xy 107.269326 -269.598455) (xy 107.2388 -269.556439)
			(xy 107.215222 -269.510165) (xy 107.199174 -269.460772) (xy 107.191049 -269.409477) (xy 106.911139 -269.409477)
			(xy 106.903014 -269.460772) (xy 106.886966 -269.510165) (xy 106.863388 -269.556439) (xy 106.832862 -269.598455)
			(xy 106.796139 -269.635178) (xy 106.754123 -269.665704) (xy 106.707849 -269.689282) (xy 106.658456 -269.70533)
			(xy 106.607161 -269.713455) (xy 106.555227 -269.713455) (xy 106.503932 -269.70533) (xy 106.454539 -269.689282)
			(xy 106.408265 -269.665704) (xy 106.366249 -269.635178) (xy 106.329526 -269.598455) (xy 106.299 -269.556439)
			(xy 106.275422 -269.510165) (xy 106.259374 -269.460772) (xy 106.251249 -269.409477) (xy 105.971339 -269.409477)
			(xy 105.963214 -269.460772) (xy 105.947166 -269.510165) (xy 105.923588 -269.556439) (xy 105.893062 -269.598455)
			(xy 105.856339 -269.635178) (xy 105.814323 -269.665704) (xy 105.768049 -269.689282) (xy 105.718656 -269.70533)
			(xy 105.667361 -269.713455) (xy 105.615427 -269.713455) (xy 105.564132 -269.70533) (xy 105.514739 -269.689282)
			(xy 105.468465 -269.665704) (xy 105.426449 -269.635178) (xy 105.389726 -269.598455) (xy 105.3592 -269.556439)
			(xy 105.335622 -269.510165) (xy 105.319574 -269.460772) (xy 105.311449 -269.409477) (xy 105.031539 -269.409477)
			(xy 105.023414 -269.460772) (xy 105.007366 -269.510165) (xy 104.983788 -269.556439) (xy 104.953262 -269.598455)
			(xy 104.916539 -269.635178) (xy 104.874523 -269.665704) (xy 104.828249 -269.689282) (xy 104.778856 -269.70533)
			(xy 104.727561 -269.713455) (xy 104.675627 -269.713455) (xy 104.624332 -269.70533) (xy 104.574939 -269.689282)
			(xy 104.528665 -269.665704) (xy 104.486649 -269.635178) (xy 104.449926 -269.598455) (xy 104.4194 -269.556439)
			(xy 104.395822 -269.510165) (xy 104.379774 -269.460772) (xy 104.371649 -269.409477) (xy 104.091739 -269.409477)
			(xy 104.083614 -269.460772) (xy 104.067566 -269.510165) (xy 104.043988 -269.556439) (xy 104.013462 -269.598455)
			(xy 103.976739 -269.635178) (xy 103.934723 -269.665704) (xy 103.888449 -269.689282) (xy 103.839056 -269.70533)
			(xy 103.787761 -269.713455) (xy 103.735827 -269.713455) (xy 103.684532 -269.70533) (xy 103.635139 -269.689282)
			(xy 103.588865 -269.665704) (xy 103.546849 -269.635178) (xy 103.510126 -269.598455) (xy 103.4796 -269.556439)
			(xy 103.456022 -269.510165) (xy 103.439974 -269.460772) (xy 103.431849 -269.409477) (xy 103.15196 -269.409477)
			(xy 103.143836 -269.460767) (xy 103.127786 -269.510163) (xy 103.104207 -269.556439) (xy 103.073679 -269.598457)
			(xy 103.036953 -269.635182) (xy 102.994934 -269.66571) (xy 102.948657 -269.689289) (xy 102.899261 -269.705338)
			(xy 102.847963 -269.713462) (xy 102.821994 -269.713964) (xy 102.82174 -269.713964) (xy 102.802576 -269.71367)
			(xy 102.764509 -269.709208) (xy 102.745794 -269.705074) (xy 102.730784 -269.702056) (xy 102.700253 -269.704138)
			(xy 102.671704 -269.715159) (xy 102.647693 -269.734131) (xy 102.630368 -269.759357) (xy 102.621281 -269.788579)
			(xy 102.620826 -269.80388) (xy 102.620826 -270.004794) (xy 102.635443 -270.025988) (xy 102.658618 -270.071959)
			(xy 102.674367 -270.120973) (xy 102.682309 -270.171838) (xy 102.682802 -270.19758) (xy 102.682308 -270.223319)
			(xy 102.682272 -270.223547) (xy 102.962203 -270.223547) (xy 102.962203 -270.171613) (xy 102.970328 -270.120318)
			(xy 102.986376 -270.070925) (xy 103.009954 -270.024651) (xy 103.04048 -269.982635) (xy 103.077203 -269.945912)
			(xy 103.119219 -269.915386) (xy 103.165493 -269.891808) (xy 103.214886 -269.87576) (xy 103.266181 -269.867635)
			(xy 103.318115 -269.867635) (xy 103.36941 -269.87576) (xy 103.418803 -269.891808) (xy 103.465077 -269.915386)
			(xy 103.507093 -269.945912) (xy 103.543816 -269.982635) (xy 103.574342 -270.024651) (xy 103.59792 -270.070925)
			(xy 103.613968 -270.120318) (xy 103.622093 -270.171613) (xy 103.622602 -270.19758) (xy 103.622093 -270.223547)
			(xy 103.902003 -270.223547) (xy 103.902003 -270.171613) (xy 103.910128 -270.120318) (xy 103.926176 -270.070925)
			(xy 103.949754 -270.024651) (xy 103.98028 -269.982635) (xy 104.017003 -269.945912) (xy 104.059019 -269.915386)
			(xy 104.105293 -269.891808) (xy 104.154686 -269.87576) (xy 104.205981 -269.867635) (xy 104.257915 -269.867635)
			(xy 104.30921 -269.87576) (xy 104.358603 -269.891808) (xy 104.404877 -269.915386) (xy 104.446893 -269.945912)
			(xy 104.483616 -269.982635) (xy 104.514142 -270.024651) (xy 104.53772 -270.070925) (xy 104.553768 -270.120318)
			(xy 104.561893 -270.171613) (xy 104.562402 -270.19758) (xy 104.561893 -270.223547) (xy 104.841803 -270.223547)
			(xy 104.841803 -270.171613) (xy 104.849928 -270.120318) (xy 104.865976 -270.070925) (xy 104.889554 -270.024651)
			(xy 104.92008 -269.982635) (xy 104.956803 -269.945912) (xy 104.998819 -269.915386) (xy 105.045093 -269.891808)
			(xy 105.094486 -269.87576) (xy 105.145781 -269.867635) (xy 105.197715 -269.867635) (xy 105.24901 -269.87576)
			(xy 105.298403 -269.891808) (xy 105.344677 -269.915386) (xy 105.386693 -269.945912) (xy 105.423416 -269.982635)
			(xy 105.453942 -270.024651) (xy 105.47752 -270.070925) (xy 105.493568 -270.120318) (xy 105.501693 -270.171613)
			(xy 105.502202 -270.19758) (xy 105.501693 -270.223547) (xy 105.781603 -270.223547) (xy 105.781603 -270.171613)
			(xy 105.789728 -270.120318) (xy 105.805776 -270.070925) (xy 105.829354 -270.024651) (xy 105.85988 -269.982635)
			(xy 105.896603 -269.945912) (xy 105.938619 -269.915386) (xy 105.984893 -269.891808) (xy 106.034286 -269.87576)
			(xy 106.085581 -269.867635) (xy 106.137515 -269.867635) (xy 106.18881 -269.87576) (xy 106.238203 -269.891808)
			(xy 106.284477 -269.915386) (xy 106.326493 -269.945912) (xy 106.363216 -269.982635) (xy 106.393742 -270.024651)
			(xy 106.41732 -270.070925) (xy 106.433368 -270.120318) (xy 106.441493 -270.171613) (xy 106.442002 -270.19758)
			(xy 106.441493 -270.223547) (xy 106.721403 -270.223547) (xy 106.721403 -270.171613) (xy 106.729528 -270.120318)
			(xy 106.745576 -270.070925) (xy 106.769154 -270.024651) (xy 106.79968 -269.982635) (xy 106.836403 -269.945912)
			(xy 106.878419 -269.915386) (xy 106.924693 -269.891808) (xy 106.974086 -269.87576) (xy 107.025381 -269.867635)
			(xy 107.077315 -269.867635) (xy 107.12861 -269.87576) (xy 107.178003 -269.891808) (xy 107.224277 -269.915386)
			(xy 107.266293 -269.945912) (xy 107.303016 -269.982635) (xy 107.333542 -270.024651) (xy 107.35712 -270.070925)
			(xy 107.373168 -270.120318) (xy 107.381293 -270.171613) (xy 107.381802 -270.19758) (xy 107.381293 -270.223547)
			(xy 107.661203 -270.223547) (xy 107.661203 -270.171613) (xy 107.669328 -270.120318) (xy 107.685376 -270.070925)
			(xy 107.708954 -270.024651) (xy 107.73948 -269.982635) (xy 107.776203 -269.945912) (xy 107.818219 -269.915386)
			(xy 107.864493 -269.891808) (xy 107.913886 -269.87576) (xy 107.965181 -269.867635) (xy 108.017115 -269.867635)
			(xy 108.06841 -269.87576) (xy 108.117803 -269.891808) (xy 108.164077 -269.915386) (xy 108.206093 -269.945912)
			(xy 108.242816 -269.982635) (xy 108.273342 -270.024651) (xy 108.29692 -270.070925) (xy 108.312968 -270.120318)
			(xy 108.321093 -270.171613) (xy 108.321602 -270.19758) (xy 108.321093 -270.223547) (xy 108.600749 -270.223547)
			(xy 108.600749 -270.171613) (xy 108.608874 -270.120318) (xy 108.624922 -270.070925) (xy 108.6485 -270.024651)
			(xy 108.679026 -269.982635) (xy 108.715749 -269.945912) (xy 108.757765 -269.915386) (xy 108.804039 -269.891808)
			(xy 108.853432 -269.87576) (xy 108.904727 -269.867635) (xy 108.956661 -269.867635) (xy 109.007956 -269.87576)
			(xy 109.057349 -269.891808) (xy 109.103623 -269.915386) (xy 109.145639 -269.945912) (xy 109.182362 -269.982635)
			(xy 109.212888 -270.024651) (xy 109.236466 -270.070925) (xy 109.252514 -270.120318) (xy 109.260639 -270.171613)
			(xy 109.261148 -270.19758) (xy 109.260639 -270.223547) (xy 109.252514 -270.274842) (xy 109.236466 -270.324235)
			(xy 109.212888 -270.370509) (xy 109.182362 -270.412525) (xy 109.145639 -270.449248) (xy 109.103623 -270.479774)
			(xy 109.057349 -270.503352) (xy 109.007956 -270.5194) (xy 108.956661 -270.527525) (xy 108.904727 -270.527525)
			(xy 108.853432 -270.5194) (xy 108.804039 -270.503352) (xy 108.757765 -270.479774) (xy 108.715749 -270.449248)
			(xy 108.679026 -270.412525) (xy 108.6485 -270.370509) (xy 108.624922 -270.324235) (xy 108.608874 -270.274842)
			(xy 108.600749 -270.223547) (xy 108.321093 -270.223547) (xy 108.312968 -270.274842) (xy 108.29692 -270.324235)
			(xy 108.273342 -270.370509) (xy 108.242816 -270.412525) (xy 108.206093 -270.449248) (xy 108.164077 -270.479774)
			(xy 108.117803 -270.503352) (xy 108.06841 -270.5194) (xy 108.017115 -270.527525) (xy 107.965181 -270.527525)
			(xy 107.913886 -270.5194) (xy 107.864493 -270.503352) (xy 107.818219 -270.479774) (xy 107.776203 -270.449248)
			(xy 107.73948 -270.412525) (xy 107.708954 -270.370509) (xy 107.685376 -270.324235) (xy 107.669328 -270.274842)
			(xy 107.661203 -270.223547) (xy 107.381293 -270.223547) (xy 107.373168 -270.274842) (xy 107.35712 -270.324235)
			(xy 107.333542 -270.370509) (xy 107.303016 -270.412525) (xy 107.266293 -270.449248) (xy 107.224277 -270.479774)
			(xy 107.178003 -270.503352) (xy 107.12861 -270.5194) (xy 107.077315 -270.527525) (xy 107.025381 -270.527525)
			(xy 106.974086 -270.5194) (xy 106.924693 -270.503352) (xy 106.878419 -270.479774) (xy 106.836403 -270.449248)
			(xy 106.79968 -270.412525) (xy 106.769154 -270.370509) (xy 106.745576 -270.324235) (xy 106.729528 -270.274842)
			(xy 106.721403 -270.223547) (xy 106.441493 -270.223547) (xy 106.433368 -270.274842) (xy 106.41732 -270.324235)
			(xy 106.393742 -270.370509) (xy 106.363216 -270.412525) (xy 106.326493 -270.449248) (xy 106.284477 -270.479774)
			(xy 106.238203 -270.503352) (xy 106.18881 -270.5194) (xy 106.137515 -270.527525) (xy 106.085581 -270.527525)
			(xy 106.034286 -270.5194) (xy 105.984893 -270.503352) (xy 105.938619 -270.479774) (xy 105.896603 -270.449248)
			(xy 105.85988 -270.412525) (xy 105.829354 -270.370509) (xy 105.805776 -270.324235) (xy 105.789728 -270.274842)
			(xy 105.781603 -270.223547) (xy 105.501693 -270.223547) (xy 105.493568 -270.274842) (xy 105.47752 -270.324235)
			(xy 105.453942 -270.370509) (xy 105.423416 -270.412525) (xy 105.386693 -270.449248) (xy 105.344677 -270.479774)
			(xy 105.298403 -270.503352) (xy 105.24901 -270.5194) (xy 105.197715 -270.527525) (xy 105.145781 -270.527525)
			(xy 105.094486 -270.5194) (xy 105.045093 -270.503352) (xy 104.998819 -270.479774) (xy 104.956803 -270.449248)
			(xy 104.92008 -270.412525) (xy 104.889554 -270.370509) (xy 104.865976 -270.324235) (xy 104.849928 -270.274842)
			(xy 104.841803 -270.223547) (xy 104.561893 -270.223547) (xy 104.553768 -270.274842) (xy 104.53772 -270.324235)
			(xy 104.514142 -270.370509) (xy 104.483616 -270.412525) (xy 104.446893 -270.449248) (xy 104.404877 -270.479774)
			(xy 104.358603 -270.503352) (xy 104.30921 -270.5194) (xy 104.257915 -270.527525) (xy 104.205981 -270.527525)
			(xy 104.154686 -270.5194) (xy 104.105293 -270.503352) (xy 104.059019 -270.479774) (xy 104.017003 -270.449248)
			(xy 103.98028 -270.412525) (xy 103.949754 -270.370509) (xy 103.926176 -270.324235) (xy 103.910128 -270.274842)
			(xy 103.902003 -270.223547) (xy 103.622093 -270.223547) (xy 103.613968 -270.274842) (xy 103.59792 -270.324235)
			(xy 103.574342 -270.370509) (xy 103.543816 -270.412525) (xy 103.507093 -270.449248) (xy 103.465077 -270.479774)
			(xy 103.418803 -270.503352) (xy 103.36941 -270.5194) (xy 103.318115 -270.527525) (xy 103.266181 -270.527525)
			(xy 103.214886 -270.5194) (xy 103.165493 -270.503352) (xy 103.119219 -270.479774) (xy 103.077203 -270.449248)
			(xy 103.04048 -270.412525) (xy 103.009954 -270.370509) (xy 102.986376 -270.324235) (xy 102.970328 -270.274842)
			(xy 102.962203 -270.223547) (xy 102.682272 -270.223547) (xy 102.67433 -270.274177) (xy 102.65858 -270.323187)
			(xy 102.635437 -270.36917) (xy 102.620826 -270.390366) (xy 102.620826 -270.591026) (xy 102.621335 -270.606328)
			(xy 102.630383 -270.635564) (xy 102.647688 -270.660805) (xy 102.671696 -270.679785) (xy 102.700249 -270.690797)
			(xy 102.730784 -270.692853) (xy 102.745794 -270.689832) (xy 102.764504 -270.685669) (xy 102.802575 -270.681211)
			(xy 102.82174 -270.680942) (xy 102.821994 -270.680942) (xy 102.847964 -270.681424) (xy 102.899264 -270.689549)
			(xy 102.948662 -270.705598) (xy 102.994941 -270.729178) (xy 103.036962 -270.759707) (xy 103.073689 -270.796434)
			(xy 103.104219 -270.838454) (xy 103.127799 -270.884732) (xy 103.14385 -270.93413) (xy 103.151975 -270.98543)
			(xy 103.151975 -271.037363) (xy 103.431849 -271.037363) (xy 103.431849 -270.985429) (xy 103.439974 -270.934134)
			(xy 103.456022 -270.884741) (xy 103.4796 -270.838467) (xy 103.510126 -270.796451) (xy 103.546849 -270.759728)
			(xy 103.588865 -270.729202) (xy 103.635139 -270.705624) (xy 103.684532 -270.689576) (xy 103.735827 -270.681451)
			(xy 103.787761 -270.681451) (xy 103.839056 -270.689576) (xy 103.888449 -270.705624) (xy 103.934723 -270.729202)
			(xy 103.976739 -270.759728) (xy 104.013462 -270.796451) (xy 104.043988 -270.838467) (xy 104.067566 -270.884741)
			(xy 104.083614 -270.934134) (xy 104.091739 -270.985429) (xy 104.092248 -271.011396) (xy 104.091739 -271.037363)
			(xy 104.371649 -271.037363) (xy 104.371649 -270.985429) (xy 104.379774 -270.934134) (xy 104.395822 -270.884741)
			(xy 104.4194 -270.838467) (xy 104.449926 -270.796451) (xy 104.486649 -270.759728) (xy 104.528665 -270.729202)
			(xy 104.574939 -270.705624) (xy 104.624332 -270.689576) (xy 104.675627 -270.681451) (xy 104.727561 -270.681451)
			(xy 104.778856 -270.689576) (xy 104.828249 -270.705624) (xy 104.874523 -270.729202) (xy 104.916539 -270.759728)
			(xy 104.953262 -270.796451) (xy 104.983788 -270.838467) (xy 105.007366 -270.884741) (xy 105.023414 -270.934134)
			(xy 105.031539 -270.985429) (xy 105.032048 -271.011396) (xy 105.031539 -271.037363) (xy 105.311449 -271.037363)
			(xy 105.311449 -270.985429) (xy 105.319574 -270.934134) (xy 105.335622 -270.884741) (xy 105.3592 -270.838467)
			(xy 105.389726 -270.796451) (xy 105.426449 -270.759728) (xy 105.468465 -270.729202) (xy 105.514739 -270.705624)
			(xy 105.564132 -270.689576) (xy 105.615427 -270.681451) (xy 105.667361 -270.681451) (xy 105.718656 -270.689576)
			(xy 105.768049 -270.705624) (xy 105.814323 -270.729202) (xy 105.856339 -270.759728) (xy 105.893062 -270.796451)
			(xy 105.923588 -270.838467) (xy 105.947166 -270.884741) (xy 105.963214 -270.934134) (xy 105.971339 -270.985429)
			(xy 105.971848 -271.011396) (xy 105.971339 -271.037363) (xy 106.251249 -271.037363) (xy 106.251249 -270.985429)
			(xy 106.259374 -270.934134) (xy 106.275422 -270.884741) (xy 106.299 -270.838467) (xy 106.329526 -270.796451)
			(xy 106.366249 -270.759728) (xy 106.408265 -270.729202) (xy 106.454539 -270.705624) (xy 106.503932 -270.689576)
			(xy 106.555227 -270.681451) (xy 106.607161 -270.681451) (xy 106.658456 -270.689576) (xy 106.707849 -270.705624)
			(xy 106.754123 -270.729202) (xy 106.796139 -270.759728) (xy 106.832862 -270.796451) (xy 106.863388 -270.838467)
			(xy 106.886966 -270.884741) (xy 106.903014 -270.934134) (xy 106.911139 -270.985429) (xy 106.911648 -271.011396)
			(xy 106.911139 -271.037363) (xy 107.191049 -271.037363) (xy 107.191049 -270.985429) (xy 107.199174 -270.934134)
			(xy 107.215222 -270.884741) (xy 107.2388 -270.838467) (xy 107.269326 -270.796451) (xy 107.306049 -270.759728)
			(xy 107.348065 -270.729202) (xy 107.394339 -270.705624) (xy 107.443732 -270.689576) (xy 107.495027 -270.681451)
			(xy 107.546961 -270.681451) (xy 107.598256 -270.689576) (xy 107.647649 -270.705624) (xy 107.693923 -270.729202)
			(xy 107.735939 -270.759728) (xy 107.772662 -270.796451) (xy 107.803188 -270.838467) (xy 107.826766 -270.884741)
			(xy 107.842814 -270.934134) (xy 107.850939 -270.985429) (xy 107.851448 -271.011396) (xy 107.850939 -271.037363)
			(xy 108.130849 -271.037363) (xy 108.130849 -270.985429) (xy 108.138974 -270.934134) (xy 108.155022 -270.884741)
			(xy 108.1786 -270.838467) (xy 108.209126 -270.796451) (xy 108.245849 -270.759728) (xy 108.287865 -270.729202)
			(xy 108.334139 -270.705624) (xy 108.383532 -270.689576) (xy 108.434827 -270.681451) (xy 108.486761 -270.681451)
			(xy 108.538056 -270.689576) (xy 108.587449 -270.705624) (xy 108.633723 -270.729202) (xy 108.675739 -270.759728)
			(xy 108.712462 -270.796451) (xy 108.742988 -270.838467) (xy 108.766566 -270.884741) (xy 108.782614 -270.934134)
			(xy 108.790739 -270.985429) (xy 108.791248 -271.011396) (xy 108.790739 -271.037363) (xy 109.070649 -271.037363)
			(xy 109.070649 -270.985429) (xy 109.078774 -270.934134) (xy 109.094822 -270.884741) (xy 109.1184 -270.838467)
			(xy 109.148926 -270.796451) (xy 109.185649 -270.759728) (xy 109.227665 -270.729202) (xy 109.273939 -270.705624)
			(xy 109.323332 -270.689576) (xy 109.374627 -270.681451) (xy 109.426561 -270.681451) (xy 109.477856 -270.689576)
			(xy 109.527249 -270.705624) (xy 109.573523 -270.729202) (xy 109.615539 -270.759728) (xy 109.652262 -270.796451)
			(xy 109.682788 -270.838467) (xy 109.706366 -270.884741) (xy 109.722414 -270.934134) (xy 109.730539 -270.985429)
			(xy 109.731048 -271.011396) (xy 109.730539 -271.037363) (xy 110.010449 -271.037363) (xy 110.010449 -270.985429)
			(xy 110.018574 -270.934134) (xy 110.034622 -270.884741) (xy 110.0582 -270.838467) (xy 110.088726 -270.796451)
			(xy 110.125449 -270.759728) (xy 110.167465 -270.729202) (xy 110.213739 -270.705624) (xy 110.263132 -270.689576)
			(xy 110.314427 -270.681451) (xy 110.366361 -270.681451) (xy 110.417656 -270.689576) (xy 110.467049 -270.705624)
			(xy 110.513323 -270.729202) (xy 110.555339 -270.759728) (xy 110.592062 -270.796451) (xy 110.622588 -270.838467)
			(xy 110.646166 -270.884741) (xy 110.662214 -270.934134) (xy 110.670339 -270.985429) (xy 110.670848 -271.011396)
			(xy 110.670339 -271.037363) (xy 110.662214 -271.088658) (xy 110.646166 -271.138051) (xy 110.622588 -271.184325)
			(xy 110.592062 -271.226341) (xy 110.555339 -271.263064) (xy 110.513323 -271.29359) (xy 110.467049 -271.317168)
			(xy 110.417656 -271.333216) (xy 110.366361 -271.341341) (xy 110.314427 -271.341341) (xy 110.263132 -271.333216)
			(xy 110.213739 -271.317168) (xy 110.167465 -271.29359) (xy 110.125449 -271.263064) (xy 110.088726 -271.226341)
			(xy 110.0582 -271.184325) (xy 110.034622 -271.138051) (xy 110.018574 -271.088658) (xy 110.010449 -271.037363)
			(xy 109.730539 -271.037363) (xy 109.722414 -271.088658) (xy 109.706366 -271.138051) (xy 109.682788 -271.184325)
			(xy 109.652262 -271.226341) (xy 109.615539 -271.263064) (xy 109.573523 -271.29359) (xy 109.527249 -271.317168)
			(xy 109.477856 -271.333216) (xy 109.426561 -271.341341) (xy 109.374627 -271.341341) (xy 109.323332 -271.333216)
			(xy 109.273939 -271.317168) (xy 109.227665 -271.29359) (xy 109.185649 -271.263064) (xy 109.148926 -271.226341)
			(xy 109.1184 -271.184325) (xy 109.094822 -271.138051) (xy 109.078774 -271.088658) (xy 109.070649 -271.037363)
			(xy 108.790739 -271.037363) (xy 108.782614 -271.088658) (xy 108.766566 -271.138051) (xy 108.742988 -271.184325)
			(xy 108.712462 -271.226341) (xy 108.675739 -271.263064) (xy 108.633723 -271.29359) (xy 108.587449 -271.317168)
			(xy 108.538056 -271.333216) (xy 108.486761 -271.341341) (xy 108.434827 -271.341341) (xy 108.383532 -271.333216)
			(xy 108.334139 -271.317168) (xy 108.287865 -271.29359) (xy 108.245849 -271.263064) (xy 108.209126 -271.226341)
			(xy 108.1786 -271.184325) (xy 108.155022 -271.138051) (xy 108.138974 -271.088658) (xy 108.130849 -271.037363)
			(xy 107.850939 -271.037363) (xy 107.842814 -271.088658) (xy 107.826766 -271.138051) (xy 107.803188 -271.184325)
			(xy 107.772662 -271.226341) (xy 107.735939 -271.263064) (xy 107.693923 -271.29359) (xy 107.647649 -271.317168)
			(xy 107.598256 -271.333216) (xy 107.546961 -271.341341) (xy 107.495027 -271.341341) (xy 107.443732 -271.333216)
			(xy 107.394339 -271.317168) (xy 107.348065 -271.29359) (xy 107.306049 -271.263064) (xy 107.269326 -271.226341)
			(xy 107.2388 -271.184325) (xy 107.215222 -271.138051) (xy 107.199174 -271.088658) (xy 107.191049 -271.037363)
			(xy 106.911139 -271.037363) (xy 106.903014 -271.088658) (xy 106.886966 -271.138051) (xy 106.863388 -271.184325)
			(xy 106.832862 -271.226341) (xy 106.796139 -271.263064) (xy 106.754123 -271.29359) (xy 106.707849 -271.317168)
			(xy 106.658456 -271.333216) (xy 106.607161 -271.341341) (xy 106.555227 -271.341341) (xy 106.503932 -271.333216)
			(xy 106.454539 -271.317168) (xy 106.408265 -271.29359) (xy 106.366249 -271.263064) (xy 106.329526 -271.226341)
			(xy 106.299 -271.184325) (xy 106.275422 -271.138051) (xy 106.259374 -271.088658) (xy 106.251249 -271.037363)
			(xy 105.971339 -271.037363) (xy 105.963214 -271.088658) (xy 105.947166 -271.138051) (xy 105.923588 -271.184325)
			(xy 105.893062 -271.226341) (xy 105.856339 -271.263064) (xy 105.814323 -271.29359) (xy 105.768049 -271.317168)
			(xy 105.718656 -271.333216) (xy 105.667361 -271.341341) (xy 105.615427 -271.341341) (xy 105.564132 -271.333216)
			(xy 105.514739 -271.317168) (xy 105.468465 -271.29359) (xy 105.426449 -271.263064) (xy 105.389726 -271.226341)
			(xy 105.3592 -271.184325) (xy 105.335622 -271.138051) (xy 105.319574 -271.088658) (xy 105.311449 -271.037363)
			(xy 105.031539 -271.037363) (xy 105.023414 -271.088658) (xy 105.007366 -271.138051) (xy 104.983788 -271.184325)
			(xy 104.953262 -271.226341) (xy 104.916539 -271.263064) (xy 104.874523 -271.29359) (xy 104.828249 -271.317168)
			(xy 104.778856 -271.333216) (xy 104.727561 -271.341341) (xy 104.675627 -271.341341) (xy 104.624332 -271.333216)
			(xy 104.574939 -271.317168) (xy 104.528665 -271.29359) (xy 104.486649 -271.263064) (xy 104.449926 -271.226341)
			(xy 104.4194 -271.184325) (xy 104.395822 -271.138051) (xy 104.379774 -271.088658) (xy 104.371649 -271.037363)
			(xy 104.091739 -271.037363) (xy 104.083614 -271.088658) (xy 104.067566 -271.138051) (xy 104.043988 -271.184325)
			(xy 104.013462 -271.226341) (xy 103.976739 -271.263064) (xy 103.934723 -271.29359) (xy 103.888449 -271.317168)
			(xy 103.839056 -271.333216) (xy 103.787761 -271.341341) (xy 103.735827 -271.341341) (xy 103.684532 -271.333216)
			(xy 103.635139 -271.317168) (xy 103.588865 -271.29359) (xy 103.546849 -271.263064) (xy 103.510126 -271.226341)
			(xy 103.4796 -271.184325) (xy 103.456022 -271.138051) (xy 103.439974 -271.088658) (xy 103.431849 -271.037363)
			(xy 103.151975 -271.037363) (xy 103.151975 -271.03737) (xy 103.14385 -271.08867) (xy 103.127799 -271.138068)
			(xy 103.104219 -271.184346) (xy 103.073689 -271.226366) (xy 103.036962 -271.263093) (xy 102.994941 -271.293622)
			(xy 102.948662 -271.317202) (xy 102.899264 -271.333251) (xy 102.847964 -271.341376) (xy 102.821994 -271.34185)
			(xy 102.82174 -271.34185) (xy 102.802576 -271.341556) (xy 102.764509 -271.337095) (xy 102.745794 -271.33296)
			(xy 102.730784 -271.329943) (xy 102.700251 -271.332025) (xy 102.671701 -271.343045) (xy 102.647687 -271.362017)
			(xy 102.63036 -271.387243) (xy 102.62127 -271.416465) (xy 102.620826 -271.431766) (xy 102.620826 -271.632426)
			(xy 102.635447 -271.653619) (xy 102.658632 -271.699588) (xy 102.674391 -271.748602) (xy 102.682343 -271.799469)
			(xy 102.682802 -271.825212) (xy 102.682305 -271.850951) (xy 102.682269 -271.851179) (xy 102.962203 -271.851179)
			(xy 102.962203 -271.799245) (xy 102.970328 -271.74795) (xy 102.986376 -271.698557) (xy 103.009954 -271.652283)
			(xy 103.04048 -271.610267) (xy 103.077203 -271.573544) (xy 103.119219 -271.543018) (xy 103.165493 -271.51944)
			(xy 103.214886 -271.503392) (xy 103.266181 -271.495267) (xy 103.318115 -271.495267) (xy 103.36941 -271.503392)
			(xy 103.418803 -271.51944) (xy 103.465077 -271.543018) (xy 103.507093 -271.573544) (xy 103.543816 -271.610267)
			(xy 103.574342 -271.652283) (xy 103.59792 -271.698557) (xy 103.613968 -271.74795) (xy 103.622093 -271.799245)
			(xy 103.622602 -271.825212) (xy 103.622093 -271.851179) (xy 103.902003 -271.851179) (xy 103.902003 -271.799245)
			(xy 103.910128 -271.74795) (xy 103.926176 -271.698557) (xy 103.949754 -271.652283) (xy 103.98028 -271.610267)
			(xy 104.017003 -271.573544) (xy 104.059019 -271.543018) (xy 104.105293 -271.51944) (xy 104.154686 -271.503392)
			(xy 104.205981 -271.495267) (xy 104.257915 -271.495267) (xy 104.30921 -271.503392) (xy 104.358603 -271.51944)
			(xy 104.404877 -271.543018) (xy 104.446893 -271.573544) (xy 104.483616 -271.610267) (xy 104.514142 -271.652283)
			(xy 104.53772 -271.698557) (xy 104.553768 -271.74795) (xy 104.561893 -271.799245) (xy 104.562402 -271.825212)
			(xy 104.561893 -271.851179) (xy 104.841803 -271.851179) (xy 104.841803 -271.799245) (xy 104.849928 -271.74795)
			(xy 104.865976 -271.698557) (xy 104.889554 -271.652283) (xy 104.92008 -271.610267) (xy 104.956803 -271.573544)
			(xy 104.998819 -271.543018) (xy 105.045093 -271.51944) (xy 105.094486 -271.503392) (xy 105.145781 -271.495267)
			(xy 105.197715 -271.495267) (xy 105.24901 -271.503392) (xy 105.298403 -271.51944) (xy 105.344677 -271.543018)
			(xy 105.386693 -271.573544) (xy 105.423416 -271.610267) (xy 105.453942 -271.652283) (xy 105.47752 -271.698557)
			(xy 105.493568 -271.74795) (xy 105.501693 -271.799245) (xy 105.502202 -271.825212) (xy 105.501693 -271.851179)
			(xy 105.781603 -271.851179) (xy 105.781603 -271.799245) (xy 105.789728 -271.74795) (xy 105.805776 -271.698557)
			(xy 105.829354 -271.652283) (xy 105.85988 -271.610267) (xy 105.896603 -271.573544) (xy 105.938619 -271.543018)
			(xy 105.984893 -271.51944) (xy 106.034286 -271.503392) (xy 106.085581 -271.495267) (xy 106.137515 -271.495267)
			(xy 106.18881 -271.503392) (xy 106.238203 -271.51944) (xy 106.284477 -271.543018) (xy 106.326493 -271.573544)
			(xy 106.363216 -271.610267) (xy 106.393742 -271.652283) (xy 106.41732 -271.698557) (xy 106.433368 -271.74795)
			(xy 106.441493 -271.799245) (xy 106.442002 -271.825212) (xy 106.441493 -271.851179) (xy 106.721403 -271.851179)
			(xy 106.721403 -271.799245) (xy 106.729528 -271.74795) (xy 106.745576 -271.698557) (xy 106.769154 -271.652283)
			(xy 106.79968 -271.610267) (xy 106.836403 -271.573544) (xy 106.878419 -271.543018) (xy 106.924693 -271.51944)
			(xy 106.974086 -271.503392) (xy 107.025381 -271.495267) (xy 107.077315 -271.495267) (xy 107.12861 -271.503392)
			(xy 107.178003 -271.51944) (xy 107.224277 -271.543018) (xy 107.266293 -271.573544) (xy 107.303016 -271.610267)
			(xy 107.333542 -271.652283) (xy 107.35712 -271.698557) (xy 107.373168 -271.74795) (xy 107.381293 -271.799245)
			(xy 107.381802 -271.825212) (xy 107.381293 -271.851179) (xy 107.661203 -271.851179) (xy 107.661203 -271.799245)
			(xy 107.669328 -271.74795) (xy 107.685376 -271.698557) (xy 107.708954 -271.652283) (xy 107.73948 -271.610267)
			(xy 107.776203 -271.573544) (xy 107.818219 -271.543018) (xy 107.864493 -271.51944) (xy 107.913886 -271.503392)
			(xy 107.965181 -271.495267) (xy 108.017115 -271.495267) (xy 108.06841 -271.503392) (xy 108.117803 -271.51944)
			(xy 108.164077 -271.543018) (xy 108.206093 -271.573544) (xy 108.242816 -271.610267) (xy 108.273342 -271.652283)
			(xy 108.29692 -271.698557) (xy 108.312968 -271.74795) (xy 108.321093 -271.799245) (xy 108.321602 -271.825212)
			(xy 108.321093 -271.851179) (xy 108.601003 -271.851179) (xy 108.601003 -271.799245) (xy 108.609128 -271.74795)
			(xy 108.625176 -271.698557) (xy 108.648754 -271.652283) (xy 108.67928 -271.610267) (xy 108.716003 -271.573544)
			(xy 108.758019 -271.543018) (xy 108.804293 -271.51944) (xy 108.853686 -271.503392) (xy 108.904981 -271.495267)
			(xy 108.956915 -271.495267) (xy 109.00821 -271.503392) (xy 109.057603 -271.51944) (xy 109.103877 -271.543018)
			(xy 109.145893 -271.573544) (xy 109.182616 -271.610267) (xy 109.213142 -271.652283) (xy 109.23672 -271.698557)
			(xy 109.252768 -271.74795) (xy 109.260893 -271.799245) (xy 109.261402 -271.825212) (xy 109.260893 -271.851179)
			(xy 109.540295 -271.851179) (xy 109.540295 -271.799245) (xy 109.54842 -271.74795) (xy 109.564468 -271.698557)
			(xy 109.588046 -271.652283) (xy 109.618572 -271.610267) (xy 109.655295 -271.573544) (xy 109.697311 -271.543018)
			(xy 109.743585 -271.51944) (xy 109.792978 -271.503392) (xy 109.844273 -271.495267) (xy 109.896207 -271.495267)
			(xy 109.947502 -271.503392) (xy 109.996895 -271.51944) (xy 110.043169 -271.543018) (xy 110.085185 -271.573544)
			(xy 110.121908 -271.610267) (xy 110.152434 -271.652283) (xy 110.176012 -271.698557) (xy 110.19206 -271.74795)
			(xy 110.200185 -271.799245) (xy 110.200694 -271.825212) (xy 110.200185 -271.851179) (xy 110.19206 -271.902474)
			(xy 110.176012 -271.951867) (xy 110.152434 -271.998141) (xy 110.121908 -272.040157) (xy 110.085185 -272.07688)
			(xy 110.043169 -272.107406) (xy 109.996895 -272.130984) (xy 109.947502 -272.147032) (xy 109.896207 -272.155157)
			(xy 109.844273 -272.155157) (xy 109.792978 -272.147032) (xy 109.743585 -272.130984) (xy 109.697311 -272.107406)
			(xy 109.655295 -272.07688) (xy 109.618572 -272.040157) (xy 109.588046 -271.998141) (xy 109.564468 -271.951867)
			(xy 109.54842 -271.902474) (xy 109.540295 -271.851179) (xy 109.260893 -271.851179) (xy 109.252768 -271.902474)
			(xy 109.23672 -271.951867) (xy 109.213142 -271.998141) (xy 109.182616 -272.040157) (xy 109.145893 -272.07688)
			(xy 109.103877 -272.107406) (xy 109.057603 -272.130984) (xy 109.00821 -272.147032) (xy 108.956915 -272.155157)
			(xy 108.904981 -272.155157) (xy 108.853686 -272.147032) (xy 108.804293 -272.130984) (xy 108.758019 -272.107406)
			(xy 108.716003 -272.07688) (xy 108.67928 -272.040157) (xy 108.648754 -271.998141) (xy 108.625176 -271.951867)
			(xy 108.609128 -271.902474) (xy 108.601003 -271.851179) (xy 108.321093 -271.851179) (xy 108.312968 -271.902474)
			(xy 108.29692 -271.951867) (xy 108.273342 -271.998141) (xy 108.242816 -272.040157) (xy 108.206093 -272.07688)
			(xy 108.164077 -272.107406) (xy 108.117803 -272.130984) (xy 108.06841 -272.147032) (xy 108.017115 -272.155157)
			(xy 107.965181 -272.155157) (xy 107.913886 -272.147032) (xy 107.864493 -272.130984) (xy 107.818219 -272.107406)
			(xy 107.776203 -272.07688) (xy 107.73948 -272.040157) (xy 107.708954 -271.998141) (xy 107.685376 -271.951867)
			(xy 107.669328 -271.902474) (xy 107.661203 -271.851179) (xy 107.381293 -271.851179) (xy 107.373168 -271.902474)
			(xy 107.35712 -271.951867) (xy 107.333542 -271.998141) (xy 107.303016 -272.040157) (xy 107.266293 -272.07688)
			(xy 107.224277 -272.107406) (xy 107.178003 -272.130984) (xy 107.12861 -272.147032) (xy 107.077315 -272.155157)
			(xy 107.025381 -272.155157) (xy 106.974086 -272.147032) (xy 106.924693 -272.130984) (xy 106.878419 -272.107406)
			(xy 106.836403 -272.07688) (xy 106.79968 -272.040157) (xy 106.769154 -271.998141) (xy 106.745576 -271.951867)
			(xy 106.729528 -271.902474) (xy 106.721403 -271.851179) (xy 106.441493 -271.851179) (xy 106.433368 -271.902474)
			(xy 106.41732 -271.951867) (xy 106.393742 -271.998141) (xy 106.363216 -272.040157) (xy 106.326493 -272.07688)
			(xy 106.284477 -272.107406) (xy 106.238203 -272.130984) (xy 106.18881 -272.147032) (xy 106.137515 -272.155157)
			(xy 106.085581 -272.155157) (xy 106.034286 -272.147032) (xy 105.984893 -272.130984) (xy 105.938619 -272.107406)
			(xy 105.896603 -272.07688) (xy 105.85988 -272.040157) (xy 105.829354 -271.998141) (xy 105.805776 -271.951867)
			(xy 105.789728 -271.902474) (xy 105.781603 -271.851179) (xy 105.501693 -271.851179) (xy 105.493568 -271.902474)
			(xy 105.47752 -271.951867) (xy 105.453942 -271.998141) (xy 105.423416 -272.040157) (xy 105.386693 -272.07688)
			(xy 105.344677 -272.107406) (xy 105.298403 -272.130984) (xy 105.24901 -272.147032) (xy 105.197715 -272.155157)
			(xy 105.145781 -272.155157) (xy 105.094486 -272.147032) (xy 105.045093 -272.130984) (xy 104.998819 -272.107406)
			(xy 104.956803 -272.07688) (xy 104.92008 -272.040157) (xy 104.889554 -271.998141) (xy 104.865976 -271.951867)
			(xy 104.849928 -271.902474) (xy 104.841803 -271.851179) (xy 104.561893 -271.851179) (xy 104.553768 -271.902474)
			(xy 104.53772 -271.951867) (xy 104.514142 -271.998141) (xy 104.483616 -272.040157) (xy 104.446893 -272.07688)
			(xy 104.404877 -272.107406) (xy 104.358603 -272.130984) (xy 104.30921 -272.147032) (xy 104.257915 -272.155157)
			(xy 104.205981 -272.155157) (xy 104.154686 -272.147032) (xy 104.105293 -272.130984) (xy 104.059019 -272.107406)
			(xy 104.017003 -272.07688) (xy 103.98028 -272.040157) (xy 103.949754 -271.998141) (xy 103.926176 -271.951867)
			(xy 103.910128 -271.902474) (xy 103.902003 -271.851179) (xy 103.622093 -271.851179) (xy 103.613968 -271.902474)
			(xy 103.59792 -271.951867) (xy 103.574342 -271.998141) (xy 103.543816 -272.040157) (xy 103.507093 -272.07688)
			(xy 103.465077 -272.107406) (xy 103.418803 -272.130984) (xy 103.36941 -272.147032) (xy 103.318115 -272.155157)
			(xy 103.266181 -272.155157) (xy 103.214886 -272.147032) (xy 103.165493 -272.130984) (xy 103.119219 -272.107406)
			(xy 103.077203 -272.07688) (xy 103.04048 -272.040157) (xy 103.009954 -271.998141) (xy 102.986376 -271.951867)
			(xy 102.970328 -271.902474) (xy 102.962203 -271.851179) (xy 102.682269 -271.851179) (xy 102.674323 -271.901806)
			(xy 102.65857 -271.950813) (xy 102.635423 -271.996793) (xy 102.620826 -272.017998) (xy 102.620826 -272.218912)
			(xy 102.621334 -272.234216) (xy 102.630379 -272.263455) (xy 102.647683 -272.2887) (xy 102.671692 -272.307683)
			(xy 102.700248 -272.318697) (xy 102.730786 -272.320753) (xy 102.745794 -272.317718) (xy 102.764504 -272.313555)
			(xy 102.802575 -272.309097) (xy 102.82174 -272.308828) (xy 102.821994 -272.308828) (xy 102.847962 -272.309337)
			(xy 102.899259 -272.31746) (xy 102.948653 -272.333508) (xy 102.994929 -272.357085) (xy 103.036948 -272.387611)
			(xy 103.073673 -272.424334) (xy 103.104202 -272.46635) (xy 103.127783 -272.512624) (xy 103.143834 -272.562018)
			(xy 103.151961 -272.613314) (xy 103.152448 -272.639282) (xy 103.152021 -272.663551) (xy 103.144919 -272.711566)
			(xy 103.130865 -272.758025) (xy 103.110163 -272.801926) (xy 103.083258 -272.842324) (xy 103.050729 -272.878349)
			(xy 103.013278 -272.909224) (xy 102.971711 -272.934285) (xy 102.949502 -272.944082) (xy 102.940104 -272.948146)
			(xy 102.897178 -272.991072) (xy 102.968806 -273.0627) (xy 103.473504 -273.0627) (xy 103.487136 -273.062263)
			(xy 103.513426 -273.055045) (xy 103.536868 -273.041127) (xy 103.55579 -273.0215) (xy 103.568843 -272.997564)
			(xy 103.575094 -272.971027) (xy 103.574098 -272.943782) (xy 103.565926 -272.917773) (xy 103.551161 -272.894854)
			(xy 103.541322 -272.885408) (xy 103.521008 -272.866443) (xy 103.486402 -272.822964) (xy 103.459553 -272.77431)
			(xy 103.441218 -272.721852) (xy 103.431912 -272.667067) (xy 103.43134 -272.639282) (xy 103.431849 -272.613315)
			(xy 103.439974 -272.56202) (xy 103.456022 -272.512627) (xy 103.4796 -272.466353) (xy 103.510126 -272.424337)
			(xy 103.546849 -272.387614) (xy 103.588865 -272.357088) (xy 103.635139 -272.33351) (xy 103.684532 -272.317462)
			(xy 103.735827 -272.309337) (xy 103.787761 -272.309337) (xy 103.839056 -272.317462) (xy 103.888449 -272.33351)
			(xy 103.934723 -272.357088) (xy 103.976739 -272.387614) (xy 104.013462 -272.424337) (xy 104.043988 -272.466353)
			(xy 104.067566 -272.512627) (xy 104.083614 -272.56202) (xy 104.091739 -272.613315) (xy 104.092248 -272.639282)
			(xy 104.091678 -272.667068) (xy 104.082382 -272.721857) (xy 104.06405 -272.774318) (xy 104.037199 -272.822972)
			(xy 104.002585 -272.866447) (xy 103.982266 -272.885408) (xy 103.972403 -272.894833) (xy 103.957635 -272.917761)
			(xy 103.949462 -272.943779) (xy 103.948466 -272.971032) (xy 103.954719 -272.997577) (xy 103.967775 -273.021521)
			(xy 103.986702 -273.041155) (xy 104.01015 -273.05508) (xy 104.036448 -273.062302) (xy 104.050084 -273.0627)
			(xy 104.413304 -273.0627) (xy 104.426936 -273.062263) (xy 104.453226 -273.055045) (xy 104.476668 -273.041127)
			(xy 104.49559 -273.0215) (xy 104.508643 -272.997564) (xy 104.514894 -272.971027) (xy 104.513898 -272.943782)
			(xy 104.505726 -272.917773) (xy 104.490961 -272.894854) (xy 104.481122 -272.885408) (xy 104.460808 -272.866443)
			(xy 104.426202 -272.822964) (xy 104.399353 -272.77431) (xy 104.381018 -272.721852) (xy 104.371712 -272.667067)
			(xy 104.37114 -272.639282) (xy 104.371649 -272.613315) (xy 104.379774 -272.56202) (xy 104.395822 -272.512627)
			(xy 104.4194 -272.466353) (xy 104.449926 -272.424337) (xy 104.486649 -272.387614) (xy 104.528665 -272.357088)
			(xy 104.574939 -272.33351) (xy 104.624332 -272.317462) (xy 104.675627 -272.309337) (xy 104.727561 -272.309337)
			(xy 104.778856 -272.317462) (xy 104.828249 -272.33351) (xy 104.874523 -272.357088) (xy 104.916539 -272.387614)
			(xy 104.953262 -272.424337) (xy 104.983788 -272.466353) (xy 105.007366 -272.512627) (xy 105.023414 -272.56202)
			(xy 105.031539 -272.613315) (xy 105.032048 -272.639282) (xy 105.031478 -272.667068) (xy 105.022182 -272.721857)
			(xy 105.00385 -272.774318) (xy 104.976999 -272.822972) (xy 104.942385 -272.866447) (xy 104.922066 -272.885408)
			(xy 104.912203 -272.894833) (xy 104.897435 -272.917761) (xy 104.889262 -272.943779) (xy 104.888266 -272.971032)
			(xy 104.894519 -272.997577) (xy 104.907575 -273.021521) (xy 104.926502 -273.041155) (xy 104.94995 -273.05508)
			(xy 104.976248 -273.062302) (xy 104.989884 -273.0627) (xy 105.353104 -273.0627) (xy 105.366736 -273.062263)
			(xy 105.393026 -273.055045) (xy 105.416468 -273.041127) (xy 105.43539 -273.0215) (xy 105.448443 -272.997564)
			(xy 105.454694 -272.971027) (xy 105.453698 -272.943782) (xy 105.445526 -272.917773) (xy 105.430761 -272.894854)
			(xy 105.420922 -272.885408) (xy 105.400608 -272.866443) (xy 105.366002 -272.822964) (xy 105.339153 -272.77431)
			(xy 105.320818 -272.721852) (xy 105.311512 -272.667067) (xy 105.31094 -272.639282) (xy 105.311449 -272.613315)
			(xy 105.319574 -272.56202) (xy 105.335622 -272.512627) (xy 105.3592 -272.466353) (xy 105.389726 -272.424337)
			(xy 105.426449 -272.387614) (xy 105.468465 -272.357088) (xy 105.514739 -272.33351) (xy 105.564132 -272.317462)
			(xy 105.615427 -272.309337) (xy 105.667361 -272.309337) (xy 105.718656 -272.317462) (xy 105.768049 -272.33351)
			(xy 105.814323 -272.357088) (xy 105.856339 -272.387614) (xy 105.893062 -272.424337) (xy 105.923588 -272.466353)
			(xy 105.947166 -272.512627) (xy 105.963214 -272.56202) (xy 105.971339 -272.613315) (xy 105.971848 -272.639282)
			(xy 105.971278 -272.667068) (xy 105.961982 -272.721857) (xy 105.94365 -272.774318) (xy 105.916799 -272.822972)
			(xy 105.882185 -272.866447) (xy 105.861866 -272.885408) (xy 105.852003 -272.894833) (xy 105.837235 -272.917761)
			(xy 105.829062 -272.943779) (xy 105.828066 -272.971032) (xy 105.834319 -272.997577) (xy 105.847375 -273.021521)
			(xy 105.866302 -273.041155) (xy 105.88975 -273.05508) (xy 105.916048 -273.062302) (xy 105.929684 -273.0627)
			(xy 106.292904 -273.0627) (xy 106.306536 -273.062263) (xy 106.332826 -273.055045) (xy 106.356268 -273.041127)
			(xy 106.37519 -273.0215) (xy 106.388243 -272.997564) (xy 106.394494 -272.971027) (xy 106.393498 -272.943782)
			(xy 106.385326 -272.917773) (xy 106.370561 -272.894854) (xy 106.360722 -272.885408) (xy 106.340408 -272.866443)
			(xy 106.305802 -272.822964) (xy 106.278953 -272.77431) (xy 106.260618 -272.721852) (xy 106.251312 -272.667067)
			(xy 106.25074 -272.639282) (xy 106.251249 -272.613315) (xy 106.259374 -272.56202) (xy 106.275422 -272.512627)
			(xy 106.299 -272.466353) (xy 106.329526 -272.424337) (xy 106.366249 -272.387614) (xy 106.408265 -272.357088)
			(xy 106.454539 -272.33351) (xy 106.503932 -272.317462) (xy 106.555227 -272.309337) (xy 106.607161 -272.309337)
			(xy 106.658456 -272.317462) (xy 106.707849 -272.33351) (xy 106.754123 -272.357088) (xy 106.796139 -272.387614)
			(xy 106.832862 -272.424337) (xy 106.863388 -272.466353) (xy 106.886966 -272.512627) (xy 106.903014 -272.56202)
			(xy 106.911139 -272.613315) (xy 106.911648 -272.639282) (xy 106.911078 -272.667068) (xy 106.901782 -272.721857)
			(xy 106.88345 -272.774318) (xy 106.856599 -272.822972) (xy 106.821985 -272.866447) (xy 106.801666 -272.885408)
			(xy 106.791803 -272.894833) (xy 106.777035 -272.917761) (xy 106.768862 -272.943779) (xy 106.767866 -272.971032)
			(xy 106.774119 -272.997577) (xy 106.787175 -273.021521) (xy 106.806102 -273.041155) (xy 106.82955 -273.05508)
			(xy 106.855848 -273.062302) (xy 106.869484 -273.0627) (xy 107.232704 -273.0627) (xy 107.246336 -273.062263)
			(xy 107.272626 -273.055045) (xy 107.296068 -273.041127) (xy 107.31499 -273.0215) (xy 107.328043 -272.997564)
			(xy 107.334294 -272.971027) (xy 107.333298 -272.943782) (xy 107.325126 -272.917773) (xy 107.310361 -272.894854)
			(xy 107.300522 -272.885408) (xy 107.280208 -272.866443) (xy 107.245602 -272.822964) (xy 107.218753 -272.77431)
			(xy 107.200418 -272.721852) (xy 107.191112 -272.667067) (xy 107.19054 -272.639282) (xy 107.191049 -272.613315)
			(xy 107.199174 -272.56202) (xy 107.215222 -272.512627) (xy 107.2388 -272.466353) (xy 107.269326 -272.424337)
			(xy 107.306049 -272.387614) (xy 107.348065 -272.357088) (xy 107.394339 -272.33351) (xy 107.443732 -272.317462)
			(xy 107.495027 -272.309337) (xy 107.546961 -272.309337) (xy 107.598256 -272.317462) (xy 107.647649 -272.33351)
			(xy 107.693923 -272.357088) (xy 107.735939 -272.387614) (xy 107.772662 -272.424337) (xy 107.803188 -272.466353)
			(xy 107.826766 -272.512627) (xy 107.842814 -272.56202) (xy 107.850939 -272.613315) (xy 107.851448 -272.639282)
			(xy 107.850878 -272.667068) (xy 107.841582 -272.721857) (xy 107.82325 -272.774318) (xy 107.796399 -272.822972)
			(xy 107.761785 -272.866447) (xy 107.741466 -272.885408) (xy 107.731603 -272.894833) (xy 107.716835 -272.917761)
			(xy 107.708662 -272.943779) (xy 107.707666 -272.971032) (xy 107.713919 -272.997577) (xy 107.726975 -273.021521)
			(xy 107.745902 -273.041155) (xy 107.76935 -273.05508) (xy 107.795648 -273.062302) (xy 107.809284 -273.0627)
			(xy 108.283248 -273.0627) (xy 108.292258 -273.047971) (xy 108.311441 -273.019256) (xy 108.321602 -273.005296)
			(xy 108.327617 -272.99616) (xy 108.332017 -272.974753) (xy 108.327165 -272.953445) (xy 108.313932 -272.936054)
			(xy 108.304584 -272.930366) (xy 108.282364 -272.917925) (xy 108.241705 -272.887265) (xy 108.206237 -272.850726)
			(xy 108.1768 -272.809173) (xy 108.154094 -272.763592) (xy 108.138657 -272.715065) (xy 108.130855 -272.664744)
			(xy 108.13034 -272.639282) (xy 108.130851 -272.613316) (xy 108.138977 -272.562022) (xy 108.155027 -272.512632)
			(xy 108.178606 -272.46636) (xy 108.209132 -272.424346) (xy 108.245855 -272.387625) (xy 108.28787 -272.3571)
			(xy 108.334143 -272.333523) (xy 108.383534 -272.317474) (xy 108.434828 -272.30935) (xy 108.460794 -272.308828)
			(xy 108.487826 -272.309374) (xy 108.541167 -272.318184) (xy 108.592365 -272.335554) (xy 108.640055 -272.361021)
			(xy 108.682968 -272.393907) (xy 108.719958 -272.433335) (xy 108.750043 -272.478256) (xy 108.772419 -272.527472)
			(xy 108.786491 -272.579673) (xy 108.789724 -272.606516) (xy 108.791807 -272.621826) (xy 108.803925 -272.650233)
			(xy 108.82396 -272.673736) (xy 108.85009 -272.6902) (xy 108.879939 -272.698125) (xy 108.895388 -272.697956)
			(xy 108.930694 -272.69694) (xy 108.966 -272.697956) (xy 108.981455 -272.698115) (xy 109.011325 -272.690228)
			(xy 109.037472 -272.673776) (xy 109.057509 -272.650261) (xy 109.069603 -272.621834) (xy 109.071664 -272.606516)
			(xy 109.074877 -272.579665) (xy 109.088918 -272.527445) (xy 109.111277 -272.47821) (xy 109.141356 -272.433273)
			(xy 109.178351 -272.393835) (xy 109.221275 -272.360948) (xy 109.268983 -272.335491) (xy 109.320199 -272.318143)
			(xy 109.373556 -272.309368) (xy 109.400594 -272.308828) (xy 109.426562 -272.309337) (xy 109.477859 -272.31746)
			(xy 109.527253 -272.333508) (xy 109.573529 -272.357085) (xy 109.615548 -272.387611) (xy 109.652273 -272.424334)
			(xy 109.682802 -272.46635) (xy 109.706383 -272.512624) (xy 109.722434 -272.562018) (xy 109.730561 -272.613314)
			(xy 109.731048 -272.639282) (xy 109.730584 -272.664677) (xy 109.730495 -272.665249) (xy 110.010449 -272.665249)
			(xy 110.010449 -272.613315) (xy 110.018574 -272.56202) (xy 110.034622 -272.512627) (xy 110.0582 -272.466353)
			(xy 110.088726 -272.424337) (xy 110.125449 -272.387614) (xy 110.167465 -272.357088) (xy 110.213739 -272.33351)
			(xy 110.263132 -272.317462) (xy 110.314427 -272.309337) (xy 110.366361 -272.309337) (xy 110.417656 -272.317462)
			(xy 110.467049 -272.33351) (xy 110.513323 -272.357088) (xy 110.555339 -272.387614) (xy 110.592062 -272.424337)
			(xy 110.622588 -272.466353) (xy 110.646166 -272.512627) (xy 110.662214 -272.56202) (xy 110.670339 -272.613315)
			(xy 110.670848 -272.639282) (xy 110.670339 -272.665249) (xy 110.662214 -272.716544) (xy 110.646166 -272.765937)
			(xy 110.622588 -272.812211) (xy 110.592062 -272.854227) (xy 110.555339 -272.89095) (xy 110.513323 -272.921476)
			(xy 110.467049 -272.945054) (xy 110.417656 -272.961102) (xy 110.366361 -272.969227) (xy 110.314427 -272.969227)
			(xy 110.263132 -272.961102) (xy 110.213739 -272.945054) (xy 110.167465 -272.921476) (xy 110.125449 -272.89095)
			(xy 110.088726 -272.854227) (xy 110.0582 -272.812211) (xy 110.034622 -272.765937) (xy 110.018574 -272.716544)
			(xy 110.010449 -272.665249) (xy 109.730495 -272.665249) (xy 109.722814 -272.714868) (xy 109.707452 -272.763279)
			(xy 109.684862 -272.808768) (xy 109.670596 -272.829782) (xy 109.662841 -272.841519) (xy 109.65348 -272.868036)
			(xy 109.651717 -272.896101) (xy 109.657687 -272.923581) (xy 109.670935 -272.948385) (xy 109.690454 -272.968628)
			(xy 109.71476 -272.98277) (xy 109.728254 -272.986754) (xy 109.771888 -272.998336) (xy 109.857607 -273.026691)
			(xy 109.941187 -273.060839) (xy 110.022237 -273.10062) (xy 110.061502 -273.122898) (xy 110.106546 -273.149516)
			(xy 110.192723 -273.208865) (xy 110.273937 -273.274845) (xy 110.349677 -273.347041) (xy 110.419471 -273.425001)
			(xy 110.48288 -273.508236) (xy 110.539507 -273.596226) (xy 110.588998 -273.688419) (xy 110.631042 -273.784238)
			(xy 110.665377 -273.883081) (xy 110.691786 -273.984331) (xy 110.710105 -274.087352) (xy 110.720219 -274.191499)
			(xy 110.721648 -274.2438) (xy 110.721648 -274.290028) (xy 110.720231 -274.341844) (xy 110.710297 -274.445032)
			(xy 110.69231 -274.547126) (xy 110.666382 -274.647497) (xy 110.65002 -274.696682) (xy 110.647226 -274.70481)
			(xy 110.647226 -275.106697) (xy 113.299749 -275.106697) (xy 113.299749 -275.054763) (xy 113.307874 -275.003468)
			(xy 113.323922 -274.954075) (xy 113.3475 -274.907801) (xy 113.378026 -274.865785) (xy 113.414749 -274.829062)
			(xy 113.456765 -274.798536) (xy 113.503039 -274.774958) (xy 113.552432 -274.75891) (xy 113.603727 -274.750785)
			(xy 113.655661 -274.750785) (xy 113.706956 -274.75891) (xy 113.756349 -274.774958) (xy 113.802623 -274.798536)
			(xy 113.844639 -274.829062) (xy 113.881362 -274.865785) (xy 113.911888 -274.907801) (xy 113.935466 -274.954075)
			(xy 113.951514 -275.003468) (xy 113.959639 -275.054763) (xy 113.960148 -275.08073) (xy 113.959639 -275.106697)
			(xy 113.951514 -275.157992) (xy 113.935466 -275.207385) (xy 113.911888 -275.253659) (xy 113.881362 -275.295675)
			(xy 113.844639 -275.332398) (xy 113.802623 -275.362924) (xy 113.756349 -275.386502) (xy 113.706956 -275.40255)
			(xy 113.655661 -275.410675) (xy 113.603727 -275.410675) (xy 113.552432 -275.40255) (xy 113.503039 -275.386502)
			(xy 113.456765 -275.362924) (xy 113.414749 -275.332398) (xy 113.378026 -275.295675) (xy 113.3475 -275.253659)
			(xy 113.323922 -275.207385) (xy 113.307874 -275.157992) (xy 113.299749 -275.106697) (xy 110.647226 -275.106697)
			(xy 110.647226 -275.45665) (xy 110.65002 -275.464524) (xy 110.667911 -275.518339) (xy 110.69551 -275.628346)
			(xy 110.705138 -275.684234) (xy 110.744346 -275.716807) (xy 110.818179 -275.787098) (xy 110.886375 -275.86287)
			(xy 110.93091 -275.920767) (xy 113.769903 -275.920767) (xy 113.769903 -275.868833) (xy 113.778028 -275.817538)
			(xy 113.794076 -275.768145) (xy 113.817654 -275.721871) (xy 113.84818 -275.679855) (xy 113.884903 -275.643132)
			(xy 113.926919 -275.612606) (xy 113.973193 -275.589028) (xy 114.022586 -275.57298) (xy 114.073881 -275.564855)
			(xy 114.125815 -275.564855) (xy 114.17711 -275.57298) (xy 114.226503 -275.589028) (xy 114.272777 -275.612606)
			(xy 114.314793 -275.643132) (xy 114.351516 -275.679855) (xy 114.382042 -275.721871) (xy 114.40562 -275.768145)
			(xy 114.421668 -275.817538) (xy 114.429793 -275.868833) (xy 114.430302 -275.8948) (xy 114.429793 -275.920767)
			(xy 114.421668 -275.972062) (xy 114.40562 -276.021455) (xy 114.382042 -276.067729) (xy 114.351516 -276.109745)
			(xy 114.314793 -276.146468) (xy 114.272777 -276.176994) (xy 114.226503 -276.200572) (xy 114.17711 -276.21662)
			(xy 114.125815 -276.224745) (xy 114.073881 -276.224745) (xy 114.022586 -276.21662) (xy 113.973193 -276.200572)
			(xy 113.926919 -276.176994) (xy 113.884903 -276.146468) (xy 113.84818 -276.109745) (xy 113.817654 -276.067729)
			(xy 113.794076 -276.021455) (xy 113.778028 -275.972062) (xy 113.769903 -275.920767) (xy 110.93091 -275.920767)
			(xy 110.948529 -275.943673) (xy 111.004271 -276.029024) (xy 111.05327 -276.118418) (xy 111.095234 -276.211322)
			(xy 111.129914 -276.307183) (xy 111.157104 -276.405432) (xy 111.176641 -276.505484) (xy 111.188409 -276.606744)
			(xy 111.19234 -276.70861) (xy 111.191337 -276.734583) (xy 114.239803 -276.734583) (xy 114.239803 -276.682649)
			(xy 114.247928 -276.631354) (xy 114.263976 -276.581961) (xy 114.287554 -276.535687) (xy 114.31808 -276.493671)
			(xy 114.354803 -276.456948) (xy 114.396819 -276.426422) (xy 114.443093 -276.402844) (xy 114.492486 -276.386796)
			(xy 114.543781 -276.378671) (xy 114.595715 -276.378671) (xy 114.64701 -276.386796) (xy 114.696403 -276.402844)
			(xy 114.742677 -276.426422) (xy 114.784693 -276.456948) (xy 114.821416 -276.493671) (xy 114.851942 -276.535687)
			(xy 114.87552 -276.581961) (xy 114.891568 -276.631354) (xy 114.899693 -276.682649) (xy 114.900202 -276.708616)
			(xy 114.899693 -276.734583) (xy 114.891568 -276.785878) (xy 114.87552 -276.835271) (xy 114.851942 -276.881545)
			(xy 114.821416 -276.923561) (xy 114.784693 -276.960284) (xy 114.742677 -276.99081) (xy 114.696403 -277.014388)
			(xy 114.64701 -277.030436) (xy 114.595715 -277.038561) (xy 114.543781 -277.038561) (xy 114.492486 -277.030436)
			(xy 114.443093 -277.014388) (xy 114.396819 -276.99081) (xy 114.354803 -276.960284) (xy 114.31808 -276.923561)
			(xy 114.287554 -276.881545) (xy 114.263976 -276.835271) (xy 114.247928 -276.785878) (xy 114.239803 -276.734583)
			(xy 111.191337 -276.734583) (xy 111.188408 -276.810476) (xy 111.176638 -276.911736) (xy 111.157099 -277.011788)
			(xy 111.129908 -277.110036) (xy 111.095227 -277.205897) (xy 111.053261 -277.2988) (xy 111.004261 -277.388193)
			(xy 110.948517 -277.473544) (xy 110.886362 -277.554345) (xy 110.818164 -277.630116) (xy 110.744331 -277.700406)
			(xy 110.705138 -277.732998) (xy 110.696107 -277.785636) (xy 110.670632 -277.889361) (xy 110.636865 -277.990692)
			(xy 110.595027 -278.088965) (xy 110.545391 -278.183539) (xy 110.488281 -278.273796) (xy 110.424069 -278.359148)
			(xy 110.421122 -278.362469) (xy 114.239803 -278.362469) (xy 114.239803 -278.310535) (xy 114.247928 -278.25924)
			(xy 114.263976 -278.209847) (xy 114.287554 -278.163573) (xy 114.31808 -278.121557) (xy 114.354803 -278.084834)
			(xy 114.396819 -278.054308) (xy 114.443093 -278.03073) (xy 114.492486 -278.014682) (xy 114.543781 -278.006557)
			(xy 114.595715 -278.006557) (xy 114.64701 -278.014682) (xy 114.696403 -278.03073) (xy 114.742677 -278.054308)
			(xy 114.784693 -278.084834) (xy 114.821416 -278.121557) (xy 114.851942 -278.163573) (xy 114.87552 -278.209847)
			(xy 114.891568 -278.25924) (xy 114.899693 -278.310535) (xy 114.900202 -278.336502) (xy 114.899693 -278.362469)
			(xy 114.891568 -278.413764) (xy 114.87552 -278.463157) (xy 114.851942 -278.509431) (xy 114.821416 -278.551447)
			(xy 114.784693 -278.58817) (xy 114.742677 -278.618696) (xy 114.696403 -278.642274) (xy 114.64701 -278.658322)
			(xy 114.595715 -278.666447) (xy 114.543781 -278.666447) (xy 114.492486 -278.658322) (xy 114.443093 -278.642274)
			(xy 114.396819 -278.618696) (xy 114.354803 -278.58817) (xy 114.31808 -278.551447) (xy 114.287554 -278.509431)
			(xy 114.263976 -278.463157) (xy 114.247928 -278.413764) (xy 114.239803 -278.362469) (xy 110.421122 -278.362469)
			(xy 110.353176 -278.439037) (xy 110.276064 -278.512941) (xy 110.234984 -278.547068) (xy 110.225956 -278.599686)
			(xy 110.200491 -278.703373) (xy 110.166741 -278.804667) (xy 110.124927 -278.902907) (xy 110.075321 -278.997452)
			(xy 110.018247 -279.087685) (xy 109.954077 -279.173018) (xy 109.88323 -279.252894) (xy 109.806168 -279.326792)
			(xy 109.765084 -279.360884) (xy 109.75607 -279.413475) (xy 109.730639 -279.517112) (xy 109.69693 -279.618359)
			(xy 109.655162 -279.716556) (xy 109.605608 -279.811063) (xy 109.548591 -279.901264) (xy 109.484482 -279.986571)
			(xy 109.481353 -279.990101) (xy 113.299749 -279.990101) (xy 113.299749 -279.938167) (xy 113.307874 -279.886872)
			(xy 113.323922 -279.837479) (xy 113.3475 -279.791205) (xy 113.378026 -279.749189) (xy 113.414749 -279.712466)
			(xy 113.456765 -279.68194) (xy 113.503039 -279.658362) (xy 113.552432 -279.642314) (xy 113.603727 -279.634189)
			(xy 113.655661 -279.634189) (xy 113.706956 -279.642314) (xy 113.756349 -279.658362) (xy 113.802623 -279.68194)
			(xy 113.844639 -279.712466) (xy 113.881362 -279.749189) (xy 113.911888 -279.791205) (xy 113.935466 -279.837479)
			(xy 113.951514 -279.886872) (xy 113.959639 -279.938167) (xy 113.960148 -279.964134) (xy 113.959639 -279.990101)
			(xy 113.951514 -280.041396) (xy 113.935466 -280.090789) (xy 113.911888 -280.137063) (xy 113.881362 -280.179079)
			(xy 113.844639 -280.215802) (xy 113.802623 -280.246328) (xy 113.756349 -280.269906) (xy 113.706956 -280.285954)
			(xy 113.655661 -280.294079) (xy 113.603727 -280.294079) (xy 113.552432 -280.285954) (xy 113.503039 -280.269906)
			(xy 113.456765 -280.246328) (xy 113.414749 -280.215802) (xy 113.378026 -280.179079) (xy 113.3475 -280.137063)
			(xy 113.323922 -280.090789) (xy 113.307874 -280.041396) (xy 113.299749 -279.990101) (xy 109.481353 -279.990101)
			(xy 109.4137 -280.066428) (xy 109.336705 -280.140314) (xy 109.295692 -280.174446) (xy 109.287106 -280.224663)
			(xy 109.263204 -280.323707) (xy 109.24794 -280.372312) (xy 109.2454 -280.379932) (xy 109.2454 -280.804171)
			(xy 110.010449 -280.804171) (xy 110.010449 -280.752237) (xy 110.018574 -280.700942) (xy 110.034622 -280.651549)
			(xy 110.0582 -280.605275) (xy 110.088726 -280.563259) (xy 110.125449 -280.526536) (xy 110.167465 -280.49601)
			(xy 110.213739 -280.472432) (xy 110.263132 -280.456384) (xy 110.314427 -280.448259) (xy 110.366361 -280.448259)
			(xy 110.417656 -280.456384) (xy 110.467049 -280.472432) (xy 110.513323 -280.49601) (xy 110.555339 -280.526536)
			(xy 110.592062 -280.563259) (xy 110.622588 -280.605275) (xy 110.646166 -280.651549) (xy 110.662214 -280.700942)
			(xy 110.670339 -280.752237) (xy 110.670848 -280.778204) (xy 110.670339 -280.804171) (xy 110.662214 -280.855466)
			(xy 110.646166 -280.904859) (xy 110.622588 -280.951133) (xy 110.592062 -280.993149) (xy 110.555339 -281.029872)
			(xy 110.513323 -281.060398) (xy 110.467049 -281.083976) (xy 110.417656 -281.100024) (xy 110.366361 -281.108149)
			(xy 110.314427 -281.108149) (xy 110.263132 -281.100024) (xy 110.213739 -281.083976) (xy 110.167465 -281.060398)
			(xy 110.125449 -281.029872) (xy 110.088726 -280.993149) (xy 110.0582 -280.951133) (xy 110.034622 -280.904859)
			(xy 110.018574 -280.855466) (xy 110.010449 -280.804171) (xy 109.2454 -280.804171) (xy 109.2454 -281.176476)
			(xy 109.24794 -281.184096) (xy 109.263139 -281.232642) (xy 109.286916 -281.331558) (xy 109.295438 -281.381708)
			(xy 109.336492 -281.415816) (xy 109.413556 -281.489675) (xy 109.484405 -281.569514) (xy 109.520872 -281.617987)
			(xy 113.299749 -281.617987) (xy 113.299749 -281.566053) (xy 113.307874 -281.514758) (xy 113.323922 -281.465365)
			(xy 113.3475 -281.419091) (xy 113.378026 -281.377075) (xy 113.414749 -281.340352) (xy 113.456765 -281.309826)
			(xy 113.503039 -281.286248) (xy 113.552432 -281.2702) (xy 113.603727 -281.262075) (xy 113.655661 -281.262075)
			(xy 113.706956 -281.2702) (xy 113.756349 -281.286248) (xy 113.802623 -281.309826) (xy 113.844639 -281.340352)
			(xy 113.881362 -281.377075) (xy 113.911888 -281.419091) (xy 113.935466 -281.465365) (xy 113.951514 -281.514758)
			(xy 113.959639 -281.566053) (xy 113.960148 -281.59202) (xy 113.959639 -281.617987) (xy 113.951514 -281.669282)
			(xy 113.935466 -281.718675) (xy 113.911888 -281.764949) (xy 113.881362 -281.806965) (xy 113.844639 -281.843688)
			(xy 113.802623 -281.874214) (xy 113.756349 -281.897792) (xy 113.706956 -281.91384) (xy 113.655661 -281.921965)
			(xy 113.603727 -281.921965) (xy 113.552432 -281.91384) (xy 113.503039 -281.897792) (xy 113.456765 -281.874214)
			(xy 113.414749 -281.843688) (xy 113.378026 -281.806965) (xy 113.3475 -281.764949) (xy 113.323922 -281.718675)
			(xy 113.307874 -281.669282) (xy 113.299749 -281.617987) (xy 109.520872 -281.617987) (xy 109.548576 -281.654813)
			(xy 109.605652 -281.745015) (xy 109.655259 -281.83953) (xy 109.697073 -281.937741) (xy 109.730821 -282.039008)
			(xy 109.756284 -282.14267) (xy 109.765338 -282.19527) (xy 109.794059 -282.219043) (xy 109.84908 -282.269368)
			(xy 109.87532 -282.295854) (xy 109.885469 -282.305651) (xy 109.909901 -282.31973) (xy 109.937255 -282.326577)
			(xy 109.965438 -282.325671) (xy 109.992295 -282.317079) (xy 110.015772 -282.301459) (xy 110.034072 -282.280006)
			(xy 110.04042 -282.267406) (xy 110.052145 -282.243202) (xy 110.082254 -282.198644) (xy 110.11919 -282.159558)
			(xy 110.161974 -282.126977) (xy 110.209474 -282.101764) (xy 110.260434 -282.084586) (xy 110.313505 -282.075898)
			(xy 110.340394 -282.075382) (xy 110.366361 -282.075864) (xy 110.417655 -282.083988) (xy 110.467047 -282.100035)
			(xy 110.51332 -282.123612) (xy 110.555336 -282.154137) (xy 110.592059 -282.19086) (xy 110.622585 -282.232874)
			(xy 110.646162 -282.279147) (xy 110.662211 -282.328539) (xy 110.670335 -282.379833) (xy 110.670335 -282.431767)
			(xy 110.662211 -282.483061) (xy 110.646162 -282.532453) (xy 110.622585 -282.578726) (xy 110.592059 -282.62074)
			(xy 110.555336 -282.657463) (xy 110.51332 -282.687988) (xy 110.467047 -282.711565) (xy 110.417655 -282.727612)
			(xy 110.366361 -282.735736) (xy 110.340394 -282.73629) (xy 110.310168 -282.73502) (xy 110.296133 -282.734213)
			(xy 110.26852 -282.739429) (xy 110.243374 -282.751975) (xy 110.222601 -282.770901) (xy 110.207774 -282.794772)
			(xy 110.200015 -282.821782) (xy 110.199913 -282.849883) (xy 110.203234 -282.863544) (xy 110.213036 -282.899639)
			(xy 110.229048 -282.972708) (xy 110.235238 -283.009594) (xy 110.276259 -283.043707) (xy 110.353261 -283.117567)
			(xy 110.424057 -283.197396) (xy 110.460512 -283.245873) (xy 113.299749 -283.245873) (xy 113.299749 -283.193939)
			(xy 113.307874 -283.142644) (xy 113.323922 -283.093251) (xy 113.3475 -283.046977) (xy 113.378026 -283.004961)
			(xy 113.414749 -282.968238) (xy 113.456765 -282.937712) (xy 113.503039 -282.914134) (xy 113.552432 -282.898086)
			(xy 113.603727 -282.889961) (xy 113.655661 -282.889961) (xy 113.706956 -282.898086) (xy 113.756349 -282.914134)
			(xy 113.802623 -282.937712) (xy 113.844639 -282.968238) (xy 113.881362 -283.004961) (xy 113.911888 -283.046977)
			(xy 113.935466 -283.093251) (xy 113.951514 -283.142644) (xy 113.959639 -283.193939) (xy 113.960148 -283.219906)
			(xy 113.959639 -283.245873) (xy 116.119403 -283.245873) (xy 116.119403 -283.193939) (xy 116.127528 -283.142644)
			(xy 116.143576 -283.093251) (xy 116.167154 -283.046977) (xy 116.19768 -283.004961) (xy 116.234403 -282.968238)
			(xy 116.276419 -282.937712) (xy 116.322693 -282.914134) (xy 116.372086 -282.898086) (xy 116.423381 -282.889961)
			(xy 116.475315 -282.889961) (xy 116.52661 -282.898086) (xy 116.576003 -282.914134) (xy 116.622277 -282.937712)
			(xy 116.664293 -282.968238) (xy 116.701016 -283.004961) (xy 116.731542 -283.046977) (xy 116.75512 -283.093251)
			(xy 116.771168 -283.142644) (xy 116.779293 -283.193939) (xy 116.779802 -283.219906) (xy 116.779293 -283.245873)
			(xy 116.771168 -283.297168) (xy 116.75512 -283.346561) (xy 116.731542 -283.392835) (xy 116.701016 -283.434851)
			(xy 116.664293 -283.471574) (xy 116.622277 -283.5021) (xy 116.576003 -283.525678) (xy 116.52661 -283.541726)
			(xy 116.475315 -283.549851) (xy 116.423381 -283.549851) (xy 116.372086 -283.541726) (xy 116.322693 -283.525678)
			(xy 116.276419 -283.5021) (xy 116.234403 -283.471574) (xy 116.19768 -283.434851) (xy 116.167154 -283.392835)
			(xy 116.143576 -283.346561) (xy 116.127528 -283.297168) (xy 116.119403 -283.245873) (xy 113.959639 -283.245873)
			(xy 113.951514 -283.297168) (xy 113.935466 -283.346561) (xy 113.911888 -283.392835) (xy 113.881362 -283.434851)
			(xy 113.844639 -283.471574) (xy 113.802623 -283.5021) (xy 113.756349 -283.525678) (xy 113.706956 -283.541726)
			(xy 113.655661 -283.549851) (xy 113.603727 -283.549851) (xy 113.552432 -283.541726) (xy 113.503039 -283.525678)
			(xy 113.456765 -283.5021) (xy 113.414749 -283.471574) (xy 113.378026 -283.434851) (xy 113.3475 -283.392835)
			(xy 113.323922 -283.346561) (xy 113.307874 -283.297168) (xy 113.299749 -283.245873) (xy 110.460512 -283.245873)
			(xy 110.488185 -283.282673) (xy 110.545227 -283.372844) (xy 110.594812 -283.467321) (xy 110.636618 -283.565489)
			(xy 110.670371 -283.666709) (xy 110.695853 -283.77032) (xy 110.704884 -283.822902) (xy 110.745959 -283.857035)
			(xy 110.823063 -283.930945) (xy 110.893949 -284.010837) (xy 110.958155 -284.09619) (xy 111.015263 -284.186447)
			(xy 111.0649 -284.281019) (xy 111.106741 -284.379289) (xy 111.140515 -284.480615) (xy 111.165999 -284.584337)
			(xy 111.175038 -284.636972) (xy 111.21669 -284.671591) (xy 111.294796 -284.746636) (xy 111.366483 -284.827835)
			(xy 111.39932 -284.870906) (xy 111.401269 -284.873505) (xy 113.299749 -284.873505) (xy 113.299749 -284.821571)
			(xy 113.307874 -284.770276) (xy 113.323922 -284.720883) (xy 113.3475 -284.674609) (xy 113.378026 -284.632593)
			(xy 113.414749 -284.59587) (xy 113.456765 -284.565344) (xy 113.503039 -284.541766) (xy 113.552432 -284.525718)
			(xy 113.603727 -284.517593) (xy 113.655661 -284.517593) (xy 113.706956 -284.525718) (xy 113.756349 -284.541766)
			(xy 113.802623 -284.565344) (xy 113.844639 -284.59587) (xy 113.881362 -284.632593) (xy 113.911888 -284.674609)
			(xy 113.935466 -284.720883) (xy 113.951514 -284.770276) (xy 113.959639 -284.821571) (xy 113.960148 -284.847538)
			(xy 113.959639 -284.873505) (xy 116.119403 -284.873505) (xy 116.119403 -284.821571) (xy 116.127528 -284.770276)
			(xy 116.143576 -284.720883) (xy 116.167154 -284.674609) (xy 116.19768 -284.632593) (xy 116.234403 -284.59587)
			(xy 116.276419 -284.565344) (xy 116.322693 -284.541766) (xy 116.372086 -284.525718) (xy 116.423381 -284.517593)
			(xy 116.475315 -284.517593) (xy 116.52661 -284.525718) (xy 116.576003 -284.541766) (xy 116.622277 -284.565344)
			(xy 116.664293 -284.59587) (xy 116.701016 -284.632593) (xy 116.731542 -284.674609) (xy 116.75512 -284.720883)
			(xy 116.771168 -284.770276) (xy 116.779293 -284.821571) (xy 116.779802 -284.847538) (xy 116.779293 -284.873505)
			(xy 116.771168 -284.9248) (xy 116.75512 -284.974193) (xy 116.731542 -285.020467) (xy 116.701016 -285.062483)
			(xy 116.664293 -285.099206) (xy 116.622277 -285.129732) (xy 116.576003 -285.15331) (xy 116.52661 -285.169358)
			(xy 116.475315 -285.177483) (xy 116.423381 -285.177483) (xy 116.372086 -285.169358) (xy 116.322693 -285.15331)
			(xy 116.276419 -285.129732) (xy 116.234403 -285.099206) (xy 116.19768 -285.062483) (xy 116.167154 -285.020467)
			(xy 116.143576 -284.974193) (xy 116.127528 -284.9248) (xy 116.119403 -284.873505) (xy 113.959639 -284.873505)
			(xy 113.951514 -284.9248) (xy 113.935466 -284.974193) (xy 113.911888 -285.020467) (xy 113.881362 -285.062483)
			(xy 113.844639 -285.099206) (xy 113.802623 -285.129732) (xy 113.756349 -285.15331) (xy 113.706956 -285.169358)
			(xy 113.655661 -285.177483) (xy 113.603727 -285.177483) (xy 113.552432 -285.169358) (xy 113.503039 -285.15331)
			(xy 113.456765 -285.129732) (xy 113.414749 -285.099206) (xy 113.378026 -285.062483) (xy 113.3475 -285.020467)
			(xy 113.323922 -284.974193) (xy 113.307874 -284.9248) (xy 113.299749 -284.873505) (xy 111.401269 -284.873505)
			(xy 111.401606 -284.873954) (xy 111.714026 -285.186374) (xy 111.714026 -285.510732) (xy 111.72952 -285.525718)
			(xy 111.767258 -285.56298) (xy 111.837308 -285.642617) (xy 111.900748 -285.727615) (xy 111.957169 -285.817425)
			(xy 112.006208 -285.911469) (xy 112.047548 -286.009143) (xy 112.080925 -286.109817) (xy 112.106122 -286.212842)
			(xy 112.115092 -286.265112) (xy 112.156124 -286.299233) (xy 112.233146 -286.373112) (xy 112.303956 -286.452964)
			(xy 112.340367 -286.501391) (xy 113.299749 -286.501391) (xy 113.299749 -286.449457) (xy 113.307874 -286.398162)
			(xy 113.323922 -286.348769) (xy 113.3475 -286.302495) (xy 113.378026 -286.260479) (xy 113.414749 -286.223756)
			(xy 113.456765 -286.19323) (xy 113.503039 -286.169652) (xy 113.552432 -286.153604) (xy 113.603727 -286.145479)
			(xy 113.655661 -286.145479) (xy 113.706956 -286.153604) (xy 113.756349 -286.169652) (xy 113.802623 -286.19323)
			(xy 113.844639 -286.223756) (xy 113.881362 -286.260479) (xy 113.911888 -286.302495) (xy 113.935466 -286.348769)
			(xy 113.951514 -286.398162) (xy 113.959639 -286.449457) (xy 113.960148 -286.475424) (xy 113.959639 -286.501391)
			(xy 116.119403 -286.501391) (xy 116.119403 -286.449457) (xy 116.127528 -286.398162) (xy 116.143576 -286.348769)
			(xy 116.167154 -286.302495) (xy 116.19768 -286.260479) (xy 116.234403 -286.223756) (xy 116.276419 -286.19323)
			(xy 116.322693 -286.169652) (xy 116.372086 -286.153604) (xy 116.423381 -286.145479) (xy 116.475315 -286.145479)
			(xy 116.52661 -286.153604) (xy 116.576003 -286.169652) (xy 116.622277 -286.19323) (xy 116.664293 -286.223756)
			(xy 116.701016 -286.260479) (xy 116.731542 -286.302495) (xy 116.75512 -286.348769) (xy 116.771168 -286.398162)
			(xy 116.779293 -286.449457) (xy 116.779802 -286.475424) (xy 116.779293 -286.501391) (xy 116.771168 -286.552686)
			(xy 116.75512 -286.602079) (xy 116.731542 -286.648353) (xy 116.701016 -286.690369) (xy 116.664293 -286.727092)
			(xy 116.622277 -286.757618) (xy 116.576003 -286.781196) (xy 116.52661 -286.797244) (xy 116.475315 -286.805369)
			(xy 116.423381 -286.805369) (xy 116.372086 -286.797244) (xy 116.322693 -286.781196) (xy 116.276419 -286.757618)
			(xy 116.234403 -286.727092) (xy 116.19768 -286.690369) (xy 116.167154 -286.648353) (xy 116.143576 -286.602079)
			(xy 116.127528 -286.552686) (xy 116.119403 -286.501391) (xy 113.959639 -286.501391) (xy 113.951514 -286.552686)
			(xy 113.935466 -286.602079) (xy 113.911888 -286.648353) (xy 113.881362 -286.690369) (xy 113.844639 -286.727092)
			(xy 113.802623 -286.757618) (xy 113.756349 -286.781196) (xy 113.706956 -286.797244) (xy 113.655661 -286.805369)
			(xy 113.603727 -286.805369) (xy 113.552432 -286.797244) (xy 113.503039 -286.781196) (xy 113.456765 -286.757618)
			(xy 113.414749 -286.727092) (xy 113.378026 -286.690369) (xy 113.3475 -286.648353) (xy 113.323922 -286.602079)
			(xy 113.307874 -286.552686) (xy 113.299749 -286.501391) (xy 112.340367 -286.501391) (xy 112.368093 -286.538268)
			(xy 112.425139 -286.628469) (xy 112.474722 -286.722978) (xy 112.516518 -286.821179) (xy 112.550256 -286.922432)
			(xy 112.575714 -287.026077) (xy 112.584738 -287.078674) (xy 112.624455 -287.111675) (xy 112.699183 -287.182957)
			(xy 112.768115 -287.259855) (xy 112.830833 -287.341902) (xy 112.886952 -287.428597) (xy 112.936129 -287.519408)
			(xy 112.978065 -287.613783) (xy 113.012504 -287.711144) (xy 113.039234 -287.810897) (xy 113.058093 -287.912433)
			(xy 113.068965 -288.015131) (xy 113.070894 -288.066734) (xy 113.071148 -288.087562) (xy 113.071148 -288.129023)
			(xy 113.299749 -288.129023) (xy 113.299749 -288.077089) (xy 113.307874 -288.025794) (xy 113.323922 -287.976401)
			(xy 113.3475 -287.930127) (xy 113.378026 -287.888111) (xy 113.414749 -287.851388) (xy 113.456765 -287.820862)
			(xy 113.503039 -287.797284) (xy 113.552432 -287.781236) (xy 113.603727 -287.773111) (xy 113.655661 -287.773111)
			(xy 113.706956 -287.781236) (xy 113.756349 -287.797284) (xy 113.802623 -287.820862) (xy 113.844639 -287.851388)
			(xy 113.881362 -287.888111) (xy 113.911888 -287.930127) (xy 113.935466 -287.976401) (xy 113.951514 -288.025794)
			(xy 113.959639 -288.077089) (xy 113.960148 -288.103056) (xy 113.959639 -288.129023) (xy 116.119403 -288.129023)
			(xy 116.119403 -288.077089) (xy 116.127528 -288.025794) (xy 116.143576 -287.976401) (xy 116.167154 -287.930127)
			(xy 116.19768 -287.888111) (xy 116.234403 -287.851388) (xy 116.276419 -287.820862) (xy 116.322693 -287.797284)
			(xy 116.372086 -287.781236) (xy 116.423381 -287.773111) (xy 116.475315 -287.773111) (xy 116.52661 -287.781236)
			(xy 116.576003 -287.797284) (xy 116.622277 -287.820862) (xy 116.664293 -287.851388) (xy 116.701016 -287.888111)
			(xy 116.731542 -287.930127) (xy 116.75512 -287.976401) (xy 116.771168 -288.025794) (xy 116.779293 -288.077089)
			(xy 116.779802 -288.103056) (xy 116.779293 -288.129023) (xy 116.771168 -288.180318) (xy 116.75512 -288.229711)
			(xy 116.731542 -288.275985) (xy 116.701016 -288.318001) (xy 116.664293 -288.354724) (xy 116.622277 -288.38525)
			(xy 116.576003 -288.408828) (xy 116.52661 -288.424876) (xy 116.475315 -288.433001) (xy 116.423381 -288.433001)
			(xy 116.372086 -288.424876) (xy 116.322693 -288.408828) (xy 116.276419 -288.38525) (xy 116.234403 -288.354724)
			(xy 116.19768 -288.318001) (xy 116.167154 -288.275985) (xy 116.143576 -288.229711) (xy 116.127528 -288.180318)
			(xy 116.119403 -288.129023) (xy 113.959639 -288.129023) (xy 113.951514 -288.180318) (xy 113.935466 -288.229711)
			(xy 113.911888 -288.275985) (xy 113.881362 -288.318001) (xy 113.844639 -288.354724) (xy 113.802623 -288.38525)
			(xy 113.756349 -288.408828) (xy 113.706956 -288.424876) (xy 113.655661 -288.433001) (xy 113.603727 -288.433001)
			(xy 113.552432 -288.424876) (xy 113.503039 -288.408828) (xy 113.456765 -288.38525) (xy 113.414749 -288.354724)
			(xy 113.378026 -288.318001) (xy 113.3475 -288.275985) (xy 113.323922 -288.229711) (xy 113.307874 -288.180318)
			(xy 113.299749 -288.129023) (xy 113.071148 -288.129023) (xy 113.071148 -288.30143) (xy 113.070568 -288.343986)
			(xy 113.061013 -288.428561) (xy 113.042028 -288.511529) (xy 113.028476 -288.551874) (xy 113.010819 -288.600702)
			(xy 112.969021 -288.695759) (xy 112.920067 -288.787337) (xy 112.864246 -288.874898) (xy 112.801884 -288.957928)
			(xy 112.733348 -289.03594) (xy 112.659041 -289.108475) (xy 112.619536 -289.14217) (xy 112.601248 -289.15741)
			(xy 112.601248 -289.403028) (xy 112.600779 -289.440114) (xy 112.593485 -289.513927) (xy 112.579 -289.586671)
			(xy 112.557463 -289.657647) (xy 112.52908 -289.726174) (xy 112.494125 -289.791593) (xy 112.452933 -289.853276)
			(xy 112.4059 -289.910629) (xy 112.380014 -289.93719) (xy 112.002316 -290.314888) (xy 111.975742 -290.340815)
			(xy 111.918345 -290.387914) (xy 111.856609 -290.429162) (xy 111.791127 -290.464161) (xy 111.722531 -290.492574)
			(xy 111.651481 -290.514128) (xy 111.57866 -290.528615) (xy 111.50477 -290.535896) (xy 111.467646 -290.536376)
			(xy 111.358426 -290.536376) (xy 110.137448 -291.757354) (xy 110.137448 -292.35527) (xy 110.137146 -292.38267)
			(xy 110.133203 -292.43733) (xy 110.129574 -292.46449) (xy 110.1281 -292.477982) (xy 110.131519 -292.504898)
			(xy 110.141913 -292.529959) (xy 110.158546 -292.551394) (xy 110.180241 -292.567686) (xy 110.205464 -292.577683)
			(xy 110.23243 -292.580676) (xy 110.245906 -292.579044) (xy 110.260606 -292.576889) (xy 110.290231 -292.574601)
			(xy 110.305088 -292.574472) (xy 110.333131 -292.574947) (xy 110.388617 -292.583123) (xy 110.442305 -292.599344)
			(xy 110.493035 -292.623261) (xy 110.539711 -292.654355) (xy 110.560866 -292.67277) (xy 110.572308 -292.682415)
			(xy 110.599351 -292.695195) (xy 110.628938 -292.699581) (xy 110.658525 -292.695195) (xy 110.685568 -292.682415)
			(xy 110.69701 -292.67277) (xy 110.718144 -292.654373) (xy 110.764789 -292.62333) (xy 110.815469 -292.599435)
			(xy 110.869096 -292.583201) (xy 110.924519 -292.574976) (xy 110.952534 -292.574472) (xy 110.952788 -292.574472)
			(xy 110.980043 -292.574934) (xy 111.033998 -292.58269) (xy 111.0863 -292.598046) (xy 111.135884 -292.620689)
			(xy 111.181741 -292.650158) (xy 111.222938 -292.685854) (xy 111.258635 -292.727049) (xy 111.288105 -292.772905)
			(xy 111.31075 -292.822489) (xy 111.326107 -292.87479) (xy 111.333865 -292.928745) (xy 111.333865 -292.983252)
			(xy 115.746758 -292.983252) (xy 115.746758 -292.928748) (xy 115.754514 -292.874799) (xy 115.769869 -292.822503)
			(xy 115.792511 -292.772924) (xy 115.821977 -292.727072) (xy 115.857669 -292.68588) (xy 115.898859 -292.650187)
			(xy 115.94471 -292.620718) (xy 115.994288 -292.598075) (xy 116.046583 -292.582718) (xy 116.100532 -292.574959)
			(xy 116.127784 -292.574472) (xy 116.155155 -292.57493) (xy 116.209335 -292.582747) (xy 116.261839 -292.598237)
			(xy 116.311586 -292.621081) (xy 116.357551 -292.650809) (xy 116.378482 -292.668452) (xy 116.38981 -292.677688)
			(xy 116.416367 -292.689864) (xy 116.445284 -292.694037) (xy 116.474201 -292.689864) (xy 116.500758 -292.677688)
			(xy 116.512086 -292.668452) (xy 116.533019 -292.650811) (xy 116.578987 -292.621087) (xy 116.628733 -292.598241)
			(xy 116.681235 -292.582745) (xy 116.735413 -292.574916) (xy 116.790155 -292.574916) (xy 116.844333 -292.582745)
			(xy 116.896835 -292.598241) (xy 116.946581 -292.621087) (xy 116.992549 -292.650811) (xy 117.013482 -292.668452)
			(xy 117.02481 -292.677688) (xy 117.051367 -292.689864) (xy 117.080284 -292.694037) (xy 117.109201 -292.689864)
			(xy 117.135758 -292.677688) (xy 117.147086 -292.668452) (xy 117.168019 -292.650814) (xy 117.213991 -292.6211)
			(xy 117.263738 -292.598263) (xy 117.316239 -292.582772) (xy 117.370415 -292.574945) (xy 117.397784 -292.574472)
			(xy 117.425036 -292.574974) (xy 117.478986 -292.582729) (xy 117.531283 -292.598083) (xy 117.580863 -292.620723)
			(xy 117.626715 -292.650189) (xy 117.667908 -292.685881) (xy 117.703601 -292.727072) (xy 117.733069 -292.772923)
			(xy 117.755712 -292.822502) (xy 117.771068 -292.874798) (xy 117.778825 -292.928748) (xy 117.778825 -292.983252)
			(xy 117.771068 -293.037202) (xy 117.755712 -293.089498) (xy 117.733069 -293.139077) (xy 117.703601 -293.184928)
			(xy 117.667908 -293.226119) (xy 117.626715 -293.261811) (xy 117.580863 -293.291277) (xy 117.531283 -293.313917)
			(xy 117.478986 -293.329271) (xy 117.425036 -293.337026) (xy 117.397784 -293.337488) (xy 117.370413 -293.337034)
			(xy 117.316234 -293.329214) (xy 117.26373 -293.313722) (xy 117.213984 -293.290878) (xy 117.168017 -293.26115)
			(xy 117.147086 -293.243508) (xy 117.135758 -293.234272) (xy 117.109201 -293.222096) (xy 117.080284 -293.217923)
			(xy 117.051367 -293.222096) (xy 117.02481 -293.234272) (xy 117.013482 -293.243508) (xy 116.992549 -293.261149)
			(xy 116.946581 -293.290873) (xy 116.896835 -293.313719) (xy 116.844333 -293.329215) (xy 116.790155 -293.337044)
			(xy 116.735413 -293.337044) (xy 116.681235 -293.329215) (xy 116.628733 -293.313719) (xy 116.578987 -293.290873)
			(xy 116.533019 -293.261149) (xy 116.512086 -293.243508) (xy 116.500758 -293.234272) (xy 116.474201 -293.222096)
			(xy 116.445284 -293.217923) (xy 116.416367 -293.222096) (xy 116.38981 -293.234272) (xy 116.378482 -293.243508)
			(xy 116.357531 -293.261123) (xy 116.311563 -293.290838) (xy 116.26182 -293.313679) (xy 116.209324 -293.329176)
			(xy 116.155152 -293.33701) (xy 116.127784 -293.337488) (xy 116.100532 -293.337041) (xy 116.046583 -293.329282)
			(xy 115.994288 -293.313925) (xy 115.94471 -293.291282) (xy 115.898859 -293.261813) (xy 115.857669 -293.22612)
			(xy 115.821977 -293.184928) (xy 115.792511 -293.139076) (xy 115.769869 -293.089497) (xy 115.754514 -293.037201)
			(xy 115.746758 -292.983252) (xy 111.333865 -292.983252) (xy 111.333865 -292.983255) (xy 111.326107 -293.03721)
			(xy 111.31075 -293.089511) (xy 111.288105 -293.139095) (xy 111.258635 -293.184951) (xy 111.222938 -293.226146)
			(xy 111.181741 -293.261842) (xy 111.135884 -293.291311) (xy 111.0863 -293.313954) (xy 111.033998 -293.32931)
			(xy 110.980043 -293.337066) (xy 110.952788 -293.337488) (xy 110.952534 -293.337488) (xy 110.924515 -293.337002)
			(xy 110.869079 -293.328813) (xy 110.81544 -293.312591) (xy 110.764757 -293.288688) (xy 110.718121 -293.257619)
			(xy 110.69701 -293.23919) (xy 110.685568 -293.229545) (xy 110.658525 -293.216765) (xy 110.628938 -293.212379)
			(xy 110.599351 -293.216765) (xy 110.572308 -293.229545) (xy 110.560866 -293.23919) (xy 110.539712 -293.257603)
			(xy 110.493021 -293.288668) (xy 110.442289 -293.31257) (xy 110.388607 -293.328796) (xy 110.333129 -293.336996)
			(xy 110.305088 -293.337488) (xy 110.274772 -293.336924) (xy 110.214899 -293.327364) (xy 110.157297 -293.308439)
			(xy 110.130082 -293.29507) (xy 110.116628 -293.288725) (xy 110.087394 -293.283309) (xy 110.057838 -293.28654)
			(xy 110.030464 -293.298145) (xy 110.007591 -293.317139) (xy 109.991155 -293.341916) (xy 109.98255 -293.370375)
			(xy 109.982 -293.38524) (xy 109.982 -294.60952) (xy 109.982507 -294.624396) (xy 109.991072 -294.652889)
			(xy 110.007497 -294.677696) (xy 110.030383 -294.696707) (xy 110.057782 -294.708302) (xy 110.087362 -294.711496)
			(xy 110.116605 -294.706015) (xy 110.130082 -294.69969) (xy 110.157297 -294.686322) (xy 110.214903 -294.667413)
			(xy 110.274773 -294.657838) (xy 110.305088 -294.657272) (xy 110.333131 -294.657747) (xy 110.388617 -294.665923)
			(xy 110.442305 -294.682144) (xy 110.493035 -294.706061) (xy 110.539711 -294.737155) (xy 110.560866 -294.75557)
			(xy 110.572308 -294.765215) (xy 110.599351 -294.777995) (xy 110.628938 -294.782381) (xy 110.658525 -294.777995)
			(xy 110.685568 -294.765215) (xy 110.69701 -294.75557) (xy 110.718144 -294.737173) (xy 110.764789 -294.70613)
			(xy 110.815469 -294.682235) (xy 110.869096 -294.666001) (xy 110.924519 -294.657776) (xy 110.952534 -294.657272)
			(xy 110.952788 -294.657272) (xy 110.980043 -294.657734) (xy 111.033998 -294.66549) (xy 111.0863 -294.680846)
			(xy 111.135884 -294.703489) (xy 111.181741 -294.732958) (xy 111.222938 -294.768654) (xy 111.258635 -294.809849)
			(xy 111.288105 -294.855705) (xy 111.31075 -294.905289) (xy 111.326107 -294.95759) (xy 111.333865 -295.011545)
			(xy 111.333865 -295.066052) (xy 115.746758 -295.066052) (xy 115.746758 -295.011548) (xy 115.754514 -294.957599)
			(xy 115.769869 -294.905303) (xy 115.792511 -294.855724) (xy 115.821977 -294.809872) (xy 115.857669 -294.76868)
			(xy 115.898859 -294.732987) (xy 115.94471 -294.703518) (xy 115.994288 -294.680875) (xy 116.046583 -294.665518)
			(xy 116.100532 -294.657759) (xy 116.127784 -294.657272) (xy 116.155155 -294.65773) (xy 116.209335 -294.665547)
			(xy 116.261839 -294.681037) (xy 116.311586 -294.703881) (xy 116.357551 -294.733609) (xy 116.378482 -294.751252)
			(xy 116.38981 -294.760488) (xy 116.416367 -294.772664) (xy 116.445284 -294.776837) (xy 116.474201 -294.772664)
			(xy 116.500758 -294.760488) (xy 116.512086 -294.751252) (xy 116.533019 -294.733611) (xy 116.578987 -294.703887)
			(xy 116.628733 -294.681041) (xy 116.681235 -294.665545) (xy 116.735413 -294.657716) (xy 116.790155 -294.657716)
			(xy 116.844333 -294.665545) (xy 116.896835 -294.681041) (xy 116.946581 -294.703887) (xy 116.992549 -294.733611)
			(xy 117.013482 -294.751252) (xy 117.02481 -294.760488) (xy 117.051367 -294.772664) (xy 117.080284 -294.776837)
			(xy 117.109201 -294.772664) (xy 117.135758 -294.760488) (xy 117.147086 -294.751252) (xy 117.168019 -294.733614)
			(xy 117.213991 -294.7039) (xy 117.263738 -294.681063) (xy 117.316239 -294.665572) (xy 117.370415 -294.657745)
			(xy 117.397784 -294.657272) (xy 117.425036 -294.657774) (xy 117.478986 -294.665529) (xy 117.531283 -294.680883)
			(xy 117.580863 -294.703523) (xy 117.626715 -294.732989) (xy 117.667908 -294.768681) (xy 117.703601 -294.809872)
			(xy 117.733069 -294.855723) (xy 117.755712 -294.905302) (xy 117.771068 -294.957598) (xy 117.778825 -295.011548)
			(xy 117.778825 -295.066052) (xy 117.771068 -295.120002) (xy 117.755712 -295.172298) (xy 117.733069 -295.221877)
			(xy 117.703601 -295.267728) (xy 117.667908 -295.308919) (xy 117.626715 -295.344611) (xy 117.580863 -295.374077)
			(xy 117.531283 -295.396717) (xy 117.478986 -295.412071) (xy 117.425036 -295.419826) (xy 117.397784 -295.420288)
			(xy 117.370413 -295.419834) (xy 117.316234 -295.412014) (xy 117.26373 -295.396522) (xy 117.213984 -295.373678)
			(xy 117.168017 -295.34395) (xy 117.147086 -295.326308) (xy 117.135758 -295.317072) (xy 117.109201 -295.304896)
			(xy 117.080284 -295.300723) (xy 117.051367 -295.304896) (xy 117.02481 -295.317072) (xy 117.013482 -295.326308)
			(xy 116.992549 -295.343949) (xy 116.946581 -295.373673) (xy 116.896835 -295.396519) (xy 116.844333 -295.412015)
			(xy 116.790155 -295.419844) (xy 116.735413 -295.419844) (xy 116.681235 -295.412015) (xy 116.628733 -295.396519)
			(xy 116.578987 -295.373673) (xy 116.533019 -295.343949) (xy 116.512086 -295.326308) (xy 116.500758 -295.317072)
			(xy 116.474201 -295.304896) (xy 116.445284 -295.300723) (xy 116.416367 -295.304896) (xy 116.38981 -295.317072)
			(xy 116.378482 -295.326308) (xy 116.357531 -295.343923) (xy 116.311563 -295.373638) (xy 116.26182 -295.396479)
			(xy 116.209324 -295.411976) (xy 116.155152 -295.41981) (xy 116.127784 -295.420288) (xy 116.100532 -295.419841)
			(xy 116.046583 -295.412082) (xy 115.994288 -295.396725) (xy 115.94471 -295.374082) (xy 115.898859 -295.344613)
			(xy 115.857669 -295.30892) (xy 115.821977 -295.267728) (xy 115.792511 -295.221876) (xy 115.769869 -295.172297)
			(xy 115.754514 -295.120001) (xy 115.746758 -295.066052) (xy 111.333865 -295.066052) (xy 111.333865 -295.066055)
			(xy 111.326107 -295.12001) (xy 111.31075 -295.172311) (xy 111.288105 -295.221895) (xy 111.258635 -295.267751)
			(xy 111.222938 -295.308946) (xy 111.181741 -295.344642) (xy 111.135884 -295.374111) (xy 111.0863 -295.396754)
			(xy 111.033998 -295.41211) (xy 110.980043 -295.419866) (xy 110.952788 -295.420288) (xy 110.952534 -295.420288)
			(xy 110.924515 -295.419802) (xy 110.869079 -295.411613) (xy 110.81544 -295.395391) (xy 110.764757 -295.371488)
			(xy 110.718121 -295.340419) (xy 110.69701 -295.32199) (xy 110.685568 -295.312345) (xy 110.658525 -295.299565)
			(xy 110.628938 -295.295179) (xy 110.599351 -295.299565) (xy 110.572308 -295.312345) (xy 110.560866 -295.32199)
			(xy 110.539712 -295.340403) (xy 110.493021 -295.371468) (xy 110.442289 -295.39537) (xy 110.388607 -295.411596)
			(xy 110.333129 -295.419796) (xy 110.305088 -295.420288) (xy 110.274772 -295.419724) (xy 110.214899 -295.410164)
			(xy 110.157297 -295.391239) (xy 110.130082 -295.37787) (xy 110.116628 -295.371525) (xy 110.087394 -295.366109)
			(xy 110.057838 -295.36934) (xy 110.030464 -295.380945) (xy 110.007591 -295.399939) (xy 109.991155 -295.424716)
			(xy 109.98255 -295.453175) (xy 109.982 -295.46804) (xy 109.982 -296.76852) (xy 109.982507 -296.783396)
			(xy 109.991072 -296.811889) (xy 110.007497 -296.836696) (xy 110.030383 -296.855707) (xy 110.057782 -296.867302)
			(xy 110.087362 -296.870496) (xy 110.116605 -296.865015) (xy 110.130082 -296.85869) (xy 110.157297 -296.845322)
			(xy 110.214903 -296.826413) (xy 110.274773 -296.816838) (xy 110.305088 -296.816272) (xy 110.333131 -296.816747)
			(xy 110.388617 -296.824923) (xy 110.442305 -296.841144) (xy 110.493035 -296.865061) (xy 110.539711 -296.896155)
			(xy 110.560866 -296.91457) (xy 110.572308 -296.924215) (xy 110.599351 -296.936995) (xy 110.628938 -296.941381)
			(xy 110.658525 -296.936995) (xy 110.685568 -296.924215) (xy 110.69701 -296.91457) (xy 110.718144 -296.896173)
			(xy 110.764789 -296.86513) (xy 110.815469 -296.841235) (xy 110.869096 -296.825001) (xy 110.924519 -296.816776)
			(xy 110.952534 -296.816272) (xy 110.952788 -296.816272) (xy 110.980043 -296.816734) (xy 111.033998 -296.82449)
			(xy 111.0863 -296.839846) (xy 111.135884 -296.862489) (xy 111.181741 -296.891958) (xy 111.222938 -296.927654)
			(xy 111.258635 -296.968849) (xy 111.288105 -297.014705) (xy 111.31075 -297.064289) (xy 111.326107 -297.11659)
			(xy 111.333865 -297.170545) (xy 111.333865 -297.225052) (xy 115.746758 -297.225052) (xy 115.746758 -297.170548)
			(xy 115.754514 -297.116599) (xy 115.769869 -297.064303) (xy 115.792511 -297.014724) (xy 115.821977 -296.968872)
			(xy 115.857669 -296.92768) (xy 115.898859 -296.891987) (xy 115.94471 -296.862518) (xy 115.994288 -296.839875)
			(xy 116.046583 -296.824518) (xy 116.100532 -296.816759) (xy 116.127784 -296.816272) (xy 116.155155 -296.81673)
			(xy 116.209335 -296.824547) (xy 116.261839 -296.840037) (xy 116.311586 -296.862881) (xy 116.357551 -296.892609)
			(xy 116.378482 -296.910252) (xy 116.38981 -296.919488) (xy 116.416367 -296.931664) (xy 116.445284 -296.935837)
			(xy 116.474201 -296.931664) (xy 116.500758 -296.919488) (xy 116.512086 -296.910252) (xy 116.533019 -296.892611)
			(xy 116.578987 -296.862887) (xy 116.628733 -296.840041) (xy 116.681235 -296.824545) (xy 116.735413 -296.816716)
			(xy 116.790155 -296.816716) (xy 116.844333 -296.824545) (xy 116.896835 -296.840041) (xy 116.946581 -296.862887)
			(xy 116.992549 -296.892611) (xy 117.013482 -296.910252) (xy 117.02481 -296.919488) (xy 117.051367 -296.931664)
			(xy 117.080284 -296.935837) (xy 117.109201 -296.931664) (xy 117.135758 -296.919488) (xy 117.147086 -296.910252)
			(xy 117.168019 -296.892614) (xy 117.213991 -296.8629) (xy 117.263738 -296.840063) (xy 117.316239 -296.824572)
			(xy 117.370415 -296.816745) (xy 117.397784 -296.816272) (xy 117.425036 -296.816774) (xy 117.478986 -296.824529)
			(xy 117.531283 -296.839883) (xy 117.580863 -296.862523) (xy 117.626715 -296.891989) (xy 117.667908 -296.927681)
			(xy 117.703601 -296.968872) (xy 117.733069 -297.014723) (xy 117.755712 -297.064302) (xy 117.771068 -297.116598)
			(xy 117.778825 -297.170548) (xy 117.778825 -297.19778) (xy 122.307602 -297.19778) (xy 122.311673 -297.142158)
			(xy 122.323799 -297.087721) (xy 122.343722 -297.03563) (xy 122.371018 -296.986995) (xy 122.405104 -296.942852)
			(xy 122.445253 -296.904143) (xy 122.490611 -296.871692) (xy 122.540211 -296.846191) (xy 122.592995 -296.828184)
			(xy 122.647838 -296.818054) (xy 122.703572 -296.816017) (xy 122.759009 -296.822117) (xy 122.812966 -296.836223)
			(xy 122.864295 -296.858035) (xy 122.911901 -296.887089) (xy 122.954769 -296.922764) (xy 122.991986 -296.964301)
			(xy 123.022759 -297.010814) (xy 123.046431 -297.061311) (xy 123.062499 -297.114718) (xy 123.070619 -297.169894)
			(xy 123.071128 -297.19778) (xy 123.070619 -297.225666) (xy 123.062499 -297.280842) (xy 123.046431 -297.334249)
			(xy 123.022759 -297.384746) (xy 122.991986 -297.431259) (xy 122.954769 -297.472796) (xy 122.911901 -297.508471)
			(xy 122.864295 -297.537525) (xy 122.812966 -297.559337) (xy 122.759009 -297.573443) (xy 122.703572 -297.579543)
			(xy 122.647838 -297.577506) (xy 122.592995 -297.567376) (xy 122.540211 -297.549369) (xy 122.490611 -297.523868)
			(xy 122.445253 -297.491417) (xy 122.405104 -297.452708) (xy 122.371018 -297.408565) (xy 122.343722 -297.35993)
			(xy 122.323799 -297.307839) (xy 122.311673 -297.253402) (xy 122.307602 -297.19778) (xy 117.778825 -297.19778)
			(xy 117.778825 -297.225052) (xy 117.771068 -297.279002) (xy 117.755712 -297.331298) (xy 117.733069 -297.380877)
			(xy 117.703601 -297.426728) (xy 117.667908 -297.467919) (xy 117.626715 -297.503611) (xy 117.580863 -297.533077)
			(xy 117.531283 -297.555717) (xy 117.478986 -297.571071) (xy 117.425036 -297.578826) (xy 117.397784 -297.579288)
			(xy 117.370413 -297.578834) (xy 117.316234 -297.571014) (xy 117.26373 -297.555522) (xy 117.213984 -297.532678)
			(xy 117.168017 -297.50295) (xy 117.147086 -297.485308) (xy 117.135758 -297.476072) (xy 117.109201 -297.463896)
			(xy 117.080284 -297.459723) (xy 117.051367 -297.463896) (xy 117.02481 -297.476072) (xy 117.013482 -297.485308)
			(xy 116.992549 -297.502949) (xy 116.946581 -297.532673) (xy 116.896835 -297.555519) (xy 116.844333 -297.571015)
			(xy 116.790155 -297.578844) (xy 116.735413 -297.578844) (xy 116.681235 -297.571015) (xy 116.628733 -297.555519)
			(xy 116.578987 -297.532673) (xy 116.533019 -297.502949) (xy 116.512086 -297.485308) (xy 116.500758 -297.476072)
			(xy 116.474201 -297.463896) (xy 116.445284 -297.459723) (xy 116.416367 -297.463896) (xy 116.38981 -297.476072)
			(xy 116.378482 -297.485308) (xy 116.357531 -297.502923) (xy 116.311563 -297.532638) (xy 116.26182 -297.555479)
			(xy 116.209324 -297.570976) (xy 116.155152 -297.57881) (xy 116.127784 -297.579288) (xy 116.100532 -297.578841)
			(xy 116.046583 -297.571082) (xy 115.994288 -297.555725) (xy 115.94471 -297.533082) (xy 115.898859 -297.503613)
			(xy 115.857669 -297.46792) (xy 115.821977 -297.426728) (xy 115.792511 -297.380876) (xy 115.769869 -297.331297)
			(xy 115.754514 -297.279001) (xy 115.746758 -297.225052) (xy 111.333865 -297.225052) (xy 111.333865 -297.225055)
			(xy 111.326107 -297.27901) (xy 111.31075 -297.331311) (xy 111.288105 -297.380895) (xy 111.258635 -297.426751)
			(xy 111.222938 -297.467946) (xy 111.181741 -297.503642) (xy 111.135884 -297.533111) (xy 111.0863 -297.555754)
			(xy 111.033998 -297.57111) (xy 110.980043 -297.578866) (xy 110.952788 -297.579288) (xy 110.952534 -297.579288)
			(xy 110.924515 -297.578802) (xy 110.869079 -297.570613) (xy 110.81544 -297.554391) (xy 110.764757 -297.530488)
			(xy 110.718121 -297.499419) (xy 110.69701 -297.48099) (xy 110.685568 -297.471345) (xy 110.658525 -297.458565)
			(xy 110.628938 -297.454179) (xy 110.599351 -297.458565) (xy 110.572308 -297.471345) (xy 110.560866 -297.48099)
			(xy 110.539733 -297.499387) (xy 110.493088 -297.530431) (xy 110.442408 -297.554325) (xy 110.388781 -297.570557)
			(xy 110.333357 -297.57878) (xy 110.305342 -297.579288) (xy 110.305088 -297.579288) (xy 110.27863 -297.578836)
			(xy 110.22622 -297.571525) (xy 110.175323 -297.557044) (xy 110.126915 -297.53567) (xy 110.104174 -297.522138)
			(xy 110.091069 -297.514686) (xy 110.061928 -297.507024) (xy 110.031819 -297.508195) (xy 110.003361 -297.518096)
			(xy 109.979028 -297.535866) (xy 109.960935 -297.559961) (xy 109.95533 -297.573954) (xy 109.6772 -298.338748)
			(xy 107.9754 -300.675548) (xy 101.7524 -306.974748) (xy 91.020841 -315.709738) (xy 97.636834 -315.709738)
			(xy 97.636834 -315.625042) (xy 97.644885 -315.540728) (xy 97.660914 -315.457562) (xy 97.684775 -315.376295)
			(xy 97.716254 -315.297665) (xy 97.755065 -315.222384) (xy 97.800855 -315.151132) (xy 97.853211 -315.084556)
			(xy 97.911659 -315.023258) (xy 97.975669 -314.967793) (xy 98.044661 -314.918664) (xy 98.118011 -314.876315)
			(xy 98.195054 -314.841131) (xy 98.275093 -314.813429) (xy 98.357402 -314.793461) (xy 98.441237 -314.781408)
			(xy 98.525838 -314.777378) (xy 98.610439 -314.781408) (xy 98.694274 -314.793461) (xy 98.776583 -314.813429)
			(xy 98.856622 -314.841131) (xy 98.933665 -314.876315) (xy 99.007015 -314.918664) (xy 99.076007 -314.967793)
			(xy 99.140017 -315.023258) (xy 99.198465 -315.084556) (xy 99.250821 -315.151132) (xy 99.296611 -315.222384)
			(xy 99.335422 -315.297665) (xy 99.366901 -315.376295) (xy 99.390762 -315.457562) (xy 99.406791 -315.540728)
			(xy 99.414842 -315.625042) (xy 99.415346 -315.66739) (xy 99.610423 -315.66739) (xy 99.614445 -315.58167)
			(xy 99.626476 -315.496702) (xy 99.646412 -315.413235) (xy 99.674075 -315.332001) (xy 99.709224 -315.253715)
			(xy 99.75155 -315.179064) (xy 99.800679 -315.108705) (xy 99.856182 -315.043255) (xy 99.917569 -314.983291)
			(xy 99.984302 -314.929338) (xy 100.055794 -314.881871) (xy 100.131416 -314.841307) (xy 100.210505 -314.808003)
			(xy 100.292365 -314.782251) (xy 100.376276 -314.764278) (xy 100.461502 -314.754242) (xy 100.547294 -314.75223)
			(xy 100.632896 -314.758261) (xy 100.717558 -314.772281) (xy 100.800535 -314.794167) (xy 100.881098 -314.823728)
			(xy 100.958538 -314.860702) (xy 101.032177 -314.904766) (xy 101.101365 -314.955532) (xy 101.165496 -315.012553)
			(xy 101.224005 -315.075329) (xy 101.276378 -315.143309) (xy 101.322156 -315.215894) (xy 101.360936 -315.292446)
			(xy 101.392377 -315.372294) (xy 101.416203 -315.454735) (xy 101.432204 -315.539045) (xy 101.440239 -315.624483)
			(xy 101.440742 -315.66739) (xy 101.440246 -315.709738) (xy 103.834434 -315.709738) (xy 103.834434 -315.625042)
			(xy 103.842485 -315.540728) (xy 103.858514 -315.457562) (xy 103.882375 -315.376295) (xy 103.913854 -315.297665)
			(xy 103.952665 -315.222384) (xy 103.998455 -315.151132) (xy 104.050811 -315.084556) (xy 104.109259 -315.023258)
			(xy 104.173269 -314.967793) (xy 104.242261 -314.918664) (xy 104.315611 -314.876315) (xy 104.392654 -314.841131)
			(xy 104.472693 -314.813429) (xy 104.555002 -314.793461) (xy 104.638837 -314.781408) (xy 104.723438 -314.777378)
			(xy 104.808039 -314.781408) (xy 104.891874 -314.793461) (xy 104.974183 -314.813429) (xy 105.054222 -314.841131)
			(xy 105.131265 -314.876315) (xy 105.204615 -314.918664) (xy 105.273607 -314.967793) (xy 105.337617 -315.023258)
			(xy 105.396065 -315.084556) (xy 105.448421 -315.151132) (xy 105.494211 -315.222384) (xy 105.533022 -315.297665)
			(xy 105.564501 -315.376295) (xy 105.588362 -315.457562) (xy 105.604391 -315.540728) (xy 105.612442 -315.625042)
			(xy 105.612946 -315.66739) (xy 105.808023 -315.66739) (xy 105.812045 -315.58167) (xy 105.824076 -315.496702)
			(xy 105.844012 -315.413235) (xy 105.871675 -315.332001) (xy 105.906824 -315.253715) (xy 105.94915 -315.179064)
			(xy 105.998279 -315.108705) (xy 106.053782 -315.043255) (xy 106.115169 -314.983291) (xy 106.181902 -314.929338)
			(xy 106.253394 -314.881871) (xy 106.329016 -314.841307) (xy 106.408105 -314.808003) (xy 106.489965 -314.782251)
			(xy 106.573876 -314.764278) (xy 106.659102 -314.754242) (xy 106.744894 -314.75223) (xy 106.830496 -314.758261)
			(xy 106.915158 -314.772281) (xy 106.998135 -314.794167) (xy 107.078698 -314.823728) (xy 107.156138 -314.860702)
			(xy 107.229777 -314.904766) (xy 107.298965 -314.955532) (xy 107.363096 -315.012553) (xy 107.421605 -315.075329)
			(xy 107.473978 -315.143309) (xy 107.519756 -315.215894) (xy 107.558536 -315.292446) (xy 107.589977 -315.372294)
			(xy 107.613803 -315.454735) (xy 107.629804 -315.539045) (xy 107.637839 -315.624483) (xy 107.638342 -315.66739)
			(xy 107.637846 -315.709738) (xy 110.012222 -315.709738) (xy 110.012222 -315.625042) (xy 110.020273 -315.540728)
			(xy 110.036302 -315.457562) (xy 110.060163 -315.376295) (xy 110.091642 -315.297665) (xy 110.130453 -315.222384)
			(xy 110.176243 -315.151132) (xy 110.228599 -315.084556) (xy 110.287047 -315.023258) (xy 110.351057 -314.967793)
			(xy 110.420049 -314.918664) (xy 110.493399 -314.876315) (xy 110.570442 -314.841131) (xy 110.650481 -314.813429)
			(xy 110.73279 -314.793461) (xy 110.816625 -314.781408) (xy 110.901226 -314.777378) (xy 110.985827 -314.781408)
			(xy 111.069662 -314.793461) (xy 111.151971 -314.813429) (xy 111.23201 -314.841131) (xy 111.309053 -314.876315)
			(xy 111.382403 -314.918664) (xy 111.451395 -314.967793) (xy 111.515405 -315.023258) (xy 111.573853 -315.084556)
			(xy 111.626209 -315.151132) (xy 111.671999 -315.222384) (xy 111.71081 -315.297665) (xy 111.742289 -315.376295)
			(xy 111.76615 -315.457562) (xy 111.782179 -315.540728) (xy 111.79023 -315.625042) (xy 111.790734 -315.66739)
			(xy 111.985811 -315.66739) (xy 111.989833 -315.58167) (xy 112.001864 -315.496702) (xy 112.0218 -315.413235)
			(xy 112.049463 -315.332001) (xy 112.084612 -315.253715) (xy 112.126938 -315.179064) (xy 112.176067 -315.108705)
			(xy 112.23157 -315.043255) (xy 112.292957 -314.983291) (xy 112.35969 -314.929338) (xy 112.431182 -314.881871)
			(xy 112.506804 -314.841307) (xy 112.585893 -314.808003) (xy 112.667753 -314.782251) (xy 112.751664 -314.764278)
			(xy 112.83689 -314.754242) (xy 112.922682 -314.75223) (xy 113.008284 -314.758261) (xy 113.092946 -314.772281)
			(xy 113.175923 -314.794167) (xy 113.256486 -314.823728) (xy 113.333926 -314.860702) (xy 113.407565 -314.904766)
			(xy 113.476753 -314.955532) (xy 113.540884 -315.012553) (xy 113.599393 -315.075329) (xy 113.651766 -315.143309)
			(xy 113.697544 -315.215894) (xy 113.736324 -315.292446) (xy 113.767765 -315.372294) (xy 113.791591 -315.454735)
			(xy 113.807592 -315.539045) (xy 113.815627 -315.624483) (xy 113.81613 -315.66739) (xy 113.815634 -315.709738)
			(xy 116.209822 -315.709738) (xy 116.209822 -315.625042) (xy 116.217873 -315.540728) (xy 116.233902 -315.457562)
			(xy 116.257763 -315.376295) (xy 116.289242 -315.297665) (xy 116.328053 -315.222384) (xy 116.373843 -315.151132)
			(xy 116.426199 -315.084556) (xy 116.484647 -315.023258) (xy 116.548657 -314.967793) (xy 116.617649 -314.918664)
			(xy 116.690999 -314.876315) (xy 116.768042 -314.841131) (xy 116.848081 -314.813429) (xy 116.93039 -314.793461)
			(xy 117.014225 -314.781408) (xy 117.098826 -314.777378) (xy 117.183427 -314.781408) (xy 117.267262 -314.793461)
			(xy 117.349571 -314.813429) (xy 117.42961 -314.841131) (xy 117.506653 -314.876315) (xy 117.580003 -314.918664)
			(xy 117.648995 -314.967793) (xy 117.713005 -315.023258) (xy 117.771453 -315.084556) (xy 117.823809 -315.151132)
			(xy 117.869599 -315.222384) (xy 117.90841 -315.297665) (xy 117.939889 -315.376295) (xy 117.96375 -315.457562)
			(xy 117.979779 -315.540728) (xy 117.98783 -315.625042) (xy 117.988334 -315.66739) (xy 118.183411 -315.66739)
			(xy 118.187433 -315.58167) (xy 118.199464 -315.496702) (xy 118.2194 -315.413235) (xy 118.247063 -315.332001)
			(xy 118.282212 -315.253715) (xy 118.324538 -315.179064) (xy 118.373667 -315.108705) (xy 118.42917 -315.043255)
			(xy 118.490557 -314.983291) (xy 118.55729 -314.929338) (xy 118.628782 -314.881871) (xy 118.704404 -314.841307)
			(xy 118.783493 -314.808003) (xy 118.865353 -314.782251) (xy 118.949264 -314.764278) (xy 119.03449 -314.754242)
			(xy 119.120282 -314.75223) (xy 119.205884 -314.758261) (xy 119.290546 -314.772281) (xy 119.373523 -314.794167)
			(xy 119.454086 -314.823728) (xy 119.531526 -314.860702) (xy 119.605165 -314.904766) (xy 119.674353 -314.955532)
			(xy 119.738484 -315.012553) (xy 119.796993 -315.075329) (xy 119.849366 -315.143309) (xy 119.895144 -315.215894)
			(xy 119.933924 -315.292446) (xy 119.965365 -315.372294) (xy 119.989191 -315.454735) (xy 120.005192 -315.539045)
			(xy 120.013227 -315.624483) (xy 120.01373 -315.66739) (xy 120.013234 -315.709738) (xy 122.407422 -315.709738)
			(xy 122.407422 -315.625042) (xy 122.415473 -315.540728) (xy 122.431502 -315.457562) (xy 122.455363 -315.376295)
			(xy 122.486842 -315.297665) (xy 122.525653 -315.222384) (xy 122.571443 -315.151132) (xy 122.623799 -315.084556)
			(xy 122.682247 -315.023258) (xy 122.746257 -314.967793) (xy 122.815249 -314.918664) (xy 122.888599 -314.876315)
			(xy 122.965642 -314.841131) (xy 123.045681 -314.813429) (xy 123.12799 -314.793461) (xy 123.211825 -314.781408)
			(xy 123.296426 -314.777378) (xy 123.381027 -314.781408) (xy 123.464862 -314.793461) (xy 123.547171 -314.813429)
			(xy 123.62721 -314.841131) (xy 123.704253 -314.876315) (xy 123.777603 -314.918664) (xy 123.846595 -314.967793)
			(xy 123.910605 -315.023258) (xy 123.969053 -315.084556) (xy 124.021409 -315.151132) (xy 124.067199 -315.222384)
			(xy 124.10601 -315.297665) (xy 124.137489 -315.376295) (xy 124.16135 -315.457562) (xy 124.177379 -315.540728)
			(xy 124.18543 -315.625042) (xy 124.185934 -315.66739) (xy 124.381011 -315.66739) (xy 124.385033 -315.58167)
			(xy 124.397064 -315.496702) (xy 124.417 -315.413235) (xy 124.444663 -315.332001) (xy 124.479812 -315.253715)
			(xy 124.522138 -315.179064) (xy 124.571267 -315.108705) (xy 124.62677 -315.043255) (xy 124.688157 -314.983291)
			(xy 124.75489 -314.929338) (xy 124.826382 -314.881871) (xy 124.902004 -314.841307) (xy 124.981093 -314.808003)
			(xy 125.062953 -314.782251) (xy 125.146864 -314.764278) (xy 125.23209 -314.754242) (xy 125.317882 -314.75223)
			(xy 125.403484 -314.758261) (xy 125.488146 -314.772281) (xy 125.571123 -314.794167) (xy 125.651686 -314.823728)
			(xy 125.729126 -314.860702) (xy 125.802765 -314.904766) (xy 125.871953 -314.955532) (xy 125.936084 -315.012553)
			(xy 125.994593 -315.075329) (xy 126.046966 -315.143309) (xy 126.092744 -315.215894) (xy 126.131524 -315.292446)
			(xy 126.162965 -315.372294) (xy 126.186791 -315.454735) (xy 126.202792 -315.539045) (xy 126.210827 -315.624483)
			(xy 126.21133 -315.66739) (xy 126.210827 -315.710297) (xy 126.202792 -315.795735) (xy 126.186791 -315.880045)
			(xy 126.162965 -315.962486) (xy 126.131524 -316.042334) (xy 126.092744 -316.118886) (xy 126.046966 -316.191471)
			(xy 125.994593 -316.259451) (xy 125.936084 -316.322227) (xy 125.871953 -316.379248) (xy 125.802765 -316.430014)
			(xy 125.729126 -316.474078) (xy 125.651686 -316.511052) (xy 125.571123 -316.540613) (xy 125.488146 -316.562499)
			(xy 125.403484 -316.576519) (xy 125.317882 -316.58255) (xy 125.23209 -316.580538) (xy 125.146864 -316.570502)
			(xy 125.062953 -316.552529) (xy 124.981093 -316.526777) (xy 124.902004 -316.493473) (xy 124.826382 -316.452909)
			(xy 124.75489 -316.405442) (xy 124.688157 -316.351489) (xy 124.62677 -316.291525) (xy 124.571267 -316.226075)
			(xy 124.522138 -316.155716) (xy 124.479812 -316.081065) (xy 124.444663 -316.002779) (xy 124.417 -315.921545)
			(xy 124.397064 -315.838078) (xy 124.385033 -315.75311) (xy 124.381011 -315.66739) (xy 124.185934 -315.66739)
			(xy 124.18543 -315.709738) (xy 124.177379 -315.794052) (xy 124.16135 -315.877218) (xy 124.137489 -315.958485)
			(xy 124.10601 -316.037115) (xy 124.067199 -316.112396) (xy 124.021409 -316.183648) (xy 123.969053 -316.250224)
			(xy 123.910605 -316.311522) (xy 123.846595 -316.366987) (xy 123.777603 -316.416116) (xy 123.704253 -316.458465)
			(xy 123.62721 -316.493649) (xy 123.547171 -316.521351) (xy 123.464862 -316.541319) (xy 123.381027 -316.553372)
			(xy 123.296426 -316.557403) (xy 123.211825 -316.553372) (xy 123.12799 -316.541319) (xy 123.045681 -316.521351)
			(xy 122.965642 -316.493649) (xy 122.888599 -316.458465) (xy 122.815249 -316.416116) (xy 122.746257 -316.366987)
			(xy 122.682247 -316.311522) (xy 122.623799 -316.250224) (xy 122.571443 -316.183648) (xy 122.525653 -316.112396)
			(xy 122.486842 -316.037115) (xy 122.455363 -315.958485) (xy 122.431502 -315.877218) (xy 122.415473 -315.794052)
			(xy 122.407422 -315.709738) (xy 120.013234 -315.709738) (xy 120.013227 -315.710297) (xy 120.005192 -315.795735)
			(xy 119.989191 -315.880045) (xy 119.965365 -315.962486) (xy 119.933924 -316.042334) (xy 119.895144 -316.118886)
			(xy 119.849366 -316.191471) (xy 119.796993 -316.259451) (xy 119.738484 -316.322227) (xy 119.674353 -316.379248)
			(xy 119.605165 -316.430014) (xy 119.531526 -316.474078) (xy 119.454086 -316.511052) (xy 119.373523 -316.540613)
			(xy 119.290546 -316.562499) (xy 119.205884 -316.576519) (xy 119.120282 -316.58255) (xy 119.03449 -316.580538)
			(xy 118.949264 -316.570502) (xy 118.865353 -316.552529) (xy 118.783493 -316.526777) (xy 118.704404 -316.493473)
			(xy 118.628782 -316.452909) (xy 118.55729 -316.405442) (xy 118.490557 -316.351489) (xy 118.42917 -316.291525)
			(xy 118.373667 -316.226075) (xy 118.324538 -316.155716) (xy 118.282212 -316.081065) (xy 118.247063 -316.002779)
			(xy 118.2194 -315.921545) (xy 118.199464 -315.838078) (xy 118.187433 -315.75311) (xy 118.183411 -315.66739)
			(xy 117.988334 -315.66739) (xy 117.98783 -315.709738) (xy 117.979779 -315.794052) (xy 117.96375 -315.877218)
			(xy 117.939889 -315.958485) (xy 117.90841 -316.037115) (xy 117.869599 -316.112396) (xy 117.823809 -316.183648)
			(xy 117.771453 -316.250224) (xy 117.713005 -316.311522) (xy 117.648995 -316.366987) (xy 117.580003 -316.416116)
			(xy 117.506653 -316.458465) (xy 117.42961 -316.493649) (xy 117.349571 -316.521351) (xy 117.267262 -316.541319)
			(xy 117.183427 -316.553372) (xy 117.098826 -316.557403) (xy 117.014225 -316.553372) (xy 116.93039 -316.541319)
			(xy 116.848081 -316.521351) (xy 116.768042 -316.493649) (xy 116.690999 -316.458465) (xy 116.617649 -316.416116)
			(xy 116.548657 -316.366987) (xy 116.484647 -316.311522) (xy 116.426199 -316.250224) (xy 116.373843 -316.183648)
			(xy 116.328053 -316.112396) (xy 116.289242 -316.037115) (xy 116.257763 -315.958485) (xy 116.233902 -315.877218)
			(xy 116.217873 -315.794052) (xy 116.209822 -315.709738) (xy 113.815634 -315.709738) (xy 113.815627 -315.710297)
			(xy 113.807592 -315.795735) (xy 113.791591 -315.880045) (xy 113.767765 -315.962486) (xy 113.736324 -316.042334)
			(xy 113.697544 -316.118886) (xy 113.651766 -316.191471) (xy 113.599393 -316.259451) (xy 113.540884 -316.322227)
			(xy 113.476753 -316.379248) (xy 113.407565 -316.430014) (xy 113.333926 -316.474078) (xy 113.256486 -316.511052)
			(xy 113.175923 -316.540613) (xy 113.092946 -316.562499) (xy 113.008284 -316.576519) (xy 112.922682 -316.58255)
			(xy 112.83689 -316.580538) (xy 112.751664 -316.570502) (xy 112.667753 -316.552529) (xy 112.585893 -316.526777)
			(xy 112.506804 -316.493473) (xy 112.431182 -316.452909) (xy 112.35969 -316.405442) (xy 112.292957 -316.351489)
			(xy 112.23157 -316.291525) (xy 112.176067 -316.226075) (xy 112.126938 -316.155716) (xy 112.084612 -316.081065)
			(xy 112.049463 -316.002779) (xy 112.0218 -315.921545) (xy 112.001864 -315.838078) (xy 111.989833 -315.75311)
			(xy 111.985811 -315.66739) (xy 111.790734 -315.66739) (xy 111.79023 -315.709738) (xy 111.782179 -315.794052)
			(xy 111.76615 -315.877218) (xy 111.742289 -315.958485) (xy 111.71081 -316.037115) (xy 111.671999 -316.112396)
			(xy 111.626209 -316.183648) (xy 111.573853 -316.250224) (xy 111.515405 -316.311522) (xy 111.451395 -316.366987)
			(xy 111.382403 -316.416116) (xy 111.309053 -316.458465) (xy 111.23201 -316.493649) (xy 111.151971 -316.521351)
			(xy 111.069662 -316.541319) (xy 110.985827 -316.553372) (xy 110.901226 -316.557403) (xy 110.816625 -316.553372)
			(xy 110.73279 -316.541319) (xy 110.650481 -316.521351) (xy 110.570442 -316.493649) (xy 110.493399 -316.458465)
			(xy 110.420049 -316.416116) (xy 110.351057 -316.366987) (xy 110.287047 -316.311522) (xy 110.228599 -316.250224)
			(xy 110.176243 -316.183648) (xy 110.130453 -316.112396) (xy 110.091642 -316.037115) (xy 110.060163 -315.958485)
			(xy 110.036302 -315.877218) (xy 110.020273 -315.794052) (xy 110.012222 -315.709738) (xy 107.637846 -315.709738)
			(xy 107.637839 -315.710297) (xy 107.629804 -315.795735) (xy 107.613803 -315.880045) (xy 107.589977 -315.962486)
			(xy 107.558536 -316.042334) (xy 107.519756 -316.118886) (xy 107.473978 -316.191471) (xy 107.421605 -316.259451)
			(xy 107.363096 -316.322227) (xy 107.298965 -316.379248) (xy 107.229777 -316.430014) (xy 107.156138 -316.474078)
			(xy 107.078698 -316.511052) (xy 106.998135 -316.540613) (xy 106.915158 -316.562499) (xy 106.830496 -316.576519)
			(xy 106.744894 -316.58255) (xy 106.659102 -316.580538) (xy 106.573876 -316.570502) (xy 106.489965 -316.552529)
			(xy 106.408105 -316.526777) (xy 106.329016 -316.493473) (xy 106.253394 -316.452909) (xy 106.181902 -316.405442)
			(xy 106.115169 -316.351489) (xy 106.053782 -316.291525) (xy 105.998279 -316.226075) (xy 105.94915 -316.155716)
			(xy 105.906824 -316.081065) (xy 105.871675 -316.002779) (xy 105.844012 -315.921545) (xy 105.824076 -315.838078)
			(xy 105.812045 -315.75311) (xy 105.808023 -315.66739) (xy 105.612946 -315.66739) (xy 105.612442 -315.709738)
			(xy 105.604391 -315.794052) (xy 105.588362 -315.877218) (xy 105.564501 -315.958485) (xy 105.533022 -316.037115)
			(xy 105.494211 -316.112396) (xy 105.448421 -316.183648) (xy 105.396065 -316.250224) (xy 105.337617 -316.311522)
			(xy 105.273607 -316.366987) (xy 105.204615 -316.416116) (xy 105.131265 -316.458465) (xy 105.054222 -316.493649)
			(xy 104.974183 -316.521351) (xy 104.891874 -316.541319) (xy 104.808039 -316.553372) (xy 104.723438 -316.557403)
			(xy 104.638837 -316.553372) (xy 104.555002 -316.541319) (xy 104.472693 -316.521351) (xy 104.392654 -316.493649)
			(xy 104.315611 -316.458465) (xy 104.242261 -316.416116) (xy 104.173269 -316.366987) (xy 104.109259 -316.311522)
			(xy 104.050811 -316.250224) (xy 103.998455 -316.183648) (xy 103.952665 -316.112396) (xy 103.913854 -316.037115)
			(xy 103.882375 -315.958485) (xy 103.858514 -315.877218) (xy 103.842485 -315.794052) (xy 103.834434 -315.709738)
			(xy 101.440246 -315.709738) (xy 101.440239 -315.710297) (xy 101.432204 -315.795735) (xy 101.416203 -315.880045)
			(xy 101.392377 -315.962486) (xy 101.360936 -316.042334) (xy 101.322156 -316.118886) (xy 101.276378 -316.191471)
			(xy 101.224005 -316.259451) (xy 101.165496 -316.322227) (xy 101.101365 -316.379248) (xy 101.032177 -316.430014)
			(xy 100.958538 -316.474078) (xy 100.881098 -316.511052) (xy 100.800535 -316.540613) (xy 100.717558 -316.562499)
			(xy 100.632896 -316.576519) (xy 100.547294 -316.58255) (xy 100.461502 -316.580538) (xy 100.376276 -316.570502)
			(xy 100.292365 -316.552529) (xy 100.210505 -316.526777) (xy 100.131416 -316.493473) (xy 100.055794 -316.452909)
			(xy 99.984302 -316.405442) (xy 99.917569 -316.351489) (xy 99.856182 -316.291525) (xy 99.800679 -316.226075)
			(xy 99.75155 -316.155716) (xy 99.709224 -316.081065) (xy 99.674075 -316.002779) (xy 99.646412 -315.921545)
			(xy 99.626476 -315.838078) (xy 99.614445 -315.75311) (xy 99.610423 -315.66739) (xy 99.415346 -315.66739)
			(xy 99.414842 -315.709738) (xy 99.406791 -315.794052) (xy 99.390762 -315.877218) (xy 99.366901 -315.958485)
			(xy 99.335422 -316.037115) (xy 99.296611 -316.112396) (xy 99.250821 -316.183648) (xy 99.198465 -316.250224)
			(xy 99.140017 -316.311522) (xy 99.076007 -316.366987) (xy 99.007015 -316.416116) (xy 98.933665 -316.458465)
			(xy 98.856622 -316.493649) (xy 98.776583 -316.521351) (xy 98.694274 -316.541319) (xy 98.610439 -316.553372)
			(xy 98.525838 -316.557403) (xy 98.441237 -316.553372) (xy 98.357402 -316.541319) (xy 98.275093 -316.521351)
			(xy 98.195054 -316.493649) (xy 98.118011 -316.458465) (xy 98.044661 -316.416116) (xy 97.975669 -316.366987)
			(xy 97.911659 -316.311522) (xy 97.853211 -316.250224) (xy 97.800855 -316.183648) (xy 97.755065 -316.112396)
			(xy 97.716254 -316.037115) (xy 97.684775 -315.958485) (xy 97.660914 -315.877218) (xy 97.644885 -315.794052)
			(xy 97.636834 -315.709738) (xy 91.020841 -315.709738) (xy 85.3694 -320.309748) (xy 78.001114 -327.678034)
			(xy 77.159866 -330.520548) (xy 77.159866 -331.870304) (xy 77.200252 -331.878686) (xy 77.226514 -331.884785)
			(xy 77.27695 -331.903829) (xy 77.323944 -331.930252) (xy 77.366422 -331.96345) (xy 77.403416 -332.002668)
			(xy 77.434082 -332.047009) (xy 77.45772 -332.095462) (xy 77.473791 -332.146924) (xy 77.48193 -332.200218)
			(xy 77.482446 -332.227174) (xy 77.482017 -332.25229) (xy 77.474963 -332.302023) (xy 77.46099 -332.350272)
			(xy 77.440377 -332.396079) (xy 77.413531 -332.438535) (xy 77.380987 -332.476798) (xy 77.343389 -332.510108)
			(xy 77.301483 -332.537804) (xy 77.278992 -332.548992) (xy 77.266654 -332.555401) (xy 77.245724 -332.573684)
			(xy 77.230493 -332.596929) (xy 77.222087 -332.623418) (xy 77.221127 -332.651192) (xy 77.227686 -332.678198)
			(xy 77.241277 -332.702439) (xy 77.250798 -332.712568) (xy 77.47 -332.93177) (xy 84.291678 -332.93177)
		)
		(stroke
			(width 0)
			(type solid)
		)
		(fill yes)
		(layer "In11.Cu")
		(net "PVCCIN_CPU1")
	)
	(gr_poly
		(pts
			(xy 419.13556 -192.585848) (xy 419.150439 -192.585325) (xy 419.178931 -192.576737) (xy 419.203742 -192.560308)
			(xy 419.22277 -192.537428) (xy 419.234403 -192.510038) (xy 419.237654 -192.480458) (xy 419.232247 -192.451196)
			(xy 419.218642 -192.42473) (xy 419.208712 -192.413636) (xy 419.188765 -192.392201) (xy 419.155021 -192.344353)
			(xy 419.128986 -192.291909) (xy 419.111273 -192.236102) (xy 419.102298 -192.178243) (xy 419.101778 -192.148968)
			(xy 419.102264 -192.121717) (xy 419.11002 -192.067769) (xy 419.125375 -192.015474) (xy 419.148017 -191.965897)
			(xy 419.177483 -191.920047) (xy 419.213174 -191.878856) (xy 419.254365 -191.843165) (xy 419.300215 -191.813699)
			(xy 419.349792 -191.791057) (xy 419.402087 -191.775702) (xy 419.456035 -191.767946) (xy 419.510537 -191.767946)
			(xy 419.564485 -191.775702) (xy 419.61678 -191.791057) (xy 419.666357 -191.813699) (xy 419.712207 -191.843165)
			(xy 419.753398 -191.878856) (xy 419.789089 -191.920047) (xy 419.818555 -191.965897) (xy 419.841197 -192.015474)
			(xy 419.856552 -192.067769) (xy 419.864308 -192.121717) (xy 419.864794 -192.148968) (xy 419.864241 -192.178241)
			(xy 419.85526 -192.236094) (xy 419.837551 -192.291898) (xy 419.811528 -192.344343) (xy 419.777802 -192.3922)
			(xy 419.75786 -192.413636) (xy 419.74789 -192.4247) (xy 419.734259 -192.451163) (xy 419.728838 -192.480433)
			(xy 419.732087 -192.510023) (xy 419.74373 -192.53742) (xy 419.762779 -192.560295) (xy 419.787614 -192.576706)
			(xy 419.816127 -192.585258) (xy 419.831012 -192.585848) (xy 422.884346 -192.585848) (xy 422.898294 -192.58538)
			(xy 422.925134 -192.577769) (xy 422.948914 -192.563181) (xy 422.967862 -192.542704) (xy 422.980565 -192.517866)
			(xy 422.986075 -192.490517) (xy 422.983983 -192.462698) (xy 422.979596 -192.44945) (xy 422.968935 -192.417934)
			(xy 422.957438 -192.352411) (xy 422.956736 -192.319148) (xy 422.957222 -192.291897) (xy 422.964978 -192.237949)
			(xy 422.980333 -192.185654) (xy 423.002975 -192.136077) (xy 423.032441 -192.090227) (xy 423.068132 -192.049036)
			(xy 423.109323 -192.013345) (xy 423.155173 -191.983879) (xy 423.20475 -191.961237) (xy 423.257045 -191.945882)
			(xy 423.310993 -191.938126) (xy 423.365495 -191.938126) (xy 423.419443 -191.945882) (xy 423.471738 -191.961237)
			(xy 423.521315 -191.983879) (xy 423.567165 -192.013345) (xy 423.608356 -192.049036) (xy 423.644047 -192.090227)
			(xy 423.673513 -192.136077) (xy 423.696155 -192.185654) (xy 423.71151 -192.237949) (xy 423.719266 -192.291897)
			(xy 423.719752 -192.319148) (xy 423.719051 -192.352411) (xy 423.707549 -192.417933) (xy 423.696892 -192.44945)
			(xy 423.692514 -192.462707) (xy 423.690395 -192.490534) (xy 423.69589 -192.517895) (xy 423.708589 -192.542746)
			(xy 423.727543 -192.563231) (xy 423.751335 -192.577817) (xy 423.778189 -192.585416) (xy 423.792142 -192.585848)
			(xy 456.585574 -192.585848) (xy 460.07274 -189.098682) (xy 460.073756 -189.07887) (xy 460.076001 -189.036386)
			(xy 460.0874 -188.952072) (xy 460.10658 -188.86918) (xy 460.133375 -188.788428) (xy 460.167554 -188.710514)
			(xy 460.208821 -188.636111) (xy 460.25682 -188.565862) (xy 460.311136 -188.500374) (xy 460.371298 -188.440213)
			(xy 460.436788 -188.3859) (xy 460.507039 -188.337904) (xy 460.581444 -188.296639) (xy 460.659359 -188.262463)
			(xy 460.740112 -188.235671) (xy 460.823004 -188.216494) (xy 460.907319 -188.205098) (xy 460.949802 -188.202824)
			(xy 460.969614 -188.201808) (xy 462.115662 -187.05576) (xy 462.136744 -187.05576) (xy 464.472528 -184.719976)
			(xy 464.472528 -176.045622) (xy 453.87006 -165.443154) (xy 453.87006 -130.188716) (xy 466.88883 -117.169946)
			(xy 466.898647 -117.15935) (xy 466.912452 -117.133993) (xy 466.918613 -117.105786) (xy 466.91664 -117.076982)
			(xy 466.906688 -117.04988) (xy 466.889553 -117.026642) (xy 466.866603 -117.009125) (xy 466.839669 -116.998727)
			(xy 466.82533 -116.996972) (xy 466.797078 -116.994095) (xy 466.741811 -116.981044) (xy 466.689089 -116.959944)
			(xy 466.640077 -116.931262) (xy 466.595858 -116.895632) (xy 466.55741 -116.853841) (xy 466.525582 -116.806811)
			(xy 466.501077 -116.755583) (xy 466.484436 -116.701289) (xy 466.476028 -116.645128) (xy 466.475572 -116.616734)
			(xy 466.476033 -116.589479) (xy 466.483785 -116.535523) (xy 466.499138 -116.48322) (xy 466.521779 -116.433634)
			(xy 466.551245 -116.387776) (xy 466.586939 -116.346577) (xy 466.628132 -116.310878) (xy 466.673987 -116.281405)
			(xy 466.723569 -116.258757) (xy 466.77587 -116.243397) (xy 466.829825 -116.235636) (xy 466.85708 -116.235226)
			(xy 466.884353 -116.23571) (xy 466.938339 -116.243515) (xy 466.990664 -116.258926) (xy 467.040262 -116.281629)
			(xy 467.086123 -116.311161) (xy 467.107016 -116.328698) (xy 467.118323 -116.337882) (xy 467.144809 -116.349979)
			(xy 467.173632 -116.354117) (xy 467.202452 -116.349961) (xy 467.22893 -116.337847) (xy 467.250919 -116.318759)
			(xy 467.266634 -116.294246) (xy 467.274799 -116.266296) (xy 467.275164 -116.251736) (xy 467.275164 -114.444272)
			(xy 467.254729 -114.424477) (xy 467.219369 -114.379909) (xy 467.191019 -114.330584) (xy 467.170308 -114.277596)
			(xy 467.157696 -114.22212) (xy 467.153462 -114.165386) (xy 467.1577 -114.108653) (xy 467.170316 -114.053178)
			(xy 467.191031 -114.000191) (xy 467.219384 -113.950869) (xy 467.254748 -113.906303) (xy 467.275164 -113.886488)
			(xy 467.275164 -109.364272) (xy 467.254729 -109.344477) (xy 467.219369 -109.299909) (xy 467.191019 -109.250584)
			(xy 467.170308 -109.197596) (xy 467.157696 -109.14212) (xy 467.153462 -109.085386) (xy 467.1577 -109.028653)
			(xy 467.170316 -108.973178) (xy 467.191031 -108.920191) (xy 467.219384 -108.870869) (xy 467.254748 -108.826303)
			(xy 467.275164 -108.806488) (xy 467.275164 -104.284272) (xy 467.254729 -104.264477) (xy 467.219369 -104.219909)
			(xy 467.191019 -104.170584) (xy 467.170308 -104.117596) (xy 467.157696 -104.06212) (xy 467.153462 -104.005386)
			(xy 467.1577 -103.948653) (xy 467.170316 -103.893178) (xy 467.191031 -103.840191) (xy 467.219384 -103.790869)
			(xy 467.254748 -103.746303) (xy 467.275164 -103.726488) (xy 467.275164 -99.204272) (xy 467.254729 -99.184477)
			(xy 467.219369 -99.139909) (xy 467.191019 -99.090584) (xy 467.170308 -99.037596) (xy 467.157696 -98.98212)
			(xy 467.153462 -98.925386) (xy 467.1577 -98.868653) (xy 467.170316 -98.813178) (xy 467.191031 -98.760191)
			(xy 467.219384 -98.710869) (xy 467.254748 -98.666303) (xy 467.275164 -98.646488) (xy 467.275164 -94.124272)
			(xy 467.254729 -94.104477) (xy 467.219369 -94.059909) (xy 467.191019 -94.010584) (xy 467.170308 -93.957596)
			(xy 467.157696 -93.90212) (xy 467.153462 -93.845386) (xy 467.1577 -93.788653) (xy 467.170316 -93.733178)
			(xy 467.191031 -93.680191) (xy 467.219384 -93.630869) (xy 467.254748 -93.586303) (xy 467.275164 -93.566488)
			(xy 467.275164 -89.044272) (xy 467.254729 -89.024477) (xy 467.219369 -88.979909) (xy 467.191019 -88.930584)
			(xy 467.170308 -88.877596) (xy 467.157696 -88.82212) (xy 467.153462 -88.765386) (xy 467.1577 -88.708653)
			(xy 467.170316 -88.653178) (xy 467.191031 -88.600191) (xy 467.219384 -88.550869) (xy 467.254748 -88.506303)
			(xy 467.275164 -88.486488) (xy 467.275164 -85.258148) (xy 465.345018 -83.327748) (xy 464.844384 -83.327748)
			(xy 464.830214 -83.328217) (xy 464.802967 -83.336013) (xy 464.778915 -83.351001) (xy 464.75991 -83.372024)
			(xy 464.747418 -83.397463) (xy 464.742402 -83.425356) (xy 464.743292 -83.439508) (xy 464.745324 -83.478116)
			(xy 464.744838 -83.505367) (xy 464.737082 -83.559315) (xy 464.721727 -83.61161) (xy 464.699085 -83.661187)
			(xy 464.669619 -83.707037) (xy 464.633928 -83.748228) (xy 464.592737 -83.783919) (xy 464.546887 -83.813385)
			(xy 464.49731 -83.836027) (xy 464.445015 -83.851382) (xy 464.391067 -83.859138) (xy 464.336565 -83.859138)
			(xy 464.282617 -83.851382) (xy 464.230322 -83.836027) (xy 464.180745 -83.813385) (xy 464.134895 -83.783919)
			(xy 464.093704 -83.748228) (xy 464.058013 -83.707037) (xy 464.028547 -83.661187) (xy 464.005905 -83.61161)
			(xy 463.99055 -83.559315) (xy 463.982794 -83.505367) (xy 463.982308 -83.478116) (xy 463.98434 -83.439508)
			(xy 463.9853 -83.425351) (xy 463.980281 -83.397436) (xy 463.967781 -83.371976) (xy 463.948764 -83.350934)
			(xy 463.924696 -83.335929) (xy 463.897429 -83.328119) (xy 463.883248 -83.327748) (xy 446.9892 -83.327748)
			(xy 445.3128 -81.651348) (xy 445.3128 -78.305152) (xy 445.312323 -78.29058) (xy 445.304081 -78.262624)
			(xy 445.288281 -78.238133) (xy 445.26621 -78.219099) (xy 445.239663 -78.207071) (xy 445.2108 -78.203027)
			(xy 445.181969 -78.207297) (xy 445.168528 -78.21295) (xy 445.143255 -78.22411) (xy 445.090297 -78.239847)
			(xy 445.035624 -78.247784) (xy 445.008 -78.248256) (xy 444.980745 -78.24777) (xy 444.926791 -78.240013)
			(xy 444.874489 -78.224656) (xy 444.824906 -78.202012) (xy 444.77905 -78.172542) (xy 444.737854 -78.136846)
			(xy 444.702158 -78.09565) (xy 444.672688 -78.049794) (xy 444.650044 -78.000211) (xy 444.634687 -77.947909)
			(xy 444.62693 -77.893955) (xy 444.62693 -77.839445) (xy 444.634687 -77.785491) (xy 444.650044 -77.733189)
			(xy 444.672688 -77.683606) (xy 444.702158 -77.63775) (xy 444.737854 -77.596554) (xy 444.77905 -77.560858)
			(xy 444.824906 -77.531388) (xy 444.874489 -77.508744) (xy 444.926791 -77.493387) (xy 444.980745 -77.48563)
			(xy 445.008 -77.48524) (xy 445.035624 -77.485709) (xy 445.0903 -77.493638) (xy 445.14326 -77.509374)
			(xy 445.168528 -77.520546) (xy 445.181957 -77.526239) (xy 445.210799 -77.530511) (xy 445.239674 -77.526466)
			(xy 445.266231 -77.514432) (xy 445.288311 -77.49539) (xy 445.304116 -77.470889) (xy 445.31236 -77.442922)
			(xy 445.3128 -77.428344) (xy 445.3128 -75.961748) (xy 444.779654 -75.428856) (xy 444.618872 -75.26782)
			(xy 444.373762 -75.02271) (xy 444.353442 -75.022456) (xy 444.326822 -75.021514) (xy 444.274216 -75.01316)
			(xy 444.223283 -74.997571) (xy 444.175013 -74.97505) (xy 444.130344 -74.946036) (xy 444.090143 -74.911091)
			(xy 444.055194 -74.870896) (xy 444.026173 -74.82623) (xy 444.003647 -74.777963) (xy 443.988051 -74.727032)
			(xy 443.97969 -74.674427) (xy 443.978792 -74.647806) (xy 443.978538 -74.627486) (xy 442.63818 -73.287128)
			(xy 442.63818 -52.949348) (xy 442.519816 -52.830984) (xy 442.25972 -52.570888) (xy 435.63032 -52.570888)
			(xy 434.54828 -53.652928) (xy 434.54828 -75.606148) (xy 433.98948 -76.164948) (xy 442.847982 -76.164948)
			(xy 442.852053 -76.109326) (xy 442.864179 -76.054889) (xy 442.884102 -76.002798) (xy 442.911398 -75.954163)
			(xy 442.945484 -75.91002) (xy 442.985633 -75.871311) (xy 443.030991 -75.83886) (xy 443.080591 -75.813359)
			(xy 443.133375 -75.795352) (xy 443.188218 -75.785222) (xy 443.243952 -75.783185) (xy 443.299389 -75.789285)
			(xy 443.353346 -75.803391) (xy 443.404675 -75.825203) (xy 443.452281 -75.854257) (xy 443.495149 -75.889932)
			(xy 443.532366 -75.931469) (xy 443.563139 -75.977982) (xy 443.586811 -76.028479) (xy 443.602879 -76.081886)
			(xy 443.610999 -76.137062) (xy 443.611508 -76.164948) (xy 443.610999 -76.192834) (xy 443.602879 -76.24801)
			(xy 443.586811 -76.301417) (xy 443.563139 -76.351914) (xy 443.532366 -76.398427) (xy 443.495149 -76.439964)
			(xy 443.452281 -76.475639) (xy 443.404675 -76.504693) (xy 443.353346 -76.526505) (xy 443.299389 -76.540611)
			(xy 443.243952 -76.546711) (xy 443.188218 -76.544674) (xy 443.133375 -76.534544) (xy 443.080591 -76.516537)
			(xy 443.030991 -76.491036) (xy 442.985633 -76.458585) (xy 442.945484 -76.419876) (xy 442.911398 -76.375733)
			(xy 442.884102 -76.327098) (xy 442.864179 -76.275007) (xy 442.852053 -76.22057) (xy 442.847982 -76.164948)
			(xy 433.98948 -76.164948) (xy 433.471828 -76.6826) (xy 433.471828 -77.373988) (xy 433.471279 -77.407264)
			(xy 433.462584 -77.473246) (xy 433.445354 -77.537529) (xy 433.419884 -77.599014) (xy 433.386609 -77.656651)
			(xy 433.346098 -77.709453) (xy 433.322984 -77.733398) (xy 419.785777 -91.270836) (xy 437.855358 -91.270836)
			(xy 437.859429 -91.215214) (xy 437.871555 -91.160777) (xy 437.891478 -91.108686) (xy 437.918774 -91.060051)
			(xy 437.95286 -91.015908) (xy 437.993009 -90.977199) (xy 438.038367 -90.944748) (xy 438.087967 -90.919247)
			(xy 438.140751 -90.90124) (xy 438.195594 -90.89111) (xy 438.251328 -90.889073) (xy 438.306765 -90.895173)
			(xy 438.360722 -90.909279) (xy 438.412051 -90.931091) (xy 438.459657 -90.960145) (xy 438.502525 -90.99582)
			(xy 438.539742 -91.037357) (xy 438.570515 -91.08387) (xy 438.594187 -91.134367) (xy 438.610255 -91.187774)
			(xy 438.618375 -91.24295) (xy 438.618884 -91.270836) (xy 438.618375 -91.298722) (xy 438.610255 -91.353898)
			(xy 438.594187 -91.407305) (xy 438.570515 -91.457802) (xy 438.539742 -91.504315) (xy 438.502525 -91.545852)
			(xy 438.459657 -91.581527) (xy 438.412051 -91.610581) (xy 438.360722 -91.632393) (xy 438.306765 -91.646499)
			(xy 438.251328 -91.652599) (xy 438.195594 -91.650562) (xy 438.140751 -91.640432) (xy 438.087967 -91.622425)
			(xy 438.038367 -91.596924) (xy 437.993009 -91.564473) (xy 437.95286 -91.525764) (xy 437.918774 -91.481621)
			(xy 437.891478 -91.432986) (xy 437.871555 -91.380895) (xy 437.859429 -91.326458) (xy 437.855358 -91.270836)
			(xy 419.785777 -91.270836) (xy 418.563042 -92.493592) (xy 449.330062 -92.493592) (xy 449.334133 -92.43797)
			(xy 449.346259 -92.383533) (xy 449.366182 -92.331442) (xy 449.393478 -92.282807) (xy 449.427564 -92.238664)
			(xy 449.467713 -92.199955) (xy 449.513071 -92.167504) (xy 449.562671 -92.142003) (xy 449.615455 -92.123996)
			(xy 449.670298 -92.113866) (xy 449.726032 -92.111829) (xy 449.736283 -92.112957) (xy 456.859523 -92.112957)
			(xy 456.859523 -92.058443) (xy 456.867282 -92.004484) (xy 456.882641 -91.952179) (xy 456.905288 -91.902592)
			(xy 456.934763 -91.856733) (xy 456.970464 -91.815535) (xy 457.011665 -91.779839) (xy 457.057527 -91.750369)
			(xy 457.107116 -91.727727) (xy 457.159423 -91.712373) (xy 457.213383 -91.70462) (xy 457.24064 -91.70416)
			(xy 457.266592 -91.704573) (xy 457.318016 -91.711626) (xy 457.36801 -91.725583) (xy 457.41565 -91.746187)
			(xy 457.460059 -91.773057) (xy 457.500417 -91.805697) (xy 457.518516 -91.824302) (xy 457.529321 -91.835131)
			(xy 457.555917 -91.850224) (xy 457.585785 -91.856791) (xy 457.616259 -91.854248) (xy 457.644625 -91.842821)
			(xy 457.668352 -91.823528) (xy 457.677266 -91.811094) (xy 457.692505 -91.78903) (xy 457.728155 -91.748977)
			(xy 457.769065 -91.714313) (xy 457.814428 -91.685723) (xy 457.86335 -91.663771) (xy 457.914864 -91.648889)
			(xy 457.967956 -91.641372) (xy 457.994766 -91.640914) (xy 458.022022 -91.641331) (xy 458.07598 -91.649084)
			(xy 458.128285 -91.664438) (xy 458.177872 -91.68708) (xy 458.223732 -91.716549) (xy 458.264931 -91.752245)
			(xy 458.300631 -91.793441) (xy 458.330104 -91.839298) (xy 458.35275 -91.888883) (xy 458.368109 -91.941187)
			(xy 458.375867 -91.995144) (xy 458.375867 -92.049656) (xy 458.368109 -92.103613) (xy 458.35275 -92.155917)
			(xy 458.330104 -92.205502) (xy 458.300631 -92.251359) (xy 458.264931 -92.292555) (xy 458.223732 -92.328251)
			(xy 458.177872 -92.35772) (xy 458.128285 -92.380362) (xy 458.103376 -92.387674) (xy 464.231988 -92.387674)
			(xy 464.236059 -92.332052) (xy 464.248185 -92.277615) (xy 464.268108 -92.225524) (xy 464.295404 -92.176889)
			(xy 464.32949 -92.132746) (xy 464.369639 -92.094037) (xy 464.414997 -92.061586) (xy 464.464597 -92.036085)
			(xy 464.517381 -92.018078) (xy 464.572224 -92.007948) (xy 464.627958 -92.005911) (xy 464.683395 -92.012011)
			(xy 464.737352 -92.026117) (xy 464.788681 -92.047929) (xy 464.836287 -92.076983) (xy 464.879155 -92.112658)
			(xy 464.916372 -92.154195) (xy 464.947145 -92.200708) (xy 464.970817 -92.251205) (xy 464.986885 -92.304612)
			(xy 464.995005 -92.359788) (xy 464.995514 -92.387674) (xy 464.995005 -92.41556) (xy 464.986885 -92.470736)
			(xy 464.970817 -92.524143) (xy 464.947145 -92.57464) (xy 464.916372 -92.621153) (xy 464.879155 -92.66269)
			(xy 464.836287 -92.698365) (xy 464.788681 -92.727419) (xy 464.737352 -92.749231) (xy 464.683395 -92.763337)
			(xy 464.627958 -92.769437) (xy 464.572224 -92.7674) (xy 464.517381 -92.75727) (xy 464.464597 -92.739263)
			(xy 464.414997 -92.713762) (xy 464.369639 -92.681311) (xy 464.32949 -92.642602) (xy 464.295404 -92.598459)
			(xy 464.268108 -92.549824) (xy 464.248185 -92.497733) (xy 464.236059 -92.443296) (xy 464.231988 -92.387674)
			(xy 458.103376 -92.387674) (xy 458.07598 -92.395716) (xy 458.022022 -92.403469) (xy 457.994766 -92.40393)
			(xy 457.968814 -92.403516) (xy 457.91739 -92.396464) (xy 457.867396 -92.382507) (xy 457.819755 -92.361904)
			(xy 457.775346 -92.335034) (xy 457.734989 -92.302393) (xy 457.71689 -92.283788) (xy 457.706091 -92.272949)
			(xy 457.679495 -92.257841) (xy 457.649623 -92.251265) (xy 457.619141 -92.253809) (xy 457.590772 -92.265246)
			(xy 457.567048 -92.284554) (xy 457.55814 -92.296996) (xy 457.542894 -92.319055) (xy 457.507246 -92.359109)
			(xy 457.466337 -92.393773) (xy 457.420975 -92.422364) (xy 457.372054 -92.444317) (xy 457.320541 -92.459199)
			(xy 457.26745 -92.466718) (xy 457.24064 -92.467176) (xy 457.213383 -92.46678) (xy 457.159423 -92.459027)
			(xy 457.107116 -92.443673) (xy 457.057527 -92.421031) (xy 457.011665 -92.391561) (xy 456.970464 -92.355865)
			(xy 456.934763 -92.314667) (xy 456.905288 -92.268809) (xy 456.882641 -92.219221) (xy 456.867282 -92.166916)
			(xy 456.859523 -92.112957) (xy 449.736283 -92.112957) (xy 449.781469 -92.117929) (xy 449.835426 -92.132035)
			(xy 449.886755 -92.153847) (xy 449.934361 -92.182901) (xy 449.977229 -92.218576) (xy 450.014446 -92.260113)
			(xy 450.045219 -92.306626) (xy 450.068891 -92.357123) (xy 450.084959 -92.41053) (xy 450.093079 -92.465706)
			(xy 450.093588 -92.493592) (xy 450.093079 -92.521478) (xy 450.084959 -92.576654) (xy 450.068891 -92.630061)
			(xy 450.045219 -92.680558) (xy 450.014446 -92.727071) (xy 449.977229 -92.768608) (xy 449.934361 -92.804283)
			(xy 449.886755 -92.833337) (xy 449.835426 -92.855149) (xy 449.781469 -92.869255) (xy 449.726032 -92.875355)
			(xy 449.670298 -92.873318) (xy 449.615455 -92.863188) (xy 449.562671 -92.845181) (xy 449.513071 -92.81968)
			(xy 449.467713 -92.787229) (xy 449.427564 -92.74852) (xy 449.393478 -92.704377) (xy 449.366182 -92.655742)
			(xy 449.346259 -92.603651) (xy 449.334133 -92.549214) (xy 449.330062 -92.493592) (xy 418.563042 -92.493592)
			(xy 418.439854 -92.616782) (xy 418.439854 -93.505528) (xy 440.882022 -93.505528) (xy 440.886093 -93.449906)
			(xy 440.898219 -93.395469) (xy 440.918142 -93.343378) (xy 440.945438 -93.294743) (xy 440.979524 -93.2506)
			(xy 441.019673 -93.211891) (xy 441.065031 -93.17944) (xy 441.114631 -93.153939) (xy 441.167415 -93.135932)
			(xy 441.222258 -93.125802) (xy 441.277992 -93.123765) (xy 441.333429 -93.129865) (xy 441.387386 -93.143971)
			(xy 441.438715 -93.165783) (xy 441.486321 -93.194837) (xy 441.529189 -93.230512) (xy 441.566406 -93.272049)
			(xy 441.597179 -93.318562) (xy 441.620851 -93.369059) (xy 441.636919 -93.422466) (xy 441.645039 -93.477642)
			(xy 441.645548 -93.505528) (xy 441.645474 -93.509592) (xy 449.330062 -93.509592) (xy 449.334133 -93.45397)
			(xy 449.346259 -93.399533) (xy 449.366182 -93.347442) (xy 449.393478 -93.298807) (xy 449.427564 -93.254664)
			(xy 449.467713 -93.215955) (xy 449.513071 -93.183504) (xy 449.562671 -93.158003) (xy 449.615455 -93.139996)
			(xy 449.670298 -93.129866) (xy 449.726032 -93.127829) (xy 449.781469 -93.133929) (xy 449.835426 -93.148035)
			(xy 449.886755 -93.169847) (xy 449.934361 -93.198901) (xy 449.977229 -93.234576) (xy 450.014446 -93.276113)
			(xy 450.045219 -93.322626) (xy 450.068891 -93.373123) (xy 450.07579 -93.396054) (xy 464.190586 -93.396054)
			(xy 464.194657 -93.340432) (xy 464.206783 -93.285995) (xy 464.226706 -93.233904) (xy 464.254002 -93.185269)
			(xy 464.288088 -93.141126) (xy 464.328237 -93.102417) (xy 464.373595 -93.069966) (xy 464.423195 -93.044465)
			(xy 464.475979 -93.026458) (xy 464.530822 -93.016328) (xy 464.586556 -93.014291) (xy 464.641993 -93.020391)
			(xy 464.69595 -93.034497) (xy 464.747279 -93.056309) (xy 464.794885 -93.085363) (xy 464.837753 -93.121038)
			(xy 464.87497 -93.162575) (xy 464.905743 -93.209088) (xy 464.929415 -93.259585) (xy 464.945483 -93.312992)
			(xy 464.953603 -93.368168) (xy 464.954112 -93.396054) (xy 464.953603 -93.42394) (xy 464.945483 -93.479116)
			(xy 464.929415 -93.532523) (xy 464.905743 -93.58302) (xy 464.87497 -93.629533) (xy 464.837753 -93.67107)
			(xy 464.794885 -93.706745) (xy 464.747279 -93.735799) (xy 464.69595 -93.757611) (xy 464.641993 -93.771717)
			(xy 464.586556 -93.777817) (xy 464.530822 -93.77578) (xy 464.475979 -93.76565) (xy 464.423195 -93.747643)
			(xy 464.373595 -93.722142) (xy 464.328237 -93.689691) (xy 464.288088 -93.650982) (xy 464.254002 -93.606839)
			(xy 464.226706 -93.558204) (xy 464.206783 -93.506113) (xy 464.194657 -93.451676) (xy 464.190586 -93.396054)
			(xy 450.07579 -93.396054) (xy 450.084959 -93.42653) (xy 450.093079 -93.481706) (xy 450.093588 -93.509592)
			(xy 450.093079 -93.537478) (xy 450.084959 -93.592654) (xy 450.068891 -93.646061) (xy 450.045219 -93.696558)
			(xy 450.014446 -93.743071) (xy 449.977229 -93.784608) (xy 449.934361 -93.820283) (xy 449.886755 -93.849337)
			(xy 449.835426 -93.871149) (xy 449.781469 -93.885255) (xy 449.726032 -93.891355) (xy 449.670298 -93.889318)
			(xy 449.615455 -93.879188) (xy 449.562671 -93.861181) (xy 449.513071 -93.83568) (xy 449.467713 -93.803229)
			(xy 449.427564 -93.76452) (xy 449.393478 -93.720377) (xy 449.366182 -93.671742) (xy 449.346259 -93.619651)
			(xy 449.334133 -93.565214) (xy 449.330062 -93.509592) (xy 441.645474 -93.509592) (xy 441.645039 -93.533414)
			(xy 441.636919 -93.58859) (xy 441.620851 -93.641997) (xy 441.597179 -93.692494) (xy 441.566406 -93.739007)
			(xy 441.529189 -93.780544) (xy 441.486321 -93.816219) (xy 441.438715 -93.845273) (xy 441.387386 -93.867085)
			(xy 441.333429 -93.881191) (xy 441.277992 -93.887291) (xy 441.222258 -93.885254) (xy 441.167415 -93.875124)
			(xy 441.114631 -93.857117) (xy 441.065031 -93.831616) (xy 441.019673 -93.799165) (xy 440.979524 -93.760456)
			(xy 440.945438 -93.716313) (xy 440.918142 -93.667678) (xy 440.898219 -93.615587) (xy 440.886093 -93.56115)
			(xy 440.882022 -93.505528) (xy 418.439854 -93.505528) (xy 418.439854 -93.891608) (xy 430.965862 -93.891608)
			(xy 430.969933 -93.835986) (xy 430.982059 -93.781549) (xy 431.001982 -93.729458) (xy 431.029278 -93.680823)
			(xy 431.063364 -93.63668) (xy 431.103513 -93.597971) (xy 431.148871 -93.56552) (xy 431.198471 -93.540019)
			(xy 431.251255 -93.522012) (xy 431.306098 -93.511882) (xy 431.361832 -93.509845) (xy 431.417269 -93.515945)
			(xy 431.471226 -93.530051) (xy 431.522555 -93.551863) (xy 431.570161 -93.580917) (xy 431.613029 -93.616592)
			(xy 431.650246 -93.658129) (xy 431.681019 -93.704642) (xy 431.704691 -93.755139) (xy 431.720759 -93.808546)
			(xy 431.728879 -93.863722) (xy 431.729388 -93.891608) (xy 431.728879 -93.919494) (xy 431.720759 -93.97467)
			(xy 431.704691 -94.028077) (xy 431.681019 -94.078574) (xy 431.650246 -94.125087) (xy 431.613029 -94.166624)
			(xy 431.570161 -94.202299) (xy 431.522555 -94.231353) (xy 431.471226 -94.253165) (xy 431.417269 -94.267271)
			(xy 431.361832 -94.273371) (xy 431.306098 -94.271334) (xy 431.251255 -94.261204) (xy 431.198471 -94.243197)
			(xy 431.148871 -94.217696) (xy 431.103513 -94.185245) (xy 431.063364 -94.146536) (xy 431.029278 -94.102393)
			(xy 431.001982 -94.053758) (xy 430.982059 -94.001667) (xy 430.969933 -93.94723) (xy 430.965862 -93.891608)
			(xy 418.439854 -93.891608) (xy 418.439854 -94.275148) (xy 436.294782 -94.275148) (xy 436.298853 -94.219526)
			(xy 436.310979 -94.165089) (xy 436.330902 -94.112998) (xy 436.358198 -94.064363) (xy 436.392284 -94.02022)
			(xy 436.432433 -93.981511) (xy 436.477791 -93.94906) (xy 436.527391 -93.923559) (xy 436.580175 -93.905552)
			(xy 436.635018 -93.895422) (xy 436.690752 -93.893385) (xy 436.746189 -93.899485) (xy 436.800146 -93.913591)
			(xy 436.851475 -93.935403) (xy 436.899081 -93.964457) (xy 436.941949 -94.000132) (xy 436.979166 -94.041669)
			(xy 437.009939 -94.088182) (xy 437.033611 -94.138679) (xy 437.049679 -94.192086) (xy 437.057799 -94.247262)
			(xy 437.058308 -94.275148) (xy 437.057799 -94.303034) (xy 437.049679 -94.35821) (xy 437.033611 -94.411617)
			(xy 437.009939 -94.462114) (xy 436.982394 -94.503748) (xy 437.869582 -94.503748) (xy 437.873653 -94.448126)
			(xy 437.885779 -94.393689) (xy 437.905702 -94.341598) (xy 437.932998 -94.292963) (xy 437.967084 -94.24882)
			(xy 438.007233 -94.210111) (xy 438.052591 -94.17766) (xy 438.102191 -94.152159) (xy 438.154975 -94.134152)
			(xy 438.209818 -94.124022) (xy 438.265552 -94.121985) (xy 438.320989 -94.128085) (xy 438.374946 -94.142191)
			(xy 438.426275 -94.164003) (xy 438.473881 -94.193057) (xy 438.516749 -94.228732) (xy 438.553966 -94.270269)
			(xy 438.584739 -94.316782) (xy 438.608411 -94.367279) (xy 438.624479 -94.420686) (xy 438.632599 -94.475862)
			(xy 438.633108 -94.503748) (xy 438.632599 -94.531634) (xy 438.624479 -94.58681) (xy 438.608411 -94.640217)
			(xy 438.597371 -94.663768) (xy 439.713622 -94.663768) (xy 439.717693 -94.608146) (xy 439.729819 -94.553709)
			(xy 439.749742 -94.501618) (xy 439.777038 -94.452983) (xy 439.811124 -94.40884) (xy 439.851273 -94.370131)
			(xy 439.896631 -94.33768) (xy 439.946231 -94.312179) (xy 439.999015 -94.294172) (xy 440.053858 -94.284042)
			(xy 440.109592 -94.282005) (xy 440.165029 -94.288105) (xy 440.218986 -94.302211) (xy 440.270315 -94.324023)
			(xy 440.317921 -94.353077) (xy 440.360789 -94.388752) (xy 440.398006 -94.430289) (xy 440.428779 -94.476802)
			(xy 440.452451 -94.527299) (xy 440.468519 -94.580706) (xy 440.471772 -94.602808) (xy 445.878964 -94.602808)
			(xy 445.883035 -94.547186) (xy 445.895161 -94.492749) (xy 445.915084 -94.440658) (xy 445.94238 -94.392023)
			(xy 445.976466 -94.34788) (xy 446.016615 -94.309171) (xy 446.061973 -94.27672) (xy 446.111573 -94.251219)
			(xy 446.164357 -94.233212) (xy 446.2192 -94.223082) (xy 446.274934 -94.221045) (xy 446.330371 -94.227145)
			(xy 446.384328 -94.241251) (xy 446.435657 -94.263063) (xy 446.483263 -94.292117) (xy 446.526131 -94.327792)
			(xy 446.563348 -94.369329) (xy 446.594121 -94.415842) (xy 446.617793 -94.466339) (xy 446.633861 -94.519746)
			(xy 446.641981 -94.574922) (xy 446.64249 -94.602808) (xy 446.641981 -94.630694) (xy 446.633861 -94.68587)
			(xy 446.617793 -94.739277) (xy 446.594121 -94.789774) (xy 446.563348 -94.836287) (xy 446.526131 -94.877824)
			(xy 446.483263 -94.913499) (xy 446.435657 -94.942553) (xy 446.412094 -94.952566) (xy 461.97596 -94.952566)
			(xy 461.980031 -94.896944) (xy 461.992157 -94.842507) (xy 462.01208 -94.790416) (xy 462.039376 -94.741781)
			(xy 462.073462 -94.697638) (xy 462.113611 -94.658929) (xy 462.158969 -94.626478) (xy 462.208569 -94.600977)
			(xy 462.261353 -94.58297) (xy 462.316196 -94.57284) (xy 462.37193 -94.570803) (xy 462.427367 -94.576903)
			(xy 462.481324 -94.591009) (xy 462.532653 -94.612821) (xy 462.580259 -94.641875) (xy 462.623127 -94.67755)
			(xy 462.660344 -94.719087) (xy 462.691117 -94.7656) (xy 462.714789 -94.816097) (xy 462.730857 -94.869504)
			(xy 462.735717 -94.902528) (xy 466.152482 -94.902528) (xy 466.156553 -94.846906) (xy 466.168679 -94.792469)
			(xy 466.188602 -94.740378) (xy 466.215898 -94.691743) (xy 466.249984 -94.6476) (xy 466.290133 -94.608891)
			(xy 466.335491 -94.57644) (xy 466.385091 -94.550939) (xy 466.437875 -94.532932) (xy 466.492718 -94.522802)
			(xy 466.548452 -94.520765) (xy 466.603889 -94.526865) (xy 466.657846 -94.540971) (xy 466.709175 -94.562783)
			(xy 466.756781 -94.591837) (xy 466.799649 -94.627512) (xy 466.836866 -94.669049) (xy 466.867639 -94.715562)
			(xy 466.891311 -94.766059) (xy 466.907379 -94.819466) (xy 466.915499 -94.874642) (xy 466.916008 -94.902528)
			(xy 466.915499 -94.930414) (xy 466.907379 -94.98559) (xy 466.891311 -95.038997) (xy 466.867639 -95.089494)
			(xy 466.836866 -95.136007) (xy 466.799649 -95.177544) (xy 466.756781 -95.213219) (xy 466.709175 -95.242273)
			(xy 466.657846 -95.264085) (xy 466.603889 -95.278191) (xy 466.548452 -95.284291) (xy 466.492718 -95.282254)
			(xy 466.437875 -95.272124) (xy 466.385091 -95.254117) (xy 466.335491 -95.228616) (xy 466.290133 -95.196165)
			(xy 466.249984 -95.157456) (xy 466.215898 -95.113313) (xy 466.188602 -95.064678) (xy 466.168679 -95.012587)
			(xy 466.156553 -94.95815) (xy 466.152482 -94.902528) (xy 462.735717 -94.902528) (xy 462.738977 -94.92468)
			(xy 462.739486 -94.952566) (xy 462.738977 -94.980452) (xy 462.730857 -95.035628) (xy 462.714789 -95.089035)
			(xy 462.691117 -95.139532) (xy 462.660344 -95.186045) (xy 462.623127 -95.227582) (xy 462.580259 -95.263257)
			(xy 462.532653 -95.292311) (xy 462.481324 -95.314123) (xy 462.427367 -95.328229) (xy 462.37193 -95.334329)
			(xy 462.316196 -95.332292) (xy 462.261353 -95.322162) (xy 462.208569 -95.304155) (xy 462.158969 -95.278654)
			(xy 462.113611 -95.246203) (xy 462.073462 -95.207494) (xy 462.039376 -95.163351) (xy 462.01208 -95.114716)
			(xy 461.992157 -95.062625) (xy 461.980031 -95.008188) (xy 461.97596 -94.952566) (xy 446.412094 -94.952566)
			(xy 446.384328 -94.964365) (xy 446.330371 -94.978471) (xy 446.274934 -94.984571) (xy 446.2192 -94.982534)
			(xy 446.164357 -94.972404) (xy 446.111573 -94.954397) (xy 446.061973 -94.928896) (xy 446.016615 -94.896445)
			(xy 445.976466 -94.857736) (xy 445.94238 -94.813593) (xy 445.915084 -94.764958) (xy 445.895161 -94.712867)
			(xy 445.883035 -94.65843) (xy 445.878964 -94.602808) (xy 440.471772 -94.602808) (xy 440.476639 -94.635882)
			(xy 440.477148 -94.663768) (xy 440.476639 -94.691654) (xy 440.468519 -94.74683) (xy 440.452451 -94.800237)
			(xy 440.428779 -94.850734) (xy 440.398006 -94.897247) (xy 440.360789 -94.938784) (xy 440.317921 -94.974459)
			(xy 440.270315 -95.003513) (xy 440.218986 -95.025325) (xy 440.165029 -95.039431) (xy 440.109592 -95.045531)
			(xy 440.053858 -95.043494) (xy 439.999015 -95.033364) (xy 439.946231 -95.015357) (xy 439.896631 -94.989856)
			(xy 439.851273 -94.957405) (xy 439.811124 -94.918696) (xy 439.777038 -94.874553) (xy 439.749742 -94.825918)
			(xy 439.729819 -94.773827) (xy 439.717693 -94.71939) (xy 439.713622 -94.663768) (xy 438.597371 -94.663768)
			(xy 438.584739 -94.690714) (xy 438.553966 -94.737227) (xy 438.516749 -94.778764) (xy 438.473881 -94.814439)
			(xy 438.426275 -94.843493) (xy 438.374946 -94.865305) (xy 438.320989 -94.879411) (xy 438.265552 -94.885511)
			(xy 438.209818 -94.883474) (xy 438.154975 -94.873344) (xy 438.102191 -94.855337) (xy 438.052591 -94.829836)
			(xy 438.007233 -94.797385) (xy 437.967084 -94.758676) (xy 437.932998 -94.714533) (xy 437.905702 -94.665898)
			(xy 437.885779 -94.613807) (xy 437.873653 -94.55937) (xy 437.869582 -94.503748) (xy 436.982394 -94.503748)
			(xy 436.979166 -94.508627) (xy 436.941949 -94.550164) (xy 436.899081 -94.585839) (xy 436.851475 -94.614893)
			(xy 436.800146 -94.636705) (xy 436.746189 -94.650811) (xy 436.690752 -94.656911) (xy 436.635018 -94.654874)
			(xy 436.580175 -94.644744) (xy 436.527391 -94.626737) (xy 436.477791 -94.601236) (xy 436.432433 -94.568785)
			(xy 436.392284 -94.530076) (xy 436.358198 -94.485933) (xy 436.330902 -94.437298) (xy 436.310979 -94.385207)
			(xy 436.298853 -94.33077) (xy 436.294782 -94.275148) (xy 418.439854 -94.275148) (xy 418.439854 -95.113348)
			(xy 436.853582 -95.113348) (xy 436.857653 -95.057726) (xy 436.869779 -95.003289) (xy 436.889702 -94.951198)
			(xy 436.916998 -94.902563) (xy 436.951084 -94.85842) (xy 436.991233 -94.819711) (xy 437.036591 -94.78726)
			(xy 437.086191 -94.761759) (xy 437.138975 -94.743752) (xy 437.193818 -94.733622) (xy 437.249552 -94.731585)
			(xy 437.304989 -94.737685) (xy 437.358946 -94.751791) (xy 437.410275 -94.773603) (xy 437.457881 -94.802657)
			(xy 437.500749 -94.838332) (xy 437.537966 -94.879869) (xy 437.568739 -94.926382) (xy 437.592411 -94.976879)
			(xy 437.608479 -95.030286) (xy 437.616599 -95.085462) (xy 437.617108 -95.113348) (xy 437.616599 -95.141234)
			(xy 437.608479 -95.19641) (xy 437.592411 -95.249817) (xy 437.568739 -95.300314) (xy 437.537966 -95.346827)
			(xy 437.500749 -95.388364) (xy 437.457881 -95.424039) (xy 437.410275 -95.453093) (xy 437.358946 -95.474905)
			(xy 437.304989 -95.489011) (xy 437.249552 -95.495111) (xy 437.193818 -95.493074) (xy 437.138975 -95.482944)
			(xy 437.086191 -95.464937) (xy 437.036591 -95.439436) (xy 436.991233 -95.406985) (xy 436.951084 -95.368276)
			(xy 436.916998 -95.324133) (xy 436.889702 -95.275498) (xy 436.869779 -95.223407) (xy 436.857653 -95.16897)
			(xy 436.853582 -95.113348) (xy 418.439854 -95.113348) (xy 418.439854 -95.872808) (xy 442.723522 -95.872808)
			(xy 442.727593 -95.817186) (xy 442.739719 -95.762749) (xy 442.759642 -95.710658) (xy 442.786938 -95.662023)
			(xy 442.821024 -95.61788) (xy 442.861173 -95.579171) (xy 442.906531 -95.54672) (xy 442.956131 -95.521219)
			(xy 443.008915 -95.503212) (xy 443.063758 -95.493082) (xy 443.119492 -95.491045) (xy 443.174929 -95.497145)
			(xy 443.228886 -95.511251) (xy 443.280215 -95.533063) (xy 443.327821 -95.562117) (xy 443.370689 -95.597792)
			(xy 443.407906 -95.639329) (xy 443.438679 -95.685842) (xy 443.462351 -95.736339) (xy 443.478419 -95.789746)
			(xy 443.486539 -95.844922) (xy 443.487048 -95.872808) (xy 443.486539 -95.900694) (xy 443.478419 -95.95587)
			(xy 443.462351 -96.009277) (xy 443.438679 -96.059774) (xy 443.407906 -96.106287) (xy 443.370689 -96.147824)
			(xy 443.327821 -96.183499) (xy 443.280215 -96.212553) (xy 443.228886 -96.234365) (xy 443.174929 -96.248471)
			(xy 443.119492 -96.254571) (xy 443.063758 -96.252534) (xy 443.008915 -96.242404) (xy 442.956131 -96.224397)
			(xy 442.906531 -96.198896) (xy 442.861173 -96.166445) (xy 442.821024 -96.127736) (xy 442.786938 -96.083593)
			(xy 442.759642 -96.034958) (xy 442.739719 -95.982867) (xy 442.727593 -95.92843) (xy 442.723522 -95.872808)
			(xy 418.439854 -95.872808) (xy 418.439854 -96.812608) (xy 434.902862 -96.812608) (xy 434.906933 -96.756986)
			(xy 434.919059 -96.702549) (xy 434.938982 -96.650458) (xy 434.966278 -96.601823) (xy 435.000364 -96.55768)
			(xy 435.040513 -96.518971) (xy 435.085871 -96.48652) (xy 435.135471 -96.461019) (xy 435.188255 -96.443012)
			(xy 435.243098 -96.432882) (xy 435.298832 -96.430845) (xy 435.354269 -96.436945) (xy 435.408226 -96.451051)
			(xy 435.459555 -96.472863) (xy 435.507161 -96.501917) (xy 435.550029 -96.537592) (xy 435.587246 -96.579129)
			(xy 435.618019 -96.625642) (xy 435.641691 -96.676139) (xy 435.657759 -96.729546) (xy 435.665879 -96.784722)
			(xy 435.666388 -96.812608) (xy 435.791862 -96.812608) (xy 435.795933 -96.756986) (xy 435.808059 -96.702549)
			(xy 435.827982 -96.650458) (xy 435.855278 -96.601823) (xy 435.889364 -96.55768) (xy 435.929513 -96.518971)
			(xy 435.974871 -96.48652) (xy 436.024471 -96.461019) (xy 436.077255 -96.443012) (xy 436.132098 -96.432882)
			(xy 436.187832 -96.430845) (xy 436.243269 -96.436945) (xy 436.297226 -96.451051) (xy 436.348555 -96.472863)
			(xy 436.396161 -96.501917) (xy 436.439029 -96.537592) (xy 436.470149 -96.572324) (xy 443.861188 -96.572324)
			(xy 443.865259 -96.516702) (xy 443.877385 -96.462265) (xy 443.897308 -96.410174) (xy 443.924604 -96.361539)
			(xy 443.95869 -96.317396) (xy 443.998839 -96.278687) (xy 444.044197 -96.246236) (xy 444.093797 -96.220735)
			(xy 444.146581 -96.202728) (xy 444.201424 -96.192598) (xy 444.257158 -96.190561) (xy 444.312595 -96.196661)
			(xy 444.366552 -96.210767) (xy 444.417881 -96.232579) (xy 444.465487 -96.261633) (xy 444.508355 -96.297308)
			(xy 444.545572 -96.338845) (xy 444.576345 -96.385358) (xy 444.600017 -96.435855) (xy 444.616085 -96.489262)
			(xy 444.624205 -96.544438) (xy 444.624714 -96.572324) (xy 444.624205 -96.60021) (xy 444.617394 -96.646492)
			(xy 448.88277 -96.646492) (xy 448.883138 -96.61975) (xy 448.890634 -96.566795) (xy 448.905451 -96.515405)
			(xy 448.927298 -96.466587) (xy 448.955748 -96.421297) (xy 448.990242 -96.380424) (xy 449.030105 -96.344767)
			(xy 449.074556 -96.315025) (xy 449.122725 -96.291781) (xy 449.173667 -96.27549) (xy 449.226385 -96.266472)
			(xy 449.253102 -96.265238) (xy 449.267008 -96.264343) (xy 449.293598 -96.256057) (xy 449.316961 -96.240896)
			(xy 449.335359 -96.219988) (xy 449.347426 -96.194886) (xy 449.352263 -96.167458) (xy 449.34951 -96.139743)
			(xy 449.339373 -96.113803) (xy 449.331334 -96.102424) (xy 449.313237 -96.077467) (xy 449.284519 -96.022919)
			(xy 449.264933 -95.964468) (xy 449.254986 -95.90363) (xy 449.254372 -95.872808) (xy 449.254858 -95.845557)
			(xy 449.262614 -95.791609) (xy 449.277969 -95.739314) (xy 449.300611 -95.689737) (xy 449.330077 -95.643887)
			(xy 449.365768 -95.602696) (xy 449.406959 -95.567005) (xy 449.452809 -95.537539) (xy 449.502386 -95.514897)
			(xy 449.554681 -95.499542) (xy 449.608629 -95.491786) (xy 449.663131 -95.491786) (xy 449.717079 -95.499542)
			(xy 449.769374 -95.514897) (xy 449.818951 -95.537539) (xy 449.864801 -95.567005) (xy 449.905992 -95.602696)
			(xy 449.941683 -95.643887) (xy 449.971149 -95.689737) (xy 449.993791 -95.739314) (xy 450.009146 -95.791609)
			(xy 450.016902 -95.845557) (xy 450.017388 -95.872808) (xy 450.016964 -95.899547) (xy 450.009469 -95.952498)
			(xy 449.994655 -96.003884) (xy 449.972812 -96.052698) (xy 449.944368 -96.097985) (xy 449.90988 -96.138857)
			(xy 449.870023 -96.174514) (xy 449.825579 -96.204257) (xy 449.777417 -96.227504) (xy 449.726482 -96.243799)
			(xy 449.67377 -96.252824) (xy 449.647056 -96.254062) (xy 449.633149 -96.25493) (xy 449.606561 -96.263225)
			(xy 449.583202 -96.278392) (xy 449.564806 -96.299304) (xy 449.552741 -96.324408) (xy 449.547904 -96.351836)
			(xy 449.550654 -96.379552) (xy 449.560787 -96.405495) (xy 449.568824 -96.416876) (xy 449.586916 -96.441837)
			(xy 449.615636 -96.496383) (xy 449.635224 -96.554833) (xy 449.645172 -96.61567) (xy 449.645786 -96.646492)
			(xy 449.645194 -96.676267) (xy 449.63588 -96.735085) (xy 449.627244 -96.763586) (xy 449.623335 -96.777461)
			(xy 449.622557 -96.806264) (xy 449.629839 -96.834141) (xy 449.644606 -96.858883) (xy 449.665686 -96.878526)
			(xy 449.691406 -96.891512) (xy 449.705476 -96.89465) (xy 449.73143 -96.899908) (xy 449.781658 -96.916684)
			(xy 449.829083 -96.940244) (xy 449.872795 -96.970136) (xy 449.911954 -97.005785) (xy 449.945808 -97.046506)
			(xy 449.973706 -97.091517) (xy 449.995112 -97.139953) (xy 450.009615 -97.190884) (xy 450.016936 -97.24333)
			(xy 450.017388 -97.269808) (xy 450.016902 -97.297059) (xy 450.009146 -97.351007) (xy 449.993791 -97.403302)
			(xy 449.980516 -97.432368) (xy 466.036658 -97.432368) (xy 466.040729 -97.376746) (xy 466.052855 -97.322309)
			(xy 466.072778 -97.270218) (xy 466.100074 -97.221583) (xy 466.13416 -97.17744) (xy 466.174309 -97.138731)
			(xy 466.219667 -97.10628) (xy 466.269267 -97.080779) (xy 466.322051 -97.062772) (xy 466.376894 -97.052642)
			(xy 466.432628 -97.050605) (xy 466.488065 -97.056705) (xy 466.542022 -97.070811) (xy 466.593351 -97.092623)
			(xy 466.640957 -97.121677) (xy 466.683825 -97.157352) (xy 466.721042 -97.198889) (xy 466.751815 -97.245402)
			(xy 466.775487 -97.295899) (xy 466.791555 -97.349306) (xy 466.799675 -97.404482) (xy 466.800184 -97.432368)
			(xy 466.799675 -97.460254) (xy 466.791555 -97.51543) (xy 466.775487 -97.568837) (xy 466.751815 -97.619334)
			(xy 466.721042 -97.665847) (xy 466.683825 -97.707384) (xy 466.640957 -97.743059) (xy 466.593351 -97.772113)
			(xy 466.542022 -97.793925) (xy 466.488065 -97.808031) (xy 466.432628 -97.814131) (xy 466.376894 -97.812094)
			(xy 466.322051 -97.801964) (xy 466.269267 -97.783957) (xy 466.219667 -97.758456) (xy 466.174309 -97.726005)
			(xy 466.13416 -97.687296) (xy 466.100074 -97.643153) (xy 466.072778 -97.594518) (xy 466.052855 -97.542427)
			(xy 466.040729 -97.48799) (xy 466.036658 -97.432368) (xy 449.980516 -97.432368) (xy 449.971149 -97.452879)
			(xy 449.941683 -97.498729) (xy 449.905992 -97.53992) (xy 449.864801 -97.575611) (xy 449.818951 -97.605077)
			(xy 449.769374 -97.627719) (xy 449.717079 -97.643074) (xy 449.663131 -97.65083) (xy 449.608629 -97.65083)
			(xy 449.554681 -97.643074) (xy 449.502386 -97.627719) (xy 449.452809 -97.605077) (xy 449.406959 -97.575611)
			(xy 449.365768 -97.53992) (xy 449.330077 -97.498729) (xy 449.300611 -97.452879) (xy 449.277969 -97.403302)
			(xy 449.262614 -97.351007) (xy 449.254858 -97.297059) (xy 449.254372 -97.269808) (xy 449.254962 -97.240033)
			(xy 449.264277 -97.181215) (xy 449.272914 -97.152714) (xy 449.276856 -97.138846) (xy 449.277636 -97.110036)
			(xy 449.27035 -97.082152) (xy 449.255576 -97.057407) (xy 449.234487 -97.037765) (xy 449.208756 -97.024783)
			(xy 449.194682 -97.02165) (xy 449.168722 -97.016423) (xy 449.118494 -96.999641) (xy 449.071069 -96.976076)
			(xy 449.027357 -96.94618) (xy 448.988199 -96.910528) (xy 448.954347 -96.869804) (xy 448.92645 -96.82479)
			(xy 448.905045 -96.776352) (xy 448.890543 -96.725419) (xy 448.883222 -96.672971) (xy 448.88277 -96.646492)
			(xy 444.617394 -96.646492) (xy 444.616085 -96.655386) (xy 444.600017 -96.708793) (xy 444.576345 -96.75929)
			(xy 444.545572 -96.805803) (xy 444.508355 -96.84734) (xy 444.465487 -96.883015) (xy 444.417881 -96.912069)
			(xy 444.366552 -96.933881) (xy 444.312595 -96.947987) (xy 444.257158 -96.954087) (xy 444.201424 -96.95205)
			(xy 444.146581 -96.94192) (xy 444.093797 -96.923913) (xy 444.044197 -96.898412) (xy 443.998839 -96.865961)
			(xy 443.95869 -96.827252) (xy 443.924604 -96.783109) (xy 443.897308 -96.734474) (xy 443.877385 -96.682383)
			(xy 443.865259 -96.627946) (xy 443.861188 -96.572324) (xy 436.470149 -96.572324) (xy 436.476246 -96.579129)
			(xy 436.507019 -96.625642) (xy 436.530691 -96.676139) (xy 436.546759 -96.729546) (xy 436.554879 -96.784722)
			(xy 436.555388 -96.812608) (xy 436.554879 -96.840494) (xy 436.546759 -96.89567) (xy 436.530691 -96.949077)
			(xy 436.507019 -96.999574) (xy 436.476246 -97.046087) (xy 436.439029 -97.087624) (xy 436.396161 -97.123299)
			(xy 436.348555 -97.152353) (xy 436.297226 -97.174165) (xy 436.243269 -97.188271) (xy 436.187832 -97.194371)
			(xy 436.132098 -97.192334) (xy 436.077255 -97.182204) (xy 436.024471 -97.164197) (xy 435.974871 -97.138696)
			(xy 435.929513 -97.106245) (xy 435.889364 -97.067536) (xy 435.855278 -97.023393) (xy 435.827982 -96.974758)
			(xy 435.808059 -96.922667) (xy 435.795933 -96.86823) (xy 435.791862 -96.812608) (xy 435.666388 -96.812608)
			(xy 435.665879 -96.840494) (xy 435.657759 -96.89567) (xy 435.641691 -96.949077) (xy 435.618019 -96.999574)
			(xy 435.587246 -97.046087) (xy 435.550029 -97.087624) (xy 435.507161 -97.123299) (xy 435.459555 -97.152353)
			(xy 435.408226 -97.174165) (xy 435.354269 -97.188271) (xy 435.298832 -97.194371) (xy 435.243098 -97.192334)
			(xy 435.188255 -97.182204) (xy 435.135471 -97.164197) (xy 435.085871 -97.138696) (xy 435.040513 -97.106245)
			(xy 435.000364 -97.067536) (xy 434.966278 -97.023393) (xy 434.938982 -96.974758) (xy 434.919059 -96.922667)
			(xy 434.906933 -96.86823) (xy 434.902862 -96.812608) (xy 418.439854 -96.812608) (xy 418.439854 -97.701608)
			(xy 434.902862 -97.701608) (xy 434.906933 -97.645986) (xy 434.919059 -97.591549) (xy 434.938982 -97.539458)
			(xy 434.966278 -97.490823) (xy 435.000364 -97.44668) (xy 435.040513 -97.407971) (xy 435.085871 -97.37552)
			(xy 435.135471 -97.350019) (xy 435.188255 -97.332012) (xy 435.243098 -97.321882) (xy 435.298832 -97.319845)
			(xy 435.354269 -97.325945) (xy 435.408226 -97.340051) (xy 435.459555 -97.361863) (xy 435.507161 -97.390917)
			(xy 435.550029 -97.426592) (xy 435.587246 -97.468129) (xy 435.618019 -97.514642) (xy 435.641691 -97.565139)
			(xy 435.657759 -97.618546) (xy 435.665879 -97.673722) (xy 435.666388 -97.701608) (xy 435.791862 -97.701608)
			(xy 435.795933 -97.645986) (xy 435.808059 -97.591549) (xy 435.827982 -97.539458) (xy 435.855278 -97.490823)
			(xy 435.889364 -97.44668) (xy 435.929513 -97.407971) (xy 435.974871 -97.37552) (xy 436.024471 -97.350019)
			(xy 436.077255 -97.332012) (xy 436.132098 -97.321882) (xy 436.187832 -97.319845) (xy 436.243269 -97.325945)
			(xy 436.297226 -97.340051) (xy 436.348555 -97.361863) (xy 436.396161 -97.390917) (xy 436.439029 -97.426592)
			(xy 436.460135 -97.450148) (xy 437.894982 -97.450148) (xy 437.899053 -97.394526) (xy 437.911179 -97.340089)
			(xy 437.931102 -97.287998) (xy 437.958398 -97.239363) (xy 437.992484 -97.19522) (xy 438.032633 -97.156511)
			(xy 438.077991 -97.12406) (xy 438.127591 -97.098559) (xy 438.180375 -97.080552) (xy 438.235218 -97.070422)
			(xy 438.290952 -97.068385) (xy 438.346389 -97.074485) (xy 438.400346 -97.088591) (xy 438.451675 -97.110403)
			(xy 438.499281 -97.139457) (xy 438.542149 -97.175132) (xy 438.579366 -97.216669) (xy 438.60444 -97.254568)
			(xy 442.690502 -97.254568) (xy 442.694573 -97.198946) (xy 442.706699 -97.144509) (xy 442.726622 -97.092418)
			(xy 442.753918 -97.043783) (xy 442.788004 -96.99964) (xy 442.828153 -96.960931) (xy 442.873511 -96.92848)
			(xy 442.923111 -96.902979) (xy 442.975895 -96.884972) (xy 443.030738 -96.874842) (xy 443.086472 -96.872805)
			(xy 443.141909 -96.878905) (xy 443.195866 -96.893011) (xy 443.247195 -96.914823) (xy 443.294801 -96.943877)
			(xy 443.337669 -96.979552) (xy 443.374886 -97.021089) (xy 443.405659 -97.067602) (xy 443.429331 -97.118099)
			(xy 443.445399 -97.171506) (xy 443.453519 -97.226682) (xy 443.454028 -97.254568) (xy 443.453519 -97.282454)
			(xy 443.445399 -97.33763) (xy 443.429331 -97.391037) (xy 443.405659 -97.441534) (xy 443.374886 -97.488047)
			(xy 443.337669 -97.529584) (xy 443.294801 -97.565259) (xy 443.247195 -97.594313) (xy 443.195866 -97.616125)
			(xy 443.141909 -97.630231) (xy 443.086472 -97.636331) (xy 443.030738 -97.634294) (xy 442.975895 -97.624164)
			(xy 442.923111 -97.606157) (xy 442.873511 -97.580656) (xy 442.828153 -97.548205) (xy 442.788004 -97.509496)
			(xy 442.753918 -97.465353) (xy 442.726622 -97.416718) (xy 442.706699 -97.364627) (xy 442.694573 -97.31019)
			(xy 442.690502 -97.254568) (xy 438.60444 -97.254568) (xy 438.610139 -97.263182) (xy 438.633811 -97.313679)
			(xy 438.649879 -97.367086) (xy 438.657999 -97.422262) (xy 438.658508 -97.450148) (xy 438.657999 -97.478034)
			(xy 438.649879 -97.53321) (xy 438.633811 -97.586617) (xy 438.610139 -97.637114) (xy 438.579366 -97.683627)
			(xy 438.542149 -97.725164) (xy 438.499281 -97.760839) (xy 438.451675 -97.789893) (xy 438.400346 -97.811705)
			(xy 438.346389 -97.825811) (xy 438.290952 -97.831911) (xy 438.235218 -97.829874) (xy 438.180375 -97.819744)
			(xy 438.127591 -97.801737) (xy 438.077991 -97.776236) (xy 438.032633 -97.743785) (xy 437.992484 -97.705076)
			(xy 437.958398 -97.660933) (xy 437.931102 -97.612298) (xy 437.911179 -97.560207) (xy 437.899053 -97.50577)
			(xy 437.894982 -97.450148) (xy 436.460135 -97.450148) (xy 436.476246 -97.468129) (xy 436.507019 -97.514642)
			(xy 436.530691 -97.565139) (xy 436.546759 -97.618546) (xy 436.554879 -97.673722) (xy 436.555388 -97.701608)
			(xy 436.554879 -97.729494) (xy 436.546759 -97.78467) (xy 436.530691 -97.838077) (xy 436.507019 -97.888574)
			(xy 436.476246 -97.935087) (xy 436.439029 -97.976624) (xy 436.396161 -98.012299) (xy 436.348555 -98.041353)
			(xy 436.297226 -98.063165) (xy 436.243269 -98.077271) (xy 436.187832 -98.083371) (xy 436.132098 -98.081334)
			(xy 436.077255 -98.071204) (xy 436.024471 -98.053197) (xy 435.974871 -98.027696) (xy 435.929513 -97.995245)
			(xy 435.889364 -97.956536) (xy 435.855278 -97.912393) (xy 435.827982 -97.863758) (xy 435.808059 -97.811667)
			(xy 435.795933 -97.75723) (xy 435.791862 -97.701608) (xy 435.666388 -97.701608) (xy 435.665879 -97.729494)
			(xy 435.657759 -97.78467) (xy 435.641691 -97.838077) (xy 435.618019 -97.888574) (xy 435.587246 -97.935087)
			(xy 435.550029 -97.976624) (xy 435.507161 -98.012299) (xy 435.459555 -98.041353) (xy 435.408226 -98.063165)
			(xy 435.354269 -98.077271) (xy 435.298832 -98.083371) (xy 435.243098 -98.081334) (xy 435.188255 -98.071204)
			(xy 435.135471 -98.053197) (xy 435.085871 -98.027696) (xy 435.040513 -97.995245) (xy 435.000364 -97.956536)
			(xy 434.966278 -97.912393) (xy 434.938982 -97.863758) (xy 434.919059 -97.811667) (xy 434.906933 -97.75723)
			(xy 434.902862 -97.701608) (xy 418.439854 -97.701608) (xy 418.439854 -98.180144) (xy 454.657458 -98.180144)
			(xy 454.661529 -98.124522) (xy 454.673655 -98.070085) (xy 454.693578 -98.017994) (xy 454.720874 -97.969359)
			(xy 454.75496 -97.925216) (xy 454.795109 -97.886507) (xy 454.840467 -97.854056) (xy 454.890067 -97.828555)
			(xy 454.942851 -97.810548) (xy 454.997694 -97.800418) (xy 455.053428 -97.798381) (xy 455.108865 -97.804481)
			(xy 455.162822 -97.818587) (xy 455.214151 -97.840399) (xy 455.261757 -97.869453) (xy 455.304625 -97.905128)
			(xy 455.341842 -97.946665) (xy 455.372615 -97.993178) (xy 455.396287 -98.043675) (xy 455.412355 -98.097082)
			(xy 455.420475 -98.152258) (xy 455.420984 -98.180144) (xy 455.420475 -98.20803) (xy 455.412355 -98.263206)
			(xy 455.396287 -98.316613) (xy 455.38488 -98.340946) (xy 456.905426 -98.340946) (xy 456.905426 -98.286454)
			(xy 456.913181 -98.232517) (xy 456.928532 -98.180232) (xy 456.951167 -98.130663) (xy 456.980626 -98.084821)
			(xy 457.016309 -98.043637) (xy 457.057489 -98.00795) (xy 457.103328 -97.978486) (xy 457.152894 -97.955846)
			(xy 457.205178 -97.940489) (xy 457.259114 -97.932729) (xy 457.28636 -97.93224) (xy 457.309885 -97.932554)
			(xy 457.356583 -97.938281) (xy 457.402218 -97.949727) (xy 457.424282 -97.957894) (xy 457.437571 -97.962579)
			(xy 457.465619 -97.965171) (xy 457.493308 -97.959999) (xy 457.51853 -97.947457) (xy 457.539363 -97.928499)
			(xy 457.554222 -97.904569) (xy 457.561975 -97.877489) (xy 457.562458 -97.863406) (xy 457.563069 -97.836205)
			(xy 457.570939 -97.782371) (xy 457.586377 -97.730201) (xy 457.609071 -97.680754) (xy 457.638559 -97.635033)
			(xy 457.674244 -97.593965) (xy 457.715402 -97.558383) (xy 457.761197 -97.52901) (xy 457.810701 -97.506441)
			(xy 457.86291 -97.491134) (xy 457.916763 -97.483399) (xy 457.943966 -97.482914) (xy 457.971222 -97.483331)
			(xy 458.02518 -97.491084) (xy 458.077485 -97.506438) (xy 458.127072 -97.52908) (xy 458.172932 -97.558549)
			(xy 458.214131 -97.594245) (xy 458.249831 -97.635441) (xy 458.279304 -97.681298) (xy 458.30195 -97.730883)
			(xy 458.317309 -97.783187) (xy 458.325067 -97.837144) (xy 458.325067 -97.891656) (xy 458.317309 -97.945613)
			(xy 458.30195 -97.997917) (xy 458.279304 -98.047502) (xy 458.249831 -98.093359) (xy 458.214131 -98.134555)
			(xy 458.172932 -98.170251) (xy 458.127072 -98.19972) (xy 458.077485 -98.222362) (xy 458.02518 -98.237716)
			(xy 457.971222 -98.245469) (xy 457.943966 -98.24593) (xy 457.920442 -98.245604) (xy 457.873744 -98.239881)
			(xy 457.828108 -98.22844) (xy 457.806044 -98.220276) (xy 457.792738 -98.21565) (xy 457.764699 -98.213054)
			(xy 457.737019 -98.218219) (xy 457.711803 -98.230752) (xy 457.690972 -98.249699) (xy 457.676113 -98.273617)
			(xy 457.668355 -98.300686) (xy 457.667868 -98.314764) (xy 457.667396 -98.341971) (xy 457.659515 -98.395814)
			(xy 457.644064 -98.44799) (xy 457.621357 -98.497442) (xy 457.591854 -98.543167) (xy 457.556154 -98.584236)
			(xy 457.514982 -98.619817) (xy 457.469172 -98.649187) (xy 457.419655 -98.671751) (xy 457.367433 -98.687051)
			(xy 457.313568 -98.694776) (xy 457.28636 -98.695256) (xy 457.259114 -98.694671) (xy 457.205178 -98.686911)
			(xy 457.152894 -98.671554) (xy 457.103328 -98.648914) (xy 457.057489 -98.61945) (xy 457.016309 -98.583763)
			(xy 456.980626 -98.542579) (xy 456.951167 -98.496737) (xy 456.928532 -98.447168) (xy 456.913181 -98.394883)
			(xy 456.905426 -98.340946) (xy 455.38488 -98.340946) (xy 455.372615 -98.36711) (xy 455.341842 -98.413623)
			(xy 455.304625 -98.45516) (xy 455.261757 -98.490835) (xy 455.214151 -98.519889) (xy 455.162822 -98.541701)
			(xy 455.108865 -98.555807) (xy 455.053428 -98.561907) (xy 454.997694 -98.55987) (xy 454.942851 -98.54974)
			(xy 454.890067 -98.531733) (xy 454.840467 -98.506232) (xy 454.795109 -98.473781) (xy 454.75496 -98.435072)
			(xy 454.720874 -98.390929) (xy 454.693578 -98.342294) (xy 454.673655 -98.290203) (xy 454.661529 -98.235766)
			(xy 454.657458 -98.180144) (xy 418.439854 -98.180144) (xy 418.439854 -98.379788) (xy 418.229034 -98.590608)
			(xy 434.902862 -98.590608) (xy 434.906933 -98.534986) (xy 434.919059 -98.480549) (xy 434.938982 -98.428458)
			(xy 434.966278 -98.379823) (xy 435.000364 -98.33568) (xy 435.040513 -98.296971) (xy 435.085871 -98.26452)
			(xy 435.135471 -98.239019) (xy 435.188255 -98.221012) (xy 435.243098 -98.210882) (xy 435.298832 -98.208845)
			(xy 435.354269 -98.214945) (xy 435.408226 -98.229051) (xy 435.459555 -98.250863) (xy 435.507161 -98.279917)
			(xy 435.550029 -98.315592) (xy 435.587246 -98.357129) (xy 435.618019 -98.403642) (xy 435.641691 -98.454139)
			(xy 435.657759 -98.507546) (xy 435.665879 -98.562722) (xy 435.666388 -98.590608) (xy 435.791862 -98.590608)
			(xy 435.795933 -98.534986) (xy 435.808059 -98.480549) (xy 435.827982 -98.428458) (xy 435.855278 -98.379823)
			(xy 435.889364 -98.33568) (xy 435.929513 -98.296971) (xy 435.974871 -98.26452) (xy 436.024471 -98.239019)
			(xy 436.077255 -98.221012) (xy 436.132098 -98.210882) (xy 436.187832 -98.208845) (xy 436.243269 -98.214945)
			(xy 436.297226 -98.229051) (xy 436.348555 -98.250863) (xy 436.396161 -98.279917) (xy 436.439029 -98.315592)
			(xy 436.476246 -98.357129) (xy 436.507019 -98.403642) (xy 436.530691 -98.454139) (xy 436.546759 -98.507546)
			(xy 436.554879 -98.562722) (xy 436.555388 -98.590608) (xy 436.554879 -98.618494) (xy 436.546759 -98.67367)
			(xy 436.530691 -98.727077) (xy 436.507019 -98.777574) (xy 436.476246 -98.824087) (xy 436.439029 -98.865624)
			(xy 436.396161 -98.901299) (xy 436.348555 -98.930353) (xy 436.297226 -98.952165) (xy 436.243269 -98.966271)
			(xy 436.187832 -98.972371) (xy 436.132098 -98.970334) (xy 436.077255 -98.960204) (xy 436.024471 -98.942197)
			(xy 435.974871 -98.916696) (xy 435.929513 -98.884245) (xy 435.889364 -98.845536) (xy 435.855278 -98.801393)
			(xy 435.827982 -98.752758) (xy 435.808059 -98.700667) (xy 435.795933 -98.64623) (xy 435.791862 -98.590608)
			(xy 435.666388 -98.590608) (xy 435.665879 -98.618494) (xy 435.657759 -98.67367) (xy 435.641691 -98.727077)
			(xy 435.618019 -98.777574) (xy 435.587246 -98.824087) (xy 435.550029 -98.865624) (xy 435.507161 -98.901299)
			(xy 435.459555 -98.930353) (xy 435.408226 -98.952165) (xy 435.354269 -98.966271) (xy 435.298832 -98.972371)
			(xy 435.243098 -98.970334) (xy 435.188255 -98.960204) (xy 435.135471 -98.942197) (xy 435.085871 -98.916696)
			(xy 435.040513 -98.884245) (xy 435.000364 -98.845536) (xy 434.966278 -98.801393) (xy 434.938982 -98.752758)
			(xy 434.919059 -98.700667) (xy 434.906933 -98.64623) (xy 434.902862 -98.590608) (xy 418.229034 -98.590608)
			(xy 417.340034 -99.479608) (xy 434.902862 -99.479608) (xy 434.906933 -99.423986) (xy 434.919059 -99.369549)
			(xy 434.938982 -99.317458) (xy 434.966278 -99.268823) (xy 435.000364 -99.22468) (xy 435.040513 -99.185971)
			(xy 435.085871 -99.15352) (xy 435.135471 -99.128019) (xy 435.188255 -99.110012) (xy 435.243098 -99.099882)
			(xy 435.298832 -99.097845) (xy 435.354269 -99.103945) (xy 435.408226 -99.118051) (xy 435.459555 -99.139863)
			(xy 435.507161 -99.168917) (xy 435.550029 -99.204592) (xy 435.587246 -99.246129) (xy 435.618019 -99.292642)
			(xy 435.641691 -99.343139) (xy 435.657759 -99.396546) (xy 435.665879 -99.451722) (xy 435.666388 -99.479608)
			(xy 435.791862 -99.479608) (xy 435.795933 -99.423986) (xy 435.808059 -99.369549) (xy 435.827982 -99.317458)
			(xy 435.855278 -99.268823) (xy 435.889364 -99.22468) (xy 435.929513 -99.185971) (xy 435.974871 -99.15352)
			(xy 436.024471 -99.128019) (xy 436.077255 -99.110012) (xy 436.132098 -99.099882) (xy 436.187832 -99.097845)
			(xy 436.243269 -99.103945) (xy 436.297226 -99.118051) (xy 436.348555 -99.139863) (xy 436.396161 -99.168917)
			(xy 436.439029 -99.204592) (xy 436.450577 -99.21748) (xy 438.989722 -99.21748) (xy 438.993793 -99.161858)
			(xy 439.005919 -99.107421) (xy 439.025842 -99.05533) (xy 439.053138 -99.006695) (xy 439.087224 -98.962552)
			(xy 439.127373 -98.923843) (xy 439.172731 -98.891392) (xy 439.222331 -98.865891) (xy 439.275115 -98.847884)
			(xy 439.329958 -98.837754) (xy 439.385692 -98.835717) (xy 439.441129 -98.841817) (xy 439.495086 -98.855923)
			(xy 439.546415 -98.877735) (xy 439.594021 -98.906789) (xy 439.636889 -98.942464) (xy 439.674106 -98.984001)
			(xy 439.704879 -99.030514) (xy 439.728551 -99.081011) (xy 439.744619 -99.134418) (xy 439.752739 -99.189594)
			(xy 439.753248 -99.21748) (xy 440.983622 -99.21748) (xy 440.987693 -99.161858) (xy 440.999819 -99.107421)
			(xy 441.019742 -99.05533) (xy 441.047038 -99.006695) (xy 441.081124 -98.962552) (xy 441.121273 -98.923843)
			(xy 441.166631 -98.891392) (xy 441.216231 -98.865891) (xy 441.269015 -98.847884) (xy 441.323858 -98.837754)
			(xy 441.379592 -98.835717) (xy 441.435029 -98.841817) (xy 441.488986 -98.855923) (xy 441.540315 -98.877735)
			(xy 441.587921 -98.906789) (xy 441.630789 -98.942464) (xy 441.668006 -98.984001) (xy 441.698779 -99.030514)
			(xy 441.722451 -99.081011) (xy 441.738519 -99.134418) (xy 441.746639 -99.189594) (xy 441.747148 -99.21748)
			(xy 441.746639 -99.245366) (xy 441.738519 -99.300542) (xy 441.722451 -99.353949) (xy 441.698779 -99.404446)
			(xy 441.668006 -99.450959) (xy 441.630789 -99.492496) (xy 441.587921 -99.528171) (xy 441.540315 -99.557225)
			(xy 441.488986 -99.579037) (xy 441.435029 -99.593143) (xy 441.379592 -99.599243) (xy 441.323858 -99.597206)
			(xy 441.269015 -99.587076) (xy 441.216231 -99.569069) (xy 441.166631 -99.543568) (xy 441.121273 -99.511117)
			(xy 441.081124 -99.472408) (xy 441.047038 -99.428265) (xy 441.019742 -99.37963) (xy 440.999819 -99.327539)
			(xy 440.987693 -99.273102) (xy 440.983622 -99.21748) (xy 439.753248 -99.21748) (xy 439.752739 -99.245366)
			(xy 439.744619 -99.300542) (xy 439.728551 -99.353949) (xy 439.704879 -99.404446) (xy 439.674106 -99.450959)
			(xy 439.636889 -99.492496) (xy 439.594021 -99.528171) (xy 439.546415 -99.557225) (xy 439.495086 -99.579037)
			(xy 439.441129 -99.593143) (xy 439.385692 -99.599243) (xy 439.329958 -99.597206) (xy 439.275115 -99.587076)
			(xy 439.222331 -99.569069) (xy 439.172731 -99.543568) (xy 439.127373 -99.511117) (xy 439.087224 -99.472408)
			(xy 439.053138 -99.428265) (xy 439.025842 -99.37963) (xy 439.005919 -99.327539) (xy 438.993793 -99.273102)
			(xy 438.989722 -99.21748) (xy 436.450577 -99.21748) (xy 436.476246 -99.246129) (xy 436.507019 -99.292642)
			(xy 436.530691 -99.343139) (xy 436.546759 -99.396546) (xy 436.554879 -99.451722) (xy 436.555388 -99.479608)
			(xy 436.554879 -99.507494) (xy 436.546759 -99.56267) (xy 436.530691 -99.616077) (xy 436.507019 -99.666574)
			(xy 436.476246 -99.713087) (xy 436.439029 -99.754624) (xy 436.396161 -99.790299) (xy 436.348555 -99.819353)
			(xy 436.297226 -99.841165) (xy 436.243269 -99.855271) (xy 436.187832 -99.861371) (xy 436.132098 -99.859334)
			(xy 436.077255 -99.849204) (xy 436.024471 -99.831197) (xy 435.974871 -99.805696) (xy 435.929513 -99.773245)
			(xy 435.889364 -99.734536) (xy 435.855278 -99.690393) (xy 435.827982 -99.641758) (xy 435.808059 -99.589667)
			(xy 435.795933 -99.53523) (xy 435.791862 -99.479608) (xy 435.666388 -99.479608) (xy 435.665879 -99.507494)
			(xy 435.657759 -99.56267) (xy 435.641691 -99.616077) (xy 435.618019 -99.666574) (xy 435.587246 -99.713087)
			(xy 435.550029 -99.754624) (xy 435.507161 -99.790299) (xy 435.459555 -99.819353) (xy 435.408226 -99.841165)
			(xy 435.354269 -99.855271) (xy 435.298832 -99.861371) (xy 435.243098 -99.859334) (xy 435.188255 -99.849204)
			(xy 435.135471 -99.831197) (xy 435.085871 -99.805696) (xy 435.040513 -99.773245) (xy 435.000364 -99.734536)
			(xy 434.966278 -99.690393) (xy 434.938982 -99.641758) (xy 434.919059 -99.589667) (xy 434.906933 -99.53523)
			(xy 434.902862 -99.479608) (xy 417.340034 -99.479608) (xy 416.558984 -100.260658) (xy 419.380922 -100.260658)
			(xy 419.384993 -100.205036) (xy 419.397119 -100.150599) (xy 419.417042 -100.098508) (xy 419.444338 -100.049873)
			(xy 419.478424 -100.00573) (xy 419.518573 -99.967021) (xy 419.563931 -99.93457) (xy 419.613531 -99.909069)
			(xy 419.666315 -99.891062) (xy 419.721158 -99.880932) (xy 419.776892 -99.878895) (xy 419.832329 -99.884995)
			(xy 419.886286 -99.899101) (xy 419.937615 -99.920913) (xy 419.985221 -99.949967) (xy 420.028089 -99.985642)
			(xy 420.065306 -100.027179) (xy 420.096079 -100.073692) (xy 420.119751 -100.124189) (xy 420.135819 -100.177596)
			(xy 420.143939 -100.232772) (xy 420.144448 -100.260658) (xy 421.158922 -100.260658) (xy 421.162993 -100.205036)
			(xy 421.175119 -100.150599) (xy 421.195042 -100.098508) (xy 421.222338 -100.049873) (xy 421.256424 -100.00573)
			(xy 421.296573 -99.967021) (xy 421.341931 -99.93457) (xy 421.391531 -99.909069) (xy 421.444315 -99.891062)
			(xy 421.499158 -99.880932) (xy 421.554892 -99.878895) (xy 421.610329 -99.884995) (xy 421.664286 -99.899101)
			(xy 421.715615 -99.920913) (xy 421.763221 -99.949967) (xy 421.806089 -99.985642) (xy 421.843306 -100.027179)
			(xy 421.874079 -100.073692) (xy 421.897751 -100.124189) (xy 421.913819 -100.177596) (xy 421.921939 -100.232772)
			(xy 421.922448 -100.260658) (xy 422.174922 -100.260658) (xy 422.178993 -100.205036) (xy 422.191119 -100.150599)
			(xy 422.211042 -100.098508) (xy 422.238338 -100.049873) (xy 422.272424 -100.00573) (xy 422.312573 -99.967021)
			(xy 422.357931 -99.93457) (xy 422.407531 -99.909069) (xy 422.460315 -99.891062) (xy 422.515158 -99.880932)
			(xy 422.570892 -99.878895) (xy 422.626329 -99.884995) (xy 422.680286 -99.899101) (xy 422.731615 -99.920913)
			(xy 422.779221 -99.949967) (xy 422.822089 -99.985642) (xy 422.859306 -100.027179) (xy 422.890079 -100.073692)
			(xy 422.913751 -100.124189) (xy 422.929819 -100.177596) (xy 422.937939 -100.232772) (xy 422.938448 -100.260658)
			(xy 422.937939 -100.288544) (xy 422.929819 -100.34372) (xy 422.913751 -100.397127) (xy 422.890079 -100.447624)
			(xy 422.859306 -100.494137) (xy 422.822089 -100.535674) (xy 422.779221 -100.571349) (xy 422.731615 -100.600403)
			(xy 422.680286 -100.622215) (xy 422.626329 -100.636321) (xy 422.570892 -100.642421) (xy 422.515158 -100.640384)
			(xy 422.460315 -100.630254) (xy 422.407531 -100.612247) (xy 422.357931 -100.586746) (xy 422.312573 -100.554295)
			(xy 422.272424 -100.515586) (xy 422.238338 -100.471443) (xy 422.211042 -100.422808) (xy 422.191119 -100.370717)
			(xy 422.178993 -100.31628) (xy 422.174922 -100.260658) (xy 421.922448 -100.260658) (xy 421.921939 -100.288544)
			(xy 421.913819 -100.34372) (xy 421.897751 -100.397127) (xy 421.874079 -100.447624) (xy 421.843306 -100.494137)
			(xy 421.806089 -100.535674) (xy 421.763221 -100.571349) (xy 421.715615 -100.600403) (xy 421.664286 -100.622215)
			(xy 421.610329 -100.636321) (xy 421.554892 -100.642421) (xy 421.499158 -100.640384) (xy 421.444315 -100.630254)
			(xy 421.391531 -100.612247) (xy 421.341931 -100.586746) (xy 421.296573 -100.554295) (xy 421.256424 -100.515586)
			(xy 421.222338 -100.471443) (xy 421.195042 -100.422808) (xy 421.175119 -100.370717) (xy 421.162993 -100.31628)
			(xy 421.158922 -100.260658) (xy 420.144448 -100.260658) (xy 420.143939 -100.288544) (xy 420.135819 -100.34372)
			(xy 420.119751 -100.397127) (xy 420.096079 -100.447624) (xy 420.065306 -100.494137) (xy 420.028089 -100.535674)
			(xy 419.985221 -100.571349) (xy 419.937615 -100.600403) (xy 419.886286 -100.622215) (xy 419.832329 -100.636321)
			(xy 419.776892 -100.642421) (xy 419.721158 -100.640384) (xy 419.666315 -100.630254) (xy 419.613531 -100.612247)
			(xy 419.563931 -100.586746) (xy 419.518573 -100.554295) (xy 419.478424 -100.515586) (xy 419.444338 -100.471443)
			(xy 419.417042 -100.422808) (xy 419.397119 -100.370717) (xy 419.384993 -100.31628) (xy 419.380922 -100.260658)
			(xy 416.558984 -100.260658) (xy 415.476182 -101.34346) (xy 440.926218 -101.34346) (xy 440.930289 -101.287838)
			(xy 440.942415 -101.233401) (xy 440.962338 -101.18131) (xy 440.989634 -101.132675) (xy 441.02372 -101.088532)
			(xy 441.063869 -101.049823) (xy 441.109227 -101.017372) (xy 441.158827 -100.991871) (xy 441.211611 -100.973864)
			(xy 441.266454 -100.963734) (xy 441.322188 -100.961697) (xy 441.377625 -100.967797) (xy 441.431582 -100.981903)
			(xy 441.482911 -101.003715) (xy 441.530517 -101.032769) (xy 441.573385 -101.068444) (xy 441.606325 -101.105208)
			(xy 461.934558 -101.105208) (xy 461.938629 -101.049586) (xy 461.950755 -100.995149) (xy 461.970678 -100.943058)
			(xy 461.997974 -100.894423) (xy 462.03206 -100.85028) (xy 462.072209 -100.811571) (xy 462.117567 -100.77912)
			(xy 462.167167 -100.753619) (xy 462.219951 -100.735612) (xy 462.274794 -100.725482) (xy 462.330528 -100.723445)
			(xy 462.385965 -100.729545) (xy 462.439922 -100.743651) (xy 462.491251 -100.765463) (xy 462.538857 -100.794517)
			(xy 462.581725 -100.830192) (xy 462.618942 -100.871729) (xy 462.649715 -100.918242) (xy 462.673387 -100.968739)
			(xy 462.689455 -101.022146) (xy 462.697575 -101.077322) (xy 462.698084 -101.105208) (xy 462.697575 -101.133094)
			(xy 462.689455 -101.18827) (xy 462.673387 -101.241677) (xy 462.649715 -101.292174) (xy 462.618942 -101.338687)
			(xy 462.581725 -101.380224) (xy 462.538857 -101.415899) (xy 462.491251 -101.444953) (xy 462.439922 -101.466765)
			(xy 462.385965 -101.480871) (xy 462.330528 -101.486971) (xy 462.274794 -101.484934) (xy 462.219951 -101.474804)
			(xy 462.167167 -101.456797) (xy 462.117567 -101.431296) (xy 462.072209 -101.398845) (xy 462.03206 -101.360136)
			(xy 461.997974 -101.315993) (xy 461.970678 -101.267358) (xy 461.950755 -101.215267) (xy 461.938629 -101.16083)
			(xy 461.934558 -101.105208) (xy 441.606325 -101.105208) (xy 441.610602 -101.109981) (xy 441.641375 -101.156494)
			(xy 441.665047 -101.206991) (xy 441.681115 -101.260398) (xy 441.689235 -101.315574) (xy 441.689744 -101.34346)
			(xy 441.689235 -101.371346) (xy 441.681115 -101.426522) (xy 441.665047 -101.479929) (xy 441.641375 -101.530426)
			(xy 441.610602 -101.576939) (xy 441.573385 -101.618476) (xy 441.530517 -101.654151) (xy 441.482911 -101.683205)
			(xy 441.431582 -101.705017) (xy 441.377625 -101.719123) (xy 441.322188 -101.725223) (xy 441.266454 -101.723186)
			(xy 441.211611 -101.713056) (xy 441.158827 -101.695049) (xy 441.109227 -101.669548) (xy 441.063869 -101.637097)
			(xy 441.02372 -101.598388) (xy 440.989634 -101.554245) (xy 440.962338 -101.50561) (xy 440.942415 -101.453519)
			(xy 440.930289 -101.399082) (xy 440.926218 -101.34346) (xy 415.476182 -101.34346) (xy 415.14522 -101.674422)
			(xy 415.14522 -102.61219) (xy 429.494948 -102.61219) (xy 429.499019 -102.556568) (xy 429.511145 -102.502131)
			(xy 429.531068 -102.45004) (xy 429.558364 -102.401405) (xy 429.59245 -102.357262) (xy 429.632599 -102.318553)
			(xy 429.677957 -102.286102) (xy 429.727557 -102.260601) (xy 429.780341 -102.242594) (xy 429.835184 -102.232464)
			(xy 429.890918 -102.230427) (xy 429.946355 -102.236527) (xy 430.000312 -102.250633) (xy 430.051641 -102.272445)
			(xy 430.099247 -102.301499) (xy 430.142115 -102.337174) (xy 430.179332 -102.378711) (xy 430.210105 -102.425224)
			(xy 430.233777 -102.475721) (xy 430.249845 -102.529128) (xy 430.257965 -102.584304) (xy 430.258474 -102.61219)
			(xy 430.257965 -102.640076) (xy 430.252425 -102.677722) (xy 432.170078 -102.677722) (xy 432.170564 -102.650471)
			(xy 432.17832 -102.596523) (xy 432.193675 -102.544228) (xy 432.216317 -102.494651) (xy 432.245783 -102.448801)
			(xy 432.281474 -102.40761) (xy 432.322665 -102.371919) (xy 432.368515 -102.342453) (xy 432.418092 -102.319811)
			(xy 432.470387 -102.304456) (xy 432.524335 -102.2967) (xy 432.578837 -102.2967) (xy 432.632785 -102.304456)
			(xy 432.68508 -102.319811) (xy 432.734657 -102.342453) (xy 432.780507 -102.371919) (xy 432.821698 -102.40761)
			(xy 432.857389 -102.448801) (xy 432.886855 -102.494651) (xy 432.909497 -102.544228) (xy 432.924852 -102.596523)
			(xy 432.925169 -102.598728) (xy 454.91476 -102.598728) (xy 454.918831 -102.543106) (xy 454.930957 -102.488669)
			(xy 454.95088 -102.436578) (xy 454.978176 -102.387943) (xy 455.012262 -102.3438) (xy 455.052411 -102.305091)
			(xy 455.097769 -102.27264) (xy 455.147369 -102.247139) (xy 455.200153 -102.229132) (xy 455.254996 -102.219002)
			(xy 455.31073 -102.216965) (xy 455.366167 -102.223065) (xy 455.420124 -102.237171) (xy 455.471453 -102.258983)
			(xy 455.519059 -102.288037) (xy 455.561927 -102.323712) (xy 455.599144 -102.365249) (xy 455.629917 -102.411762)
			(xy 455.653589 -102.462259) (xy 455.669657 -102.515666) (xy 455.677777 -102.570842) (xy 455.678286 -102.598728)
			(xy 455.677777 -102.626614) (xy 455.669657 -102.68179) (xy 455.653589 -102.735197) (xy 455.629917 -102.785694)
			(xy 455.599144 -102.832207) (xy 455.561927 -102.873744) (xy 455.519059 -102.909419) (xy 455.471453 -102.938473)
			(xy 455.420124 -102.960285) (xy 455.366167 -102.974391) (xy 455.31073 -102.980491) (xy 455.254996 -102.978454)
			(xy 455.200153 -102.968324) (xy 455.147369 -102.950317) (xy 455.097769 -102.924816) (xy 455.052411 -102.892365)
			(xy 455.012262 -102.853656) (xy 454.978176 -102.809513) (xy 454.95088 -102.760878) (xy 454.930957 -102.708787)
			(xy 454.918831 -102.65435) (xy 454.91476 -102.598728) (xy 432.925169 -102.598728) (xy 432.932608 -102.650471)
			(xy 432.933094 -102.677722) (xy 432.932429 -102.709434) (xy 432.921911 -102.771982) (xy 432.901216 -102.831937)
			(xy 432.886612 -102.860094) (xy 432.880202 -102.872935) (xy 432.87402 -102.900946) (xy 432.875883 -102.929571)
			(xy 432.885645 -102.956544) (xy 432.902533 -102.979732) (xy 432.92521 -102.997299) (xy 432.951882 -103.007855)
			(xy 432.966114 -103.0097) (xy 432.991746 -103.012642) (xy 433.04194 -103.024582) (xy 433.090069 -103.043172)
			(xy 433.135256 -103.068076) (xy 433.176676 -103.098838) (xy 433.213577 -103.134899) (xy 433.229766 -103.154988)
			(xy 433.239663 -103.166793) (xy 433.264987 -103.184312) (xy 433.29438 -103.193488) (xy 433.325172 -103.193488)
			(xy 433.354565 -103.184312) (xy 433.379889 -103.166793) (xy 433.389786 -103.154988) (xy 433.407982 -103.132509)
			(xy 433.450001 -103.092774) (xy 433.497535 -103.059835) (xy 433.549495 -103.034446) (xy 433.604692 -103.017188)
			(xy 433.66186 -103.008458) (xy 433.690776 -103.007922) (xy 433.718032 -103.008323) (xy 433.77199 -103.016078)
			(xy 433.824295 -103.031433) (xy 433.873882 -103.054076) (xy 433.919742 -103.083546) (xy 433.960941 -103.119242)
			(xy 433.99664 -103.160439) (xy 434.026112 -103.206297) (xy 434.028896 -103.212392) (xy 464.294218 -103.212392)
			(xy 464.298289 -103.15677) (xy 464.310415 -103.102333) (xy 464.330338 -103.050242) (xy 464.357634 -103.001607)
			(xy 464.39172 -102.957464) (xy 464.431869 -102.918755) (xy 464.477227 -102.886304) (xy 464.526827 -102.860803)
			(xy 464.579611 -102.842796) (xy 464.634454 -102.832666) (xy 464.690188 -102.830629) (xy 464.745625 -102.836729)
			(xy 464.799582 -102.850835) (xy 464.850911 -102.872647) (xy 464.898517 -102.901701) (xy 464.941385 -102.937376)
			(xy 464.978602 -102.978913) (xy 465.009375 -103.025426) (xy 465.033047 -103.075923) (xy 465.049115 -103.12933)
			(xy 465.057235 -103.184506) (xy 465.057744 -103.212392) (xy 465.057308 -103.236268) (xy 465.606382 -103.236268)
			(xy 465.610453 -103.180646) (xy 465.622579 -103.126209) (xy 465.642502 -103.074118) (xy 465.669798 -103.025483)
			(xy 465.703884 -102.98134) (xy 465.744033 -102.942631) (xy 465.789391 -102.91018) (xy 465.838991 -102.884679)
			(xy 465.891775 -102.866672) (xy 465.946618 -102.856542) (xy 466.002352 -102.854505) (xy 466.057789 -102.860605)
			(xy 466.111746 -102.874711) (xy 466.163075 -102.896523) (xy 466.210681 -102.925577) (xy 466.253549 -102.961252)
			(xy 466.290766 -103.002789) (xy 466.321539 -103.049302) (xy 466.345211 -103.099799) (xy 466.361279 -103.153206)
			(xy 466.369399 -103.208382) (xy 466.369908 -103.236268) (xy 466.369399 -103.264154) (xy 466.361279 -103.31933)
			(xy 466.345211 -103.372737) (xy 466.321539 -103.423234) (xy 466.290766 -103.469747) (xy 466.253549 -103.511284)
			(xy 466.210681 -103.546959) (xy 466.163075 -103.576013) (xy 466.111746 -103.597825) (xy 466.057789 -103.611931)
			(xy 466.002352 -103.618031) (xy 465.946618 -103.615994) (xy 465.891775 -103.605864) (xy 465.838991 -103.587857)
			(xy 465.789391 -103.562356) (xy 465.744033 -103.529905) (xy 465.703884 -103.491196) (xy 465.669798 -103.447053)
			(xy 465.642502 -103.398418) (xy 465.622579 -103.346327) (xy 465.610453 -103.29189) (xy 465.606382 -103.236268)
			(xy 465.057308 -103.236268) (xy 465.057235 -103.240278) (xy 465.049115 -103.295454) (xy 465.033047 -103.348861)
			(xy 465.009375 -103.399358) (xy 464.978602 -103.445871) (xy 464.941385 -103.487408) (xy 464.898517 -103.523083)
			(xy 464.850911 -103.552137) (xy 464.799582 -103.573949) (xy 464.745625 -103.588055) (xy 464.690188 -103.594155)
			(xy 464.634454 -103.592118) (xy 464.579611 -103.581988) (xy 464.526827 -103.563981) (xy 464.477227 -103.53848)
			(xy 464.431869 -103.506029) (xy 464.39172 -103.46732) (xy 464.357634 -103.423177) (xy 464.330338 -103.374542)
			(xy 464.310415 -103.322451) (xy 464.298289 -103.268014) (xy 464.294218 -103.212392) (xy 434.028896 -103.212392)
			(xy 434.048758 -103.255883) (xy 434.064117 -103.308187) (xy 434.071875 -103.362144) (xy 434.071875 -103.416656)
			(xy 434.064117 -103.470613) (xy 434.048758 -103.522917) (xy 434.026112 -103.572503) (xy 433.99664 -103.618361)
			(xy 433.972495 -103.646224) (xy 455.669648 -103.646224) (xy 455.673719 -103.590602) (xy 455.685845 -103.536165)
			(xy 455.705768 -103.484074) (xy 455.733064 -103.435439) (xy 455.76715 -103.391296) (xy 455.807299 -103.352587)
			(xy 455.852657 -103.320136) (xy 455.902257 -103.294635) (xy 455.955041 -103.276628) (xy 456.009884 -103.266498)
			(xy 456.065618 -103.264461) (xy 456.121055 -103.270561) (xy 456.175012 -103.284667) (xy 456.226341 -103.306479)
			(xy 456.273947 -103.335533) (xy 456.316815 -103.371208) (xy 456.354032 -103.412745) (xy 456.384805 -103.459258)
			(xy 456.408477 -103.509755) (xy 456.424545 -103.563162) (xy 456.432665 -103.618338) (xy 456.433174 -103.646224)
			(xy 456.432665 -103.67411) (xy 456.424545 -103.729286) (xy 456.408477 -103.782693) (xy 456.384805 -103.83319)
			(xy 456.354032 -103.879703) (xy 456.316815 -103.92124) (xy 456.273947 -103.956915) (xy 456.226341 -103.985969)
			(xy 456.175012 -104.007781) (xy 456.121055 -104.021887) (xy 456.065618 -104.027987) (xy 456.009884 -104.02595)
			(xy 455.955041 -104.01582) (xy 455.902257 -103.997813) (xy 455.852657 -103.972312) (xy 455.807299 -103.939861)
			(xy 455.76715 -103.901152) (xy 455.733064 -103.857009) (xy 455.705768 -103.808374) (xy 455.685845 -103.756283)
			(xy 455.673719 -103.701846) (xy 455.669648 -103.646224) (xy 433.972495 -103.646224) (xy 433.960941 -103.659558)
			(xy 433.919742 -103.695254) (xy 433.873882 -103.724724) (xy 433.824295 -103.747367) (xy 433.77199 -103.762722)
			(xy 433.718032 -103.770477) (xy 433.690776 -103.770938) (xy 433.66186 -103.770388) (xy 433.604689 -103.761669)
			(xy 433.54949 -103.744419) (xy 433.497528 -103.719033) (xy 433.449993 -103.686094) (xy 433.407976 -103.646356)
			(xy 433.389786 -103.623872) (xy 433.379889 -103.612067) (xy 433.354565 -103.594548) (xy 433.325172 -103.585372)
			(xy 433.29438 -103.585372) (xy 433.264987 -103.594548) (xy 433.239663 -103.612067) (xy 433.229766 -103.623872)
			(xy 433.211587 -103.646366) (xy 433.169566 -103.686102) (xy 433.122029 -103.71904) (xy 433.070065 -103.744427)
			(xy 433.014865 -103.761681) (xy 432.957693 -103.770406) (xy 432.928776 -103.770938) (xy 432.901526 -103.770445)
			(xy 432.84758 -103.762686) (xy 432.795287 -103.747329) (xy 432.745712 -103.724687) (xy 432.699863 -103.695221)
			(xy 432.658674 -103.659531) (xy 432.622982 -103.618342) (xy 432.593516 -103.572494) (xy 432.570873 -103.522919)
			(xy 432.555516 -103.470626) (xy 432.547756 -103.41668) (xy 432.547268 -103.38943) (xy 432.547919 -103.357717)
			(xy 432.558443 -103.295169) (xy 432.579144 -103.235215) (xy 432.59375 -103.207058) (xy 432.600171 -103.194225)
			(xy 432.606338 -103.166213) (xy 432.604464 -103.137592) (xy 432.594699 -103.110624) (xy 432.577814 -103.087439)
			(xy 432.555143 -103.069869) (xy 432.528478 -103.059304) (xy 432.514248 -103.057452) (xy 432.48632 -103.054223)
			(xy 432.431787 -103.040557) (xy 432.37985 -103.019038) (xy 432.331631 -102.990132) (xy 432.288175 -102.954464)
			(xy 432.250422 -102.912807) (xy 432.219189 -102.866062) (xy 432.195152 -102.81524) (xy 432.178831 -102.761442)
			(xy 432.17058 -102.705832) (xy 432.170078 -102.677722) (xy 430.252425 -102.677722) (xy 430.249845 -102.695252)
			(xy 430.233777 -102.748659) (xy 430.210105 -102.799156) (xy 430.179332 -102.845669) (xy 430.142115 -102.887206)
			(xy 430.099247 -102.922881) (xy 430.051641 -102.951935) (xy 430.000312 -102.973747) (xy 429.946355 -102.987853)
			(xy 429.890918 -102.993953) (xy 429.835184 -102.991916) (xy 429.780341 -102.981786) (xy 429.727557 -102.963779)
			(xy 429.677957 -102.938278) (xy 429.632599 -102.905827) (xy 429.59245 -102.867118) (xy 429.558364 -102.822975)
			(xy 429.531068 -102.77434) (xy 429.511145 -102.722249) (xy 429.499019 -102.667812) (xy 429.494948 -102.61219)
			(xy 415.14522 -102.61219) (xy 415.14522 -103.480108) (xy 419.431722 -103.480108) (xy 419.435793 -103.424486)
			(xy 419.447919 -103.370049) (xy 419.467842 -103.317958) (xy 419.495138 -103.269323) (xy 419.529224 -103.22518)
			(xy 419.569373 -103.186471) (xy 419.614731 -103.15402) (xy 419.664331 -103.128519) (xy 419.717115 -103.110512)
			(xy 419.771958 -103.100382) (xy 419.827692 -103.098345) (xy 419.883129 -103.104445) (xy 419.937086 -103.118551)
			(xy 419.988415 -103.140363) (xy 420.036021 -103.169417) (xy 420.078889 -103.205092) (xy 420.116106 -103.246629)
			(xy 420.136139 -103.276908) (xy 430.696876 -103.276908) (xy 430.700947 -103.221286) (xy 430.713073 -103.166849)
			(xy 430.732996 -103.114758) (xy 430.760292 -103.066123) (xy 430.794378 -103.02198) (xy 430.834527 -102.983271)
			(xy 430.879885 -102.95082) (xy 430.929485 -102.925319) (xy 430.982269 -102.907312) (xy 431.037112 -102.897182)
			(xy 431.092846 -102.895145) (xy 431.148283 -102.901245) (xy 431.20224 -102.915351) (xy 431.253569 -102.937163)
			(xy 431.301175 -102.966217) (xy 431.344043 -103.001892) (xy 431.38126 -103.043429) (xy 431.412033 -103.089942)
			(xy 431.435705 -103.140439) (xy 431.451773 -103.193846) (xy 431.459893 -103.249022) (xy 431.460402 -103.276908)
			(xy 431.459893 -103.304794) (xy 431.451773 -103.35997) (xy 431.435705 -103.413377) (xy 431.412033 -103.463874)
			(xy 431.38126 -103.510387) (xy 431.344043 -103.551924) (xy 431.301175 -103.587599) (xy 431.253569 -103.616653)
			(xy 431.20224 -103.638465) (xy 431.148283 -103.652571) (xy 431.092846 -103.658671) (xy 431.037112 -103.656634)
			(xy 430.982269 -103.646504) (xy 430.929485 -103.628497) (xy 430.879885 -103.602996) (xy 430.834527 -103.570545)
			(xy 430.794378 -103.531836) (xy 430.760292 -103.487693) (xy 430.732996 -103.439058) (xy 430.713073 -103.386967)
			(xy 430.700947 -103.33253) (xy 430.696876 -103.276908) (xy 420.136139 -103.276908) (xy 420.146879 -103.293142)
			(xy 420.170551 -103.343639) (xy 420.186619 -103.397046) (xy 420.194739 -103.452222) (xy 420.195248 -103.480108)
			(xy 420.194739 -103.507994) (xy 420.186619 -103.56317) (xy 420.170551 -103.616577) (xy 420.146879 -103.667074)
			(xy 420.116106 -103.713587) (xy 420.078889 -103.755124) (xy 420.036021 -103.790799) (xy 419.988415 -103.819853)
			(xy 419.937086 -103.841665) (xy 419.883129 -103.855771) (xy 419.827692 -103.861871) (xy 419.771958 -103.859834)
			(xy 419.717115 -103.849704) (xy 419.664331 -103.831697) (xy 419.614731 -103.806196) (xy 419.569373 -103.773745)
			(xy 419.529224 -103.735036) (xy 419.495138 -103.690893) (xy 419.467842 -103.642258) (xy 419.447919 -103.590167)
			(xy 419.435793 -103.53573) (xy 419.431722 -103.480108) (xy 415.14522 -103.480108) (xy 415.14522 -104.327452)
			(xy 433.394102 -104.327452) (xy 433.398173 -104.27183) (xy 433.410299 -104.217393) (xy 433.430222 -104.165302)
			(xy 433.457518 -104.116667) (xy 433.491604 -104.072524) (xy 433.531753 -104.033815) (xy 433.577111 -104.001364)
			(xy 433.626711 -103.975863) (xy 433.679495 -103.957856) (xy 433.734338 -103.947726) (xy 433.790072 -103.945689)
			(xy 433.845509 -103.951789) (xy 433.899466 -103.965895) (xy 433.950795 -103.987707) (xy 433.998401 -104.016761)
			(xy 434.041269 -104.052436) (xy 434.078486 -104.093973) (xy 434.109259 -104.140486) (xy 434.132931 -104.190983)
			(xy 434.148999 -104.24439) (xy 434.156625 -104.29621) (xy 454.900282 -104.29621) (xy 454.904353 -104.240588)
			(xy 454.916479 -104.186151) (xy 454.936402 -104.13406) (xy 454.963698 -104.085425) (xy 454.997784 -104.041282)
			(xy 455.037933 -104.002573) (xy 455.083291 -103.970122) (xy 455.132891 -103.944621) (xy 455.185675 -103.926614)
			(xy 455.240518 -103.916484) (xy 455.296252 -103.914447) (xy 455.351689 -103.920547) (xy 455.405646 -103.934653)
			(xy 455.456975 -103.956465) (xy 455.504581 -103.985519) (xy 455.547449 -104.021194) (xy 455.584666 -104.062731)
			(xy 455.615439 -104.109244) (xy 455.639111 -104.159741) (xy 455.655179 -104.213148) (xy 455.660562 -104.249728)
			(xy 461.738978 -104.249728) (xy 461.743049 -104.194106) (xy 461.755175 -104.139669) (xy 461.775098 -104.087578)
			(xy 461.802394 -104.038943) (xy 461.83648 -103.9948) (xy 461.876629 -103.956091) (xy 461.921987 -103.92364)
			(xy 461.971587 -103.898139) (xy 462.024371 -103.880132) (xy 462.079214 -103.870002) (xy 462.134948 -103.867965)
			(xy 462.190385 -103.874065) (xy 462.244342 -103.888171) (xy 462.295671 -103.909983) (xy 462.343277 -103.939037)
			(xy 462.386145 -103.974712) (xy 462.423362 -104.016249) (xy 462.454135 -104.062762) (xy 462.477807 -104.113259)
			(xy 462.493875 -104.166666) (xy 462.501995 -104.221842) (xy 462.502504 -104.249728) (xy 462.501995 -104.277614)
			(xy 462.493875 -104.33279) (xy 462.477807 -104.386197) (xy 462.454135 -104.436694) (xy 462.423362 -104.483207)
			(xy 462.386145 -104.524744) (xy 462.343277 -104.560419) (xy 462.295671 -104.589473) (xy 462.244342 -104.611285)
			(xy 462.190385 -104.625391) (xy 462.134948 -104.631491) (xy 462.079214 -104.629454) (xy 462.024371 -104.619324)
			(xy 461.971587 -104.601317) (xy 461.921987 -104.575816) (xy 461.876629 -104.543365) (xy 461.83648 -104.504656)
			(xy 461.802394 -104.460513) (xy 461.775098 -104.411878) (xy 461.755175 -104.359787) (xy 461.743049 -104.30535)
			(xy 461.738978 -104.249728) (xy 455.660562 -104.249728) (xy 455.663299 -104.268324) (xy 455.663808 -104.29621)
			(xy 455.663299 -104.324096) (xy 455.655179 -104.379272) (xy 455.639111 -104.432679) (xy 455.615439 -104.483176)
			(xy 455.584666 -104.529689) (xy 455.547449 -104.571226) (xy 455.504581 -104.606901) (xy 455.456975 -104.635955)
			(xy 455.405646 -104.657767) (xy 455.351689 -104.671873) (xy 455.296252 -104.677973) (xy 455.240518 -104.675936)
			(xy 455.185675 -104.665806) (xy 455.132891 -104.647799) (xy 455.083291 -104.622298) (xy 455.037933 -104.589847)
			(xy 454.997784 -104.551138) (xy 454.963698 -104.506995) (xy 454.936402 -104.45836) (xy 454.916479 -104.406269)
			(xy 454.904353 -104.351832) (xy 454.900282 -104.29621) (xy 434.156625 -104.29621) (xy 434.157119 -104.299566)
			(xy 434.157628 -104.327452) (xy 434.157119 -104.355338) (xy 434.148999 -104.410514) (xy 434.132931 -104.463921)
			(xy 434.109259 -104.514418) (xy 434.078486 -104.560931) (xy 434.041269 -104.602468) (xy 433.998401 -104.638143)
			(xy 433.950795 -104.667197) (xy 433.899466 -104.689009) (xy 433.845509 -104.703115) (xy 433.790072 -104.709215)
			(xy 433.734338 -104.707178) (xy 433.679495 -104.697048) (xy 433.626711 -104.679041) (xy 433.577111 -104.65354)
			(xy 433.531753 -104.621089) (xy 433.491604 -104.58238) (xy 433.457518 -104.538237) (xy 433.430222 -104.489602)
			(xy 433.410299 -104.437511) (xy 433.398173 -104.383074) (xy 433.394102 -104.327452) (xy 415.14522 -104.327452)
			(xy 415.14522 -105.207308) (xy 416.720272 -105.207308) (xy 416.724343 -105.151686) (xy 416.736469 -105.097249)
			(xy 416.756392 -105.045158) (xy 416.783688 -104.996523) (xy 416.817774 -104.95238) (xy 416.857923 -104.913671)
			(xy 416.903281 -104.88122) (xy 416.952881 -104.855719) (xy 417.005665 -104.837712) (xy 417.060508 -104.827582)
			(xy 417.116242 -104.825545) (xy 417.171679 -104.831645) (xy 417.225636 -104.845751) (xy 417.276965 -104.867563)
			(xy 417.324571 -104.896617) (xy 417.367439 -104.932292) (xy 417.404656 -104.973829) (xy 417.435429 -105.020342)
			(xy 417.459101 -105.070839) (xy 417.475169 -105.124246) (xy 417.483289 -105.179422) (xy 417.483798 -105.207308)
			(xy 417.483289 -105.235194) (xy 417.475169 -105.29037) (xy 417.459101 -105.343777) (xy 417.435429 -105.394274)
			(xy 417.404656 -105.440787) (xy 417.367439 -105.482324) (xy 417.324571 -105.517999) (xy 417.276965 -105.547053)
			(xy 417.225636 -105.568865) (xy 417.171679 -105.582971) (xy 417.116242 -105.589071) (xy 417.060508 -105.587034)
			(xy 417.005665 -105.576904) (xy 416.952881 -105.558897) (xy 416.903281 -105.533396) (xy 416.857923 -105.500945)
			(xy 416.817774 -105.462236) (xy 416.783688 -105.418093) (xy 416.756392 -105.369458) (xy 416.736469 -105.317367)
			(xy 416.724343 -105.26293) (xy 416.720272 -105.207308) (xy 415.14522 -105.207308) (xy 415.14522 -105.827322)
			(xy 429.906682 -105.827322) (xy 429.910753 -105.7717) (xy 429.922879 -105.717263) (xy 429.942802 -105.665172)
			(xy 429.970098 -105.616537) (xy 430.004184 -105.572394) (xy 430.044333 -105.533685) (xy 430.089691 -105.501234)
			(xy 430.139291 -105.475733) (xy 430.192075 -105.457726) (xy 430.246918 -105.447596) (xy 430.302652 -105.445559)
			(xy 430.358089 -105.451659) (xy 430.412046 -105.465765) (xy 430.463375 -105.487577) (xy 430.510981 -105.516631)
			(xy 430.553849 -105.552306) (xy 430.591066 -105.593843) (xy 430.621839 -105.640356) (xy 430.645511 -105.690853)
			(xy 430.661579 -105.74426) (xy 430.669699 -105.799436) (xy 430.670208 -105.827322) (xy 430.669699 -105.855208)
			(xy 430.661579 -105.910384) (xy 430.645511 -105.963791) (xy 430.621839 -106.014288) (xy 430.591066 -106.060801)
			(xy 430.553849 -106.102338) (xy 430.510981 -106.138013) (xy 430.463375 -106.167067) (xy 430.412046 -106.188879)
			(xy 430.358089 -106.202985) (xy 430.302652 -106.209085) (xy 430.246918 -106.207048) (xy 430.192075 -106.196918)
			(xy 430.139291 -106.178911) (xy 430.089691 -106.15341) (xy 430.044333 -106.120959) (xy 430.004184 -106.08225)
			(xy 429.970098 -106.038107) (xy 429.942802 -105.989472) (xy 429.922879 -105.937381) (xy 429.910753 -105.882944)
			(xy 429.906682 -105.827322) (xy 415.14522 -105.827322) (xy 415.14522 -106.36885) (xy 454.871072 -106.36885)
			(xy 454.875143 -106.313228) (xy 454.887269 -106.258791) (xy 454.907192 -106.2067) (xy 454.934488 -106.158065)
			(xy 454.968574 -106.113922) (xy 455.008723 -106.075213) (xy 455.054081 -106.042762) (xy 455.103681 -106.017261)
			(xy 455.156465 -105.999254) (xy 455.211308 -105.989124) (xy 455.267042 -105.987087) (xy 455.322479 -105.993187)
			(xy 455.376436 -106.007293) (xy 455.424525 -106.027728) (xy 459.55915 -106.027728) (xy 459.563221 -105.972106)
			(xy 459.575347 -105.917669) (xy 459.59527 -105.865578) (xy 459.622566 -105.816943) (xy 459.656652 -105.7728)
			(xy 459.696801 -105.734091) (xy 459.742159 -105.70164) (xy 459.791759 -105.676139) (xy 459.844543 -105.658132)
			(xy 459.899386 -105.648002) (xy 459.95512 -105.645965) (xy 460.010557 -105.652065) (xy 460.064514 -105.666171)
			(xy 460.115843 -105.687983) (xy 460.163449 -105.717037) (xy 460.206317 -105.752712) (xy 460.243534 -105.794249)
			(xy 460.274307 -105.840762) (xy 460.297979 -105.891259) (xy 460.314047 -105.944666) (xy 460.322167 -105.999842)
			(xy 460.322676 -106.027728) (xy 460.322167 -106.055614) (xy 460.314047 -106.11079) (xy 460.297979 -106.164197)
			(xy 460.274307 -106.214694) (xy 460.243534 -106.261207) (xy 460.206317 -106.302744) (xy 460.163449 -106.338419)
			(xy 460.115843 -106.367473) (xy 460.064514 -106.389285) (xy 460.010557 -106.403391) (xy 459.95512 -106.409491)
			(xy 459.899386 -106.407454) (xy 459.844543 -106.397324) (xy 459.791759 -106.379317) (xy 459.742159 -106.353816)
			(xy 459.696801 -106.321365) (xy 459.656652 -106.282656) (xy 459.622566 -106.238513) (xy 459.59527 -106.189878)
			(xy 459.575347 -106.137787) (xy 459.563221 -106.08335) (xy 459.55915 -106.027728) (xy 455.424525 -106.027728)
			(xy 455.427765 -106.029105) (xy 455.475371 -106.058159) (xy 455.518239 -106.093834) (xy 455.555456 -106.135371)
			(xy 455.586229 -106.181884) (xy 455.609901 -106.232381) (xy 455.625969 -106.285788) (xy 455.634089 -106.340964)
			(xy 455.634598 -106.36885) (xy 455.634089 -106.396736) (xy 455.625969 -106.451912) (xy 455.609901 -106.505319)
			(xy 455.586229 -106.555816) (xy 455.555456 -106.602329) (xy 455.518239 -106.643866) (xy 455.475371 -106.679541)
			(xy 455.427765 -106.708595) (xy 455.376436 -106.730407) (xy 455.322479 -106.744513) (xy 455.267042 -106.750613)
			(xy 455.211308 -106.748576) (xy 455.156465 -106.738446) (xy 455.103681 -106.720439) (xy 455.054081 -106.694938)
			(xy 455.008723 -106.662487) (xy 454.968574 -106.623778) (xy 454.934488 -106.579635) (xy 454.907192 -106.531)
			(xy 454.887269 -106.478909) (xy 454.875143 -106.424472) (xy 454.871072 -106.36885) (xy 415.14522 -106.36885)
			(xy 415.14522 -107.15117) (xy 428.930814 -107.15117) (xy 428.934885 -107.095548) (xy 428.947011 -107.041111)
			(xy 428.966934 -106.98902) (xy 428.99423 -106.940385) (xy 429.028316 -106.896242) (xy 429.068465 -106.857533)
			(xy 429.113823 -106.825082) (xy 429.163423 -106.799581) (xy 429.216207 -106.781574) (xy 429.27105 -106.771444)
			(xy 429.326784 -106.769407) (xy 429.368344 -106.77398) (xy 433.340254 -106.77398) (xy 433.344325 -106.718358)
			(xy 433.356451 -106.663921) (xy 433.376374 -106.61183) (xy 433.40367 -106.563195) (xy 433.437756 -106.519052)
			(xy 433.477905 -106.480343) (xy 433.523263 -106.447892) (xy 433.572863 -106.422391) (xy 433.625647 -106.404384)
			(xy 433.68049 -106.394254) (xy 433.736224 -106.392217) (xy 433.791661 -106.398317) (xy 433.845618 -106.412423)
			(xy 433.896947 -106.434235) (xy 433.944553 -106.463289) (xy 433.987421 -106.498964) (xy 434.024638 -106.540501)
			(xy 434.055411 -106.587014) (xy 434.079083 -106.637511) (xy 434.095151 -106.690918) (xy 434.103271 -106.746094)
			(xy 434.10378 -106.77398) (xy 434.103571 -106.78541) (xy 438.469022 -106.78541) (xy 438.473093 -106.729788)
			(xy 438.485219 -106.675351) (xy 438.505142 -106.62326) (xy 438.532438 -106.574625) (xy 438.566524 -106.530482)
			(xy 438.606673 -106.491773) (xy 438.652031 -106.459322) (xy 438.701631 -106.433821) (xy 438.754415 -106.415814)
			(xy 438.809258 -106.405684) (xy 438.864992 -106.403647) (xy 438.920429 -106.409747) (xy 438.974386 -106.423853)
			(xy 439.025715 -106.445665) (xy 439.073321 -106.474719) (xy 439.116189 -106.510394) (xy 439.153406 -106.551931)
			(xy 439.184179 -106.598444) (xy 439.207851 -106.648941) (xy 439.223919 -106.702348) (xy 439.232039 -106.757524)
			(xy 439.232548 -106.78541) (xy 439.232039 -106.813296) (xy 439.223919 -106.868472) (xy 439.207851 -106.921879)
			(xy 439.184179 -106.972376) (xy 439.153441 -107.018836) (xy 455.666854 -107.018836) (xy 455.670925 -106.963214)
			(xy 455.683051 -106.908777) (xy 455.702974 -106.856686) (xy 455.73027 -106.808051) (xy 455.764356 -106.763908)
			(xy 455.804505 -106.725199) (xy 455.849863 -106.692748) (xy 455.899463 -106.667247) (xy 455.952247 -106.64924)
			(xy 456.00709 -106.63911) (xy 456.062824 -106.637073) (xy 456.118261 -106.643173) (xy 456.172218 -106.657279)
			(xy 456.223547 -106.679091) (xy 456.271153 -106.708145) (xy 456.314021 -106.74382) (xy 456.351238 -106.785357)
			(xy 456.382011 -106.83187) (xy 456.405683 -106.882367) (xy 456.421751 -106.935774) (xy 456.429871 -106.99095)
			(xy 456.43038 -107.018836) (xy 456.429871 -107.046722) (xy 456.421751 -107.101898) (xy 456.405683 -107.155305)
			(xy 456.382011 -107.205802) (xy 456.351238 -107.252315) (xy 456.314021 -107.293852) (xy 456.271153 -107.329527)
			(xy 456.223547 -107.358581) (xy 456.172218 -107.380393) (xy 456.118261 -107.394499) (xy 456.062824 -107.400599)
			(xy 456.00709 -107.398562) (xy 455.952247 -107.388432) (xy 455.899463 -107.370425) (xy 455.849863 -107.344924)
			(xy 455.804505 -107.312473) (xy 455.764356 -107.273764) (xy 455.73027 -107.229621) (xy 455.702974 -107.180986)
			(xy 455.683051 -107.128895) (xy 455.670925 -107.074458) (xy 455.666854 -107.018836) (xy 439.153441 -107.018836)
			(xy 439.153406 -107.018889) (xy 439.116189 -107.060426) (xy 439.073321 -107.096101) (xy 439.025715 -107.125155)
			(xy 438.974386 -107.146967) (xy 438.920429 -107.161073) (xy 438.864992 -107.167173) (xy 438.809258 -107.165136)
			(xy 438.754415 -107.155006) (xy 438.701631 -107.136999) (xy 438.652031 -107.111498) (xy 438.606673 -107.079047)
			(xy 438.566524 -107.040338) (xy 438.532438 -106.996195) (xy 438.505142 -106.94756) (xy 438.485219 -106.895469)
			(xy 438.473093 -106.841032) (xy 438.469022 -106.78541) (xy 434.103571 -106.78541) (xy 434.103271 -106.801866)
			(xy 434.095151 -106.857042) (xy 434.079083 -106.910449) (xy 434.055411 -106.960946) (xy 434.024638 -107.007459)
			(xy 433.987421 -107.048996) (xy 433.944553 -107.084671) (xy 433.896947 -107.113725) (xy 433.845618 -107.135537)
			(xy 433.791661 -107.149643) (xy 433.736224 -107.155743) (xy 433.68049 -107.153706) (xy 433.625647 -107.143576)
			(xy 433.572863 -107.125569) (xy 433.523263 -107.100068) (xy 433.477905 -107.067617) (xy 433.437756 -107.028908)
			(xy 433.40367 -106.984765) (xy 433.376374 -106.93613) (xy 433.356451 -106.884039) (xy 433.344325 -106.829602)
			(xy 433.340254 -106.77398) (xy 429.368344 -106.77398) (xy 429.382221 -106.775507) (xy 429.436178 -106.789613)
			(xy 429.487507 -106.811425) (xy 429.535113 -106.840479) (xy 429.577981 -106.876154) (xy 429.615198 -106.917691)
			(xy 429.645971 -106.964204) (xy 429.669643 -107.014701) (xy 429.685711 -107.068108) (xy 429.693831 -107.123284)
			(xy 429.69434 -107.15117) (xy 429.693831 -107.179056) (xy 429.685711 -107.234232) (xy 429.669643 -107.287639)
			(xy 429.669403 -107.28815) (xy 430.264576 -107.28815) (xy 430.264576 -107.23365) (xy 430.272331 -107.179705)
			(xy 430.287685 -107.127412) (xy 430.310324 -107.077836) (xy 430.339788 -107.031987) (xy 430.375476 -106.990798)
			(xy 430.416663 -106.955106) (xy 430.46251 -106.925639) (xy 430.512084 -106.902996) (xy 430.564375 -106.887638)
			(xy 430.61832 -106.879878) (xy 430.64557 -106.87939) (xy 430.672671 -106.879881) (xy 430.726329 -106.887549)
			(xy 430.778362 -106.902734) (xy 430.827721 -106.925132) (xy 430.873413 -106.95429) (xy 430.914517 -106.989622)
			(xy 430.950207 -107.030417) (xy 430.979764 -107.075852) (xy 431.002592 -107.125013) (xy 431.018231 -107.176911)
			(xy 431.026368 -107.2305) (xy 431.027078 -107.257596) (xy 431.027686 -107.271487) (xy 431.035494 -107.298161)
			(xy 431.050204 -107.321743) (xy 431.070727 -107.340486) (xy 431.095543 -107.353002) (xy 431.122814 -107.358364)
			(xy 431.150522 -107.356176) (xy 431.16373 -107.35183) (xy 431.195585 -107.340909) (xy 431.261888 -107.329156)
			(xy 431.295556 -107.328462) (xy 431.323565 -107.328982) (xy 431.378981 -107.337174) (xy 431.432602 -107.353388)
			(xy 431.483272 -107.377274) (xy 431.529901 -107.408318) (xy 431.571485 -107.445853) (xy 431.589688 -107.467146)
			(xy 431.598926 -107.477639) (xy 431.621933 -107.493507) (xy 431.648375 -107.50256) (xy 431.67628 -107.504124)
			(xy 431.703567 -107.498081) (xy 431.728203 -107.484883) (xy 431.74835 -107.465513) (xy 431.755804 -107.453684)
			(xy 431.770568 -107.429362) (xy 431.806195 -107.385002) (xy 431.848012 -107.346423) (xy 431.895094 -107.31448)
			(xy 431.946397 -107.289882) (xy 432.000784 -107.273174) (xy 432.057048 -107.264726) (xy 432.085496 -107.2642)
			(xy 432.11275 -107.264647) (xy 432.166702 -107.272404) (xy 432.219002 -107.28776) (xy 432.268583 -107.310402)
			(xy 432.314438 -107.339871) (xy 432.355632 -107.375565) (xy 432.391327 -107.416759) (xy 432.420796 -107.462613)
			(xy 432.443439 -107.512195) (xy 432.458795 -107.564494) (xy 432.466553 -107.618446) (xy 432.466553 -107.65028)
			(xy 440.127642 -107.65028) (xy 440.131713 -107.594658) (xy 440.143839 -107.540221) (xy 440.163762 -107.48813)
			(xy 440.191058 -107.439495) (xy 440.225144 -107.395352) (xy 440.265293 -107.356643) (xy 440.310651 -107.324192)
			(xy 440.360251 -107.298691) (xy 440.413035 -107.280684) (xy 440.467878 -107.270554) (xy 440.523612 -107.268517)
			(xy 440.579049 -107.274617) (xy 440.633006 -107.288723) (xy 440.684335 -107.310535) (xy 440.731941 -107.339589)
			(xy 440.774809 -107.375264) (xy 440.812026 -107.416801) (xy 440.842799 -107.463314) (xy 440.866471 -107.513811)
			(xy 440.882539 -107.567218) (xy 440.890659 -107.622394) (xy 440.891168 -107.65028) (xy 440.890659 -107.678166)
			(xy 440.882539 -107.733342) (xy 440.866471 -107.786749) (xy 440.842799 -107.837246) (xy 440.812026 -107.883759)
			(xy 440.774809 -107.925296) (xy 440.731941 -107.960971) (xy 440.684335 -107.990025) (xy 440.633006 -108.011837)
			(xy 440.579049 -108.025943) (xy 440.523612 -108.032043) (xy 440.467878 -108.030006) (xy 440.413035 -108.019876)
			(xy 440.360251 -108.001869) (xy 440.310651 -107.976368) (xy 440.265293 -107.943917) (xy 440.225144 -107.905208)
			(xy 440.191058 -107.861065) (xy 440.163762 -107.81243) (xy 440.143839 -107.760339) (xy 440.131713 -107.705902)
			(xy 440.127642 -107.65028) (xy 432.466553 -107.65028) (xy 432.466553 -107.672954) (xy 432.458795 -107.726906)
			(xy 432.443439 -107.779205) (xy 432.420796 -107.828787) (xy 432.391327 -107.874641) (xy 432.355632 -107.915835)
			(xy 432.314438 -107.951529) (xy 432.268583 -107.980998) (xy 432.219002 -108.00364) (xy 432.166702 -108.018996)
			(xy 432.11275 -108.026753) (xy 432.085496 -108.027216) (xy 432.057485 -108.026737) (xy 432.002067 -108.018538)
			(xy 431.948445 -108.002317) (xy 431.897775 -107.978423) (xy 431.851147 -107.947371) (xy 431.809565 -107.909829)
			(xy 431.791364 -107.888532) (xy 431.782079 -107.87808) (xy 431.759086 -107.862198) (xy 431.732654 -107.853132)
			(xy 431.704753 -107.851559) (xy 431.677469 -107.857596) (xy 431.652837 -107.870793) (xy 431.632697 -107.890165)
			(xy 431.625248 -107.901994) (xy 431.610092 -107.926885) (xy 431.573457 -107.972201) (xy 431.530354 -108.011417)
			(xy 431.506376 -108.027978) (xy 431.495092 -108.03605) (xy 431.476923 -108.056997) (xy 431.46507 -108.082066)
			(xy 431.460412 -108.1094) (xy 431.463292 -108.136979) (xy 431.473497 -108.162762) (xy 431.490273 -108.184841)
			(xy 431.496663 -108.19003) (xy 434.248558 -108.19003) (xy 434.252629 -108.134408) (xy 434.264755 -108.079971)
			(xy 434.284678 -108.02788) (xy 434.311974 -107.979245) (xy 434.34606 -107.935102) (xy 434.386209 -107.896393)
			(xy 434.431567 -107.863942) (xy 434.481167 -107.838441) (xy 434.533951 -107.820434) (xy 434.588794 -107.810304)
			(xy 434.644528 -107.808267) (xy 434.699965 -107.814367) (xy 434.753922 -107.828473) (xy 434.805251 -107.850285)
			(xy 434.852857 -107.879339) (xy 434.895725 -107.915014) (xy 434.932942 -107.956551) (xy 434.963715 -108.003064)
			(xy 434.987387 -108.053561) (xy 434.989242 -108.059728) (xy 454.841862 -108.059728) (xy 454.845933 -108.004106)
			(xy 454.858059 -107.949669) (xy 454.877982 -107.897578) (xy 454.905278 -107.848943) (xy 454.939364 -107.8048)
			(xy 454.979513 -107.766091) (xy 455.024871 -107.73364) (xy 455.074471 -107.708139) (xy 455.127255 -107.690132)
			(xy 455.182098 -107.680002) (xy 455.237832 -107.677965) (xy 455.244766 -107.678728) (xy 461.611978 -107.678728)
			(xy 461.616049 -107.623106) (xy 461.628175 -107.568669) (xy 461.648098 -107.516578) (xy 461.675394 -107.467943)
			(xy 461.70948 -107.4238) (xy 461.749629 -107.385091) (xy 461.794987 -107.35264) (xy 461.844587 -107.327139)
			(xy 461.897371 -107.309132) (xy 461.952214 -107.299002) (xy 462.007948 -107.296965) (xy 462.063385 -107.303065)
			(xy 462.117342 -107.317171) (xy 462.168671 -107.338983) (xy 462.216277 -107.368037) (xy 462.259145 -107.403712)
			(xy 462.296362 -107.445249) (xy 462.327135 -107.491762) (xy 462.350807 -107.542259) (xy 462.366875 -107.595666)
			(xy 462.374995 -107.650842) (xy 462.375504 -107.678728) (xy 462.374995 -107.706614) (xy 462.366875 -107.76179)
			(xy 462.350807 -107.815197) (xy 462.327135 -107.865694) (xy 462.296362 -107.912207) (xy 462.259145 -107.953744)
			(xy 462.216277 -107.989419) (xy 462.168671 -108.018473) (xy 462.117342 -108.040285) (xy 462.063385 -108.054391)
			(xy 462.007948 -108.060491) (xy 461.952214 -108.058454) (xy 461.897371 -108.048324) (xy 461.844587 -108.030317)
			(xy 461.794987 -108.004816) (xy 461.749629 -107.972365) (xy 461.70948 -107.933656) (xy 461.675394 -107.889513)
			(xy 461.648098 -107.840878) (xy 461.628175 -107.788787) (xy 461.616049 -107.73435) (xy 461.611978 -107.678728)
			(xy 455.244766 -107.678728) (xy 455.293269 -107.684065) (xy 455.347226 -107.698171) (xy 455.398555 -107.719983)
			(xy 455.446161 -107.749037) (xy 455.489029 -107.784712) (xy 455.526246 -107.826249) (xy 455.557019 -107.872762)
			(xy 455.580691 -107.923259) (xy 455.596759 -107.976666) (xy 455.604879 -108.031842) (xy 455.605388 -108.059728)
			(xy 455.604879 -108.087614) (xy 455.596759 -108.14279) (xy 455.580691 -108.196197) (xy 455.557019 -108.246694)
			(xy 455.526246 -108.293207) (xy 455.489029 -108.334744) (xy 455.446161 -108.370419) (xy 455.398555 -108.399473)
			(xy 455.347226 -108.421285) (xy 455.293269 -108.435391) (xy 455.237832 -108.441491) (xy 455.182098 -108.439454)
			(xy 455.127255 -108.429324) (xy 455.074471 -108.411317) (xy 455.024871 -108.385816) (xy 454.979513 -108.353365)
			(xy 454.939364 -108.314656) (xy 454.905278 -108.270513) (xy 454.877982 -108.221878) (xy 454.858059 -108.169787)
			(xy 454.845933 -108.11535) (xy 454.841862 -108.059728) (xy 434.989242 -108.059728) (xy 435.003455 -108.106968)
			(xy 435.011575 -108.162144) (xy 435.012084 -108.19003) (xy 435.011575 -108.217916) (xy 435.003455 -108.273092)
			(xy 434.987387 -108.326499) (xy 434.963715 -108.376996) (xy 434.932942 -108.423509) (xy 434.895725 -108.465046)
			(xy 434.852857 -108.500721) (xy 434.805251 -108.529775) (xy 434.753922 -108.551587) (xy 434.699965 -108.565693)
			(xy 434.644528 -108.571793) (xy 434.588794 -108.569756) (xy 434.533951 -108.559626) (xy 434.481167 -108.541619)
			(xy 434.431567 -108.516118) (xy 434.386209 -108.483667) (xy 434.34606 -108.444958) (xy 434.311974 -108.400815)
			(xy 434.284678 -108.35218) (xy 434.264755 -108.300089) (xy 434.252629 -108.245652) (xy 434.248558 -108.19003)
			(xy 431.496663 -108.19003) (xy 431.501042 -108.193586) (xy 431.524051 -108.211729) (xy 431.564722 -108.253909)
			(xy 431.598468 -108.30181) (xy 431.624493 -108.354307) (xy 431.642188 -108.410166) (xy 431.651135 -108.468073)
			(xy 431.651664 -108.49737) (xy 431.651178 -108.524621) (xy 431.643422 -108.578569) (xy 431.628067 -108.630864)
			(xy 431.605425 -108.680441) (xy 431.575959 -108.726291) (xy 431.540268 -108.767482) (xy 431.499077 -108.803173)
			(xy 431.453227 -108.832639) (xy 431.40365 -108.855281) (xy 431.351355 -108.870636) (xy 431.297407 -108.878392)
			(xy 431.242905 -108.878392) (xy 431.188957 -108.870636) (xy 431.136662 -108.855281) (xy 431.087085 -108.832639)
			(xy 431.041235 -108.803173) (xy 431.000044 -108.767482) (xy 430.964353 -108.726291) (xy 430.934887 -108.680441)
			(xy 430.912245 -108.630864) (xy 430.89689 -108.578569) (xy 430.889134 -108.524621) (xy 430.888648 -108.49737)
			(xy 430.889057 -108.470502) (xy 430.89659 -108.417297) (xy 430.911516 -108.365675) (xy 430.933541 -108.31666)
			(xy 430.962227 -108.271222) (xy 430.997007 -108.23026) (xy 431.037192 -108.194585) (xy 431.059336 -108.179362)
			(xy 431.070676 -108.171363) (xy 431.088845 -108.1504) (xy 431.100694 -108.125315) (xy 431.105344 -108.097966)
			(xy 431.102454 -108.070376) (xy 431.092236 -108.044584) (xy 431.075446 -108.022501) (xy 431.06467 -108.013754)
			(xy 431.041903 -107.995752) (xy 431.001562 -107.954029) (xy 430.968 -107.906679) (xy 430.941992 -107.854796)
			(xy 430.924137 -107.799573) (xy 430.914846 -107.742285) (xy 430.914048 -107.713272) (xy 430.913351 -107.699387)
			(xy 430.905561 -107.672718) (xy 430.890868 -107.649138) (xy 430.87036 -107.630394) (xy 430.845557 -107.617875)
			(xy 430.818297 -107.61251) (xy 430.7906 -107.614695) (xy 430.777396 -107.619038) (xy 430.745539 -107.629955)
			(xy 430.679238 -107.64171) (xy 430.64557 -107.642406) (xy 430.61832 -107.641922) (xy 430.564375 -107.634162)
			(xy 430.512084 -107.618804) (xy 430.46251 -107.596161) (xy 430.416663 -107.566694) (xy 430.375476 -107.531002)
			(xy 430.339788 -107.489813) (xy 430.310324 -107.443964) (xy 430.287685 -107.394388) (xy 430.272331 -107.342095)
			(xy 430.264576 -107.28815) (xy 429.669403 -107.28815) (xy 429.645971 -107.338136) (xy 429.615198 -107.384649)
			(xy 429.577981 -107.426186) (xy 429.535113 -107.461861) (xy 429.487507 -107.490915) (xy 429.436178 -107.512727)
			(xy 429.382221 -107.526833) (xy 429.326784 -107.532933) (xy 429.27105 -107.530896) (xy 429.216207 -107.520766)
			(xy 429.163423 -107.502759) (xy 429.113823 -107.477258) (xy 429.068465 -107.444807) (xy 429.028316 -107.406098)
			(xy 428.99423 -107.361955) (xy 428.966934 -107.31332) (xy 428.947011 -107.261229) (xy 428.934885 -107.206792)
			(xy 428.930814 -107.15117) (xy 415.14522 -107.15117) (xy 415.14522 -109.66323) (xy 433.334158 -109.66323)
			(xy 433.338229 -109.607608) (xy 433.350355 -109.553171) (xy 433.370278 -109.50108) (xy 433.397574 -109.452445)
			(xy 433.43166 -109.408302) (xy 433.471809 -109.369593) (xy 433.517167 -109.337142) (xy 433.566767 -109.311641)
			(xy 433.619551 -109.293634) (xy 433.674394 -109.283504) (xy 433.730128 -109.281467) (xy 433.785565 -109.287567)
			(xy 433.839522 -109.301673) (xy 433.890851 -109.323485) (xy 433.938457 -109.352539) (xy 433.981325 -109.388214)
			(xy 434.018542 -109.429751) (xy 434.049315 -109.476264) (xy 434.072987 -109.526761) (xy 434.089055 -109.580168)
			(xy 434.097175 -109.635344) (xy 434.097684 -109.66323) (xy 434.097175 -109.691116) (xy 434.089055 -109.746292)
			(xy 434.072987 -109.799699) (xy 434.049315 -109.850196) (xy 434.018542 -109.896709) (xy 433.981325 -109.938246)
			(xy 433.938457 -109.973921) (xy 433.890851 -110.002975) (xy 433.839522 -110.024787) (xy 433.785565 -110.038893)
			(xy 433.730128 -110.044993) (xy 433.674394 -110.042956) (xy 433.619551 -110.032826) (xy 433.566767 -110.014819)
			(xy 433.517167 -109.989318) (xy 433.471809 -109.956867) (xy 433.43166 -109.918158) (xy 433.397574 -109.874015)
			(xy 433.370278 -109.82538) (xy 433.350355 -109.773289) (xy 433.338229 -109.718852) (xy 433.334158 -109.66323)
			(xy 415.14522 -109.66323) (xy 415.14522 -110.280958) (xy 417.983922 -110.280958) (xy 417.987993 -110.225336)
			(xy 418.000119 -110.170899) (xy 418.020042 -110.118808) (xy 418.047338 -110.070173) (xy 418.081424 -110.02603)
			(xy 418.121573 -109.987321) (xy 418.166931 -109.95487) (xy 418.216531 -109.929369) (xy 418.269315 -109.911362)
			(xy 418.324158 -109.901232) (xy 418.379892 -109.899195) (xy 418.435329 -109.905295) (xy 418.489286 -109.919401)
			(xy 418.540615 -109.941213) (xy 418.588221 -109.970267) (xy 418.631089 -110.005942) (xy 418.668306 -110.047479)
			(xy 418.699079 -110.093992) (xy 418.722751 -110.144489) (xy 418.738819 -110.197896) (xy 418.746939 -110.253072)
			(xy 418.747448 -110.280958) (xy 419.761922 -110.280958) (xy 419.765993 -110.225336) (xy 419.778119 -110.170899)
			(xy 419.798042 -110.118808) (xy 419.825338 -110.070173) (xy 419.859424 -110.02603) (xy 419.899573 -109.987321)
			(xy 419.944931 -109.95487) (xy 419.994531 -109.929369) (xy 420.047315 -109.911362) (xy 420.102158 -109.901232)
			(xy 420.157892 -109.899195) (xy 420.213329 -109.905295) (xy 420.267286 -109.919401) (xy 420.318615 -109.941213)
			(xy 420.366221 -109.970267) (xy 420.409089 -110.005942) (xy 420.446306 -110.047479) (xy 420.477079 -110.093992)
			(xy 420.500751 -110.144489) (xy 420.516819 -110.197896) (xy 420.524939 -110.253072) (xy 420.525448 -110.280958)
			(xy 421.539922 -110.280958) (xy 421.543993 -110.225336) (xy 421.556119 -110.170899) (xy 421.576042 -110.118808)
			(xy 421.603338 -110.070173) (xy 421.637424 -110.02603) (xy 421.677573 -109.987321) (xy 421.722931 -109.95487)
			(xy 421.772531 -109.929369) (xy 421.825315 -109.911362) (xy 421.880158 -109.901232) (xy 421.935892 -109.899195)
			(xy 421.991329 -109.905295) (xy 422.045286 -109.919401) (xy 422.096615 -109.941213) (xy 422.144221 -109.970267)
			(xy 422.187089 -110.005942) (xy 422.224306 -110.047479) (xy 422.255079 -110.093992) (xy 422.278751 -110.144489)
			(xy 422.294819 -110.197896) (xy 422.302939 -110.253072) (xy 422.303369 -110.27664) (xy 427.901098 -110.27664)
			(xy 427.905169 -110.221018) (xy 427.917295 -110.166581) (xy 427.937218 -110.11449) (xy 427.964514 -110.065855)
			(xy 427.9986 -110.021712) (xy 428.038749 -109.983003) (xy 428.084107 -109.950552) (xy 428.133707 -109.925051)
			(xy 428.186491 -109.907044) (xy 428.241334 -109.896914) (xy 428.297068 -109.894877) (xy 428.352505 -109.900977)
			(xy 428.406462 -109.915083) (xy 428.457791 -109.936895) (xy 428.505397 -109.965949) (xy 428.548265 -110.001624)
			(xy 428.585482 -110.043161) (xy 428.616255 -110.089674) (xy 428.639927 -110.140171) (xy 428.642394 -110.14837)
			(xy 430.710338 -110.14837) (xy 430.714409 -110.092748) (xy 430.726535 -110.038311) (xy 430.746458 -109.98622)
			(xy 430.773754 -109.937585) (xy 430.80784 -109.893442) (xy 430.847989 -109.854733) (xy 430.893347 -109.822282)
			(xy 430.942947 -109.796781) (xy 430.995731 -109.778774) (xy 431.050574 -109.768644) (xy 431.106308 -109.766607)
			(xy 431.161745 -109.772707) (xy 431.215702 -109.786813) (xy 431.267031 -109.808625) (xy 431.314637 -109.837679)
			(xy 431.357505 -109.873354) (xy 431.394722 -109.914891) (xy 431.425495 -109.961404) (xy 431.449167 -110.011901)
			(xy 431.465235 -110.065308) (xy 431.473355 -110.120484) (xy 431.473841 -110.1471) (xy 431.703478 -110.1471)
			(xy 431.707549 -110.091478) (xy 431.719675 -110.037041) (xy 431.739598 -109.98495) (xy 431.766894 -109.936315)
			(xy 431.80098 -109.892172) (xy 431.841129 -109.853463) (xy 431.886487 -109.821012) (xy 431.936087 -109.795511)
			(xy 431.988871 -109.777504) (xy 432.043714 -109.767374) (xy 432.099448 -109.765337) (xy 432.154885 -109.771437)
			(xy 432.208842 -109.785543) (xy 432.260171 -109.807355) (xy 432.307777 -109.836409) (xy 432.350645 -109.872084)
			(xy 432.387862 -109.913621) (xy 432.418635 -109.960134) (xy 432.442307 -110.010631) (xy 432.458375 -110.064038)
			(xy 432.466495 -110.119214) (xy 432.467004 -110.1471) (xy 432.592478 -110.1471) (xy 432.596549 -110.091478)
			(xy 432.608675 -110.037041) (xy 432.628598 -109.98495) (xy 432.655894 -109.936315) (xy 432.68998 -109.892172)
			(xy 432.730129 -109.853463) (xy 432.775487 -109.821012) (xy 432.825087 -109.795511) (xy 432.877871 -109.777504)
			(xy 432.932714 -109.767374) (xy 432.988448 -109.765337) (xy 433.043885 -109.771437) (xy 433.097842 -109.785543)
			(xy 433.149171 -109.807355) (xy 433.196777 -109.836409) (xy 433.239645 -109.872084) (xy 433.276862 -109.913621)
			(xy 433.307635 -109.960134) (xy 433.331307 -110.010631) (xy 433.347375 -110.064038) (xy 433.355495 -110.119214)
			(xy 433.356004 -110.1471) (xy 433.355495 -110.174986) (xy 433.347375 -110.230162) (xy 433.331307 -110.283569)
			(xy 433.307635 -110.334066) (xy 433.276862 -110.380579) (xy 433.239645 -110.422116) (xy 433.196777 -110.457791)
			(xy 433.149171 -110.486845) (xy 433.097842 -110.508657) (xy 433.043885 -110.522763) (xy 432.988448 -110.528863)
			(xy 432.932714 -110.526826) (xy 432.877871 -110.516696) (xy 432.825087 -110.498689) (xy 432.775487 -110.473188)
			(xy 432.730129 -110.440737) (xy 432.68998 -110.402028) (xy 432.655894 -110.357885) (xy 432.628598 -110.30925)
			(xy 432.608675 -110.257159) (xy 432.596549 -110.202722) (xy 432.592478 -110.1471) (xy 432.467004 -110.1471)
			(xy 432.466495 -110.174986) (xy 432.458375 -110.230162) (xy 432.442307 -110.283569) (xy 432.418635 -110.334066)
			(xy 432.387862 -110.380579) (xy 432.350645 -110.422116) (xy 432.307777 -110.457791) (xy 432.260171 -110.486845)
			(xy 432.208842 -110.508657) (xy 432.154885 -110.522763) (xy 432.099448 -110.528863) (xy 432.043714 -110.526826)
			(xy 431.988871 -110.516696) (xy 431.936087 -110.498689) (xy 431.886487 -110.473188) (xy 431.841129 -110.440737)
			(xy 431.80098 -110.402028) (xy 431.766894 -110.357885) (xy 431.739598 -110.30925) (xy 431.719675 -110.257159)
			(xy 431.707549 -110.202722) (xy 431.703478 -110.1471) (xy 431.473841 -110.1471) (xy 431.473864 -110.14837)
			(xy 431.473355 -110.176256) (xy 431.465235 -110.231432) (xy 431.449167 -110.284839) (xy 431.425495 -110.335336)
			(xy 431.394722 -110.381849) (xy 431.357505 -110.423386) (xy 431.314637 -110.459061) (xy 431.267031 -110.488115)
			(xy 431.215702 -110.509927) (xy 431.161745 -110.524033) (xy 431.106308 -110.530133) (xy 431.050574 -110.528096)
			(xy 430.995731 -110.517966) (xy 430.942947 -110.499959) (xy 430.893347 -110.474458) (xy 430.847989 -110.442007)
			(xy 430.80784 -110.403298) (xy 430.773754 -110.359155) (xy 430.746458 -110.31052) (xy 430.726535 -110.258429)
			(xy 430.714409 -110.203992) (xy 430.710338 -110.14837) (xy 428.642394 -110.14837) (xy 428.655995 -110.193578)
			(xy 428.664115 -110.248754) (xy 428.664624 -110.27664) (xy 428.664115 -110.304526) (xy 428.655995 -110.359702)
			(xy 428.639927 -110.413109) (xy 428.616255 -110.463606) (xy 428.585482 -110.510119) (xy 428.548265 -110.551656)
			(xy 428.505397 -110.587331) (xy 428.457791 -110.616385) (xy 428.406462 -110.638197) (xy 428.352505 -110.652303)
			(xy 428.297068 -110.658403) (xy 428.241334 -110.656366) (xy 428.186491 -110.646236) (xy 428.133707 -110.628229)
			(xy 428.084107 -110.602728) (xy 428.038749 -110.570277) (xy 427.9986 -110.531568) (xy 427.964514 -110.487425)
			(xy 427.937218 -110.43879) (xy 427.917295 -110.386699) (xy 427.905169 -110.332262) (xy 427.901098 -110.27664)
			(xy 422.303369 -110.27664) (xy 422.303448 -110.280958) (xy 422.302939 -110.308844) (xy 422.294819 -110.36402)
			(xy 422.278751 -110.417427) (xy 422.255079 -110.467924) (xy 422.224306 -110.514437) (xy 422.187089 -110.555974)
			(xy 422.144221 -110.591649) (xy 422.096615 -110.620703) (xy 422.045286 -110.642515) (xy 421.991329 -110.656621)
			(xy 421.935892 -110.662721) (xy 421.880158 -110.660684) (xy 421.825315 -110.650554) (xy 421.772531 -110.632547)
			(xy 421.722931 -110.607046) (xy 421.677573 -110.574595) (xy 421.637424 -110.535886) (xy 421.603338 -110.491743)
			(xy 421.576042 -110.443108) (xy 421.556119 -110.391017) (xy 421.543993 -110.33658) (xy 421.539922 -110.280958)
			(xy 420.525448 -110.280958) (xy 420.524939 -110.308844) (xy 420.516819 -110.36402) (xy 420.500751 -110.417427)
			(xy 420.477079 -110.467924) (xy 420.446306 -110.514437) (xy 420.409089 -110.555974) (xy 420.366221 -110.591649)
			(xy 420.318615 -110.620703) (xy 420.267286 -110.642515) (xy 420.213329 -110.656621) (xy 420.157892 -110.662721)
			(xy 420.102158 -110.660684) (xy 420.047315 -110.650554) (xy 419.994531 -110.632547) (xy 419.944931 -110.607046)
			(xy 419.899573 -110.574595) (xy 419.859424 -110.535886) (xy 419.825338 -110.491743) (xy 419.798042 -110.443108)
			(xy 419.778119 -110.391017) (xy 419.765993 -110.33658) (xy 419.761922 -110.280958) (xy 418.747448 -110.280958)
			(xy 418.746939 -110.308844) (xy 418.738819 -110.36402) (xy 418.722751 -110.417427) (xy 418.699079 -110.467924)
			(xy 418.668306 -110.514437) (xy 418.631089 -110.555974) (xy 418.588221 -110.591649) (xy 418.540615 -110.620703)
			(xy 418.489286 -110.642515) (xy 418.435329 -110.656621) (xy 418.379892 -110.662721) (xy 418.324158 -110.660684)
			(xy 418.269315 -110.650554) (xy 418.216531 -110.632547) (xy 418.166931 -110.607046) (xy 418.121573 -110.574595)
			(xy 418.081424 -110.535886) (xy 418.047338 -110.491743) (xy 418.020042 -110.443108) (xy 418.000119 -110.391017)
			(xy 417.987993 -110.33658) (xy 417.983922 -110.280958) (xy 415.14522 -110.280958) (xy 415.14522 -110.71098)
			(xy 443.376302 -110.71098) (xy 443.380373 -110.655358) (xy 443.392499 -110.600921) (xy 443.412422 -110.54883)
			(xy 443.439718 -110.500195) (xy 443.473804 -110.456052) (xy 443.513953 -110.417343) (xy 443.559311 -110.384892)
			(xy 443.608911 -110.359391) (xy 443.661695 -110.341384) (xy 443.716538 -110.331254) (xy 443.772272 -110.329217)
			(xy 443.827709 -110.335317) (xy 443.881666 -110.349423) (xy 443.932995 -110.371235) (xy 443.980601 -110.400289)
			(xy 444.023469 -110.435964) (xy 444.060686 -110.477501) (xy 444.091459 -110.524014) (xy 444.115131 -110.574511)
			(xy 444.131199 -110.627918) (xy 444.139319 -110.683094) (xy 444.139828 -110.71098) (xy 444.139319 -110.738866)
			(xy 444.131199 -110.794042) (xy 444.115131 -110.847449) (xy 444.091459 -110.897946) (xy 444.060686 -110.944459)
			(xy 444.023469 -110.985996) (xy 443.980601 -111.021671) (xy 443.932995 -111.050725) (xy 443.881666 -111.072537)
			(xy 443.827709 -111.086643) (xy 443.772272 -111.092743) (xy 443.716538 -111.090706) (xy 443.661695 -111.080576)
			(xy 443.608911 -111.062569) (xy 443.559311 -111.037068) (xy 443.513953 -111.004617) (xy 443.473804 -110.965908)
			(xy 443.439718 -110.921765) (xy 443.412422 -110.87313) (xy 443.392499 -110.821039) (xy 443.380373 -110.766602)
			(xy 443.376302 -110.71098) (xy 415.14522 -110.71098) (xy 415.14522 -111.308388) (xy 450.180962 -111.308388)
			(xy 450.185033 -111.252766) (xy 450.197159 -111.198329) (xy 450.217082 -111.146238) (xy 450.244378 -111.097603)
			(xy 450.278464 -111.05346) (xy 450.318613 -111.014751) (xy 450.363971 -110.9823) (xy 450.413571 -110.956799)
			(xy 450.466355 -110.938792) (xy 450.521198 -110.928662) (xy 450.576932 -110.926625) (xy 450.632369 -110.932725)
			(xy 450.686326 -110.946831) (xy 450.737655 -110.968643) (xy 450.785261 -110.997697) (xy 450.828129 -111.033372)
			(xy 450.865346 -111.074909) (xy 450.896119 -111.121422) (xy 450.919791 -111.171919) (xy 450.935859 -111.225326)
			(xy 450.943979 -111.280502) (xy 450.944488 -111.308388) (xy 450.943979 -111.336274) (xy 450.935859 -111.39145)
			(xy 450.919791 -111.444857) (xy 450.896119 -111.495354) (xy 450.865346 -111.541867) (xy 450.828129 -111.583404)
			(xy 450.785261 -111.619079) (xy 450.737655 -111.648133) (xy 450.686326 -111.669945) (xy 450.632369 -111.684051)
			(xy 450.576932 -111.690151) (xy 450.521198 -111.688114) (xy 450.466355 -111.677984) (xy 450.413571 -111.659977)
			(xy 450.363971 -111.634476) (xy 450.318613 -111.602025) (xy 450.278464 -111.563316) (xy 450.244378 -111.519173)
			(xy 450.217082 -111.470538) (xy 450.197159 -111.418447) (xy 450.185033 -111.36401) (xy 450.180962 -111.308388)
			(xy 415.14522 -111.308388) (xy 415.14522 -112.772698) (xy 452.352662 -112.772698) (xy 452.356733 -112.717076)
			(xy 452.368859 -112.662639) (xy 452.388782 -112.610548) (xy 452.416078 -112.561913) (xy 452.450164 -112.51777)
			(xy 452.490313 -112.479061) (xy 452.535671 -112.44661) (xy 452.585271 -112.421109) (xy 452.638055 -112.403102)
			(xy 452.692898 -112.392972) (xy 452.748632 -112.390935) (xy 452.804069 -112.397035) (xy 452.858026 -112.411141)
			(xy 452.909355 -112.432953) (xy 452.956961 -112.462007) (xy 452.999829 -112.497682) (xy 453.037046 -112.539219)
			(xy 453.067819 -112.585732) (xy 453.091491 -112.636229) (xy 453.107559 -112.689636) (xy 453.115679 -112.744812)
			(xy 453.116188 -112.772698) (xy 453.115679 -112.800584) (xy 453.107559 -112.85576) (xy 453.091491 -112.909167)
			(xy 453.067819 -112.959664) (xy 453.037046 -113.006177) (xy 452.999829 -113.047714) (xy 452.956961 -113.083389)
			(xy 452.909355 -113.112443) (xy 452.858026 -113.134255) (xy 452.804069 -113.148361) (xy 452.748632 -113.154461)
			(xy 452.692898 -113.152424) (xy 452.638055 -113.142294) (xy 452.585271 -113.124287) (xy 452.535671 -113.098786)
			(xy 452.490313 -113.066335) (xy 452.450164 -113.027626) (xy 452.416078 -112.983483) (xy 452.388782 -112.934848)
			(xy 452.368859 -112.882757) (xy 452.356733 -112.82832) (xy 452.352662 -112.772698) (xy 415.14522 -112.772698)
			(xy 415.14522 -113.162588) (xy 416.57778 -114.595148) (xy 455.807062 -114.595148) (xy 455.811133 -114.539526)
			(xy 455.823259 -114.485089) (xy 455.843182 -114.432998) (xy 455.870478 -114.384363) (xy 455.904564 -114.34022)
			(xy 455.944713 -114.301511) (xy 455.990071 -114.26906) (xy 456.039671 -114.243559) (xy 456.092455 -114.225552)
			(xy 456.147298 -114.215422) (xy 456.203032 -114.213385) (xy 456.258469 -114.219485) (xy 456.312426 -114.233591)
			(xy 456.363755 -114.255403) (xy 456.411361 -114.284457) (xy 456.454229 -114.320132) (xy 456.491446 -114.361669)
			(xy 456.522219 -114.408182) (xy 456.545891 -114.458679) (xy 456.561959 -114.512086) (xy 456.570079 -114.567262)
			(xy 456.570588 -114.595148) (xy 456.570079 -114.623034) (xy 456.561959 -114.67821) (xy 456.545891 -114.731617)
			(xy 456.522219 -114.782114) (xy 456.491446 -114.828627) (xy 456.454229 -114.870164) (xy 456.411361 -114.905839)
			(xy 456.363755 -114.934893) (xy 456.312426 -114.956705) (xy 456.258469 -114.970811) (xy 456.203032 -114.976911)
			(xy 456.147298 -114.974874) (xy 456.092455 -114.964744) (xy 456.039671 -114.946737) (xy 455.990071 -114.921236)
			(xy 455.944713 -114.888785) (xy 455.904564 -114.850076) (xy 455.870478 -114.805933) (xy 455.843182 -114.757298)
			(xy 455.823259 -114.705207) (xy 455.811133 -114.65077) (xy 455.807062 -114.595148) (xy 416.57778 -114.595148)
			(xy 417.77158 -115.788948) (xy 429.822862 -115.788948) (xy 429.826933 -115.733326) (xy 429.839059 -115.678889)
			(xy 429.858982 -115.626798) (xy 429.886278 -115.578163) (xy 429.920364 -115.53402) (xy 429.960513 -115.495311)
			(xy 430.005871 -115.46286) (xy 430.055471 -115.437359) (xy 430.108255 -115.419352) (xy 430.163098 -115.409222)
			(xy 430.218832 -115.407185) (xy 430.274269 -115.413285) (xy 430.328226 -115.427391) (xy 430.379555 -115.449203)
			(xy 430.427161 -115.478257) (xy 430.470029 -115.513932) (xy 430.507246 -115.555469) (xy 430.538019 -115.601982)
			(xy 430.561691 -115.652479) (xy 430.577759 -115.705886) (xy 430.585879 -115.761062) (xy 430.586388 -115.788948)
			(xy 430.711862 -115.788948) (xy 430.715933 -115.733326) (xy 430.728059 -115.678889) (xy 430.747982 -115.626798)
			(xy 430.775278 -115.578163) (xy 430.809364 -115.53402) (xy 430.849513 -115.495311) (xy 430.894871 -115.46286)
			(xy 430.944471 -115.437359) (xy 430.997255 -115.419352) (xy 431.052098 -115.409222) (xy 431.107832 -115.407185)
			(xy 431.163269 -115.413285) (xy 431.217226 -115.427391) (xy 431.268555 -115.449203) (xy 431.316161 -115.478257)
			(xy 431.359029 -115.513932) (xy 431.396246 -115.555469) (xy 431.427019 -115.601982) (xy 431.450691 -115.652479)
			(xy 431.466759 -115.705886) (xy 431.474879 -115.761062) (xy 431.475388 -115.788948) (xy 431.47524 -115.797076)
			(xy 431.632866 -115.797076) (xy 431.636937 -115.741454) (xy 431.649063 -115.687017) (xy 431.668986 -115.634926)
			(xy 431.696282 -115.586291) (xy 431.730368 -115.542148) (xy 431.770517 -115.503439) (xy 431.815875 -115.470988)
			(xy 431.865475 -115.445487) (xy 431.918259 -115.42748) (xy 431.973102 -115.41735) (xy 432.028836 -115.415313)
			(xy 432.084273 -115.421413) (xy 432.13823 -115.435519) (xy 432.189559 -115.457331) (xy 432.237165 -115.486385)
			(xy 432.280033 -115.52206) (xy 432.31725 -115.563597) (xy 432.348023 -115.61011) (xy 432.371695 -115.660607)
			(xy 432.387763 -115.714014) (xy 432.395883 -115.76919) (xy 432.396392 -115.797076) (xy 432.395883 -115.824962)
			(xy 432.387763 -115.880138) (xy 432.371695 -115.933545) (xy 432.348023 -115.984042) (xy 432.31725 -116.030555)
			(xy 432.280033 -116.072092) (xy 432.237165 -116.107767) (xy 432.189559 -116.136821) (xy 432.13823 -116.158633)
			(xy 432.084273 -116.172739) (xy 432.028836 -116.178839) (xy 431.973102 -116.176802) (xy 431.918259 -116.166672)
			(xy 431.865475 -116.148665) (xy 431.815875 -116.123164) (xy 431.770517 -116.090713) (xy 431.730368 -116.052004)
			(xy 431.696282 -116.007861) (xy 431.668986 -115.959226) (xy 431.649063 -115.907135) (xy 431.636937 -115.852698)
			(xy 431.632866 -115.797076) (xy 431.47524 -115.797076) (xy 431.474879 -115.816834) (xy 431.466759 -115.87201)
			(xy 431.450691 -115.925417) (xy 431.427019 -115.975914) (xy 431.396246 -116.022427) (xy 431.359029 -116.063964)
			(xy 431.316161 -116.099639) (xy 431.268555 -116.128693) (xy 431.217226 -116.150505) (xy 431.163269 -116.164611)
			(xy 431.107832 -116.170711) (xy 431.052098 -116.168674) (xy 430.997255 -116.158544) (xy 430.944471 -116.140537)
			(xy 430.894871 -116.115036) (xy 430.849513 -116.082585) (xy 430.809364 -116.043876) (xy 430.775278 -115.999733)
			(xy 430.747982 -115.951098) (xy 430.728059 -115.899007) (xy 430.715933 -115.84457) (xy 430.711862 -115.788948)
			(xy 430.586388 -115.788948) (xy 430.585879 -115.816834) (xy 430.577759 -115.87201) (xy 430.561691 -115.925417)
			(xy 430.538019 -115.975914) (xy 430.507246 -116.022427) (xy 430.470029 -116.063964) (xy 430.427161 -116.099639)
			(xy 430.379555 -116.128693) (xy 430.328226 -116.150505) (xy 430.274269 -116.164611) (xy 430.218832 -116.170711)
			(xy 430.163098 -116.168674) (xy 430.108255 -116.158544) (xy 430.055471 -116.140537) (xy 430.005871 -116.115036)
			(xy 429.960513 -116.082585) (xy 429.920364 -116.043876) (xy 429.886278 -115.999733) (xy 429.858982 -115.951098)
			(xy 429.839059 -115.899007) (xy 429.826933 -115.84457) (xy 429.822862 -115.788948) (xy 417.77158 -115.788948)
			(xy 418.372544 -116.389912) (xy 418.372544 -116.469668) (xy 433.69814 -116.469668) (xy 433.702211 -116.414046)
			(xy 433.714337 -116.359609) (xy 433.73426 -116.307518) (xy 433.761556 -116.258883) (xy 433.795642 -116.21474)
			(xy 433.835791 -116.176031) (xy 433.881149 -116.14358) (xy 433.930749 -116.118079) (xy 433.983533 -116.100072)
			(xy 434.038376 -116.089942) (xy 434.09411 -116.087905) (xy 434.149547 -116.094005) (xy 434.203504 -116.108111)
			(xy 434.214534 -116.112798) (xy 434.96814 -116.112798) (xy 434.972211 -116.057176) (xy 434.984337 -116.002739)
			(xy 435.00426 -115.950648) (xy 435.031556 -115.902013) (xy 435.065642 -115.85787) (xy 435.105791 -115.819161)
			(xy 435.151149 -115.78671) (xy 435.200749 -115.761209) (xy 435.253533 -115.743202) (xy 435.308376 -115.733072)
			(xy 435.36411 -115.731035) (xy 435.419547 -115.737135) (xy 435.473504 -115.751241) (xy 435.524833 -115.773053)
			(xy 435.572439 -115.802107) (xy 435.615307 -115.837782) (xy 435.652524 -115.879319) (xy 435.683297 -115.925832)
			(xy 435.706969 -115.976329) (xy 435.723037 -116.029736) (xy 435.731157 -116.084912) (xy 435.731666 -116.112798)
			(xy 435.731157 -116.140684) (xy 435.723037 -116.19586) (xy 435.706969 -116.249267) (xy 435.683297 -116.299764)
			(xy 435.652524 -116.346277) (xy 435.615307 -116.387814) (xy 435.572439 -116.423489) (xy 435.571687 -116.423948)
			(xy 436.807862 -116.423948) (xy 436.811933 -116.368326) (xy 436.824059 -116.313889) (xy 436.843982 -116.261798)
			(xy 436.871278 -116.213163) (xy 436.905364 -116.16902) (xy 436.945513 -116.130311) (xy 436.990871 -116.09786)
			(xy 437.040471 -116.072359) (xy 437.093255 -116.054352) (xy 437.148098 -116.044222) (xy 437.203832 -116.042185)
			(xy 437.259269 -116.048285) (xy 437.313226 -116.062391) (xy 437.364555 -116.084203) (xy 437.412161 -116.113257)
			(xy 437.455029 -116.148932) (xy 437.492246 -116.190469) (xy 437.523019 -116.236982) (xy 437.546691 -116.287479)
			(xy 437.561003 -116.335048) (xy 448.098162 -116.335048) (xy 448.102233 -116.279426) (xy 448.114359 -116.224989)
			(xy 448.134282 -116.172898) (xy 448.161578 -116.124263) (xy 448.195664 -116.08012) (xy 448.235813 -116.041411)
			(xy 448.281171 -116.00896) (xy 448.330771 -115.983459) (xy 448.383555 -115.965452) (xy 448.438398 -115.955322)
			(xy 448.494132 -115.953285) (xy 448.549569 -115.959385) (xy 448.603526 -115.973491) (xy 448.654855 -115.995303)
			(xy 448.702461 -116.024357) (xy 448.745329 -116.060032) (xy 448.782546 -116.101569) (xy 448.813319 -116.148082)
			(xy 448.836991 -116.198579) (xy 448.853059 -116.251986) (xy 448.861179 -116.307162) (xy 448.861688 -116.335048)
			(xy 448.861179 -116.362934) (xy 448.853059 -116.41811) (xy 448.836991 -116.471517) (xy 448.813319 -116.522014)
			(xy 448.782546 -116.568527) (xy 448.745329 -116.610064) (xy 448.702461 -116.645739) (xy 448.654855 -116.674793)
			(xy 448.603526 -116.696605) (xy 448.549569 -116.710711) (xy 448.494132 -116.716811) (xy 448.438398 -116.714774)
			(xy 448.383555 -116.704644) (xy 448.330771 -116.686637) (xy 448.281171 -116.661136) (xy 448.235813 -116.628685)
			(xy 448.195664 -116.589976) (xy 448.161578 -116.545833) (xy 448.134282 -116.497198) (xy 448.114359 -116.445107)
			(xy 448.102233 -116.39067) (xy 448.098162 -116.335048) (xy 437.561003 -116.335048) (xy 437.562759 -116.340886)
			(xy 437.570879 -116.396062) (xy 437.571388 -116.423948) (xy 437.570879 -116.451834) (xy 437.562759 -116.50701)
			(xy 437.546691 -116.560417) (xy 437.523019 -116.610914) (xy 437.492246 -116.657427) (xy 437.455029 -116.698964)
			(xy 437.412161 -116.734639) (xy 437.364555 -116.763693) (xy 437.313226 -116.785505) (xy 437.259269 -116.799611)
			(xy 437.203832 -116.805711) (xy 437.148098 -116.803674) (xy 437.093255 -116.793544) (xy 437.040471 -116.775537)
			(xy 436.990871 -116.750036) (xy 436.945513 -116.717585) (xy 436.905364 -116.678876) (xy 436.871278 -116.634733)
			(xy 436.843982 -116.586098) (xy 436.824059 -116.534007) (xy 436.811933 -116.47957) (xy 436.807862 -116.423948)
			(xy 435.571687 -116.423948) (xy 435.524833 -116.452543) (xy 435.473504 -116.474355) (xy 435.419547 -116.488461)
			(xy 435.36411 -116.494561) (xy 435.308376 -116.492524) (xy 435.253533 -116.482394) (xy 435.200749 -116.464387)
			(xy 435.151149 -116.438886) (xy 435.105791 -116.406435) (xy 435.065642 -116.367726) (xy 435.031556 -116.323583)
			(xy 435.00426 -116.274948) (xy 434.984337 -116.222857) (xy 434.972211 -116.16842) (xy 434.96814 -116.112798)
			(xy 434.214534 -116.112798) (xy 434.254833 -116.129923) (xy 434.302439 -116.158977) (xy 434.345307 -116.194652)
			(xy 434.382524 -116.236189) (xy 434.413297 -116.282702) (xy 434.436969 -116.333199) (xy 434.453037 -116.386606)
			(xy 434.461157 -116.441782) (xy 434.461666 -116.469668) (xy 434.461157 -116.497554) (xy 434.453037 -116.55273)
			(xy 434.436969 -116.606137) (xy 434.413297 -116.656634) (xy 434.382524 -116.703147) (xy 434.345307 -116.744684)
			(xy 434.302439 -116.780359) (xy 434.254833 -116.809413) (xy 434.203504 -116.831225) (xy 434.149547 -116.845331)
			(xy 434.09411 -116.851431) (xy 434.038376 -116.849394) (xy 433.983533 -116.839264) (xy 433.930749 -116.821257)
			(xy 433.881149 -116.795756) (xy 433.835791 -116.763305) (xy 433.795642 -116.724596) (xy 433.761556 -116.680453)
			(xy 433.73426 -116.631818) (xy 433.714337 -116.579727) (xy 433.702211 -116.52529) (xy 433.69814 -116.469668)
			(xy 418.372544 -116.469668) (xy 418.372544 -117.469158) (xy 418.413984 -117.5106) (xy 428.267046 -117.5106)
			(xy 428.270961 -117.433401) (xy 428.282667 -117.356995) (xy 428.302042 -117.282164) (xy 428.328889 -117.209678)
			(xy 428.362931 -117.14028) (xy 428.40382 -117.074682) (xy 428.451135 -117.013557) (xy 428.504392 -116.957533)
			(xy 428.563044 -116.907185) (xy 428.626488 -116.863028) (xy 428.694075 -116.825517) (xy 428.765109 -116.795036)
			(xy 428.838863 -116.771899) (xy 428.914579 -116.756341) (xy 428.991481 -116.748524) (xy 429.03013 -116.748052)
			(xy 429.069615 -116.748551) (xy 429.148161 -116.756716) (xy 429.225443 -116.772955) (xy 429.300633 -116.797094)
			(xy 429.372926 -116.828874) (xy 429.441547 -116.867956) (xy 429.505761 -116.91392) (xy 429.564881 -116.966275)
			(xy 429.618273 -117.02446) (xy 429.665366 -117.087851) (xy 429.705656 -117.15577) (xy 429.723193 -117.193822)
			(xy 448.512182 -117.193822) (xy 448.516253 -117.1382) (xy 448.528379 -117.083763) (xy 448.548302 -117.031672)
			(xy 448.575598 -116.983037) (xy 448.609684 -116.938894) (xy 448.649833 -116.900185) (xy 448.695191 -116.867734)
			(xy 448.744791 -116.842233) (xy 448.797575 -116.824226) (xy 448.852418 -116.814096) (xy 448.908152 -116.812059)
			(xy 448.963589 -116.818159) (xy 449.017546 -116.832265) (xy 449.068875 -116.854077) (xy 449.116481 -116.883131)
			(xy 449.159349 -116.918806) (xy 449.196566 -116.960343) (xy 449.227339 -117.006856) (xy 449.251011 -117.057353)
			(xy 449.267079 -117.11076) (xy 449.275199 -117.165936) (xy 449.275708 -117.193822) (xy 449.275199 -117.221708)
			(xy 449.267079 -117.276884) (xy 449.251011 -117.330291) (xy 449.227339 -117.380788) (xy 449.196566 -117.427301)
			(xy 449.159349 -117.468838) (xy 449.116481 -117.504513) (xy 449.068875 -117.533567) (xy 449.017546 -117.555379)
			(xy 448.963589 -117.569485) (xy 448.908152 -117.575585) (xy 448.852418 -117.573548) (xy 448.797575 -117.563418)
			(xy 448.744791 -117.545411) (xy 448.695191 -117.51991) (xy 448.649833 -117.487459) (xy 448.609684 -117.44875)
			(xy 448.575598 -117.404607) (xy 448.548302 -117.355972) (xy 448.528379 -117.303881) (xy 448.516253 -117.249444)
			(xy 448.512182 -117.193822) (xy 429.723193 -117.193822) (xy 429.73871 -117.227489) (xy 429.764175 -117.302241)
			(xy 429.781778 -117.379223) (xy 429.78705 -117.418358) (xy 429.789156 -117.43165) (xy 429.799269 -117.456574)
			(xy 429.815545 -117.477989) (xy 429.836854 -117.494403) (xy 429.861712 -117.504677) (xy 429.888392 -117.508095)
			(xy 429.915038 -117.50442) (xy 429.939796 -117.493907) (xy 429.950626 -117.485922) (xy 429.970876 -117.470511)
			(xy 430.014717 -117.444672) (xy 430.061604 -117.42489) (xy 430.110705 -117.411517) (xy 430.161147 -117.40479)
			(xy 430.186592 -117.404388) (xy 430.213845 -117.404859) (xy 430.267796 -117.412615) (xy 430.320094 -117.42797)
			(xy 430.369675 -117.450612) (xy 430.415529 -117.480079) (xy 430.456722 -117.515772) (xy 430.492416 -117.556965)
			(xy 430.521884 -117.602818) (xy 430.544527 -117.652398) (xy 430.559884 -117.704696) (xy 430.567641 -117.758647)
			(xy 430.567641 -117.785896) (xy 430.820574 -117.785896) (xy 430.824645 -117.730274) (xy 430.836771 -117.675837)
			(xy 430.856694 -117.623746) (xy 430.88399 -117.575111) (xy 430.918076 -117.530968) (xy 430.958225 -117.492259)
			(xy 431.003583 -117.459808) (xy 431.053183 -117.434307) (xy 431.105967 -117.4163) (xy 431.16081 -117.40617)
			(xy 431.216544 -117.404133) (xy 431.271981 -117.410233) (xy 431.325938 -117.424339) (xy 431.377267 -117.446151)
			(xy 431.424873 -117.475205) (xy 431.467741 -117.51088) (xy 431.504958 -117.552417) (xy 431.535731 -117.59893)
			(xy 431.559403 -117.649427) (xy 431.575471 -117.702834) (xy 431.583591 -117.75801) (xy 431.5841 -117.785896)
			(xy 431.583591 -117.813782) (xy 431.575471 -117.868958) (xy 431.559403 -117.922365) (xy 431.535731 -117.972862)
			(xy 431.504958 -118.019375) (xy 431.467741 -118.060912) (xy 431.424873 -118.096587) (xy 431.377267 -118.125641)
			(xy 431.325938 -118.147453) (xy 431.271981 -118.161559) (xy 431.216544 -118.167659) (xy 431.16081 -118.165622)
			(xy 431.105967 -118.155492) (xy 431.053183 -118.137485) (xy 431.003583 -118.111984) (xy 430.958225 -118.079533)
			(xy 430.918076 -118.040824) (xy 430.88399 -117.996681) (xy 430.856694 -117.948046) (xy 430.836771 -117.895955)
			(xy 430.824645 -117.841518) (xy 430.820574 -117.785896) (xy 430.567641 -117.785896) (xy 430.567641 -117.813153)
			(xy 430.559884 -117.867104) (xy 430.544527 -117.919402) (xy 430.521884 -117.968982) (xy 430.492416 -118.014835)
			(xy 430.456722 -118.056028) (xy 430.415529 -118.091721) (xy 430.369675 -118.121188) (xy 430.320094 -118.14383)
			(xy 430.267796 -118.159185) (xy 430.213845 -118.166941) (xy 430.186592 -118.167404) (xy 430.159537 -118.166929)
			(xy 430.105972 -118.15927) (xy 430.054026 -118.144122) (xy 430.00474 -118.121787) (xy 429.959104 -118.092715)
			(xy 429.918032 -118.057488) (xy 429.882348 -118.016812) (xy 429.852767 -117.971503) (xy 429.840898 -117.947186)
			(xy 429.834793 -117.935188) (xy 429.817402 -117.914653) (xy 429.795248 -117.899377) (xy 429.769872 -117.890424)
			(xy 429.743037 -117.888414) (xy 429.71661 -117.893489) (xy 429.692428 -117.905294) (xy 429.672172 -117.92301)
			(xy 429.664368 -117.933978) (xy 429.643235 -117.964905) (xy 429.59572 -118.022819) (xy 429.542756 -118.075796)
			(xy 429.484853 -118.123325) (xy 429.422569 -118.164948) (xy 429.356505 -118.200264) (xy 429.287296 -118.228932)
			(xy 429.21561 -118.250677) (xy 429.142137 -118.265288) (xy 429.067586 -118.272626) (xy 429.03013 -118.273068)
			(xy 428.991481 -118.272676) (xy 428.914579 -118.264859) (xy 428.838863 -118.249301) (xy 428.765109 -118.226164)
			(xy 428.694075 -118.195683) (xy 428.626488 -118.158172) (xy 428.563044 -118.114015) (xy 428.504392 -118.063667)
			(xy 428.451135 -118.007643) (xy 428.40382 -117.946518) (xy 428.362931 -117.88092) (xy 428.328889 -117.811522)
			(xy 428.302042 -117.739036) (xy 428.282667 -117.664205) (xy 428.270961 -117.587799) (xy 428.267046 -117.5106)
			(xy 418.413984 -117.5106) (xy 419.252094 -118.34876) (xy 427.051722 -118.34876) (xy 427.055793 -118.293138)
			(xy 427.067919 -118.238701) (xy 427.087842 -118.18661) (xy 427.115138 -118.137975) (xy 427.149224 -118.093832)
			(xy 427.189373 -118.055123) (xy 427.234731 -118.022672) (xy 427.284331 -117.997171) (xy 427.337115 -117.979164)
			(xy 427.391958 -117.969034) (xy 427.447692 -117.966997) (xy 427.503129 -117.973097) (xy 427.557086 -117.987203)
			(xy 427.608415 -118.009015) (xy 427.656021 -118.038069) (xy 427.698889 -118.073744) (xy 427.736106 -118.115281)
			(xy 427.766879 -118.161794) (xy 427.790551 -118.212291) (xy 427.806619 -118.265698) (xy 427.814739 -118.320874)
			(xy 427.815248 -118.34876) (xy 427.814739 -118.376646) (xy 427.806619 -118.431822) (xy 427.790551 -118.485229)
			(xy 427.766879 -118.535726) (xy 427.736106 -118.582239) (xy 427.698889 -118.623776) (xy 427.656021 -118.659451)
			(xy 427.608415 -118.688505) (xy 427.557086 -118.710317) (xy 427.503129 -118.724423) (xy 427.447692 -118.730523)
			(xy 427.391958 -118.728486) (xy 427.337115 -118.718356) (xy 427.284331 -118.700349) (xy 427.234731 -118.674848)
			(xy 427.189373 -118.642397) (xy 427.149224 -118.603688) (xy 427.115138 -118.559545) (xy 427.087842 -118.51091)
			(xy 427.067919 -118.458819) (xy 427.055793 -118.404382) (xy 427.051722 -118.34876) (xy 419.252094 -118.34876)
			(xy 420.252286 -119.349012) (xy 427.200058 -119.349012) (xy 427.204129 -119.29339) (xy 427.216255 -119.238953)
			(xy 427.236178 -119.186862) (xy 427.263474 -119.138227) (xy 427.29756 -119.094084) (xy 427.337709 -119.055375)
			(xy 427.383067 -119.022924) (xy 427.432667 -118.997423) (xy 427.485451 -118.979416) (xy 427.540294 -118.969286)
			(xy 427.596028 -118.967249) (xy 427.651465 -118.973349) (xy 427.705422 -118.987455) (xy 427.756751 -119.009267)
			(xy 427.804357 -119.038321) (xy 427.82395 -119.054626) (xy 431.577244 -119.054626) (xy 431.581288 -118.976172)
			(xy 431.593377 -118.89855) (xy 431.613384 -118.822582) (xy 431.641095 -118.749074) (xy 431.676218 -118.678805)
			(xy 431.71838 -118.61252) (xy 431.767134 -118.550921) (xy 431.821963 -118.494661) (xy 431.882286 -118.444337)
			(xy 431.947464 -118.400483) (xy 432.016805 -118.363562) (xy 432.089576 -118.333967) (xy 432.165003 -118.312012)
			(xy 432.242288 -118.297928) (xy 432.320612 -118.291865) (xy 432.399144 -118.293888) (xy 432.477052 -118.303974)
			(xy 432.553509 -118.322018) (xy 432.627707 -118.347828) (xy 432.698857 -118.38113) (xy 432.766206 -118.421571)
			(xy 432.82904 -118.468722) (xy 432.886692 -118.522085) (xy 432.938552 -118.581092) (xy 432.984071 -118.645119)
			(xy 433.022764 -118.713487) (xy 433.054223 -118.785471) (xy 433.078114 -118.860308) (xy 433.094183 -118.937205)
			(xy 433.097394 -118.968266) (xy 434.33365 -118.968266) (xy 434.334127 -118.941663) (xy 434.341501 -118.88897)
			(xy 434.356129 -118.837814) (xy 434.377726 -118.789188) (xy 434.405874 -118.744037) (xy 434.440025 -118.703238)
			(xy 434.479517 -118.667583) (xy 434.50129 -118.65229) (xy 434.512755 -118.643936) (xy 434.53096 -118.622198)
			(xy 434.542479 -118.596288) (xy 434.546422 -118.568209) (xy 434.542484 -118.540129) (xy 434.53097 -118.514218)
			(xy 434.512769 -118.492476) (xy 434.50129 -118.484142) (xy 434.479542 -118.468817) (xy 434.44006 -118.433157)
			(xy 434.405913 -118.39236) (xy 434.377764 -118.347215) (xy 434.356158 -118.298598) (xy 434.341514 -118.247452)
			(xy 434.334116 -118.194767) (xy 434.33365 -118.168166) (xy 434.334136 -118.140915) (xy 434.341892 -118.086967)
			(xy 434.357247 -118.034672) (xy 434.379889 -117.985095) (xy 434.409355 -117.939245) (xy 434.445046 -117.898054)
			(xy 434.486237 -117.862363) (xy 434.532087 -117.832897) (xy 434.581664 -117.810255) (xy 434.633959 -117.7949)
			(xy 434.687907 -117.787144) (xy 434.742409 -117.787144) (xy 434.796357 -117.7949) (xy 434.848652 -117.810255)
			(xy 434.898229 -117.832897) (xy 434.944079 -117.862363) (xy 434.98527 -117.898054) (xy 435.020961 -117.939245)
			(xy 435.050427 -117.985095) (xy 435.073069 -118.034672) (xy 435.084895 -118.074948) (xy 443.284862 -118.074948)
			(xy 443.288933 -118.019326) (xy 443.301059 -117.964889) (xy 443.320982 -117.912798) (xy 443.348278 -117.864163)
			(xy 443.382364 -117.82002) (xy 443.422513 -117.781311) (xy 443.467871 -117.74886) (xy 443.517471 -117.723359)
			(xy 443.570255 -117.705352) (xy 443.625098 -117.695222) (xy 443.680832 -117.693185) (xy 443.736269 -117.699285)
			(xy 443.790226 -117.713391) (xy 443.841555 -117.735203) (xy 443.889161 -117.764257) (xy 443.932029 -117.799932)
			(xy 443.969246 -117.841469) (xy 444.000019 -117.887982) (xy 444.023691 -117.938479) (xy 444.039759 -117.991886)
			(xy 444.047879 -118.047062) (xy 444.048388 -118.074948) (xy 444.047879 -118.102834) (xy 444.039759 -118.15801)
			(xy 444.023691 -118.211417) (xy 444.000019 -118.261914) (xy 443.969246 -118.308427) (xy 443.943804 -118.336822)
			(xy 448.512182 -118.336822) (xy 448.516253 -118.2812) (xy 448.528379 -118.226763) (xy 448.548302 -118.174672)
			(xy 448.575598 -118.126037) (xy 448.609684 -118.081894) (xy 448.649833 -118.043185) (xy 448.695191 -118.010734)
			(xy 448.744791 -117.985233) (xy 448.797575 -117.967226) (xy 448.852418 -117.957096) (xy 448.908152 -117.955059)
			(xy 448.963589 -117.961159) (xy 449.017546 -117.975265) (xy 449.068875 -117.997077) (xy 449.116481 -118.026131)
			(xy 449.159349 -118.061806) (xy 449.196566 -118.103343) (xy 449.227339 -118.149856) (xy 449.251011 -118.200353)
			(xy 449.267079 -118.25376) (xy 449.275199 -118.308936) (xy 449.275708 -118.336822) (xy 449.275199 -118.364708)
			(xy 449.267079 -118.419884) (xy 449.251011 -118.473291) (xy 449.227339 -118.523788) (xy 449.196566 -118.570301)
			(xy 449.159349 -118.611838) (xy 449.116481 -118.647513) (xy 449.068875 -118.676567) (xy 449.017546 -118.698379)
			(xy 448.963589 -118.712485) (xy 448.908152 -118.718585) (xy 448.852418 -118.716548) (xy 448.797575 -118.706418)
			(xy 448.744791 -118.688411) (xy 448.695191 -118.66291) (xy 448.649833 -118.630459) (xy 448.609684 -118.59175)
			(xy 448.575598 -118.547607) (xy 448.548302 -118.498972) (xy 448.528379 -118.446881) (xy 448.516253 -118.392444)
			(xy 448.512182 -118.336822) (xy 443.943804 -118.336822) (xy 443.932029 -118.349964) (xy 443.889161 -118.385639)
			(xy 443.841555 -118.414693) (xy 443.790226 -118.436505) (xy 443.736269 -118.450611) (xy 443.680832 -118.456711)
			(xy 443.625098 -118.454674) (xy 443.570255 -118.444544) (xy 443.517471 -118.426537) (xy 443.467871 -118.401036)
			(xy 443.422513 -118.368585) (xy 443.382364 -118.329876) (xy 443.348278 -118.285733) (xy 443.320982 -118.237098)
			(xy 443.301059 -118.185007) (xy 443.288933 -118.13057) (xy 443.284862 -118.074948) (xy 435.084895 -118.074948)
			(xy 435.088424 -118.086967) (xy 435.09618 -118.140915) (xy 435.096666 -118.168166) (xy 435.096206 -118.19477)
			(xy 435.088828 -118.247463) (xy 435.074197 -118.298619) (xy 435.052597 -118.347245) (xy 435.024447 -118.392395)
			(xy 434.990293 -118.433194) (xy 434.9508 -118.468849) (xy 434.929026 -118.484142) (xy 434.917528 -118.492455)
			(xy 434.899319 -118.514202) (xy 434.8878 -118.540121) (xy 434.883861 -118.568209) (xy 434.887805 -118.596297)
			(xy 434.899329 -118.622213) (xy 434.917541 -118.643957) (xy 434.929026 -118.65229) (xy 434.950793 -118.66759)
			(xy 434.990274 -118.703254) (xy 435.024418 -118.744056) (xy 435.052565 -118.789205) (xy 435.074168 -118.837826)
			(xy 435.088808 -118.888976) (xy 435.096203 -118.941664) (xy 435.096666 -118.968266) (xy 435.09618 -118.995517)
			(xy 435.088424 -119.049465) (xy 435.075498 -119.093488) (xy 461.597246 -119.093488) (xy 461.601317 -119.037866)
			(xy 461.613443 -118.983429) (xy 461.633366 -118.931338) (xy 461.660662 -118.882703) (xy 461.694748 -118.83856)
			(xy 461.734897 -118.799851) (xy 461.780255 -118.7674) (xy 461.829855 -118.741899) (xy 461.882639 -118.723892)
			(xy 461.937482 -118.713762) (xy 461.993216 -118.711725) (xy 462.048653 -118.717825) (xy 462.10261 -118.731931)
			(xy 462.153939 -118.753743) (xy 462.201545 -118.782797) (xy 462.244413 -118.818472) (xy 462.28163 -118.860009)
			(xy 462.312403 -118.906522) (xy 462.336075 -118.957019) (xy 462.352143 -119.010426) (xy 462.360263 -119.065602)
			(xy 462.360772 -119.093488) (xy 462.360263 -119.121374) (xy 462.352143 -119.17655) (xy 462.336075 -119.229957)
			(xy 462.312403 -119.280454) (xy 462.28163 -119.326967) (xy 462.244413 -119.368504) (xy 462.201545 -119.404179)
			(xy 462.153939 -119.433233) (xy 462.10261 -119.455045) (xy 462.048653 -119.469151) (xy 461.993216 -119.475251)
			(xy 461.937482 -119.473214) (xy 461.882639 -119.463084) (xy 461.829855 -119.445077) (xy 461.780255 -119.419576)
			(xy 461.734897 -119.387125) (xy 461.694748 -119.348416) (xy 461.660662 -119.304273) (xy 461.633366 -119.255638)
			(xy 461.613443 -119.203547) (xy 461.601317 -119.14911) (xy 461.597246 -119.093488) (xy 435.075498 -119.093488)
			(xy 435.073069 -119.10176) (xy 435.050427 -119.151337) (xy 435.020961 -119.197187) (xy 434.98527 -119.238378)
			(xy 434.944079 -119.274069) (xy 434.898229 -119.303535) (xy 434.848652 -119.326177) (xy 434.796357 -119.341532)
			(xy 434.742409 -119.349288) (xy 434.687907 -119.349288) (xy 434.633959 -119.341532) (xy 434.581664 -119.326177)
			(xy 434.532087 -119.303535) (xy 434.486237 -119.274069) (xy 434.445046 -119.238378) (xy 434.409355 -119.197187)
			(xy 434.379889 -119.151337) (xy 434.357247 -119.10176) (xy 434.341892 -119.049465) (xy 434.334136 -118.995517)
			(xy 434.33365 -118.968266) (xy 433.097394 -118.968266) (xy 433.10226 -119.015347) (xy 433.102766 -119.054626)
			(xy 433.10226 -119.093905) (xy 433.094183 -119.172047) (xy 433.078114 -119.248944) (xy 433.054223 -119.323781)
			(xy 433.022764 -119.395765) (xy 432.984071 -119.464133) (xy 432.938552 -119.52816) (xy 432.889286 -119.584216)
			(xy 433.69814 -119.584216) (xy 433.702211 -119.528594) (xy 433.714337 -119.474157) (xy 433.73426 -119.422066)
			(xy 433.761556 -119.373431) (xy 433.795642 -119.329288) (xy 433.835791 -119.290579) (xy 433.881149 -119.258128)
			(xy 433.930749 -119.232627) (xy 433.983533 -119.21462) (xy 434.038376 -119.20449) (xy 434.09411 -119.202453)
			(xy 434.149547 -119.208553) (xy 434.203504 -119.222659) (xy 434.254833 -119.244471) (xy 434.302439 -119.273525)
			(xy 434.345307 -119.3092) (xy 434.382524 -119.350737) (xy 434.413297 -119.39725) (xy 434.436969 -119.447747)
			(xy 434.453037 -119.501154) (xy 434.461157 -119.55633) (xy 434.461666 -119.584216) (xy 434.96814 -119.584216)
			(xy 434.972211 -119.528594) (xy 434.984337 -119.474157) (xy 435.00426 -119.422066) (xy 435.031556 -119.373431)
			(xy 435.065642 -119.329288) (xy 435.105791 -119.290579) (xy 435.151149 -119.258128) (xy 435.200749 -119.232627)
			(xy 435.253533 -119.21462) (xy 435.308376 -119.20449) (xy 435.36411 -119.202453) (xy 435.419547 -119.208553)
			(xy 435.473504 -119.222659) (xy 435.524833 -119.244471) (xy 435.572439 -119.273525) (xy 435.615307 -119.3092)
			(xy 435.652524 -119.350737) (xy 435.683297 -119.39725) (xy 435.706969 -119.447747) (xy 435.723037 -119.501154)
			(xy 435.731157 -119.55633) (xy 435.731666 -119.584216) (xy 435.731157 -119.612102) (xy 435.723037 -119.667278)
			(xy 435.706969 -119.720685) (xy 435.683297 -119.771182) (xy 435.652524 -119.817695) (xy 435.615307 -119.859232)
			(xy 435.572439 -119.894907) (xy 435.524833 -119.923961) (xy 435.473504 -119.945773) (xy 435.419547 -119.959879)
			(xy 435.36411 -119.965979) (xy 435.308376 -119.963942) (xy 435.253533 -119.953812) (xy 435.200749 -119.935805)
			(xy 435.151149 -119.910304) (xy 435.105791 -119.877853) (xy 435.065642 -119.839144) (xy 435.031556 -119.795001)
			(xy 435.00426 -119.746366) (xy 434.984337 -119.694275) (xy 434.972211 -119.639838) (xy 434.96814 -119.584216)
			(xy 434.461666 -119.584216) (xy 434.461157 -119.612102) (xy 434.453037 -119.667278) (xy 434.436969 -119.720685)
			(xy 434.413297 -119.771182) (xy 434.382524 -119.817695) (xy 434.345307 -119.859232) (xy 434.302439 -119.894907)
			(xy 434.254833 -119.923961) (xy 434.203504 -119.945773) (xy 434.149547 -119.959879) (xy 434.09411 -119.965979)
			(xy 434.038376 -119.963942) (xy 433.983533 -119.953812) (xy 433.930749 -119.935805) (xy 433.881149 -119.910304)
			(xy 433.835791 -119.877853) (xy 433.795642 -119.839144) (xy 433.761556 -119.795001) (xy 433.73426 -119.746366)
			(xy 433.714337 -119.694275) (xy 433.702211 -119.639838) (xy 433.69814 -119.584216) (xy 432.889286 -119.584216)
			(xy 432.886692 -119.587167) (xy 432.82904 -119.64053) (xy 432.766206 -119.687681) (xy 432.698857 -119.728122)
			(xy 432.627707 -119.761424) (xy 432.553509 -119.787234) (xy 432.477052 -119.805278) (xy 432.399144 -119.815364)
			(xy 432.320612 -119.817387) (xy 432.242288 -119.811324) (xy 432.165003 -119.79724) (xy 432.089576 -119.775285)
			(xy 432.016805 -119.74569) (xy 431.947464 -119.708769) (xy 431.882286 -119.664915) (xy 431.821963 -119.614591)
			(xy 431.767134 -119.558331) (xy 431.71838 -119.496732) (xy 431.676218 -119.430447) (xy 431.641095 -119.360178)
			(xy 431.613384 -119.28667) (xy 431.593377 -119.210702) (xy 431.581288 -119.13308) (xy 431.577244 -119.054626)
			(xy 427.82395 -119.054626) (xy 427.847225 -119.073996) (xy 427.884442 -119.115533) (xy 427.915215 -119.162046)
			(xy 427.938887 -119.212543) (xy 427.954955 -119.26595) (xy 427.963075 -119.321126) (xy 427.963584 -119.349012)
			(xy 427.963075 -119.376898) (xy 427.954955 -119.432074) (xy 427.938887 -119.485481) (xy 427.915215 -119.535978)
			(xy 427.884442 -119.582491) (xy 427.847225 -119.624028) (xy 427.804357 -119.659703) (xy 427.756751 -119.688757)
			(xy 427.705422 -119.710569) (xy 427.651465 -119.724675) (xy 427.596028 -119.730775) (xy 427.540294 -119.728738)
			(xy 427.485451 -119.718608) (xy 427.432667 -119.700601) (xy 427.383067 -119.6751) (xy 427.337709 -119.642649)
			(xy 427.29756 -119.60394) (xy 427.263474 -119.559797) (xy 427.236178 -119.511162) (xy 427.216255 -119.459071)
			(xy 427.204129 -119.404634) (xy 427.200058 -119.349012) (xy 420.252286 -119.349012) (xy 420.819688 -119.916448)
			(xy 422.520362 -119.916448) (xy 422.524433 -119.860826) (xy 422.536559 -119.806389) (xy 422.556482 -119.754298)
			(xy 422.583778 -119.705663) (xy 422.617864 -119.66152) (xy 422.658013 -119.622811) (xy 422.703371 -119.59036)
			(xy 422.752971 -119.564859) (xy 422.805755 -119.546852) (xy 422.860598 -119.536722) (xy 422.916332 -119.534685)
			(xy 422.971769 -119.540785) (xy 423.025726 -119.554891) (xy 423.077055 -119.576703) (xy 423.124661 -119.605757)
			(xy 423.167529 -119.641432) (xy 423.204746 -119.682969) (xy 423.235519 -119.729482) (xy 423.259191 -119.779979)
			(xy 423.275259 -119.833386) (xy 423.283379 -119.888562) (xy 423.283888 -119.916448) (xy 423.283379 -119.944334)
			(xy 423.275259 -119.99951) (xy 423.259191 -120.052917) (xy 423.235519 -120.103414) (xy 423.204746 -120.149927)
			(xy 423.167529 -120.191464) (xy 423.124661 -120.227139) (xy 423.106845 -120.238012) (xy 427.221396 -120.238012)
			(xy 427.221882 -120.210761) (xy 427.229638 -120.156813) (xy 427.244993 -120.104518) (xy 427.267635 -120.054941)
			(xy 427.297101 -120.009091) (xy 427.332792 -119.9679) (xy 427.373983 -119.932209) (xy 427.419833 -119.902743)
			(xy 427.46941 -119.880101) (xy 427.521705 -119.864746) (xy 427.575653 -119.85699) (xy 427.630155 -119.85699)
			(xy 427.684103 -119.864746) (xy 427.736398 -119.880101) (xy 427.785975 -119.902743) (xy 427.831825 -119.932209)
			(xy 427.873016 -119.9679) (xy 427.908707 -120.009091) (xy 427.93699 -120.0531) (xy 429.31893 -120.0531)
			(xy 429.322974 -119.974646) (xy 429.335063 -119.897024) (xy 429.35507 -119.821056) (xy 429.382781 -119.747548)
			(xy 429.417904 -119.677279) (xy 429.460066 -119.610994) (xy 429.50882 -119.549395) (xy 429.563649 -119.493135)
			(xy 429.623972 -119.442811) (xy 429.68915 -119.398957) (xy 429.758491 -119.362036) (xy 429.831262 -119.332441)
			(xy 429.906689 -119.310486) (xy 429.983974 -119.296402) (xy 430.062298 -119.290339) (xy 430.14083 -119.292362)
			(xy 430.218738 -119.302448) (xy 430.295195 -119.320492) (xy 430.369393 -119.346302) (xy 430.440543 -119.379604)
			(xy 430.507892 -119.420045) (xy 430.570726 -119.467196) (xy 430.628378 -119.520559) (xy 430.680238 -119.579566)
			(xy 430.725757 -119.643593) (xy 430.76445 -119.711961) (xy 430.795909 -119.783945) (xy 430.8198 -119.858782)
			(xy 430.835869 -119.935679) (xy 430.843946 -120.013821) (xy 430.844452 -120.0531) (xy 430.843946 -120.092379)
			(xy 430.835869 -120.170521) (xy 430.8198 -120.247418) (xy 430.795909 -120.322255) (xy 430.76445 -120.394239)
			(xy 430.725757 -120.462607) (xy 430.680238 -120.526634) (xy 430.628378 -120.585641) (xy 430.570726 -120.639004)
			(xy 430.507892 -120.686155) (xy 430.440543 -120.726596) (xy 430.369393 -120.759898) (xy 430.295195 -120.785708)
			(xy 430.218738 -120.803752) (xy 430.14083 -120.813838) (xy 430.062298 -120.815861) (xy 429.983974 -120.809798)
			(xy 429.906689 -120.795714) (xy 429.831262 -120.773759) (xy 429.758491 -120.744164) (xy 429.68915 -120.707243)
			(xy 429.623972 -120.663389) (xy 429.563649 -120.613065) (xy 429.50882 -120.556805) (xy 429.460066 -120.495206)
			(xy 429.417904 -120.428921) (xy 429.382781 -120.358652) (xy 429.35507 -120.285144) (xy 429.335063 -120.209176)
			(xy 429.322974 -120.131554) (xy 429.31893 -120.0531) (xy 427.93699 -120.0531) (xy 427.938173 -120.054941)
			(xy 427.960815 -120.104518) (xy 427.97617 -120.156813) (xy 427.983926 -120.210761) (xy 427.984412 -120.238012)
			(xy 427.983871 -120.268234) (xy 427.974372 -120.327925) (xy 427.955565 -120.385367) (xy 427.927923 -120.439119)
			(xy 427.910498 -120.463818) (xy 427.902886 -120.474932) (xy 427.893193 -120.500054) (xy 427.890409 -120.526838)
			(xy 427.89473 -120.553416) (xy 427.905852 -120.577939) (xy 427.923003 -120.598698) (xy 427.944987 -120.614248)
			(xy 427.957488 -120.619266) (xy 427.98463 -120.629809) (xy 428.035637 -120.657889) (xy 428.081785 -120.693392)
			(xy 428.122002 -120.735495) (xy 428.155356 -120.78322) (xy 428.181071 -120.835458) (xy 428.19855 -120.890997)
			(xy 428.207387 -120.948548) (xy 428.207932 -120.97766) (xy 428.207446 -121.004911) (xy 428.19969 -121.058859)
			(xy 428.184335 -121.111154) (xy 428.161693 -121.160731) (xy 428.132227 -121.206581) (xy 428.096536 -121.247772)
			(xy 428.055345 -121.283463) (xy 428.009495 -121.312929) (xy 427.959918 -121.335571) (xy 427.907623 -121.350926)
			(xy 427.853675 -121.358682) (xy 427.799173 -121.358682) (xy 427.745225 -121.350926) (xy 427.69293 -121.335571)
			(xy 427.643353 -121.312929) (xy 427.597503 -121.283463) (xy 427.556312 -121.247772) (xy 427.520621 -121.206581)
			(xy 427.491155 -121.160731) (xy 427.468513 -121.111154) (xy 427.453158 -121.058859) (xy 427.445402 -121.004911)
			(xy 427.444916 -120.97766) (xy 427.445488 -120.947439) (xy 427.454977 -120.887749) (xy 427.473775 -120.830307)
			(xy 427.501409 -120.776554) (xy 427.51883 -120.751854) (xy 427.526463 -120.740755) (xy 427.536149 -120.715628)
			(xy 427.538926 -120.688842) (xy 427.534602 -120.662263) (xy 427.523476 -120.637739) (xy 427.506325 -120.616978)
			(xy 427.484341 -120.601426) (xy 427.47184 -120.596406) (xy 427.444672 -120.585926) (xy 427.393667 -120.557834)
			(xy 427.347521 -120.52232) (xy 427.307307 -120.480207) (xy 427.273957 -120.432474) (xy 427.248246 -120.380228)
			(xy 427.230772 -120.324683) (xy 427.221938 -120.267127) (xy 427.221396 -120.238012) (xy 423.106845 -120.238012)
			(xy 423.077055 -120.256193) (xy 423.025726 -120.278005) (xy 422.971769 -120.292111) (xy 422.916332 -120.298211)
			(xy 422.860598 -120.296174) (xy 422.805755 -120.286044) (xy 422.752971 -120.268037) (xy 422.703371 -120.242536)
			(xy 422.658013 -120.210085) (xy 422.617864 -120.171376) (xy 422.583778 -120.127233) (xy 422.556482 -120.078598)
			(xy 422.536559 -120.026507) (xy 422.524433 -119.97207) (xy 422.520362 -119.916448) (xy 420.819688 -119.916448)
			(xy 422.620948 -121.717816) (xy 422.644113 -121.741716) (xy 422.684632 -121.794521) (xy 422.717909 -121.852165)
			(xy 422.743374 -121.91366) (xy 422.760591 -121.977954) (xy 422.769266 -122.043946) (xy 422.769792 -122.077226)
			(xy 422.769327 -122.107941) (xy 422.76192 -122.168924) (xy 422.747216 -122.22857) (xy 422.725431 -122.286008)
			(xy 422.696882 -122.340402) (xy 422.661985 -122.390959) (xy 422.621249 -122.436941) (xy 422.575268 -122.477678)
			(xy 422.524713 -122.512576) (xy 422.470319 -122.541126) (xy 422.412881 -122.562913) (xy 422.353236 -122.577617)
			(xy 422.292253 -122.585026) (xy 422.261538 -122.58548) (xy 422.228261 -122.584933) (xy 422.162277 -122.576241)
			(xy 422.097991 -122.559015) (xy 422.036501 -122.53355) (xy 421.97886 -122.500279) (xy 421.926052 -122.459772)
			(xy 421.902128 -122.436636) (xy 418.546026 -119.080534) (xy 418.535046 -119.070312) (xy 418.508599 -119.056185)
			(xy 418.479189 -119.050342) (xy 418.44935 -119.053288) (xy 418.421651 -119.064769) (xy 418.398477 -119.083795)
			(xy 418.381823 -119.108729) (xy 418.373124 -119.137424) (xy 418.372544 -119.152416) (xy 418.372544 -129.926588)
			(xy 418.373075 -129.941587) (xy 418.381778 -129.970295) (xy 418.39844 -129.99524) (xy 418.421626 -130.014275)
			(xy 418.449338 -130.025761) (xy 418.479191 -130.028708) (xy 418.508614 -130.022863) (xy 418.535074 -130.00873)
			(xy 418.546026 -129.99847) (xy 424.738546 -123.805696) (xy 424.764104 -123.780833) (xy 424.819868 -123.73639)
			(xy 424.880258 -123.698471) (xy 424.944515 -123.667554) (xy 425.01183 -123.644027) (xy 425.081355 -123.628186)
			(xy 425.152218 -123.620231) (xy 425.187872 -123.619768) (xy 426.734986 -123.619768) (xy 426.748959 -123.619331)
			(xy 426.775858 -123.611757) (xy 426.799696 -123.597173) (xy 426.818686 -123.576672) (xy 426.831406 -123.551789)
			(xy 426.836902 -123.524389) (xy 426.834763 -123.496526) (xy 426.825148 -123.470287) (xy 426.817282 -123.458732)
			(xy 426.800334 -123.43423) (xy 426.773455 -123.381065) (xy 426.755183 -123.324363) (xy 426.745964 -123.265507)
			(xy 426.7454 -123.23572) (xy 426.745862 -123.208466) (xy 426.753617 -123.154514) (xy 426.768971 -123.102214)
			(xy 426.791613 -123.052632) (xy 426.82108 -123.006777) (xy 426.856774 -122.965582) (xy 426.897967 -122.929887)
			(xy 426.943821 -122.900418) (xy 426.993403 -122.877775) (xy 427.045702 -122.862419) (xy 427.099654 -122.854663)
			(xy 427.126908 -122.854212) (xy 427.153746 -122.85467) (xy 427.20689 -122.862197) (xy 427.258455 -122.877101)
			(xy 427.30742 -122.899087) (xy 427.352819 -122.927722) (xy 427.393755 -122.962439) (xy 427.429418 -123.002553)
			(xy 427.444662 -123.024646) (xy 427.452752 -123.036035) (xy 427.473933 -123.054237) (xy 427.499256 -123.066012)
			(xy 427.526823 -123.070479) (xy 427.554568 -123.067301) (xy 427.580412 -123.056719) (xy 427.591728 -123.048522)
			(xy 427.611925 -123.03331) (xy 427.655571 -123.007781) (xy 427.702207 -122.988243) (xy 427.751016 -122.975039)
			(xy 427.801142 -122.9684) (xy 427.826424 -122.968004) (xy 427.83942 -122.968123) (xy 427.86535 -122.9699)
			(xy 427.87824 -122.97156) (xy 427.895916 -122.937688) (xy 427.937079 -122.873317) (xy 427.984473 -122.813384)
			(xy 428.037622 -122.758491) (xy 428.095994 -122.709189) (xy 428.159004 -122.66597) (xy 428.22602 -122.62927)
			(xy 428.29637 -122.599454) (xy 428.369349 -122.576824) (xy 428.444226 -122.561604) (xy 428.520248 -122.553949)
			(xy 428.558452 -122.553476) (xy 428.601979 -122.554082) (xy 428.68847 -122.563975) (xy 428.773269 -122.58366)
			(xy 428.814484 -122.597672) (xy 428.827496 -122.601831) (xy 428.854731 -122.603826) (xy 428.881519 -122.598526)
			(xy 428.905941 -122.586309) (xy 428.926247 -122.568051) (xy 428.940983 -122.545061) (xy 428.949093 -122.518985)
			(xy 428.949995 -122.491693) (xy 428.947326 -122.478292) (xy 428.942322 -122.456216) (xy 428.936979 -122.411264)
			(xy 428.936658 -122.38863) (xy 428.937239 -122.358804) (xy 428.946531 -122.29988) (xy 428.964877 -122.243119)
			(xy 428.991832 -122.189904) (xy 429.008794 -122.165364) (xy 429.017147 -122.152891) (xy 429.026892 -122.124512)
			(xy 429.027968 -122.094526) (xy 429.02028 -122.065523) (xy 429.004494 -122.040006) (xy 428.993554 -122.029728)
			(xy 428.973568 -122.011535) (xy 428.938418 -121.970483) (xy 428.909416 -121.924879) (xy 428.887144 -121.875637)
			(xy 428.872047 -121.823743) (xy 428.864429 -121.770238) (xy 428.864014 -121.743216) (xy 428.8645 -121.715965)
			(xy 428.872256 -121.662017) (xy 428.887611 -121.609722) (xy 428.910253 -121.560145) (xy 428.939719 -121.514295)
			(xy 428.97541 -121.473104) (xy 429.016601 -121.437413) (xy 429.062451 -121.407947) (xy 429.112028 -121.385305)
			(xy 429.164323 -121.36995) (xy 429.218271 -121.362194) (xy 429.272773 -121.362194) (xy 429.326721 -121.36995)
			(xy 429.379016 -121.385305) (xy 429.428593 -121.407947) (xy 429.474443 -121.437413) (xy 429.505794 -121.464578)
			(xy 430.595022 -121.464578) (xy 430.599093 -121.408956) (xy 430.611219 -121.354519) (xy 430.631142 -121.302428)
			(xy 430.658438 -121.253793) (xy 430.692524 -121.20965) (xy 430.732673 -121.170941) (xy 430.778031 -121.13849)
			(xy 430.827631 -121.112989) (xy 430.880415 -121.094982) (xy 430.935258 -121.084852) (xy 430.990992 -121.082815)
			(xy 431.046429 -121.088915) (xy 431.100386 -121.103021) (xy 431.151715 -121.124833) (xy 431.199321 -121.153887)
			(xy 431.242189 -121.189562) (xy 431.279406 -121.231099) (xy 431.310179 -121.277612) (xy 431.333851 -121.328109)
			(xy 431.349919 -121.381516) (xy 431.358039 -121.436692) (xy 431.358548 -121.464578) (xy 432.119022 -121.464578)
			(xy 432.123093 -121.408956) (xy 432.135219 -121.354519) (xy 432.155142 -121.302428) (xy 432.182438 -121.253793)
			(xy 432.216524 -121.20965) (xy 432.256673 -121.170941) (xy 432.302031 -121.13849) (xy 432.351631 -121.112989)
			(xy 432.404415 -121.094982) (xy 432.459258 -121.084852) (xy 432.514992 -121.082815) (xy 432.570429 -121.088915)
			(xy 432.624386 -121.103021) (xy 432.675715 -121.124833) (xy 432.723321 -121.153887) (xy 432.766189 -121.189562)
			(xy 432.803406 -121.231099) (xy 432.834179 -121.277612) (xy 432.857851 -121.328109) (xy 432.873919 -121.381516)
			(xy 432.879564 -121.419874) (xy 433.643022 -121.419874) (xy 433.647093 -121.364252) (xy 433.659219 -121.309815)
			(xy 433.679142 -121.257724) (xy 433.706438 -121.209089) (xy 433.740524 -121.164946) (xy 433.780673 -121.126237)
			(xy 433.826031 -121.093786) (xy 433.875631 -121.068285) (xy 433.928415 -121.050278) (xy 433.983258 -121.040148)
			(xy 434.038992 -121.038111) (xy 434.094429 -121.044211) (xy 434.148386 -121.058317) (xy 434.199715 -121.080129)
			(xy 434.247321 -121.109183) (xy 434.290189 -121.144858) (xy 434.327406 -121.186395) (xy 434.358179 -121.232908)
			(xy 434.381851 -121.283405) (xy 434.397919 -121.336812) (xy 434.406039 -121.391988) (xy 434.406548 -121.419874)
			(xy 434.406039 -121.44776) (xy 434.397919 -121.502936) (xy 434.391425 -121.524522) (xy 435.135528 -121.524522)
			(xy 435.135992 -121.487049) (xy 435.143332 -121.412462) (xy 435.157953 -121.338955) (xy 435.179713 -121.267237)
			(xy 435.208404 -121.198) (xy 435.243748 -121.13191) (xy 435.285404 -121.069606) (xy 435.332971 -121.011689)
			(xy 435.38599 -120.958717) (xy 435.443949 -120.911202) (xy 435.474872 -120.89003) (xy 435.486439 -120.881759)
			(xy 435.504882 -120.860133) (xy 435.516641 -120.834258) (xy 435.520806 -120.806142) (xy 435.517051 -120.777969)
			(xy 435.505669 -120.751926) (xy 435.49697 -120.740678) (xy 435.480451 -120.720072) (xy 435.452661 -120.675162)
			(xy 435.431331 -120.626849) (xy 435.416869 -120.576055) (xy 435.409551 -120.523752) (xy 435.409086 -120.497346)
			(xy 435.409572 -120.470095) (xy 435.417328 -120.416147) (xy 435.432683 -120.363852) (xy 435.455325 -120.314275)
			(xy 435.484791 -120.268425) (xy 435.520482 -120.227234) (xy 435.561673 -120.191543) (xy 435.607523 -120.162077)
			(xy 435.6571 -120.139435) (xy 435.709395 -120.12408) (xy 435.763343 -120.116324) (xy 435.817845 -120.116324)
			(xy 435.871793 -120.12408) (xy 435.924088 -120.139435) (xy 435.973665 -120.162077) (xy 436.019515 -120.191543)
			(xy 436.060706 -120.227234) (xy 436.096397 -120.268425) (xy 436.125863 -120.314275) (xy 436.148505 -120.363852)
			(xy 436.16386 -120.416147) (xy 436.171616 -120.470095) (xy 436.172102 -120.497346) (xy 436.171516 -120.528096)
			(xy 436.161657 -120.588801) (xy 436.153184 -120.614186) (xy 437.888124 -120.614186) (xy 437.892195 -120.558564)
			(xy 437.904321 -120.504127) (xy 437.924244 -120.452036) (xy 437.95154 -120.403401) (xy 437.985626 -120.359258)
			(xy 438.025775 -120.320549) (xy 438.071133 -120.288098) (xy 438.120733 -120.262597) (xy 438.173517 -120.24459)
			(xy 438.22836 -120.23446) (xy 438.284094 -120.232423) (xy 438.339531 -120.238523) (xy 438.393488 -120.252629)
			(xy 438.444817 -120.274441) (xy 438.492423 -120.303495) (xy 438.535291 -120.33917) (xy 438.572508 -120.380707)
			(xy 438.603281 -120.42722) (xy 438.626953 -120.477717) (xy 438.643021 -120.531124) (xy 438.651141 -120.5863)
			(xy 438.65165 -120.614186) (xy 438.651141 -120.642072) (xy 438.643021 -120.697248) (xy 438.626953 -120.750655)
			(xy 438.603281 -120.801152) (xy 438.572508 -120.847665) (xy 438.535291 -120.889202) (xy 438.492423 -120.924877)
			(xy 438.444817 -120.953931) (xy 438.393488 -120.975743) (xy 438.339531 -120.989849) (xy 438.284094 -120.995949)
			(xy 438.22836 -120.993912) (xy 438.173517 -120.983782) (xy 438.120733 -120.965775) (xy 438.071133 -120.940274)
			(xy 438.025775 -120.907823) (xy 437.985626 -120.869114) (xy 437.95154 -120.824971) (xy 437.924244 -120.776336)
			(xy 437.904321 -120.724245) (xy 437.892195 -120.669808) (xy 437.888124 -120.614186) (xy 436.153184 -120.614186)
			(xy 436.142185 -120.647138) (xy 436.128414 -120.674638) (xy 436.122177 -120.687433) (xy 436.116365 -120.715287)
			(xy 436.11847 -120.743663) (xy 436.128327 -120.770355) (xy 436.14517 -120.793288) (xy 436.16769 -120.81068)
			(xy 436.180738 -120.81637) (xy 436.215713 -120.830838) (xy 436.282886 -120.865725) (xy 436.346272 -120.907097)
			(xy 436.405247 -120.954547) (xy 436.459229 -121.007606) (xy 436.507687 -121.065754) (xy 436.550145 -121.128417)
			(xy 436.586185 -121.19498) (xy 436.615452 -121.264786) (xy 436.637657 -121.337148) (xy 436.652582 -121.411355)
			(xy 436.66008 -121.486676) (xy 436.660544 -121.524522) (xy 436.660094 -121.562018) (xy 436.652736 -121.636648)
			(xy 436.638084 -121.710195) (xy 436.616279 -121.781947) (xy 436.587532 -121.851211) (xy 436.552121 -121.917316)
			(xy 436.510389 -121.979624) (xy 436.462739 -122.037532) (xy 436.409632 -122.090479) (xy 436.38089 -122.114564)
			(xy 436.369546 -122.124509) (xy 436.352805 -122.14959) (xy 436.350119 -122.158506) (xy 441.404246 -122.158506)
			(xy 441.408317 -122.102884) (xy 441.420443 -122.048447) (xy 441.440366 -121.996356) (xy 441.467662 -121.947721)
			(xy 441.501748 -121.903578) (xy 441.541897 -121.864869) (xy 441.587255 -121.832418) (xy 441.636855 -121.806917)
			(xy 441.689639 -121.78891) (xy 441.744482 -121.77878) (xy 441.800216 -121.776743) (xy 441.855653 -121.782843)
			(xy 441.90961 -121.796949) (xy 441.960939 -121.818761) (xy 442.008545 -121.847815) (xy 442.051413 -121.88349)
			(xy 442.08863 -121.925027) (xy 442.119403 -121.97154) (xy 442.143075 -122.022037) (xy 442.159143 -122.075444)
			(xy 442.167263 -122.13062) (xy 442.167772 -122.158506) (xy 442.167263 -122.186392) (xy 442.159143 -122.241568)
			(xy 442.143075 -122.294975) (xy 442.119403 -122.345472) (xy 442.08863 -122.391985) (xy 442.051413 -122.433522)
			(xy 442.008545 -122.469197) (xy 441.960939 -122.498251) (xy 441.90961 -122.520063) (xy 441.855653 -122.534169)
			(xy 441.800216 -122.540269) (xy 441.744482 -122.538232) (xy 441.689639 -122.528102) (xy 441.636855 -122.510095)
			(xy 441.587255 -122.484594) (xy 441.541897 -122.452143) (xy 441.501748 -122.413434) (xy 441.467662 -122.369291)
			(xy 441.440366 -122.320656) (xy 441.420443 -122.268565) (xy 441.408317 -122.214128) (xy 441.404246 -122.158506)
			(xy 436.350119 -122.158506) (xy 436.344107 -122.178464) (xy 436.344209 -122.208618) (xy 436.353101 -122.237433)
			(xy 436.370011 -122.2624) (xy 436.381398 -122.272298) (xy 436.410438 -122.29637) (xy 436.464098 -122.349391)
			(xy 436.512257 -122.407452) (xy 436.554447 -122.469987) (xy 436.590253 -122.536383) (xy 436.619325 -122.605991)
			(xy 436.64138 -122.67813) (xy 436.656202 -122.752095) (xy 436.663645 -122.827162) (xy 436.6641 -122.86488)
			(xy 436.663633 -122.90565) (xy 436.654934 -122.986723) (xy 436.637633 -123.066406) (xy 436.611929 -123.143787)
			(xy 436.578113 -123.217984) (xy 436.536573 -123.288148) (xy 436.487783 -123.353479) (xy 436.4323 -123.41323)
			(xy 436.370758 -123.46672) (xy 436.303859 -123.513337) (xy 436.268368 -123.533408) (xy 436.256604 -123.540352)
			(xy 436.237046 -123.559413) (xy 436.223228 -123.582969) (xy 436.216132 -123.609341) (xy 436.216266 -123.63665)
			(xy 436.223618 -123.662952) (xy 436.224607 -123.664726) (xy 439.889898 -123.664726) (xy 439.893969 -123.609104)
			(xy 439.906095 -123.554667) (xy 439.926018 -123.502576) (xy 439.953314 -123.453941) (xy 439.9874 -123.409798)
			(xy 440.027549 -123.371089) (xy 440.072907 -123.338638) (xy 440.122507 -123.313137) (xy 440.175291 -123.29513)
			(xy 440.230134 -123.285) (xy 440.285868 -123.282963) (xy 440.341305 -123.289063) (xy 440.395262 -123.303169)
			(xy 440.446591 -123.324981) (xy 440.494197 -123.354035) (xy 440.537065 -123.38971) (xy 440.574282 -123.431247)
			(xy 440.605055 -123.47776) (xy 440.628727 -123.528257) (xy 440.644795 -123.581664) (xy 440.652915 -123.63684)
			(xy 440.653424 -123.664726) (xy 440.652915 -123.692612) (xy 440.644795 -123.747788) (xy 440.628727 -123.801195)
			(xy 440.605055 -123.851692) (xy 440.574282 -123.898205) (xy 440.537065 -123.939742) (xy 440.494197 -123.975417)
			(xy 440.446591 -124.004471) (xy 440.395262 -124.026283) (xy 440.341305 -124.040389) (xy 440.285868 -124.046489)
			(xy 440.230134 -124.044452) (xy 440.175291 -124.034322) (xy 440.122507 -124.016315) (xy 440.072907 -123.990814)
			(xy 440.027549 -123.958363) (xy 439.9874 -123.919654) (xy 439.953314 -123.875511) (xy 439.926018 -123.826876)
			(xy 439.906095 -123.774785) (xy 439.893969 -123.720348) (xy 439.889898 -123.664726) (xy 436.224607 -123.664726)
			(xy 436.230268 -123.674886) (xy 436.24327 -123.697292) (xy 436.263791 -123.744857) (xy 436.277685 -123.794762)
			(xy 436.284697 -123.846089) (xy 436.285132 -123.87199) (xy 436.284646 -123.899241) (xy 436.27689 -123.953189)
			(xy 436.261535 -124.005484) (xy 436.238893 -124.055061) (xy 436.209427 -124.100911) (xy 436.173736 -124.142102)
			(xy 436.132545 -124.177793) (xy 436.086695 -124.207259) (xy 436.037118 -124.229901) (xy 435.984823 -124.245256)
			(xy 435.930875 -124.253012) (xy 435.876373 -124.253012) (xy 435.822425 -124.245256) (xy 435.77013 -124.229901)
			(xy 435.720553 -124.207259) (xy 435.674703 -124.177793) (xy 435.633512 -124.142102) (xy 435.597821 -124.100911)
			(xy 435.568355 -124.055061) (xy 435.545713 -124.005484) (xy 435.530358 -123.953189) (xy 435.522602 -123.899241)
			(xy 435.522116 -123.87199) (xy 435.522546 -123.846274) (xy 435.529457 -123.795307) (xy 435.543151 -123.74573)
			(xy 435.56338 -123.698443) (xy 435.576218 -123.676156) (xy 435.582862 -123.664223) (xy 435.590147 -123.637909)
			(xy 435.59019 -123.610605) (xy 435.582987 -123.584269) (xy 435.569054 -123.560787) (xy 435.549391 -123.541843)
			(xy 435.53761 -123.534932) (xy 435.501881 -123.514964) (xy 435.434559 -123.468404) (xy 435.37261 -123.414901)
			(xy 435.316747 -123.355071) (xy 435.267614 -123.289603) (xy 435.225775 -123.219249) (xy 435.191712 -123.144819)
			(xy 435.165816 -123.067169) (xy 435.148386 -122.987191) (xy 435.139621 -122.905807) (xy 435.139084 -122.86488)
			(xy 435.139562 -122.827385) (xy 435.146919 -122.752756) (xy 435.161569 -122.679211) (xy 435.183372 -122.60746)
			(xy 435.212116 -122.538197) (xy 435.247523 -122.472091) (xy 435.289251 -122.409783) (xy 435.336896 -122.351874)
			(xy 435.389999 -122.298924) (xy 435.418738 -122.274838) (xy 435.430077 -122.264889) (xy 435.446814 -122.239808)
			(xy 435.455509 -122.210936) (xy 435.455408 -122.180784) (xy 435.446518 -122.151971) (xy 435.429614 -122.127003)
			(xy 435.41823 -122.117104) (xy 435.389175 -122.093049) (xy 435.335519 -122.040024) (xy 435.287362 -121.98196)
			(xy 435.245175 -121.919422) (xy 435.209371 -121.853024) (xy 435.1803 -121.783415) (xy 435.158246 -121.711274)
			(xy 435.143426 -121.637308) (xy 435.135983 -121.56224) (xy 435.135528 -121.524522) (xy 434.391425 -121.524522)
			(xy 434.381851 -121.556343) (xy 434.358179 -121.60684) (xy 434.327406 -121.653353) (xy 434.290189 -121.69489)
			(xy 434.247321 -121.730565) (xy 434.199715 -121.759619) (xy 434.148386 -121.781431) (xy 434.094429 -121.795537)
			(xy 434.038992 -121.801637) (xy 433.983258 -121.7996) (xy 433.928415 -121.78947) (xy 433.875631 -121.771463)
			(xy 433.826031 -121.745962) (xy 433.780673 -121.713511) (xy 433.740524 -121.674802) (xy 433.706438 -121.630659)
			(xy 433.679142 -121.582024) (xy 433.659219 -121.529933) (xy 433.647093 -121.475496) (xy 433.643022 -121.419874)
			(xy 432.879564 -121.419874) (xy 432.882039 -121.436692) (xy 432.882548 -121.464578) (xy 432.882039 -121.492464)
			(xy 432.873919 -121.54764) (xy 432.857851 -121.601047) (xy 432.834179 -121.651544) (xy 432.803406 -121.698057)
			(xy 432.766189 -121.739594) (xy 432.723321 -121.775269) (xy 432.675715 -121.804323) (xy 432.624386 -121.826135)
			(xy 432.570429 -121.840241) (xy 432.514992 -121.846341) (xy 432.459258 -121.844304) (xy 432.404415 -121.834174)
			(xy 432.351631 -121.816167) (xy 432.302031 -121.790666) (xy 432.256673 -121.758215) (xy 432.216524 -121.719506)
			(xy 432.182438 -121.675363) (xy 432.155142 -121.626728) (xy 432.135219 -121.574637) (xy 432.123093 -121.5202)
			(xy 432.119022 -121.464578) (xy 431.358548 -121.464578) (xy 431.358039 -121.492464) (xy 431.349919 -121.54764)
			(xy 431.333851 -121.601047) (xy 431.310179 -121.651544) (xy 431.279406 -121.698057) (xy 431.242189 -121.739594)
			(xy 431.199321 -121.775269) (xy 431.151715 -121.804323) (xy 431.100386 -121.826135) (xy 431.046429 -121.840241)
			(xy 430.990992 -121.846341) (xy 430.935258 -121.844304) (xy 430.880415 -121.834174) (xy 430.827631 -121.816167)
			(xy 430.778031 -121.790666) (xy 430.732673 -121.758215) (xy 430.692524 -121.719506) (xy 430.658438 -121.675363)
			(xy 430.631142 -121.626728) (xy 430.611219 -121.574637) (xy 430.599093 -121.5202) (xy 430.595022 -121.464578)
			(xy 429.505794 -121.464578) (xy 429.515634 -121.473104) (xy 429.551325 -121.514295) (xy 429.580791 -121.560145)
			(xy 429.603433 -121.609722) (xy 429.618788 -121.662017) (xy 429.626544 -121.715965) (xy 429.62703 -121.743216)
			(xy 429.626453 -121.773043) (xy 429.617169 -121.831971) (xy 429.598828 -121.888736) (xy 429.571878 -121.941956)
			(xy 429.554894 -121.966482) (xy 429.546549 -121.978955) (xy 429.536818 -122.007328) (xy 429.535753 -122.037305)
			(xy 429.543447 -122.066297) (xy 429.559235 -122.091801) (xy 429.570134 -122.102118) (xy 429.590114 -122.120314)
			(xy 429.625251 -122.161371) (xy 429.65424 -122.206977) (xy 429.676501 -122.256218) (xy 429.691588 -122.308109)
			(xy 429.699198 -122.36161) (xy 429.699674 -122.38863) (xy 429.699209 -122.415881) (xy 429.691448 -122.469826)
			(xy 429.676089 -122.522119) (xy 429.653444 -122.571693) (xy 429.623975 -122.61754) (xy 429.588281 -122.658726)
			(xy 429.547089 -122.694413) (xy 429.501237 -122.723875) (xy 429.451659 -122.746511) (xy 429.399364 -122.761862)
			(xy 429.345417 -122.769613) (xy 429.318166 -122.770138) (xy 429.303434 -122.769884) (xy 429.289752 -122.769771)
			(xy 429.26311 -122.77596) (xy 429.239072 -122.789008) (xy 429.219366 -122.807976) (xy 429.205411 -122.831499)
			(xy 429.198209 -122.857885) (xy 429.198279 -122.885236) (xy 429.205617 -122.911584) (xy 429.212248 -122.923554)
			(xy 429.232986 -122.959194) (xy 429.246547 -122.988578) (xy 430.595022 -122.988578) (xy 430.599093 -122.932956)
			(xy 430.611219 -122.878519) (xy 430.631142 -122.826428) (xy 430.658438 -122.777793) (xy 430.692524 -122.73365)
			(xy 430.732673 -122.694941) (xy 430.778031 -122.66249) (xy 430.827631 -122.636989) (xy 430.880415 -122.618982)
			(xy 430.935258 -122.608852) (xy 430.990992 -122.606815) (xy 431.046429 -122.612915) (xy 431.100386 -122.627021)
			(xy 431.151715 -122.648833) (xy 431.199321 -122.677887) (xy 431.242189 -122.713562) (xy 431.279406 -122.755099)
			(xy 431.310179 -122.801612) (xy 431.333851 -122.852109) (xy 431.349919 -122.905516) (xy 431.358039 -122.960692)
			(xy 431.358548 -122.988578) (xy 433.643022 -122.988578) (xy 433.647093 -122.932956) (xy 433.659219 -122.878519)
			(xy 433.679142 -122.826428) (xy 433.706438 -122.777793) (xy 433.740524 -122.73365) (xy 433.780673 -122.694941)
			(xy 433.826031 -122.66249) (xy 433.875631 -122.636989) (xy 433.928415 -122.618982) (xy 433.983258 -122.608852)
			(xy 434.038992 -122.606815) (xy 434.094429 -122.612915) (xy 434.148386 -122.627021) (xy 434.199715 -122.648833)
			(xy 434.247321 -122.677887) (xy 434.290189 -122.713562) (xy 434.327406 -122.755099) (xy 434.358179 -122.801612)
			(xy 434.381851 -122.852109) (xy 434.397919 -122.905516) (xy 434.406039 -122.960692) (xy 434.406548 -122.988578)
			(xy 434.406039 -123.016464) (xy 434.397919 -123.07164) (xy 434.381851 -123.125047) (xy 434.358179 -123.175544)
			(xy 434.327406 -123.222057) (xy 434.290189 -123.263594) (xy 434.247321 -123.299269) (xy 434.199715 -123.328323)
			(xy 434.148386 -123.350135) (xy 434.094429 -123.364241) (xy 434.038992 -123.370341) (xy 433.983258 -123.368304)
			(xy 433.928415 -123.358174) (xy 433.875631 -123.340167) (xy 433.826031 -123.314666) (xy 433.780673 -123.282215)
			(xy 433.740524 -123.243506) (xy 433.706438 -123.199363) (xy 433.679142 -123.150728) (xy 433.659219 -123.098637)
			(xy 433.647093 -123.0442) (xy 433.643022 -122.988578) (xy 431.358548 -122.988578) (xy 431.358039 -123.016464)
			(xy 431.349919 -123.07164) (xy 431.333851 -123.125047) (xy 431.310179 -123.175544) (xy 431.279406 -123.222057)
			(xy 431.242189 -123.263594) (xy 431.199321 -123.299269) (xy 431.151715 -123.328323) (xy 431.100386 -123.350135)
			(xy 431.046429 -123.364241) (xy 430.990992 -123.370341) (xy 430.935258 -123.368304) (xy 430.880415 -123.358174)
			(xy 430.827631 -123.340167) (xy 430.778031 -123.314666) (xy 430.732673 -123.282215) (xy 430.692524 -123.243506)
			(xy 430.658438 -123.199363) (xy 430.631142 -123.150728) (xy 430.611219 -123.098637) (xy 430.599093 -123.0442)
			(xy 430.595022 -122.988578) (xy 429.246547 -122.988578) (xy 429.26754 -123.034068) (xy 429.293817 -123.112232)
			(xy 429.311511 -123.192773) (xy 429.320416 -123.274753) (xy 429.32096 -123.315984) (xy 429.320497 -123.354219)
			(xy 429.312852 -123.430305) (xy 429.297626 -123.505243) (xy 429.274974 -123.578281) (xy 429.245123 -123.648683)
			(xy 429.208372 -123.715742) (xy 429.165091 -123.778785) (xy 429.115716 -123.837177) (xy 429.060742 -123.890331)
			(xy 429.000722 -123.937714) (xy 428.936259 -123.97885) (xy 428.868001 -124.013323) (xy 428.796634 -124.040789)
			(xy 428.759874 -124.051314) (xy 428.747019 -124.055241) (xy 428.723833 -124.068821) (xy 428.704992 -124.087978)
			(xy 428.691798 -124.111386) (xy 428.685165 -124.137425) (xy 428.685552 -124.164292) (xy 428.692932 -124.190129)
			(xy 428.706795 -124.213147) (xy 428.716186 -124.222764) (xy 428.743826 -124.250008) (xy 428.794022 -124.309204)
			(xy 428.83795 -124.37319) (xy 428.875155 -124.441305) (xy 428.90514 -124.512578) (xy 430.595022 -124.512578)
			(xy 430.599093 -124.456956) (xy 430.611219 -124.402519) (xy 430.631142 -124.350428) (xy 430.658438 -124.301793)
			(xy 430.692524 -124.25765) (xy 430.732673 -124.218941) (xy 430.778031 -124.18649) (xy 430.827631 -124.160989)
			(xy 430.880415 -124.142982) (xy 430.935258 -124.132852) (xy 430.990992 -124.130815) (xy 431.046429 -124.136915)
			(xy 431.100386 -124.151021) (xy 431.151715 -124.172833) (xy 431.199321 -124.201887) (xy 431.242189 -124.237562)
			(xy 431.279406 -124.279099) (xy 431.310179 -124.325612) (xy 431.333851 -124.376109) (xy 431.349919 -124.429516)
			(xy 431.358039 -124.484692) (xy 431.358548 -124.512578) (xy 432.119022 -124.512578) (xy 432.123093 -124.456956)
			(xy 432.135219 -124.402519) (xy 432.155142 -124.350428) (xy 432.182438 -124.301793) (xy 432.216524 -124.25765)
			(xy 432.256673 -124.218941) (xy 432.302031 -124.18649) (xy 432.351631 -124.160989) (xy 432.404415 -124.142982)
			(xy 432.459258 -124.132852) (xy 432.514992 -124.130815) (xy 432.570429 -124.136915) (xy 432.624386 -124.151021)
			(xy 432.675715 -124.172833) (xy 432.723321 -124.201887) (xy 432.766189 -124.237562) (xy 432.803406 -124.279099)
			(xy 432.834179 -124.325612) (xy 432.857851 -124.376109) (xy 432.873919 -124.429516) (xy 432.882039 -124.484692)
			(xy 432.882548 -124.512578) (xy 433.643022 -124.512578) (xy 433.647093 -124.456956) (xy 433.659219 -124.402519)
			(xy 433.679142 -124.350428) (xy 433.706438 -124.301793) (xy 433.740524 -124.25765) (xy 433.780673 -124.218941)
			(xy 433.826031 -124.18649) (xy 433.875631 -124.160989) (xy 433.928415 -124.142982) (xy 433.983258 -124.132852)
			(xy 434.038992 -124.130815) (xy 434.094429 -124.136915) (xy 434.148386 -124.151021) (xy 434.199715 -124.172833)
			(xy 434.247321 -124.201887) (xy 434.290189 -124.237562) (xy 434.327406 -124.279099) (xy 434.339876 -124.297948)
			(xy 441.789056 -124.297948) (xy 441.793127 -124.242326) (xy 441.805253 -124.187889) (xy 441.825176 -124.135798)
			(xy 441.852472 -124.087163) (xy 441.886558 -124.04302) (xy 441.926707 -124.004311) (xy 441.972065 -123.97186)
			(xy 442.021665 -123.946359) (xy 442.074449 -123.928352) (xy 442.129292 -123.918222) (xy 442.185026 -123.916185)
			(xy 442.240463 -123.922285) (xy 442.29442 -123.936391) (xy 442.345749 -123.958203) (xy 442.393355 -123.987257)
			(xy 442.436223 -124.022932) (xy 442.47344 -124.064469) (xy 442.504213 -124.110982) (xy 442.527885 -124.161479)
			(xy 442.543953 -124.214886) (xy 442.552073 -124.270062) (xy 442.552582 -124.297948) (xy 442.552073 -124.325834)
			(xy 442.543953 -124.38101) (xy 442.527885 -124.434417) (xy 442.504213 -124.484914) (xy 442.47344 -124.531427)
			(xy 442.436223 -124.572964) (xy 442.393355 -124.608639) (xy 442.345749 -124.637693) (xy 442.29442 -124.659505)
			(xy 442.240463 -124.673611) (xy 442.185026 -124.679711) (xy 442.129292 -124.677674) (xy 442.074449 -124.667544)
			(xy 442.021665 -124.649537) (xy 441.972065 -124.624036) (xy 441.926707 -124.591585) (xy 441.886558 -124.552876)
			(xy 441.852472 -124.508733) (xy 441.825176 -124.460098) (xy 441.805253 -124.408007) (xy 441.793127 -124.35357)
			(xy 441.789056 -124.297948) (xy 434.339876 -124.297948) (xy 434.358179 -124.325612) (xy 434.381851 -124.376109)
			(xy 434.397919 -124.429516) (xy 434.406039 -124.484692) (xy 434.406548 -124.512578) (xy 434.406039 -124.540464)
			(xy 434.397919 -124.59564) (xy 434.381851 -124.649047) (xy 434.358179 -124.699544) (xy 434.327406 -124.746057)
			(xy 434.290189 -124.787594) (xy 434.247321 -124.823269) (xy 434.199715 -124.852323) (xy 434.148386 -124.874135)
			(xy 434.104133 -124.885704) (xy 435.552594 -124.885704) (xy 435.556665 -124.830082) (xy 435.568791 -124.775645)
			(xy 435.588714 -124.723554) (xy 435.61601 -124.674919) (xy 435.650096 -124.630776) (xy 435.690245 -124.592067)
			(xy 435.735603 -124.559616) (xy 435.785203 -124.534115) (xy 435.837987 -124.516108) (xy 435.89283 -124.505978)
			(xy 435.948564 -124.503941) (xy 436.004001 -124.510041) (xy 436.057958 -124.524147) (xy 436.109287 -124.545959)
			(xy 436.156893 -124.575013) (xy 436.199761 -124.610688) (xy 436.236978 -124.652225) (xy 436.255834 -124.680726)
			(xy 439.889898 -124.680726) (xy 439.893969 -124.625104) (xy 439.906095 -124.570667) (xy 439.926018 -124.518576)
			(xy 439.953314 -124.469941) (xy 439.9874 -124.425798) (xy 440.027549 -124.387089) (xy 440.072907 -124.354638)
			(xy 440.122507 -124.329137) (xy 440.175291 -124.31113) (xy 440.230134 -124.301) (xy 440.285868 -124.298963)
			(xy 440.341305 -124.305063) (xy 440.395262 -124.319169) (xy 440.446591 -124.340981) (xy 440.494197 -124.370035)
			(xy 440.537065 -124.40571) (xy 440.574282 -124.447247) (xy 440.605055 -124.49376) (xy 440.628727 -124.544257)
			(xy 440.644795 -124.597664) (xy 440.652915 -124.65284) (xy 440.653424 -124.680726) (xy 440.652915 -124.708612)
			(xy 440.644795 -124.763788) (xy 440.628727 -124.817195) (xy 440.605055 -124.867692) (xy 440.574282 -124.914205)
			(xy 440.537065 -124.955742) (xy 440.494197 -124.991417) (xy 440.446591 -125.020471) (xy 440.395262 -125.042283)
			(xy 440.341305 -125.056389) (xy 440.285868 -125.062489) (xy 440.230134 -125.060452) (xy 440.175291 -125.050322)
			(xy 440.122507 -125.032315) (xy 440.072907 -125.006814) (xy 440.027549 -124.974363) (xy 439.9874 -124.935654)
			(xy 439.953314 -124.891511) (xy 439.926018 -124.842876) (xy 439.906095 -124.790785) (xy 439.893969 -124.736348)
			(xy 439.889898 -124.680726) (xy 436.255834 -124.680726) (xy 436.267751 -124.698738) (xy 436.291423 -124.749235)
			(xy 436.307491 -124.802642) (xy 436.315611 -124.857818) (xy 436.31612 -124.885704) (xy 436.315611 -124.91359)
			(xy 436.307491 -124.968766) (xy 436.291423 -125.022173) (xy 436.267751 -125.07267) (xy 436.236978 -125.119183)
			(xy 436.199761 -125.16072) (xy 436.156893 -125.196395) (xy 436.109287 -125.225449) (xy 436.057958 -125.247261)
			(xy 436.004001 -125.261367) (xy 435.948564 -125.267467) (xy 435.89283 -125.26543) (xy 435.837987 -125.2553)
			(xy 435.785203 -125.237293) (xy 435.735603 -125.211792) (xy 435.690245 -125.179341) (xy 435.650096 -125.140632)
			(xy 435.61601 -125.096489) (xy 435.588714 -125.047854) (xy 435.568791 -124.995763) (xy 435.556665 -124.941326)
			(xy 435.552594 -124.885704) (xy 434.104133 -124.885704) (xy 434.094429 -124.888241) (xy 434.038992 -124.894341)
			(xy 433.983258 -124.892304) (xy 433.928415 -124.882174) (xy 433.875631 -124.864167) (xy 433.826031 -124.838666)
			(xy 433.780673 -124.806215) (xy 433.740524 -124.767506) (xy 433.706438 -124.723363) (xy 433.679142 -124.674728)
			(xy 433.659219 -124.622637) (xy 433.647093 -124.5682) (xy 433.643022 -124.512578) (xy 432.882548 -124.512578)
			(xy 432.882039 -124.540464) (xy 432.873919 -124.59564) (xy 432.857851 -124.649047) (xy 432.834179 -124.699544)
			(xy 432.803406 -124.746057) (xy 432.766189 -124.787594) (xy 432.723321 -124.823269) (xy 432.675715 -124.852323)
			(xy 432.624386 -124.874135) (xy 432.570429 -124.888241) (xy 432.514992 -124.894341) (xy 432.459258 -124.892304)
			(xy 432.404415 -124.882174) (xy 432.351631 -124.864167) (xy 432.302031 -124.838666) (xy 432.256673 -124.806215)
			(xy 432.216524 -124.767506) (xy 432.182438 -124.723363) (xy 432.155142 -124.674728) (xy 432.135219 -124.622637)
			(xy 432.123093 -124.5682) (xy 432.119022 -124.512578) (xy 431.358548 -124.512578) (xy 431.358039 -124.540464)
			(xy 431.349919 -124.59564) (xy 431.333851 -124.649047) (xy 431.310179 -124.699544) (xy 431.279406 -124.746057)
			(xy 431.242189 -124.787594) (xy 431.199321 -124.823269) (xy 431.151715 -124.852323) (xy 431.100386 -124.874135)
			(xy 431.046429 -124.888241) (xy 430.990992 -124.894341) (xy 430.935258 -124.892304) (xy 430.880415 -124.882174)
			(xy 430.827631 -124.864167) (xy 430.778031 -124.838666) (xy 430.732673 -124.806215) (xy 430.692524 -124.767506)
			(xy 430.658438 -124.723363) (xy 430.631142 -124.674728) (xy 430.611219 -124.622637) (xy 430.599093 -124.5682)
			(xy 430.595022 -124.512578) (xy 428.90514 -124.512578) (xy 428.905253 -124.512846) (xy 428.927934 -124.587071)
			(xy 428.942962 -124.663216) (xy 428.947072 -124.701808) (xy 428.949014 -124.716977) (xy 428.960737 -124.74521)
			(xy 428.980278 -124.768718) (xy 429.005891 -124.785403) (xy 429.035291 -124.793777) (xy 429.065853 -124.79309)
			(xy 429.094847 -124.783405) (xy 429.1076 -124.77496) (xy 429.140038 -124.752268) (xy 429.208769 -124.712979)
			(xy 429.281204 -124.681028) (xy 429.356561 -124.65676) (xy 429.434028 -124.640436) (xy 429.51277 -124.632233)
			(xy 429.552354 -124.631704) (xy 429.591001 -124.632175) (xy 429.667899 -124.63999) (xy 429.743611 -124.655546)
			(xy 429.817361 -124.678681) (xy 429.888392 -124.709159) (xy 429.955975 -124.746667) (xy 430.019417 -124.79082)
			(xy 430.078066 -124.841165) (xy 430.13132 -124.897186) (xy 430.178634 -124.958307) (xy 430.219521 -125.023901)
			(xy 430.253562 -125.093295) (xy 430.280407 -125.165777) (xy 430.299782 -125.240603) (xy 430.311487 -125.317005)
			(xy 430.315402 -125.3942) (xy 430.311769 -125.46584) (xy 441.803026 -125.46584) (xy 441.807097 -125.410218)
			(xy 441.819223 -125.355781) (xy 441.839146 -125.30369) (xy 441.866442 -125.255055) (xy 441.900528 -125.210912)
			(xy 441.940677 -125.172203) (xy 441.986035 -125.139752) (xy 442.035635 -125.114251) (xy 442.088419 -125.096244)
			(xy 442.143262 -125.086114) (xy 442.198996 -125.084077) (xy 442.254433 -125.090177) (xy 442.30839 -125.104283)
			(xy 442.359719 -125.126095) (xy 442.407325 -125.155149) (xy 442.450193 -125.190824) (xy 442.48741 -125.232361)
			(xy 442.518183 -125.278874) (xy 442.541855 -125.329371) (xy 442.557923 -125.382778) (xy 442.566043 -125.437954)
			(xy 442.566552 -125.46584) (xy 442.566043 -125.493726) (xy 442.557923 -125.548902) (xy 442.541855 -125.602309)
			(xy 442.518183 -125.652806) (xy 442.48741 -125.699319) (xy 442.450193 -125.740856) (xy 442.407325 -125.776531)
			(xy 442.359719 -125.805585) (xy 442.30839 -125.827397) (xy 442.254433 -125.841503) (xy 442.198996 -125.847603)
			(xy 442.143262 -125.845566) (xy 442.088419 -125.835436) (xy 442.035635 -125.817429) (xy 441.986035 -125.791928)
			(xy 441.940677 -125.759477) (xy 441.900528 -125.720768) (xy 441.866442 -125.676625) (xy 441.839146 -125.62799)
			(xy 441.819223 -125.575899) (xy 441.807097 -125.521462) (xy 441.803026 -125.46584) (xy 430.311769 -125.46584)
			(xy 430.311487 -125.471395) (xy 430.299782 -125.547797) (xy 430.280407 -125.622623) (xy 430.253562 -125.695105)
			(xy 430.219521 -125.764499) (xy 430.178634 -125.830093) (xy 430.13132 -125.891214) (xy 430.124004 -125.89891)
			(xy 435.50408 -125.89891) (xy 435.508151 -125.843288) (xy 435.520277 -125.788851) (xy 435.5402 -125.73676)
			(xy 435.567496 -125.688125) (xy 435.601582 -125.643982) (xy 435.641731 -125.605273) (xy 435.687089 -125.572822)
			(xy 435.736689 -125.547321) (xy 435.789473 -125.529314) (xy 435.844316 -125.519184) (xy 435.90005 -125.517147)
			(xy 435.955487 -125.523247) (xy 436.009444 -125.537353) (xy 436.060773 -125.559165) (xy 436.108379 -125.588219)
			(xy 436.151247 -125.623894) (xy 436.188464 -125.665431) (xy 436.219237 -125.711944) (xy 436.242909 -125.762441)
			(xy 436.258977 -125.815848) (xy 436.267097 -125.871024) (xy 436.267606 -125.89891) (xy 436.267097 -125.926796)
			(xy 436.258977 -125.981972) (xy 436.242909 -126.035379) (xy 436.219237 -126.085876) (xy 436.188464 -126.132389)
			(xy 436.151247 -126.173926) (xy 436.108379 -126.209601) (xy 436.060773 -126.238655) (xy 436.009444 -126.260467)
			(xy 435.955487 -126.274573) (xy 435.90005 -126.280673) (xy 435.844316 -126.278636) (xy 435.789473 -126.268506)
			(xy 435.736689 -126.250499) (xy 435.687089 -126.224998) (xy 435.641731 -126.192547) (xy 435.601582 -126.153838)
			(xy 435.567496 -126.109695) (xy 435.5402 -126.06106) (xy 435.520277 -126.008969) (xy 435.508151 -125.954532)
			(xy 435.50408 -125.89891) (xy 430.124004 -125.89891) (xy 430.078066 -125.947235) (xy 430.019417 -125.99758)
			(xy 429.955975 -126.041733) (xy 429.888392 -126.079241) (xy 429.817361 -126.109719) (xy 429.743611 -126.132854)
			(xy 429.667899 -126.14841) (xy 429.591001 -126.156225) (xy 429.552354 -126.15672) (xy 429.512093 -126.156201)
			(xy 429.432018 -126.14772) (xy 429.353284 -126.130847) (xy 429.276766 -126.105771) (xy 429.203317 -126.072769)
			(xy 429.133755 -126.032211) (xy 429.068856 -125.984547) (xy 429.009341 -125.930308) (xy 428.955874 -125.870099)
			(xy 428.90905 -125.804591) (xy 428.869391 -125.734512) (xy 428.837338 -125.660644) (xy 428.81325 -125.58381)
			(xy 428.797393 -125.504864) (xy 428.793148 -125.464824) (xy 428.791198 -125.44966) (xy 428.779465 -125.421442)
			(xy 428.759923 -125.397947) (xy 428.734315 -125.38127) (xy 428.704924 -125.372898) (xy 428.674372 -125.373578)
			(xy 428.645383 -125.38325) (xy 428.63262 -125.391672) (xy 428.600183 -125.414367) (xy 428.531453 -125.453661)
			(xy 428.459019 -125.485617) (xy 428.383662 -125.509889) (xy 428.306194 -125.526216) (xy 428.227451 -125.534422)
			(xy 428.187866 -125.534928) (xy 428.151961 -125.534512) (xy 428.080468 -125.527768) (xy 428.045118 -125.521466)
			(xy 428.030955 -125.519263) (xy 428.002431 -125.52193) (xy 427.975771 -125.53242) (xy 427.953078 -125.549908)
			(xy 427.93614 -125.573014) (xy 427.926291 -125.599917) (xy 427.924308 -125.628497) (xy 427.926754 -125.642624)
			(xy 427.934812 -125.682396) (xy 427.94347 -125.763084) (xy 427.944026 -125.80366) (xy 427.94353 -125.842781)
			(xy 427.935521 -125.920611) (xy 427.919583 -125.997211) (xy 427.895883 -126.071777) (xy 427.864671 -126.143523)
			(xy 427.826275 -126.211695) (xy 427.781098 -126.275576) (xy 427.729617 -126.334494) (xy 427.672372 -126.38783)
			(xy 427.609966 -126.435022) (xy 427.543054 -126.475575) (xy 427.507908 -126.492762) (xy 427.495565 -126.499128)
			(xy 427.474604 -126.517329) (xy 427.459321 -126.540503) (xy 427.450846 -126.566938) (xy 427.449805 -126.594679)
			(xy 427.456276 -126.621674) (xy 427.458458 -126.625858) (xy 429.821086 -126.625858) (xy 429.821572 -126.598607)
			(xy 429.829328 -126.544659) (xy 429.844683 -126.492364) (xy 429.867325 -126.442787) (xy 429.896791 -126.396937)
			(xy 429.932482 -126.355746) (xy 429.973673 -126.320055) (xy 430.019523 -126.290589) (xy 430.0691 -126.267947)
			(xy 430.121395 -126.252592) (xy 430.175343 -126.244836) (xy 430.229845 -126.244836) (xy 430.283793 -126.252592)
			(xy 430.336088 -126.267947) (xy 430.385665 -126.290589) (xy 430.431515 -126.320055) (xy 430.472706 -126.355746)
			(xy 430.508397 -126.396937) (xy 430.537863 -126.442787) (xy 430.560505 -126.492364) (xy 430.57586 -126.544659)
			(xy 430.583616 -126.598607) (xy 430.584102 -126.625858) (xy 430.583605 -126.654741) (xy 430.574894 -126.711847)
			(xy 430.557665 -126.766985) (xy 430.532312 -126.818891) (xy 430.499417 -126.866377) (xy 430.479962 -126.887732)
			(xy 430.470104 -126.898824) (xy 430.456792 -126.925334) (xy 430.451664 -126.954552) (xy 430.455154 -126.984011)
			(xy 430.466967 -127.011222) (xy 430.486105 -127.033888) (xy 430.49825 -127.042418) (xy 430.516772 -127.054963)
			(xy 430.55102 -127.083745) (xy 430.566576 -127.099822) (xy 430.577044 -127.110092) (xy 430.602417 -127.124763)
			(xy 430.63091 -127.131636) (xy 430.660182 -127.130146) (xy 430.687829 -127.120415) (xy 430.711582 -127.103243)
			(xy 430.729488 -127.080039) (xy 430.735232 -127.066548) (xy 430.746045 -127.039951) (xy 430.774487 -126.990078)
			(xy 430.810079 -126.945029) (xy 430.852019 -126.90582) (xy 430.899358 -126.873337) (xy 430.95103 -126.848312)
			(xy 431.005868 -126.83131) (xy 431.062634 -126.822715) (xy 431.09134 -126.8222) (xy 431.101839 -126.822264)
			(xy 431.122806 -126.82341) (xy 431.13325 -126.824486) (xy 431.146494 -126.82561) (xy 431.172767 -126.821628)
			(xy 431.197115 -126.810984) (xy 431.21788 -126.794402) (xy 431.233649 -126.773013) (xy 431.243346 -126.748272)
			(xy 431.246312 -126.721864) (xy 431.244756 -126.708662) (xy 431.242843 -126.694707) (xy 431.240806 -126.666612)
			(xy 431.240692 -126.652528) (xy 431.241181 -126.625276) (xy 431.248935 -126.571326) (xy 431.264287 -126.519028)
			(xy 431.286926 -126.469448) (xy 431.316391 -126.423595) (xy 431.352082 -126.382402) (xy 431.393273 -126.346708)
			(xy 431.439124 -126.31724) (xy 431.488702 -126.294597) (xy 431.540998 -126.27924) (xy 431.594948 -126.271483)
			(xy 431.6222 -126.27102) (xy 431.646145 -126.271364) (xy 431.693659 -126.277356) (xy 431.716942 -126.282958)
			(xy 431.730331 -126.285959) (xy 431.757756 -126.285459) (xy 431.784058 -126.277672) (xy 431.807335 -126.263162)
			(xy 431.825907 -126.242975) (xy 431.838431 -126.218572) (xy 431.841656 -126.205234) (xy 431.848089 -126.176987)
			(xy 431.868334 -126.122708) (xy 431.896552 -126.072114) (xy 431.932094 -126.026367) (xy 431.974143 -125.986519)
			(xy 432.021733 -125.953486) (xy 432.07377 -125.928026) (xy 432.129057 -125.910725) (xy 432.186324 -125.901981)
			(xy 432.21529 -125.90145) (xy 432.24254 -125.901997) (xy 432.296486 -125.909752) (xy 432.34878 -125.925105)
			(xy 432.398356 -125.947744) (xy 432.444205 -125.977209) (xy 432.485394 -126.012899) (xy 432.521085 -126.054087)
			(xy 432.550551 -126.099936) (xy 432.573192 -126.149511) (xy 432.588546 -126.201804) (xy 432.596303 -126.25575)
			(xy 432.596303 -126.31025) (xy 432.588546 -126.364196) (xy 432.573192 -126.416489) (xy 432.550551 -126.466064)
			(xy 432.521085 -126.511913) (xy 432.485394 -126.553101) (xy 432.444205 -126.588791) (xy 432.398356 -126.618256)
			(xy 432.34878 -126.640895) (xy 432.296486 -126.656248) (xy 432.24254 -126.664003) (xy 432.21529 -126.664466)
			(xy 432.191346 -126.664106) (xy 432.143832 -126.658124) (xy 432.120548 -126.652528) (xy 432.107159 -126.649527)
			(xy 432.079735 -126.65003) (xy 432.053435 -126.657818) (xy 432.030158 -126.672328) (xy 432.011586 -126.692513)
			(xy 431.99906 -126.716915) (xy 431.995834 -126.730252) (xy 431.994462 -126.736348) (xy 432.866292 -126.736348)
			(xy 432.866781 -126.697703) (xy 432.874601 -126.620809) (xy 432.890159 -126.545101) (xy 432.913297 -126.471355)
			(xy 432.943777 -126.400328) (xy 432.981286 -126.33275) (xy 433.02544 -126.269312) (xy 433.075785 -126.210668)
			(xy 433.131804 -126.157417) (xy 433.192923 -126.110107) (xy 433.258516 -126.069223) (xy 433.327907 -126.035185)
			(xy 433.400387 -126.008342) (xy 433.47521 -125.988969) (xy 433.551609 -125.977265) (xy 433.6288 -125.97335)
			(xy 433.705991 -125.977265) (xy 433.78239 -125.988969) (xy 433.857213 -126.008342) (xy 433.929693 -126.035185)
			(xy 433.999084 -126.069223) (xy 434.064677 -126.110107) (xy 434.125796 -126.157417) (xy 434.181815 -126.210668)
			(xy 434.23216 -126.269312) (xy 434.276314 -126.33275) (xy 434.313823 -126.400328) (xy 434.344303 -126.471355)
			(xy 434.367441 -126.545101) (xy 434.382999 -126.620809) (xy 434.390819 -126.697703) (xy 434.391308 -126.736348)
			(xy 434.390777 -126.776976) (xy 434.382145 -126.857771) (xy 434.364972 -126.937191) (xy 434.339454 -127.014335)
			(xy 434.305879 -127.088329) (xy 434.264628 -127.158335) (xy 434.216169 -127.223558) (xy 434.161051 -127.283261)
			(xy 434.099898 -127.336765) (xy 434.033404 -127.383466) (xy 433.998116 -127.403606) (xy 433.986409 -127.410706)
			(xy 433.966877 -127.429872) (xy 433.953137 -127.453538) (xy 433.946178 -127.480003) (xy 433.946498 -127.507366)
			(xy 433.954076 -127.533661) (xy 433.968365 -127.556999) (xy 433.97805 -127.566674) (xy 433.996902 -127.584781)
			(xy 434.029955 -127.625275) (xy 434.057169 -127.669904) (xy 434.078037 -127.717829) (xy 434.092166 -127.768155)
			(xy 434.099292 -127.819938) (xy 434.099716 -127.846074) (xy 434.099297 -127.872454) (xy 434.092035 -127.924712)
			(xy 434.077645 -127.975473) (xy 434.056402 -128.023768) (xy 434.028711 -128.068677) (xy 433.995099 -128.109345)
			(xy 433.956207 -128.144997) (xy 433.912775 -128.174953) (xy 433.889404 -128.187196) (xy 433.877071 -128.193938)
			(xy 433.856351 -128.21291) (xy 433.841595 -128.236816) (xy 433.833924 -128.263842) (xy 433.833921 -128.291935)
			(xy 433.841586 -128.318963) (xy 433.856336 -128.342872) (xy 433.877052 -128.361848) (xy 433.889404 -128.368552)
			(xy 433.912764 -128.380812) (xy 433.956188 -128.410771) (xy 433.995074 -128.446424) (xy 434.028681 -128.487091)
			(xy 434.056369 -128.531997) (xy 434.077611 -128.580288) (xy 434.092002 -128.631043) (xy 434.099269 -128.683296)
			(xy 434.099716 -128.709674) (xy 434.09923 -128.736925) (xy 434.091474 -128.790873) (xy 434.076119 -128.843168)
			(xy 434.053477 -128.892745) (xy 434.024011 -128.938595) (xy 433.98832 -128.979786) (xy 433.947129 -129.015477)
			(xy 433.901279 -129.044943) (xy 433.851702 -129.067585) (xy 433.799407 -129.08294) (xy 433.745459 -129.090696)
			(xy 433.690957 -129.090696) (xy 433.637009 -129.08294) (xy 433.584714 -129.067585) (xy 433.535137 -129.044943)
			(xy 433.489287 -129.015477) (xy 433.448096 -128.979786) (xy 433.412405 -128.938595) (xy 433.382939 -128.892745)
			(xy 433.360297 -128.843168) (xy 433.344942 -128.790873) (xy 433.337186 -128.736925) (xy 433.3367 -128.709674)
			(xy 433.33715 -128.683295) (xy 433.344406 -128.631037) (xy 433.35879 -128.580278) (xy 433.380028 -128.531982)
			(xy 433.407715 -128.487073) (xy 433.441324 -128.446404) (xy 433.480213 -128.410752) (xy 433.523642 -128.380795)
			(xy 433.547012 -128.368552) (xy 433.559389 -128.361886) (xy 433.580112 -128.3429) (xy 433.594866 -128.31898)
			(xy 433.602533 -128.291941) (xy 433.60253 -128.263836) (xy 433.594857 -128.236799) (xy 433.580097 -128.212882)
			(xy 433.55937 -128.193901) (xy 433.547012 -128.187196) (xy 433.523634 -128.174968) (xy 433.480208 -128.145005)
			(xy 433.441322 -128.109349) (xy 433.407716 -128.068677) (xy 433.38003 -128.023766) (xy 433.358791 -127.975471)
			(xy 433.344404 -127.924711) (xy 433.337143 -127.872454) (xy 433.3367 -127.846074) (xy 433.337075 -127.820851)
			(xy 433.343723 -127.770846) (xy 433.356899 -127.722151) (xy 433.376374 -127.675617) (xy 433.401809 -127.632052)
			(xy 433.416964 -127.611886) (xy 433.424998 -127.600754) (xy 433.435469 -127.57539) (xy 433.4388 -127.548154)
			(xy 433.434751 -127.521014) (xy 433.423615 -127.495936) (xy 433.406197 -127.474734) (xy 433.383757 -127.458941)
			(xy 433.37099 -127.453898) (xy 433.334482 -127.440299) (xy 433.264224 -127.40662) (xy 433.197767 -127.365951)
			(xy 433.135805 -127.318717) (xy 433.078984 -127.265409) (xy 433.027896 -127.206583) (xy 432.983074 -127.142854)
			(xy 432.944986 -127.074886) (xy 432.914028 -127.003387) (xy 432.890525 -126.929104) (xy 432.87472 -126.852811)
			(xy 432.866779 -126.775304) (xy 432.866292 -126.736348) (xy 431.994462 -126.736348) (xy 431.989471 -126.758516)
			(xy 431.969213 -126.812795) (xy 431.940984 -126.863387) (xy 431.905432 -126.909132) (xy 431.863374 -126.948978)
			(xy 431.815776 -126.982009) (xy 431.763733 -127.007466) (xy 431.70844 -127.024764) (xy 431.651168 -127.033506)
			(xy 431.6222 -127.034036) (xy 431.611701 -127.033969) (xy 431.590734 -127.032825) (xy 431.58029 -127.03175)
			(xy 431.567042 -127.030739) (xy 431.540783 -127.034709) (xy 431.516446 -127.045337) (xy 431.495687 -127.0619)
			(xy 431.479918 -127.083269) (xy 431.470215 -127.107989) (xy 431.467237 -127.134379) (xy 431.468784 -127.147574)
			(xy 431.470701 -127.161528) (xy 431.472736 -127.189623) (xy 431.472848 -127.203708) (xy 431.47233 -127.230958)
			(xy 431.464573 -127.284902) (xy 431.44993 -127.334772) (xy 431.877976 -127.334772) (xy 431.882047 -127.27915)
			(xy 431.894173 -127.224713) (xy 431.914096 -127.172622) (xy 431.941392 -127.123987) (xy 431.975478 -127.079844)
			(xy 432.015627 -127.041135) (xy 432.060985 -127.008684) (xy 432.110585 -126.983183) (xy 432.163369 -126.965176)
			(xy 432.218212 -126.955046) (xy 432.273946 -126.953009) (xy 432.329383 -126.959109) (xy 432.38334 -126.973215)
			(xy 432.434669 -126.995027) (xy 432.482275 -127.024081) (xy 432.525143 -127.059756) (xy 432.56236 -127.101293)
			(xy 432.593133 -127.147806) (xy 432.616805 -127.198303) (xy 432.632873 -127.25171) (xy 432.640993 -127.306886)
			(xy 432.641502 -127.334772) (xy 432.640993 -127.362658) (xy 432.632873 -127.417834) (xy 432.616805 -127.471241)
			(xy 432.593133 -127.521738) (xy 432.56236 -127.568251) (xy 432.525143 -127.609788) (xy 432.482275 -127.645463)
			(xy 432.434669 -127.674517) (xy 432.38334 -127.696329) (xy 432.329383 -127.710435) (xy 432.273946 -127.716535)
			(xy 432.218212 -127.714498) (xy 432.163369 -127.704368) (xy 432.110585 -127.686361) (xy 432.060985 -127.66086)
			(xy 432.015627 -127.628409) (xy 431.975478 -127.5897) (xy 431.941392 -127.545557) (xy 431.914096 -127.496922)
			(xy 431.894173 -127.444831) (xy 431.882047 -127.390394) (xy 431.877976 -127.334772) (xy 431.44993 -127.334772)
			(xy 431.449219 -127.337194) (xy 431.42658 -127.386768) (xy 431.397117 -127.432617) (xy 431.361429 -127.473806)
			(xy 431.320242 -127.509497) (xy 431.274397 -127.538965) (xy 431.224824 -127.561608) (xy 431.172533 -127.576966)
			(xy 431.11859 -127.584727) (xy 431.09134 -127.585216) (xy 431.065389 -127.584758) (xy 431.013967 -127.577715)
			(xy 430.963974 -127.563767) (xy 430.916333 -127.543172) (xy 430.871923 -127.51631) (xy 430.831564 -127.483676)
			(xy 430.813464 -127.465074) (xy 430.803058 -127.454737) (xy 430.777668 -127.440069) (xy 430.74916 -127.433203)
			(xy 430.719876 -127.434703) (xy 430.69222 -127.444446) (xy 430.668461 -127.461632) (xy 430.650552 -127.48485)
			(xy 430.644808 -127.498348) (xy 430.634042 -127.524966) (xy 430.605595 -127.574841) (xy 430.569997 -127.619891)
			(xy 430.528051 -127.659099) (xy 430.480704 -127.69158) (xy 430.429025 -127.716602) (xy 430.37418 -127.733598)
			(xy 430.317409 -127.742185) (xy 430.2887 -127.742696) (xy 430.261447 -127.742245) (xy 430.207495 -127.734487)
			(xy 430.155196 -127.719131) (xy 430.105615 -127.696487) (xy 430.059761 -127.667018) (xy 430.018568 -127.631323)
			(xy 429.982875 -127.590129) (xy 429.953407 -127.544275) (xy 429.930765 -127.494693) (xy 429.91541 -127.442394)
			(xy 429.907655 -127.388441) (xy 429.907192 -127.361188) (xy 429.907719 -127.332306) (xy 429.916423 -127.275201)
			(xy 429.933645 -127.220064) (xy 429.958991 -127.168157) (xy 429.99188 -127.12067) (xy 430.011332 -127.099314)
			(xy 430.021141 -127.088182) (xy 430.034458 -127.061685) (xy 430.039593 -127.032477) (xy 430.036113 -127.003027)
			(xy 430.02431 -126.975821) (xy 430.005183 -126.953158) (xy 429.993044 -126.944628) (xy 429.970749 -126.929445)
			(xy 429.930294 -126.893767) (xy 429.89527 -126.852744) (xy 429.866375 -126.807196) (xy 429.844185 -126.758032)
			(xy 429.829143 -126.706231) (xy 429.82155 -126.652828) (xy 429.821086 -126.625858) (xy 427.458458 -126.625858)
			(xy 427.462696 -126.633986) (xy 427.474174 -126.65535) (xy 427.492228 -126.700363) (xy 427.504426 -126.747303)
			(xy 427.510571 -126.795411) (xy 427.510956 -126.81966) (xy 427.51047 -126.846911) (xy 427.502714 -126.900859)
			(xy 427.487359 -126.953154) (xy 427.464717 -127.002731) (xy 427.435251 -127.048581) (xy 427.39956 -127.089772)
			(xy 427.358369 -127.125463) (xy 427.312519 -127.154929) (xy 427.262942 -127.177571) (xy 427.210647 -127.192926)
			(xy 427.156699 -127.200682) (xy 427.102197 -127.200682) (xy 427.048249 -127.192926) (xy 426.995954 -127.177571)
			(xy 426.946377 -127.154929) (xy 426.900527 -127.125463) (xy 426.859336 -127.089772) (xy 426.823645 -127.048581)
			(xy 426.794179 -127.002731) (xy 426.771537 -126.953154) (xy 426.756182 -126.900859) (xy 426.748426 -126.846911)
			(xy 426.74794 -126.81966) (xy 426.748491 -126.790538) (xy 426.757342 -126.732971) (xy 426.774833 -126.677416)
			(xy 426.800557 -126.625161) (xy 426.816774 -126.600966) (xy 426.824427 -126.589347) (xy 426.833703 -126.563127)
			(xy 426.835559 -126.535376) (xy 426.829858 -126.508154) (xy 426.817023 -126.48348) (xy 426.798005 -126.463185)
			(xy 426.786294 -126.455678) (xy 426.753102 -126.434973) (xy 426.690706 -126.387777) (xy 426.63347 -126.334441)
			(xy 426.581994 -126.275526) (xy 426.536821 -126.21165) (xy 426.498425 -126.143485) (xy 426.467209 -126.071748)
			(xy 426.4435 -125.997191) (xy 426.42755 -125.9206) (xy 426.419524 -125.842777) (xy 426.41901 -125.80366)
			(xy 426.419535 -125.763728) (xy 426.427887 -125.684301) (xy 426.444495 -125.606183) (xy 426.469179 -125.530228)
			(xy 426.501666 -125.45727) (xy 426.541601 -125.388107) (xy 426.588547 -125.323497) (xy 426.641989 -125.264148)
			(xy 426.701342 -125.21071) (xy 426.765955 -125.163769) (xy 426.835121 -125.123839) (xy 426.908082 -125.091358)
			(xy 426.984039 -125.06668) (xy 427.062158 -125.050078) (xy 427.141586 -125.041732) (xy 427.181518 -125.041152)
			(xy 427.218451 -125.0416) (xy 427.291968 -125.04876) (xy 427.364452 -125.062982) (xy 427.399958 -125.073156)
			(xy 427.410784 -125.075848) (xy 427.432841 -125.072689) (xy 427.451489 -125.060492) (xy 427.463222 -125.041549)
			(xy 427.465835 -125.01942) (xy 427.46295 -125.00864) (xy 427.457375 -124.991136) (xy 427.447721 -124.955687)
			(xy 427.443646 -124.937774) (xy 427.440344 -124.92355) (xy 427.407324 -124.890276) (xy 426.45965 -124.890276)
			(xy 426.456602 -124.938028) (xy 426.454446 -124.96538) (xy 426.443274 -125.019096) (xy 426.424521 -125.070658)
			(xy 426.398575 -125.119001) (xy 426.365971 -125.163128) (xy 426.327381 -125.202129) (xy 426.283601 -125.235199)
			(xy 426.235535 -125.261655) (xy 426.184175 -125.280952) (xy 426.13058 -125.292692) (xy 426.075856 -125.296632)
			(xy 426.021132 -125.292692) (xy 425.967537 -125.280952) (xy 425.916177 -125.261655) (xy 425.868111 -125.235199)
			(xy 425.824331 -125.202129) (xy 425.785741 -125.163128) (xy 425.753137 -125.119001) (xy 425.727191 -125.070658)
			(xy 425.708438 -125.019096) (xy 425.697266 -124.96538) (xy 425.69511 -124.938028) (xy 425.692062 -124.890276)
			(xy 425.451016 -124.890276) (xy 421.579433 -128.761998) (xy 430.432462 -128.761998) (xy 430.436533 -128.706376)
			(xy 430.448659 -128.651939) (xy 430.468582 -128.599848) (xy 430.495878 -128.551213) (xy 430.529964 -128.50707)
			(xy 430.570113 -128.468361) (xy 430.615471 -128.43591) (xy 430.665071 -128.410409) (xy 430.717855 -128.392402)
			(xy 430.772698 -128.382272) (xy 430.828432 -128.380235) (xy 430.883869 -128.386335) (xy 430.937826 -128.400441)
			(xy 430.989155 -128.422253) (xy 431.036761 -128.451307) (xy 431.079629 -128.486982) (xy 431.116846 -128.528519)
			(xy 431.147619 -128.575032) (xy 431.171291 -128.625529) (xy 431.187359 -128.678936) (xy 431.195479 -128.734112)
			(xy 431.195988 -128.761998) (xy 431.195479 -128.789884) (xy 431.187359 -128.84506) (xy 431.171291 -128.898467)
			(xy 431.147619 -128.948964) (xy 431.116846 -128.995477) (xy 431.079629 -129.037014) (xy 431.036761 -129.072689)
			(xy 430.989155 -129.101743) (xy 430.937826 -129.123555) (xy 430.883869 -129.137661) (xy 430.828432 -129.143761)
			(xy 430.772698 -129.141724) (xy 430.717855 -129.131594) (xy 430.665071 -129.113587) (xy 430.615471 -129.088086)
			(xy 430.570113 -129.055635) (xy 430.529964 -129.016926) (xy 430.495878 -128.972783) (xy 430.468582 -128.924148)
			(xy 430.448659 -128.872057) (xy 430.436533 -128.81762) (xy 430.432462 -128.761998) (xy 421.579433 -128.761998)
			(xy 420.963505 -129.377948) (xy 432.362862 -129.377948) (xy 432.366933 -129.322326) (xy 432.379059 -129.267889)
			(xy 432.398982 -129.215798) (xy 432.426278 -129.167163) (xy 432.460364 -129.12302) (xy 432.500513 -129.084311)
			(xy 432.545871 -129.05186) (xy 432.595471 -129.026359) (xy 432.648255 -129.008352) (xy 432.703098 -128.998222)
			(xy 432.758832 -128.996185) (xy 432.814269 -129.002285) (xy 432.868226 -129.016391) (xy 432.919555 -129.038203)
			(xy 432.967161 -129.067257) (xy 433.010029 -129.102932) (xy 433.047246 -129.144469) (xy 433.078019 -129.190982)
			(xy 433.101691 -129.241479) (xy 433.117759 -129.294886) (xy 433.125879 -129.350062) (xy 433.126388 -129.377948)
			(xy 433.125879 -129.405834) (xy 433.117759 -129.46101) (xy 433.101691 -129.514417) (xy 433.078019 -129.564914)
			(xy 433.047246 -129.611427) (xy 433.010029 -129.652964) (xy 432.967161 -129.688639) (xy 432.919555 -129.717693)
			(xy 432.868226 -129.739505) (xy 432.814269 -129.753611) (xy 432.758832 -129.759711) (xy 432.703098 -129.757674)
			(xy 432.648255 -129.747544) (xy 432.595471 -129.729537) (xy 432.545871 -129.704036) (xy 432.500513 -129.671585)
			(xy 432.460364 -129.632876) (xy 432.426278 -129.588733) (xy 432.398982 -129.540098) (xy 432.379059 -129.488007)
			(xy 432.366933 -129.43357) (xy 432.362862 -129.377948) (xy 420.963505 -129.377948) (xy 419.835786 -130.505708)
			(xy 424.855642 -130.505708) (xy 424.859686 -130.427254) (xy 424.871775 -130.349632) (xy 424.891782 -130.273664)
			(xy 424.919493 -130.200156) (xy 424.954616 -130.129887) (xy 424.996778 -130.063602) (xy 425.045532 -130.002003)
			(xy 425.100361 -129.945743) (xy 425.160684 -129.895419) (xy 425.225862 -129.851565) (xy 425.295203 -129.814644)
			(xy 425.367974 -129.785049) (xy 425.443401 -129.763094) (xy 425.520686 -129.74901) (xy 425.59901 -129.742947)
			(xy 425.677542 -129.74497) (xy 425.75545 -129.755056) (xy 425.831907 -129.7731) (xy 425.906105 -129.79891)
			(xy 425.977255 -129.832212) (xy 426.044604 -129.872653) (xy 426.107438 -129.919804) (xy 426.16509 -129.973167)
			(xy 426.21695 -130.032174) (xy 426.262469 -130.096201) (xy 426.301162 -130.164569) (xy 426.332621 -130.236553)
			(xy 426.356512 -130.31139) (xy 426.372581 -130.388287) (xy 426.380658 -130.466429) (xy 426.381164 -130.505708)
			(xy 426.380658 -130.544987) (xy 426.372581 -130.623129) (xy 426.356512 -130.700026) (xy 426.346784 -130.730498)
			(xy 426.897294 -130.730498) (xy 426.901338 -130.652044) (xy 426.913427 -130.574422) (xy 426.933434 -130.498454)
			(xy 426.961145 -130.424946) (xy 426.996268 -130.354677) (xy 427.03843 -130.288392) (xy 427.087184 -130.226793)
			(xy 427.142013 -130.170533) (xy 427.202336 -130.120209) (xy 427.267514 -130.076355) (xy 427.336855 -130.039434)
			(xy 427.409626 -130.009839) (xy 427.485053 -129.987884) (xy 427.562338 -129.9738) (xy 427.640662 -129.967737)
			(xy 427.719194 -129.96976) (xy 427.797102 -129.979846) (xy 427.873559 -129.99789) (xy 427.947757 -130.0237)
			(xy 428.018907 -130.057002) (xy 428.086256 -130.097443) (xy 428.14909 -130.144594) (xy 428.206742 -130.197957)
			(xy 428.258602 -130.256964) (xy 428.304121 -130.320991) (xy 428.308754 -130.329178) (xy 429.131728 -130.329178)
			(xy 429.135799 -130.273556) (xy 429.147925 -130.219119) (xy 429.167848 -130.167028) (xy 429.195144 -130.118393)
			(xy 429.22923 -130.07425) (xy 429.269379 -130.035541) (xy 429.314737 -130.00309) (xy 429.364337 -129.977589)
			(xy 429.417121 -129.959582) (xy 429.471964 -129.949452) (xy 429.527698 -129.947415) (xy 429.583135 -129.953515)
			(xy 429.637092 -129.967621) (xy 429.688421 -129.989433) (xy 429.736027 -130.018487) (xy 429.778895 -130.054162)
			(xy 429.816112 -130.095699) (xy 429.846885 -130.142212) (xy 429.870557 -130.192709) (xy 429.886625 -130.246116)
			(xy 429.894745 -130.301292) (xy 429.895254 -130.329178) (xy 431.304444 -130.329178) (xy 431.308515 -130.273556)
			(xy 431.320641 -130.219119) (xy 431.340564 -130.167028) (xy 431.36786 -130.118393) (xy 431.401946 -130.07425)
			(xy 431.442095 -130.035541) (xy 431.487453 -130.00309) (xy 431.537053 -129.977589) (xy 431.589837 -129.959582)
			(xy 431.64468 -129.949452) (xy 431.700414 -129.947415) (xy 431.755851 -129.953515) (xy 431.809808 -129.967621)
			(xy 431.861137 -129.989433) (xy 431.908743 -130.018487) (xy 431.951611 -130.054162) (xy 431.988828 -130.095699)
			(xy 432.019601 -130.142212) (xy 432.043273 -130.192709) (xy 432.059341 -130.246116) (xy 432.067461 -130.301292)
			(xy 432.06797 -130.329178) (xy 432.067461 -130.357064) (xy 432.059341 -130.41224) (xy 432.043273 -130.465647)
			(xy 432.040337 -130.471911) (xy 433.378888 -130.471911) (xy 433.378894 -130.41741) (xy 433.386656 -130.363464)
			(xy 433.402016 -130.311173) (xy 433.424662 -130.261599) (xy 433.454133 -130.215753) (xy 433.489828 -130.174568)
			(xy 433.531021 -130.138882) (xy 433.576873 -130.109422) (xy 433.626451 -130.086787) (xy 433.678746 -130.071438)
			(xy 433.732693 -130.063688) (xy 433.787194 -130.063694) (xy 433.84114 -130.071457) (xy 433.893431 -130.086818)
			(xy 433.943004 -130.109464) (xy 433.98885 -130.138935) (xy 434.030035 -130.174631) (xy 434.06572 -130.215824)
			(xy 434.09518 -130.261677) (xy 434.117814 -130.311255) (xy 434.133163 -130.36355) (xy 434.140912 -130.417497)
			(xy 434.141372 -130.444748) (xy 434.141021 -130.467824) (xy 434.135445 -130.513638) (xy 434.12437 -130.558442)
			(xy 434.11648 -130.58013) (xy 434.112148 -130.592902) (xy 434.109514 -130.61973) (xy 434.113997 -130.646312)
			(xy 434.125283 -130.670792) (xy 434.142586 -130.691463) (xy 434.164698 -130.706882) (xy 434.190076 -130.715973)
			(xy 434.216949 -130.718102) (xy 434.230272 -130.71602) (xy 434.247635 -130.712941) (xy 434.282744 -130.709636)
			(xy 434.300376 -130.709416) (xy 434.327631 -130.709829) (xy 434.381585 -130.717583) (xy 434.433888 -130.732937)
			(xy 434.483472 -130.755578) (xy 434.52933 -130.785045) (xy 434.570528 -130.820738) (xy 434.606226 -130.861931)
			(xy 434.635699 -130.907785) (xy 434.658346 -130.957367) (xy 434.673707 -131.009668) (xy 434.681467 -131.063621)
			(xy 434.681471 -131.118131) (xy 434.673717 -131.172085) (xy 434.658363 -131.224388) (xy 434.635722 -131.273972)
			(xy 434.606255 -131.31983) (xy 434.570562 -131.361028) (xy 434.529369 -131.396726) (xy 434.483515 -131.426199)
			(xy 434.433933 -131.448846) (xy 434.381632 -131.464207) (xy 434.327679 -131.471967) (xy 434.273169 -131.471971)
			(xy 434.219215 -131.464217) (xy 434.166912 -131.448863) (xy 434.117328 -131.426222) (xy 434.07147 -131.396755)
			(xy 434.030272 -131.361062) (xy 433.994574 -131.319869) (xy 433.965101 -131.274015) (xy 433.942454 -131.224433)
			(xy 433.927093 -131.172132) (xy 433.919333 -131.118179) (xy 433.918868 -131.090924) (xy 433.919209 -131.067847)
			(xy 433.924788 -131.022033) (xy 433.935868 -130.97723) (xy 433.94376 -130.955542) (xy 433.948192 -130.942799)
			(xy 433.950824 -130.915954) (xy 433.946334 -130.889357) (xy 433.935035 -130.864865) (xy 433.917716 -130.844186)
			(xy 433.895585 -130.828766) (xy 433.870188 -130.81968) (xy 433.843298 -130.817562) (xy 433.829968 -130.819652)
			(xy 433.812604 -130.822725) (xy 433.777496 -130.826034) (xy 433.759864 -130.826256) (xy 433.732614 -130.825706)
			(xy 433.678668 -130.817945) (xy 433.626376 -130.802585) (xy 433.576803 -130.77994) (xy 433.530957 -130.75047)
			(xy 433.489771 -130.714775) (xy 433.454085 -130.673583) (xy 433.424624 -130.62773) (xy 433.401988 -130.578152)
			(xy 433.386639 -130.525858) (xy 433.378888 -130.471911) (xy 432.040337 -130.471911) (xy 432.019601 -130.516144)
			(xy 431.988828 -130.562657) (xy 431.951611 -130.604194) (xy 431.908743 -130.639869) (xy 431.861137 -130.668923)
			(xy 431.809808 -130.690735) (xy 431.755851 -130.704841) (xy 431.700414 -130.710941) (xy 431.64468 -130.708904)
			(xy 431.589837 -130.698774) (xy 431.537053 -130.680767) (xy 431.487453 -130.655266) (xy 431.442095 -130.622815)
			(xy 431.401946 -130.584106) (xy 431.36786 -130.539963) (xy 431.340564 -130.491328) (xy 431.320641 -130.439237)
			(xy 431.308515 -130.3848) (xy 431.304444 -130.329178) (xy 429.895254 -130.329178) (xy 429.894745 -130.357064)
			(xy 429.886625 -130.41224) (xy 429.870557 -130.465647) (xy 429.846885 -130.516144) (xy 429.816112 -130.562657)
			(xy 429.778895 -130.604194) (xy 429.736027 -130.639869) (xy 429.688421 -130.668923) (xy 429.637092 -130.690735)
			(xy 429.583135 -130.704841) (xy 429.527698 -130.710941) (xy 429.471964 -130.708904) (xy 429.417121 -130.698774)
			(xy 429.364337 -130.680767) (xy 429.314737 -130.655266) (xy 429.269379 -130.622815) (xy 429.22923 -130.584106)
			(xy 429.195144 -130.539963) (xy 429.167848 -130.491328) (xy 429.147925 -130.439237) (xy 429.135799 -130.3848)
			(xy 429.131728 -130.329178) (xy 428.308754 -130.329178) (xy 428.342814 -130.389359) (xy 428.374273 -130.461343)
			(xy 428.398164 -130.53618) (xy 428.414233 -130.613077) (xy 428.42231 -130.691219) (xy 428.422816 -130.730498)
			(xy 428.42231 -130.769777) (xy 428.414233 -130.847919) (xy 428.398164 -130.924816) (xy 428.376891 -130.991451)
			(xy 429.819056 -130.991451) (xy 429.819056 -130.936949) (xy 429.826811 -130.883002) (xy 429.842165 -130.830708)
			(xy 429.864804 -130.781131) (xy 429.894268 -130.735281) (xy 429.929957 -130.694089) (xy 429.971144 -130.658396)
			(xy 430.016991 -130.628926) (xy 430.066565 -130.606281) (xy 430.118857 -130.590921) (xy 430.172803 -130.583159)
			(xy 430.200054 -130.58267) (xy 430.226658 -130.583123) (xy 430.279352 -130.5905) (xy 430.330509 -130.605131)
			(xy 430.379135 -130.626732) (xy 430.424286 -130.654884) (xy 430.465085 -130.689039) (xy 430.500738 -130.728535)
			(xy 430.51603 -130.75031) (xy 430.524364 -130.76179) (xy 430.546108 -130.779994) (xy 430.572021 -130.791512)
			(xy 430.600104 -130.795452) (xy 430.628187 -130.791512) (xy 430.6541 -130.779994) (xy 430.675844 -130.76179)
			(xy 430.684178 -130.75031) (xy 430.699465 -130.728534) (xy 430.735134 -130.689057) (xy 430.775939 -130.654915)
			(xy 430.821091 -130.626771) (xy 430.869713 -130.605169) (xy 430.920863 -130.590529) (xy 430.973552 -130.583134)
			(xy 431.000154 -130.58267) (xy 431.027407 -130.583174) (xy 431.08136 -130.590925) (xy 431.133661 -130.606277)
			(xy 431.183244 -130.628915) (xy 431.2291 -130.65838) (xy 431.270296 -130.694072) (xy 431.305992 -130.735263)
			(xy 431.335463 -130.781116) (xy 431.358107 -130.830696) (xy 431.373465 -130.882995) (xy 431.381223 -130.936947)
			(xy 431.381223 -130.991453) (xy 431.373465 -131.045405) (xy 431.358107 -131.097704) (xy 431.335463 -131.147284)
			(xy 431.305992 -131.193137) (xy 431.270296 -131.234328) (xy 431.2291 -131.27002) (xy 431.183244 -131.299485)
			(xy 431.133661 -131.322123) (xy 431.08136 -131.337475) (xy 431.027407 -131.345226) (xy 431.000154 -131.345686)
			(xy 430.973551 -131.345202) (xy 430.920859 -131.337828) (xy 430.869704 -131.3232) (xy 430.821079 -131.301603)
			(xy 430.775928 -131.273457) (xy 430.735128 -131.239308) (xy 430.699472 -131.199818) (xy 430.684178 -131.178046)
			(xy 430.675844 -131.166566) (xy 430.6541 -131.148362) (xy 430.628187 -131.136844) (xy 430.600104 -131.132904)
			(xy 430.572021 -131.136844) (xy 430.546108 -131.148362) (xy 430.524364 -131.166566) (xy 430.51603 -131.178046)
			(xy 430.500724 -131.199808) (xy 430.46506 -131.239288) (xy 430.424258 -131.273432) (xy 430.37911 -131.301579)
			(xy 430.330491 -131.323183) (xy 430.279342 -131.337825) (xy 430.226656 -131.345221) (xy 430.200054 -131.345686)
			(xy 430.172803 -131.345241) (xy 430.118857 -131.337479) (xy 430.066565 -131.322119) (xy 430.016991 -131.299474)
			(xy 429.971144 -131.270004) (xy 429.929957 -131.234311) (xy 429.894268 -131.193119) (xy 429.864804 -131.147269)
			(xy 429.842165 -131.097692) (xy 429.826811 -131.045398) (xy 429.819056 -130.991451) (xy 428.376891 -130.991451)
			(xy 428.374273 -130.999653) (xy 428.342814 -131.071637) (xy 428.304121 -131.140005) (xy 428.258602 -131.204032)
			(xy 428.206742 -131.263039) (xy 428.14909 -131.316402) (xy 428.086256 -131.363553) (xy 428.018907 -131.403994)
			(xy 427.947757 -131.437296) (xy 427.873559 -131.463106) (xy 427.797102 -131.48115) (xy 427.719194 -131.491236)
			(xy 427.640662 -131.493259) (xy 427.562338 -131.487196) (xy 427.485053 -131.473112) (xy 427.409626 -131.451157)
			(xy 427.336855 -131.421562) (xy 427.267514 -131.384641) (xy 427.202336 -131.340787) (xy 427.142013 -131.290463)
			(xy 427.087184 -131.234203) (xy 427.03843 -131.172604) (xy 426.996268 -131.106319) (xy 426.961145 -131.03605)
			(xy 426.933434 -130.962542) (xy 426.913427 -130.886574) (xy 426.901338 -130.808952) (xy 426.897294 -130.730498)
			(xy 426.346784 -130.730498) (xy 426.332621 -130.774863) (xy 426.301162 -130.846847) (xy 426.262469 -130.915215)
			(xy 426.21695 -130.979242) (xy 426.16509 -131.038249) (xy 426.107438 -131.091612) (xy 426.044604 -131.138763)
			(xy 425.977255 -131.179204) (xy 425.906105 -131.212506) (xy 425.831907 -131.238316) (xy 425.75545 -131.25636)
			(xy 425.677542 -131.266446) (xy 425.59901 -131.268469) (xy 425.520686 -131.262406) (xy 425.443401 -131.248322)
			(xy 425.367974 -131.226367) (xy 425.295203 -131.196772) (xy 425.225862 -131.159851) (xy 425.160684 -131.115997)
			(xy 425.100361 -131.065673) (xy 425.045532 -131.009413) (xy 424.996778 -130.947814) (xy 424.954616 -130.881529)
			(xy 424.919493 -130.81126) (xy 424.891782 -130.737752) (xy 424.871775 -130.661784) (xy 424.859686 -130.584162)
			(xy 424.855642 -130.505708) (xy 419.835786 -130.505708) (xy 418.792391 -131.54914) (xy 420.306756 -131.54914)
			(xy 420.3108 -131.470686) (xy 420.322889 -131.393064) (xy 420.342896 -131.317096) (xy 420.370607 -131.243588)
			(xy 420.40573 -131.173319) (xy 420.447892 -131.107034) (xy 420.496646 -131.045435) (xy 420.551475 -130.989175)
			(xy 420.611798 -130.938851) (xy 420.676976 -130.894997) (xy 420.746317 -130.858076) (xy 420.819088 -130.828481)
			(xy 420.894515 -130.806526) (xy 420.9718 -130.792442) (xy 421.050124 -130.786379) (xy 421.128656 -130.788402)
			(xy 421.206564 -130.798488) (xy 421.283021 -130.816532) (xy 421.357219 -130.842342) (xy 421.428369 -130.875644)
			(xy 421.495718 -130.916085) (xy 421.534083 -130.944874) (xy 422.115486 -130.944874) (xy 422.119557 -130.889252)
			(xy 422.131683 -130.834815) (xy 422.151606 -130.782724) (xy 422.178902 -130.734089) (xy 422.212988 -130.689946)
			(xy 422.253137 -130.651237) (xy 422.298495 -130.618786) (xy 422.348095 -130.593285) (xy 422.400879 -130.575278)
			(xy 422.455722 -130.565148) (xy 422.511456 -130.563111) (xy 422.566893 -130.569211) (xy 422.62085 -130.583317)
			(xy 422.672179 -130.605129) (xy 422.719785 -130.634183) (xy 422.762653 -130.669858) (xy 422.79987 -130.711395)
			(xy 422.830643 -130.757908) (xy 422.854315 -130.808405) (xy 422.870383 -130.861812) (xy 422.878503 -130.916988)
			(xy 422.879012 -130.944874) (xy 423.131486 -130.944874) (xy 423.135557 -130.889252) (xy 423.147683 -130.834815)
			(xy 423.167606 -130.782724) (xy 423.194902 -130.734089) (xy 423.228988 -130.689946) (xy 423.269137 -130.651237)
			(xy 423.314495 -130.618786) (xy 423.364095 -130.593285) (xy 423.416879 -130.575278) (xy 423.471722 -130.565148)
			(xy 423.527456 -130.563111) (xy 423.582893 -130.569211) (xy 423.63685 -130.583317) (xy 423.688179 -130.605129)
			(xy 423.735785 -130.634183) (xy 423.778653 -130.669858) (xy 423.81587 -130.711395) (xy 423.846643 -130.757908)
			(xy 423.870315 -130.808405) (xy 423.886383 -130.861812) (xy 423.894503 -130.916988) (xy 423.895012 -130.944874)
			(xy 423.894503 -130.97276) (xy 423.886383 -131.027936) (xy 423.870315 -131.081343) (xy 423.846643 -131.13184)
			(xy 423.81587 -131.178353) (xy 423.778653 -131.21989) (xy 423.735785 -131.255565) (xy 423.688179 -131.284619)
			(xy 423.63685 -131.306431) (xy 423.582893 -131.320537) (xy 423.527456 -131.326637) (xy 423.471722 -131.3246)
			(xy 423.416879 -131.31447) (xy 423.364095 -131.296463) (xy 423.314495 -131.270962) (xy 423.269137 -131.238511)
			(xy 423.228988 -131.199802) (xy 423.194902 -131.155659) (xy 423.167606 -131.107024) (xy 423.147683 -131.054933)
			(xy 423.135557 -131.000496) (xy 423.131486 -130.944874) (xy 422.879012 -130.944874) (xy 422.878503 -130.97276)
			(xy 422.870383 -131.027936) (xy 422.854315 -131.081343) (xy 422.830643 -131.13184) (xy 422.79987 -131.178353)
			(xy 422.762653 -131.21989) (xy 422.719785 -131.255565) (xy 422.672179 -131.284619) (xy 422.62085 -131.306431)
			(xy 422.566893 -131.320537) (xy 422.511456 -131.326637) (xy 422.455722 -131.3246) (xy 422.400879 -131.31447)
			(xy 422.348095 -131.296463) (xy 422.298495 -131.270962) (xy 422.253137 -131.238511) (xy 422.212988 -131.199802)
			(xy 422.178902 -131.155659) (xy 422.151606 -131.107024) (xy 422.131683 -131.054933) (xy 422.119557 -131.000496)
			(xy 422.115486 -130.944874) (xy 421.534083 -130.944874) (xy 421.558552 -130.963236) (xy 421.616204 -131.016599)
			(xy 421.668064 -131.075606) (xy 421.713583 -131.139633) (xy 421.752276 -131.208001) (xy 421.783735 -131.279985)
			(xy 421.807626 -131.354822) (xy 421.823695 -131.431719) (xy 421.831772 -131.509861) (xy 421.832278 -131.54914)
			(xy 421.831772 -131.588419) (xy 421.83066 -131.599178) (xy 428.565054 -131.599178) (xy 428.569125 -131.543556)
			(xy 428.581251 -131.489119) (xy 428.601174 -131.437028) (xy 428.62847 -131.388393) (xy 428.662556 -131.34425)
			(xy 428.702705 -131.305541) (xy 428.748063 -131.27309) (xy 428.797663 -131.247589) (xy 428.850447 -131.229582)
			(xy 428.90529 -131.219452) (xy 428.961024 -131.217415) (xy 429.016461 -131.223515) (xy 429.070418 -131.237621)
			(xy 429.121747 -131.259433) (xy 429.169353 -131.288487) (xy 429.212221 -131.324162) (xy 429.249438 -131.365699)
			(xy 429.280211 -131.412212) (xy 429.303883 -131.462709) (xy 429.319951 -131.516116) (xy 429.328071 -131.571292)
			(xy 429.32858 -131.599178) (xy 431.856386 -131.599178) (xy 431.860457 -131.543556) (xy 431.872583 -131.489119)
			(xy 431.892506 -131.437028) (xy 431.919802 -131.388393) (xy 431.953888 -131.34425) (xy 431.994037 -131.305541)
			(xy 432.039395 -131.27309) (xy 432.088995 -131.247589) (xy 432.141779 -131.229582) (xy 432.196622 -131.219452)
			(xy 432.252356 -131.217415) (xy 432.307793 -131.223515) (xy 432.36175 -131.237621) (xy 432.413079 -131.259433)
			(xy 432.460685 -131.288487) (xy 432.503553 -131.324162) (xy 432.54077 -131.365699) (xy 432.571543 -131.412212)
			(xy 432.595215 -131.462709) (xy 432.611283 -131.516116) (xy 432.619403 -131.571292) (xy 432.619912 -131.599178)
			(xy 432.619403 -131.627064) (xy 432.611283 -131.68224) (xy 432.595215 -131.735647) (xy 432.571543 -131.786144)
			(xy 432.54077 -131.832657) (xy 432.503553 -131.874194) (xy 432.460685 -131.909869) (xy 432.413079 -131.938923)
			(xy 432.36175 -131.960735) (xy 432.307793 -131.974841) (xy 432.252356 -131.980941) (xy 432.196622 -131.978904)
			(xy 432.141779 -131.968774) (xy 432.088995 -131.950767) (xy 432.039395 -131.925266) (xy 431.994037 -131.892815)
			(xy 431.953888 -131.854106) (xy 431.919802 -131.809963) (xy 431.892506 -131.761328) (xy 431.872583 -131.709237)
			(xy 431.860457 -131.6548) (xy 431.856386 -131.599178) (xy 429.32858 -131.599178) (xy 429.328071 -131.627064)
			(xy 429.319951 -131.68224) (xy 429.303883 -131.735647) (xy 429.280211 -131.786144) (xy 429.249438 -131.832657)
			(xy 429.212221 -131.874194) (xy 429.169353 -131.909869) (xy 429.121747 -131.938923) (xy 429.070418 -131.960735)
			(xy 429.016461 -131.974841) (xy 428.961024 -131.980941) (xy 428.90529 -131.978904) (xy 428.850447 -131.968774)
			(xy 428.797663 -131.950767) (xy 428.748063 -131.925266) (xy 428.702705 -131.892815) (xy 428.662556 -131.854106)
			(xy 428.62847 -131.809963) (xy 428.601174 -131.761328) (xy 428.581251 -131.709237) (xy 428.569125 -131.6548)
			(xy 428.565054 -131.599178) (xy 421.83066 -131.599178) (xy 421.823695 -131.666561) (xy 421.807626 -131.743458)
			(xy 421.783735 -131.818295) (xy 421.752276 -131.890279) (xy 421.713583 -131.958647) (xy 421.668064 -132.022674)
			(xy 421.616204 -132.081681) (xy 421.558552 -132.135044) (xy 421.495718 -132.182195) (xy 421.428369 -132.222636)
			(xy 421.357219 -132.255938) (xy 421.283021 -132.281748) (xy 421.206564 -132.299792) (xy 421.128656 -132.309878)
			(xy 421.050124 -132.311901) (xy 420.9718 -132.305838) (xy 420.894515 -132.291754) (xy 420.819088 -132.269799)
			(xy 420.746317 -132.240204) (xy 420.676976 -132.203283) (xy 420.611798 -132.159429) (xy 420.551475 -132.109105)
			(xy 420.496646 -132.052845) (xy 420.447892 -131.991246) (xy 420.40573 -131.924961) (xy 420.370607 -131.854692)
			(xy 420.342896 -131.781184) (xy 420.322889 -131.705216) (xy 420.3108 -131.627594) (xy 420.306756 -131.54914)
			(xy 418.792391 -131.54914) (xy 418.372544 -131.969002) (xy 418.372544 -132.21716) (xy 419.198042 -132.21716)
			(xy 419.202113 -132.161538) (xy 419.214239 -132.107101) (xy 419.234162 -132.05501) (xy 419.261458 -132.006375)
			(xy 419.295544 -131.962232) (xy 419.335693 -131.923523) (xy 419.381051 -131.891072) (xy 419.430651 -131.865571)
			(xy 419.483435 -131.847564) (xy 419.538278 -131.837434) (xy 419.594012 -131.835397) (xy 419.649449 -131.841497)
			(xy 419.703406 -131.855603) (xy 419.754735 -131.877415) (xy 419.802341 -131.906469) (xy 419.845209 -131.942144)
			(xy 419.882426 -131.983681) (xy 419.913199 -132.030194) (xy 419.936871 -132.080691) (xy 419.952939 -132.134098)
			(xy 419.961059 -132.189274) (xy 419.961568 -132.21716) (xy 419.961059 -132.245046) (xy 419.952939 -132.300222)
			(xy 419.936871 -132.353629) (xy 419.913199 -132.404126) (xy 419.882426 -132.450639) (xy 419.845209 -132.492176)
			(xy 419.802341 -132.527851) (xy 419.754735 -132.556905) (xy 419.703406 -132.578717) (xy 419.649449 -132.592823)
			(xy 419.594012 -132.598923) (xy 419.538278 -132.596886) (xy 419.483435 -132.586756) (xy 419.430651 -132.568749)
			(xy 419.381051 -132.543248) (xy 419.335693 -132.510797) (xy 419.295544 -132.472088) (xy 419.261458 -132.427945)
			(xy 419.234162 -132.37931) (xy 419.214239 -132.327219) (xy 419.202113 -132.272782) (xy 419.198042 -132.21716)
			(xy 418.372544 -132.21716) (xy 418.372544 -133.94055) (xy 419.255194 -133.94055) (xy 419.255727 -133.912354)
			(xy 419.26401 -133.856573) (xy 419.280416 -133.80262) (xy 419.304588 -133.751671) (xy 419.335999 -133.704837)
			(xy 419.373965 -133.66314) (xy 419.417657 -133.627487) (xy 419.44163 -133.612636) (xy 419.454164 -133.604553)
			(xy 419.474224 -133.5825) (xy 419.487077 -133.5556) (xy 419.491632 -133.526138) (xy 419.487503 -133.496613)
			(xy 419.475039 -133.469531) (xy 419.455298 -133.447191) (xy 419.4429 -133.4389) (xy 419.419513 -133.423912)
			(xy 419.376953 -133.388218) (xy 419.340018 -133.346729) (xy 419.30949 -133.300324) (xy 419.286013 -133.249982)
			(xy 419.270084 -133.196769) (xy 419.262039 -133.141807) (xy 419.261544 -133.114034) (xy 419.26203 -133.086783)
			(xy 419.269786 -133.032835) (xy 419.285141 -132.98054) (xy 419.307783 -132.930963) (xy 419.337249 -132.885113)
			(xy 419.37294 -132.843922) (xy 419.414131 -132.808231) (xy 419.459981 -132.778765) (xy 419.509558 -132.756123)
			(xy 419.561853 -132.740768) (xy 419.615801 -132.733012) (xy 419.670303 -132.733012) (xy 419.724251 -132.740768)
			(xy 419.776546 -132.756123) (xy 419.826123 -132.778765) (xy 419.871973 -132.808231) (xy 419.913164 -132.843922)
			(xy 419.948855 -132.885113) (xy 419.978321 -132.930963) (xy 419.986064 -132.947918) (xy 422.347646 -132.947918)
			(xy 422.35169 -132.869464) (xy 422.363779 -132.791842) (xy 422.383786 -132.715874) (xy 422.411497 -132.642366)
			(xy 422.44662 -132.572097) (xy 422.488782 -132.505812) (xy 422.537536 -132.444213) (xy 422.592365 -132.387953)
			(xy 422.652688 -132.337629) (xy 422.717866 -132.293775) (xy 422.787207 -132.256854) (xy 422.859978 -132.227259)
			(xy 422.935405 -132.205304) (xy 423.01269 -132.19122) (xy 423.091014 -132.185157) (xy 423.169546 -132.18718)
			(xy 423.247454 -132.197266) (xy 423.323911 -132.21531) (xy 423.398109 -132.24112) (xy 423.469259 -132.274422)
			(xy 423.536608 -132.314863) (xy 423.599442 -132.362014) (xy 423.657094 -132.415377) (xy 423.708954 -132.474384)
			(xy 423.754473 -132.538411) (xy 423.793166 -132.606779) (xy 423.824625 -132.678763) (xy 423.848516 -132.7536)
			(xy 423.864585 -132.830497) (xy 423.872662 -132.908639) (xy 423.873168 -132.947918) (xy 423.872662 -132.987197)
			(xy 423.864585 -133.065339) (xy 423.863379 -133.071108) (xy 425.093386 -133.071108) (xy 425.09743 -132.992654)
			(xy 425.109519 -132.915032) (xy 425.129526 -132.839064) (xy 425.157237 -132.765556) (xy 425.19236 -132.695287)
			(xy 425.234522 -132.629002) (xy 425.283276 -132.567403) (xy 425.338105 -132.511143) (xy 425.398428 -132.460819)
			(xy 425.463606 -132.416965) (xy 425.532947 -132.380044) (xy 425.605718 -132.350449) (xy 425.681145 -132.328494)
			(xy 425.75843 -132.31441) (xy 425.836754 -132.308347) (xy 425.915286 -132.31037) (xy 425.993194 -132.320456)
			(xy 426.069651 -132.3385) (xy 426.143849 -132.36431) (xy 426.214999 -132.397612) (xy 426.282348 -132.438053)
			(xy 426.345182 -132.485204) (xy 426.402834 -132.538567) (xy 426.454694 -132.597574) (xy 426.500213 -132.661601)
			(xy 426.538906 -132.729969) (xy 426.570365 -132.801953) (xy 426.594256 -132.87679) (xy 426.610325 -132.953687)
			(xy 426.618402 -133.031829) (xy 426.618908 -133.071108) (xy 426.618402 -133.110387) (xy 426.610325 -133.188529)
			(xy 426.594256 -133.265426) (xy 426.570365 -133.340263) (xy 426.538906 -133.412247) (xy 426.501253 -133.478778)
			(xy 429.131728 -133.478778) (xy 429.135799 -133.423156) (xy 429.147925 -133.368719) (xy 429.167848 -133.316628)
			(xy 429.195144 -133.267993) (xy 429.22923 -133.22385) (xy 429.269379 -133.185141) (xy 429.314737 -133.15269)
			(xy 429.364337 -133.127189) (xy 429.417121 -133.109182) (xy 429.471964 -133.099052) (xy 429.527698 -133.097015)
			(xy 429.583135 -133.103115) (xy 429.637092 -133.117221) (xy 429.688421 -133.139033) (xy 429.736027 -133.168087)
			(xy 429.778895 -133.203762) (xy 429.816112 -133.245299) (xy 429.846885 -133.291812) (xy 429.870557 -133.342309)
			(xy 429.886625 -133.395716) (xy 429.894745 -133.450892) (xy 429.895254 -133.478778) (xy 431.231292 -133.478778)
			(xy 431.235363 -133.423156) (xy 431.247489 -133.368719) (xy 431.267412 -133.316628) (xy 431.294708 -133.267993)
			(xy 431.328794 -133.22385) (xy 431.368943 -133.185141) (xy 431.414301 -133.15269) (xy 431.463901 -133.127189)
			(xy 431.516685 -133.109182) (xy 431.571528 -133.099052) (xy 431.627262 -133.097015) (xy 431.682699 -133.103115)
			(xy 431.736656 -133.117221) (xy 431.787985 -133.139033) (xy 431.835591 -133.168087) (xy 431.878459 -133.203762)
			(xy 431.915676 -133.245299) (xy 431.946449 -133.291812) (xy 431.970121 -133.342309) (xy 431.986189 -133.395716)
			(xy 431.994309 -133.450892) (xy 431.994818 -133.478778) (xy 431.994309 -133.506664) (xy 431.986189 -133.56184)
			(xy 431.970121 -133.615247) (xy 431.963248 -133.629908) (xy 432.162202 -133.629908) (xy 432.166273 -133.574286)
			(xy 432.178399 -133.519849) (xy 432.198322 -133.467758) (xy 432.225618 -133.419123) (xy 432.259704 -133.37498)
			(xy 432.299853 -133.336271) (xy 432.345211 -133.30382) (xy 432.394811 -133.278319) (xy 432.447595 -133.260312)
			(xy 432.502438 -133.250182) (xy 432.558172 -133.248145) (xy 432.613609 -133.254245) (xy 432.667566 -133.268351)
			(xy 432.718895 -133.290163) (xy 432.766501 -133.319217) (xy 432.809369 -133.354892) (xy 432.846586 -133.396429)
			(xy 432.877359 -133.442942) (xy 432.901031 -133.493439) (xy 432.917099 -133.546846) (xy 432.925219 -133.602022)
			(xy 432.925728 -133.629908) (xy 432.925219 -133.657794) (xy 432.917099 -133.71297) (xy 432.901031 -133.766377)
			(xy 432.877359 -133.816874) (xy 432.846586 -133.863387) (xy 432.809369 -133.904924) (xy 432.766501 -133.940599)
			(xy 432.718895 -133.969653) (xy 432.667566 -133.991465) (xy 432.613609 -134.005571) (xy 432.558172 -134.011671)
			(xy 432.502438 -134.009634) (xy 432.447595 -133.999504) (xy 432.394811 -133.981497) (xy 432.345211 -133.955996)
			(xy 432.299853 -133.923545) (xy 432.259704 -133.884836) (xy 432.225618 -133.840693) (xy 432.198322 -133.792058)
			(xy 432.178399 -133.739967) (xy 432.166273 -133.68553) (xy 432.162202 -133.629908) (xy 431.963248 -133.629908)
			(xy 431.946449 -133.665744) (xy 431.915676 -133.712257) (xy 431.878459 -133.753794) (xy 431.835591 -133.789469)
			(xy 431.787985 -133.818523) (xy 431.736656 -133.840335) (xy 431.682699 -133.854441) (xy 431.627262 -133.860541)
			(xy 431.571528 -133.858504) (xy 431.516685 -133.848374) (xy 431.463901 -133.830367) (xy 431.414301 -133.804866)
			(xy 431.368943 -133.772415) (xy 431.328794 -133.733706) (xy 431.294708 -133.689563) (xy 431.267412 -133.640928)
			(xy 431.247489 -133.588837) (xy 431.235363 -133.5344) (xy 431.231292 -133.478778) (xy 429.895254 -133.478778)
			(xy 429.894745 -133.506664) (xy 429.886625 -133.56184) (xy 429.870557 -133.615247) (xy 429.846885 -133.665744)
			(xy 429.816112 -133.712257) (xy 429.778895 -133.753794) (xy 429.736027 -133.789469) (xy 429.688421 -133.818523)
			(xy 429.637092 -133.840335) (xy 429.583135 -133.854441) (xy 429.527698 -133.860541) (xy 429.471964 -133.858504)
			(xy 429.417121 -133.848374) (xy 429.364337 -133.830367) (xy 429.314737 -133.804866) (xy 429.269379 -133.772415)
			(xy 429.22923 -133.733706) (xy 429.195144 -133.689563) (xy 429.167848 -133.640928) (xy 429.147925 -133.588837)
			(xy 429.135799 -133.5344) (xy 429.131728 -133.478778) (xy 426.501253 -133.478778) (xy 426.500213 -133.480615)
			(xy 426.454694 -133.544642) (xy 426.402834 -133.603649) (xy 426.345182 -133.657012) (xy 426.282348 -133.704163)
			(xy 426.214999 -133.744604) (xy 426.143849 -133.777906) (xy 426.069651 -133.803716) (xy 425.993194 -133.82176)
			(xy 425.915286 -133.831846) (xy 425.836754 -133.833869) (xy 425.75843 -133.827806) (xy 425.681145 -133.813722)
			(xy 425.605718 -133.791767) (xy 425.532947 -133.762172) (xy 425.463606 -133.725251) (xy 425.398428 -133.681397)
			(xy 425.338105 -133.631073) (xy 425.283276 -133.574813) (xy 425.234522 -133.513214) (xy 425.19236 -133.446929)
			(xy 425.157237 -133.37666) (xy 425.129526 -133.303152) (xy 425.109519 -133.227184) (xy 425.09743 -133.149562)
			(xy 425.093386 -133.071108) (xy 423.863379 -133.071108) (xy 423.848516 -133.142236) (xy 423.824625 -133.217073)
			(xy 423.793166 -133.289057) (xy 423.754473 -133.357425) (xy 423.708954 -133.421452) (xy 423.657094 -133.480459)
			(xy 423.599442 -133.533822) (xy 423.536608 -133.580973) (xy 423.469259 -133.621414) (xy 423.398109 -133.654716)
			(xy 423.323911 -133.680526) (xy 423.247454 -133.69857) (xy 423.169546 -133.708656) (xy 423.091014 -133.710679)
			(xy 423.01269 -133.704616) (xy 422.935405 -133.690532) (xy 422.859978 -133.668577) (xy 422.787207 -133.638982)
			(xy 422.717866 -133.602061) (xy 422.652688 -133.558207) (xy 422.592365 -133.507883) (xy 422.537536 -133.451623)
			(xy 422.488782 -133.390024) (xy 422.44662 -133.323739) (xy 422.411497 -133.25347) (xy 422.383786 -133.179962)
			(xy 422.363779 -133.103994) (xy 422.35169 -133.026372) (xy 422.347646 -132.947918) (xy 419.986064 -132.947918)
			(xy 420.000963 -132.98054) (xy 420.016318 -133.032835) (xy 420.024074 -133.086783) (xy 420.02456 -133.114034)
			(xy 420.024036 -133.142231) (xy 420.015755 -133.198013) (xy 419.999349 -133.251967) (xy 419.975176 -133.302917)
			(xy 419.943762 -133.349751) (xy 419.905794 -133.391448) (xy 419.862099 -133.427098) (xy 419.838124 -133.441948)
			(xy 419.8256 -133.450049) (xy 419.80553 -133.472095) (xy 419.792669 -133.498991) (xy 419.78811 -133.528454)
			(xy 419.792239 -133.55798) (xy 419.804706 -133.585061) (xy 419.824452 -133.607397) (xy 419.836854 -133.615684)
			(xy 419.860223 -133.630699) (xy 419.902785 -133.666387) (xy 419.939723 -133.70787) (xy 419.970254 -133.754271)
			(xy 419.993733 -133.804609) (xy 420.009665 -133.857819) (xy 420.017713 -133.912778) (xy 420.01821 -133.94055)
			(xy 420.017724 -133.967801) (xy 420.009968 -134.021749) (xy 419.994613 -134.074044) (xy 419.971971 -134.123621)
			(xy 419.942505 -134.169471) (xy 419.906814 -134.210662) (xy 419.865623 -134.246353) (xy 419.819773 -134.275819)
			(xy 419.770196 -134.298461) (xy 419.717901 -134.313816) (xy 419.663953 -134.321572) (xy 419.609451 -134.321572)
			(xy 419.555503 -134.313816) (xy 419.503208 -134.298461) (xy 419.453631 -134.275819) (xy 419.407781 -134.246353)
			(xy 419.36659 -134.210662) (xy 419.330899 -134.169471) (xy 419.301433 -134.123621) (xy 419.278791 -134.074044)
			(xy 419.263436 -134.021749) (xy 419.25568 -133.967801) (xy 419.255194 -133.94055) (xy 418.372544 -133.94055)
			(xy 418.372544 -135.142478) (xy 419.188136 -135.142478) (xy 419.192207 -135.086856) (xy 419.204333 -135.032419)
			(xy 419.224256 -134.980328) (xy 419.251552 -134.931693) (xy 419.285638 -134.88755) (xy 419.325787 -134.848841)
			(xy 419.371145 -134.81639) (xy 419.420745 -134.790889) (xy 419.473529 -134.772882) (xy 419.528372 -134.762752)
			(xy 419.584106 -134.760715) (xy 419.639543 -134.766815) (xy 419.6935 -134.780921) (xy 419.744829 -134.802733)
			(xy 419.792435 -134.831787) (xy 419.835303 -134.867462) (xy 419.87252 -134.908999) (xy 419.903293 -134.955512)
			(xy 419.926965 -135.006009) (xy 419.943033 -135.059416) (xy 419.951153 -135.114592) (xy 419.951489 -135.132976)
			(xy 420.938775 -135.132976) (xy 420.944107 -135.055023) (xy 420.957383 -134.978024) (xy 420.978463 -134.902787)
			(xy 421.007128 -134.8301) (xy 421.043075 -134.760725) (xy 421.085929 -134.69539) (xy 421.135239 -134.63478)
			(xy 421.190489 -134.579531) (xy 421.2511 -134.530221) (xy 421.316435 -134.487369) (xy 421.38581 -134.451423)
			(xy 421.458498 -134.42276) (xy 421.533736 -134.40168) (xy 421.610735 -134.388406) (xy 421.688688 -134.383075)
			(xy 421.766777 -134.385744) (xy 421.844184 -134.396385) (xy 421.920097 -134.414887) (xy 421.99372 -134.441054)
			(xy 422.06428 -134.474614) (xy 422.131039 -134.515213) (xy 422.193296 -134.562427) (xy 422.250398 -134.61576)
			(xy 422.301747 -134.674653) (xy 422.346804 -134.738489) (xy 422.385096 -134.806597) (xy 422.416222 -134.878265)
			(xy 422.439856 -134.95274) (xy 422.45575 -135.029241) (xy 422.463737 -135.106967) (xy 422.46423 -135.146034)
			(xy 422.463737 -135.185672) (xy 422.455523 -135.264521) (xy 422.439177 -135.342094) (xy 422.414875 -135.417553)
			(xy 422.382879 -135.490085) (xy 422.363646 -135.524748) (xy 422.384176 -135.542961) (xy 422.420307 -135.584269)
			(xy 422.45015 -135.630325) (xy 422.47309 -135.680181) (xy 422.488652 -135.732808) (xy 422.496517 -135.787122)
			(xy 422.496996 -135.814562) (xy 422.496421 -135.844475) (xy 422.487063 -135.903565) (xy 422.468587 -135.960466)
			(xy 422.441447 -136.013782) (xy 422.424352 -136.038336) (xy 422.417 -136.049244) (xy 422.407492 -136.073757)
			(xy 422.404562 -136.099886) (xy 422.408405 -136.125896) (xy 422.418765 -136.150062) (xy 422.434956 -136.170778)
			(xy 422.44518 -136.179052) (xy 422.468223 -136.197173) (xy 422.508955 -136.239328) (xy 422.542755 -136.287221)
			(xy 422.568827 -136.339723) (xy 422.586555 -136.395597) (xy 422.595522 -136.453526) (xy 422.596056 -136.482836)
			(xy 422.59557 -136.510087) (xy 422.587814 -136.564035) (xy 422.572459 -136.61633) (xy 422.549817 -136.665907)
			(xy 422.520351 -136.711757) (xy 422.48466 -136.752948) (xy 422.443469 -136.788639) (xy 422.397619 -136.818105)
			(xy 422.348042 -136.840747) (xy 422.295747 -136.856102) (xy 422.241799 -136.863858) (xy 422.187297 -136.863858)
			(xy 422.133349 -136.856102) (xy 422.081054 -136.840747) (xy 422.031477 -136.818105) (xy 421.985627 -136.788639)
			(xy 421.944436 -136.752948) (xy 421.908745 -136.711757) (xy 421.879279 -136.665907) (xy 421.856637 -136.61633)
			(xy 421.841282 -136.564035) (xy 421.833526 -136.510087) (xy 421.83304 -136.482836) (xy 421.833608 -136.452923)
			(xy 421.842966 -136.393832) (xy 421.861444 -136.33693) (xy 421.888587 -136.283615) (xy 421.905684 -136.259062)
			(xy 421.913053 -136.248163) (xy 421.922569 -136.223647) (xy 421.925501 -136.197514) (xy 421.921655 -136.171499)
			(xy 421.911287 -136.147331) (xy 421.895086 -136.126617) (xy 421.884856 -136.118346) (xy 421.86456 -136.102419)
			(xy 421.828046 -136.065973) (xy 421.79677 -136.024942) (xy 421.771304 -135.980074) (xy 421.752109 -135.932186)
			(xy 421.74541 -135.907272) (xy 421.701722 -135.908542) (xy 421.662655 -135.908036) (xy 421.584929 -135.900048)
			(xy 421.508428 -135.884153) (xy 421.433954 -135.860518) (xy 421.362287 -135.82939) (xy 421.294179 -135.791097)
			(xy 421.230344 -135.746039) (xy 421.171452 -135.69469) (xy 421.11812 -135.637587) (xy 421.070907 -135.575329)
			(xy 421.030308 -135.50857) (xy 420.99675 -135.438009) (xy 420.970583 -135.364385) (xy 420.952083 -135.288472)
			(xy 420.941443 -135.211065) (xy 420.938775 -135.132976) (xy 419.951489 -135.132976) (xy 419.951662 -135.142478)
			(xy 419.951153 -135.170364) (xy 419.943033 -135.22554) (xy 419.926965 -135.278947) (xy 419.903293 -135.329444)
			(xy 419.87252 -135.375957) (xy 419.835303 -135.417494) (xy 419.792435 -135.453169) (xy 419.744829 -135.482223)
			(xy 419.6935 -135.504035) (xy 419.639543 -135.518141) (xy 419.584106 -135.524241) (xy 419.528372 -135.522204)
			(xy 419.473529 -135.512074) (xy 419.420745 -135.494067) (xy 419.371145 -135.468566) (xy 419.325787 -135.436115)
			(xy 419.285638 -135.397406) (xy 419.251552 -135.353263) (xy 419.224256 -135.304628) (xy 419.204333 -135.252537)
			(xy 419.192207 -135.1981) (xy 419.188136 -135.142478) (xy 418.372544 -135.142478) (xy 418.372544 -136.162034)
			(xy 419.208456 -136.162034) (xy 419.212527 -136.106412) (xy 419.224653 -136.051975) (xy 419.244576 -135.999884)
			(xy 419.271872 -135.951249) (xy 419.305958 -135.907106) (xy 419.346107 -135.868397) (xy 419.391465 -135.835946)
			(xy 419.441065 -135.810445) (xy 419.493849 -135.792438) (xy 419.548692 -135.782308) (xy 419.604426 -135.780271)
			(xy 419.659863 -135.786371) (xy 419.71382 -135.800477) (xy 419.765149 -135.822289) (xy 419.812755 -135.851343)
			(xy 419.855623 -135.887018) (xy 419.89284 -135.928555) (xy 419.923613 -135.975068) (xy 419.947285 -136.025565)
			(xy 419.963353 -136.078972) (xy 419.971473 -136.134148) (xy 419.971982 -136.162034) (xy 419.971473 -136.18992)
			(xy 419.963353 -136.245096) (xy 419.947285 -136.298503) (xy 419.923613 -136.349) (xy 419.89284 -136.395513)
			(xy 419.855623 -136.43705) (xy 419.812755 -136.472725) (xy 419.765149 -136.501779) (xy 419.71382 -136.523591)
			(xy 419.659863 -136.537697) (xy 419.604426 -136.543797) (xy 419.548692 -136.54176) (xy 419.493849 -136.53163)
			(xy 419.441065 -136.513623) (xy 419.391465 -136.488122) (xy 419.346107 -136.455671) (xy 419.305958 -136.416962)
			(xy 419.271872 -136.372819) (xy 419.244576 -136.324184) (xy 419.224653 -136.272093) (xy 419.212527 -136.217656)
			(xy 419.208456 -136.162034) (xy 418.372544 -136.162034) (xy 418.372544 -137.178034) (xy 419.208456 -137.178034)
			(xy 419.212527 -137.122412) (xy 419.224653 -137.067975) (xy 419.244576 -137.015884) (xy 419.271872 -136.967249)
			(xy 419.305958 -136.923106) (xy 419.346107 -136.884397) (xy 419.391465 -136.851946) (xy 419.441065 -136.826445)
			(xy 419.493849 -136.808438) (xy 419.548692 -136.798308) (xy 419.604426 -136.796271) (xy 419.659863 -136.802371)
			(xy 419.71382 -136.816477) (xy 419.765149 -136.838289) (xy 419.812755 -136.867343) (xy 419.855623 -136.903018)
			(xy 419.89284 -136.944555) (xy 419.923613 -136.991068) (xy 419.947285 -137.041565) (xy 419.963353 -137.094972)
			(xy 419.971473 -137.150148) (xy 419.971982 -137.178034) (xy 419.971473 -137.20592) (xy 419.963353 -137.261096)
			(xy 419.947285 -137.314503) (xy 419.923613 -137.365) (xy 419.89284 -137.411513) (xy 419.855623 -137.45305)
			(xy 419.812755 -137.488725) (xy 419.765149 -137.517779) (xy 419.71382 -137.539591) (xy 419.659863 -137.553697)
			(xy 419.604426 -137.559797) (xy 419.548692 -137.55776) (xy 419.493849 -137.54763) (xy 419.441065 -137.529623)
			(xy 419.391465 -137.504122) (xy 419.346107 -137.471671) (xy 419.305958 -137.432962) (xy 419.271872 -137.388819)
			(xy 419.244576 -137.340184) (xy 419.224653 -137.288093) (xy 419.212527 -137.233656) (xy 419.208456 -137.178034)
			(xy 418.372544 -137.178034) (xy 418.372544 -137.724388) (xy 420.811452 -137.724388) (xy 420.811941 -137.685743)
			(xy 420.819761 -137.608849) (xy 420.835319 -137.533141) (xy 420.858457 -137.459395) (xy 420.888937 -137.388368)
			(xy 420.926446 -137.32079) (xy 420.9706 -137.257352) (xy 421.020945 -137.198708) (xy 421.076964 -137.145457)
			(xy 421.138083 -137.098147) (xy 421.203676 -137.057263) (xy 421.273067 -137.023225) (xy 421.345547 -136.996382)
			(xy 421.42037 -136.977009) (xy 421.496769 -136.965305) (xy 421.57396 -136.96139) (xy 421.651151 -136.965305)
			(xy 421.72755 -136.977009) (xy 421.802373 -136.996382) (xy 421.874853 -137.023225) (xy 421.944244 -137.057263)
			(xy 422.009837 -137.098147) (xy 422.070956 -137.145457) (xy 422.126975 -137.198708) (xy 422.17732 -137.257352)
			(xy 422.221474 -137.32079) (xy 422.258983 -137.388368) (xy 422.289463 -137.459395) (xy 422.312601 -137.533141)
			(xy 422.328159 -137.608849) (xy 422.335979 -137.685743) (xy 422.336468 -137.724388) (xy 422.335878 -137.765404)
			(xy 422.327083 -137.846964) (xy 422.309582 -137.927108) (xy 422.283578 -138.004911) (xy 422.249372 -138.079471)
			(xy 422.207358 -138.149928) (xy 422.158023 -138.215467) (xy 422.101936 -138.275331) (xy 422.046149 -138.32332)
			(xy 423.596308 -138.32332) (xy 423.596308 -134.5057) (xy 423.796206 -134.306056) (xy 427.613826 -134.306056)
			(xy 427.813724 -134.5057) (xy 427.813724 -137.130028) (xy 428.753016 -137.130028) (xy 428.753463 -137.103293)
			(xy 428.760925 -137.050348) (xy 428.775708 -136.998963) (xy 428.797521 -136.950146) (xy 428.825937 -136.904853)
			(xy 428.860399 -136.863971) (xy 428.880016 -136.845802) (xy 428.890822 -136.835406) (xy 428.906368 -136.809781)
			(xy 428.913789 -136.780743) (xy 428.912443 -136.750802) (xy 428.902446 -136.722547) (xy 428.893986 -136.710166)
			(xy 428.876517 -136.68545) (xy 428.848814 -136.631639) (xy 428.829949 -136.574132) (xy 428.820397 -136.514367)
			(xy 428.819818 -136.484106) (xy 428.82029 -136.455888) (xy 428.828576 -136.400063) (xy 428.844998 -136.34607)
			(xy 428.869197 -136.295085) (xy 428.900645 -136.248223) (xy 428.938655 -136.206507) (xy 428.982397 -136.170847)
			(xy 429.030917 -136.142022) (xy 429.083154 -136.120661) (xy 429.137969 -136.107232) (xy 429.16602 -136.104122)
			(xy 429.180402 -136.102296) (xy 429.207356 -136.091662) (xy 429.230235 -136.073881) (xy 429.247195 -136.050386)
			(xy 429.256869 -136.023073) (xy 429.258478 -135.994141) (xy 429.255682 -135.979916) (xy 429.250944 -135.958447)
			(xy 429.245847 -135.914777) (xy 429.245522 -135.892794) (xy 429.246052 -135.864672) (xy 429.254319 -135.809039)
			(xy 429.270671 -135.755224) (xy 429.294754 -135.704397) (xy 429.326045 -135.657661) (xy 429.344582 -135.636508)
			(xy 429.353973 -135.625483) (xy 429.366648 -135.599455) (xy 429.371511 -135.570917) (xy 429.368172 -135.54216)
			(xy 429.3569 -135.515495) (xy 429.338599 -135.493063) (xy 429.31474 -135.476667) (xy 429.301148 -135.471662)
			(xy 429.26354 -135.458714) (xy 429.191024 -135.426028) (xy 429.122305 -135.38597) (xy 429.058129 -135.338975)
			(xy 428.999194 -135.285555) (xy 428.946141 -135.22629) (xy 428.899546 -135.161823) (xy 428.859916 -135.092856)
			(xy 428.82768 -135.020138) (xy 428.803191 -134.94446) (xy 428.786713 -134.866643) (xy 428.778425 -134.787533)
			(xy 428.777908 -134.747762) (xy 428.778397 -134.709117) (xy 428.786217 -134.632223) (xy 428.801775 -134.556515)
			(xy 428.824913 -134.482769) (xy 428.855393 -134.411742) (xy 428.892902 -134.344164) (xy 428.937056 -134.280726)
			(xy 428.987401 -134.222082) (xy 429.04342 -134.168831) (xy 429.104539 -134.121521) (xy 429.170132 -134.080637)
			(xy 429.239523 -134.046599) (xy 429.312003 -134.019756) (xy 429.386826 -134.000383) (xy 429.463225 -133.988679)
			(xy 429.540416 -133.984764) (xy 429.617607 -133.988679) (xy 429.694006 -134.000383) (xy 429.768829 -134.019756)
			(xy 429.841309 -134.046599) (xy 429.9107 -134.080637) (xy 429.976293 -134.121521) (xy 430.037412 -134.168831)
			(xy 430.093431 -134.222082) (xy 430.143776 -134.280726) (xy 430.18793 -134.344164) (xy 430.225439 -134.411742)
			(xy 430.255919 -134.482769) (xy 430.259687 -134.494778) (xy 431.227736 -134.494778) (xy 431.231807 -134.439156)
			(xy 431.243933 -134.384719) (xy 431.263856 -134.332628) (xy 431.291152 -134.283993) (xy 431.325238 -134.23985)
			(xy 431.365387 -134.201141) (xy 431.410745 -134.16869) (xy 431.460345 -134.143189) (xy 431.513129 -134.125182)
			(xy 431.567972 -134.115052) (xy 431.623706 -134.113015) (xy 431.679143 -134.119115) (xy 431.7331 -134.133221)
			(xy 431.784429 -134.155033) (xy 431.832035 -134.184087) (xy 431.874903 -134.219762) (xy 431.91212 -134.261299)
			(xy 431.942893 -134.307812) (xy 431.966565 -134.358309) (xy 431.982633 -134.411716) (xy 431.990753 -134.466892)
			(xy 431.991262 -134.494778) (xy 431.990753 -134.522664) (xy 431.982633 -134.57784) (xy 431.966565 -134.631247)
			(xy 431.942893 -134.681744) (xy 431.91212 -134.728257) (xy 431.874903 -134.769794) (xy 431.832035 -134.805469)
			(xy 431.784429 -134.834523) (xy 431.7331 -134.856335) (xy 431.679143 -134.870441) (xy 431.623706 -134.876541)
			(xy 431.567972 -134.874504) (xy 431.513129 -134.864374) (xy 431.460345 -134.846367) (xy 431.410745 -134.820866)
			(xy 431.365387 -134.788415) (xy 431.325238 -134.749706) (xy 431.291152 -134.705563) (xy 431.263856 -134.656928)
			(xy 431.243933 -134.604837) (xy 431.231807 -134.5504) (xy 431.227736 -134.494778) (xy 430.259687 -134.494778)
			(xy 430.279057 -134.556515) (xy 430.294615 -134.632223) (xy 430.302435 -134.709117) (xy 430.302924 -134.747762)
			(xy 430.302472 -134.785915) (xy 430.294836 -134.861837) (xy 430.279656 -134.936617) (xy 430.257084 -135.009507)
			(xy 430.227345 -135.079779) (xy 430.190738 -135.14673) (xy 430.147628 -135.20969) (xy 430.098445 -135.268031)
			(xy 430.077321 -135.288528) (xy 435.509922 -135.288528) (xy 435.513993 -135.232906) (xy 435.526119 -135.178469)
			(xy 435.546042 -135.126378) (xy 435.573338 -135.077743) (xy 435.607424 -135.0336) (xy 435.647573 -134.994891)
			(xy 435.692931 -134.96244) (xy 435.742531 -134.936939) (xy 435.795315 -134.918932) (xy 435.850158 -134.908802)
			(xy 435.905892 -134.906765) (xy 435.961329 -134.912865) (xy 436.015286 -134.926971) (xy 436.066615 -134.948783)
			(xy 436.114221 -134.977837) (xy 436.157089 -135.013512) (xy 436.194306 -135.055049) (xy 436.225079 -135.101562)
			(xy 436.248751 -135.152059) (xy 436.264819 -135.205466) (xy 436.272939 -135.260642) (xy 436.273448 -135.288528)
			(xy 436.272939 -135.316414) (xy 436.264819 -135.37159) (xy 436.248751 -135.424997) (xy 436.225079 -135.475494)
			(xy 436.194306 -135.522007) (xy 436.157089 -135.563544) (xy 436.114221 -135.599219) (xy 436.066615 -135.628273)
			(xy 436.015286 -135.650085) (xy 435.961329 -135.664191) (xy 435.905892 -135.670291) (xy 435.850158 -135.668254)
			(xy 435.795315 -135.658124) (xy 435.742531 -135.640117) (xy 435.692931 -135.614616) (xy 435.647573 -135.582165)
			(xy 435.607424 -135.543456) (xy 435.573338 -135.499313) (xy 435.546042 -135.450678) (xy 435.526119 -135.398587)
			(xy 435.513993 -135.34415) (xy 435.509922 -135.288528) (xy 430.077321 -135.288528) (xy 430.043683 -135.321168)
			(xy 429.983887 -135.368571) (xy 429.919657 -135.409765) (xy 429.885856 -135.427466) (xy 429.87325 -135.434543)
			(xy 429.852218 -135.45435) (xy 429.837569 -135.479252) (xy 429.830475 -135.507259) (xy 429.831501 -135.536132)
			(xy 429.840567 -135.563563) (xy 429.856947 -135.587362) (xy 429.867822 -135.596884) (xy 429.889389 -135.615117)
			(xy 429.927464 -135.656823) (xy 429.958973 -135.703688) (xy 429.983229 -135.754686) (xy 429.990721 -135.779256)
			(xy 432.659026 -135.779256) (xy 432.663097 -135.723634) (xy 432.675223 -135.669197) (xy 432.695146 -135.617106)
			(xy 432.722442 -135.568471) (xy 432.756528 -135.524328) (xy 432.796677 -135.485619) (xy 432.842035 -135.453168)
			(xy 432.891635 -135.427667) (xy 432.944419 -135.40966) (xy 432.999262 -135.39953) (xy 433.054996 -135.397493)
			(xy 433.110433 -135.403593) (xy 433.16439 -135.417699) (xy 433.215719 -135.439511) (xy 433.263325 -135.468565)
			(xy 433.306193 -135.50424) (xy 433.34341 -135.545777) (xy 433.374183 -135.59229) (xy 433.397855 -135.642787)
			(xy 433.413923 -135.696194) (xy 433.422043 -135.75137) (xy 433.422552 -135.779256) (xy 433.422043 -135.807142)
			(xy 433.413923 -135.862318) (xy 433.397855 -135.915725) (xy 433.374183 -135.966222) (xy 433.34341 -136.012735)
			(xy 433.306193 -136.054272) (xy 433.263325 -136.089947) (xy 433.215719 -136.119001) (xy 433.16439 -136.140813)
			(xy 433.110433 -136.154919) (xy 433.054996 -136.161019) (xy 432.999262 -136.158982) (xy 432.944419 -136.148852)
			(xy 432.891635 -136.130845) (xy 432.842035 -136.105344) (xy 432.796677 -136.072893) (xy 432.756528 -136.034184)
			(xy 432.722442 -135.990041) (xy 432.695146 -135.941406) (xy 432.675223 -135.889315) (xy 432.663097 -135.834878)
			(xy 432.659026 -135.779256) (xy 429.990721 -135.779256) (xy 429.9997 -135.808703) (xy 430.008027 -135.864558)
			(xy 430.008538 -135.892794) (xy 430.008015 -135.92101) (xy 429.999731 -135.97683) (xy 429.983312 -136.030819)
			(xy 429.959117 -136.081801) (xy 429.927675 -136.128661) (xy 429.889671 -136.170376) (xy 429.845935 -136.206037)
			(xy 429.797423 -136.234864) (xy 429.745192 -136.256229) (xy 429.690384 -136.269664) (xy 429.662336 -136.272778)
			(xy 429.64796 -136.274645) (xy 429.621005 -136.285266) (xy 429.598123 -136.303038) (xy 429.58116 -136.326525)
			(xy 429.571485 -136.353834) (xy 429.569877 -136.382761) (xy 429.572674 -136.396984) (xy 429.577413 -136.418453)
			(xy 429.582509 -136.462123) (xy 429.582834 -136.484106) (xy 429.582359 -136.51084) (xy 429.580115 -136.526778)
			(xy 431.237896 -136.526778) (xy 431.241967 -136.471156) (xy 431.254093 -136.416719) (xy 431.274016 -136.364628)
			(xy 431.301312 -136.315993) (xy 431.335398 -136.27185) (xy 431.375547 -136.233141) (xy 431.420905 -136.20069)
			(xy 431.470505 -136.175189) (xy 431.523289 -136.157182) (xy 431.578132 -136.147052) (xy 431.633866 -136.145015)
			(xy 431.689303 -136.151115) (xy 431.74326 -136.165221) (xy 431.794589 -136.187033) (xy 431.842195 -136.216087)
			(xy 431.885063 -136.251762) (xy 431.92228 -136.293299) (xy 431.953053 -136.339812) (xy 431.976725 -136.390309)
			(xy 431.992793 -136.443716) (xy 432.000913 -136.498892) (xy 432.001422 -136.526778) (xy 432.000913 -136.554664)
			(xy 431.992793 -136.60984) (xy 431.976725 -136.663247) (xy 431.953053 -136.713744) (xy 431.92228 -136.760257)
			(xy 431.885063 -136.801794) (xy 431.842195 -136.837469) (xy 431.794589 -136.866523) (xy 431.74326 -136.888335)
			(xy 431.689303 -136.902441) (xy 431.633866 -136.908541) (xy 431.578132 -136.906504) (xy 431.523289 -136.896374)
			(xy 431.470505 -136.878367) (xy 431.420905 -136.852866) (xy 431.375547 -136.820415) (xy 431.335398 -136.781706)
			(xy 431.301312 -136.737563) (xy 431.274016 -136.688928) (xy 431.254093 -136.636837) (xy 431.241967 -136.5824)
			(xy 431.237896 -136.526778) (xy 429.580115 -136.526778) (xy 429.574905 -136.563785) (xy 429.560129 -136.61517)
			(xy 429.538321 -136.663988) (xy 429.509909 -136.709281) (xy 429.47545 -136.750163) (xy 429.455834 -136.768332)
			(xy 429.444998 -136.778702) (xy 429.429448 -136.804333) (xy 429.422029 -136.83338) (xy 429.423384 -136.863329)
			(xy 429.433395 -136.891588) (xy 429.441864 -136.903968) (xy 429.459298 -136.928708) (xy 429.487011 -136.982509)
			(xy 429.505885 -137.04001) (xy 429.515448 -137.099769) (xy 429.516032 -137.130028) (xy 429.515546 -137.157279)
			(xy 429.50779 -137.211227) (xy 429.492435 -137.263522) (xy 429.469793 -137.313099) (xy 429.440327 -137.358949)
			(xy 429.404636 -137.40014) (xy 429.363445 -137.435831) (xy 429.340501 -137.450576) (xy 433.794916 -137.450576)
			(xy 433.795427 -137.421667) (xy 433.804127 -137.364509) (xy 433.821355 -137.309318) (xy 433.846716 -137.25736)
			(xy 433.879629 -137.209826) (xy 433.919339 -137.167803) (xy 433.964937 -137.132256) (xy 434.015378 -137.103998)
			(xy 434.069507 -137.083678) (xy 434.097684 -137.077196) (xy 434.111796 -137.073807) (xy 434.137386 -137.060134)
			(xy 434.158092 -137.039811) (xy 434.17224 -137.014482) (xy 434.178687 -136.986193) (xy 434.176909 -136.957235)
			(xy 434.167053 -136.929947) (xy 434.158898 -136.917938) (xy 434.141646 -136.893303) (xy 434.11424 -136.839771)
			(xy 434.095565 -136.782604) (xy 434.086082 -136.723217) (xy 434.085492 -136.693148) (xy 434.085978 -136.665897)
			(xy 434.093734 -136.611949) (xy 434.109089 -136.559654) (xy 434.131731 -136.510077) (xy 434.161197 -136.464227)
			(xy 434.196888 -136.423036) (xy 434.238079 -136.387345) (xy 434.283929 -136.357879) (xy 434.333506 -136.335237)
			(xy 434.385801 -136.319882) (xy 434.439749 -136.312126) (xy 434.494251 -136.312126) (xy 434.548199 -136.319882)
			(xy 434.600494 -136.335237) (xy 434.650071 -136.357879) (xy 434.695921 -136.387345) (xy 434.737112 -136.423036)
			(xy 434.772803 -136.464227) (xy 434.802269 -136.510077) (xy 434.824911 -136.559654) (xy 434.840266 -136.611949)
			(xy 434.848022 -136.665897) (xy 434.848508 -136.693148) (xy 434.848 -136.722056) (xy 434.839297 -136.779214)
			(xy 434.822067 -136.834404) (xy 434.796705 -136.88636) (xy 434.763792 -136.933894) (xy 434.754283 -136.943957)
			(xy 448.198123 -136.943957) (xy 448.198123 -136.889443) (xy 448.205882 -136.835484) (xy 448.221241 -136.783179)
			(xy 448.243888 -136.733592) (xy 448.273363 -136.687733) (xy 448.309064 -136.646535) (xy 448.350265 -136.610839)
			(xy 448.396127 -136.581369) (xy 448.445716 -136.558727) (xy 448.498023 -136.543373) (xy 448.551983 -136.53562)
			(xy 448.57924 -136.53516) (xy 448.60661 -136.535647) (xy 448.660788 -136.543457) (xy 448.713292 -136.558941)
			(xy 448.763039 -136.581778) (xy 448.809006 -136.6115) (xy 448.829938 -136.62914) (xy 448.841266 -136.638376)
			(xy 448.867823 -136.650552) (xy 448.89674 -136.654725) (xy 448.925657 -136.650552) (xy 448.952214 -136.638376)
			(xy 448.963542 -136.62914) (xy 448.98449 -136.611521) (xy 449.030458 -136.581805) (xy 449.080201 -136.558964)
			(xy 449.132699 -136.543469) (xy 449.186872 -136.535636) (xy 449.21424 -136.53516) (xy 449.241487 -136.535713)
			(xy 449.295426 -136.543473) (xy 449.347711 -136.558831) (xy 449.397279 -136.581472) (xy 449.443121 -136.610937)
			(xy 449.484303 -136.646626) (xy 449.519987 -136.687811) (xy 449.549447 -136.733656) (xy 449.572083 -136.783226)
			(xy 449.587435 -136.835513) (xy 449.59519 -136.889453) (xy 449.59519 -136.943947) (xy 449.587435 -136.997887)
			(xy 449.572083 -137.050174) (xy 449.549447 -137.099744) (xy 449.519987 -137.145589) (xy 449.484303 -137.186774)
			(xy 449.443121 -137.222463) (xy 449.397279 -137.251928) (xy 449.347711 -137.274569) (xy 449.295426 -137.289927)
			(xy 449.241487 -137.297687) (xy 449.21424 -137.298176) (xy 449.18687 -137.297692) (xy 449.132692 -137.28988)
			(xy 449.080189 -137.274395) (xy 449.030441 -137.251557) (xy 448.984474 -137.221836) (xy 448.963542 -137.204196)
			(xy 448.952214 -137.19496) (xy 448.925657 -137.182784) (xy 448.89674 -137.178611) (xy 448.867823 -137.182784)
			(xy 448.841266 -137.19496) (xy 448.829938 -137.204196) (xy 448.809002 -137.22183) (xy 448.76303 -137.251543)
			(xy 448.713284 -137.27438) (xy 448.660784 -137.289872) (xy 448.606609 -137.297701) (xy 448.57924 -137.298176)
			(xy 448.551983 -137.29778) (xy 448.498023 -137.290027) (xy 448.445716 -137.274673) (xy 448.396127 -137.252031)
			(xy 448.350265 -137.222561) (xy 448.309064 -137.186865) (xy 448.273363 -137.145667) (xy 448.243888 -137.099809)
			(xy 448.221241 -137.050221) (xy 448.205882 -136.997916) (xy 448.198123 -136.943957) (xy 434.754283 -136.943957)
			(xy 434.724082 -136.975917) (xy 434.678484 -137.011464) (xy 434.628044 -137.039723) (xy 434.573917 -137.060045)
			(xy 434.54574 -137.066528) (xy 434.531663 -137.07004) (xy 434.506085 -137.083693) (xy 434.485385 -137.103994)
			(xy 434.471235 -137.129301) (xy 434.464781 -137.157568) (xy 434.466545 -137.186508) (xy 434.476383 -137.213781)
			(xy 434.484526 -137.225786) (xy 434.501792 -137.250412) (xy 434.529194 -137.303948) (xy 434.547865 -137.361117)
			(xy 434.557344 -137.420506) (xy 434.557932 -137.450576) (xy 434.557446 -137.477827) (xy 434.54969 -137.531775)
			(xy 434.534335 -137.58407) (xy 434.511693 -137.633647) (xy 434.482227 -137.679497) (xy 434.446536 -137.720688)
			(xy 434.405345 -137.756379) (xy 434.359495 -137.785845) (xy 434.309918 -137.808487) (xy 434.257623 -137.823842)
			(xy 434.203675 -137.831598) (xy 434.149173 -137.831598) (xy 434.095225 -137.823842) (xy 434.04293 -137.808487)
			(xy 433.993353 -137.785845) (xy 433.947503 -137.756379) (xy 433.906312 -137.720688) (xy 433.870621 -137.679497)
			(xy 433.841155 -137.633647) (xy 433.818513 -137.58407) (xy 433.803158 -137.531775) (xy 433.795402 -137.477827)
			(xy 433.794916 -137.450576) (xy 429.340501 -137.450576) (xy 429.317595 -137.465297) (xy 429.268018 -137.487939)
			(xy 429.215723 -137.503294) (xy 429.161775 -137.51105) (xy 429.107273 -137.51105) (xy 429.053325 -137.503294)
			(xy 429.00103 -137.487939) (xy 428.951453 -137.465297) (xy 428.905603 -137.435831) (xy 428.864412 -137.40014)
			(xy 428.828721 -137.358949) (xy 428.799255 -137.313099) (xy 428.776613 -137.263522) (xy 428.761258 -137.211227)
			(xy 428.753502 -137.157279) (xy 428.753016 -137.130028) (xy 427.813724 -137.130028) (xy 427.813724 -138.143996)
			(xy 428.762158 -138.143996) (xy 428.766229 -138.088374) (xy 428.778355 -138.033937) (xy 428.798278 -137.981846)
			(xy 428.825574 -137.933211) (xy 428.85966 -137.889068) (xy 428.899809 -137.850359) (xy 428.945167 -137.817908)
			(xy 428.994767 -137.792407) (xy 429.047551 -137.7744) (xy 429.102394 -137.76427) (xy 429.158128 -137.762233)
			(xy 429.213565 -137.768333) (xy 429.267522 -137.782439) (xy 429.318851 -137.804251) (xy 429.366457 -137.833305)
			(xy 429.409325 -137.86898) (xy 429.446542 -137.910517) (xy 429.477315 -137.95703) (xy 429.500987 -138.007527)
			(xy 429.517055 -138.060934) (xy 429.525175 -138.11611) (xy 429.525684 -138.143996) (xy 429.525175 -138.171882)
			(xy 429.517055 -138.227058) (xy 429.500987 -138.280465) (xy 429.477315 -138.330962) (xy 429.446542 -138.377475)
			(xy 429.409325 -138.419012) (xy 429.366457 -138.454687) (xy 429.318851 -138.483741) (xy 429.267522 -138.505553)
			(xy 429.213565 -138.519659) (xy 429.158128 -138.525759) (xy 429.102394 -138.523722) (xy 429.047551 -138.513592)
			(xy 428.994767 -138.495585) (xy 428.945167 -138.470084) (xy 428.899809 -138.437633) (xy 428.85966 -138.398924)
			(xy 428.825574 -138.354781) (xy 428.798278 -138.306146) (xy 428.778355 -138.254055) (xy 428.766229 -138.199618)
			(xy 428.762158 -138.143996) (xy 427.813724 -138.143996) (xy 427.813724 -138.32332) (xy 427.613826 -138.522964)
			(xy 423.796206 -138.522964) (xy 423.596308 -138.32332) (xy 422.046149 -138.32332) (xy 422.039747 -138.328827)
			(xy 422.006268 -138.35253) (xy 421.993945 -138.361614) (xy 421.974992 -138.385642) (xy 421.964005 -138.414205)
			(xy 421.961967 -138.44474) (xy 421.969062 -138.474509) (xy 421.984653 -138.500842) (xy 422.007343 -138.521379)
			(xy 422.021 -138.528298) (xy 422.045347 -138.540166) (xy 422.090718 -138.569745) (xy 422.13145 -138.605444)
			(xy 422.166725 -138.646543) (xy 422.195834 -138.692217) (xy 422.218192 -138.741549) (xy 422.233349 -138.793547)
			(xy 422.241002 -138.847165) (xy 422.241472 -138.874246) (xy 422.240986 -138.901497) (xy 422.23323 -138.955445)
			(xy 422.217875 -139.00774) (xy 422.195233 -139.057317) (xy 422.165767 -139.103167) (xy 422.130076 -139.144358)
			(xy 422.088885 -139.180049) (xy 422.043035 -139.209515) (xy 421.993458 -139.232157) (xy 421.941163 -139.247512)
			(xy 421.887215 -139.255268) (xy 421.832713 -139.255268) (xy 421.778765 -139.247512) (xy 421.72647 -139.232157)
			(xy 421.676893 -139.209515) (xy 421.631043 -139.180049) (xy 421.589852 -139.144358) (xy 421.554161 -139.103167)
			(xy 421.524695 -139.057317) (xy 421.502053 -139.00774) (xy 421.486698 -138.955445) (xy 421.478942 -138.901497)
			(xy 421.478456 -138.874246) (xy 421.479062 -138.843349) (xy 421.489016 -138.782362) (xy 421.50867 -138.723777)
			(xy 421.537512 -138.669126) (xy 421.555672 -138.644122) (xy 421.564435 -138.631571) (xy 421.574835 -138.602798)
			(xy 421.576261 -138.572237) (xy 421.568588 -138.542621) (xy 421.552501 -138.516597) (xy 421.529438 -138.496494)
			(xy 421.501463 -138.484109) (xy 421.48633 -138.481816) (xy 421.447004 -138.476744) (xy 421.369602 -138.45951)
			(xy 421.294407 -138.434335) (xy 421.222231 -138.401492) (xy 421.153854 -138.361335) (xy 421.090014 -138.314297)
			(xy 421.031401 -138.260888) (xy 420.978648 -138.201683) (xy 420.932325 -138.137323) (xy 420.892932 -138.068503)
			(xy 420.860894 -137.995966) (xy 420.836559 -137.920495) (xy 420.820188 -137.842906) (xy 420.811959 -137.764037)
			(xy 420.811452 -137.724388) (xy 418.372544 -137.724388) (xy 418.372544 -138.842496) (xy 418.405134 -138.863701)
			(xy 418.466259 -138.91176) (xy 418.522177 -138.96579) (xy 418.572307 -139.02523) (xy 418.616129 -139.089461)
			(xy 418.653188 -139.157818) (xy 418.683098 -139.229592) (xy 418.705551 -139.304036) (xy 418.713412 -139.342114)
			(xy 418.716206 -139.357354) (xy 418.984938 -139.626086) (xy 418.996079 -139.636378) (xy 419.0229 -139.650505)
			(xy 419.052685 -139.656145) (xy 419.082814 -139.652801) (xy 419.110637 -139.640769) (xy 419.133709 -139.621105)
			(xy 419.149999 -139.59554) (xy 419.158074 -139.566321) (xy 419.158166 -139.551156) (xy 419.157912 -139.527788)
			(xy 419.158407 -139.488724) (xy 419.166398 -139.411005) (xy 419.182295 -139.33451) (xy 419.205931 -139.260043)
			(xy 419.237058 -139.188383) (xy 419.275351 -139.120281) (xy 419.320407 -139.056453) (xy 419.371754 -138.997567)
			(xy 419.428854 -138.94424) (xy 419.491107 -138.897032) (xy 419.557862 -138.856439) (xy 419.628419 -138.822884)
			(xy 419.702036 -138.796721) (xy 419.777944 -138.778223) (xy 419.855345 -138.767584) (xy 419.933428 -138.764917)
			(xy 420.011374 -138.770249) (xy 420.088367 -138.783524) (xy 420.163599 -138.804603) (xy 420.23628 -138.833264)
			(xy 420.305649 -138.869209) (xy 420.370979 -138.912058) (xy 420.431585 -138.961364) (xy 420.486831 -139.016609)
			(xy 420.536137 -139.077214) (xy 420.578987 -139.142544) (xy 420.614932 -139.211913) (xy 420.643595 -139.284594)
			(xy 420.664674 -139.359825) (xy 420.67795 -139.436818) (xy 420.683283 -139.514764) (xy 420.680616 -139.592847)
			(xy 420.669979 -139.670248) (xy 420.651482 -139.746156) (xy 420.625319 -139.819774) (xy 420.591765 -139.890331)
			(xy 420.551172 -139.957086) (xy 420.503965 -140.01934) (xy 420.450639 -140.076441) (xy 420.391753 -140.127788)
			(xy 420.327926 -140.172845) (xy 420.259825 -140.211138) (xy 420.188165 -140.242266) (xy 420.113697 -140.265903)
			(xy 420.037203 -140.281801) (xy 419.959484 -140.289792) (xy 419.92042 -140.290296) (xy 419.881275 -140.289796)
			(xy 419.803398 -140.281777) (xy 419.764972 -140.274294) (xy 419.738302 -140.268706) (xy 419.68293 -140.324078)
			(xy 419.7604 -140.401548) (xy 423.284904 -140.401548) (xy 423.299811 -140.401029) (xy 423.328357 -140.392425)
			(xy 423.353206 -140.37595) (xy 423.372245 -140.353006) (xy 423.383853 -140.325544) (xy 423.387044 -140.295901)
			(xy 423.381545 -140.266598) (xy 423.367825 -140.240128) (xy 423.357802 -140.229082) (xy 423.332534 -140.202422)
			(xy 423.286675 -140.145037) (xy 423.246547 -140.083507) (xy 423.212523 -140.018403) (xy 423.184918 -139.950329)
			(xy 423.163988 -139.879915) (xy 423.149927 -139.807815) (xy 423.142865 -139.734697) (xy 423.14241 -139.697968)
			(xy 423.142906 -139.658904) (xy 423.150899 -139.581185) (xy 423.166798 -139.504691) (xy 423.190436 -139.430225)
			(xy 423.221565 -139.358565) (xy 423.259859 -139.290465) (xy 423.304916 -139.226638) (xy 423.356264 -139.167753)
			(xy 423.413365 -139.114428) (xy 423.47562 -139.067222) (xy 423.542375 -139.026629) (xy 423.612932 -138.993076)
			(xy 423.68655 -138.966914) (xy 423.762458 -138.948418) (xy 423.839859 -138.937781) (xy 423.917942 -138.935115)
			(xy 423.995888 -138.940449) (xy 424.07288 -138.953725) (xy 424.148111 -138.974805) (xy 424.220792 -139.003468)
			(xy 424.288893 -139.038756) (xy 433.284894 -139.038756) (xy 433.292649 -138.984811) (xy 433.308002 -138.932519)
			(xy 433.330641 -138.882945) (xy 433.360104 -138.837096) (xy 433.395793 -138.795908) (xy 433.436979 -138.760217)
			(xy 433.482826 -138.730751) (xy 433.532399 -138.70811) (xy 433.58469 -138.692754) (xy 433.638634 -138.684995)
			(xy 433.665884 -138.684508) (xy 433.688455 -138.684839) (xy 433.733278 -138.690182) (xy 433.755292 -138.695176)
			(xy 433.769008 -138.697889) (xy 433.796927 -138.696765) (xy 433.823496 -138.688112) (xy 433.846722 -138.672579)
			(xy 433.864866 -138.651329) (xy 433.876567 -138.625955) (xy 433.880949 -138.598359) (xy 433.879752 -138.584432)
			(xy 433.878541 -138.573296) (xy 433.87727 -138.550929) (xy 433.877212 -138.539728) (xy 433.877625 -138.512473)
			(xy 433.885379 -138.458517) (xy 433.900732 -138.406214) (xy 433.923373 -138.356628) (xy 433.95284 -138.31077)
			(xy 433.988533 -138.269571) (xy 434.029727 -138.233872) (xy 434.075582 -138.204398) (xy 434.125164 -138.181751)
			(xy 434.177465 -138.16639) (xy 434.23142 -138.158629) (xy 434.28593 -138.158625) (xy 434.339885 -138.166379)
			(xy 434.392188 -138.181733) (xy 434.441774 -138.204374) (xy 434.487633 -138.233841) (xy 434.528831 -138.269535)
			(xy 434.56453 -138.310729) (xy 434.594003 -138.356584) (xy 434.61665 -138.406167) (xy 434.632011 -138.458468)
			(xy 434.639771 -138.512422) (xy 434.639775 -138.566932) (xy 434.63202 -138.620888) (xy 434.616666 -138.673191)
			(xy 434.594025 -138.722776) (xy 434.564557 -138.768635) (xy 434.528863 -138.809833) (xy 434.487669 -138.845531)
			(xy 434.441814 -138.875004) (xy 434.392231 -138.897651) (xy 434.33993 -138.913011) (xy 434.285975 -138.920772)
			(xy 434.25872 -138.921236) (xy 434.236149 -138.920903) (xy 434.191326 -138.915561) (xy 434.169312 -138.910568)
			(xy 434.155602 -138.90781) (xy 434.127674 -138.908933) (xy 434.101098 -138.91759) (xy 434.077866 -138.93313)
			(xy 434.059721 -138.95439) (xy 434.048023 -138.979775) (xy 434.043649 -139.007382) (xy 434.044852 -139.021312)
			(xy 434.046067 -139.032448) (xy 434.047335 -139.054814) (xy 434.047392 -139.066016) (xy 434.046905 -139.093266)
			(xy 434.039146 -139.14721) (xy 434.02379 -139.199501) (xy 434.001149 -139.249074) (xy 433.971683 -139.294921)
			(xy 433.935992 -139.336107) (xy 433.894804 -139.371796) (xy 433.848955 -139.401259) (xy 433.799381 -139.423898)
			(xy 433.747089 -139.439251) (xy 433.693144 -139.447006) (xy 433.638645 -139.447005) (xy 433.584701 -139.439249)
			(xy 433.532409 -139.423894) (xy 433.482835 -139.401254) (xy 433.436988 -139.371789) (xy 433.3958 -139.3361)
			(xy 433.360111 -139.294912) (xy 433.330646 -139.249065) (xy 433.308006 -139.199491) (xy 433.292651 -139.147199)
			(xy 433.284895 -139.093255) (xy 433.284894 -139.038756) (xy 424.288893 -139.038756) (xy 424.290161 -139.039413)
			(xy 424.35549 -139.082263) (xy 424.416095 -139.13157) (xy 424.471339 -139.186816) (xy 424.520645 -139.247421)
			(xy 424.563494 -139.312751) (xy 424.599438 -139.382121) (xy 424.6281 -139.454802) (xy 424.649178 -139.530033)
			(xy 424.662453 -139.607026) (xy 424.667785 -139.684972) (xy 424.665118 -139.763055) (xy 424.654479 -139.840456)
			(xy 424.635982 -139.916363) (xy 424.609818 -139.989981) (xy 424.576264 -140.060537) (xy 424.53567 -140.127292)
			(xy 424.488463 -140.189546) (xy 424.435137 -140.246645) (xy 424.376251 -140.297993) (xy 424.312423 -140.343049)
			(xy 424.244322 -140.381341) (xy 424.172662 -140.412469) (xy 424.098195 -140.436106) (xy 424.021701 -140.452003)
			(xy 423.943982 -140.459994) (xy 423.904918 -140.460476) (xy 423.886026 -140.460338) (xy 423.84829 -140.45843)
			(xy 423.82948 -140.456666) (xy 423.81563 -140.455784) (xy 423.788313 -140.460619) (xy 423.763307 -140.472629)
			(xy 423.742456 -140.490928) (xy 423.727302 -140.514164) (xy 423.718963 -140.540622) (xy 423.718053 -140.568348)
			(xy 423.724642 -140.595296) (xy 423.738242 -140.619475) (xy 423.747692 -140.62964) (xy 424.53306 -141.415008)
			(xy 425.667932 -141.415008) (xy 425.668387 -141.377325) (xy 425.675828 -141.302328) (xy 425.690628 -141.22843)
			(xy 425.712643 -141.156351) (xy 425.741658 -141.086795) (xy 425.777391 -141.020439) (xy 425.819493 -140.95793)
			(xy 425.867554 -140.899877) (xy 425.921105 -140.846847) (xy 425.979624 -140.799355) (xy 426.010832 -140.77823)
			(xy 426.023317 -140.76932) (xy 426.042725 -140.745588) (xy 426.054233 -140.717172) (xy 426.056808 -140.686623)
			(xy 426.050219 -140.656682) (xy 426.04309 -140.643102) (xy 426.023847 -140.608444) (xy 425.99184 -140.535915)
			(xy 425.967535 -140.460455) (xy 425.951195 -140.382879) (xy 425.942998 -140.304027) (xy 425.942506 -140.264388)
			(xy 425.942995 -140.225743) (xy 425.950815 -140.148849) (xy 425.966373 -140.073141) (xy 425.989511 -139.999395)
			(xy 426.019991 -139.928368) (xy 426.0575 -139.86079) (xy 426.101654 -139.797352) (xy 426.151999 -139.738708)
			(xy 426.208018 -139.685457) (xy 426.269137 -139.638147) (xy 426.33473 -139.597263) (xy 426.404121 -139.563225)
			(xy 426.476601 -139.536382) (xy 426.551424 -139.517009) (xy 426.627823 -139.505305) (xy 426.705014 -139.50139)
			(xy 426.782205 -139.505305) (xy 426.858604 -139.517009) (xy 426.933427 -139.536382) (xy 427.005907 -139.563225)
			(xy 427.029459 -139.574778) (xy 431.23942 -139.574778) (xy 431.243491 -139.519156) (xy 431.255617 -139.464719)
			(xy 431.27554 -139.412628) (xy 431.302836 -139.363993) (xy 431.336922 -139.31985) (xy 431.377071 -139.281141)
			(xy 431.422429 -139.24869) (xy 431.472029 -139.223189) (xy 431.524813 -139.205182) (xy 431.579656 -139.195052)
			(xy 431.63539 -139.193015) (xy 431.690827 -139.199115) (xy 431.744784 -139.213221) (xy 431.796113 -139.235033)
			(xy 431.843719 -139.264087) (xy 431.886587 -139.299762) (xy 431.923804 -139.341299) (xy 431.954577 -139.387812)
			(xy 431.978249 -139.438309) (xy 431.994317 -139.491716) (xy 432.002437 -139.546892) (xy 432.002946 -139.574778)
			(xy 432.002437 -139.602664) (xy 431.994317 -139.65784) (xy 431.978249 -139.711247) (xy 431.954577 -139.761744)
			(xy 431.923804 -139.808257) (xy 431.886587 -139.849794) (xy 431.843719 -139.885469) (xy 431.796113 -139.914523)
			(xy 431.744784 -139.936335) (xy 431.690827 -139.950441) (xy 431.63539 -139.956541) (xy 431.579656 -139.954504)
			(xy 431.524813 -139.944374) (xy 431.472029 -139.926367) (xy 431.422429 -139.900866) (xy 431.377071 -139.868415)
			(xy 431.336922 -139.829706) (xy 431.302836 -139.785563) (xy 431.27554 -139.736928) (xy 431.255617 -139.684837)
			(xy 431.243491 -139.6304) (xy 431.23942 -139.574778) (xy 427.029459 -139.574778) (xy 427.075298 -139.597263)
			(xy 427.140891 -139.638147) (xy 427.20201 -139.685457) (xy 427.258029 -139.738708) (xy 427.308374 -139.797352)
			(xy 427.352528 -139.86079) (xy 427.390037 -139.928368) (xy 427.420517 -139.999395) (xy 427.443655 -140.073141)
			(xy 427.459213 -140.148849) (xy 427.467033 -140.225743) (xy 427.467522 -140.264388) (xy 427.467085 -140.302071)
			(xy 427.459644 -140.37707) (xy 427.455759 -140.396468) (xy 431.995072 -140.396468) (xy 431.995666 -140.367256)
			(xy 432.004551 -140.309513) (xy 432.022138 -140.2538) (xy 432.048017 -140.201422) (xy 432.081582 -140.153603)
			(xy 432.122047 -140.111463) (xy 432.168466 -140.075988) (xy 432.219752 -140.048006) (xy 432.24704 -140.037566)
			(xy 432.260494 -140.032113) (xy 432.283929 -140.015014) (xy 432.301603 -139.99201) (xy 432.312085 -139.96496)
			(xy 432.31453 -139.936053) (xy 432.308737 -139.907627) (xy 432.302412 -139.894564) (xy 432.288477 -139.866933)
			(xy 432.268785 -139.808269) (xy 432.258812 -139.747197) (xy 432.258216 -139.716256) (xy 432.258702 -139.689005)
			(xy 432.266458 -139.635057) (xy 432.281813 -139.582762) (xy 432.304455 -139.533185) (xy 432.333921 -139.487335)
			(xy 432.369612 -139.446144) (xy 432.410803 -139.410453) (xy 432.456653 -139.380987) (xy 432.50623 -139.358345)
			(xy 432.558525 -139.34299) (xy 432.612473 -139.335234) (xy 432.666975 -139.335234) (xy 432.720923 -139.34299)
			(xy 432.773218 -139.358345) (xy 432.822795 -139.380987) (xy 432.868645 -139.410453) (xy 432.909836 -139.446144)
			(xy 432.945527 -139.487335) (xy 432.974993 -139.533185) (xy 432.997635 -139.582762) (xy 433.01299 -139.635057)
			(xy 433.020746 -139.689005) (xy 433.021232 -139.716256) (xy 433.020656 -139.745468) (xy 433.011768 -139.803212)
			(xy 432.994177 -139.858925) (xy 432.968295 -139.911303) (xy 432.934728 -139.959122) (xy 432.894261 -140.001262)
			(xy 432.84784 -140.036737) (xy 432.796552 -140.064718) (xy 432.769264 -140.075158) (xy 432.755797 -140.080583)
			(xy 432.732359 -140.097686) (xy 432.714685 -140.120697) (xy 432.704204 -140.147753) (xy 432.701764 -140.176666)
			(xy 432.707563 -140.205096) (xy 432.713892 -140.21816) (xy 432.7278 -140.245804) (xy 432.747502 -140.304462)
			(xy 432.757486 -140.365529) (xy 432.758088 -140.396468) (xy 432.757602 -140.423719) (xy 432.749846 -140.477667)
			(xy 432.734491 -140.529962) (xy 432.711849 -140.579539) (xy 432.682383 -140.625389) (xy 432.646692 -140.66658)
			(xy 432.605501 -140.702271) (xy 432.559651 -140.731737) (xy 432.510074 -140.754379) (xy 432.457779 -140.769734)
			(xy 432.403831 -140.77749) (xy 432.349329 -140.77749) (xy 432.295381 -140.769734) (xy 432.243086 -140.754379)
			(xy 432.193509 -140.731737) (xy 432.147659 -140.702271) (xy 432.106468 -140.66658) (xy 432.070777 -140.625389)
			(xy 432.041311 -140.579539) (xy 432.018669 -140.529962) (xy 432.003314 -140.477667) (xy 431.995558 -140.423719)
			(xy 431.995072 -140.396468) (xy 427.455759 -140.396468) (xy 427.444843 -140.450969) (xy 427.422827 -140.523048)
			(xy 427.39381 -140.592605) (xy 427.358075 -140.658962) (xy 427.315971 -140.72147) (xy 427.267907 -140.779523)
			(xy 427.214353 -140.832552) (xy 427.155831 -140.880042) (xy 427.124622 -140.901166) (xy 427.112146 -140.91009)
			(xy 427.092731 -140.933815) (xy 427.081217 -140.962227) (xy 427.078641 -140.992776) (xy 427.085233 -141.022715)
			(xy 427.092364 -141.036294) (xy 427.111601 -141.070955) (xy 427.14361 -141.143483) (xy 427.151792 -141.168882)
			(xy 431.19116 -141.168882) (xy 431.195231 -141.11326) (xy 431.207357 -141.058823) (xy 431.22728 -141.006732)
			(xy 431.254576 -140.958097) (xy 431.288662 -140.913954) (xy 431.328811 -140.875245) (xy 431.374169 -140.842794)
			(xy 431.423769 -140.817293) (xy 431.476553 -140.799286) (xy 431.531396 -140.789156) (xy 431.58713 -140.787119)
			(xy 431.642567 -140.793219) (xy 431.696524 -140.807325) (xy 431.747853 -140.829137) (xy 431.795459 -140.858191)
			(xy 431.838327 -140.893866) (xy 431.875544 -140.935403) (xy 431.906317 -140.981916) (xy 431.929989 -141.032413)
			(xy 431.946057 -141.08582) (xy 431.954177 -141.140996) (xy 431.954686 -141.168882) (xy 431.954177 -141.196768)
			(xy 431.946057 -141.251944) (xy 431.929989 -141.305351) (xy 431.906317 -141.355848) (xy 431.875544 -141.402361)
			(xy 431.838327 -141.443898) (xy 431.795459 -141.479573) (xy 431.747853 -141.508627) (xy 431.696524 -141.530439)
			(xy 431.642567 -141.544545) (xy 431.58713 -141.550645) (xy 431.531396 -141.548608) (xy 431.476553 -141.538478)
			(xy 431.423769 -141.520471) (xy 431.374169 -141.49497) (xy 431.328811 -141.462519) (xy 431.288662 -141.42381)
			(xy 431.254576 -141.379667) (xy 431.22728 -141.331032) (xy 431.207357 -141.278941) (xy 431.195231 -141.224504)
			(xy 431.19116 -141.168882) (xy 427.151792 -141.168882) (xy 427.167917 -141.218942) (xy 427.184257 -141.296517)
			(xy 427.192456 -141.375369) (xy 427.192948 -141.415008) (xy 427.192459 -141.453653) (xy 427.184639 -141.530547)
			(xy 427.169081 -141.606255) (xy 427.145943 -141.680001) (xy 427.115463 -141.751028) (xy 427.077954 -141.818606)
			(xy 427.0338 -141.882044) (xy 426.983455 -141.940688) (xy 426.927436 -141.993939) (xy 426.866317 -142.041249)
			(xy 426.800724 -142.082133) (xy 426.731333 -142.116171) (xy 426.658853 -142.143014) (xy 426.58403 -142.162387)
			(xy 426.507631 -142.174091) (xy 426.43044 -142.178006) (xy 426.353249 -142.174091) (xy 426.27685 -142.162387)
			(xy 426.202027 -142.143014) (xy 426.129547 -142.116171) (xy 426.060156 -142.082133) (xy 425.994563 -142.041249)
			(xy 425.933444 -141.993939) (xy 425.877425 -141.940688) (xy 425.82708 -141.882044) (xy 425.782926 -141.818606)
			(xy 425.745417 -141.751028) (xy 425.714937 -141.680001) (xy 425.691799 -141.606255) (xy 425.676241 -141.530547)
			(xy 425.668421 -141.453653) (xy 425.667932 -141.415008) (xy 424.53306 -141.415008) (xy 427.022768 -143.904716)
			(xy 427.032869 -143.914175) (xy 427.056956 -143.927779) (xy 427.083812 -143.934409) (xy 427.111461 -143.933577)
			(xy 427.137871 -143.925346) (xy 427.161096 -143.91032) (xy 427.179429 -143.889605) (xy 427.19152 -143.864725)
			(xy 427.196481 -143.837512) (xy 427.195742 -143.82369) (xy 427.194218 -143.788892) (xy 427.194663 -143.762512)
			(xy 427.201927 -143.710256) (xy 427.216315 -143.659496) (xy 427.237554 -143.611201) (xy 427.265239 -143.566289)
			(xy 427.298842 -143.525616) (xy 427.337725 -143.489956) (xy 427.381147 -143.459987) (xy 427.40453 -143.44777)
			(xy 427.416891 -143.441071) (xy 427.437625 -143.422099) (xy 427.45239 -143.398185) (xy 427.460063 -143.371149)
			(xy 427.460062 -143.343044) (xy 427.452387 -143.316008) (xy 427.43762 -143.292096) (xy 427.416885 -143.273125)
			(xy 427.40453 -143.266414) (xy 427.38116 -143.254171) (xy 427.337732 -143.224215) (xy 427.298844 -143.188562)
			(xy 427.265238 -143.147893) (xy 427.237553 -143.102983) (xy 427.216319 -143.054688) (xy 427.201938 -143.003928)
			(xy 427.194686 -142.951671) (xy 427.194218 -142.925292) (xy 427.194704 -142.898041) (xy 427.20246 -142.844093)
			(xy 427.217815 -142.791798) (xy 427.240457 -142.742221) (xy 427.269923 -142.696371) (xy 427.305614 -142.65518)
			(xy 427.346805 -142.619489) (xy 427.392655 -142.590023) (xy 427.442232 -142.567381) (xy 427.494527 -142.552026)
			(xy 427.548475 -142.54427) (xy 427.602977 -142.54427) (xy 427.656925 -142.552026) (xy 427.70922 -142.567381)
			(xy 427.758797 -142.590023) (xy 427.804647 -142.619489) (xy 427.845838 -142.65518) (xy 427.881529 -142.696371)
			(xy 427.910995 -142.742221) (xy 427.933637 -142.791798) (xy 427.948992 -142.844093) (xy 427.956748 -142.898041)
			(xy 427.957234 -142.925292) (xy 427.956789 -142.951671) (xy 427.949527 -143.003928) (xy 427.935139 -143.054687)
			(xy 427.9139 -143.102982) (xy 427.886214 -143.147893) (xy 427.852609 -143.188565) (xy 427.813724 -143.224223)
			(xy 427.770301 -143.254188) (xy 427.746922 -143.266414) (xy 427.734563 -143.273117) (xy 427.713835 -143.292094)
			(xy 427.699074 -143.316009) (xy 427.691401 -143.343045) (xy 427.6914 -143.371148) (xy 427.699071 -143.398185)
			(xy 427.71383 -143.422101) (xy 427.734558 -143.441079) (xy 427.746922 -143.44777) (xy 427.77029 -143.460015)
			(xy 427.813714 -143.489974) (xy 427.852598 -143.525628) (xy 427.886201 -143.566297) (xy 427.913884 -143.611207)
			(xy 427.935117 -143.659501) (xy 427.949498 -143.710259) (xy 427.956751 -143.762514) (xy 427.957234 -143.788892)
			(xy 427.956749 -143.816144) (xy 427.948993 -143.870094) (xy 427.933639 -143.922391) (xy 427.910999 -143.971971)
			(xy 427.881533 -144.017825) (xy 427.845842 -144.059018) (xy 427.804652 -144.094713) (xy 427.758801 -144.124183)
			(xy 427.709223 -144.146827) (xy 427.656928 -144.162186) (xy 427.602978 -144.169946) (xy 427.575726 -144.1704)
			(xy 427.540928 -144.168876) (xy 427.527124 -144.168108) (xy 427.499948 -144.173125) (xy 427.475113 -144.185245)
			(xy 427.454437 -144.203582) (xy 427.439437 -144.226791) (xy 427.431209 -144.253174) (xy 427.430358 -144.280796)
			(xy 427.436946 -144.307634) (xy 427.450489 -144.331723) (xy 427.459902 -144.34185) (xy 427.823122 -144.70507)
			(xy 435.98668 -144.70507) (xy 435.990751 -144.649448) (xy 436.002877 -144.595011) (xy 436.0228 -144.54292)
			(xy 436.050096 -144.494285) (xy 436.084182 -144.450142) (xy 436.124331 -144.411433) (xy 436.169689 -144.378982)
			(xy 436.219289 -144.353481) (xy 436.272073 -144.335474) (xy 436.326916 -144.325344) (xy 436.38265 -144.323307)
			(xy 436.438087 -144.329407) (xy 436.492044 -144.343513) (xy 436.543373 -144.365325) (xy 436.590979 -144.394379)
			(xy 436.633847 -144.430054) (xy 436.671064 -144.471591) (xy 436.701837 -144.518104) (xy 436.725509 -144.568601)
			(xy 436.741577 -144.622008) (xy 436.749697 -144.677184) (xy 436.750206 -144.70507) (xy 436.749697 -144.732956)
			(xy 436.741577 -144.788132) (xy 436.725509 -144.841539) (xy 436.701837 -144.892036) (xy 436.671064 -144.938549)
			(xy 436.633847 -144.980086) (xy 436.590979 -145.015761) (xy 436.543373 -145.044815) (xy 436.492044 -145.066627)
			(xy 436.438087 -145.080733) (xy 436.38265 -145.086833) (xy 436.326916 -145.084796) (xy 436.272073 -145.074666)
			(xy 436.219289 -145.056659) (xy 436.169689 -145.031158) (xy 436.124331 -144.998707) (xy 436.084182 -144.959998)
			(xy 436.050096 -144.915855) (xy 436.0228 -144.86722) (xy 436.002877 -144.815129) (xy 435.990751 -144.760692)
			(xy 435.98668 -144.70507) (xy 427.823122 -144.70507) (xy 430.86782 -147.749768) (xy 430.86782 -153.774902)
			(xy 436.385725 -153.774902) (xy 436.389718 -153.565161) (xy 436.401694 -153.355724) (xy 436.421635 -153.146895)
			(xy 436.449512 -152.938976) (xy 436.485284 -152.732269) (xy 436.528899 -152.527074) (xy 436.580295 -152.323689)
			(xy 436.639397 -152.122407) (xy 436.706119 -151.923521) (xy 436.780364 -151.72732) (xy 436.862024 -151.534088)
			(xy 436.950982 -151.344104) (xy 437.047109 -151.157645) (xy 437.150264 -150.974981) (xy 437.260299 -150.796376)
			(xy 437.377053 -150.62209) (xy 437.500358 -150.452375) (xy 437.630035 -150.287477) (xy 437.765896 -150.127636)
			(xy 437.907743 -149.973083) (xy 438.055372 -149.824043) (xy 438.208567 -149.68073) (xy 438.367108 -149.543354)
			(xy 438.530763 -149.412113) (xy 438.699297 -149.287198) (xy 438.872463 -149.16879) (xy 439.050013 -149.05706)
			(xy 439.231687 -148.95217) (xy 439.417222 -148.854273) (xy 439.60635 -148.763511) (xy 439.798797 -148.680014)
			(xy 439.994282 -148.603904) (xy 440.192524 -148.535292) (xy 440.393234 -148.474277) (xy 440.596121 -148.420948)
			(xy 440.800891 -148.375381) (xy 441.007248 -148.337642) (xy 441.214892 -148.307788) (xy 441.423522 -148.28586)
			(xy 441.632835 -148.271891) (xy 441.842529 -148.2659) (xy 442.052298 -148.267897) (xy 442.26184 -148.277879)
			(xy 442.47085 -148.295831) (xy 442.679024 -148.321727) (xy 442.886062 -148.355529) (xy 443.091663 -148.397189)
			(xy 443.295529 -148.446647) (xy 443.497364 -148.50383) (xy 443.696876 -148.568655) (xy 443.893775 -148.641029)
			(xy 444.087776 -148.720846) (xy 444.278598 -148.807992) (xy 444.465964 -148.902339) (xy 444.649602 -149.00375)
			(xy 444.829246 -149.11208) (xy 445.004636 -149.22717) (xy 445.175517 -149.348854) (xy 445.341641 -149.476955)
			(xy 445.502768 -149.611288) (xy 445.658665 -149.751657) (xy 445.809104 -149.89786) (xy 445.953868 -150.049684)
			(xy 446.092747 -150.20691) (xy 446.22554 -150.369309) (xy 446.352054 -150.536645) (xy 446.393794 -150.596457)
			(xy 450.763523 -150.596457) (xy 450.763523 -150.541943) (xy 450.771282 -150.487984) (xy 450.786641 -150.435679)
			(xy 450.809288 -150.386092) (xy 450.838763 -150.340233) (xy 450.874464 -150.299035) (xy 450.915665 -150.263339)
			(xy 450.961527 -150.233869) (xy 451.011116 -150.211227) (xy 451.063423 -150.195873) (xy 451.117383 -150.18812)
			(xy 451.14464 -150.18766) (xy 451.157894 -150.187804) (xy 451.184334 -150.189711) (xy 451.197472 -150.19147)
			(xy 451.210812 -150.192969) (xy 451.237441 -150.189644) (xy 451.262282 -150.179486) (xy 451.283611 -150.163199)
			(xy 451.299953 -150.141912) (xy 451.310176 -150.117099) (xy 451.31228 -150.10384) (xy 451.316264 -150.076592)
			(xy 451.331102 -150.023562) (xy 451.353407 -149.973214) (xy 451.382716 -149.926594) (xy 451.41842 -149.88467)
			(xy 451.459777 -149.848311) (xy 451.505931 -149.818273) (xy 451.555921 -149.795179) (xy 451.608712 -149.779509)
			(xy 451.663206 -149.771587) (xy 451.69074 -149.7711) (xy 451.71799 -149.771573) (xy 451.771934 -149.779334)
			(xy 451.824226 -149.794693) (xy 451.873799 -149.817337) (xy 451.919645 -149.846805) (xy 451.960831 -149.882497)
			(xy 451.996519 -149.923687) (xy 452.025983 -149.969536) (xy 452.048621 -150.019112) (xy 452.063975 -150.071405)
			(xy 452.07173 -150.12535) (xy 452.07173 -150.17985) (xy 452.063975 -150.233795) (xy 452.048621 -150.286088)
			(xy 452.025983 -150.335664) (xy 451.996519 -150.381513) (xy 451.960831 -150.422703) (xy 451.919645 -150.458395)
			(xy 451.873799 -150.487863) (xy 451.824226 -150.510507) (xy 451.771934 -150.525866) (xy 451.71799 -150.533627)
			(xy 451.69074 -150.534116) (xy 451.677486 -150.533973) (xy 451.651046 -150.532065) (xy 451.637908 -150.530306)
			(xy 451.624569 -150.528808) (xy 451.597941 -150.532137) (xy 451.573103 -150.542296) (xy 451.554543 -150.556468)
			(xy 452.174862 -150.556468) (xy 452.178933 -150.500846) (xy 452.191059 -150.446409) (xy 452.210982 -150.394318)
			(xy 452.238278 -150.345683) (xy 452.272364 -150.30154) (xy 452.312513 -150.262831) (xy 452.357871 -150.23038)
			(xy 452.407471 -150.204879) (xy 452.460255 -150.186872) (xy 452.515098 -150.176742) (xy 452.570832 -150.174705)
			(xy 452.626269 -150.180805) (xy 452.680226 -150.194911) (xy 452.731555 -150.216723) (xy 452.779161 -150.245777)
			(xy 452.822029 -150.281452) (xy 452.859246 -150.322989) (xy 452.890019 -150.369502) (xy 452.913691 -150.419999)
			(xy 452.929759 -150.473406) (xy 452.937879 -150.528582) (xy 452.938388 -150.556468) (xy 452.937879 -150.584354)
			(xy 452.929759 -150.63953) (xy 452.913691 -150.692937) (xy 452.890019 -150.743434) (xy 452.859246 -150.789947)
			(xy 452.822029 -150.831484) (xy 452.779161 -150.867159) (xy 452.731555 -150.896213) (xy 452.680226 -150.918025)
			(xy 452.626269 -150.932131) (xy 452.570832 -150.938231) (xy 452.515098 -150.936194) (xy 452.460255 -150.926064)
			(xy 452.407471 -150.908057) (xy 452.357871 -150.882556) (xy 452.312513 -150.850105) (xy 452.272364 -150.811396)
			(xy 452.238278 -150.767253) (xy 452.210982 -150.718618) (xy 452.191059 -150.666527) (xy 452.178933 -150.61209)
			(xy 452.174862 -150.556468) (xy 451.554543 -150.556468) (xy 451.551775 -150.558582) (xy 451.535432 -150.579868)
			(xy 451.525206 -150.604678) (xy 451.5231 -150.617936) (xy 451.519116 -150.645184) (xy 451.50428 -150.698216)
			(xy 451.481977 -150.748565) (xy 451.452669 -150.795186) (xy 451.416965 -150.837111) (xy 451.375607 -150.873471)
			(xy 451.329453 -150.903508) (xy 451.279461 -150.926602) (xy 451.226669 -150.942271) (xy 451.172174 -150.950191)
			(xy 451.14464 -150.950676) (xy 451.117383 -150.95028) (xy 451.063423 -150.942527) (xy 451.011116 -150.927173)
			(xy 450.961527 -150.904531) (xy 450.915665 -150.875061) (xy 450.874464 -150.839365) (xy 450.838763 -150.798167)
			(xy 450.809288 -150.752309) (xy 450.786641 -150.702721) (xy 450.771282 -150.650416) (xy 450.763523 -150.596457)
			(xy 446.393794 -150.596457) (xy 446.472106 -150.708677) (xy 446.585521 -150.885154) (xy 446.692135 -151.065822)
			(xy 446.791794 -151.250417) (xy 446.884353 -151.438672) (xy 446.969678 -151.630315) (xy 447.047645 -151.825067)
			(xy 447.118141 -152.022647) (xy 447.181064 -152.222766) (xy 447.236323 -152.425137) (xy 447.283837 -152.629464)
			(xy 447.323538 -152.835452) (xy 447.355368 -153.042803) (xy 447.379281 -153.251214) (xy 447.395242 -153.460385)
			(xy 447.403229 -153.670012) (xy 447.403728 -153.774902) (xy 447.403229 -153.879792) (xy 447.395242 -154.089419)
			(xy 447.379281 -154.29859) (xy 447.355368 -154.507001) (xy 447.323538 -154.714352) (xy 447.283837 -154.92034)
			(xy 447.236323 -155.124667) (xy 447.181064 -155.327038) (xy 447.118141 -155.527157) (xy 447.047645 -155.724737)
			(xy 446.969678 -155.919489) (xy 446.884353 -156.111132) (xy 446.791794 -156.299387) (xy 446.692135 -156.483982)
			(xy 446.585521 -156.66465) (xy 446.472106 -156.841127) (xy 446.352054 -157.013159) (xy 446.22554 -157.180495)
			(xy 446.092747 -157.342894) (xy 445.953868 -157.50012) (xy 445.809104 -157.651944) (xy 445.658665 -157.798147)
			(xy 445.502768 -157.938516) (xy 445.341641 -158.072849) (xy 445.175517 -158.20095) (xy 445.004636 -158.322634)
			(xy 444.829246 -158.437724) (xy 444.649602 -158.546054) (xy 444.465964 -158.647465) (xy 444.278598 -158.741812)
			(xy 444.087776 -158.828958) (xy 443.893775 -158.908775) (xy 443.696876 -158.981149) (xy 443.497364 -159.045974)
			(xy 443.295529 -159.103157) (xy 443.091663 -159.152615) (xy 442.886062 -159.194275) (xy 442.679024 -159.228077)
			(xy 442.47085 -159.253973) (xy 442.26184 -159.271925) (xy 442.052298 -159.281907) (xy 441.842529 -159.283904)
			(xy 441.632835 -159.277913) (xy 441.423522 -159.263944) (xy 441.214892 -159.242016) (xy 441.007248 -159.212162)
			(xy 440.800891 -159.174423) (xy 440.596121 -159.128856) (xy 440.393234 -159.075527) (xy 440.192524 -159.014512)
			(xy 439.994282 -158.9459) (xy 439.798797 -158.86979) (xy 439.60635 -158.786293) (xy 439.417222 -158.695531)
			(xy 439.231687 -158.597634) (xy 439.050013 -158.492744) (xy 438.872463 -158.381014) (xy 438.699297 -158.262606)
			(xy 438.530763 -158.137691) (xy 438.367108 -158.00645) (xy 438.208567 -157.869074) (xy 438.055372 -157.725761)
			(xy 437.907743 -157.576721) (xy 437.765896 -157.422168) (xy 437.630035 -157.262327) (xy 437.500358 -157.097429)
			(xy 437.377053 -156.927714) (xy 437.260299 -156.753428) (xy 437.150264 -156.574823) (xy 437.047109 -156.392159)
			(xy 436.950982 -156.2057) (xy 436.862024 -156.015716) (xy 436.780364 -155.822484) (xy 436.706119 -155.626283)
			(xy 436.639397 -155.427397) (xy 436.580295 -155.226115) (xy 436.528899 -155.02273) (xy 436.485284 -154.817535)
			(xy 436.449512 -154.610828) (xy 436.421635 -154.402909) (xy 436.401694 -154.19408) (xy 436.389718 -153.984643)
			(xy 436.385725 -153.774902) (xy 430.86782 -153.774902) (xy 430.86782 -166.4208) (xy 430.96942 -166.4208)
			(xy 430.969965 -166.392062) (xy 430.978586 -166.335237) (xy 430.995632 -166.280347) (xy 431.020718 -166.228635)
			(xy 431.053277 -166.181271) (xy 431.072544 -166.159942) (xy 431.082618 -166.148409) (xy 431.095963 -166.120863)
			(xy 431.100549 -166.0906) (xy 431.095963 -166.060337) (xy 431.082618 -166.032791) (xy 431.072544 -166.021258)
			(xy 431.053272 -165.999932) (xy 431.020705 -165.95257) (xy 430.995612 -165.900858) (xy 430.978561 -165.845967)
			(xy 430.969938 -165.789139) (xy 430.969938 -165.731661) (xy 430.978561 -165.674833) (xy 430.995612 -165.619942)
			(xy 431.020705 -165.56823) (xy 431.053272 -165.520868) (xy 431.072544 -165.499542) (xy 431.082618 -165.488009)
			(xy 431.095963 -165.460463) (xy 431.100549 -165.4302) (xy 431.095963 -165.399937) (xy 431.082618 -165.372391)
			(xy 431.072544 -165.360858) (xy 431.053272 -165.339532) (xy 431.020705 -165.29217) (xy 430.995612 -165.240458)
			(xy 430.978561 -165.185567) (xy 430.969938 -165.128739) (xy 430.969938 -165.071261) (xy 430.978561 -165.014433)
			(xy 430.995612 -164.959542) (xy 431.020705 -164.90783) (xy 431.053272 -164.860468) (xy 431.072544 -164.839142)
			(xy 431.082618 -164.827609) (xy 431.095963 -164.800063) (xy 431.100549 -164.7698) (xy 431.095963 -164.739537)
			(xy 431.082618 -164.711991) (xy 431.072544 -164.700458) (xy 431.053272 -164.679132) (xy 431.020705 -164.63177)
			(xy 430.995612 -164.580058) (xy 430.978561 -164.525167) (xy 430.969938 -164.468339) (xy 430.969938 -164.410861)
			(xy 430.978561 -164.354033) (xy 430.995612 -164.299142) (xy 431.020705 -164.24743) (xy 431.053272 -164.200068)
			(xy 431.072544 -164.178742) (xy 431.082618 -164.167209) (xy 431.095963 -164.139663) (xy 431.100549 -164.1094)
			(xy 431.095963 -164.079137) (xy 431.082618 -164.051591) (xy 431.072544 -164.040058) (xy 431.053274 -164.01873)
			(xy 431.020708 -163.971368) (xy 430.995615 -163.919657) (xy 430.978564 -163.864766) (xy 430.969941 -163.807939)
			(xy 430.96942 -163.7792) (xy 430.96983 -163.753378) (xy 430.976782 -163.702204) (xy 430.990572 -163.652435)
			(xy 431.010949 -163.604981) (xy 431.037539 -163.560709) (xy 431.069858 -163.520427) (xy 431.088292 -163.50234)
			(xy 431.09798 -163.492559) (xy 431.112152 -163.468967) (xy 431.119503 -163.442447) (xy 431.1195 -163.414926)
			(xy 431.112141 -163.388407) (xy 431.097962 -163.36482) (xy 431.088292 -163.35502) (xy 431.069869 -163.336925)
			(xy 431.037565 -163.296636) (xy 431.010985 -163.252362) (xy 430.990611 -163.204911) (xy 430.976815 -163.155148)
			(xy 430.96985 -163.10398) (xy 430.96942 -163.07816) (xy 430.969941 -163.049421) (xy 430.978567 -162.992595)
			(xy 430.995619 -162.937705) (xy 431.020711 -162.885993) (xy 431.053274 -162.83863) (xy 431.072544 -162.817302)
			(xy 431.082657 -162.8058) (xy 431.095999 -162.778243) (xy 431.100577 -162.747971) (xy 431.095981 -162.717701)
			(xy 431.082624 -162.690151) (xy 431.072544 -162.678618) (xy 431.053255 -162.657306) (xy 431.020691 -162.60994)
			(xy 430.995602 -162.558225) (xy 430.978556 -162.503331) (xy 430.969938 -162.4465) (xy 430.96942 -162.41776)
			(xy 430.969841 -162.390506) (xy 430.977603 -162.336555) (xy 430.992965 -162.284257) (xy 431.015613 -162.234678)
			(xy 431.045086 -162.188827) (xy 431.080784 -162.147636) (xy 431.121981 -162.111945) (xy 431.167838 -162.08248)
			(xy 431.217421 -162.059841) (xy 431.269722 -162.044489) (xy 431.323674 -162.036736) (xy 431.350928 -162.036252)
			(xy 431.379073 -162.036771) (xy 431.434754 -162.04504) (xy 431.488617 -162.061394) (xy 431.539495 -162.085478)
			(xy 431.586286 -162.116772) (xy 431.607468 -162.135312) (xy 431.619251 -162.145371) (xy 431.647348 -162.158396)
			(xy 431.678057 -162.16241) (xy 431.708558 -162.157044) (xy 431.736054 -162.142792) (xy 431.747422 -162.132264)
			(xy 431.76902 -162.111621) (xy 431.817422 -162.076604) (xy 431.870692 -162.049563) (xy 431.927528 -162.031161)
			(xy 431.986538 -162.021846) (xy 432.016408 -162.021266) (xy 432.045147 -162.021794) (xy 432.101973 -162.030417)
			(xy 432.156864 -162.047466) (xy 432.208576 -162.072557) (xy 432.255939 -162.10512) (xy 432.277266 -162.12439)
			(xy 432.2888 -162.134462) (xy 432.316346 -162.147804) (xy 432.346608 -162.152389) (xy 432.37687 -162.147804)
			(xy 432.404416 -162.134462) (xy 432.41595 -162.12439) (xy 432.437282 -162.105124) (xy 432.484642 -162.072556)
			(xy 432.536352 -162.047461) (xy 432.591242 -162.03041) (xy 432.648069 -162.021787) (xy 432.676808 -162.021266)
			(xy 432.704058 -162.02177) (xy 432.758004 -162.029527) (xy 432.810297 -162.044882) (xy 432.859872 -162.067522)
			(xy 432.905721 -162.096987) (xy 432.946911 -162.132676) (xy 432.982602 -162.173864) (xy 433.012069 -162.219712)
			(xy 433.034712 -162.269286) (xy 433.050069 -162.321578) (xy 433.057828 -162.375524) (xy 433.058316 -162.402774)
			(xy 433.057772 -162.431512) (xy 433.049154 -162.488338) (xy 433.032108 -162.543229) (xy 433.007021 -162.594941)
			(xy 432.974461 -162.642304) (xy 432.955192 -162.663632) (xy 432.945149 -162.675188) (xy 432.931809 -162.702727)
			(xy 432.927221 -162.732981) (xy 432.931798 -162.763237) (xy 432.945127 -162.790781) (xy 432.955192 -162.802316)
			(xy 432.974455 -162.823649) (xy 433.007022 -162.87101) (xy 433.032115 -162.92272) (xy 433.049167 -162.977609)
			(xy 433.057793 -163.034436) (xy 433.058316 -163.063174) (xy 433.057878 -163.088995) (xy 433.05093 -163.140167)
			(xy 433.037145 -163.189935) (xy 433.016773 -163.237389) (xy 432.990188 -163.281662) (xy 432.957875 -163.321945)
			(xy 432.939444 -163.340034) (xy 432.92978 -163.349838) (xy 432.915601 -163.373422) (xy 432.908243 -163.399937)
			(xy 432.908242 -163.427455) (xy 432.915598 -163.453971) (xy 432.929774 -163.477556) (xy 432.939444 -163.487354)
			(xy 432.957891 -163.505427) (xy 432.990194 -163.545719) (xy 433.016773 -163.589997) (xy 433.037143 -163.637453)
			(xy 433.050933 -163.68722) (xy 433.05789 -163.738393) (xy 433.058316 -163.764214) (xy 433.057796 -163.792953)
			(xy 433.049172 -163.84978) (xy 433.032121 -163.904671) (xy 433.007029 -163.956383) (xy 432.974463 -164.003745)
			(xy 432.955192 -164.025072) (xy 432.94511 -164.036597) (xy 432.931774 -164.064147) (xy 432.927194 -164.09441)
			(xy 432.93178 -164.124673) (xy 432.945121 -164.15222) (xy 432.955192 -164.163756) (xy 432.974476 -164.185071)
			(xy 433.007039 -164.232436) (xy 433.032129 -164.28415) (xy 433.049177 -164.339042) (xy 433.057798 -164.395871)
			(xy 433.057797 -164.45335) (xy 433.049173 -164.510178) (xy 433.032122 -164.565069) (xy 433.007029 -164.616782)
			(xy 432.974463 -164.664145) (xy 432.955192 -164.685472) (xy 432.94511 -164.696997) (xy 432.931774 -164.724547)
			(xy 432.927194 -164.75481) (xy 432.93178 -164.785073) (xy 432.945121 -164.81262) (xy 432.955192 -164.824156)
			(xy 432.974476 -164.845471) (xy 433.007039 -164.892836) (xy 433.032129 -164.94455) (xy 433.049177 -164.999442)
			(xy 433.057798 -165.056271) (xy 433.057797 -165.11375) (xy 433.049173 -165.170578) (xy 433.032122 -165.225469)
			(xy 433.007029 -165.277182) (xy 432.974463 -165.324545) (xy 432.955192 -165.345872) (xy 432.94511 -165.357397)
			(xy 432.931774 -165.384947) (xy 432.927194 -165.41521) (xy 432.93178 -165.445473) (xy 432.945121 -165.47302)
			(xy 432.955192 -165.484556) (xy 432.974474 -165.505873) (xy 433.007038 -165.553238) (xy 433.032128 -165.604952)
			(xy 433.049176 -165.659845) (xy 433.057796 -165.716674) (xy 433.058316 -165.745414) (xy 433.057835 -165.772665)
			(xy 433.050077 -165.826613) (xy 433.034721 -165.878907) (xy 433.012078 -165.928484) (xy 432.982611 -165.974334)
			(xy 432.946919 -166.015524) (xy 432.905729 -166.051215) (xy 432.859879 -166.080681) (xy 432.810301 -166.103323)
			(xy 432.758007 -166.118678) (xy 432.704059 -166.126436) (xy 432.676808 -166.126922) (xy 432.649163 -166.126403)
			(xy 432.594453 -166.118406) (xy 432.541471 -166.102593) (xy 432.491328 -166.079296) (xy 432.445074 -166.049002)
			(xy 432.40368 -166.012347) (xy 432.38547 -165.99154) (xy 432.377861 -165.983437) (xy 432.35771 -165.974116)
			(xy 432.335506 -165.974116) (xy 432.315355 -165.983437) (xy 432.307746 -165.99154) (xy 432.294792 -166.006272)
			(xy 432.28471 -166.017797) (xy 432.271374 -166.045347) (xy 432.266794 -166.07561) (xy 432.27138 -166.105873)
			(xy 432.284721 -166.13342) (xy 432.294792 -166.144956) (xy 432.314074 -166.166273) (xy 432.346638 -166.213638)
			(xy 432.371728 -166.265352) (xy 432.388776 -166.320245) (xy 432.397396 -166.377074) (xy 432.397916 -166.405814)
			(xy 433.71084 -166.405814) (xy 433.714911 -166.350192) (xy 433.727037 -166.295755) (xy 433.74696 -166.243664)
			(xy 433.774256 -166.195029) (xy 433.808342 -166.150886) (xy 433.848491 -166.112177) (xy 433.893849 -166.079726)
			(xy 433.943449 -166.054225) (xy 433.996233 -166.036218) (xy 434.051076 -166.026088) (xy 434.10681 -166.024051)
			(xy 434.162247 -166.030151) (xy 434.216204 -166.044257) (xy 434.267533 -166.066069) (xy 434.315139 -166.095123)
			(xy 434.358007 -166.130798) (xy 434.395224 -166.172335) (xy 434.425997 -166.218848) (xy 434.449669 -166.269345)
			(xy 434.465737 -166.322752) (xy 434.473857 -166.377928) (xy 434.474366 -166.405814) (xy 434.473857 -166.4337)
			(xy 434.465737 -166.488876) (xy 434.449669 -166.542283) (xy 434.425997 -166.59278) (xy 434.395224 -166.639293)
			(xy 434.358007 -166.68083) (xy 434.315139 -166.716505) (xy 434.267533 -166.745559) (xy 434.216204 -166.767371)
			(xy 434.162247 -166.781477) (xy 434.10681 -166.787577) (xy 434.051076 -166.78554) (xy 433.996233 -166.77541)
			(xy 433.943449 -166.757403) (xy 433.893849 -166.731902) (xy 433.848491 -166.699451) (xy 433.808342 -166.660742)
			(xy 433.774256 -166.616599) (xy 433.74696 -166.567964) (xy 433.727037 -166.515873) (xy 433.714911 -166.461436)
			(xy 433.71084 -166.405814) (xy 432.397916 -166.405814) (xy 432.397371 -166.4341) (xy 432.389016 -166.490053)
			(xy 432.372492 -166.544159) (xy 432.34816 -166.595232) (xy 432.316555 -166.642153) (xy 432.29784 -166.66337)
			(xy 432.28775 -166.675307) (xy 432.274637 -166.703659) (xy 432.270696 -166.734646) (xy 432.276295 -166.765378)
			(xy 432.290912 -166.792984) (xy 432.30165 -166.80434) (xy 432.322827 -166.826023) (xy 432.358792 -166.874803)
			(xy 432.386591 -166.928657) (xy 432.405522 -166.98623) (xy 432.415111 -167.046071) (xy 432.415696 -167.076374)
			(xy 432.41522 -167.103627) (xy 432.407467 -167.157578) (xy 432.392113 -167.209876) (xy 432.369473 -167.259457)
			(xy 432.340007 -167.305311) (xy 432.304314 -167.346504) (xy 432.263122 -167.382198) (xy 432.217269 -167.411666)
			(xy 432.167689 -167.434308) (xy 432.115392 -167.449664) (xy 432.061441 -167.457419) (xy 432.034188 -167.457882)
			(xy 432.006043 -167.457345) (xy 431.950364 -167.449079) (xy 431.896502 -167.432729) (xy 431.845623 -167.408649)
			(xy 431.798831 -167.37736) (xy 431.777648 -167.358822) (xy 431.765855 -167.348775) (xy 431.737762 -167.335744)
			(xy 431.707055 -167.331725) (xy 431.676555 -167.337089) (xy 431.649061 -167.351341) (xy 431.637694 -167.36187)
			(xy 431.616095 -167.382511) (xy 431.567692 -167.417527) (xy 431.514422 -167.444567) (xy 431.457587 -167.462971)
			(xy 431.398578 -167.472287) (xy 431.368708 -167.472868) (xy 431.341454 -167.472437) (xy 431.287499 -167.46468)
			(xy 431.235198 -167.449323) (xy 431.185616 -167.426679) (xy 431.139761 -167.397208) (xy 431.098567 -167.361511)
			(xy 431.062873 -167.320314) (xy 431.033406 -167.274456) (xy 431.010766 -167.224872) (xy 430.995413 -167.172569)
			(xy 430.987661 -167.118615) (xy 430.9872 -167.09136) (xy 430.987726 -167.063073) (xy 430.996085 -167.007119)
			(xy 431.012613 -166.953013) (xy 431.036949 -166.90194) (xy 431.068559 -166.85502) (xy 431.087276 -166.833804)
			(xy 431.09739 -166.821886) (xy 431.110498 -166.793527) (xy 431.114434 -166.762534) (xy 431.108828 -166.7318)
			(xy 431.094206 -166.704191) (xy 431.083466 -166.692834) (xy 431.062279 -166.67116) (xy 431.026315 -166.622378)
			(xy 430.998518 -166.568521) (xy 430.979589 -166.510947) (xy 430.970003 -166.451103) (xy 430.96942 -166.4208)
			(xy 430.86782 -166.4208) (xy 430.86782 -173.68647) (xy 454.757534 -173.68647) (xy 454.761605 -173.630848)
			(xy 454.773731 -173.576411) (xy 454.793654 -173.52432) (xy 454.82095 -173.475685) (xy 454.855036 -173.431542)
			(xy 454.895185 -173.392833) (xy 454.940543 -173.360382) (xy 454.990143 -173.334881) (xy 455.042927 -173.316874)
			(xy 455.09777 -173.306744) (xy 455.153504 -173.304707) (xy 455.208941 -173.310807) (xy 455.262898 -173.324913)
			(xy 455.314227 -173.346725) (xy 455.361833 -173.375779) (xy 455.404701 -173.411454) (xy 455.441918 -173.452991)
			(xy 455.472691 -173.499504) (xy 455.496363 -173.550001) (xy 455.512431 -173.603408) (xy 455.520551 -173.658584)
			(xy 455.52106 -173.68647) (xy 455.520551 -173.714356) (xy 455.512431 -173.769532) (xy 455.496363 -173.822939)
			(xy 455.472691 -173.873436) (xy 455.441918 -173.919949) (xy 455.404701 -173.961486) (xy 455.361833 -173.997161)
			(xy 455.314227 -174.026215) (xy 455.262898 -174.048027) (xy 455.208941 -174.062133) (xy 455.153504 -174.068233)
			(xy 455.09777 -174.066196) (xy 455.042927 -174.056066) (xy 454.990143 -174.038059) (xy 454.940543 -174.012558)
			(xy 454.895185 -173.980107) (xy 454.855036 -173.941398) (xy 454.82095 -173.897255) (xy 454.793654 -173.84862)
			(xy 454.773731 -173.796529) (xy 454.761605 -173.742092) (xy 454.757534 -173.68647) (xy 430.86782 -173.68647)
			(xy 430.86782 -174.713392) (xy 430.868351 -174.728393) (xy 430.877056 -174.757105) (xy 430.89372 -174.782054)
			(xy 430.916908 -174.801093) (xy 430.944623 -174.812582) (xy 430.97448 -174.815533) (xy 431.003908 -174.809692)
			(xy 431.030374 -174.79556) (xy 431.041302 -174.785274) (xy 431.55362 -174.272956) (xy 431.571716 -174.255702)
			(xy 431.613263 -174.227897) (xy 431.659434 -174.208729) (xy 431.708457 -174.198932) (xy 431.733452 -174.19828)
			(xy 434.8988 -174.19828) (xy 434.923802 -174.198872) (xy 434.972838 -174.208666) (xy 435.019021 -174.227839)
			(xy 435.060576 -174.255653) (xy 435.078632 -174.272956) (xy 435.144962 -174.33925) (xy 448.7705 -174.33925)
			(xy 448.774571 -174.283628) (xy 448.786697 -174.229191) (xy 448.80662 -174.1771) (xy 448.833916 -174.128465)
			(xy 448.868002 -174.084322) (xy 448.908151 -174.045613) (xy 448.953509 -174.013162) (xy 449.003109 -173.987661)
			(xy 449.055893 -173.969654) (xy 449.110736 -173.959524) (xy 449.16647 -173.957487) (xy 449.221907 -173.963587)
			(xy 449.275864 -173.977693) (xy 449.327193 -173.999505) (xy 449.374799 -174.028559) (xy 449.417667 -174.064234)
			(xy 449.454884 -174.105771) (xy 449.485657 -174.152284) (xy 449.509329 -174.202781) (xy 449.525397 -174.256188)
			(xy 449.533517 -174.311364) (xy 449.534026 -174.33925) (xy 449.533517 -174.367136) (xy 449.525397 -174.422312)
			(xy 449.509329 -174.475719) (xy 449.485657 -174.526216) (xy 449.454884 -174.572729) (xy 449.417667 -174.614266)
			(xy 449.374799 -174.649941) (xy 449.327193 -174.678995) (xy 449.275864 -174.700807) (xy 449.221907 -174.714913)
			(xy 449.16647 -174.721013) (xy 449.110736 -174.718976) (xy 449.055893 -174.708846) (xy 449.003109 -174.690839)
			(xy 448.953509 -174.665338) (xy 448.908151 -174.632887) (xy 448.868002 -174.594178) (xy 448.833916 -174.550035)
			(xy 448.80662 -174.5014) (xy 448.786697 -174.449309) (xy 448.774571 -174.394872) (xy 448.7705 -174.33925)
			(xy 435.144962 -174.33925) (xy 435.552342 -174.746412) (xy 436.1561 -174.746412) (xy 436.181098 -174.747044)
			(xy 436.230129 -174.756835) (xy 436.276307 -174.776) (xy 436.317861 -174.803805) (xy 436.335932 -174.821088)
			(xy 436.706772 -175.191928) (xy 436.724024 -175.210025) (xy 436.751825 -175.251573) (xy 436.77099 -175.297744)
			(xy 436.780784 -175.346765) (xy 436.781448 -175.37176) (xy 436.781448 -175.83404) (xy 436.780812 -175.859037)
			(xy 436.771014 -175.908061) (xy 436.751841 -175.954233) (xy 436.72403 -175.995778) (xy 436.706772 -176.013872)
			(xy 436.701692 -176.018952) (xy 444.68161 -176.018952) (xy 444.682033 -175.991699) (xy 444.689797 -175.937748)
			(xy 444.705159 -175.885451) (xy 444.727807 -175.835872) (xy 444.75728 -175.790021) (xy 444.792978 -175.748831)
			(xy 444.834174 -175.71314) (xy 444.88003 -175.683675) (xy 444.929613 -175.661036) (xy 444.981912 -175.645683)
			(xy 445.035865 -175.637929) (xy 445.063118 -175.637444) (xy 445.08913 -175.637893) (xy 445.140672 -175.644964)
			(xy 445.190775 -175.658973) (xy 445.238509 -175.67966) (xy 445.28299 -175.706641) (xy 445.323393 -175.739415)
			(xy 445.341502 -175.758094) (xy 445.351381 -175.768042) (xy 445.37536 -175.78255) (xy 445.402382 -175.789987)
			(xy 445.430407 -175.789795) (xy 445.457324 -175.781987) (xy 445.481102 -175.767151) (xy 445.490854 -175.757078)
			(xy 445.509036 -175.737781) (xy 445.549776 -175.703855) (xy 445.594821 -175.675895) (xy 445.643302 -175.65444)
			(xy 445.694287 -175.639904) (xy 445.746794 -175.632565) (xy 445.773302 -175.63211) (xy 445.800556 -175.632554)
			(xy 445.854508 -175.640311) (xy 445.906808 -175.655668) (xy 445.956389 -175.678312) (xy 446.002243 -175.707782)
			(xy 446.043436 -175.743478) (xy 446.07913 -175.784673) (xy 446.108597 -175.830529) (xy 446.131239 -175.880111)
			(xy 446.146593 -175.932411) (xy 446.154348 -175.986364) (xy 446.15481 -176.013618) (xy 446.15429 -176.041314)
			(xy 446.146295 -176.096126) (xy 446.130461 -176.149206) (xy 446.10712 -176.19944) (xy 446.076763 -176.245773)
			(xy 446.040027 -176.28723) (xy 446.019174 -176.305464) (xy 446.012336 -176.311719) (xy 446.003266 -176.32786)
			(xy 446.000545 -176.346174) (xy 446.004531 -176.364255) (xy 446.014699 -176.379727) (xy 446.021968 -176.385474)
			(xy 446.049146 -176.407064) (xy 446.060474 -176.4163) (xy 446.087031 -176.428476) (xy 446.115948 -176.432649)
			(xy 446.144865 -176.428476) (xy 446.171422 -176.4163) (xy 446.18275 -176.407064) (xy 446.203685 -176.389429)
			(xy 446.249658 -176.359718) (xy 446.299405 -176.336882) (xy 446.351904 -176.32139) (xy 446.406079 -176.313559)
			(xy 446.433448 -176.313084) (xy 446.460696 -176.313589) (xy 446.514638 -176.321351) (xy 446.566926 -176.33671)
			(xy 446.616496 -176.359353) (xy 446.662339 -176.38882) (xy 446.703523 -176.424511) (xy 446.739209 -176.465699)
			(xy 446.76867 -176.511546) (xy 446.791307 -176.561119) (xy 446.806659 -176.613409) (xy 446.814414 -176.667352)
			(xy 446.814414 -176.721848) (xy 446.814413 -176.721856) (xy 447.068348 -176.721856) (xy 447.068348 -176.667344)
			(xy 447.076106 -176.613388) (xy 447.091465 -176.561085) (xy 447.114111 -176.511501) (xy 447.143584 -176.465645)
			(xy 447.179284 -176.42445) (xy 447.220483 -176.388755) (xy 447.266343 -176.359288) (xy 447.31593 -176.336648)
			(xy 447.368235 -176.321296) (xy 447.422192 -176.313544) (xy 447.449448 -176.313084) (xy 447.477642 -176.3141)
			(xy 447.491734 -176.314647) (xy 447.519327 -176.308873) (xy 447.544292 -176.295778) (xy 447.564729 -176.276361)
			(xy 447.579082 -176.252098) (xy 447.586259 -176.224836) (xy 447.585714 -176.196651) (xy 447.582036 -176.183036)
			(xy 447.574146 -176.155645) (xy 447.565733 -176.099269) (xy 447.565272 -176.070768) (xy 447.565758 -176.043517)
			(xy 447.573514 -175.989569) (xy 447.588869 -175.937274) (xy 447.611511 -175.887697) (xy 447.640977 -175.841847)
			(xy 447.676668 -175.800656) (xy 447.717859 -175.764965) (xy 447.763709 -175.735499) (xy 447.813286 -175.712857)
			(xy 447.865581 -175.697502) (xy 447.919529 -175.689746) (xy 447.974031 -175.689746) (xy 448.027979 -175.697502)
			(xy 448.080274 -175.712857) (xy 448.129851 -175.735499) (xy 448.175701 -175.764965) (xy 448.216892 -175.800656)
			(xy 448.252583 -175.841847) (xy 448.282049 -175.887697) (xy 448.304691 -175.937274) (xy 448.320046 -175.989569)
			(xy 448.327802 -176.043517) (xy 448.328288 -176.070768) (xy 448.327622 -176.102919) (xy 448.316828 -176.166308)
			(xy 448.295539 -176.226983) (xy 448.280536 -176.255426) (xy 448.273907 -176.268551) (xy 448.267588 -176.297251)
			(xy 448.269715 -176.326561) (xy 448.280112 -176.354047) (xy 448.297916 -176.377427) (xy 448.309492 -176.38649)
			(xy 448.333303 -176.404583) (xy 448.375488 -176.446968) (xy 448.410546 -176.495413) (xy 448.43762 -176.548734)
			(xy 448.456046 -176.605624) (xy 448.465374 -176.664692) (xy 448.465956 -176.694592) (xy 448.465415 -176.721841)
			(xy 448.457661 -176.775784) (xy 448.442309 -176.828075) (xy 448.419672 -176.877649) (xy 448.390211 -176.923497)
			(xy 448.354526 -176.964686) (xy 448.313342 -177.000378) (xy 448.267498 -177.029845) (xy 448.217927 -177.052489)
			(xy 448.165639 -177.067849) (xy 448.111697 -177.075611) (xy 448.084448 -177.0761) (xy 448.057079 -177.075606)
			(xy 448.002901 -177.067795) (xy 447.950398 -177.052312) (xy 447.900651 -177.029477) (xy 447.854683 -176.999758)
			(xy 447.83375 -176.98212) (xy 447.822422 -176.972884) (xy 447.795865 -176.960708) (xy 447.766948 -176.956535)
			(xy 447.738031 -176.960708) (xy 447.711474 -176.972884) (xy 447.700146 -176.98212) (xy 447.67921 -176.999754)
			(xy 447.633238 -177.029466) (xy 447.583491 -177.052303) (xy 447.530992 -177.067795) (xy 447.476817 -177.075625)
			(xy 447.449448 -177.0761) (xy 447.422192 -177.075656) (xy 447.368235 -177.067904) (xy 447.31593 -177.052552)
			(xy 447.266343 -177.029912) (xy 447.220483 -177.000445) (xy 447.179284 -176.96475) (xy 447.143584 -176.923555)
			(xy 447.114111 -176.877699) (xy 447.091465 -176.828115) (xy 447.076106 -176.775812) (xy 447.068348 -176.721856)
			(xy 446.814413 -176.721856) (xy 446.806659 -176.775791) (xy 446.791307 -176.828081) (xy 446.76867 -176.877654)
			(xy 446.739209 -176.923501) (xy 446.703523 -176.964689) (xy 446.662339 -177.00038) (xy 446.616496 -177.029847)
			(xy 446.566926 -177.05249) (xy 446.514638 -177.067849) (xy 446.460696 -177.075611) (xy 446.433448 -177.0761)
			(xy 446.406079 -177.075606) (xy 446.351901 -177.067795) (xy 446.299398 -177.052312) (xy 446.249651 -177.029477)
			(xy 446.203683 -176.999758) (xy 446.18275 -176.98212) (xy 446.171422 -176.972884) (xy 446.144865 -176.960708)
			(xy 446.115948 -176.956535) (xy 446.087031 -176.960708) (xy 446.060474 -176.972884) (xy 446.049146 -176.98212)
			(xy 446.02821 -176.999754) (xy 445.982238 -177.029466) (xy 445.932491 -177.052303) (xy 445.879992 -177.067795)
			(xy 445.825817 -177.075625) (xy 445.798448 -177.0761) (xy 445.772434 -177.075691) (xy 445.72089 -177.068614)
			(xy 445.670786 -177.054599) (xy 445.623051 -177.033904) (xy 445.578571 -177.006916) (xy 445.538171 -176.974133)
			(xy 445.520064 -176.95545) (xy 445.510219 -176.945464) (xy 445.486231 -176.930952) (xy 445.4592 -176.923515)
			(xy 445.431165 -176.923714) (xy 445.404242 -176.931534) (xy 445.380462 -176.946385) (xy 445.370712 -176.956466)
			(xy 445.352556 -176.975788) (xy 445.311809 -177.00971) (xy 445.266759 -177.037665) (xy 445.218272 -177.059116)
			(xy 445.167283 -177.073648) (xy 445.114774 -177.080982) (xy 445.088264 -177.081434) (xy 445.061013 -177.080956)
			(xy 445.007066 -177.073195) (xy 444.954773 -177.057837) (xy 444.905197 -177.035193) (xy 444.859349 -177.005726)
			(xy 444.818159 -176.970034) (xy 444.782468 -176.928843) (xy 444.753002 -176.882994) (xy 444.73036 -176.833417)
			(xy 444.715003 -176.781124) (xy 444.707244 -176.727177) (xy 444.706756 -176.699926) (xy 444.707283 -176.671461)
			(xy 444.715757 -176.615165) (xy 444.732506 -176.560755) (xy 444.757158 -176.509439) (xy 444.789165 -176.462358)
			(xy 444.808102 -176.4411) (xy 444.816772 -176.431026) (xy 444.829184 -176.407541) (xy 444.835101 -176.381646)
			(xy 444.834121 -176.3551) (xy 444.826309 -176.329712) (xy 444.812199 -176.307206) (xy 444.802768 -176.297844)
			(xy 444.784021 -176.279718) (xy 444.751106 -176.239272) (xy 444.724005 -176.194722) (xy 444.703222 -176.146895)
			(xy 444.689146 -176.096685) (xy 444.682038 -176.045025) (xy 444.68161 -176.018952) (xy 436.701692 -176.018952)
			(xy 436.366412 -176.354232) (xy 436.348317 -176.371489) (xy 436.306772 -176.399301) (xy 436.260601 -176.418476)
			(xy 436.211577 -176.42828) (xy 436.18658 -176.428908) (xy 435.057042 -176.428908) (xy 435.032047 -176.42827)
			(xy 434.983025 -176.418468) (xy 434.936857 -176.39929) (xy 434.895318 -176.371474) (xy 434.87721 -176.354232)
			(xy 434.503068 -175.98009) (xy 434.481732 -175.98009) (xy 434.4797 -175.980344) (xy 434.452326 -175.979878)
			(xy 434.398137 -175.972084) (xy 434.345609 -175.956654) (xy 434.295813 -175.933903) (xy 434.249764 -175.904293)
			(xy 434.208399 -175.86843) (xy 434.172561 -175.827042) (xy 434.142981 -175.780974) (xy 434.120261 -175.731164)
			(xy 434.104865 -175.678626) (xy 434.097104 -175.624432) (xy 434.096668 -175.597058) (xy 434.096993 -175.573762)
			(xy 434.102616 -175.527513) (xy 434.113821 -175.48229) (xy 434.121814 -175.460406) (xy 434.126426 -175.447091)
			(xy 434.128924 -175.419035) (xy 434.123657 -175.391365) (xy 434.111026 -175.366189) (xy 434.091994 -175.345424)
			(xy 434.06801 -175.330654) (xy 434.040902 -175.323002) (xy 434.026818 -175.322484) (xy 431.941986 -175.322484)
			(xy 430.86782 -176.39665) (xy 430.86782 -177.434748) (xy 431.143662 -177.434748) (xy 431.147733 -177.379126)
			(xy 431.159859 -177.324689) (xy 431.179782 -177.272598) (xy 431.207078 -177.223963) (xy 431.241164 -177.17982)
			(xy 431.281313 -177.141111) (xy 431.326671 -177.10866) (xy 431.376271 -177.083159) (xy 431.429055 -177.065152)
			(xy 431.483898 -177.055022) (xy 431.539632 -177.052985) (xy 431.595069 -177.059085) (xy 431.649026 -177.073191)
			(xy 431.700355 -177.095003) (xy 431.747961 -177.124057) (xy 431.790829 -177.159732) (xy 431.828046 -177.201269)
			(xy 431.858819 -177.247782) (xy 431.882491 -177.298279) (xy 431.898559 -177.351686) (xy 431.906679 -177.406862)
			(xy 431.907188 -177.434748) (xy 431.906679 -177.462634) (xy 431.898559 -177.51781) (xy 431.882491 -177.571217)
			(xy 431.858819 -177.621714) (xy 431.828046 -177.668227) (xy 431.790829 -177.709764) (xy 431.747961 -177.745439)
			(xy 431.700355 -177.774493) (xy 431.649026 -177.796305) (xy 431.595069 -177.810411) (xy 431.539632 -177.816511)
			(xy 431.483898 -177.814474) (xy 431.429055 -177.804344) (xy 431.376271 -177.786337) (xy 431.326671 -177.760836)
			(xy 431.281313 -177.728385) (xy 431.241164 -177.689676) (xy 431.207078 -177.645533) (xy 431.179782 -177.596898)
			(xy 431.159859 -177.544807) (xy 431.147733 -177.49037) (xy 431.143662 -177.434748) (xy 430.86782 -177.434748)
			(xy 430.86782 -178.044348) (xy 434.953662 -178.044348) (xy 434.957733 -177.988726) (xy 434.969859 -177.934289)
			(xy 434.989782 -177.882198) (xy 435.017078 -177.833563) (xy 435.051164 -177.78942) (xy 435.091313 -177.750711)
			(xy 435.136671 -177.71826) (xy 435.186271 -177.692759) (xy 435.239055 -177.674752) (xy 435.293898 -177.664622)
			(xy 435.349632 -177.662585) (xy 435.405069 -177.668685) (xy 435.459026 -177.682791) (xy 435.510355 -177.704603)
			(xy 435.557961 -177.733657) (xy 435.600829 -177.769332) (xy 435.638046 -177.810869) (xy 435.668819 -177.857382)
			(xy 435.692491 -177.907879) (xy 435.708559 -177.961286) (xy 435.716679 -178.016462) (xy 435.717188 -178.044348)
			(xy 435.716679 -178.072234) (xy 435.708559 -178.12741) (xy 435.692491 -178.180817) (xy 435.668819 -178.231314)
			(xy 435.638046 -178.277827) (xy 435.600829 -178.319364) (xy 435.557961 -178.355039) (xy 435.510355 -178.384093)
			(xy 435.459026 -178.405905) (xy 435.405069 -178.420011) (xy 435.349632 -178.426111) (xy 435.293898 -178.424074)
			(xy 435.239055 -178.413944) (xy 435.186271 -178.395937) (xy 435.136671 -178.370436) (xy 435.091313 -178.337985)
			(xy 435.051164 -178.299276) (xy 435.017078 -178.255133) (xy 434.989782 -178.206498) (xy 434.969859 -178.154407)
			(xy 434.957733 -178.09997) (xy 434.953662 -178.044348) (xy 430.86782 -178.044348) (xy 430.86782 -178.197256)
			(xy 430.868309 -178.211994) (xy 430.876712 -178.240246) (xy 430.892832 -178.264922) (xy 430.915327 -178.283969)
			(xy 430.942323 -178.2958) (xy 430.971574 -178.29943) (xy 431.000644 -178.294558) (xy 431.027112 -178.281589)
			(xy 431.038254 -178.271932) (xy 431.059516 -178.253011) (xy 431.106603 -178.221042) (xy 431.157923 -178.196436)
			(xy 431.212334 -178.179741) (xy 431.268622 -178.171328) (xy 431.29708 -178.17084) (xy 431.324333 -178.171302)
			(xy 431.378283 -178.179057) (xy 431.430581 -178.194412) (xy 431.48016 -178.217054) (xy 431.526012 -178.246522)
			(xy 431.567203 -178.282216) (xy 431.602895 -178.32341) (xy 431.63236 -178.369264) (xy 431.654998 -178.418846)
			(xy 431.670349 -178.471144) (xy 431.6781 -178.525095) (xy 431.678588 -178.552348) (xy 431.678023 -178.582077)
			(xy 431.668804 -178.640815) (xy 431.650582 -178.69741) (xy 431.623798 -178.750493) (xy 431.620165 -178.755548)
			(xy 433.124862 -178.755548) (xy 433.128933 -178.699926) (xy 433.141059 -178.645489) (xy 433.160982 -178.593398)
			(xy 433.188278 -178.544763) (xy 433.222364 -178.50062) (xy 433.262513 -178.461911) (xy 433.307871 -178.42946)
			(xy 433.357471 -178.403959) (xy 433.410255 -178.385952) (xy 433.465098 -178.375822) (xy 433.520832 -178.373785)
			(xy 433.576269 -178.379885) (xy 433.630226 -178.393991) (xy 433.681555 -178.415803) (xy 433.729161 -178.444857)
			(xy 433.772029 -178.480532) (xy 433.809246 -178.522069) (xy 433.840019 -178.568582) (xy 433.863691 -178.619079)
			(xy 433.879759 -178.672486) (xy 433.882526 -178.691286) (xy 433.98897 -178.691286) (xy 433.993041 -178.635664)
			(xy 434.005167 -178.581227) (xy 434.02509 -178.529136) (xy 434.052386 -178.480501) (xy 434.086472 -178.436358)
			(xy 434.126621 -178.397649) (xy 434.171979 -178.365198) (xy 434.221579 -178.339697) (xy 434.274363 -178.32169)
			(xy 434.329206 -178.31156) (xy 434.38494 -178.309523) (xy 434.440377 -178.315623) (xy 434.494334 -178.329729)
			(xy 434.545663 -178.351541) (xy 434.593269 -178.380595) (xy 434.636137 -178.41627) (xy 434.673354 -178.457807)
			(xy 434.704127 -178.50432) (xy 434.727799 -178.554817) (xy 434.743867 -178.608224) (xy 434.751987 -178.6634)
			(xy 434.752496 -178.691286) (xy 434.751987 -178.719172) (xy 434.743867 -178.774348) (xy 434.727799 -178.827755)
			(xy 434.72424 -178.835348) (xy 444.707304 -178.835348) (xy 444.707304 -178.780852) (xy 444.715059 -178.726911)
			(xy 444.730411 -178.674623) (xy 444.753048 -178.625052) (xy 444.782509 -178.579206) (xy 444.818194 -178.53802)
			(xy 444.859377 -178.502331) (xy 444.90522 -178.472866) (xy 444.954789 -178.450224) (xy 445.007076 -178.434867)
			(xy 445.061016 -178.427107) (xy 445.088264 -178.426618) (xy 445.114278 -178.427013) (xy 445.165823 -178.434092)
			(xy 445.215928 -178.44811) (xy 445.263663 -178.468807) (xy 445.308143 -178.495798) (xy 445.348542 -178.528584)
			(xy 445.366648 -178.547268) (xy 445.376576 -178.557164) (xy 445.40054 -178.571678) (xy 445.42755 -178.579125)
			(xy 445.455566 -178.578943) (xy 445.482476 -178.571145) (xy 445.506249 -178.55632) (xy 445.516 -178.546252)
			(xy 445.534154 -178.526928) (xy 445.574901 -178.493005) (xy 445.619952 -178.46505) (xy 445.668438 -178.4436)
			(xy 445.719428 -178.429068) (xy 445.771938 -178.421735) (xy 445.798448 -178.421284) (xy 445.825818 -178.42176)
			(xy 445.879998 -178.429572) (xy 445.932501 -178.445058) (xy 445.982249 -178.467898) (xy 446.028215 -178.497622)
			(xy 446.049146 -178.515264) (xy 446.060474 -178.5245) (xy 446.087031 -178.536676) (xy 446.115948 -178.540849)
			(xy 446.144865 -178.536676) (xy 446.171422 -178.5245) (xy 446.18275 -178.515264) (xy 446.203685 -178.497629)
			(xy 446.249658 -178.467918) (xy 446.299405 -178.445082) (xy 446.351904 -178.42959) (xy 446.406079 -178.421759)
			(xy 446.433448 -178.421284) (xy 446.460696 -178.421789) (xy 446.514638 -178.429551) (xy 446.566926 -178.44491)
			(xy 446.616496 -178.467553) (xy 446.662339 -178.49702) (xy 446.703523 -178.532711) (xy 446.739209 -178.573899)
			(xy 446.76867 -178.619746) (xy 446.791307 -178.669319) (xy 446.806659 -178.721609) (xy 446.814414 -178.775552)
			(xy 446.814414 -178.830048) (xy 446.814413 -178.830056) (xy 447.068348 -178.830056) (xy 447.068348 -178.775544)
			(xy 447.076106 -178.721588) (xy 447.091465 -178.669285) (xy 447.114111 -178.619701) (xy 447.143584 -178.573845)
			(xy 447.179284 -178.53265) (xy 447.220483 -178.496955) (xy 447.266343 -178.467488) (xy 447.31593 -178.444848)
			(xy 447.368235 -178.429496) (xy 447.422192 -178.421744) (xy 447.449448 -178.421284) (xy 447.476818 -178.42176)
			(xy 447.530998 -178.429572) (xy 447.583501 -178.445058) (xy 447.633249 -178.467898) (xy 447.679215 -178.497622)
			(xy 447.700146 -178.515264) (xy 447.711474 -178.5245) (xy 447.738031 -178.536676) (xy 447.766948 -178.540849)
			(xy 447.795865 -178.536676) (xy 447.822422 -178.5245) (xy 447.83375 -178.515264) (xy 447.854685 -178.497629)
			(xy 447.900658 -178.467918) (xy 447.950405 -178.445082) (xy 448.002904 -178.42959) (xy 448.057079 -178.421759)
			(xy 448.084448 -178.421284) (xy 448.111696 -178.421789) (xy 448.165638 -178.429551) (xy 448.217926 -178.44491)
			(xy 448.267496 -178.467553) (xy 448.313339 -178.49702) (xy 448.354523 -178.532711) (xy 448.390209 -178.573899)
			(xy 448.41967 -178.619746) (xy 448.442307 -178.669319) (xy 448.457659 -178.721609) (xy 448.465414 -178.775552)
			(xy 448.465414 -178.830048) (xy 448.457659 -178.883991) (xy 448.442307 -178.936281) (xy 448.41967 -178.985854)
			(xy 448.390209 -179.031701) (xy 448.354523 -179.072889) (xy 448.313339 -179.10858) (xy 448.267496 -179.138047)
			(xy 448.217926 -179.16069) (xy 448.165638 -179.176049) (xy 448.111696 -179.183811) (xy 448.084448 -179.1843)
			(xy 448.057079 -179.183806) (xy 448.002901 -179.175995) (xy 447.950398 -179.160512) (xy 447.900651 -179.137677)
			(xy 447.854683 -179.107958) (xy 447.83375 -179.09032) (xy 447.822422 -179.081084) (xy 447.795865 -179.068908)
			(xy 447.766948 -179.064735) (xy 447.738031 -179.068908) (xy 447.711474 -179.081084) (xy 447.700146 -179.09032)
			(xy 447.67921 -179.107954) (xy 447.633238 -179.137666) (xy 447.583491 -179.160503) (xy 447.530992 -179.175995)
			(xy 447.476817 -179.183825) (xy 447.449448 -179.1843) (xy 447.422192 -179.183856) (xy 447.368235 -179.176104)
			(xy 447.31593 -179.160752) (xy 447.266343 -179.138112) (xy 447.220483 -179.108645) (xy 447.179284 -179.07295)
			(xy 447.143584 -179.031755) (xy 447.114111 -178.985899) (xy 447.091465 -178.936315) (xy 447.076106 -178.884012)
			(xy 447.068348 -178.830056) (xy 446.814413 -178.830056) (xy 446.806659 -178.883991) (xy 446.791307 -178.936281)
			(xy 446.76867 -178.985854) (xy 446.739209 -179.031701) (xy 446.703523 -179.072889) (xy 446.662339 -179.10858)
			(xy 446.616496 -179.138047) (xy 446.566926 -179.16069) (xy 446.514638 -179.176049) (xy 446.460696 -179.183811)
			(xy 446.433448 -179.1843) (xy 446.406079 -179.183806) (xy 446.351901 -179.175995) (xy 446.299398 -179.160512)
			(xy 446.249651 -179.137677) (xy 446.203683 -179.107958) (xy 446.18275 -179.09032) (xy 446.171422 -179.081084)
			(xy 446.144865 -179.068908) (xy 446.115948 -179.064735) (xy 446.087031 -179.068908) (xy 446.060474 -179.081084)
			(xy 446.049146 -179.09032) (xy 446.02821 -179.107954) (xy 445.982238 -179.137666) (xy 445.932491 -179.160503)
			(xy 445.879992 -179.175995) (xy 445.825817 -179.183825) (xy 445.798448 -179.1843) (xy 445.772434 -179.183891)
			(xy 445.72089 -179.176814) (xy 445.670786 -179.162799) (xy 445.623051 -179.142104) (xy 445.578571 -179.115116)
			(xy 445.538171 -179.082333) (xy 445.520064 -179.06365) (xy 445.510219 -179.053664) (xy 445.486231 -179.039152)
			(xy 445.4592 -179.031715) (xy 445.431165 -179.031914) (xy 445.404242 -179.039734) (xy 445.380462 -179.054585)
			(xy 445.370712 -179.064666) (xy 445.352556 -179.083988) (xy 445.311809 -179.11791) (xy 445.266759 -179.145865)
			(xy 445.218272 -179.167316) (xy 445.167283 -179.181848) (xy 445.114774 -179.189182) (xy 445.088264 -179.189634)
			(xy 445.061016 -179.189093) (xy 445.007076 -179.181333) (xy 444.954789 -179.165976) (xy 444.90522 -179.143334)
			(xy 444.859377 -179.113869) (xy 444.818194 -179.07818) (xy 444.782509 -179.036994) (xy 444.753048 -178.991148)
			(xy 444.730411 -178.941577) (xy 444.715059 -178.889289) (xy 444.707304 -178.835348) (xy 434.72424 -178.835348)
			(xy 434.704127 -178.878252) (xy 434.673354 -178.924765) (xy 434.636137 -178.966302) (xy 434.593269 -179.001977)
			(xy 434.545663 -179.031031) (xy 434.494334 -179.052843) (xy 434.440377 -179.066949) (xy 434.38494 -179.073049)
			(xy 434.329206 -179.071012) (xy 434.274363 -179.060882) (xy 434.221579 -179.042875) (xy 434.171979 -179.017374)
			(xy 434.126621 -178.984923) (xy 434.086472 -178.946214) (xy 434.052386 -178.902071) (xy 434.02509 -178.853436)
			(xy 434.005167 -178.801345) (xy 433.993041 -178.746908) (xy 433.98897 -178.691286) (xy 433.882526 -178.691286)
			(xy 433.887879 -178.727662) (xy 433.888388 -178.755548) (xy 433.887879 -178.783434) (xy 433.879759 -178.83861)
			(xy 433.863691 -178.892017) (xy 433.840019 -178.942514) (xy 433.809246 -178.989027) (xy 433.772029 -179.030564)
			(xy 433.729161 -179.066239) (xy 433.681555 -179.095293) (xy 433.630226 -179.117105) (xy 433.576269 -179.131211)
			(xy 433.520832 -179.137311) (xy 433.465098 -179.135274) (xy 433.410255 -179.125144) (xy 433.357471 -179.107137)
			(xy 433.307871 -179.081636) (xy 433.262513 -179.049185) (xy 433.222364 -179.010476) (xy 433.188278 -178.966333)
			(xy 433.160982 -178.917698) (xy 433.141059 -178.865607) (xy 433.128933 -178.81117) (xy 433.124862 -178.755548)
			(xy 431.620165 -178.755548) (xy 431.5891 -178.798776) (xy 431.568606 -178.820318) (xy 431.559491 -178.830137)
			(xy 431.54629 -178.853442) (xy 431.539601 -178.879377) (xy 431.539883 -178.906159) (xy 431.547118 -178.931947)
			(xy 431.560807 -178.954968) (xy 431.57013 -178.96459) (xy 431.58827 -178.982779) (xy 431.619996 -179.023179)
			(xy 431.633376 -179.045108) (xy 431.641456 -179.057827) (xy 431.663594 -179.078248) (xy 431.69072 -179.091334)
			(xy 431.720482 -179.095949) (xy 431.750297 -179.091694) (xy 431.77758 -179.078937) (xy 431.799962 -179.058785)
			(xy 431.808128 -179.046124) (xy 431.822992 -179.022268) (xy 431.858628 -178.978803) (xy 431.90026 -178.941042)
			(xy 431.946986 -178.909804) (xy 431.997793 -178.885766) (xy 432.051578 -178.869449) (xy 432.107177 -178.861207)
			(xy 432.13528 -178.860704) (xy 432.162533 -178.861166) (xy 432.216484 -178.86892) (xy 432.268783 -178.884274)
			(xy 432.318364 -178.906915) (xy 432.364218 -178.936381) (xy 432.405412 -178.972074) (xy 432.441107 -179.013266)
			(xy 432.470576 -179.059118) (xy 432.493219 -179.108698) (xy 432.508575 -179.160996) (xy 432.516333 -179.214947)
			(xy 432.516333 -179.269453) (xy 432.508575 -179.323404) (xy 432.493219 -179.375702) (xy 432.470576 -179.425282)
			(xy 432.441107 -179.471134) (xy 432.405412 -179.512326) (xy 432.364218 -179.548019) (xy 432.318364 -179.577485)
			(xy 432.268783 -179.600126) (xy 432.216484 -179.61548) (xy 432.162533 -179.623234) (xy 432.13528 -179.62372)
			(xy 432.106912 -179.623199) (xy 432.050802 -179.614799) (xy 431.996554 -179.598186) (xy 431.945361 -179.573726)
			(xy 431.898354 -179.541959) (xy 431.856565 -179.503583) (xy 431.820918 -179.459446) (xy 431.806096 -179.435252)
			(xy 431.79802 -179.422531) (xy 431.775889 -179.402106) (xy 431.748765 -179.389018) (xy 431.719004 -179.384405)
			(xy 431.68919 -179.388666) (xy 431.661914 -179.401433) (xy 431.639542 -179.421595) (xy 431.631344 -179.434236)
			(xy 431.616481 -179.458093) (xy 431.580847 -179.501559) (xy 431.539215 -179.539321) (xy 431.492488 -179.570559)
			(xy 431.441681 -179.594596) (xy 431.387895 -179.610911) (xy 431.332295 -179.61915) (xy 431.304192 -179.619656)
			(xy 431.274968 -179.619098) (xy 431.217204 -179.610183) (xy 431.161476 -179.592562) (xy 431.109087 -179.566649)
			(xy 431.061262 -179.533049) (xy 431.039778 -179.51323) (xy 431.028709 -179.503307) (xy 431.002263 -179.48976)
			(xy 430.973038 -179.484396) (xy 430.943505 -179.487667) (xy 430.916162 -179.499298) (xy 430.893322 -179.518304)
			(xy 430.876917 -179.543079) (xy 430.868334 -179.571526) (xy 430.86782 -179.586382) (xy 430.86782 -179.790344)
			(xy 430.86821 -179.799871) (xy 430.875173 -179.817606) (xy 430.888151 -179.831555) (xy 430.905339 -179.839777)
			(xy 430.91481 -179.84089) (xy 430.941883 -179.843415) (xy 430.994972 -179.85516) (xy 431.045855 -179.874323)
			(xy 431.093504 -179.900514) (xy 431.136952 -179.933203) (xy 431.175321 -179.971729) (xy 431.207832 -180.015311)
			(xy 431.233828 -180.063066) (xy 431.252782 -180.114028) (xy 431.26431 -180.167164) (xy 431.268179 -180.221399)
			(xy 431.26431 -180.275633) (xy 431.252783 -180.32877) (xy 431.233829 -180.379732) (xy 431.207834 -180.427487)
			(xy 431.175323 -180.471069) (xy 431.136955 -180.509595) (xy 431.093506 -180.542285) (xy 431.045858 -180.568476)
			(xy 430.994974 -180.587639) (xy 430.941886 -180.599385) (xy 430.91481 -180.601874) (xy 430.90535 -180.602991)
			(xy 430.888203 -180.611258) (xy 430.875244 -180.6252) (xy 430.86825 -180.642904) (xy 430.86782 -180.65242)
			(xy 430.86782 -180.943548) (xy 444.707304 -180.943548) (xy 444.707304 -180.889052) (xy 444.715059 -180.835111)
			(xy 444.730411 -180.782823) (xy 444.753048 -180.733252) (xy 444.782509 -180.687406) (xy 444.818194 -180.64622)
			(xy 444.859377 -180.610531) (xy 444.90522 -180.581066) (xy 444.954789 -180.558424) (xy 445.007076 -180.543067)
			(xy 445.061016 -180.535307) (xy 445.088264 -180.534818) (xy 445.114278 -180.535213) (xy 445.165823 -180.542292)
			(xy 445.215928 -180.55631) (xy 445.263663 -180.577007) (xy 445.308143 -180.603998) (xy 445.348542 -180.636784)
			(xy 445.366648 -180.655468) (xy 445.376576 -180.665364) (xy 445.40054 -180.679878) (xy 445.42755 -180.687325)
			(xy 445.455566 -180.687143) (xy 445.482476 -180.679345) (xy 445.506249 -180.66452) (xy 445.516 -180.654452)
			(xy 445.534154 -180.635128) (xy 445.574901 -180.601205) (xy 445.619952 -180.57325) (xy 445.668438 -180.5518)
			(xy 445.719428 -180.537268) (xy 445.771938 -180.529935) (xy 445.798448 -180.529484) (xy 445.825818 -180.52996)
			(xy 445.879998 -180.537772) (xy 445.932501 -180.553258) (xy 445.982249 -180.576098) (xy 446.028215 -180.605822)
			(xy 446.049146 -180.623464) (xy 446.060474 -180.6327) (xy 446.087031 -180.644876) (xy 446.115948 -180.649049)
			(xy 446.144865 -180.644876) (xy 446.171422 -180.6327) (xy 446.18275 -180.623464) (xy 446.203685 -180.605829)
			(xy 446.249658 -180.576118) (xy 446.299405 -180.553282) (xy 446.351904 -180.53779) (xy 446.406079 -180.529959)
			(xy 446.433448 -180.529484) (xy 446.460696 -180.529989) (xy 446.514638 -180.537751) (xy 446.566926 -180.55311)
			(xy 446.616496 -180.575753) (xy 446.662339 -180.60522) (xy 446.703523 -180.640911) (xy 446.739209 -180.682099)
			(xy 446.76867 -180.727946) (xy 446.791307 -180.777519) (xy 446.806659 -180.829809) (xy 446.814414 -180.883752)
			(xy 446.814414 -180.938248) (xy 446.814413 -180.938256) (xy 447.068348 -180.938256) (xy 447.068348 -180.883744)
			(xy 447.076106 -180.829788) (xy 447.091465 -180.777485) (xy 447.114111 -180.727901) (xy 447.143584 -180.682045)
			(xy 447.179284 -180.64085) (xy 447.220483 -180.605155) (xy 447.266343 -180.575688) (xy 447.31593 -180.553048)
			(xy 447.368235 -180.537696) (xy 447.422192 -180.529944) (xy 447.449448 -180.529484) (xy 447.476818 -180.52996)
			(xy 447.530998 -180.537772) (xy 447.583501 -180.553258) (xy 447.633249 -180.576098) (xy 447.679215 -180.605822)
			(xy 447.700146 -180.623464) (xy 447.711474 -180.6327) (xy 447.738031 -180.644876) (xy 447.766948 -180.649049)
			(xy 447.795865 -180.644876) (xy 447.822422 -180.6327) (xy 447.83375 -180.623464) (xy 447.854685 -180.605829)
			(xy 447.900658 -180.576118) (xy 447.950405 -180.553282) (xy 448.002904 -180.53779) (xy 448.057079 -180.529959)
			(xy 448.084448 -180.529484) (xy 448.111696 -180.529989) (xy 448.165638 -180.537751) (xy 448.217926 -180.55311)
			(xy 448.267496 -180.575753) (xy 448.313339 -180.60522) (xy 448.354523 -180.640911) (xy 448.390209 -180.682099)
			(xy 448.41967 -180.727946) (xy 448.442307 -180.777519) (xy 448.457659 -180.829809) (xy 448.465414 -180.883752)
			(xy 448.465414 -180.938248) (xy 448.457659 -180.992191) (xy 448.442307 -181.044481) (xy 448.41967 -181.094054)
			(xy 448.390209 -181.139901) (xy 448.354523 -181.181089) (xy 448.313339 -181.21678) (xy 448.267496 -181.246247)
			(xy 448.217926 -181.26889) (xy 448.165638 -181.284249) (xy 448.111696 -181.292011) (xy 448.084448 -181.2925)
			(xy 448.057079 -181.292006) (xy 448.002901 -181.284195) (xy 447.950398 -181.268712) (xy 447.900651 -181.245877)
			(xy 447.854683 -181.216158) (xy 447.83375 -181.19852) (xy 447.822422 -181.189284) (xy 447.795865 -181.177108)
			(xy 447.766948 -181.172935) (xy 447.738031 -181.177108) (xy 447.711474 -181.189284) (xy 447.700146 -181.19852)
			(xy 447.67921 -181.216154) (xy 447.633238 -181.245866) (xy 447.583491 -181.268703) (xy 447.530992 -181.284195)
			(xy 447.476817 -181.292025) (xy 447.449448 -181.2925) (xy 447.422192 -181.292056) (xy 447.368235 -181.284304)
			(xy 447.31593 -181.268952) (xy 447.266343 -181.246312) (xy 447.220483 -181.216845) (xy 447.179284 -181.18115)
			(xy 447.143584 -181.139955) (xy 447.114111 -181.094099) (xy 447.091465 -181.044515) (xy 447.076106 -180.992212)
			(xy 447.068348 -180.938256) (xy 446.814413 -180.938256) (xy 446.806659 -180.992191) (xy 446.791307 -181.044481)
			(xy 446.76867 -181.094054) (xy 446.739209 -181.139901) (xy 446.703523 -181.181089) (xy 446.662339 -181.21678)
			(xy 446.616496 -181.246247) (xy 446.566926 -181.26889) (xy 446.514638 -181.284249) (xy 446.460696 -181.292011)
			(xy 446.433448 -181.2925) (xy 446.406079 -181.292006) (xy 446.351901 -181.284195) (xy 446.299398 -181.268712)
			(xy 446.249651 -181.245877) (xy 446.203683 -181.216158) (xy 446.18275 -181.19852) (xy 446.171422 -181.189284)
			(xy 446.144865 -181.177108) (xy 446.115948 -181.172935) (xy 446.087031 -181.177108) (xy 446.060474 -181.189284)
			(xy 446.049146 -181.19852) (xy 446.02821 -181.216154) (xy 445.982238 -181.245866) (xy 445.932491 -181.268703)
			(xy 445.879992 -181.284195) (xy 445.825817 -181.292025) (xy 445.798448 -181.2925) (xy 445.772434 -181.292091)
			(xy 445.72089 -181.285014) (xy 445.670786 -181.270999) (xy 445.623051 -181.250304) (xy 445.578571 -181.223316)
			(xy 445.538171 -181.190533) (xy 445.520064 -181.17185) (xy 445.510219 -181.161864) (xy 445.486231 -181.147352)
			(xy 445.4592 -181.139915) (xy 445.431165 -181.140114) (xy 445.404242 -181.147934) (xy 445.380462 -181.162785)
			(xy 445.370712 -181.172866) (xy 445.352556 -181.192188) (xy 445.311809 -181.22611) (xy 445.266759 -181.254065)
			(xy 445.218272 -181.275516) (xy 445.167283 -181.290048) (xy 445.114774 -181.297382) (xy 445.088264 -181.297834)
			(xy 445.061016 -181.297293) (xy 445.007076 -181.289533) (xy 444.954789 -181.274176) (xy 444.90522 -181.251534)
			(xy 444.859377 -181.222069) (xy 444.818194 -181.18638) (xy 444.782509 -181.145194) (xy 444.753048 -181.099348)
			(xy 444.730411 -181.049777) (xy 444.715059 -180.997489) (xy 444.707304 -180.943548) (xy 430.86782 -180.943548)
			(xy 430.86782 -182.13451) (xy 430.868253 -182.148099) (xy 430.875429 -182.174314) (xy 430.889269 -182.197704)
			(xy 430.908792 -182.216612) (xy 430.932614 -182.229697) (xy 430.959044 -182.236031) (xy 430.986209 -182.235164)
			(xy 431.012182 -182.227158) (xy 431.035121 -182.21258) (xy 431.044604 -182.202836) (xy 431.06276 -182.183555)
			(xy 431.103478 -182.149691) (xy 431.14849 -182.121786) (xy 431.19693 -182.100377) (xy 431.247866 -182.085876)
			(xy 431.300318 -182.078562) (xy 431.326798 -182.078122) (xy 431.354468 -182.078615) (xy 431.409228 -182.086609)
			(xy 431.462259 -182.102429) (xy 431.512448 -182.125744) (xy 431.558743 -182.156065) (xy 431.600172 -182.192756)
			(xy 431.635867 -182.235046) (xy 431.665077 -182.282049) (xy 431.676556 -182.30723) (xy 431.682314 -182.319341)
			(xy 431.699105 -182.340238) (xy 431.720758 -182.356043) (xy 431.745778 -182.365668) (xy 431.772441 -182.368446)
			(xy 431.798908 -182.364189) (xy 431.823354 -182.353187) (xy 431.834036 -182.345076) (xy 431.854589 -182.328766)
			(xy 431.899322 -182.301343) (xy 431.947391 -182.280309) (xy 431.997889 -182.266062) (xy 432.049863 -182.258871)
			(xy 432.076098 -182.258462) (xy 432.103353 -182.258925) (xy 432.157309 -182.266682) (xy 432.209611 -182.282039)
			(xy 432.259195 -182.304683) (xy 432.305052 -182.334154) (xy 432.346248 -182.36985) (xy 432.381945 -182.411046)
			(xy 432.411416 -182.456903) (xy 432.43406 -182.506487) (xy 432.449417 -182.558789) (xy 432.457175 -182.612745)
			(xy 432.457175 -182.667255) (xy 432.452771 -182.697882) (xy 433.533298 -182.697882) (xy 433.537342 -182.619428)
			(xy 433.549431 -182.541806) (xy 433.569438 -182.465838) (xy 433.597149 -182.39233) (xy 433.632272 -182.322061)
			(xy 433.674434 -182.255776) (xy 433.723188 -182.194177) (xy 433.778017 -182.137917) (xy 433.83834 -182.087593)
			(xy 433.903518 -182.043739) (xy 433.972859 -182.006818) (xy 434.04563 -181.977223) (xy 434.121057 -181.955268)
			(xy 434.198342 -181.941184) (xy 434.276666 -181.935121) (xy 434.355198 -181.937144) (xy 434.433106 -181.94723)
			(xy 434.509563 -181.965274) (xy 434.583761 -181.991084) (xy 434.654911 -182.024386) (xy 434.72226 -182.064827)
			(xy 434.785094 -182.111978) (xy 434.842746 -182.165341) (xy 434.894606 -182.224348) (xy 434.940125 -182.288375)
			(xy 434.978818 -182.356743) (xy 435.010277 -182.428727) (xy 435.034168 -182.503564) (xy 435.050237 -182.580461)
			(xy 435.058314 -182.658603) (xy 435.05882 -182.697882) (xy 435.058314 -182.737161) (xy 435.050237 -182.815303)
			(xy 435.034168 -182.8922) (xy 435.010277 -182.967037) (xy 434.978818 -183.039021) (xy 434.977327 -183.041655)
			(xy 444.697021 -183.041655) (xy 444.697021 -182.987145) (xy 444.704779 -182.933188) (xy 444.720136 -182.880885)
			(xy 444.742781 -182.831301) (xy 444.772252 -182.785443) (xy 444.80795 -182.744247) (xy 444.849146 -182.70855)
			(xy 444.895004 -182.679079) (xy 444.944589 -182.656435) (xy 444.996892 -182.641078) (xy 445.050849 -182.633321)
			(xy 445.078104 -182.632858) (xy 445.104116 -182.633312) (xy 445.155658 -182.640381) (xy 445.205761 -182.654389)
			(xy 445.253495 -182.675075) (xy 445.297977 -182.702055) (xy 445.338379 -182.734829) (xy 445.356488 -182.753508)
			(xy 445.366376 -182.76345) (xy 445.39035 -182.77797) (xy 445.417371 -182.785417) (xy 445.445399 -182.785227)
			(xy 445.472317 -182.777415) (xy 445.496092 -182.76257) (xy 445.50584 -182.752492) (xy 445.524031 -182.733205)
			(xy 445.564769 -182.699277) (xy 445.609812 -182.671316) (xy 445.658292 -182.649859) (xy 445.709275 -182.63532)
			(xy 445.76178 -182.62798) (xy 445.788288 -182.627524) (xy 445.815658 -182.627991) (xy 445.869838 -182.635808)
			(xy 445.922341 -182.651296) (xy 445.972088 -182.674138) (xy 446.018054 -182.703863) (xy 446.038986 -182.721504)
			(xy 446.050314 -182.73074) (xy 446.076871 -182.742916) (xy 446.105788 -182.747089) (xy 446.134705 -182.742916)
			(xy 446.161262 -182.73074) (xy 446.17259 -182.721504) (xy 446.193516 -182.703857) (xy 446.23949 -182.674146)
			(xy 446.289239 -182.651312) (xy 446.341741 -182.635822) (xy 446.395918 -182.627997) (xy 446.423288 -182.627524)
			(xy 446.450544 -182.627922) (xy 446.504501 -182.635678) (xy 446.556804 -182.651035) (xy 446.60639 -182.673678)
			(xy 446.652249 -182.703149) (xy 446.693446 -182.738845) (xy 446.729144 -182.780042) (xy 446.758616 -182.825899)
			(xy 446.781261 -182.875484) (xy 446.796619 -182.927788) (xy 446.804377 -182.981744) (xy 446.804377 -183.036248)
			(xy 447.05831 -183.036248) (xy 447.05831 -182.981752) (xy 447.066066 -182.92781) (xy 447.081419 -182.87552)
			(xy 447.104057 -182.825948) (xy 447.13352 -182.780102) (xy 447.169207 -182.738916) (xy 447.210392 -182.703227)
			(xy 447.256237 -182.673763) (xy 447.305809 -182.651123) (xy 447.358098 -182.635768) (xy 447.41204 -182.628011)
			(xy 447.439288 -182.627524) (xy 447.466658 -182.627991) (xy 447.520838 -182.635808) (xy 447.573341 -182.651296)
			(xy 447.623088 -182.674138) (xy 447.669054 -182.703863) (xy 447.689986 -182.721504) (xy 447.701314 -182.73074)
			(xy 447.727871 -182.742916) (xy 447.756788 -182.747089) (xy 447.785705 -182.742916) (xy 447.812262 -182.73074)
			(xy 447.82359 -182.721504) (xy 447.844516 -182.703857) (xy 447.89049 -182.674146) (xy 447.940239 -182.651312)
			(xy 447.992741 -182.635822) (xy 448.046918 -182.627997) (xy 448.074288 -182.627524) (xy 448.101544 -182.627922)
			(xy 448.155501 -182.635678) (xy 448.207804 -182.651035) (xy 448.25739 -182.673678) (xy 448.303249 -182.703149)
			(xy 448.344446 -182.738845) (xy 448.380144 -182.780042) (xy 448.409616 -182.825899) (xy 448.432261 -182.875484)
			(xy 448.447619 -182.927788) (xy 448.455377 -182.981744) (xy 448.455377 -183.036256) (xy 448.447619 -183.090212)
			(xy 448.432261 -183.142516) (xy 448.409616 -183.192101) (xy 448.380144 -183.237958) (xy 448.344446 -183.279155)
			(xy 448.303249 -183.314851) (xy 448.25739 -183.344322) (xy 448.207804 -183.366965) (xy 448.155501 -183.382322)
			(xy 448.101544 -183.390078) (xy 448.074288 -183.39054) (xy 448.046917 -183.390096) (xy 447.992736 -183.382275)
			(xy 447.940232 -183.366781) (xy 447.890486 -183.343935) (xy 447.84452 -183.314204) (xy 447.82359 -183.29656)
			(xy 447.812262 -183.287324) (xy 447.785705 -183.275148) (xy 447.756788 -183.270975) (xy 447.727871 -183.275148)
			(xy 447.701314 -183.287324) (xy 447.689986 -183.29656) (xy 447.669027 -183.314166) (xy 447.623062 -183.343884)
			(xy 447.573322 -183.366727) (xy 447.520827 -183.382226) (xy 447.466655 -183.390062) (xy 447.439288 -183.39054)
			(xy 447.41204 -183.389989) (xy 447.358098 -183.382232) (xy 447.305809 -183.366877) (xy 447.256237 -183.344237)
			(xy 447.210392 -183.314773) (xy 447.169207 -183.279084) (xy 447.13352 -183.237898) (xy 447.104057 -183.192052)
			(xy 447.081419 -183.14248) (xy 447.066066 -183.09019) (xy 447.05831 -183.036248) (xy 446.804377 -183.036248)
			(xy 446.804377 -183.036256) (xy 446.796619 -183.090212) (xy 446.781261 -183.142516) (xy 446.758616 -183.192101)
			(xy 446.729144 -183.237958) (xy 446.693446 -183.279155) (xy 446.652249 -183.314851) (xy 446.60639 -183.344322)
			(xy 446.556804 -183.366965) (xy 446.504501 -183.382322) (xy 446.450544 -183.390078) (xy 446.423288 -183.39054)
			(xy 446.395917 -183.390096) (xy 446.341736 -183.382275) (xy 446.289232 -183.366781) (xy 446.239486 -183.343935)
			(xy 446.19352 -183.314204) (xy 446.17259 -183.29656) (xy 446.161262 -183.287324) (xy 446.134705 -183.275148)
			(xy 446.105788 -183.270975) (xy 446.076871 -183.275148) (xy 446.050314 -183.287324) (xy 446.038986 -183.29656)
			(xy 446.018027 -183.314166) (xy 445.972062 -183.343884) (xy 445.922322 -183.366727) (xy 445.869827 -183.382226)
			(xy 445.815655 -183.390062) (xy 445.788288 -183.39054) (xy 445.762276 -183.390092) (xy 445.710734 -183.383021)
			(xy 445.660631 -183.369013) (xy 445.612896 -183.348326) (xy 445.568415 -183.321344) (xy 445.528013 -183.288569)
			(xy 445.509904 -183.26989) (xy 445.500024 -183.25994) (xy 445.476048 -183.24542) (xy 445.449024 -183.237975)
			(xy 445.420995 -183.238166) (xy 445.394076 -183.24598) (xy 445.3703 -183.260827) (xy 445.360552 -183.270906)
			(xy 445.342364 -183.290197) (xy 445.301626 -183.324124) (xy 445.256582 -183.352085) (xy 445.208102 -183.373541)
			(xy 445.157118 -183.388079) (xy 445.104612 -183.395419) (xy 445.078104 -183.395874) (xy 445.050849 -183.395479)
			(xy 444.996892 -183.387722) (xy 444.944589 -183.372365) (xy 444.895004 -183.349721) (xy 444.849146 -183.32025)
			(xy 444.80795 -183.284553) (xy 444.772252 -183.243357) (xy 444.742781 -183.197499) (xy 444.720136 -183.147915)
			(xy 444.704779 -183.095612) (xy 444.697021 -183.041655) (xy 434.977327 -183.041655) (xy 434.940125 -183.107389)
			(xy 434.894606 -183.171416) (xy 434.842746 -183.230423) (xy 434.785094 -183.283786) (xy 434.72226 -183.330937)
			(xy 434.654911 -183.371378) (xy 434.583761 -183.40468) (xy 434.509563 -183.43049) (xy 434.433106 -183.448534)
			(xy 434.355198 -183.45862) (xy 434.276666 -183.460643) (xy 434.198342 -183.45458) (xy 434.121057 -183.440496)
			(xy 434.04563 -183.418541) (xy 433.972859 -183.388946) (xy 433.903518 -183.352025) (xy 433.83834 -183.308171)
			(xy 433.778017 -183.257847) (xy 433.723188 -183.201587) (xy 433.674434 -183.139988) (xy 433.632272 -183.073703)
			(xy 433.597149 -183.003434) (xy 433.569438 -182.929926) (xy 433.549431 -182.853958) (xy 433.537342 -182.776336)
			(xy 433.533298 -182.697882) (xy 432.452771 -182.697882) (xy 432.449417 -182.721211) (xy 432.43406 -182.773513)
			(xy 432.411416 -182.823097) (xy 432.381945 -182.868954) (xy 432.346248 -182.91015) (xy 432.305052 -182.945846)
			(xy 432.259195 -182.975317) (xy 432.209611 -182.997961) (xy 432.157309 -183.013318) (xy 432.103353 -183.021075)
			(xy 432.076098 -183.021478) (xy 432.048428 -183.020985) (xy 431.993668 -183.012991) (xy 431.940638 -182.99717)
			(xy 431.890449 -182.973854) (xy 431.844155 -182.943533) (xy 431.802726 -182.906843) (xy 431.767032 -182.864553)
			(xy 431.737822 -182.81755) (xy 431.72634 -182.79237) (xy 431.720583 -182.780249) (xy 431.703789 -182.75933)
			(xy 431.68213 -182.743504) (xy 431.657098 -182.73386) (xy 431.630419 -182.731064) (xy 431.603931 -182.735308)
			(xy 431.579461 -182.746299) (xy 431.56886 -182.754524) (xy 431.548307 -182.770834) (xy 431.503574 -182.798257)
			(xy 431.455505 -182.81929) (xy 431.405007 -182.833536) (xy 431.353033 -182.840727) (xy 431.326798 -182.841138)
			(xy 431.301081 -182.840716) (xy 431.250114 -182.833805) (xy 431.200538 -182.820107) (xy 431.153253 -182.799871)
			(xy 431.130964 -182.787036) (xy 431.117809 -182.779802) (xy 431.088688 -182.772567) (xy 431.058721 -182.774111)
			(xy 431.030497 -182.784299) (xy 431.006454 -182.802252) (xy 430.988667 -182.826418) (xy 430.983136 -182.840376)
			(xy 430.974248 -182.864381) (xy 430.950946 -182.909958) (xy 430.921758 -182.95201) (xy 430.88721 -182.989781)
			(xy 430.86782 -183.006492) (xy 430.86782 -183.21147) (xy 430.886762 -183.232754) (xy 430.918771 -183.279885)
			(xy 430.94342 -183.33125) (xy 430.960161 -183.385708) (xy 430.968623 -183.44205) (xy 430.968618 -183.499023)
			(xy 430.967552 -183.50611) (xy 431.24196 -183.50611) (xy 431.246031 -183.450488) (xy 431.258157 -183.396051)
			(xy 431.27808 -183.34396) (xy 431.305376 -183.295325) (xy 431.339462 -183.251182) (xy 431.379611 -183.212473)
			(xy 431.424969 -183.180022) (xy 431.474569 -183.154521) (xy 431.527353 -183.136514) (xy 431.582196 -183.126384)
			(xy 431.63793 -183.124347) (xy 431.693367 -183.130447) (xy 431.747324 -183.144553) (xy 431.798653 -183.166365)
			(xy 431.846259 -183.195419) (xy 431.889127 -183.231094) (xy 431.926344 -183.272631) (xy 431.957117 -183.319144)
			(xy 431.980789 -183.369641) (xy 431.996857 -183.423048) (xy 432.004977 -183.478224) (xy 432.005486 -183.50611)
			(xy 432.004977 -183.533996) (xy 431.996857 -183.589172) (xy 431.980789 -183.642579) (xy 431.957117 -183.693076)
			(xy 431.926344 -183.739589) (xy 431.889127 -183.781126) (xy 431.846259 -183.816801) (xy 431.798653 -183.845855)
			(xy 431.747324 -183.867667) (xy 431.693367 -183.881773) (xy 431.63793 -183.887873) (xy 431.582196 -183.885836)
			(xy 431.527353 -183.875706) (xy 431.474569 -183.857699) (xy 431.424969 -183.832198) (xy 431.379611 -183.799747)
			(xy 431.339462 -183.761038) (xy 431.305376 -183.716895) (xy 431.27808 -183.66826) (xy 431.258157 -183.616169)
			(xy 431.246031 -183.561732) (xy 431.24196 -183.50611) (xy 430.967552 -183.50611) (xy 430.960145 -183.555363)
			(xy 430.943393 -183.609818) (xy 430.918734 -183.661179) (xy 430.886716 -183.708304) (xy 430.86782 -183.72963)
			(xy 430.86782 -185.118248) (xy 430.766768 -185.2193) (xy 432.315942 -185.2193) (xy 432.319856 -185.142113)
			(xy 432.33156 -185.065719) (xy 432.350931 -184.9909) (xy 432.377773 -184.918425) (xy 432.411809 -184.849038)
			(xy 432.45269 -184.78345) (xy 432.499996 -184.722334) (xy 432.553243 -184.666317) (xy 432.611884 -184.615975)
			(xy 432.675317 -184.571823) (xy 432.742891 -184.534316) (xy 432.813913 -184.503837) (xy 432.887655 -184.4807)
			(xy 432.963358 -184.465142) (xy 433.040247 -184.457322) (xy 433.07889 -184.456832) (xy 433.117654 -184.457295)
			(xy 433.194781 -184.465161) (xy 433.270712 -184.480814) (xy 433.344662 -184.504091) (xy 433.415869 -184.534752)
			(xy 433.483596 -184.572481) (xy 433.547146 -184.616888) (xy 433.60586 -184.667515) (xy 433.659134 -184.723839)
			(xy 433.683156 -184.754266) (xy 433.692409 -184.765626) (xy 433.716103 -184.782845) (xy 433.743705 -184.792647)
			(xy 433.772952 -184.794229) (xy 433.80145 -184.787462) (xy 433.826864 -184.772899) (xy 433.837334 -184.762648)
			(xy 433.855367 -184.744315) (xy 433.895538 -184.712208) (xy 433.939662 -184.685796) (xy 433.986938 -184.665557)
			(xy 434.036506 -184.651861) (xy 434.087465 -184.644955) (xy 434.113178 -184.644538) (xy 434.140435 -184.644907)
			(xy 434.194395 -184.652663) (xy 434.246702 -184.668019) (xy 434.296291 -184.690663) (xy 434.342152 -184.720134)
			(xy 434.383353 -184.755832) (xy 434.419053 -184.79703) (xy 434.448527 -184.84289) (xy 434.471173 -184.892477)
			(xy 434.486532 -184.944783) (xy 434.494291 -184.998743) (xy 434.494291 -185.053257) (xy 434.486532 -185.107217)
			(xy 434.471173 -185.159523) (xy 434.448527 -185.20911) (xy 434.419053 -185.25497) (xy 434.383353 -185.296168)
			(xy 434.342152 -185.331866) (xy 434.296291 -185.361337) (xy 434.246702 -185.383981) (xy 434.194395 -185.399337)
			(xy 434.140435 -185.407093) (xy 434.113178 -185.407554) (xy 434.08527 -185.407085) (xy 434.030045 -185.398984)
			(xy 433.976597 -185.382902) (xy 433.951126 -185.371486) (xy 433.937674 -185.365703) (xy 433.908751 -185.361238)
			(xy 433.879749 -185.365164) (xy 433.853053 -185.377158) (xy 433.830859 -185.396235) (xy 433.814991 -185.420826)
			(xy 433.81041 -185.434732) (xy 433.799278 -185.47073) (xy 433.770959 -185.540559) (xy 433.735891 -185.607255)
			(xy 433.694417 -185.670168) (xy 433.64694 -185.728683) (xy 433.593924 -185.782231) (xy 433.535885 -185.830289)
			(xy 433.473389 -185.872389) (xy 433.407046 -185.90812) (xy 433.337503 -185.937134) (xy 433.265437 -185.959148)
			(xy 433.191551 -185.973947) (xy 433.116567 -185.981387) (xy 433.07889 -185.981848) (xy 433.040247 -185.981278)
			(xy 432.963358 -185.973458) (xy 432.887655 -185.9579) (xy 432.813913 -185.934763) (xy 432.742891 -185.904284)
			(xy 432.675317 -185.866777) (xy 432.611884 -185.822625) (xy 432.553243 -185.772283) (xy 432.499996 -185.716266)
			(xy 432.45269 -185.65515) (xy 432.411809 -185.589562) (xy 432.377773 -185.520175) (xy 432.350931 -185.4477)
			(xy 432.33156 -185.372881) (xy 432.319856 -185.296487) (xy 432.315942 -185.2193) (xy 430.766768 -185.2193)
			(xy 430.10328 -185.882788) (xy 428.1424 -185.882788) (xy 428.1297 -185.895488) (xy 413.281114 -185.895488)
			(xy 412.651702 -186.5249) (xy 412.651702 -189.158978) (xy 414.810381 -189.158978) (xy 414.810381 -189.074422)
			(xy 414.818183 -188.990228) (xy 414.833721 -188.907113) (xy 414.856861 -188.825786) (xy 414.887407 -188.746941)
			(xy 414.925098 -188.671251) (xy 414.969611 -188.599362) (xy 415.020569 -188.531886) (xy 415.077535 -188.469401)
			(xy 415.140023 -188.412438) (xy 415.207501 -188.361484) (xy 415.279393 -188.316974) (xy 415.355085 -188.279288)
			(xy 415.433931 -188.248746) (xy 415.51526 -188.22561) (xy 415.598376 -188.210077) (xy 415.68257 -188.202279)
			(xy 415.724848 -188.201808) (xy 416.969448 -188.201808) (xy 417.011723 -188.202266) (xy 417.095913 -188.210072)
			(xy 417.179024 -188.225612) (xy 417.260346 -188.248754) (xy 417.339187 -188.279301) (xy 417.414872 -188.316991)
			(xy 417.486757 -188.361504) (xy 417.554229 -188.412459) (xy 417.616711 -188.469423) (xy 417.673671 -188.531908)
			(xy 417.724623 -188.599382) (xy 417.769132 -188.67127) (xy 417.806819 -188.746957) (xy 417.837361 -188.825799)
			(xy 417.860499 -188.907123) (xy 417.876035 -188.990234) (xy 417.883836 -189.074424) (xy 417.883836 -189.158976)
			(xy 417.883836 -189.158978) (xy 422.354181 -189.158978) (xy 422.354181 -189.074422) (xy 422.361983 -188.990228)
			(xy 422.377521 -188.907113) (xy 422.400661 -188.825786) (xy 422.431207 -188.746941) (xy 422.468898 -188.671251)
			(xy 422.513411 -188.599362) (xy 422.564369 -188.531886) (xy 422.621335 -188.469401) (xy 422.683823 -188.412438)
			(xy 422.751301 -188.361484) (xy 422.823193 -188.316974) (xy 422.898885 -188.279288) (xy 422.977731 -188.248746)
			(xy 423.05906 -188.22561) (xy 423.142176 -188.210077) (xy 423.22637 -188.202279) (xy 423.268648 -188.201808)
			(xy 424.513248 -188.201808) (xy 424.555523 -188.202266) (xy 424.639713 -188.210072) (xy 424.722824 -188.225612)
			(xy 424.804146 -188.248754) (xy 424.882987 -188.279301) (xy 424.958672 -188.316991) (xy 425.030557 -188.361504)
			(xy 425.098029 -188.412459) (xy 425.160511 -188.469423) (xy 425.217471 -188.531908) (xy 425.268423 -188.599382)
			(xy 425.312932 -188.67127) (xy 425.350619 -188.746957) (xy 425.381161 -188.825799) (xy 425.404299 -188.907123)
			(xy 425.419835 -188.990234) (xy 425.427636 -189.074424) (xy 425.427636 -189.158976) (xy 425.427636 -189.158978)
			(xy 429.897981 -189.158978) (xy 429.897981 -189.074422) (xy 429.905783 -188.990228) (xy 429.921321 -188.907113)
			(xy 429.944461 -188.825786) (xy 429.975007 -188.746941) (xy 430.012698 -188.671251) (xy 430.057211 -188.599362)
			(xy 430.108169 -188.531886) (xy 430.165135 -188.469401) (xy 430.227623 -188.412438) (xy 430.295101 -188.361484)
			(xy 430.366993 -188.316974) (xy 430.442685 -188.279288) (xy 430.521531 -188.248746) (xy 430.60286 -188.22561)
			(xy 430.685976 -188.210077) (xy 430.77017 -188.202279) (xy 430.812448 -188.201808) (xy 432.057048 -188.201808)
			(xy 432.099325 -188.202234) (xy 432.183519 -188.21004) (xy 432.266634 -188.225581) (xy 432.34796 -188.248725)
			(xy 432.426803 -188.279273) (xy 432.502492 -188.316966) (xy 432.574381 -188.361481) (xy 432.641855 -188.412439)
			(xy 432.70434 -188.469406) (xy 432.761302 -188.531894) (xy 432.812255 -188.599372) (xy 432.856766 -188.671264)
			(xy 432.894453 -188.746955) (xy 432.924996 -188.825801) (xy 432.948133 -188.907129) (xy 432.963668 -188.990244)
			(xy 432.971468 -189.074439) (xy 432.971956 -189.116716) (xy 432.971445 -189.158978) (xy 437.441781 -189.158978)
			(xy 437.441781 -189.074422) (xy 437.449583 -188.990228) (xy 437.465121 -188.907113) (xy 437.488261 -188.825786)
			(xy 437.518807 -188.746941) (xy 437.556498 -188.671251) (xy 437.601011 -188.599362) (xy 437.651969 -188.531886)
			(xy 437.708935 -188.469401) (xy 437.771423 -188.412438) (xy 437.838901 -188.361484) (xy 437.910793 -188.316974)
			(xy 437.986485 -188.279288) (xy 438.065331 -188.248746) (xy 438.14666 -188.22561) (xy 438.229776 -188.210077)
			(xy 438.31397 -188.202279) (xy 438.356248 -188.201808) (xy 439.600848 -188.201808) (xy 439.643123 -188.202266)
			(xy 439.727313 -188.210072) (xy 439.810424 -188.225612) (xy 439.891746 -188.248754) (xy 439.970587 -188.279301)
			(xy 440.046272 -188.316991) (xy 440.118157 -188.361504) (xy 440.185629 -188.412459) (xy 440.248111 -188.469423)
			(xy 440.305071 -188.531908) (xy 440.356023 -188.599382) (xy 440.400532 -188.67127) (xy 440.438219 -188.746957)
			(xy 440.468761 -188.825799) (xy 440.491899 -188.907123) (xy 440.507435 -188.990234) (xy 440.515236 -189.074424)
			(xy 440.515236 -189.158976) (xy 440.515236 -189.158978) (xy 444.985581 -189.158978) (xy 444.985581 -189.074422)
			(xy 444.993383 -188.990228) (xy 445.008921 -188.907113) (xy 445.032061 -188.825786) (xy 445.062607 -188.746941)
			(xy 445.100298 -188.671251) (xy 445.144811 -188.599362) (xy 445.195769 -188.531886) (xy 445.252735 -188.469401)
			(xy 445.315223 -188.412438) (xy 445.382701 -188.361484) (xy 445.454593 -188.316974) (xy 445.530285 -188.279288)
			(xy 445.609131 -188.248746) (xy 445.69046 -188.22561) (xy 445.773576 -188.210077) (xy 445.85777 -188.202279)
			(xy 445.900048 -188.201808) (xy 447.144648 -188.201808) (xy 447.186923 -188.202266) (xy 447.271113 -188.210072)
			(xy 447.354224 -188.225612) (xy 447.435546 -188.248754) (xy 447.514387 -188.279301) (xy 447.590072 -188.316991)
			(xy 447.661957 -188.361504) (xy 447.729429 -188.412459) (xy 447.791911 -188.469423) (xy 447.848871 -188.531908)
			(xy 447.899823 -188.599382) (xy 447.944332 -188.67127) (xy 447.982019 -188.746957) (xy 448.012561 -188.825799)
			(xy 448.035699 -188.907123) (xy 448.051235 -188.990234) (xy 448.059036 -189.074424) (xy 448.059036 -189.158976)
			(xy 448.059036 -189.158978) (xy 452.529381 -189.158978) (xy 452.529381 -189.074422) (xy 452.537183 -188.990228)
			(xy 452.552721 -188.907113) (xy 452.575861 -188.825786) (xy 452.606407 -188.746941) (xy 452.644098 -188.671251)
			(xy 452.688611 -188.599362) (xy 452.739569 -188.531886) (xy 452.796535 -188.469401) (xy 452.859023 -188.412438)
			(xy 452.926501 -188.361484) (xy 452.998393 -188.316974) (xy 453.074085 -188.279288) (xy 453.152931 -188.248746)
			(xy 453.23426 -188.22561) (xy 453.317376 -188.210077) (xy 453.40157 -188.202279) (xy 453.443848 -188.201808)
			(xy 454.688448 -188.201808) (xy 454.730723 -188.202266) (xy 454.814913 -188.210072) (xy 454.898024 -188.225612)
			(xy 454.979346 -188.248754) (xy 455.058187 -188.279301) (xy 455.133872 -188.316991) (xy 455.205757 -188.361504)
			(xy 455.273229 -188.412459) (xy 455.335711 -188.469423) (xy 455.392671 -188.531908) (xy 455.443623 -188.599382)
			(xy 455.488132 -188.67127) (xy 455.525819 -188.746957) (xy 455.556361 -188.825799) (xy 455.579499 -188.907123)
			(xy 455.595035 -188.990234) (xy 455.602836 -189.074424) (xy 455.602836 -189.158976) (xy 455.595035 -189.243166)
			(xy 455.579499 -189.326277) (xy 455.556361 -189.407601) (xy 455.525819 -189.486443) (xy 455.488132 -189.56213)
			(xy 455.443623 -189.634018) (xy 455.392671 -189.701492) (xy 455.335711 -189.763977) (xy 455.273229 -189.820941)
			(xy 455.205757 -189.871896) (xy 455.133872 -189.916409) (xy 455.058187 -189.954099) (xy 454.979346 -189.984646)
			(xy 454.898024 -190.007788) (xy 454.814913 -190.023328) (xy 454.730723 -190.031134) (xy 454.688448 -190.031624)
			(xy 453.443848 -190.031624) (xy 453.40157 -190.031121) (xy 453.317376 -190.023323) (xy 453.23426 -190.00779)
			(xy 453.152931 -189.984654) (xy 453.074085 -189.954112) (xy 452.998393 -189.916426) (xy 452.926501 -189.871916)
			(xy 452.859023 -189.820962) (xy 452.796535 -189.763999) (xy 452.739569 -189.701514) (xy 452.688611 -189.634038)
			(xy 452.644098 -189.562149) (xy 452.606407 -189.486459) (xy 452.575861 -189.407614) (xy 452.552721 -189.326287)
			(xy 452.537183 -189.243172) (xy 452.529381 -189.158978) (xy 448.059036 -189.158978) (xy 448.051235 -189.243166)
			(xy 448.035699 -189.326277) (xy 448.012561 -189.407601) (xy 447.982019 -189.486443) (xy 447.944332 -189.56213)
			(xy 447.899823 -189.634018) (xy 447.848871 -189.701492) (xy 447.791911 -189.763977) (xy 447.729429 -189.820941)
			(xy 447.661957 -189.871896) (xy 447.590072 -189.916409) (xy 447.514387 -189.954099) (xy 447.435546 -189.984646)
			(xy 447.354224 -190.007788) (xy 447.271113 -190.023328) (xy 447.186923 -190.031134) (xy 447.144648 -190.031624)
			(xy 445.900048 -190.031624) (xy 445.85777 -190.031121) (xy 445.773576 -190.023323) (xy 445.69046 -190.00779)
			(xy 445.609131 -189.984654) (xy 445.530285 -189.954112) (xy 445.454593 -189.916426) (xy 445.382701 -189.871916)
			(xy 445.315223 -189.820962) (xy 445.252735 -189.763999) (xy 445.195769 -189.701514) (xy 445.144811 -189.634038)
			(xy 445.100298 -189.562149) (xy 445.062607 -189.486459) (xy 445.032061 -189.407614) (xy 445.008921 -189.326287)
			(xy 444.993383 -189.243172) (xy 444.985581 -189.158978) (xy 440.515236 -189.158978) (xy 440.507435 -189.243166)
			(xy 440.491899 -189.326277) (xy 440.468761 -189.407601) (xy 440.438219 -189.486443) (xy 440.400532 -189.56213)
			(xy 440.356023 -189.634018) (xy 440.305071 -189.701492) (xy 440.248111 -189.763977) (xy 440.185629 -189.820941)
			(xy 440.118157 -189.871896) (xy 440.046272 -189.916409) (xy 439.970587 -189.954099) (xy 439.891746 -189.984646)
			(xy 439.810424 -190.007788) (xy 439.727313 -190.023328) (xy 439.643123 -190.031134) (xy 439.600848 -190.031624)
			(xy 438.356248 -190.031624) (xy 438.31397 -190.031121) (xy 438.229776 -190.023323) (xy 438.14666 -190.00779)
			(xy 438.065331 -189.984654) (xy 437.986485 -189.954112) (xy 437.910793 -189.916426) (xy 437.838901 -189.871916)
			(xy 437.771423 -189.820962) (xy 437.708935 -189.763999) (xy 437.651969 -189.701514) (xy 437.601011 -189.634038)
			(xy 437.556498 -189.562149) (xy 437.518807 -189.486459) (xy 437.488261 -189.407614) (xy 437.465121 -189.326287)
			(xy 437.449583 -189.243172) (xy 437.441781 -189.158978) (xy 432.971445 -189.158978) (xy 432.971429 -189.160318)
			(xy 432.96312 -189.247124) (xy 432.946588 -189.332746) (xy 432.921984 -189.416406) (xy 432.889531 -189.497346)
			(xy 432.849523 -189.57483) (xy 432.802323 -189.648155) (xy 432.74836 -189.716657) (xy 432.688124 -189.779712)
			(xy 432.655472 -189.808612) (xy 432.644945 -189.81839) (xy 432.629354 -189.842508) (xy 432.6211 -189.870015)
			(xy 432.620837 -189.898732) (xy 432.628585 -189.926386) (xy 432.643731 -189.950786) (xy 432.665075 -189.97)
			(xy 432.690928 -189.982506) (xy 432.705002 -189.985396) (xy 432.731293 -189.990361) (xy 432.782255 -190.006657)
			(xy 432.830441 -190.029914) (xy 432.874905 -190.059673) (xy 432.914775 -190.095353) (xy 432.949269 -190.136253)
			(xy 432.977712 -190.181572) (xy 432.999544 -190.230419) (xy 433.014337 -190.281837) (xy 433.021803 -190.334818)
			(xy 433.022248 -190.36157) (xy 433.021762 -190.388821) (xy 433.014006 -190.442769) (xy 432.998651 -190.495064)
			(xy 432.976009 -190.544641) (xy 432.946543 -190.590491) (xy 432.910852 -190.631682) (xy 432.869661 -190.667373)
			(xy 432.823811 -190.696839) (xy 432.774234 -190.719481) (xy 432.721939 -190.734836) (xy 432.667991 -190.742592)
			(xy 432.613489 -190.742592) (xy 432.559541 -190.734836) (xy 432.507246 -190.719481) (xy 432.457669 -190.696839)
			(xy 432.411819 -190.667373) (xy 432.370628 -190.631682) (xy 432.334937 -190.590491) (xy 432.305471 -190.544641)
			(xy 432.282829 -190.495064) (xy 432.267474 -190.442769) (xy 432.259718 -190.388821) (xy 432.259232 -190.36157)
			(xy 432.259603 -190.33652) (xy 432.266154 -190.286851) (xy 432.279141 -190.238464) (xy 432.29834 -190.192189)
			(xy 432.31054 -190.170308) (xy 432.317244 -190.15759) (xy 432.324171 -190.129708) (xy 432.323048 -190.101)
			(xy 432.313965 -190.073744) (xy 432.297642 -190.050102) (xy 432.275373 -190.031949) (xy 432.248927 -190.020726)
			(xy 432.220399 -190.017323) (xy 432.206146 -190.019178) (xy 432.169142 -190.024964) (xy 432.094499 -190.031196)
			(xy 432.057048 -190.031624) (xy 430.812448 -190.031624) (xy 430.77017 -190.031121) (xy 430.685976 -190.023323)
			(xy 430.60286 -190.00779) (xy 430.521531 -189.984654) (xy 430.442685 -189.954112) (xy 430.366993 -189.916426)
			(xy 430.295101 -189.871916) (xy 430.227623 -189.820962) (xy 430.165135 -189.763999) (xy 430.108169 -189.701514)
			(xy 430.057211 -189.634038) (xy 430.012698 -189.562149) (xy 429.975007 -189.486459) (xy 429.944461 -189.407614)
			(xy 429.921321 -189.326287) (xy 429.905783 -189.243172) (xy 429.897981 -189.158978) (xy 425.427636 -189.158978)
			(xy 425.419835 -189.243166) (xy 425.404299 -189.326277) (xy 425.381161 -189.407601) (xy 425.350619 -189.486443)
			(xy 425.312932 -189.56213) (xy 425.268423 -189.634018) (xy 425.217471 -189.701492) (xy 425.160511 -189.763977)
			(xy 425.098029 -189.820941) (xy 425.030557 -189.871896) (xy 424.958672 -189.916409) (xy 424.882987 -189.954099)
			(xy 424.804146 -189.984646) (xy 424.722824 -190.007788) (xy 424.639713 -190.023328) (xy 424.555523 -190.031134)
			(xy 424.513248 -190.031624) (xy 423.268648 -190.031624) (xy 423.22637 -190.031121) (xy 423.142176 -190.023323)
			(xy 423.05906 -190.00779) (xy 422.977731 -189.984654) (xy 422.898885 -189.954112) (xy 422.823193 -189.916426)
			(xy 422.751301 -189.871916) (xy 422.683823 -189.820962) (xy 422.621335 -189.763999) (xy 422.564369 -189.701514)
			(xy 422.513411 -189.634038) (xy 422.468898 -189.562149) (xy 422.431207 -189.486459) (xy 422.400661 -189.407614)
			(xy 422.377521 -189.326287) (xy 422.361983 -189.243172) (xy 422.354181 -189.158978) (xy 417.883836 -189.158978)
			(xy 417.876035 -189.243166) (xy 417.860499 -189.326277) (xy 417.837361 -189.407601) (xy 417.806819 -189.486443)
			(xy 417.769132 -189.56213) (xy 417.724623 -189.634018) (xy 417.673671 -189.701492) (xy 417.616711 -189.763977)
			(xy 417.554229 -189.820941) (xy 417.486757 -189.871896) (xy 417.414872 -189.916409) (xy 417.339187 -189.954099)
			(xy 417.260346 -189.984646) (xy 417.179024 -190.007788) (xy 417.095913 -190.023328) (xy 417.011723 -190.031134)
			(xy 416.969448 -190.031624) (xy 415.724848 -190.031624) (xy 415.68257 -190.031121) (xy 415.598376 -190.023323)
			(xy 415.51526 -190.00779) (xy 415.433931 -189.984654) (xy 415.355085 -189.954112) (xy 415.279393 -189.916426)
			(xy 415.207501 -189.871916) (xy 415.140023 -189.820962) (xy 415.077535 -189.763999) (xy 415.020569 -189.701514)
			(xy 414.969611 -189.634038) (xy 414.925098 -189.562149) (xy 414.887407 -189.486459) (xy 414.856861 -189.407614)
			(xy 414.833721 -189.326287) (xy 414.818183 -189.243172) (xy 414.810381 -189.158978) (xy 412.651702 -189.158978)
			(xy 412.651702 -191.25057) (xy 426.797722 -191.25057) (xy 426.801793 -191.194948) (xy 426.813919 -191.140511)
			(xy 426.833842 -191.08842) (xy 426.861138 -191.039785) (xy 426.895224 -190.995642) (xy 426.935373 -190.956933)
			(xy 426.980731 -190.924482) (xy 427.030331 -190.898981) (xy 427.083115 -190.880974) (xy 427.137958 -190.870844)
			(xy 427.193692 -190.868807) (xy 427.249129 -190.874907) (xy 427.303086 -190.889013) (xy 427.354415 -190.910825)
			(xy 427.402021 -190.939879) (xy 427.444889 -190.975554) (xy 427.482106 -191.017091) (xy 427.512879 -191.063604)
			(xy 427.536551 -191.114101) (xy 427.552619 -191.167508) (xy 427.560739 -191.222684) (xy 427.561248 -191.25057)
			(xy 427.560951 -191.266826) (xy 432.681124 -191.266826) (xy 432.685195 -191.211204) (xy 432.697321 -191.156767)
			(xy 432.717244 -191.104676) (xy 432.74454 -191.056041) (xy 432.778626 -191.011898) (xy 432.818775 -190.973189)
			(xy 432.864133 -190.940738) (xy 432.913733 -190.915237) (xy 432.966517 -190.89723) (xy 433.02136 -190.8871)
			(xy 433.077094 -190.885063) (xy 433.132531 -190.891163) (xy 433.186488 -190.905269) (xy 433.237817 -190.927081)
			(xy 433.285423 -190.956135) (xy 433.328291 -190.99181) (xy 433.365508 -191.033347) (xy 433.396281 -191.07986)
			(xy 433.419953 -191.130357) (xy 433.436021 -191.183764) (xy 433.444141 -191.23894) (xy 433.44465 -191.266826)
			(xy 433.444141 -191.294712) (xy 433.436021 -191.349888) (xy 433.419953 -191.403295) (xy 433.396281 -191.453792)
			(xy 433.365508 -191.500305) (xy 433.328291 -191.541842) (xy 433.285423 -191.577517) (xy 433.237817 -191.606571)
			(xy 433.186488 -191.628383) (xy 433.132531 -191.642489) (xy 433.077094 -191.648589) (xy 433.02136 -191.646552)
			(xy 432.966517 -191.636422) (xy 432.913733 -191.618415) (xy 432.864133 -191.592914) (xy 432.818775 -191.560463)
			(xy 432.778626 -191.521754) (xy 432.74454 -191.477611) (xy 432.717244 -191.428976) (xy 432.697321 -191.376885)
			(xy 432.685195 -191.322448) (xy 432.681124 -191.266826) (xy 427.560951 -191.266826) (xy 427.560739 -191.278456)
			(xy 427.552619 -191.333632) (xy 427.536551 -191.387039) (xy 427.512879 -191.437536) (xy 427.482106 -191.484049)
			(xy 427.444889 -191.525586) (xy 427.402021 -191.561261) (xy 427.354415 -191.590315) (xy 427.303086 -191.612127)
			(xy 427.249129 -191.626233) (xy 427.193692 -191.632333) (xy 427.137958 -191.630296) (xy 427.083115 -191.620166)
			(xy 427.030331 -191.602159) (xy 426.980731 -191.576658) (xy 426.935373 -191.544207) (xy 426.895224 -191.505498)
			(xy 426.861138 -191.461355) (xy 426.833842 -191.41272) (xy 426.813919 -191.360629) (xy 426.801793 -191.306192)
			(xy 426.797722 -191.25057) (xy 412.651702 -191.25057) (xy 412.651702 -192.09131) (xy 413.14624 -192.585848)
		)
		(stroke
			(width 0)
			(type solid)
		)
		(fill yes)
		(layer "In11.Cu")
		(net "P3V3_AUX")
	)
	(gr_poly
		(pts
			(xy 111.894874 -236.347) (xy 111.914983 -236.330387) (xy 111.959403 -236.30305) (xy 112.007563 -236.283025)
			(xy 112.05827 -236.270808) (xy 112.110266 -236.266702) (xy 112.162262 -236.270808) (xy 112.212969 -236.283025)
			(xy 112.261129 -236.30305) (xy 112.305549 -236.330387) (xy 112.325658 -236.347) (xy 112.834674 -236.347)
			(xy 112.854783 -236.330387) (xy 112.899203 -236.30305) (xy 112.947363 -236.283025) (xy 112.99807 -236.270808)
			(xy 113.050066 -236.266702) (xy 113.102062 -236.270808) (xy 113.152769 -236.283025) (xy 113.200929 -236.30305)
			(xy 113.245349 -236.330387) (xy 113.265458 -236.347) (xy 113.774728 -236.347) (xy 113.794837 -236.330387)
			(xy 113.839257 -236.30305) (xy 113.887417 -236.283025) (xy 113.938124 -236.270808) (xy 113.99012 -236.266702)
			(xy 114.042116 -236.270808) (xy 114.092823 -236.283025) (xy 114.140983 -236.30305) (xy 114.185403 -236.330387)
			(xy 114.205512 -236.347) (xy 115.094004 -236.347) (xy 115.111222 -236.328137) (xy 115.150443 -236.295428)
			(xy 115.19423 -236.269143) (xy 115.241539 -236.249908) (xy 115.291244 -236.23818) (xy 115.342162 -236.23424)
			(xy 115.39308 -236.23818) (xy 115.442785 -236.249908) (xy 115.490094 -236.269143) (xy 115.533881 -236.295428)
			(xy 115.573102 -236.328137) (xy 115.59032 -236.347) (xy 120.544336 -236.347) (xy 120.557525 -236.346578)
			(xy 120.58302 -236.339807) (xy 120.605927 -236.326726) (xy 120.624715 -236.308211) (xy 120.63813 -236.285498)
			(xy 120.645273 -236.260105) (xy 120.645936 -236.246924) (xy 120.646821 -236.22122) (xy 120.655569 -236.170541)
			(xy 120.672064 -236.12183) (xy 120.695907 -236.076262) (xy 120.726523 -236.034939) (xy 120.763171 -235.998859)
			(xy 120.804968 -235.968893) (xy 120.850902 -235.945766) (xy 120.899866 -235.930034) (xy 120.950676 -235.92208)
			(xy 120.97639 -235.92155) (xy 121.002119 -235.92204) (xy 121.052956 -235.930018) (xy 121.101941 -235.945781)
			(xy 121.147888 -235.96895) (xy 121.189688 -235.998963) (xy 121.226329 -236.035094) (xy 121.256923 -236.07647)
			(xy 121.280732 -236.122089) (xy 121.29718 -236.170849) (xy 121.302018 -236.196124) (xy 121.304805 -236.20984)
			(xy 121.316813 -236.235111) (xy 121.335222 -236.256181) (xy 121.358652 -236.271473) (xy 121.38535 -236.279842)
			(xy 121.413317 -236.280661) (xy 121.426986 -236.277658) (xy 121.446907 -236.272918) (xy 121.487538 -236.267817)
			(xy 121.508012 -236.267498) (xy 121.53142 -236.267907) (xy 121.577767 -236.274524) (xy 121.622714 -236.287622)
			(xy 121.665359 -236.306939) (xy 121.704847 -236.332088) (xy 121.722896 -236.347) (xy 122.233182 -236.347)
			(xy 122.251222 -236.332078) (xy 122.290716 -236.30694) (xy 122.333364 -236.287631) (xy 122.378312 -236.274537)
			(xy 122.424658 -236.267922) (xy 122.448066 -236.267498) (xy 122.475236 -236.268045) (xy 122.528844 -236.276929)
			(xy 122.580276 -236.294461) (xy 122.628149 -236.320171) (xy 122.649996 -236.336332) (xy 122.663712 -236.347)
			(xy 122.712988 -236.347) (xy 122.811032 -236.248956) (xy 122.820655 -236.238715) (xy 122.834371 -236.214201)
			(xy 122.840885 -236.186875) (xy 122.839702 -236.158809) (xy 122.830912 -236.132129) (xy 122.81518 -236.108856)
			(xy 122.7937 -236.090754) (xy 122.78106 -236.084618) (xy 122.7567 -236.072939) (xy 122.71183 -236.042861)
			(xy 122.672448 -236.005888) (xy 122.639602 -235.963002) (xy 122.614167 -235.915346) (xy 122.59682 -235.864189)
			(xy 122.588023 -235.810891) (xy 122.587512 -235.783882) (xy 122.587977 -235.758919) (xy 122.5955 -235.709561)
			(xy 122.610357 -235.661896) (xy 122.632211 -235.617006) (xy 122.660566 -235.575911) (xy 122.694775 -235.539546)
			(xy 122.734063 -235.508736) (xy 122.777536 -235.484183) (xy 122.824205 -235.466444) (xy 122.873011 -235.455923)
			(xy 122.8979 -235.453936) (xy 122.91321 -235.452471) (xy 122.941951 -235.44156) (xy 122.96615 -235.4226)
			(xy 122.98362 -235.397305) (xy 122.992783 -235.36796) (xy 122.993404 -235.35259) (xy 122.993404 -234.587542)
			(xy 122.992878 -234.572157) (xy 122.983726 -234.54278) (xy 122.96624 -234.517461) (xy 122.942008 -234.4985)
			(xy 122.913228 -234.487615) (xy 122.8979 -234.486196) (xy 122.871675 -234.484113) (xy 122.820325 -234.472686)
			(xy 122.771432 -234.45327) (xy 122.726232 -234.426357) (xy 122.685864 -234.392625) (xy 122.651347 -234.352926)
			(xy 122.623553 -234.308262) (xy 122.603184 -234.259759) (xy 122.590752 -234.208643) (xy 122.586573 -234.156203)
			(xy 122.590751 -234.103763) (xy 122.603182 -234.052646) (xy 122.62355 -234.004144) (xy 122.651343 -233.959479)
			(xy 122.685859 -233.919779) (xy 122.726227 -233.886046) (xy 122.771427 -233.859132) (xy 122.820319 -233.839716)
			(xy 122.871669 -233.828288) (xy 122.8979 -233.826304) (xy 122.913214 -233.82484) (xy 122.941964 -233.813931)
			(xy 122.966175 -233.794974) (xy 122.98366 -233.769679) (xy 122.992842 -233.740332) (xy 122.993404 -233.724958)
			(xy 122.993404 -232.959656) (xy 122.992879 -232.94427) (xy 122.98373 -232.914889) (xy 122.966245 -232.889567)
			(xy 122.942012 -232.870602) (xy 122.91323 -232.859716) (xy 122.8979 -232.85831) (xy 122.871698 -232.856205)
			(xy 122.820398 -232.844745) (xy 122.771559 -232.82531) (xy 122.726412 -232.798389) (xy 122.686095 -232.764663)
			(xy 122.651623 -232.72498) (xy 122.623868 -232.680342) (xy 122.603527 -232.631873) (xy 122.591113 -232.580796)
			(xy 122.586941 -232.528398) (xy 122.591114 -232.476) (xy 122.603528 -232.424923) (xy 122.62387 -232.376454)
			(xy 122.651626 -232.331816) (xy 122.686098 -232.292134) (xy 122.726416 -232.258408) (xy 122.771563 -232.231488)
			(xy 122.820402 -232.212054) (xy 122.871702 -232.200594) (xy 122.8979 -232.198418) (xy 122.913215 -232.196954)
			(xy 122.941967 -232.186046) (xy 122.96618 -232.167089) (xy 122.983668 -232.141794) (xy 122.992853 -232.112447)
			(xy 122.993404 -232.097072) (xy 122.993404 -231.33177) (xy 122.992881 -231.316382) (xy 122.983735 -231.286998)
			(xy 122.966251 -231.261672) (xy 122.942016 -231.242704) (xy 122.913232 -231.231816) (xy 122.8979 -231.230424)
			(xy 122.871696 -231.228319) (xy 122.820395 -231.216858) (xy 122.771554 -231.197422) (xy 122.726405 -231.170501)
			(xy 122.686085 -231.136773) (xy 122.651613 -231.097089) (xy 122.623856 -231.052449) (xy 122.603514 -231.003978)
			(xy 122.5911 -230.952899) (xy 122.586927 -230.900499) (xy 122.5911 -230.848098) (xy 122.603514 -230.797019)
			(xy 122.623857 -230.748549) (xy 122.651614 -230.703909) (xy 122.686087 -230.664225) (xy 122.726407 -230.630497)
			(xy 122.771556 -230.603576) (xy 122.820397 -230.584141) (xy 122.871699 -230.57268) (xy 122.8979 -230.570532)
			(xy 122.91321 -230.569067) (xy 122.94195 -230.558156) (xy 122.966148 -230.539196) (xy 122.983618 -230.513901)
			(xy 122.99278 -230.484556) (xy 122.993404 -230.469186) (xy 122.993404 -229.704138) (xy 122.992877 -229.688753)
			(xy 122.983725 -229.659377) (xy 122.966239 -229.63406) (xy 122.942007 -229.615099) (xy 122.913227 -229.604215)
			(xy 122.8979 -229.602792) (xy 122.872989 -229.600845) (xy 122.824129 -229.590388) (xy 122.777401 -229.572694)
			(xy 122.73387 -229.548165) (xy 122.69453 -229.51736) (xy 122.660276 -229.480983) (xy 122.631892 -229.439862)
			(xy 122.610023 -229.394936) (xy 122.595168 -229.347229) (xy 122.587667 -229.297829) (xy 122.587258 -229.272846)
			(xy 122.587788 -229.245885) (xy 122.596536 -229.192676) (xy 122.613807 -229.141594) (xy 122.639142 -229.093993)
			(xy 122.67187 -229.051138) (xy 122.711122 -229.014166) (xy 122.755855 -228.984057) (xy 122.804884 -228.96161)
			(xy 122.856907 -228.947422) (xy 122.883676 -228.94417) (xy 122.929142 -228.939344) (xy 122.929142 -227.978462)
			(xy 122.883676 -227.973636) (xy 122.856934 -227.970308) (xy 122.804958 -227.956088) (xy 122.755978 -227.933623)
			(xy 122.711293 -227.903508) (xy 122.672086 -227.866541) (xy 122.639397 -227.823702) (xy 122.614092 -227.776127)
			(xy 122.596843 -227.725076) (xy 122.588106 -227.671903) (xy 122.587512 -227.64496) (xy 122.588024 -227.618994)
			(xy 122.596153 -227.567702) (xy 122.612205 -227.518312) (xy 122.635784 -227.472041) (xy 122.666311 -227.430028)
			(xy 122.703033 -227.393307) (xy 122.745047 -227.362781) (xy 122.791318 -227.339203) (xy 122.840708 -227.323152)
			(xy 122.892 -227.315024) (xy 122.917966 -227.314506) (xy 122.940341 -227.314863) (xy 122.984689 -227.320852)
			(xy 123.006358 -227.326444) (xy 123.015198 -227.328486) (xy 123.033259 -227.326896) (xy 123.049638 -227.319121)
			(xy 123.06229 -227.306134) (xy 123.066302 -227.297996) (xy 123.08078 -227.266754) (xy 123.087017 -227.252722)
			(xy 123.091643 -227.22238) (xy 123.087064 -227.19203) (xy 123.073692 -227.164403) (xy 123.05273 -227.141983)
			(xy 123.026062 -227.126787) (xy 123.011184 -227.12299) (xy 122.986535 -227.117057) (xy 122.939546 -227.09803)
			(xy 122.917712 -227.085144) (xy 122.893892 -227.099126) (xy 122.842387 -227.119059) (xy 122.788099 -227.129205)
			(xy 122.760486 -227.129848) (xy 122.589544 -227.129848) (xy 122.579892 -227.134166) (xy 122.558972 -227.14286)
			(xy 122.515349 -227.155086) (xy 122.470464 -227.161237) (xy 122.447812 -227.161598) (xy 122.421839 -227.161116)
			(xy 122.370531 -227.152991) (xy 122.321127 -227.13694) (xy 122.274841 -227.113358) (xy 122.232815 -227.082826)
			(xy 122.196082 -227.046094) (xy 122.165548 -227.004069) (xy 122.141964 -226.957785) (xy 122.125911 -226.90838)
			(xy 122.117785 -226.857073) (xy 122.117785 -226.805127) (xy 122.125911 -226.75382) (xy 122.141964 -226.704415)
			(xy 122.165548 -226.658131) (xy 122.196082 -226.616106) (xy 122.232815 -226.579374) (xy 122.274841 -226.548842)
			(xy 122.321127 -226.52526) (xy 122.370531 -226.509209) (xy 122.421839 -226.501084) (xy 122.447812 -226.50069)
			(xy 122.47026 -226.501083) (xy 122.514738 -226.5072) (xy 122.536458 -226.512882) (xy 122.545319 -226.514932)
			(xy 122.563422 -226.513314) (xy 122.57981 -226.505456) (xy 122.592405 -226.492353) (xy 122.596402 -226.48418)
			(xy 122.616182 -226.440764) (xy 122.663914 -226.358151) (xy 122.691652 -226.319334) (xy 122.696711 -226.311777)
			(xy 122.701645 -226.294288) (xy 122.700183 -226.276175) (xy 122.692508 -226.259703) (xy 122.686318 -226.25304)
			(xy 122.66794 -226.234277) (xy 122.63677 -226.192008) (xy 122.612682 -226.145339) (xy 122.596281 -226.095446)
			(xy 122.587982 -226.043588) (xy 122.587512 -226.017328) (xy 122.588019 -225.991358) (xy 122.59614 -225.940058)
			(xy 122.612185 -225.890659) (xy 122.635761 -225.844379) (xy 122.666286 -225.802357) (xy 122.70301 -225.765627)
			(xy 122.745026 -225.735094) (xy 122.791302 -225.711509) (xy 122.840698 -225.695454) (xy 122.891996 -225.687324)
			(xy 122.917966 -225.686874) (xy 122.945185 -225.687435) (xy 122.998885 -225.696371) (xy 123.050393 -225.713992)
			(xy 123.098315 -225.739819) (xy 123.141353 -225.773154) (xy 123.178343 -225.813095) (xy 123.208284 -225.85856)
			(xy 123.230365 -225.90832) (xy 123.237752 -225.934524) (xy 123.240454 -225.943201) (xy 123.250948 -225.958023)
			(xy 123.265933 -225.968284) (xy 123.283547 -225.972709) (xy 123.292616 -225.972116) (xy 123.340139 -225.967585)
			(xy 123.435605 -225.967714) (xy 123.483116 -225.97237) (xy 123.49218 -225.972947) (xy 123.509762 -225.968435)
			(xy 123.524678 -225.958093) (xy 123.535067 -225.94321) (xy 123.537726 -225.934524) (xy 123.545108 -225.908309)
			(xy 123.567249 -225.858555) (xy 123.59724 -225.813099) (xy 123.634271 -225.77317) (xy 123.677342 -225.739844)
			(xy 123.725289 -225.714023) (xy 123.776818 -225.696404) (xy 123.830537 -225.687463) (xy 123.857766 -225.686874)
			(xy 123.885011 -225.687435) (xy 123.938762 -225.696381) (xy 123.990319 -225.714019) (xy 124.038285 -225.739872)
			(xy 124.081364 -225.77324) (xy 124.118388 -225.81322) (xy 124.148355 -225.85873) (xy 124.170455 -225.908538)
			(xy 124.177806 -225.934778) (xy 124.180491 -225.943427) (xy 124.190928 -225.958212) (xy 124.205838 -225.96847)
			(xy 124.223377 -225.972932) (xy 124.232416 -225.97237) (xy 124.256154 -225.969954) (xy 124.303806 -225.967415)
			(xy 124.327666 -225.96729) (xy 124.351526 -225.967404) (xy 124.399179 -225.969947) (xy 124.422916 -225.97237)
			(xy 124.431972 -225.973017) (xy 124.449575 -225.968618) (xy 124.464526 -225.958339) (xy 124.474934 -225.943478)
			(xy 124.477526 -225.934778) (xy 124.484886 -225.90847) (xy 124.507033 -225.858536) (xy 124.537094 -225.812926)
			(xy 124.574249 -225.772884) (xy 124.617485 -225.7395) (xy 124.665624 -225.713684) (xy 124.717355 -225.696139)
			(xy 124.771268 -225.687345) (xy 124.798582 -225.686874) (xy 124.819664 -225.686874) (xy 125.049788 -225.45675)
			(xy 125.018546 -225.420936) (xy 125.003197 -225.402777) (xy 124.97733 -225.362881) (xy 124.957452 -225.319688)
			(xy 124.943974 -225.274091) (xy 124.937175 -225.227032) (xy 124.936758 -225.203258) (xy 124.937367 -225.175277)
			(xy 124.946811 -225.120117) (xy 124.955554 -225.09353) (xy 124.963174 -225.071432) (xy 124.759466 -224.718626)
			(xy 124.736606 -224.714308) (xy 124.711678 -224.709156) (xy 124.66368 -224.692211) (xy 124.618849 -224.668105)
			(xy 124.578246 -224.637408) (xy 124.542831 -224.600846) (xy 124.513444 -224.559286) (xy 124.490778 -224.513709)
			(xy 124.475372 -224.465195) (xy 124.467589 -224.414893) (xy 124.467112 -224.389442) (xy 124.467621 -224.363475)
			(xy 124.475746 -224.31218) (xy 124.491794 -224.262787) (xy 124.515372 -224.216513) (xy 124.545898 -224.174497)
			(xy 124.582621 -224.137774) (xy 124.624637 -224.107248) (xy 124.670911 -224.08367) (xy 124.720304 -224.067622)
			(xy 124.771599 -224.059497) (xy 124.823533 -224.059497) (xy 124.874828 -224.067622) (xy 124.924221 -224.08367)
			(xy 124.970495 -224.107248) (xy 125.012511 -224.137774) (xy 125.049234 -224.174497) (xy 125.07976 -224.216513)
			(xy 125.103338 -224.262787) (xy 125.119386 -224.31218) (xy 125.127511 -224.363475) (xy 125.12802 -224.389442)
			(xy 125.127412 -224.417423) (xy 125.11797 -224.472584) (xy 125.109224 -224.49917) (xy 125.101604 -224.521268)
			(xy 125.305312 -224.874074) (xy 125.328172 -224.878392) (xy 125.356961 -224.884446) (xy 125.411938 -224.905367)
			(xy 125.462334 -224.935704) (xy 125.48489 -224.954592) (xy 125.520704 -224.985834) (xy 125.645418 -224.86112)
			(xy 125.655186 -224.850667) (xy 125.669006 -224.825632) (xy 125.675339 -224.797746) (xy 125.673691 -224.769198)
			(xy 125.664189 -224.742226) (xy 125.647579 -224.718948) (xy 125.625165 -224.70119) (xy 125.612144 -224.695258)
			(xy 125.589708 -224.685592) (xy 125.547723 -224.66062) (xy 125.509872 -224.629739) (xy 125.476981 -224.593621)
			(xy 125.449765 -224.553054) (xy 125.428819 -224.508922) (xy 125.414599 -224.462187) (xy 125.407416 -224.413867)
			(xy 125.406912 -224.389442) (xy 125.407385 -224.363995) (xy 125.415193 -224.313704) (xy 125.430617 -224.265204)
			(xy 125.453292 -224.219641) (xy 125.482681 -224.178091) (xy 125.518091 -224.141535) (xy 125.558686 -224.110839)
			(xy 125.603505 -224.086727) (xy 125.651489 -224.069768) (xy 125.676406 -224.064576) (xy 125.699266 -224.060258)
			(xy 125.902974 -223.707198) (xy 125.895354 -223.685354) (xy 125.886557 -223.65878) (xy 125.877101 -223.603612)
			(xy 125.876558 -223.575626) (xy 125.877067 -223.549659) (xy 125.885192 -223.498364) (xy 125.90124 -223.448971)
			(xy 125.924818 -223.402697) (xy 125.955344 -223.360681) (xy 125.992067 -223.323958) (xy 126.034083 -223.293432)
			(xy 126.080357 -223.269854) (xy 126.12975 -223.253806) (xy 126.181045 -223.245681) (xy 126.232979 -223.245681)
			(xy 126.284274 -223.253806) (xy 126.333667 -223.269854) (xy 126.379941 -223.293432) (xy 126.421957 -223.323958)
			(xy 126.45868 -223.360681) (xy 126.489206 -223.402697) (xy 126.512784 -223.448971) (xy 126.528832 -223.498364)
			(xy 126.536957 -223.549659) (xy 126.537466 -223.575626) (xy 126.536996 -223.601076) (xy 126.529192 -223.651374)
			(xy 126.513772 -223.699882) (xy 126.491102 -223.745455) (xy 126.461715 -223.787015) (xy 126.426308 -223.823581)
			(xy 126.385714 -223.85429) (xy 126.340895 -223.878415) (xy 126.292908 -223.895387) (xy 126.267972 -223.900492)
			(xy 126.244858 -223.90481) (xy 126.041404 -224.257616) (xy 126.049024 -224.279714) (xy 126.053353 -224.292284)
			(xy 126.060219 -224.317969) (xy 126.06274 -224.331022) (xy 126.065534 -224.34677) (xy 126.112524 -224.394014)
			(xy 126.72314 -223.783398) (xy 126.72314 -223.14281) (xy 126.722673 -223.132893) (xy 126.715158 -223.114537)
			(xy 126.701245 -223.1004) (xy 126.683011 -223.092592) (xy 126.673102 -223.09201) (xy 126.647349 -223.091197)
			(xy 126.596554 -223.08257) (xy 126.547714 -223.066163) (xy 126.502012 -223.042375) (xy 126.460556 -223.011782)
			(xy 126.424351 -222.975124) (xy 126.394274 -222.933292) (xy 126.371054 -222.887299) (xy 126.355254 -222.838259)
			(xy 126.347258 -222.787361) (xy 126.347258 -222.735838) (xy 126.355255 -222.68494) (xy 126.371054 -222.6359)
			(xy 126.394274 -222.589907) (xy 126.424351 -222.548075) (xy 126.460557 -222.511418) (xy 126.502013 -222.480824)
			(xy 126.547715 -222.457036) (xy 126.596555 -222.44063) (xy 126.64735 -222.432003) (xy 126.673102 -222.431102)
			(xy 126.683003 -222.430477) (xy 126.701223 -222.422676) (xy 126.715127 -222.408552) (xy 126.722639 -222.390212)
			(xy 126.72314 -222.380302) (xy 126.72314 -221.515178) (xy 126.722667 -221.505265) (xy 126.715146 -221.48692)
			(xy 126.701235 -221.472793) (xy 126.683007 -221.464991) (xy 126.673102 -221.464378) (xy 126.647343 -221.463572)
			(xy 126.596533 -221.454956) (xy 126.547678 -221.438555) (xy 126.501962 -221.414767) (xy 126.460493 -221.38417)
			(xy 126.424278 -221.347506) (xy 126.394195 -221.305663) (xy 126.370973 -221.259657) (xy 126.355175 -221.210603)
			(xy 126.347186 -221.159691) (xy 126.346712 -221.133924) (xy 126.347323 -221.105944) (xy 126.356771 -221.050785)
			(xy 126.365508 -221.024196) (xy 126.373128 -221.002098) (xy 126.16942 -220.649038) (xy 126.146306 -220.64472)
			(xy 126.121363 -220.639581) (xy 126.073333 -220.622659) (xy 126.028468 -220.598568) (xy 125.987829 -220.56788)
			(xy 125.95238 -220.53132) (xy 125.922959 -220.489755) (xy 125.900263 -220.444168) (xy 125.88483 -220.395639)
			(xy 125.877025 -220.345316) (xy 125.876558 -220.319854) (xy 125.877067 -220.293887) (xy 125.885192 -220.242592)
			(xy 125.90124 -220.193199) (xy 125.924818 -220.146925) (xy 125.955344 -220.104909) (xy 125.992067 -220.068186)
			(xy 126.034083 -220.03766) (xy 126.080357 -220.014082) (xy 126.12975 -219.998034) (xy 126.181045 -219.989909)
			(xy 126.232979 -219.989909) (xy 126.284274 -219.998034) (xy 126.333667 -220.014082) (xy 126.379941 -220.03766)
			(xy 126.421957 -220.068186) (xy 126.45868 -220.104909) (xy 126.489206 -220.146925) (xy 126.512784 -220.193199)
			(xy 126.528832 -220.242592) (xy 126.536957 -220.293887) (xy 126.537466 -220.319854) (xy 126.536903 -220.347761)
			(xy 126.527579 -220.402791) (xy 126.518924 -220.429328) (xy 126.51105 -220.451172) (xy 126.533656 -220.490288)
			(xy 126.541503 -220.502845) (xy 126.563047 -220.52314) (xy 126.589504 -220.536408) (xy 126.618654 -220.541537)
			(xy 126.648051 -220.538097) (xy 126.675229 -220.526375) (xy 126.697907 -220.507356) (xy 126.714182 -220.482635)
			(xy 126.72269 -220.454286) (xy 126.72314 -220.439488) (xy 126.72314 -219.887292) (xy 126.72267 -219.877377)
			(xy 126.715151 -219.859027) (xy 126.701239 -219.844896) (xy 126.683009 -219.837091) (xy 126.673102 -219.836492)
			(xy 126.647343 -219.835679) (xy 126.596535 -219.82705) (xy 126.547683 -219.810639) (xy 126.501969 -219.786845)
			(xy 126.460503 -219.756244) (xy 126.424289 -219.719578) (xy 126.394204 -219.677736) (xy 126.370979 -219.631731)
			(xy 126.355175 -219.582679) (xy 126.347176 -219.531768) (xy 126.347176 -219.480233) (xy 126.355175 -219.429322)
			(xy 126.370978 -219.38027) (xy 126.394204 -219.334265) (xy 126.424288 -219.292423) (xy 126.460502 -219.255756)
			(xy 126.501968 -219.225155) (xy 126.547682 -219.201361) (xy 126.596534 -219.18495) (xy 126.647342 -219.176321)
			(xy 126.673102 -219.175584) (xy 126.683002 -219.174959) (xy 126.701218 -219.167158) (xy 126.715118 -219.153033)
			(xy 126.722625 -219.134693) (xy 126.72314 -219.124784) (xy 126.72314 -218.25966) (xy 126.722664 -218.249749)
			(xy 126.71514 -218.23141) (xy 126.701229 -218.217289) (xy 126.683005 -218.20949) (xy 126.673102 -218.20886)
			(xy 126.64734 -218.208055) (xy 126.596526 -218.199438) (xy 126.547666 -218.183038) (xy 126.501943 -218.159252)
			(xy 126.460468 -218.128657) (xy 126.424245 -218.091993) (xy 126.394152 -218.050151) (xy 126.37092 -218.004145)
			(xy 126.355112 -217.95509) (xy 126.34711 -217.904176) (xy 126.346712 -217.878406) (xy 126.347325 -217.850426)
			(xy 126.356776 -217.795268) (xy 126.365508 -217.768678) (xy 126.373128 -217.74658) (xy 126.16942 -217.39352)
			(xy 126.146306 -217.389202) (xy 126.121364 -217.384063) (xy 126.073335 -217.36714) (xy 126.028471 -217.343049)
			(xy 125.987834 -217.312361) (xy 125.952387 -217.275801) (xy 125.922968 -217.234235) (xy 125.900275 -217.188648)
			(xy 125.884844 -217.140119) (xy 125.877041 -217.089798) (xy 125.876558 -217.064336) (xy 125.877067 -217.038369)
			(xy 125.885192 -216.987074) (xy 125.90124 -216.937681) (xy 125.924818 -216.891407) (xy 125.955344 -216.849391)
			(xy 125.992067 -216.812668) (xy 126.034083 -216.782142) (xy 126.080357 -216.758564) (xy 126.12975 -216.742516)
			(xy 126.181045 -216.734391) (xy 126.232979 -216.734391) (xy 126.284274 -216.742516) (xy 126.333667 -216.758564)
			(xy 126.379941 -216.782142) (xy 126.421957 -216.812668) (xy 126.45868 -216.849391) (xy 126.489206 -216.891407)
			(xy 126.512784 -216.937681) (xy 126.528832 -216.987074) (xy 126.536957 -217.038369) (xy 126.537466 -217.064336)
			(xy 126.536904 -217.092243) (xy 126.527583 -217.147274) (xy 126.518924 -217.17381) (xy 126.51105 -217.195654)
			(xy 126.533656 -217.23477) (xy 126.541502 -217.247328) (xy 126.563044 -217.267626) (xy 126.589501 -217.280898)
			(xy 126.618652 -217.286028) (xy 126.64805 -217.282588) (xy 126.675228 -217.270865) (xy 126.697906 -217.251843)
			(xy 126.714179 -217.22712) (xy 126.722683 -217.198769) (xy 126.72314 -217.18397) (xy 126.72314 -216.631774)
			(xy 126.722667 -216.621861) (xy 126.715145 -216.603517) (xy 126.701233 -216.589392) (xy 126.683007 -216.581591)
			(xy 126.673102 -216.580974) (xy 126.647344 -216.580161) (xy 126.596539 -216.571532) (xy 126.547689 -216.555123)
			(xy 126.501979 -216.53133) (xy 126.460514 -216.50073) (xy 126.424302 -216.464066) (xy 126.394219 -216.422226)
			(xy 126.370995 -216.376224) (xy 126.355192 -216.327174) (xy 126.347194 -216.276266) (xy 126.347194 -216.224734)
			(xy 126.355192 -216.173826) (xy 126.370995 -216.124777) (xy 126.394219 -216.078774) (xy 126.424302 -216.036934)
			(xy 126.460514 -216.00027) (xy 126.501978 -215.969671) (xy 126.547689 -215.945878) (xy 126.596539 -215.929468)
			(xy 126.647343 -215.920839) (xy 126.673102 -215.920066) (xy 126.683001 -215.919441) (xy 126.701214 -215.911639)
			(xy 126.715109 -215.897513) (xy 126.72261 -215.879173) (xy 126.72314 -215.869266) (xy 126.72314 -215.176608)
			(xy 126.222252 -214.67572) (xy 126.211267 -214.665493) (xy 126.184807 -214.651358) (xy 126.155383 -214.645514)
			(xy 126.125529 -214.648464) (xy 126.097818 -214.659955) (xy 126.074637 -214.678997) (xy 126.057983 -214.703948)
			(xy 126.053088 -214.718138) (xy 126.045163 -214.74268) (xy 126.022774 -214.789138) (xy 125.993442 -214.831555)
			(xy 125.95788 -214.868904) (xy 125.916949 -214.900277) (xy 125.871644 -214.924914) (xy 125.823062 -214.942216)
			(xy 125.797818 -214.9475) (xy 125.774958 -214.951818) (xy 125.57125 -215.304878) (xy 125.57887 -215.326976)
			(xy 125.587664 -215.35355) (xy 125.597114 -215.408718) (xy 125.597666 -215.436704) (xy 125.597157 -215.462671)
			(xy 125.589032 -215.513966) (xy 125.572984 -215.563359) (xy 125.549406 -215.609633) (xy 125.51888 -215.651649)
			(xy 125.482157 -215.688372) (xy 125.440141 -215.718898) (xy 125.393867 -215.742476) (xy 125.344474 -215.758524)
			(xy 125.293179 -215.766649) (xy 125.241245 -215.766649) (xy 125.18995 -215.758524) (xy 125.140557 -215.742476)
			(xy 125.094283 -215.718898) (xy 125.052267 -215.688372) (xy 125.015544 -215.651649) (xy 124.985018 -215.609633)
			(xy 124.96144 -215.563359) (xy 124.945392 -215.513966) (xy 124.937267 -215.462671) (xy 124.936758 -215.436704)
			(xy 124.937234 -215.411258) (xy 124.945046 -215.360969) (xy 124.960473 -215.31247) (xy 124.983148 -215.266908)
			(xy 125.012537 -215.225359) (xy 125.047946 -215.188804) (xy 125.088537 -215.158106) (xy 125.133353 -215.13399)
			(xy 125.181335 -215.117026) (xy 125.206252 -215.111838) (xy 125.229112 -215.10752) (xy 125.43282 -214.75446)
			(xy 125.4252 -214.732362) (xy 125.418625 -214.712772) (xy 125.409835 -214.672395) (xy 125.407674 -214.651844)
			(xy 125.405765 -214.636896) (xy 125.394406 -214.609002) (xy 125.375414 -214.585626) (xy 125.350437 -214.568796)
			(xy 125.32164 -214.559971) (xy 125.306582 -214.559388) (xy 125.227334 -214.559388) (xy 125.212268 -214.559929)
			(xy 125.183447 -214.568725) (xy 125.158455 -214.585559) (xy 125.139473 -214.608961) (xy 125.128158 -214.636888)
			(xy 125.126242 -214.651844) (xy 125.123468 -214.677495) (xy 125.110978 -214.727552) (xy 125.09086 -214.775061)
			(xy 125.063604 -214.818865) (xy 125.029872 -214.857902) (xy 124.990483 -214.891223) (xy 124.946395 -214.918018)
			(xy 124.898679 -214.937637) (xy 124.848493 -214.949602) (xy 124.797058 -214.953622) (xy 124.745623 -214.949602)
			(xy 124.695437 -214.937637) (xy 124.647721 -214.918018) (xy 124.603633 -214.891223) (xy 124.564244 -214.857902)
			(xy 124.530512 -214.818865) (xy 124.503256 -214.775061) (xy 124.483138 -214.727552) (xy 124.470648 -214.677495)
			(xy 124.467874 -214.651844) (xy 124.465965 -214.636896) (xy 124.454606 -214.609002) (xy 124.435614 -214.585626)
			(xy 124.410637 -214.568796) (xy 124.38184 -214.559971) (xy 124.366782 -214.559388) (xy 124.287534 -214.559388)
			(xy 124.272468 -214.559929) (xy 124.243647 -214.568725) (xy 124.218655 -214.585559) (xy 124.199673 -214.608961)
			(xy 124.188358 -214.636888) (xy 124.186442 -214.651844) (xy 124.183553 -214.678497) (xy 124.170259 -214.730431)
			(xy 124.148761 -214.77954) (xy 124.119621 -214.824538) (xy 124.083604 -214.864245) (xy 124.041653 -214.897621)
			(xy 123.994867 -214.923792) (xy 123.944471 -214.942072) (xy 123.918218 -214.9475) (xy 123.895358 -214.951818)
			(xy 123.69165 -215.304878) (xy 123.69927 -215.326976) (xy 123.708064 -215.35355) (xy 123.717514 -215.408718)
			(xy 123.718066 -215.436704) (xy 123.717557 -215.462671) (xy 123.709432 -215.513966) (xy 123.693384 -215.563359)
			(xy 123.669806 -215.609633) (xy 123.63928 -215.651649) (xy 123.602557 -215.688372) (xy 123.560541 -215.718898)
			(xy 123.514267 -215.742476) (xy 123.464874 -215.758524) (xy 123.413579 -215.766649) (xy 123.361645 -215.766649)
			(xy 123.31035 -215.758524) (xy 123.260957 -215.742476) (xy 123.214683 -215.718898) (xy 123.172667 -215.688372)
			(xy 123.135944 -215.651649) (xy 123.105418 -215.609633) (xy 123.08184 -215.563359) (xy 123.065792 -215.513966)
			(xy 123.057667 -215.462671) (xy 123.057158 -215.436704) (xy 123.057634 -215.411258) (xy 123.065446 -215.360969)
			(xy 123.080873 -215.31247) (xy 123.103548 -215.266908) (xy 123.132937 -215.225359) (xy 123.168346 -215.188804)
			(xy 123.208937 -215.158106) (xy 123.253753 -215.13399) (xy 123.301735 -215.117026) (xy 123.326652 -215.111838)
			(xy 123.349512 -215.10752) (xy 123.55322 -214.75446) (xy 123.5456 -214.732362) (xy 123.539025 -214.712772)
			(xy 123.530235 -214.672395) (xy 123.528074 -214.651844) (xy 123.526165 -214.636896) (xy 123.514806 -214.609002)
			(xy 123.495814 -214.585626) (xy 123.470837 -214.568796) (xy 123.44204 -214.559971) (xy 123.426982 -214.559388)
			(xy 123.347734 -214.559388) (xy 123.332668 -214.559929) (xy 123.303847 -214.568725) (xy 123.278855 -214.585559)
			(xy 123.259873 -214.608961) (xy 123.248558 -214.636888) (xy 123.246642 -214.651844) (xy 123.243868 -214.677495)
			(xy 123.231378 -214.727552) (xy 123.21126 -214.775061) (xy 123.184004 -214.818865) (xy 123.150272 -214.857902)
			(xy 123.110883 -214.891223) (xy 123.066795 -214.918018) (xy 123.019079 -214.937637) (xy 122.968893 -214.949602)
			(xy 122.917458 -214.953622) (xy 122.866023 -214.949602) (xy 122.815837 -214.937637) (xy 122.768121 -214.918018)
			(xy 122.724033 -214.891223) (xy 122.684644 -214.857902) (xy 122.650912 -214.818865) (xy 122.623656 -214.775061)
			(xy 122.603538 -214.727552) (xy 122.591048 -214.677495) (xy 122.588274 -214.651844) (xy 122.586365 -214.636896)
			(xy 122.575006 -214.609002) (xy 122.556014 -214.585626) (xy 122.531037 -214.568796) (xy 122.50224 -214.559971)
			(xy 122.487182 -214.559388) (xy 122.407934 -214.559388) (xy 122.392868 -214.559929) (xy 122.364047 -214.568725)
			(xy 122.339055 -214.585559) (xy 122.320073 -214.608961) (xy 122.308758 -214.636888) (xy 122.306842 -214.651844)
			(xy 122.303953 -214.678497) (xy 122.290659 -214.730431) (xy 122.269161 -214.77954) (xy 122.240021 -214.824538)
			(xy 122.204004 -214.864245) (xy 122.162053 -214.897621) (xy 122.115267 -214.923792) (xy 122.064871 -214.942072)
			(xy 122.038618 -214.9475) (xy 122.015758 -214.951818) (xy 121.81205 -215.304878) (xy 121.81967 -215.326976)
			(xy 121.828464 -215.35355) (xy 121.837914 -215.408718) (xy 121.838466 -215.436704) (xy 121.837957 -215.462671)
			(xy 121.829832 -215.513966) (xy 121.813784 -215.563359) (xy 121.790206 -215.609633) (xy 121.75968 -215.651649)
			(xy 121.722957 -215.688372) (xy 121.680941 -215.718898) (xy 121.634667 -215.742476) (xy 121.585274 -215.758524)
			(xy 121.533979 -215.766649) (xy 121.482045 -215.766649) (xy 121.43075 -215.758524) (xy 121.381357 -215.742476)
			(xy 121.335083 -215.718898) (xy 121.293067 -215.688372) (xy 121.256344 -215.651649) (xy 121.225818 -215.609633)
			(xy 121.20224 -215.563359) (xy 121.186192 -215.513966) (xy 121.178067 -215.462671) (xy 121.177558 -215.436704)
			(xy 121.178034 -215.411258) (xy 121.185846 -215.360969) (xy 121.201273 -215.31247) (xy 121.223948 -215.266908)
			(xy 121.253337 -215.225359) (xy 121.288746 -215.188804) (xy 121.329337 -215.158106) (xy 121.374153 -215.13399)
			(xy 121.422135 -215.117026) (xy 121.447052 -215.111838) (xy 121.469912 -215.10752) (xy 121.67362 -214.75446)
			(xy 121.666 -214.732362) (xy 121.659425 -214.712772) (xy 121.650635 -214.672395) (xy 121.648474 -214.651844)
			(xy 121.646565 -214.636896) (xy 121.635206 -214.609002) (xy 121.616214 -214.585626) (xy 121.591237 -214.568796)
			(xy 121.56244 -214.559971) (xy 121.547382 -214.559388) (xy 121.468134 -214.559388) (xy 121.453068 -214.559929)
			(xy 121.424247 -214.568725) (xy 121.399255 -214.585559) (xy 121.380273 -214.608961) (xy 121.368958 -214.636888)
			(xy 121.367042 -214.651844) (xy 121.364268 -214.677495) (xy 121.351778 -214.727552) (xy 121.33166 -214.775061)
			(xy 121.304404 -214.818865) (xy 121.270672 -214.857902) (xy 121.231283 -214.891223) (xy 121.187195 -214.918018)
			(xy 121.139479 -214.937637) (xy 121.089293 -214.949602) (xy 121.037858 -214.953622) (xy 120.986423 -214.949602)
			(xy 120.936237 -214.937637) (xy 120.888521 -214.918018) (xy 120.844433 -214.891223) (xy 120.805044 -214.857902)
			(xy 120.771312 -214.818865) (xy 120.744056 -214.775061) (xy 120.723938 -214.727552) (xy 120.711448 -214.677495)
			(xy 120.708674 -214.651844) (xy 120.706765 -214.636896) (xy 120.695406 -214.609002) (xy 120.676414 -214.585626)
			(xy 120.651437 -214.568796) (xy 120.62264 -214.559971) (xy 120.607582 -214.559388) (xy 120.528334 -214.559388)
			(xy 120.513268 -214.559929) (xy 120.484447 -214.568725) (xy 120.459455 -214.585559) (xy 120.440473 -214.608961)
			(xy 120.429158 -214.636888) (xy 120.427242 -214.651844) (xy 120.424353 -214.678497) (xy 120.411059 -214.730431)
			(xy 120.389561 -214.77954) (xy 120.360421 -214.824538) (xy 120.324404 -214.864245) (xy 120.282453 -214.897621)
			(xy 120.235667 -214.923792) (xy 120.185271 -214.942072) (xy 120.159018 -214.9475) (xy 120.136158 -214.951818)
			(xy 119.93245 -215.304878) (xy 119.94007 -215.326976) (xy 119.948864 -215.35355) (xy 119.958314 -215.408718)
			(xy 119.958866 -215.436704) (xy 119.958403 -215.462163) (xy 119.950602 -215.512481) (xy 119.935172 -215.561005)
			(xy 119.912476 -215.606586) (xy 119.883054 -215.648144) (xy 119.847603 -215.684693) (xy 119.806961 -215.715368)
			(xy 119.762093 -215.739443) (xy 119.714062 -215.756346) (xy 119.664006 -215.765676) (xy 119.638572 -215.766904)
			(xy 119.622903 -215.767951) (xy 119.593296 -215.778365) (xy 119.568246 -215.797275) (xy 119.550118 -215.822896)
			(xy 119.540622 -215.852811) (xy 119.54002 -215.868504) (xy 119.54002 -216.276487) (xy 119.768621 -216.276487)
			(xy 119.768621 -216.224553) (xy 119.776746 -216.173258) (xy 119.792794 -216.123865) (xy 119.816372 -216.077591)
			(xy 119.846898 -216.035575) (xy 119.883621 -215.998852) (xy 119.925637 -215.968326) (xy 119.971911 -215.944748)
			(xy 120.021304 -215.9287) (xy 120.072599 -215.920575) (xy 120.124533 -215.920575) (xy 120.175828 -215.9287)
			(xy 120.225221 -215.944748) (xy 120.271495 -215.968326) (xy 120.313511 -215.998852) (xy 120.350234 -216.035575)
			(xy 120.38076 -216.077591) (xy 120.404338 -216.123865) (xy 120.420386 -216.173258) (xy 120.428511 -216.224553)
			(xy 120.42902 -216.25052) (xy 120.428511 -216.276487) (xy 120.708421 -216.276487) (xy 120.708421 -216.224553)
			(xy 120.716546 -216.173258) (xy 120.732594 -216.123865) (xy 120.756172 -216.077591) (xy 120.786698 -216.035575)
			(xy 120.823421 -215.998852) (xy 120.865437 -215.968326) (xy 120.911711 -215.944748) (xy 120.961104 -215.9287)
			(xy 121.012399 -215.920575) (xy 121.064333 -215.920575) (xy 121.115628 -215.9287) (xy 121.165021 -215.944748)
			(xy 121.211295 -215.968326) (xy 121.253311 -215.998852) (xy 121.290034 -216.035575) (xy 121.32056 -216.077591)
			(xy 121.344138 -216.123865) (xy 121.360186 -216.173258) (xy 121.368311 -216.224553) (xy 121.36882 -216.25052)
			(xy 121.368311 -216.276487) (xy 121.648221 -216.276487) (xy 121.648221 -216.224553) (xy 121.656346 -216.173258)
			(xy 121.672394 -216.123865) (xy 121.695972 -216.077591) (xy 121.726498 -216.035575) (xy 121.763221 -215.998852)
			(xy 121.805237 -215.968326) (xy 121.851511 -215.944748) (xy 121.900904 -215.9287) (xy 121.952199 -215.920575)
			(xy 122.004133 -215.920575) (xy 122.055428 -215.9287) (xy 122.104821 -215.944748) (xy 122.151095 -215.968326)
			(xy 122.193111 -215.998852) (xy 122.229834 -216.035575) (xy 122.26036 -216.077591) (xy 122.283938 -216.123865)
			(xy 122.299986 -216.173258) (xy 122.308111 -216.224553) (xy 122.30862 -216.25052) (xy 122.308111 -216.276487)
			(xy 122.588021 -216.276487) (xy 122.588021 -216.224553) (xy 122.596146 -216.173258) (xy 122.612194 -216.123865)
			(xy 122.635772 -216.077591) (xy 122.666298 -216.035575) (xy 122.703021 -215.998852) (xy 122.745037 -215.968326)
			(xy 122.791311 -215.944748) (xy 122.840704 -215.9287) (xy 122.891999 -215.920575) (xy 122.943933 -215.920575)
			(xy 122.995228 -215.9287) (xy 123.044621 -215.944748) (xy 123.090895 -215.968326) (xy 123.132911 -215.998852)
			(xy 123.169634 -216.035575) (xy 123.20016 -216.077591) (xy 123.223738 -216.123865) (xy 123.239786 -216.173258)
			(xy 123.247911 -216.224553) (xy 123.24842 -216.25052) (xy 123.247911 -216.276487) (xy 123.527821 -216.276487)
			(xy 123.527821 -216.224553) (xy 123.535946 -216.173258) (xy 123.551994 -216.123865) (xy 123.575572 -216.077591)
			(xy 123.606098 -216.035575) (xy 123.642821 -215.998852) (xy 123.684837 -215.968326) (xy 123.731111 -215.944748)
			(xy 123.780504 -215.9287) (xy 123.831799 -215.920575) (xy 123.883733 -215.920575) (xy 123.935028 -215.9287)
			(xy 123.984421 -215.944748) (xy 124.030695 -215.968326) (xy 124.072711 -215.998852) (xy 124.109434 -216.035575)
			(xy 124.13996 -216.077591) (xy 124.163538 -216.123865) (xy 124.179586 -216.173258) (xy 124.187711 -216.224553)
			(xy 124.18822 -216.25052) (xy 124.187711 -216.276487) (xy 124.467621 -216.276487) (xy 124.467621 -216.224553)
			(xy 124.475746 -216.173258) (xy 124.491794 -216.123865) (xy 124.515372 -216.077591) (xy 124.545898 -216.035575)
			(xy 124.582621 -215.998852) (xy 124.624637 -215.968326) (xy 124.670911 -215.944748) (xy 124.720304 -215.9287)
			(xy 124.771599 -215.920575) (xy 124.823533 -215.920575) (xy 124.874828 -215.9287) (xy 124.924221 -215.944748)
			(xy 124.970495 -215.968326) (xy 125.012511 -215.998852) (xy 125.049234 -216.035575) (xy 125.07976 -216.077591)
			(xy 125.103338 -216.123865) (xy 125.119386 -216.173258) (xy 125.127511 -216.224553) (xy 125.12802 -216.25052)
			(xy 125.127511 -216.276487) (xy 125.407421 -216.276487) (xy 125.407421 -216.224553) (xy 125.415546 -216.173258)
			(xy 125.431594 -216.123865) (xy 125.455172 -216.077591) (xy 125.485698 -216.035575) (xy 125.522421 -215.998852)
			(xy 125.564437 -215.968326) (xy 125.610711 -215.944748) (xy 125.660104 -215.9287) (xy 125.711399 -215.920575)
			(xy 125.763333 -215.920575) (xy 125.814628 -215.9287) (xy 125.864021 -215.944748) (xy 125.910295 -215.968326)
			(xy 125.952311 -215.998852) (xy 125.989034 -216.035575) (xy 126.01956 -216.077591) (xy 126.043138 -216.123865)
			(xy 126.059186 -216.173258) (xy 126.067311 -216.224553) (xy 126.06782 -216.25052) (xy 126.067311 -216.276487)
			(xy 126.059186 -216.327782) (xy 126.043138 -216.377175) (xy 126.01956 -216.423449) (xy 125.989034 -216.465465)
			(xy 125.952311 -216.502188) (xy 125.910295 -216.532714) (xy 125.864021 -216.556292) (xy 125.814628 -216.57234)
			(xy 125.763333 -216.580465) (xy 125.711399 -216.580465) (xy 125.660104 -216.57234) (xy 125.610711 -216.556292)
			(xy 125.564437 -216.532714) (xy 125.522421 -216.502188) (xy 125.485698 -216.465465) (xy 125.455172 -216.423449)
			(xy 125.431594 -216.377175) (xy 125.415546 -216.327782) (xy 125.407421 -216.276487) (xy 125.127511 -216.276487)
			(xy 125.119386 -216.327782) (xy 125.103338 -216.377175) (xy 125.07976 -216.423449) (xy 125.049234 -216.465465)
			(xy 125.012511 -216.502188) (xy 124.970495 -216.532714) (xy 124.924221 -216.556292) (xy 124.874828 -216.57234)
			(xy 124.823533 -216.580465) (xy 124.771599 -216.580465) (xy 124.720304 -216.57234) (xy 124.670911 -216.556292)
			(xy 124.624637 -216.532714) (xy 124.582621 -216.502188) (xy 124.545898 -216.465465) (xy 124.515372 -216.423449)
			(xy 124.491794 -216.377175) (xy 124.475746 -216.327782) (xy 124.467621 -216.276487) (xy 124.187711 -216.276487)
			(xy 124.179586 -216.327782) (xy 124.163538 -216.377175) (xy 124.13996 -216.423449) (xy 124.109434 -216.465465)
			(xy 124.072711 -216.502188) (xy 124.030695 -216.532714) (xy 123.984421 -216.556292) (xy 123.935028 -216.57234)
			(xy 123.883733 -216.580465) (xy 123.831799 -216.580465) (xy 123.780504 -216.57234) (xy 123.731111 -216.556292)
			(xy 123.684837 -216.532714) (xy 123.642821 -216.502188) (xy 123.606098 -216.465465) (xy 123.575572 -216.423449)
			(xy 123.551994 -216.377175) (xy 123.535946 -216.327782) (xy 123.527821 -216.276487) (xy 123.247911 -216.276487)
			(xy 123.239786 -216.327782) (xy 123.223738 -216.377175) (xy 123.20016 -216.423449) (xy 123.169634 -216.465465)
			(xy 123.132911 -216.502188) (xy 123.090895 -216.532714) (xy 123.044621 -216.556292) (xy 122.995228 -216.57234)
			(xy 122.943933 -216.580465) (xy 122.891999 -216.580465) (xy 122.840704 -216.57234) (xy 122.791311 -216.556292)
			(xy 122.745037 -216.532714) (xy 122.703021 -216.502188) (xy 122.666298 -216.465465) (xy 122.635772 -216.423449)
			(xy 122.612194 -216.377175) (xy 122.596146 -216.327782) (xy 122.588021 -216.276487) (xy 122.308111 -216.276487)
			(xy 122.299986 -216.327782) (xy 122.283938 -216.377175) (xy 122.26036 -216.423449) (xy 122.229834 -216.465465)
			(xy 122.193111 -216.502188) (xy 122.151095 -216.532714) (xy 122.104821 -216.556292) (xy 122.055428 -216.57234)
			(xy 122.004133 -216.580465) (xy 121.952199 -216.580465) (xy 121.900904 -216.57234) (xy 121.851511 -216.556292)
			(xy 121.805237 -216.532714) (xy 121.763221 -216.502188) (xy 121.726498 -216.465465) (xy 121.695972 -216.423449)
			(xy 121.672394 -216.377175) (xy 121.656346 -216.327782) (xy 121.648221 -216.276487) (xy 121.368311 -216.276487)
			(xy 121.360186 -216.327782) (xy 121.344138 -216.377175) (xy 121.32056 -216.423449) (xy 121.290034 -216.465465)
			(xy 121.253311 -216.502188) (xy 121.211295 -216.532714) (xy 121.165021 -216.556292) (xy 121.115628 -216.57234)
			(xy 121.064333 -216.580465) (xy 121.012399 -216.580465) (xy 120.961104 -216.57234) (xy 120.911711 -216.556292)
			(xy 120.865437 -216.532714) (xy 120.823421 -216.502188) (xy 120.786698 -216.465465) (xy 120.756172 -216.423449)
			(xy 120.732594 -216.377175) (xy 120.716546 -216.327782) (xy 120.708421 -216.276487) (xy 120.428511 -216.276487)
			(xy 120.420386 -216.327782) (xy 120.404338 -216.377175) (xy 120.38076 -216.423449) (xy 120.350234 -216.465465)
			(xy 120.313511 -216.502188) (xy 120.271495 -216.532714) (xy 120.225221 -216.556292) (xy 120.175828 -216.57234)
			(xy 120.124533 -216.580465) (xy 120.072599 -216.580465) (xy 120.021304 -216.57234) (xy 119.971911 -216.556292)
			(xy 119.925637 -216.532714) (xy 119.883621 -216.502188) (xy 119.846898 -216.465465) (xy 119.816372 -216.423449)
			(xy 119.792794 -216.377175) (xy 119.776746 -216.327782) (xy 119.768621 -216.276487) (xy 119.54002 -216.276487)
			(xy 119.54002 -216.632536) (xy 119.540602 -216.648227) (xy 119.550124 -216.678129) (xy 119.568262 -216.703738)
			(xy 119.593308 -216.722646) (xy 119.622907 -216.733073) (xy 119.638572 -216.734136) (xy 119.664012 -216.735374)
			(xy 119.714082 -216.744702) (xy 119.762129 -216.761601) (xy 119.807014 -216.78567) (xy 119.847676 -216.81634)
			(xy 119.883152 -216.852884) (xy 119.912602 -216.894439) (xy 119.935328 -216.940019) (xy 119.950794 -216.988545)
			(xy 119.958632 -217.03887) (xy 119.95912 -217.064336) (xy 120.237758 -217.064336) (xy 120.238267 -217.038369)
			(xy 120.246392 -216.987074) (xy 120.26244 -216.937681) (xy 120.286018 -216.891407) (xy 120.316544 -216.849391)
			(xy 120.353267 -216.812668) (xy 120.395283 -216.782142) (xy 120.441557 -216.758564) (xy 120.49095 -216.742516)
			(xy 120.542245 -216.734391) (xy 120.594179 -216.734391) (xy 120.645474 -216.742516) (xy 120.694867 -216.758564)
			(xy 120.741141 -216.782142) (xy 120.783157 -216.812668) (xy 120.81988 -216.849391) (xy 120.850406 -216.891407)
			(xy 120.873984 -216.937681) (xy 120.890032 -216.987074) (xy 120.898157 -217.038369) (xy 120.898666 -217.064336)
			(xy 120.898165 -217.090303) (xy 121.178321 -217.090303) (xy 121.178321 -217.038369) (xy 121.186446 -216.987074)
			(xy 121.202494 -216.937681) (xy 121.226072 -216.891407) (xy 121.256598 -216.849391) (xy 121.293321 -216.812668)
			(xy 121.335337 -216.782142) (xy 121.381611 -216.758564) (xy 121.431004 -216.742516) (xy 121.482299 -216.734391)
			(xy 121.534233 -216.734391) (xy 121.585528 -216.742516) (xy 121.634921 -216.758564) (xy 121.681195 -216.782142)
			(xy 121.723211 -216.812668) (xy 121.759934 -216.849391) (xy 121.79046 -216.891407) (xy 121.814038 -216.937681)
			(xy 121.830086 -216.987074) (xy 121.838211 -217.038369) (xy 121.83872 -217.064336) (xy 122.117358 -217.064336)
			(xy 122.117867 -217.038369) (xy 122.125992 -216.987074) (xy 122.14204 -216.937681) (xy 122.165618 -216.891407)
			(xy 122.196144 -216.849391) (xy 122.232867 -216.812668) (xy 122.274883 -216.782142) (xy 122.321157 -216.758564)
			(xy 122.37055 -216.742516) (xy 122.421845 -216.734391) (xy 122.473779 -216.734391) (xy 122.525074 -216.742516)
			(xy 122.574467 -216.758564) (xy 122.620741 -216.782142) (xy 122.662757 -216.812668) (xy 122.69948 -216.849391)
			(xy 122.730006 -216.891407) (xy 122.753584 -216.937681) (xy 122.769632 -216.987074) (xy 122.777757 -217.038369)
			(xy 122.778266 -217.064336) (xy 122.777765 -217.090303) (xy 123.057921 -217.090303) (xy 123.057921 -217.038369)
			(xy 123.066046 -216.987074) (xy 123.082094 -216.937681) (xy 123.105672 -216.891407) (xy 123.136198 -216.849391)
			(xy 123.172921 -216.812668) (xy 123.214937 -216.782142) (xy 123.261211 -216.758564) (xy 123.310604 -216.742516)
			(xy 123.361899 -216.734391) (xy 123.413833 -216.734391) (xy 123.465128 -216.742516) (xy 123.514521 -216.758564)
			(xy 123.560795 -216.782142) (xy 123.602811 -216.812668) (xy 123.639534 -216.849391) (xy 123.67006 -216.891407)
			(xy 123.693638 -216.937681) (xy 123.709686 -216.987074) (xy 123.717811 -217.038369) (xy 123.71832 -217.064336)
			(xy 123.996958 -217.064336) (xy 123.997467 -217.038369) (xy 124.005592 -216.987074) (xy 124.02164 -216.937681)
			(xy 124.045218 -216.891407) (xy 124.075744 -216.849391) (xy 124.112467 -216.812668) (xy 124.154483 -216.782142)
			(xy 124.200757 -216.758564) (xy 124.25015 -216.742516) (xy 124.301445 -216.734391) (xy 124.353379 -216.734391)
			(xy 124.404674 -216.742516) (xy 124.454067 -216.758564) (xy 124.500341 -216.782142) (xy 124.542357 -216.812668)
			(xy 124.57908 -216.849391) (xy 124.609606 -216.891407) (xy 124.633184 -216.937681) (xy 124.649232 -216.987074)
			(xy 124.657357 -217.038369) (xy 124.657866 -217.064336) (xy 124.657365 -217.090303) (xy 124.937521 -217.090303)
			(xy 124.937521 -217.038369) (xy 124.945646 -216.987074) (xy 124.961694 -216.937681) (xy 124.985272 -216.891407)
			(xy 125.015798 -216.849391) (xy 125.052521 -216.812668) (xy 125.094537 -216.782142) (xy 125.140811 -216.758564)
			(xy 125.190204 -216.742516) (xy 125.241499 -216.734391) (xy 125.293433 -216.734391) (xy 125.344728 -216.742516)
			(xy 125.394121 -216.758564) (xy 125.440395 -216.782142) (xy 125.482411 -216.812668) (xy 125.519134 -216.849391)
			(xy 125.54966 -216.891407) (xy 125.573238 -216.937681) (xy 125.589286 -216.987074) (xy 125.597411 -217.038369)
			(xy 125.59792 -217.064336) (xy 125.597411 -217.090303) (xy 125.589286 -217.141598) (xy 125.573238 -217.190991)
			(xy 125.54966 -217.237265) (xy 125.519134 -217.279281) (xy 125.482411 -217.316004) (xy 125.440395 -217.34653)
			(xy 125.394121 -217.370108) (xy 125.344728 -217.386156) (xy 125.293433 -217.394281) (xy 125.241499 -217.394281)
			(xy 125.190204 -217.386156) (xy 125.140811 -217.370108) (xy 125.094537 -217.34653) (xy 125.052521 -217.316004)
			(xy 125.015798 -217.279281) (xy 124.985272 -217.237265) (xy 124.961694 -217.190991) (xy 124.945646 -217.141598)
			(xy 124.937521 -217.090303) (xy 124.657365 -217.090303) (xy 124.657327 -217.092245) (xy 124.648002 -217.147278)
			(xy 124.639324 -217.17381) (xy 124.63145 -217.195654) (xy 124.835666 -217.549222) (xy 124.858526 -217.55354)
			(xy 124.88344 -217.558742) (xy 124.931422 -217.575703) (xy 124.976238 -217.599816) (xy 125.016831 -217.630512)
			(xy 125.05224 -217.667066) (xy 125.081629 -217.708614) (xy 125.104305 -217.754174) (xy 125.119732 -217.802672)
			(xy 125.127545 -217.85296) (xy 125.12802 -217.878406) (xy 125.127511 -217.904373) (xy 125.119386 -217.955668)
			(xy 125.103338 -218.005061) (xy 125.07976 -218.051335) (xy 125.049234 -218.093351) (xy 125.012511 -218.130074)
			(xy 124.970495 -218.1606) (xy 124.924221 -218.184178) (xy 124.874828 -218.200226) (xy 124.823533 -218.208351)
			(xy 124.771599 -218.208351) (xy 124.720304 -218.200226) (xy 124.670911 -218.184178) (xy 124.624637 -218.1606)
			(xy 124.582621 -218.130074) (xy 124.545898 -218.093351) (xy 124.515372 -218.051335) (xy 124.491794 -218.005061)
			(xy 124.475746 -217.955668) (xy 124.467621 -217.904373) (xy 124.467112 -217.878406) (xy 124.467666 -217.85042)
			(xy 124.477115 -217.795252) (xy 124.485908 -217.768678) (xy 124.493528 -217.74658) (xy 124.28982 -217.39352)
			(xy 124.266706 -217.389202) (xy 124.241766 -217.384059) (xy 124.193742 -217.367128) (xy 124.148882 -217.343032)
			(xy 124.108249 -217.312342) (xy 124.072803 -217.275784) (xy 124.043382 -217.234221) (xy 124.020684 -217.188639)
			(xy 124.005245 -217.140115) (xy 123.99743 -217.089797) (xy 123.996958 -217.064336) (xy 123.71832 -217.064336)
			(xy 123.717811 -217.090303) (xy 123.709686 -217.141598) (xy 123.693638 -217.190991) (xy 123.67006 -217.237265)
			(xy 123.639534 -217.279281) (xy 123.602811 -217.316004) (xy 123.560795 -217.34653) (xy 123.514521 -217.370108)
			(xy 123.465128 -217.386156) (xy 123.413833 -217.394281) (xy 123.361899 -217.394281) (xy 123.310604 -217.386156)
			(xy 123.261211 -217.370108) (xy 123.214937 -217.34653) (xy 123.172921 -217.316004) (xy 123.136198 -217.279281)
			(xy 123.105672 -217.237265) (xy 123.082094 -217.190991) (xy 123.066046 -217.141598) (xy 123.057921 -217.090303)
			(xy 122.777765 -217.090303) (xy 122.777727 -217.092245) (xy 122.768402 -217.147278) (xy 122.759724 -217.17381)
			(xy 122.75185 -217.195654) (xy 122.956066 -217.549222) (xy 122.978926 -217.55354) (xy 123.00384 -217.558742)
			(xy 123.051822 -217.575703) (xy 123.096638 -217.599816) (xy 123.137231 -217.630512) (xy 123.17264 -217.667066)
			(xy 123.202029 -217.708614) (xy 123.224705 -217.754174) (xy 123.240132 -217.802672) (xy 123.247945 -217.85296)
			(xy 123.24842 -217.878406) (xy 123.247911 -217.904373) (xy 123.239786 -217.955668) (xy 123.223738 -218.005061)
			(xy 123.20016 -218.051335) (xy 123.169634 -218.093351) (xy 123.132911 -218.130074) (xy 123.090895 -218.1606)
			(xy 123.044621 -218.184178) (xy 122.995228 -218.200226) (xy 122.943933 -218.208351) (xy 122.891999 -218.208351)
			(xy 122.840704 -218.200226) (xy 122.791311 -218.184178) (xy 122.745037 -218.1606) (xy 122.703021 -218.130074)
			(xy 122.666298 -218.093351) (xy 122.635772 -218.051335) (xy 122.612194 -218.005061) (xy 122.596146 -217.955668)
			(xy 122.588021 -217.904373) (xy 122.587512 -217.878406) (xy 122.588066 -217.85042) (xy 122.597515 -217.795252)
			(xy 122.606308 -217.768678) (xy 122.613928 -217.74658) (xy 122.41022 -217.39352) (xy 122.387106 -217.389202)
			(xy 122.362166 -217.384059) (xy 122.314142 -217.367128) (xy 122.269282 -217.343032) (xy 122.228649 -217.312342)
			(xy 122.193203 -217.275784) (xy 122.163782 -217.234221) (xy 122.141084 -217.188639) (xy 122.125645 -217.140115)
			(xy 122.11783 -217.089797) (xy 122.117358 -217.064336) (xy 121.83872 -217.064336) (xy 121.838211 -217.090303)
			(xy 121.830086 -217.141598) (xy 121.814038 -217.190991) (xy 121.79046 -217.237265) (xy 121.759934 -217.279281)
			(xy 121.723211 -217.316004) (xy 121.681195 -217.34653) (xy 121.634921 -217.370108) (xy 121.585528 -217.386156)
			(xy 121.534233 -217.394281) (xy 121.482299 -217.394281) (xy 121.431004 -217.386156) (xy 121.381611 -217.370108)
			(xy 121.335337 -217.34653) (xy 121.293321 -217.316004) (xy 121.256598 -217.279281) (xy 121.226072 -217.237265)
			(xy 121.202494 -217.190991) (xy 121.186446 -217.141598) (xy 121.178321 -217.090303) (xy 120.898165 -217.090303)
			(xy 120.898127 -217.092245) (xy 120.888802 -217.147278) (xy 120.880124 -217.17381) (xy 120.87225 -217.195654)
			(xy 121.076466 -217.549222) (xy 121.099326 -217.55354) (xy 121.12424 -217.558742) (xy 121.172222 -217.575703)
			(xy 121.217038 -217.599816) (xy 121.257631 -217.630512) (xy 121.29304 -217.667066) (xy 121.322429 -217.708614)
			(xy 121.345105 -217.754174) (xy 121.360532 -217.802672) (xy 121.368345 -217.85296) (xy 121.36882 -217.878406)
			(xy 121.368311 -217.904373) (xy 121.360186 -217.955668) (xy 121.344138 -218.005061) (xy 121.32056 -218.051335)
			(xy 121.290034 -218.093351) (xy 121.253311 -218.130074) (xy 121.211295 -218.1606) (xy 121.165021 -218.184178)
			(xy 121.115628 -218.200226) (xy 121.064333 -218.208351) (xy 121.012399 -218.208351) (xy 120.961104 -218.200226)
			(xy 120.911711 -218.184178) (xy 120.865437 -218.1606) (xy 120.823421 -218.130074) (xy 120.786698 -218.093351)
			(xy 120.756172 -218.051335) (xy 120.732594 -218.005061) (xy 120.716546 -217.955668) (xy 120.708421 -217.904373)
			(xy 120.707912 -217.878406) (xy 120.708466 -217.85042) (xy 120.717915 -217.795252) (xy 120.726708 -217.768678)
			(xy 120.734328 -217.74658) (xy 120.53062 -217.39352) (xy 120.507506 -217.389202) (xy 120.482566 -217.384059)
			(xy 120.434542 -217.367128) (xy 120.389682 -217.343032) (xy 120.349049 -217.312342) (xy 120.313603 -217.275784)
			(xy 120.284182 -217.234221) (xy 120.261484 -217.188639) (xy 120.246045 -217.140115) (xy 120.23823 -217.089797)
			(xy 120.237758 -217.064336) (xy 119.95912 -217.064336) (xy 119.958676 -217.0888) (xy 119.95146 -217.137193)
			(xy 119.93719 -217.183994) (xy 119.916179 -217.228181) (xy 119.888885 -217.26879) (xy 119.855904 -217.304932)
			(xy 119.817957 -217.335818) (xy 119.775873 -217.360775) (xy 119.75338 -217.370406) (xy 119.739999 -217.376411)
			(xy 119.717138 -217.394763) (xy 119.700416 -217.418843) (xy 119.691203 -217.446674) (xy 119.690255 -217.475975)
			(xy 119.693436 -217.490294) (xy 119.698851 -217.511315) (xy 119.708632 -217.553612) (xy 119.712994 -217.574876)
			(xy 119.716598 -217.589674) (xy 119.731209 -217.61638) (xy 119.753035 -217.6376) (xy 119.780141 -217.651453)
			(xy 119.810124 -217.656713) (xy 119.840326 -217.652912) (xy 119.868071 -217.640387) (xy 119.879872 -217.630756)
			(xy 119.898069 -217.615231) (xy 119.938096 -217.589048) (xy 119.981483 -217.568913) (xy 120.027321 -217.55525)
			(xy 120.074651 -217.548344) (xy 120.098566 -217.547952) (xy 120.124537 -217.548432) (xy 120.17584 -217.556553)
			(xy 120.22524 -217.5726) (xy 120.271522 -217.596178) (xy 120.313546 -217.626706) (xy 120.350276 -217.663433)
			(xy 120.380807 -217.705454) (xy 120.404389 -217.751734) (xy 120.42044 -217.801133) (xy 120.428565 -217.852435)
			(xy 120.42902 -217.878406) (xy 120.428549 -217.903879) (xy 120.420728 -217.954221) (xy 120.405273 -218.002767)
			(xy 120.38255 -218.048365) (xy 120.353097 -218.089934) (xy 120.317612 -218.126491) (xy 120.276937 -218.157167)
			(xy 120.232036 -218.181237) (xy 120.183972 -218.19813) (xy 120.159018 -218.203272) (xy 120.135904 -218.20759)
			(xy 119.93245 -218.560396) (xy 119.94007 -218.582494) (xy 119.948862 -218.609068) (xy 119.95831 -218.664236)
			(xy 119.958866 -218.692222) (xy 121.177558 -218.692222) (xy 121.177965 -218.666768) (xy 121.185754 -218.616461)
			(xy 121.201169 -218.567943) (xy 121.223842 -218.522364) (xy 121.253239 -218.480803) (xy 121.288662 -218.444242)
			(xy 121.329274 -218.413547) (xy 121.374114 -218.389444) (xy 121.42212 -218.372505) (xy 121.447052 -218.367356)
			(xy 121.469912 -218.363038) (xy 121.673874 -218.00947) (xy 121.666254 -217.987626) (xy 121.657617 -217.96115)
			(xy 121.648292 -217.906249) (xy 121.647712 -217.878406) (xy 121.648221 -217.852439) (xy 121.656346 -217.801144)
			(xy 121.672394 -217.751751) (xy 121.695972 -217.705477) (xy 121.726498 -217.663461) (xy 121.763221 -217.626738)
			(xy 121.805237 -217.596212) (xy 121.851511 -217.572634) (xy 121.900904 -217.556586) (xy 121.952199 -217.548461)
			(xy 122.004133 -217.548461) (xy 122.055428 -217.556586) (xy 122.104821 -217.572634) (xy 122.151095 -217.596212)
			(xy 122.193111 -217.626738) (xy 122.229834 -217.663461) (xy 122.26036 -217.705477) (xy 122.283938 -217.751751)
			(xy 122.299986 -217.801144) (xy 122.308111 -217.852439) (xy 122.30862 -217.878406) (xy 122.308171 -217.903881)
			(xy 122.30035 -217.954227) (xy 122.284894 -218.002775) (xy 122.262169 -218.048376) (xy 122.232714 -218.089949)
			(xy 122.197227 -218.126507) (xy 122.156549 -218.157186) (xy 122.111645 -218.181258) (xy 122.063577 -218.198151)
			(xy 122.038618 -218.203272) (xy 122.015504 -218.20759) (xy 121.81205 -218.560396) (xy 121.81967 -218.582494)
			(xy 121.828405 -218.609083) (xy 121.837855 -218.664242) (xy 121.838466 -218.692222) (xy 123.057158 -218.692222)
			(xy 123.057565 -218.666768) (xy 123.065354 -218.616461) (xy 123.080769 -218.567943) (xy 123.103442 -218.522364)
			(xy 123.132839 -218.480803) (xy 123.168262 -218.444242) (xy 123.208874 -218.413547) (xy 123.253714 -218.389444)
			(xy 123.30172 -218.372505) (xy 123.326652 -218.367356) (xy 123.349512 -218.363038) (xy 123.553474 -218.00947)
			(xy 123.545854 -217.987626) (xy 123.537217 -217.96115) (xy 123.527892 -217.906249) (xy 123.527312 -217.878406)
			(xy 123.527821 -217.852439) (xy 123.535946 -217.801144) (xy 123.551994 -217.751751) (xy 123.575572 -217.705477)
			(xy 123.606098 -217.663461) (xy 123.642821 -217.626738) (xy 123.684837 -217.596212) (xy 123.731111 -217.572634)
			(xy 123.780504 -217.556586) (xy 123.831799 -217.548461) (xy 123.883733 -217.548461) (xy 123.935028 -217.556586)
			(xy 123.984421 -217.572634) (xy 124.030695 -217.596212) (xy 124.072711 -217.626738) (xy 124.109434 -217.663461)
			(xy 124.13996 -217.705477) (xy 124.163538 -217.751751) (xy 124.179586 -217.801144) (xy 124.187711 -217.852439)
			(xy 124.18822 -217.878406) (xy 124.187771 -217.903881) (xy 124.17995 -217.954227) (xy 124.164494 -218.002775)
			(xy 124.141769 -218.048376) (xy 124.112314 -218.089949) (xy 124.076827 -218.126507) (xy 124.036149 -218.157186)
			(xy 123.991245 -218.181258) (xy 123.943177 -218.198151) (xy 123.918218 -218.203272) (xy 123.895104 -218.20759)
			(xy 123.69165 -218.560396) (xy 123.69927 -218.582494) (xy 123.708005 -218.609083) (xy 123.717455 -218.664242)
			(xy 123.718066 -218.692222) (xy 124.936758 -218.692222) (xy 124.937165 -218.666768) (xy 124.944954 -218.616461)
			(xy 124.960369 -218.567943) (xy 124.983042 -218.522364) (xy 125.012439 -218.480803) (xy 125.047862 -218.444242)
			(xy 125.088474 -218.413547) (xy 125.133314 -218.389444) (xy 125.18132 -218.372505) (xy 125.206252 -218.367356)
			(xy 125.229112 -218.363038) (xy 125.433074 -218.00947) (xy 125.425454 -217.987626) (xy 125.416817 -217.96115)
			(xy 125.407492 -217.906249) (xy 125.406912 -217.878406) (xy 125.407421 -217.852439) (xy 125.415546 -217.801144)
			(xy 125.431594 -217.751751) (xy 125.455172 -217.705477) (xy 125.485698 -217.663461) (xy 125.522421 -217.626738)
			(xy 125.564437 -217.596212) (xy 125.610711 -217.572634) (xy 125.660104 -217.556586) (xy 125.711399 -217.548461)
			(xy 125.763333 -217.548461) (xy 125.814628 -217.556586) (xy 125.864021 -217.572634) (xy 125.910295 -217.596212)
			(xy 125.952311 -217.626738) (xy 125.989034 -217.663461) (xy 126.01956 -217.705477) (xy 126.043138 -217.751751)
			(xy 126.059186 -217.801144) (xy 126.067311 -217.852439) (xy 126.06782 -217.878406) (xy 126.067371 -217.903881)
			(xy 126.05955 -217.954227) (xy 126.044094 -218.002775) (xy 126.021369 -218.048376) (xy 125.991914 -218.089949)
			(xy 125.956427 -218.126507) (xy 125.915749 -218.157186) (xy 125.870845 -218.181258) (xy 125.822777 -218.198151)
			(xy 125.797818 -218.203272) (xy 125.774704 -218.20759) (xy 125.57125 -218.560396) (xy 125.57887 -218.582494)
			(xy 125.587605 -218.609083) (xy 125.597055 -218.664242) (xy 125.597666 -218.692222) (xy 125.597157 -218.718189)
			(xy 125.589032 -218.769484) (xy 125.572984 -218.818877) (xy 125.549406 -218.865151) (xy 125.51888 -218.907167)
			(xy 125.482157 -218.94389) (xy 125.440141 -218.974416) (xy 125.393867 -218.997994) (xy 125.344474 -219.014042)
			(xy 125.293179 -219.022167) (xy 125.241245 -219.022167) (xy 125.18995 -219.014042) (xy 125.140557 -218.997994)
			(xy 125.094283 -218.974416) (xy 125.052267 -218.94389) (xy 125.015544 -218.907167) (xy 124.985018 -218.865151)
			(xy 124.96144 -218.818877) (xy 124.945392 -218.769484) (xy 124.937267 -218.718189) (xy 124.936758 -218.692222)
			(xy 123.718066 -218.692222) (xy 123.717557 -218.718189) (xy 123.709432 -218.769484) (xy 123.693384 -218.818877)
			(xy 123.669806 -218.865151) (xy 123.63928 -218.907167) (xy 123.602557 -218.94389) (xy 123.560541 -218.974416)
			(xy 123.514267 -218.997994) (xy 123.464874 -219.014042) (xy 123.413579 -219.022167) (xy 123.361645 -219.022167)
			(xy 123.31035 -219.014042) (xy 123.260957 -218.997994) (xy 123.214683 -218.974416) (xy 123.172667 -218.94389)
			(xy 123.135944 -218.907167) (xy 123.105418 -218.865151) (xy 123.08184 -218.818877) (xy 123.065792 -218.769484)
			(xy 123.057667 -218.718189) (xy 123.057158 -218.692222) (xy 121.838466 -218.692222) (xy 121.837957 -218.718189)
			(xy 121.829832 -218.769484) (xy 121.813784 -218.818877) (xy 121.790206 -218.865151) (xy 121.75968 -218.907167)
			(xy 121.722957 -218.94389) (xy 121.680941 -218.974416) (xy 121.634667 -218.997994) (xy 121.585274 -219.014042)
			(xy 121.533979 -219.022167) (xy 121.482045 -219.022167) (xy 121.43075 -219.014042) (xy 121.381357 -218.997994)
			(xy 121.335083 -218.974416) (xy 121.293067 -218.94389) (xy 121.256344 -218.907167) (xy 121.225818 -218.865151)
			(xy 121.20224 -218.818877) (xy 121.186192 -218.769484) (xy 121.178067 -218.718189) (xy 121.177558 -218.692222)
			(xy 119.958866 -218.692222) (xy 119.958423 -218.716686) (xy 119.951208 -218.765078) (xy 119.936938 -218.811879)
			(xy 119.915926 -218.856065) (xy 119.888631 -218.896671) (xy 119.855648 -218.93281) (xy 119.817699 -218.963693)
			(xy 119.775612 -218.988645) (xy 119.753126 -218.998292) (xy 119.739739 -219.004292) (xy 119.716865 -219.022641)
			(xy 119.700131 -219.046722) (xy 119.69091 -219.074559) (xy 119.689959 -219.103868) (xy 119.693182 -219.11818)
			(xy 119.709692 -219.187776) (xy 119.762016 -219.237052) (xy 119.772772 -219.247063) (xy 119.79863 -219.260991)
			(xy 119.827384 -219.266979) (xy 119.856653 -219.264531) (xy 119.884013 -219.25385) (xy 119.895874 -219.24518)
			(xy 119.917762 -219.228856) (xy 119.965777 -219.202866) (xy 120.017415 -219.185133) (xy 120.071267 -219.176142)
			(xy 120.098566 -219.175584) (xy 120.124536 -219.176064) (xy 120.175837 -219.184185) (xy 120.225236 -219.200233)
			(xy 120.271515 -219.223811) (xy 120.313536 -219.25434) (xy 120.350263 -219.291067) (xy 120.380791 -219.333088)
			(xy 120.404369 -219.379368) (xy 120.420416 -219.428767) (xy 120.428536 -219.480068) (xy 120.42902 -219.506038)
			(xy 120.428581 -219.530516) (xy 120.428359 -219.532005) (xy 120.708421 -219.532005) (xy 120.708421 -219.480071)
			(xy 120.716546 -219.428776) (xy 120.732594 -219.379383) (xy 120.756172 -219.333109) (xy 120.786698 -219.291093)
			(xy 120.823421 -219.25437) (xy 120.865437 -219.223844) (xy 120.911711 -219.200266) (xy 120.961104 -219.184218)
			(xy 121.012399 -219.176093) (xy 121.064333 -219.176093) (xy 121.115628 -219.184218) (xy 121.165021 -219.200266)
			(xy 121.211295 -219.223844) (xy 121.253311 -219.25437) (xy 121.290034 -219.291093) (xy 121.32056 -219.333109)
			(xy 121.344138 -219.379383) (xy 121.360186 -219.428776) (xy 121.368311 -219.480071) (xy 121.36882 -219.506038)
			(xy 121.368311 -219.532005) (xy 121.648221 -219.532005) (xy 121.648221 -219.480071) (xy 121.656346 -219.428776)
			(xy 121.672394 -219.379383) (xy 121.695972 -219.333109) (xy 121.726498 -219.291093) (xy 121.763221 -219.25437)
			(xy 121.805237 -219.223844) (xy 121.851511 -219.200266) (xy 121.900904 -219.184218) (xy 121.952199 -219.176093)
			(xy 122.004133 -219.176093) (xy 122.055428 -219.184218) (xy 122.104821 -219.200266) (xy 122.151095 -219.223844)
			(xy 122.193111 -219.25437) (xy 122.229834 -219.291093) (xy 122.26036 -219.333109) (xy 122.283938 -219.379383)
			(xy 122.299986 -219.428776) (xy 122.308111 -219.480071) (xy 122.30862 -219.506038) (xy 122.308111 -219.532005)
			(xy 122.588021 -219.532005) (xy 122.588021 -219.480071) (xy 122.596146 -219.428776) (xy 122.612194 -219.379383)
			(xy 122.635772 -219.333109) (xy 122.666298 -219.291093) (xy 122.703021 -219.25437) (xy 122.745037 -219.223844)
			(xy 122.791311 -219.200266) (xy 122.840704 -219.184218) (xy 122.891999 -219.176093) (xy 122.943933 -219.176093)
			(xy 122.995228 -219.184218) (xy 123.044621 -219.200266) (xy 123.090895 -219.223844) (xy 123.132911 -219.25437)
			(xy 123.169634 -219.291093) (xy 123.20016 -219.333109) (xy 123.223738 -219.379383) (xy 123.239786 -219.428776)
			(xy 123.247911 -219.480071) (xy 123.24842 -219.506038) (xy 123.247911 -219.532005) (xy 123.527821 -219.532005)
			(xy 123.527821 -219.480071) (xy 123.535946 -219.428776) (xy 123.551994 -219.379383) (xy 123.575572 -219.333109)
			(xy 123.606098 -219.291093) (xy 123.642821 -219.25437) (xy 123.684837 -219.223844) (xy 123.731111 -219.200266)
			(xy 123.780504 -219.184218) (xy 123.831799 -219.176093) (xy 123.883733 -219.176093) (xy 123.935028 -219.184218)
			(xy 123.984421 -219.200266) (xy 124.030695 -219.223844) (xy 124.072711 -219.25437) (xy 124.109434 -219.291093)
			(xy 124.13996 -219.333109) (xy 124.163538 -219.379383) (xy 124.179586 -219.428776) (xy 124.187711 -219.480071)
			(xy 124.18822 -219.506038) (xy 124.187711 -219.532005) (xy 124.467621 -219.532005) (xy 124.467621 -219.480071)
			(xy 124.475746 -219.428776) (xy 124.491794 -219.379383) (xy 124.515372 -219.333109) (xy 124.545898 -219.291093)
			(xy 124.582621 -219.25437) (xy 124.624637 -219.223844) (xy 124.670911 -219.200266) (xy 124.720304 -219.184218)
			(xy 124.771599 -219.176093) (xy 124.823533 -219.176093) (xy 124.874828 -219.184218) (xy 124.924221 -219.200266)
			(xy 124.970495 -219.223844) (xy 125.012511 -219.25437) (xy 125.049234 -219.291093) (xy 125.07976 -219.333109)
			(xy 125.103338 -219.379383) (xy 125.119386 -219.428776) (xy 125.127511 -219.480071) (xy 125.12802 -219.506038)
			(xy 125.127511 -219.532005) (xy 125.407421 -219.532005) (xy 125.407421 -219.480071) (xy 125.415546 -219.428776)
			(xy 125.431594 -219.379383) (xy 125.455172 -219.333109) (xy 125.485698 -219.291093) (xy 125.522421 -219.25437)
			(xy 125.564437 -219.223844) (xy 125.610711 -219.200266) (xy 125.660104 -219.184218) (xy 125.711399 -219.176093)
			(xy 125.763333 -219.176093) (xy 125.814628 -219.184218) (xy 125.864021 -219.200266) (xy 125.910295 -219.223844)
			(xy 125.952311 -219.25437) (xy 125.989034 -219.291093) (xy 126.01956 -219.333109) (xy 126.043138 -219.379383)
			(xy 126.059186 -219.428776) (xy 126.067311 -219.480071) (xy 126.06782 -219.506038) (xy 126.067311 -219.532005)
			(xy 126.059186 -219.5833) (xy 126.043138 -219.632693) (xy 126.01956 -219.678967) (xy 125.989034 -219.720983)
			(xy 125.952311 -219.757706) (xy 125.910295 -219.788232) (xy 125.864021 -219.81181) (xy 125.814628 -219.827858)
			(xy 125.763333 -219.835983) (xy 125.711399 -219.835983) (xy 125.660104 -219.827858) (xy 125.610711 -219.81181)
			(xy 125.564437 -219.788232) (xy 125.522421 -219.757706) (xy 125.485698 -219.720983) (xy 125.455172 -219.678967)
			(xy 125.431594 -219.632693) (xy 125.415546 -219.5833) (xy 125.407421 -219.532005) (xy 125.127511 -219.532005)
			(xy 125.119386 -219.5833) (xy 125.103338 -219.632693) (xy 125.07976 -219.678967) (xy 125.049234 -219.720983)
			(xy 125.012511 -219.757706) (xy 124.970495 -219.788232) (xy 124.924221 -219.81181) (xy 124.874828 -219.827858)
			(xy 124.823533 -219.835983) (xy 124.771599 -219.835983) (xy 124.720304 -219.827858) (xy 124.670911 -219.81181)
			(xy 124.624637 -219.788232) (xy 124.582621 -219.757706) (xy 124.545898 -219.720983) (xy 124.515372 -219.678967)
			(xy 124.491794 -219.632693) (xy 124.475746 -219.5833) (xy 124.467621 -219.532005) (xy 124.187711 -219.532005)
			(xy 124.179586 -219.5833) (xy 124.163538 -219.632693) (xy 124.13996 -219.678967) (xy 124.109434 -219.720983)
			(xy 124.072711 -219.757706) (xy 124.030695 -219.788232) (xy 123.984421 -219.81181) (xy 123.935028 -219.827858)
			(xy 123.883733 -219.835983) (xy 123.831799 -219.835983) (xy 123.780504 -219.827858) (xy 123.731111 -219.81181)
			(xy 123.684837 -219.788232) (xy 123.642821 -219.757706) (xy 123.606098 -219.720983) (xy 123.575572 -219.678967)
			(xy 123.551994 -219.632693) (xy 123.535946 -219.5833) (xy 123.527821 -219.532005) (xy 123.247911 -219.532005)
			(xy 123.239786 -219.5833) (xy 123.223738 -219.632693) (xy 123.20016 -219.678967) (xy 123.169634 -219.720983)
			(xy 123.132911 -219.757706) (xy 123.090895 -219.788232) (xy 123.044621 -219.81181) (xy 122.995228 -219.827858)
			(xy 122.943933 -219.835983) (xy 122.891999 -219.835983) (xy 122.840704 -219.827858) (xy 122.791311 -219.81181)
			(xy 122.745037 -219.788232) (xy 122.703021 -219.757706) (xy 122.666298 -219.720983) (xy 122.635772 -219.678967)
			(xy 122.612194 -219.632693) (xy 122.596146 -219.5833) (xy 122.588021 -219.532005) (xy 122.308111 -219.532005)
			(xy 122.299986 -219.5833) (xy 122.283938 -219.632693) (xy 122.26036 -219.678967) (xy 122.229834 -219.720983)
			(xy 122.193111 -219.757706) (xy 122.151095 -219.788232) (xy 122.104821 -219.81181) (xy 122.055428 -219.827858)
			(xy 122.004133 -219.835983) (xy 121.952199 -219.835983) (xy 121.900904 -219.827858) (xy 121.851511 -219.81181)
			(xy 121.805237 -219.788232) (xy 121.763221 -219.757706) (xy 121.726498 -219.720983) (xy 121.695972 -219.678967)
			(xy 121.672394 -219.632693) (xy 121.656346 -219.5833) (xy 121.648221 -219.532005) (xy 121.368311 -219.532005)
			(xy 121.360186 -219.5833) (xy 121.344138 -219.632693) (xy 121.32056 -219.678967) (xy 121.290034 -219.720983)
			(xy 121.253311 -219.757706) (xy 121.211295 -219.788232) (xy 121.165021 -219.81181) (xy 121.115628 -219.827858)
			(xy 121.064333 -219.835983) (xy 121.012399 -219.835983) (xy 120.961104 -219.827858) (xy 120.911711 -219.81181)
			(xy 120.865437 -219.788232) (xy 120.823421 -219.757706) (xy 120.786698 -219.720983) (xy 120.756172 -219.678967)
			(xy 120.732594 -219.632693) (xy 120.716546 -219.5833) (xy 120.708421 -219.532005) (xy 120.428359 -219.532005)
			(xy 120.421364 -219.578936) (xy 120.40708 -219.625762) (xy 120.386042 -219.669966) (xy 120.358709 -219.710581)
			(xy 120.325682 -219.746717) (xy 120.287683 -219.777583) (xy 120.245544 -219.802502) (xy 120.223026 -219.812108)
			(xy 120.209641 -219.818109) (xy 120.18677 -219.836458) (xy 120.170039 -219.860539) (xy 120.160822 -219.888374)
			(xy 120.159875 -219.917681) (xy 120.163082 -219.931996) (xy 120.168498 -219.952953) (xy 120.178278 -219.995123)
			(xy 120.18264 -220.016324) (xy 120.186238 -220.031135) (xy 120.200845 -220.057866) (xy 120.222675 -220.07911)
			(xy 120.249795 -220.092983) (xy 120.279797 -220.098255) (xy 120.310021 -220.094458) (xy 120.337786 -220.081928)
			(xy 120.349518 -220.072204) (xy 120.367717 -220.056684) (xy 120.407746 -220.03051) (xy 120.451134 -220.010385)
			(xy 120.496971 -219.99673) (xy 120.544298 -219.989832) (xy 120.568212 -219.9894) (xy 120.59418 -219.98991)
			(xy 120.645476 -219.998036) (xy 120.69487 -220.014085) (xy 120.741146 -220.037662) (xy 120.783164 -220.068188)
			(xy 120.81989 -220.10491) (xy 120.85042 -220.146925) (xy 120.874002 -220.193198) (xy 120.890056 -220.242591)
			(xy 120.898187 -220.293886) (xy 120.898666 -220.319854) (xy 120.898142 -220.345821) (xy 121.178321 -220.345821)
			(xy 121.178321 -220.293887) (xy 121.186446 -220.242592) (xy 121.202494 -220.193199) (xy 121.226072 -220.146925)
			(xy 121.256598 -220.104909) (xy 121.293321 -220.068186) (xy 121.335337 -220.03766) (xy 121.381611 -220.014082)
			(xy 121.431004 -219.998034) (xy 121.482299 -219.989909) (xy 121.534233 -219.989909) (xy 121.585528 -219.998034)
			(xy 121.634921 -220.014082) (xy 121.681195 -220.03766) (xy 121.723211 -220.068186) (xy 121.759934 -220.104909)
			(xy 121.79046 -220.146925) (xy 121.814038 -220.193199) (xy 121.830086 -220.242592) (xy 121.838211 -220.293887)
			(xy 121.83872 -220.319854) (xy 122.117358 -220.319854) (xy 122.117867 -220.293887) (xy 122.125992 -220.242592)
			(xy 122.14204 -220.193199) (xy 122.165618 -220.146925) (xy 122.196144 -220.104909) (xy 122.232867 -220.068186)
			(xy 122.274883 -220.03766) (xy 122.321157 -220.014082) (xy 122.37055 -219.998034) (xy 122.421845 -219.989909)
			(xy 122.473779 -219.989909) (xy 122.525074 -219.998034) (xy 122.574467 -220.014082) (xy 122.620741 -220.03766)
			(xy 122.662757 -220.068186) (xy 122.69948 -220.104909) (xy 122.730006 -220.146925) (xy 122.753584 -220.193199)
			(xy 122.769632 -220.242592) (xy 122.777757 -220.293887) (xy 122.778266 -220.319854) (xy 122.777769 -220.345821)
			(xy 123.057921 -220.345821) (xy 123.057921 -220.293887) (xy 123.066046 -220.242592) (xy 123.082094 -220.193199)
			(xy 123.105672 -220.146925) (xy 123.136198 -220.104909) (xy 123.172921 -220.068186) (xy 123.214937 -220.03766)
			(xy 123.261211 -220.014082) (xy 123.310604 -219.998034) (xy 123.361899 -219.989909) (xy 123.413833 -219.989909)
			(xy 123.465128 -219.998034) (xy 123.514521 -220.014082) (xy 123.560795 -220.03766) (xy 123.602811 -220.068186)
			(xy 123.639534 -220.104909) (xy 123.67006 -220.146925) (xy 123.693638 -220.193199) (xy 123.709686 -220.242592)
			(xy 123.717811 -220.293887) (xy 123.71832 -220.319854) (xy 123.996958 -220.319854) (xy 123.997467 -220.293887)
			(xy 124.005592 -220.242592) (xy 124.02164 -220.193199) (xy 124.045218 -220.146925) (xy 124.075744 -220.104909)
			(xy 124.112467 -220.068186) (xy 124.154483 -220.03766) (xy 124.200757 -220.014082) (xy 124.25015 -219.998034)
			(xy 124.301445 -219.989909) (xy 124.353379 -219.989909) (xy 124.404674 -219.998034) (xy 124.454067 -220.014082)
			(xy 124.500341 -220.03766) (xy 124.542357 -220.068186) (xy 124.57908 -220.104909) (xy 124.609606 -220.146925)
			(xy 124.633184 -220.193199) (xy 124.649232 -220.242592) (xy 124.657357 -220.293887) (xy 124.657866 -220.319854)
			(xy 124.657369 -220.345821) (xy 124.937521 -220.345821) (xy 124.937521 -220.293887) (xy 124.945646 -220.242592)
			(xy 124.961694 -220.193199) (xy 124.985272 -220.146925) (xy 125.015798 -220.104909) (xy 125.052521 -220.068186)
			(xy 125.094537 -220.03766) (xy 125.140811 -220.014082) (xy 125.190204 -219.998034) (xy 125.241499 -219.989909)
			(xy 125.293433 -219.989909) (xy 125.344728 -219.998034) (xy 125.394121 -220.014082) (xy 125.440395 -220.03766)
			(xy 125.482411 -220.068186) (xy 125.519134 -220.104909) (xy 125.54966 -220.146925) (xy 125.573238 -220.193199)
			(xy 125.589286 -220.242592) (xy 125.597411 -220.293887) (xy 125.59792 -220.319854) (xy 125.597411 -220.345821)
			(xy 125.589286 -220.397116) (xy 125.573238 -220.446509) (xy 125.54966 -220.492783) (xy 125.519134 -220.534799)
			(xy 125.482411 -220.571522) (xy 125.440395 -220.602048) (xy 125.394121 -220.625626) (xy 125.344728 -220.641674)
			(xy 125.293433 -220.649799) (xy 125.241499 -220.649799) (xy 125.190204 -220.641674) (xy 125.140811 -220.625626)
			(xy 125.094537 -220.602048) (xy 125.052521 -220.571522) (xy 125.015798 -220.534799) (xy 124.985272 -220.492783)
			(xy 124.961694 -220.446509) (xy 124.945646 -220.397116) (xy 124.937521 -220.345821) (xy 124.657369 -220.345821)
			(xy 124.657332 -220.347764) (xy 124.648004 -220.402797) (xy 124.639324 -220.429328) (xy 124.63145 -220.451172)
			(xy 124.835666 -220.80474) (xy 124.858526 -220.809058) (xy 124.883444 -220.814243) (xy 124.931427 -220.831206)
			(xy 124.976245 -220.85532) (xy 125.016838 -220.886018) (xy 125.052247 -220.922574) (xy 125.081636 -220.964124)
			(xy 125.104311 -221.009687) (xy 125.119735 -221.058187) (xy 125.127546 -221.108477) (xy 125.12802 -221.133924)
			(xy 125.127511 -221.159891) (xy 125.119386 -221.211186) (xy 125.103338 -221.260579) (xy 125.07976 -221.306853)
			(xy 125.049234 -221.348869) (xy 125.012511 -221.385592) (xy 124.970495 -221.416118) (xy 124.924221 -221.439696)
			(xy 124.874828 -221.455744) (xy 124.823533 -221.463869) (xy 124.771599 -221.463869) (xy 124.720304 -221.455744)
			(xy 124.670911 -221.439696) (xy 124.624637 -221.416118) (xy 124.582621 -221.385592) (xy 124.545898 -221.348869)
			(xy 124.515372 -221.306853) (xy 124.491794 -221.260579) (xy 124.475746 -221.211186) (xy 124.467621 -221.159891)
			(xy 124.467112 -221.133924) (xy 124.46767 -221.105938) (xy 124.477116 -221.050771) (xy 124.485908 -221.024196)
			(xy 124.493528 -221.002098) (xy 124.28982 -220.649038) (xy 124.266706 -220.64472) (xy 124.24177 -220.63956)
			(xy 124.193747 -220.62263) (xy 124.148888 -220.598536) (xy 124.108255 -220.567848) (xy 124.072809 -220.531292)
			(xy 124.043389 -220.489732) (xy 124.020689 -220.444152) (xy 124.005249 -220.39563) (xy 123.997432 -220.345314)
			(xy 123.996958 -220.319854) (xy 123.71832 -220.319854) (xy 123.717811 -220.345821) (xy 123.709686 -220.397116)
			(xy 123.693638 -220.446509) (xy 123.67006 -220.492783) (xy 123.639534 -220.534799) (xy 123.602811 -220.571522)
			(xy 123.560795 -220.602048) (xy 123.514521 -220.625626) (xy 123.465128 -220.641674) (xy 123.413833 -220.649799)
			(xy 123.361899 -220.649799) (xy 123.310604 -220.641674) (xy 123.261211 -220.625626) (xy 123.214937 -220.602048)
			(xy 123.172921 -220.571522) (xy 123.136198 -220.534799) (xy 123.105672 -220.492783) (xy 123.082094 -220.446509)
			(xy 123.066046 -220.397116) (xy 123.057921 -220.345821) (xy 122.777769 -220.345821) (xy 122.777732 -220.347764)
			(xy 122.768404 -220.402797) (xy 122.759724 -220.429328) (xy 122.75185 -220.451172) (xy 122.956066 -220.80474)
			(xy 122.978926 -220.809058) (xy 123.003844 -220.814243) (xy 123.051827 -220.831206) (xy 123.096645 -220.85532)
			(xy 123.137238 -220.886018) (xy 123.172647 -220.922574) (xy 123.202036 -220.964124) (xy 123.224711 -221.009687)
			(xy 123.240135 -221.058187) (xy 123.247946 -221.108477) (xy 123.24842 -221.133924) (xy 123.247911 -221.159891)
			(xy 123.239786 -221.211186) (xy 123.223738 -221.260579) (xy 123.20016 -221.306853) (xy 123.169634 -221.348869)
			(xy 123.132911 -221.385592) (xy 123.090895 -221.416118) (xy 123.044621 -221.439696) (xy 122.995228 -221.455744)
			(xy 122.943933 -221.463869) (xy 122.891999 -221.463869) (xy 122.840704 -221.455744) (xy 122.791311 -221.439696)
			(xy 122.745037 -221.416118) (xy 122.703021 -221.385592) (xy 122.666298 -221.348869) (xy 122.635772 -221.306853)
			(xy 122.612194 -221.260579) (xy 122.596146 -221.211186) (xy 122.588021 -221.159891) (xy 122.587512 -221.133924)
			(xy 122.58807 -221.105938) (xy 122.597516 -221.050771) (xy 122.606308 -221.024196) (xy 122.613928 -221.002098)
			(xy 122.41022 -220.649038) (xy 122.387106 -220.64472) (xy 122.36217 -220.63956) (xy 122.314147 -220.62263)
			(xy 122.269288 -220.598536) (xy 122.228655 -220.567848) (xy 122.193209 -220.531292) (xy 122.163789 -220.489732)
			(xy 122.141089 -220.444152) (xy 122.125649 -220.39563) (xy 122.117832 -220.345314) (xy 122.117358 -220.319854)
			(xy 121.83872 -220.319854) (xy 121.838211 -220.345821) (xy 121.830086 -220.397116) (xy 121.814038 -220.446509)
			(xy 121.79046 -220.492783) (xy 121.759934 -220.534799) (xy 121.723211 -220.571522) (xy 121.681195 -220.602048)
			(xy 121.634921 -220.625626) (xy 121.585528 -220.641674) (xy 121.534233 -220.649799) (xy 121.482299 -220.649799)
			(xy 121.431004 -220.641674) (xy 121.381611 -220.625626) (xy 121.335337 -220.602048) (xy 121.293321 -220.571522)
			(xy 121.256598 -220.534799) (xy 121.226072 -220.492783) (xy 121.202494 -220.446509) (xy 121.186446 -220.397116)
			(xy 121.178321 -220.345821) (xy 120.898142 -220.345821) (xy 120.898103 -220.347761) (xy 120.888779 -220.402791)
			(xy 120.880124 -220.429328) (xy 120.87225 -220.451172) (xy 121.076466 -220.80474) (xy 121.099326 -220.809058)
			(xy 121.124259 -220.814206) (xy 121.172268 -220.831143) (xy 121.21711 -220.855244) (xy 121.257725 -220.885938)
			(xy 121.293151 -220.922499) (xy 121.322549 -220.964061) (xy 121.345224 -221.009641) (xy 121.360639 -221.05816)
			(xy 121.368429 -221.108469) (xy 121.36882 -221.133924) (xy 121.368311 -221.159891) (xy 121.360186 -221.211186)
			(xy 121.344138 -221.260579) (xy 121.32056 -221.306853) (xy 121.290034 -221.348869) (xy 121.253311 -221.385592)
			(xy 121.211295 -221.416118) (xy 121.165021 -221.439696) (xy 121.115628 -221.455744) (xy 121.064333 -221.463869)
			(xy 121.012399 -221.463869) (xy 120.961104 -221.455744) (xy 120.911711 -221.439696) (xy 120.865437 -221.416118)
			(xy 120.823421 -221.385592) (xy 120.786698 -221.348869) (xy 120.756172 -221.306853) (xy 120.732594 -221.260579)
			(xy 120.716546 -221.211186) (xy 120.708421 -221.159891) (xy 120.707912 -221.133924) (xy 120.708523 -221.105944)
			(xy 120.717971 -221.050785) (xy 120.726708 -221.024196) (xy 120.734328 -221.002098) (xy 120.53062 -220.649038)
			(xy 120.507506 -220.64472) (xy 120.478513 -220.6386) (xy 120.423161 -220.617469) (xy 120.37245 -220.58683)
			(xy 120.349772 -220.567758) (xy 120.337988 -220.558103) (xy 120.310243 -220.545562) (xy 120.280034 -220.541753)
			(xy 120.250044 -220.547015) (xy 120.222937 -220.56088) (xy 120.201118 -220.582118) (xy 120.186526 -220.608841)
			(xy 120.182894 -220.623638) (xy 120.178529 -220.644838) (xy 120.168749 -220.687009) (xy 120.163336 -220.707966)
			(xy 120.16006 -220.72226) (xy 120.160933 -220.75156) (xy 120.170095 -220.779405) (xy 120.186791 -220.803499)
			(xy 120.209644 -220.821857) (xy 120.223026 -220.827854) (xy 120.245517 -220.837494) (xy 120.287614 -220.862435)
			(xy 120.325571 -220.893313) (xy 120.358559 -220.929452) (xy 120.385855 -220.970062) (xy 120.406863 -221.014253)
			(xy 120.421122 -221.06106) (xy 120.428322 -221.109458) (xy 120.428766 -221.133924) (xy 120.428255 -221.15989)
			(xy 120.420128 -221.211183) (xy 120.404077 -221.260573) (xy 120.380498 -221.306845) (xy 120.349972 -221.348858)
			(xy 120.313249 -221.38558) (xy 120.271234 -221.416105) (xy 120.224962 -221.439682) (xy 120.175571 -221.455731)
			(xy 120.124278 -221.463856) (xy 120.098312 -221.464378) (xy 120.088764 -221.464287) (xy 120.069702 -221.463146)
			(xy 120.060212 -221.462092) (xy 120.045446 -221.501243) (xy 120.010036 -221.577063) (xy 119.968162 -221.649513)
			(xy 119.920143 -221.718045) (xy 119.893588 -221.750382) (xy 119.908996 -221.7719) (xy 119.933478 -221.818817)
			(xy 119.95016 -221.869039) (xy 119.958614 -221.92128) (xy 119.95912 -221.94774) (xy 121.177558 -221.94774)
			(xy 121.177981 -221.922287) (xy 121.185768 -221.87198) (xy 121.20118 -221.823463) (xy 121.223851 -221.777884)
			(xy 121.253245 -221.736322) (xy 121.288667 -221.699761) (xy 121.329278 -221.669066) (xy 121.374116 -221.644963)
			(xy 121.422121 -221.628023) (xy 121.447052 -221.622874) (xy 121.469912 -221.618556) (xy 121.673874 -221.264988)
			(xy 121.666254 -221.243144) (xy 121.657621 -221.216666) (xy 121.648293 -221.161767) (xy 121.647712 -221.133924)
			(xy 121.648221 -221.107957) (xy 121.656346 -221.056662) (xy 121.672394 -221.007269) (xy 121.695972 -220.960995)
			(xy 121.726498 -220.918979) (xy 121.763221 -220.882256) (xy 121.805237 -220.85173) (xy 121.851511 -220.828152)
			(xy 121.900904 -220.812104) (xy 121.952199 -220.803979) (xy 122.004133 -220.803979) (xy 122.055428 -220.812104)
			(xy 122.104821 -220.828152) (xy 122.151095 -220.85173) (xy 122.193111 -220.882256) (xy 122.229834 -220.918979)
			(xy 122.26036 -220.960995) (xy 122.283938 -221.007269) (xy 122.299986 -221.056662) (xy 122.308111 -221.107957)
			(xy 122.30862 -221.133924) (xy 122.308187 -221.159399) (xy 122.300363 -221.209746) (xy 122.284905 -221.258295)
			(xy 122.262178 -221.303896) (xy 122.232721 -221.345468) (xy 122.197232 -221.382027) (xy 122.156553 -221.412705)
			(xy 122.111646 -221.436776) (xy 122.063578 -221.453669) (xy 122.038618 -221.45879) (xy 122.015504 -221.463108)
			(xy 121.81205 -221.815914) (xy 121.81967 -221.838012) (xy 121.82841 -221.8646) (xy 121.837856 -221.919759)
			(xy 121.838466 -221.94774) (xy 123.057158 -221.94774) (xy 123.057581 -221.922287) (xy 123.065368 -221.87198)
			(xy 123.08078 -221.823463) (xy 123.103451 -221.777884) (xy 123.132845 -221.736322) (xy 123.168267 -221.699761)
			(xy 123.208878 -221.669066) (xy 123.253716 -221.644963) (xy 123.301721 -221.628023) (xy 123.326652 -221.622874)
			(xy 123.349512 -221.618556) (xy 123.553474 -221.264988) (xy 123.545854 -221.243144) (xy 123.537221 -221.216666)
			(xy 123.527893 -221.161767) (xy 123.527312 -221.133924) (xy 123.527821 -221.107957) (xy 123.535946 -221.056662)
			(xy 123.551994 -221.007269) (xy 123.575572 -220.960995) (xy 123.606098 -220.918979) (xy 123.642821 -220.882256)
			(xy 123.684837 -220.85173) (xy 123.731111 -220.828152) (xy 123.780504 -220.812104) (xy 123.831799 -220.803979)
			(xy 123.883733 -220.803979) (xy 123.935028 -220.812104) (xy 123.984421 -220.828152) (xy 124.030695 -220.85173)
			(xy 124.072711 -220.882256) (xy 124.109434 -220.918979) (xy 124.13996 -220.960995) (xy 124.163538 -221.007269)
			(xy 124.179586 -221.056662) (xy 124.187711 -221.107957) (xy 124.18822 -221.133924) (xy 124.187787 -221.159399)
			(xy 124.179963 -221.209746) (xy 124.164505 -221.258295) (xy 124.141778 -221.303896) (xy 124.112321 -221.345468)
			(xy 124.076832 -221.382027) (xy 124.036153 -221.412705) (xy 123.991246 -221.436776) (xy 123.943178 -221.453669)
			(xy 123.918218 -221.45879) (xy 123.895104 -221.463108) (xy 123.69165 -221.815914) (xy 123.69927 -221.838012)
			(xy 123.70801 -221.8646) (xy 123.717456 -221.919759) (xy 123.718066 -221.94774) (xy 124.936758 -221.94774)
			(xy 124.937181 -221.922287) (xy 124.944968 -221.87198) (xy 124.96038 -221.823463) (xy 124.983051 -221.777884)
			(xy 125.012445 -221.736322) (xy 125.047867 -221.699761) (xy 125.088478 -221.669066) (xy 125.133316 -221.644963)
			(xy 125.181321 -221.628023) (xy 125.206252 -221.622874) (xy 125.229112 -221.618556) (xy 125.433074 -221.264988)
			(xy 125.425454 -221.243144) (xy 125.416821 -221.216666) (xy 125.407493 -221.161767) (xy 125.406912 -221.133924)
			(xy 125.407421 -221.107957) (xy 125.415546 -221.056662) (xy 125.431594 -221.007269) (xy 125.455172 -220.960995)
			(xy 125.485698 -220.918979) (xy 125.522421 -220.882256) (xy 125.564437 -220.85173) (xy 125.610711 -220.828152)
			(xy 125.660104 -220.812104) (xy 125.711399 -220.803979) (xy 125.763333 -220.803979) (xy 125.814628 -220.812104)
			(xy 125.864021 -220.828152) (xy 125.910295 -220.85173) (xy 125.952311 -220.882256) (xy 125.989034 -220.918979)
			(xy 126.01956 -220.960995) (xy 126.043138 -221.007269) (xy 126.059186 -221.056662) (xy 126.067311 -221.107957)
			(xy 126.06782 -221.133924) (xy 126.067387 -221.159399) (xy 126.059563 -221.209746) (xy 126.044105 -221.258295)
			(xy 126.021378 -221.303896) (xy 125.991921 -221.345468) (xy 125.956432 -221.382027) (xy 125.915753 -221.412705)
			(xy 125.870846 -221.436776) (xy 125.822778 -221.453669) (xy 125.797818 -221.45879) (xy 125.774704 -221.463108)
			(xy 125.57125 -221.815914) (xy 125.57887 -221.838012) (xy 125.58761 -221.8646) (xy 125.597056 -221.919759)
			(xy 125.597666 -221.94774) (xy 125.597157 -221.973707) (xy 125.589032 -222.025002) (xy 125.572984 -222.074395)
			(xy 125.549406 -222.120669) (xy 125.51888 -222.162685) (xy 125.482157 -222.199408) (xy 125.440141 -222.229934)
			(xy 125.393867 -222.253512) (xy 125.344474 -222.26956) (xy 125.293179 -222.277685) (xy 125.241245 -222.277685)
			(xy 125.18995 -222.26956) (xy 125.140557 -222.253512) (xy 125.094283 -222.229934) (xy 125.052267 -222.199408)
			(xy 125.015544 -222.162685) (xy 124.985018 -222.120669) (xy 124.96144 -222.074395) (xy 124.945392 -222.025002)
			(xy 124.937267 -221.973707) (xy 124.936758 -221.94774) (xy 123.718066 -221.94774) (xy 123.717557 -221.973707)
			(xy 123.709432 -222.025002) (xy 123.693384 -222.074395) (xy 123.669806 -222.120669) (xy 123.63928 -222.162685)
			(xy 123.602557 -222.199408) (xy 123.560541 -222.229934) (xy 123.514267 -222.253512) (xy 123.464874 -222.26956)
			(xy 123.413579 -222.277685) (xy 123.361645 -222.277685) (xy 123.31035 -222.26956) (xy 123.260957 -222.253512)
			(xy 123.214683 -222.229934) (xy 123.172667 -222.199408) (xy 123.135944 -222.162685) (xy 123.105418 -222.120669)
			(xy 123.08184 -222.074395) (xy 123.065792 -222.025002) (xy 123.057667 -221.973707) (xy 123.057158 -221.94774)
			(xy 121.838466 -221.94774) (xy 121.837957 -221.973707) (xy 121.829832 -222.025002) (xy 121.813784 -222.074395)
			(xy 121.790206 -222.120669) (xy 121.75968 -222.162685) (xy 121.722957 -222.199408) (xy 121.680941 -222.229934)
			(xy 121.634667 -222.253512) (xy 121.585274 -222.26956) (xy 121.533979 -222.277685) (xy 121.482045 -222.277685)
			(xy 121.43075 -222.26956) (xy 121.381357 -222.253512) (xy 121.335083 -222.229934) (xy 121.293067 -222.199408)
			(xy 121.256344 -222.162685) (xy 121.225818 -222.120669) (xy 121.20224 -222.074395) (xy 121.186192 -222.025002)
			(xy 121.178067 -221.973707) (xy 121.177558 -221.94774) (xy 119.95912 -221.94774) (xy 119.958608 -221.973704)
			(xy 119.950478 -222.024992) (xy 119.934426 -222.074377) (xy 119.910845 -222.120643) (xy 119.880318 -222.162651)
			(xy 119.843595 -222.199366) (xy 119.80158 -222.229884) (xy 119.755309 -222.253454) (xy 119.70592 -222.269496)
			(xy 119.65463 -222.277614) (xy 119.628666 -222.278194) (xy 119.601371 -222.277608) (xy 119.547529 -222.268593)
			(xy 119.495897 -222.250862) (xy 119.447876 -222.224898) (xy 119.425974 -222.208598) (xy 119.414075 -222.200003)
			(xy 119.386727 -222.189372) (xy 119.357486 -222.186936) (xy 119.328756 -222.192897) (xy 119.302898 -222.206765)
			(xy 119.292116 -222.216726) (xy 119.276676 -222.231914) (xy 119.245049 -222.26151) (xy 119.22887 -222.275908)
			(xy 119.217764 -222.286375) (xy 119.201848 -222.312401) (xy 119.194325 -222.341964) (xy 119.195864 -222.372431)
			(xy 119.206329 -222.401086) (xy 119.224786 -222.425375) (xy 119.249591 -222.443132) (xy 119.263922 -222.448374)
			(xy 119.288202 -222.457019) (xy 119.333942 -222.480768) (xy 119.375434 -222.511336) (xy 119.411672 -222.547982)
			(xy 119.441773 -222.589815) (xy 119.465008 -222.635818) (xy 119.48081 -222.684872) (xy 119.488796 -222.735787)
			(xy 119.48922 -222.761556) (xy 119.488711 -222.787523) (xy 119.768621 -222.787523) (xy 119.768621 -222.735589)
			(xy 119.776746 -222.684294) (xy 119.792794 -222.634901) (xy 119.816372 -222.588627) (xy 119.846898 -222.546611)
			(xy 119.883621 -222.509888) (xy 119.925637 -222.479362) (xy 119.971911 -222.455784) (xy 120.021304 -222.439736)
			(xy 120.072599 -222.431611) (xy 120.124533 -222.431611) (xy 120.175828 -222.439736) (xy 120.225221 -222.455784)
			(xy 120.271495 -222.479362) (xy 120.313511 -222.509888) (xy 120.350234 -222.546611) (xy 120.38076 -222.588627)
			(xy 120.404338 -222.634901) (xy 120.420386 -222.684294) (xy 120.428511 -222.735589) (xy 120.42902 -222.761556)
			(xy 120.428511 -222.787523) (xy 120.708421 -222.787523) (xy 120.708421 -222.735589) (xy 120.716546 -222.684294)
			(xy 120.732594 -222.634901) (xy 120.756172 -222.588627) (xy 120.786698 -222.546611) (xy 120.823421 -222.509888)
			(xy 120.865437 -222.479362) (xy 120.911711 -222.455784) (xy 120.961104 -222.439736) (xy 121.012399 -222.431611)
			(xy 121.064333 -222.431611) (xy 121.115628 -222.439736) (xy 121.165021 -222.455784) (xy 121.211295 -222.479362)
			(xy 121.253311 -222.509888) (xy 121.290034 -222.546611) (xy 121.32056 -222.588627) (xy 121.344138 -222.634901)
			(xy 121.360186 -222.684294) (xy 121.368311 -222.735589) (xy 121.36882 -222.761556) (xy 121.368311 -222.787523)
			(xy 121.648221 -222.787523) (xy 121.648221 -222.735589) (xy 121.656346 -222.684294) (xy 121.672394 -222.634901)
			(xy 121.695972 -222.588627) (xy 121.726498 -222.546611) (xy 121.763221 -222.509888) (xy 121.805237 -222.479362)
			(xy 121.851511 -222.455784) (xy 121.900904 -222.439736) (xy 121.952199 -222.431611) (xy 122.004133 -222.431611)
			(xy 122.055428 -222.439736) (xy 122.104821 -222.455784) (xy 122.151095 -222.479362) (xy 122.193111 -222.509888)
			(xy 122.229834 -222.546611) (xy 122.26036 -222.588627) (xy 122.283938 -222.634901) (xy 122.299986 -222.684294)
			(xy 122.308111 -222.735589) (xy 122.30862 -222.761556) (xy 122.308111 -222.787523) (xy 122.588021 -222.787523)
			(xy 122.588021 -222.735589) (xy 122.596146 -222.684294) (xy 122.612194 -222.634901) (xy 122.635772 -222.588627)
			(xy 122.666298 -222.546611) (xy 122.703021 -222.509888) (xy 122.745037 -222.479362) (xy 122.791311 -222.455784)
			(xy 122.840704 -222.439736) (xy 122.891999 -222.431611) (xy 122.943933 -222.431611) (xy 122.995228 -222.439736)
			(xy 123.044621 -222.455784) (xy 123.090895 -222.479362) (xy 123.132911 -222.509888) (xy 123.169634 -222.546611)
			(xy 123.20016 -222.588627) (xy 123.223738 -222.634901) (xy 123.239786 -222.684294) (xy 123.247911 -222.735589)
			(xy 123.24842 -222.761556) (xy 123.247911 -222.787523) (xy 123.527821 -222.787523) (xy 123.527821 -222.735589)
			(xy 123.535946 -222.684294) (xy 123.551994 -222.634901) (xy 123.575572 -222.588627) (xy 123.606098 -222.546611)
			(xy 123.642821 -222.509888) (xy 123.684837 -222.479362) (xy 123.731111 -222.455784) (xy 123.780504 -222.439736)
			(xy 123.831799 -222.431611) (xy 123.883733 -222.431611) (xy 123.935028 -222.439736) (xy 123.984421 -222.455784)
			(xy 124.030695 -222.479362) (xy 124.072711 -222.509888) (xy 124.109434 -222.546611) (xy 124.13996 -222.588627)
			(xy 124.163538 -222.634901) (xy 124.179586 -222.684294) (xy 124.187711 -222.735589) (xy 124.18822 -222.761556)
			(xy 124.187711 -222.787523) (xy 124.467621 -222.787523) (xy 124.467621 -222.735589) (xy 124.475746 -222.684294)
			(xy 124.491794 -222.634901) (xy 124.515372 -222.588627) (xy 124.545898 -222.546611) (xy 124.582621 -222.509888)
			(xy 124.624637 -222.479362) (xy 124.670911 -222.455784) (xy 124.720304 -222.439736) (xy 124.771599 -222.431611)
			(xy 124.823533 -222.431611) (xy 124.874828 -222.439736) (xy 124.924221 -222.455784) (xy 124.970495 -222.479362)
			(xy 125.012511 -222.509888) (xy 125.049234 -222.546611) (xy 125.07976 -222.588627) (xy 125.103338 -222.634901)
			(xy 125.119386 -222.684294) (xy 125.127511 -222.735589) (xy 125.12802 -222.761556) (xy 125.127511 -222.787523)
			(xy 125.407421 -222.787523) (xy 125.407421 -222.735589) (xy 125.415546 -222.684294) (xy 125.431594 -222.634901)
			(xy 125.455172 -222.588627) (xy 125.485698 -222.546611) (xy 125.522421 -222.509888) (xy 125.564437 -222.479362)
			(xy 125.610711 -222.455784) (xy 125.660104 -222.439736) (xy 125.711399 -222.431611) (xy 125.763333 -222.431611)
			(xy 125.814628 -222.439736) (xy 125.864021 -222.455784) (xy 125.910295 -222.479362) (xy 125.952311 -222.509888)
			(xy 125.989034 -222.546611) (xy 126.01956 -222.588627) (xy 126.043138 -222.634901) (xy 126.059186 -222.684294)
			(xy 126.067311 -222.735589) (xy 126.06782 -222.761556) (xy 126.067311 -222.787523) (xy 126.059186 -222.838818)
			(xy 126.043138 -222.888211) (xy 126.01956 -222.934485) (xy 125.989034 -222.976501) (xy 125.952311 -223.013224)
			(xy 125.910295 -223.04375) (xy 125.864021 -223.067328) (xy 125.814628 -223.083376) (xy 125.763333 -223.091501)
			(xy 125.711399 -223.091501) (xy 125.660104 -223.083376) (xy 125.610711 -223.067328) (xy 125.564437 -223.04375)
			(xy 125.522421 -223.013224) (xy 125.485698 -222.976501) (xy 125.455172 -222.934485) (xy 125.431594 -222.888211)
			(xy 125.415546 -222.838818) (xy 125.407421 -222.787523) (xy 125.127511 -222.787523) (xy 125.119386 -222.838818)
			(xy 125.103338 -222.888211) (xy 125.07976 -222.934485) (xy 125.049234 -222.976501) (xy 125.012511 -223.013224)
			(xy 124.970495 -223.04375) (xy 124.924221 -223.067328) (xy 124.874828 -223.083376) (xy 124.823533 -223.091501)
			(xy 124.771599 -223.091501) (xy 124.720304 -223.083376) (xy 124.670911 -223.067328) (xy 124.624637 -223.04375)
			(xy 124.582621 -223.013224) (xy 124.545898 -222.976501) (xy 124.515372 -222.934485) (xy 124.491794 -222.888211)
			(xy 124.475746 -222.838818) (xy 124.467621 -222.787523) (xy 124.187711 -222.787523) (xy 124.179586 -222.838818)
			(xy 124.163538 -222.888211) (xy 124.13996 -222.934485) (xy 124.109434 -222.976501) (xy 124.072711 -223.013224)
			(xy 124.030695 -223.04375) (xy 123.984421 -223.067328) (xy 123.935028 -223.083376) (xy 123.883733 -223.091501)
			(xy 123.831799 -223.091501) (xy 123.780504 -223.083376) (xy 123.731111 -223.067328) (xy 123.684837 -223.04375)
			(xy 123.642821 -223.013224) (xy 123.606098 -222.976501) (xy 123.575572 -222.934485) (xy 123.551994 -222.888211)
			(xy 123.535946 -222.838818) (xy 123.527821 -222.787523) (xy 123.247911 -222.787523) (xy 123.239786 -222.838818)
			(xy 123.223738 -222.888211) (xy 123.20016 -222.934485) (xy 123.169634 -222.976501) (xy 123.132911 -223.013224)
			(xy 123.090895 -223.04375) (xy 123.044621 -223.067328) (xy 122.995228 -223.083376) (xy 122.943933 -223.091501)
			(xy 122.891999 -223.091501) (xy 122.840704 -223.083376) (xy 122.791311 -223.067328) (xy 122.745037 -223.04375)
			(xy 122.703021 -223.013224) (xy 122.666298 -222.976501) (xy 122.635772 -222.934485) (xy 122.612194 -222.888211)
			(xy 122.596146 -222.838818) (xy 122.588021 -222.787523) (xy 122.308111 -222.787523) (xy 122.299986 -222.838818)
			(xy 122.283938 -222.888211) (xy 122.26036 -222.934485) (xy 122.229834 -222.976501) (xy 122.193111 -223.013224)
			(xy 122.151095 -223.04375) (xy 122.104821 -223.067328) (xy 122.055428 -223.083376) (xy 122.004133 -223.091501)
			(xy 121.952199 -223.091501) (xy 121.900904 -223.083376) (xy 121.851511 -223.067328) (xy 121.805237 -223.04375)
			(xy 121.763221 -223.013224) (xy 121.726498 -222.976501) (xy 121.695972 -222.934485) (xy 121.672394 -222.888211)
			(xy 121.656346 -222.838818) (xy 121.648221 -222.787523) (xy 121.368311 -222.787523) (xy 121.360186 -222.838818)
			(xy 121.344138 -222.888211) (xy 121.32056 -222.934485) (xy 121.290034 -222.976501) (xy 121.253311 -223.013224)
			(xy 121.211295 -223.04375) (xy 121.165021 -223.067328) (xy 121.115628 -223.083376) (xy 121.064333 -223.091501)
			(xy 121.012399 -223.091501) (xy 120.961104 -223.083376) (xy 120.911711 -223.067328) (xy 120.865437 -223.04375)
			(xy 120.823421 -223.013224) (xy 120.786698 -222.976501) (xy 120.756172 -222.934485) (xy 120.732594 -222.888211)
			(xy 120.716546 -222.838818) (xy 120.708421 -222.787523) (xy 120.428511 -222.787523) (xy 120.420386 -222.838818)
			(xy 120.404338 -222.888211) (xy 120.38076 -222.934485) (xy 120.350234 -222.976501) (xy 120.313511 -223.013224)
			(xy 120.271495 -223.04375) (xy 120.225221 -223.067328) (xy 120.175828 -223.083376) (xy 120.124533 -223.091501)
			(xy 120.072599 -223.091501) (xy 120.021304 -223.083376) (xy 119.971911 -223.067328) (xy 119.925637 -223.04375)
			(xy 119.883621 -223.013224) (xy 119.846898 -222.976501) (xy 119.816372 -222.934485) (xy 119.792794 -222.888211)
			(xy 119.776746 -222.838818) (xy 119.768621 -222.787523) (xy 119.488711 -222.787523) (xy 119.480586 -222.838818)
			(xy 119.464538 -222.888211) (xy 119.44096 -222.934485) (xy 119.410434 -222.976501) (xy 119.373711 -223.013224)
			(xy 119.331695 -223.04375) (xy 119.285421 -223.067328) (xy 119.236028 -223.083376) (xy 119.184733 -223.091501)
			(xy 119.132799 -223.091501) (xy 119.081504 -223.083376) (xy 119.032111 -223.067328) (xy 118.985837 -223.04375)
			(xy 118.943821 -223.013224) (xy 118.907098 -222.976501) (xy 118.876572 -222.934485) (xy 118.852994 -222.888211)
			(xy 118.836946 -222.838818) (xy 118.828821 -222.787523) (xy 118.828312 -222.761556) (xy 118.82854 -222.745123)
			(xy 118.831846 -222.712423) (xy 118.834916 -222.696278) (xy 118.837476 -222.681241) (xy 118.834507 -222.650896)
			(xy 118.822712 -222.62278) (xy 118.803141 -222.5994) (xy 118.777541 -222.58284) (xy 118.748192 -222.574576)
			(xy 118.717712 -222.575346) (xy 118.70309 -222.579692) (xy 118.682548 -222.586491) (xy 118.64114 -222.599067)
			(xy 118.620286 -222.604838) (xy 118.606255 -222.609145) (xy 118.581293 -222.624564) (xy 118.561756 -222.646451)
			(xy 118.54926 -222.672996) (xy 118.54484 -222.702001) (xy 118.546372 -222.716598) (xy 118.5478 -222.727783)
			(xy 118.549324 -222.750281) (xy 118.54942 -222.761556) (xy 118.54894 -222.787527) (xy 118.540821 -222.838829)
			(xy 118.524774 -222.888229) (xy 118.501196 -222.934511) (xy 118.470668 -222.976533) (xy 118.433941 -223.013261)
			(xy 118.391919 -223.043791) (xy 118.345639 -223.06737) (xy 118.296239 -223.083418) (xy 118.244937 -223.09154)
			(xy 118.218966 -223.09201) (xy 118.191475 -223.091462) (xy 118.13725 -223.08236) (xy 118.085279 -223.064413)
			(xy 118.036992 -223.038116) (xy 117.993722 -223.004193) (xy 117.95666 -222.963578) (xy 117.926827 -222.917392)
			(xy 117.915436 -222.892366) (xy 117.874118 -222.899182) (xy 117.790686 -222.906431) (xy 117.748812 -222.906844)
			(xy 117.707066 -222.906392) (xy 117.62389 -222.899144) (xy 117.582696 -222.892366) (xy 117.571317 -222.917403)
			(xy 117.541502 -222.96361) (xy 117.504447 -223.004242) (xy 117.461175 -223.038176) (xy 117.41288 -223.064477)
			(xy 117.360898 -223.082417) (xy 117.306662 -223.091501) (xy 117.279166 -223.09201) (xy 117.2532 -223.091525)
			(xy 117.201907 -223.083395) (xy 117.152518 -223.067342) (xy 117.106248 -223.04376) (xy 117.064237 -223.013229)
			(xy 117.02752 -222.976503) (xy 116.997 -222.934485) (xy 116.973428 -222.88821) (xy 116.957387 -222.838817)
			(xy 116.949269 -222.787522) (xy 116.948712 -222.761556) (xy 116.94894 -222.745123) (xy 116.952246 -222.712423)
			(xy 116.955316 -222.696278) (xy 116.957876 -222.681241) (xy 116.954907 -222.650896) (xy 116.943112 -222.62278)
			(xy 116.923541 -222.5994) (xy 116.897941 -222.58284) (xy 116.868592 -222.574576) (xy 116.838112 -222.575346)
			(xy 116.82349 -222.579692) (xy 116.802948 -222.586491) (xy 116.76154 -222.599067) (xy 116.740686 -222.604838)
			(xy 116.726655 -222.609145) (xy 116.701693 -222.624564) (xy 116.682156 -222.646451) (xy 116.66966 -222.672996)
			(xy 116.66524 -222.702001) (xy 116.666772 -222.716598) (xy 116.6682 -222.727783) (xy 116.669724 -222.750281)
			(xy 116.66982 -222.761556) (xy 116.66934 -222.787527) (xy 116.661221 -222.838829) (xy 116.645174 -222.888229)
			(xy 116.621596 -222.934511) (xy 116.591068 -222.976533) (xy 116.554341 -223.013261) (xy 116.512319 -223.043791)
			(xy 116.466039 -223.06737) (xy 116.416639 -223.083418) (xy 116.365337 -223.09154) (xy 116.339366 -223.09201)
			(xy 116.311875 -223.091462) (xy 116.25765 -223.08236) (xy 116.205679 -223.064413) (xy 116.157392 -223.038116)
			(xy 116.114122 -223.004193) (xy 116.07706 -222.963578) (xy 116.047227 -222.917392) (xy 116.035836 -222.892366)
			(xy 115.994518 -222.899182) (xy 115.911086 -222.906431) (xy 115.869212 -222.906844) (xy 115.827466 -222.906392)
			(xy 115.74429 -222.899144) (xy 115.703096 -222.892366) (xy 115.691717 -222.917403) (xy 115.661902 -222.96361)
			(xy 115.624847 -223.004242) (xy 115.581575 -223.038176) (xy 115.53328 -223.064477) (xy 115.481298 -223.082417)
			(xy 115.427062 -223.091501) (xy 115.399566 -223.09201) (xy 115.3736 -223.091525) (xy 115.322307 -223.083395)
			(xy 115.272918 -223.067342) (xy 115.226648 -223.04376) (xy 115.184637 -223.013229) (xy 115.14792 -222.976503)
			(xy 115.1174 -222.934485) (xy 115.093828 -222.88821) (xy 115.077787 -222.838817) (xy 115.069669 -222.787522)
			(xy 115.069112 -222.761556) (xy 115.069334 -222.74506) (xy 115.072646 -222.712234) (xy 115.075716 -222.696024)
			(xy 115.078267 -222.680992) (xy 115.075287 -222.650662) (xy 115.063488 -222.622562) (xy 115.043921 -222.599196)
			(xy 115.018329 -222.582647) (xy 114.988993 -222.574387) (xy 114.958526 -222.575154) (xy 114.94389 -222.579438)
			(xy 114.923349 -222.586239) (xy 114.88194 -222.598814) (xy 114.861086 -222.604584) (xy 114.847038 -222.60891)
			(xy 114.822056 -222.624376) (xy 114.802516 -222.64632) (xy 114.79004 -222.672921) (xy 114.78566 -222.701975)
			(xy 114.787172 -222.716598) (xy 114.7886 -222.727783) (xy 114.790124 -222.750281) (xy 114.79022 -222.761556)
			(xy 114.78974 -222.787527) (xy 114.781621 -222.838829) (xy 114.765574 -222.888229) (xy 114.741996 -222.934511)
			(xy 114.711468 -222.976533) (xy 114.674741 -223.013261) (xy 114.632719 -223.043791) (xy 114.586439 -223.06737)
			(xy 114.537039 -223.083418) (xy 114.485737 -223.09154) (xy 114.459766 -223.09201) (xy 114.432275 -223.091462)
			(xy 114.37805 -223.08236) (xy 114.326079 -223.064413) (xy 114.277792 -223.038116) (xy 114.234522 -223.004193)
			(xy 114.19746 -222.963578) (xy 114.167627 -222.917392) (xy 114.156236 -222.892366) (xy 114.114982 -222.899174)
			(xy 114.031676 -222.906424) (xy 113.989866 -222.906844) (xy 113.948057 -222.9064) (xy 113.864753 -222.899151)
			(xy 113.823496 -222.892366) (xy 113.812117 -222.917403) (xy 113.782302 -222.96361) (xy 113.745247 -223.004242)
			(xy 113.701975 -223.038176) (xy 113.65368 -223.064477) (xy 113.601698 -223.082417) (xy 113.547462 -223.091501)
			(xy 113.519966 -223.09201) (xy 113.494 -223.091525) (xy 113.442707 -223.083395) (xy 113.393318 -223.067342)
			(xy 113.347048 -223.04376) (xy 113.305037 -223.013229) (xy 113.26832 -222.976503) (xy 113.2378 -222.934485)
			(xy 113.214228 -222.88821) (xy 113.198187 -222.838817) (xy 113.190069 -222.787522) (xy 113.189512 -222.761556)
			(xy 113.18974 -222.745123) (xy 113.193046 -222.712423) (xy 113.196116 -222.696278) (xy 113.198676 -222.681241)
			(xy 113.195707 -222.650896) (xy 113.183912 -222.62278) (xy 113.164341 -222.5994) (xy 113.138741 -222.58284)
			(xy 113.109392 -222.574576) (xy 113.078912 -222.575346) (xy 113.06429 -222.579692) (xy 113.043748 -222.586491)
			(xy 113.00234 -222.599067) (xy 112.981486 -222.604838) (xy 112.967455 -222.609145) (xy 112.942493 -222.624564)
			(xy 112.922956 -222.646451) (xy 112.91046 -222.672996) (xy 112.90604 -222.702001) (xy 112.907572 -222.716598)
			(xy 112.909 -222.727783) (xy 112.910524 -222.750281) (xy 112.91062 -222.761556) (xy 112.91014 -222.787527)
			(xy 112.902021 -222.838829) (xy 112.885974 -222.888229) (xy 112.862396 -222.934511) (xy 112.831868 -222.976533)
			(xy 112.795141 -223.013261) (xy 112.753119 -223.043791) (xy 112.706839 -223.06737) (xy 112.657439 -223.083418)
			(xy 112.606137 -223.09154) (xy 112.580166 -223.09201) (xy 112.552675 -223.091462) (xy 112.49845 -223.08236)
			(xy 112.446479 -223.064413) (xy 112.398192 -223.038116) (xy 112.354922 -223.004193) (xy 112.31786 -222.963578)
			(xy 112.288027 -222.917392) (xy 112.276636 -222.892366) (xy 112.235318 -222.899182) (xy 112.151886 -222.906431)
			(xy 112.110012 -222.906844) (xy 112.068266 -222.906392) (xy 111.98509 -222.899144) (xy 111.943896 -222.892366)
			(xy 111.932517 -222.917403) (xy 111.902702 -222.96361) (xy 111.865647 -223.004242) (xy 111.822375 -223.038176)
			(xy 111.77408 -223.064477) (xy 111.722098 -223.082417) (xy 111.667862 -223.091501) (xy 111.640366 -223.09201)
			(xy 111.6144 -223.091525) (xy 111.563107 -223.083395) (xy 111.513718 -223.067342) (xy 111.467448 -223.04376)
			(xy 111.425437 -223.013229) (xy 111.38872 -222.976503) (xy 111.3582 -222.934485) (xy 111.334628 -222.88821)
			(xy 111.318587 -222.838817) (xy 111.310469 -222.787522) (xy 111.309912 -222.761556) (xy 111.310134 -222.74506)
			(xy 111.313446 -222.712234) (xy 111.316516 -222.696024) (xy 111.318958 -222.680992) (xy 111.315906 -222.650707)
			(xy 111.304086 -222.622658) (xy 111.284541 -222.599324) (xy 111.259 -222.582767) (xy 111.22972 -222.574452)
			(xy 111.199289 -222.575112) (xy 111.18469 -222.579438) (xy 111.164149 -222.58624) (xy 111.122741 -222.598815)
			(xy 111.101886 -222.604584) (xy 111.087838 -222.60891) (xy 111.062856 -222.624376) (xy 111.043316 -222.64632)
			(xy 111.03084 -222.672921) (xy 111.02646 -222.701975) (xy 111.027972 -222.716598) (xy 111.0294 -222.727783)
			(xy 111.030924 -222.750281) (xy 111.03102 -222.761556) (xy 111.03054 -222.787527) (xy 111.022421 -222.838829)
			(xy 111.006374 -222.888229) (xy 110.982796 -222.934511) (xy 110.952268 -222.976533) (xy 110.915541 -223.013261)
			(xy 110.873519 -223.043791) (xy 110.827239 -223.06737) (xy 110.777839 -223.083418) (xy 110.726537 -223.09154)
			(xy 110.700566 -223.09201) (xy 110.673075 -223.091462) (xy 110.61885 -223.08236) (xy 110.566879 -223.064413)
			(xy 110.518592 -223.038116) (xy 110.475322 -223.004193) (xy 110.43826 -222.963578) (xy 110.408427 -222.917392)
			(xy 110.397036 -222.892366) (xy 110.355782 -222.899174) (xy 110.272476 -222.906424) (xy 110.230666 -222.906844)
			(xy 110.188857 -222.9064) (xy 110.105553 -222.899151) (xy 110.064296 -222.892366) (xy 110.052917 -222.917403)
			(xy 110.023102 -222.96361) (xy 109.986047 -223.004242) (xy 109.942775 -223.038176) (xy 109.89448 -223.064477)
			(xy 109.842498 -223.082417) (xy 109.788262 -223.091501) (xy 109.760766 -223.09201) (xy 109.7348 -223.091525)
			(xy 109.683507 -223.083395) (xy 109.634118 -223.067342) (xy 109.587848 -223.04376) (xy 109.545837 -223.013229)
			(xy 109.50912 -222.976503) (xy 109.4786 -222.934485) (xy 109.455028 -222.88821) (xy 109.438987 -222.838817)
			(xy 109.430869 -222.787522) (xy 109.430312 -222.761556) (xy 109.43054 -222.745123) (xy 109.433846 -222.712423)
			(xy 109.436916 -222.696278) (xy 109.439476 -222.681241) (xy 109.436507 -222.650896) (xy 109.424712 -222.62278)
			(xy 109.405141 -222.5994) (xy 109.379541 -222.58284) (xy 109.350192 -222.574576) (xy 109.319712 -222.575346)
			(xy 109.30509 -222.579692) (xy 109.284548 -222.586491) (xy 109.24314 -222.599067) (xy 109.222286 -222.604838)
			(xy 109.208255 -222.609145) (xy 109.183293 -222.624564) (xy 109.163756 -222.646451) (xy 109.15126 -222.672996)
			(xy 109.14684 -222.702001) (xy 109.148372 -222.716598) (xy 109.1498 -222.727783) (xy 109.151324 -222.750281)
			(xy 109.15142 -222.761556) (xy 109.15094 -222.787527) (xy 109.142821 -222.838829) (xy 109.126774 -222.888229)
			(xy 109.103196 -222.934511) (xy 109.072668 -222.976533) (xy 109.035941 -223.013261) (xy 108.993919 -223.043791)
			(xy 108.947639 -223.06737) (xy 108.898239 -223.083418) (xy 108.846937 -223.09154) (xy 108.820966 -223.09201)
			(xy 108.793475 -223.091462) (xy 108.73925 -223.08236) (xy 108.687279 -223.064413) (xy 108.638992 -223.038116)
			(xy 108.595722 -223.004193) (xy 108.55866 -222.963578) (xy 108.528827 -222.917392) (xy 108.517436 -222.892366)
			(xy 108.476118 -222.899182) (xy 108.392686 -222.906431) (xy 108.350812 -222.906844) (xy 108.309066 -222.906392)
			(xy 108.22589 -222.899144) (xy 108.184696 -222.892366) (xy 108.173317 -222.917403) (xy 108.143502 -222.96361)
			(xy 108.106447 -223.004242) (xy 108.063175 -223.038176) (xy 108.01488 -223.064477) (xy 107.962898 -223.082417)
			(xy 107.908662 -223.091501) (xy 107.881166 -223.09201) (xy 107.8552 -223.091525) (xy 107.803907 -223.083395)
			(xy 107.754518 -223.067342) (xy 107.708248 -223.04376) (xy 107.666237 -223.013229) (xy 107.62952 -222.976503)
			(xy 107.599 -222.934485) (xy 107.575428 -222.88821) (xy 107.559387 -222.838817) (xy 107.551269 -222.787522)
			(xy 107.550712 -222.761556) (xy 107.55094 -222.745123) (xy 107.554246 -222.712423) (xy 107.557316 -222.696278)
			(xy 107.559876 -222.681241) (xy 107.556907 -222.650896) (xy 107.545112 -222.62278) (xy 107.525541 -222.5994)
			(xy 107.499941 -222.58284) (xy 107.470592 -222.574576) (xy 107.440112 -222.575346) (xy 107.42549 -222.579692)
			(xy 107.404948 -222.586491) (xy 107.36354 -222.599067) (xy 107.342686 -222.604838) (xy 107.328655 -222.609145)
			(xy 107.303693 -222.624564) (xy 107.284156 -222.646451) (xy 107.27166 -222.672996) (xy 107.26724 -222.702001)
			(xy 107.268772 -222.716598) (xy 107.2702 -222.727783) (xy 107.271724 -222.750281) (xy 107.27182 -222.761556)
			(xy 107.27134 -222.787527) (xy 107.263221 -222.838829) (xy 107.247174 -222.888229) (xy 107.223596 -222.934511)
			(xy 107.193068 -222.976533) (xy 107.156341 -223.013261) (xy 107.114319 -223.043791) (xy 107.068039 -223.06737)
			(xy 107.018639 -223.083418) (xy 106.967337 -223.09154) (xy 106.941366 -223.09201) (xy 106.913875 -223.091462)
			(xy 106.85965 -223.08236) (xy 106.807679 -223.064413) (xy 106.759392 -223.038116) (xy 106.716122 -223.004193)
			(xy 106.67906 -222.963578) (xy 106.649227 -222.917392) (xy 106.637836 -222.892366) (xy 106.596518 -222.899182)
			(xy 106.513086 -222.906431) (xy 106.471212 -222.906844) (xy 106.429466 -222.906392) (xy 106.34629 -222.899144)
			(xy 106.305096 -222.892366) (xy 106.293717 -222.917403) (xy 106.263902 -222.96361) (xy 106.226847 -223.004242)
			(xy 106.183575 -223.038176) (xy 106.13528 -223.064477) (xy 106.083298 -223.082417) (xy 106.029062 -223.091501)
			(xy 106.001566 -223.09201) (xy 105.9756 -223.091525) (xy 105.924307 -223.083395) (xy 105.874918 -223.067342)
			(xy 105.828648 -223.04376) (xy 105.786637 -223.013229) (xy 105.74992 -222.976503) (xy 105.7194 -222.934485)
			(xy 105.695828 -222.88821) (xy 105.679787 -222.838817) (xy 105.671669 -222.787522) (xy 105.671112 -222.761556)
			(xy 105.67134 -222.745123) (xy 105.674646 -222.712423) (xy 105.677716 -222.696278) (xy 105.680276 -222.681241)
			(xy 105.677307 -222.650896) (xy 105.665512 -222.62278) (xy 105.645941 -222.5994) (xy 105.620341 -222.58284)
			(xy 105.590992 -222.574576) (xy 105.560512 -222.575346) (xy 105.54589 -222.579692) (xy 105.525348 -222.586491)
			(xy 105.48394 -222.599067) (xy 105.463086 -222.604838) (xy 105.449055 -222.609145) (xy 105.424093 -222.624564)
			(xy 105.404556 -222.646451) (xy 105.39206 -222.672996) (xy 105.38764 -222.702001) (xy 105.389172 -222.716598)
			(xy 105.3906 -222.727783) (xy 105.392124 -222.750281) (xy 105.39222 -222.761556) (xy 105.391768 -222.7861)
			(xy 105.384497 -222.834647) (xy 105.370124 -222.881583) (xy 105.348966 -222.925877) (xy 105.321487 -222.966553)
			(xy 105.288292 -223.002716) (xy 105.250113 -223.03357) (xy 105.207789 -223.058436) (xy 105.162252 -223.076767)
			(xy 105.138474 -223.082866) (xy 105.099612 -223.092264) (xy 105.099612 -223.296988) (xy 105.10007 -223.310799)
			(xy 105.107466 -223.337412) (xy 105.121722 -223.361072) (xy 105.141794 -223.380048) (xy 105.166216 -223.392953)
			(xy 105.193202 -223.398845) (xy 105.22078 -223.397292) (xy 105.246935 -223.388408) (xy 105.269753 -223.372842)
			(xy 105.278936 -223.36252) (xy 105.294708 -223.344478) (xy 105.330571 -223.312693) (xy 105.370652 -223.286428)
			(xy 105.414111 -223.266235) (xy 105.460032 -223.252538) (xy 105.507452 -223.245625) (xy 105.531412 -223.245172)
			(xy 105.55738 -223.245656) (xy 105.608676 -223.253782) (xy 105.658069 -223.269834) (xy 105.704343 -223.293414)
			(xy 105.746359 -223.323944) (xy 105.783081 -223.36067) (xy 105.813606 -223.402689) (xy 105.837181 -223.448966)
			(xy 105.853226 -223.498361) (xy 105.861347 -223.549658) (xy 105.861866 -223.575626) (xy 105.861396 -223.601076)
			(xy 105.861316 -223.601593) (xy 106.141521 -223.601593) (xy 106.141521 -223.549659) (xy 106.149646 -223.498364)
			(xy 106.165694 -223.448971) (xy 106.189272 -223.402697) (xy 106.219798 -223.360681) (xy 106.256521 -223.323958)
			(xy 106.298537 -223.293432) (xy 106.344811 -223.269854) (xy 106.394204 -223.253806) (xy 106.445499 -223.245681)
			(xy 106.497433 -223.245681) (xy 106.548728 -223.253806) (xy 106.598121 -223.269854) (xy 106.644395 -223.293432)
			(xy 106.686411 -223.323958) (xy 106.723134 -223.360681) (xy 106.75366 -223.402697) (xy 106.777238 -223.448971)
			(xy 106.793286 -223.498364) (xy 106.801411 -223.549659) (xy 106.80192 -223.575626) (xy 106.801411 -223.601593)
			(xy 106.793286 -223.652888) (xy 106.777238 -223.702281) (xy 106.75366 -223.748555) (xy 106.723134 -223.790571)
			(xy 106.686411 -223.827294) (xy 106.644395 -223.85782) (xy 106.598121 -223.881398) (xy 106.548728 -223.897446)
			(xy 106.497433 -223.905571) (xy 106.445499 -223.905571) (xy 106.394204 -223.897446) (xy 106.344811 -223.881398)
			(xy 106.298537 -223.85782) (xy 106.256521 -223.827294) (xy 106.219798 -223.790571) (xy 106.189272 -223.748555)
			(xy 106.165694 -223.702281) (xy 106.149646 -223.652888) (xy 106.141521 -223.601593) (xy 105.861316 -223.601593)
			(xy 105.853592 -223.651374) (xy 105.838172 -223.699882) (xy 105.815502 -223.745455) (xy 105.786115 -223.787015)
			(xy 105.750708 -223.823581) (xy 105.710114 -223.85429) (xy 105.665295 -223.878415) (xy 105.617308 -223.895387)
			(xy 105.592372 -223.900492) (xy 105.569258 -223.90481) (xy 105.365804 -224.257616) (xy 105.373424 -224.279714)
			(xy 105.382213 -224.306289) (xy 105.391656 -224.361457) (xy 105.39222 -224.389442) (xy 105.671112 -224.389442)
			(xy 105.671621 -224.363475) (xy 105.679746 -224.31218) (xy 105.695794 -224.262787) (xy 105.719372 -224.216513)
			(xy 105.749898 -224.174497) (xy 105.786621 -224.137774) (xy 105.828637 -224.107248) (xy 105.874911 -224.08367)
			(xy 105.924304 -224.067622) (xy 105.975599 -224.059497) (xy 106.027533 -224.059497) (xy 106.078828 -224.067622)
			(xy 106.128221 -224.08367) (xy 106.174495 -224.107248) (xy 106.216511 -224.137774) (xy 106.253234 -224.174497)
			(xy 106.28376 -224.216513) (xy 106.307338 -224.262787) (xy 106.323386 -224.31218) (xy 106.331511 -224.363475)
			(xy 106.33202 -224.389442) (xy 106.610912 -224.389442) (xy 106.611374 -224.363991) (xy 106.61916 -224.313687)
			(xy 106.634568 -224.265174) (xy 106.657236 -224.219597) (xy 106.686625 -224.178036) (xy 106.722041 -224.141475)
			(xy 106.762646 -224.110778) (xy 106.807478 -224.086672) (xy 106.855477 -224.069728) (xy 106.880406 -224.064576)
			(xy 106.903266 -224.060258) (xy 107.106974 -223.707198) (xy 107.099354 -223.685354) (xy 107.090631 -223.658761)
			(xy 107.081174 -223.603606) (xy 107.080558 -223.575626) (xy 107.081067 -223.549659) (xy 107.089192 -223.498364)
			(xy 107.10524 -223.448971) (xy 107.128818 -223.402697) (xy 107.159344 -223.360681) (xy 107.196067 -223.323958)
			(xy 107.238083 -223.293432) (xy 107.284357 -223.269854) (xy 107.33375 -223.253806) (xy 107.385045 -223.245681)
			(xy 107.436979 -223.245681) (xy 107.488274 -223.253806) (xy 107.537667 -223.269854) (xy 107.583941 -223.293432)
			(xy 107.625957 -223.323958) (xy 107.66268 -223.360681) (xy 107.693206 -223.402697) (xy 107.716784 -223.448971)
			(xy 107.732832 -223.498364) (xy 107.740957 -223.549659) (xy 107.741466 -223.575626) (xy 107.740993 -223.601077)
			(xy 107.740913 -223.601593) (xy 108.021121 -223.601593) (xy 108.021121 -223.549659) (xy 108.029246 -223.498364)
			(xy 108.045294 -223.448971) (xy 108.068872 -223.402697) (xy 108.099398 -223.360681) (xy 108.136121 -223.323958)
			(xy 108.178137 -223.293432) (xy 108.224411 -223.269854) (xy 108.273804 -223.253806) (xy 108.325099 -223.245681)
			(xy 108.377033 -223.245681) (xy 108.428328 -223.253806) (xy 108.477721 -223.269854) (xy 108.523995 -223.293432)
			(xy 108.566011 -223.323958) (xy 108.602734 -223.360681) (xy 108.63326 -223.402697) (xy 108.656838 -223.448971)
			(xy 108.672886 -223.498364) (xy 108.681011 -223.549659) (xy 108.68152 -223.575626) (xy 108.681011 -223.601593)
			(xy 108.672886 -223.652888) (xy 108.656838 -223.702281) (xy 108.63326 -223.748555) (xy 108.602734 -223.790571)
			(xy 108.566011 -223.827294) (xy 108.523995 -223.85782) (xy 108.477721 -223.881398) (xy 108.428328 -223.897446)
			(xy 108.377033 -223.905571) (xy 108.325099 -223.905571) (xy 108.273804 -223.897446) (xy 108.224411 -223.881398)
			(xy 108.178137 -223.85782) (xy 108.136121 -223.827294) (xy 108.099398 -223.790571) (xy 108.068872 -223.748555)
			(xy 108.045294 -223.702281) (xy 108.029246 -223.652888) (xy 108.021121 -223.601593) (xy 107.740913 -223.601593)
			(xy 107.733211 -223.651381) (xy 107.717806 -223.699896) (xy 107.695141 -223.745473) (xy 107.665753 -223.787035)
			(xy 107.630337 -223.823597) (xy 107.589733 -223.854293) (xy 107.5449 -223.878398) (xy 107.496901 -223.895341)
			(xy 107.471972 -223.900492) (xy 107.448858 -223.90481) (xy 107.245404 -224.257616) (xy 107.253024 -224.279714)
			(xy 107.261766 -224.306301) (xy 107.27121 -224.361461) (xy 107.27182 -224.389442) (xy 107.550712 -224.389442)
			(xy 107.551221 -224.363475) (xy 107.559346 -224.31218) (xy 107.575394 -224.262787) (xy 107.598972 -224.216513)
			(xy 107.629498 -224.174497) (xy 107.666221 -224.137774) (xy 107.708237 -224.107248) (xy 107.754511 -224.08367)
			(xy 107.803904 -224.067622) (xy 107.855199 -224.059497) (xy 107.907133 -224.059497) (xy 107.958428 -224.067622)
			(xy 108.007821 -224.08367) (xy 108.054095 -224.107248) (xy 108.096111 -224.137774) (xy 108.132834 -224.174497)
			(xy 108.16336 -224.216513) (xy 108.186938 -224.262787) (xy 108.202986 -224.31218) (xy 108.211111 -224.363475)
			(xy 108.21162 -224.389442) (xy 108.490512 -224.389442) (xy 108.490974 -224.363991) (xy 108.49876 -224.313687)
			(xy 108.514168 -224.265174) (xy 108.536836 -224.219597) (xy 108.566225 -224.178036) (xy 108.601641 -224.141475)
			(xy 108.642246 -224.110778) (xy 108.687078 -224.086672) (xy 108.735077 -224.069728) (xy 108.760006 -224.064576)
			(xy 108.782866 -224.060258) (xy 108.986574 -223.707198) (xy 108.978954 -223.685354) (xy 108.970231 -223.658761)
			(xy 108.960774 -223.603606) (xy 108.960158 -223.575626) (xy 108.960667 -223.549659) (xy 108.968792 -223.498364)
			(xy 108.98484 -223.448971) (xy 109.008418 -223.402697) (xy 109.038944 -223.360681) (xy 109.075667 -223.323958)
			(xy 109.117683 -223.293432) (xy 109.163957 -223.269854) (xy 109.21335 -223.253806) (xy 109.264645 -223.245681)
			(xy 109.316579 -223.245681) (xy 109.367874 -223.253806) (xy 109.417267 -223.269854) (xy 109.463541 -223.293432)
			(xy 109.505557 -223.323958) (xy 109.54228 -223.360681) (xy 109.572806 -223.402697) (xy 109.596384 -223.448971)
			(xy 109.612432 -223.498364) (xy 109.620557 -223.549659) (xy 109.621066 -223.575626) (xy 109.620593 -223.601077)
			(xy 109.620513 -223.601593) (xy 109.900721 -223.601593) (xy 109.900721 -223.549659) (xy 109.908846 -223.498364)
			(xy 109.924894 -223.448971) (xy 109.948472 -223.402697) (xy 109.978998 -223.360681) (xy 110.015721 -223.323958)
			(xy 110.057737 -223.293432) (xy 110.104011 -223.269854) (xy 110.153404 -223.253806) (xy 110.204699 -223.245681)
			(xy 110.256633 -223.245681) (xy 110.307928 -223.253806) (xy 110.357321 -223.269854) (xy 110.403595 -223.293432)
			(xy 110.445611 -223.323958) (xy 110.482334 -223.360681) (xy 110.51286 -223.402697) (xy 110.536438 -223.448971)
			(xy 110.552486 -223.498364) (xy 110.560611 -223.549659) (xy 110.56112 -223.575626) (xy 110.560611 -223.601593)
			(xy 110.552486 -223.652888) (xy 110.536438 -223.702281) (xy 110.51286 -223.748555) (xy 110.482334 -223.790571)
			(xy 110.445611 -223.827294) (xy 110.403595 -223.85782) (xy 110.357321 -223.881398) (xy 110.307928 -223.897446)
			(xy 110.256633 -223.905571) (xy 110.204699 -223.905571) (xy 110.153404 -223.897446) (xy 110.104011 -223.881398)
			(xy 110.057737 -223.85782) (xy 110.015721 -223.827294) (xy 109.978998 -223.790571) (xy 109.948472 -223.748555)
			(xy 109.924894 -223.702281) (xy 109.908846 -223.652888) (xy 109.900721 -223.601593) (xy 109.620513 -223.601593)
			(xy 109.612811 -223.651381) (xy 109.597406 -223.699896) (xy 109.574741 -223.745473) (xy 109.545353 -223.787035)
			(xy 109.509937 -223.823597) (xy 109.469333 -223.854293) (xy 109.4245 -223.878398) (xy 109.376501 -223.895341)
			(xy 109.351572 -223.900492) (xy 109.328458 -223.90481) (xy 109.125004 -224.257616) (xy 109.132624 -224.279714)
			(xy 109.141366 -224.306301) (xy 109.15081 -224.361461) (xy 109.15142 -224.389442) (xy 109.430312 -224.389442)
			(xy 109.430821 -224.363475) (xy 109.438946 -224.31218) (xy 109.454994 -224.262787) (xy 109.478572 -224.216513)
			(xy 109.509098 -224.174497) (xy 109.545821 -224.137774) (xy 109.587837 -224.107248) (xy 109.634111 -224.08367)
			(xy 109.683504 -224.067622) (xy 109.734799 -224.059497) (xy 109.786733 -224.059497) (xy 109.838028 -224.067622)
			(xy 109.887421 -224.08367) (xy 109.933695 -224.107248) (xy 109.975711 -224.137774) (xy 110.012434 -224.174497)
			(xy 110.04296 -224.216513) (xy 110.066538 -224.262787) (xy 110.082586 -224.31218) (xy 110.090711 -224.363475)
			(xy 110.09122 -224.389442) (xy 110.370112 -224.389442) (xy 110.370574 -224.363991) (xy 110.37836 -224.313687)
			(xy 110.393768 -224.265174) (xy 110.416436 -224.219597) (xy 110.445825 -224.178036) (xy 110.481241 -224.141475)
			(xy 110.521846 -224.110778) (xy 110.566678 -224.086672) (xy 110.614677 -224.069728) (xy 110.639606 -224.064576)
			(xy 110.662466 -224.060258) (xy 110.866174 -223.707198) (xy 110.858554 -223.685354) (xy 110.849831 -223.658761)
			(xy 110.840374 -223.603606) (xy 110.839758 -223.575626) (xy 110.840267 -223.549659) (xy 110.848392 -223.498364)
			(xy 110.86444 -223.448971) (xy 110.888018 -223.402697) (xy 110.918544 -223.360681) (xy 110.955267 -223.323958)
			(xy 110.997283 -223.293432) (xy 111.043557 -223.269854) (xy 111.09295 -223.253806) (xy 111.144245 -223.245681)
			(xy 111.196179 -223.245681) (xy 111.247474 -223.253806) (xy 111.296867 -223.269854) (xy 111.343141 -223.293432)
			(xy 111.385157 -223.323958) (xy 111.42188 -223.360681) (xy 111.452406 -223.402697) (xy 111.475984 -223.448971)
			(xy 111.492032 -223.498364) (xy 111.500157 -223.549659) (xy 111.500666 -223.575626) (xy 111.500193 -223.601077)
			(xy 111.500113 -223.601593) (xy 111.780321 -223.601593) (xy 111.780321 -223.549659) (xy 111.788446 -223.498364)
			(xy 111.804494 -223.448971) (xy 111.828072 -223.402697) (xy 111.858598 -223.360681) (xy 111.895321 -223.323958)
			(xy 111.937337 -223.293432) (xy 111.983611 -223.269854) (xy 112.033004 -223.253806) (xy 112.084299 -223.245681)
			(xy 112.136233 -223.245681) (xy 112.187528 -223.253806) (xy 112.236921 -223.269854) (xy 112.283195 -223.293432)
			(xy 112.325211 -223.323958) (xy 112.361934 -223.360681) (xy 112.39246 -223.402697) (xy 112.416038 -223.448971)
			(xy 112.432086 -223.498364) (xy 112.440211 -223.549659) (xy 112.44072 -223.575626) (xy 112.440211 -223.601593)
			(xy 112.432086 -223.652888) (xy 112.416038 -223.702281) (xy 112.39246 -223.748555) (xy 112.361934 -223.790571)
			(xy 112.325211 -223.827294) (xy 112.283195 -223.85782) (xy 112.236921 -223.881398) (xy 112.187528 -223.897446)
			(xy 112.136233 -223.905571) (xy 112.084299 -223.905571) (xy 112.033004 -223.897446) (xy 111.983611 -223.881398)
			(xy 111.937337 -223.85782) (xy 111.895321 -223.827294) (xy 111.858598 -223.790571) (xy 111.828072 -223.748555)
			(xy 111.804494 -223.702281) (xy 111.788446 -223.652888) (xy 111.780321 -223.601593) (xy 111.500113 -223.601593)
			(xy 111.492411 -223.651381) (xy 111.477006 -223.699896) (xy 111.454341 -223.745473) (xy 111.424953 -223.787035)
			(xy 111.389537 -223.823597) (xy 111.348933 -223.854293) (xy 111.3041 -223.878398) (xy 111.256101 -223.895341)
			(xy 111.231172 -223.900492) (xy 111.208058 -223.90481) (xy 111.004604 -224.257616) (xy 111.012224 -224.279714)
			(xy 111.020966 -224.306301) (xy 111.03041 -224.361461) (xy 111.03102 -224.389442) (xy 111.309912 -224.389442)
			(xy 111.310421 -224.363475) (xy 111.318546 -224.31218) (xy 111.334594 -224.262787) (xy 111.358172 -224.216513)
			(xy 111.388698 -224.174497) (xy 111.425421 -224.137774) (xy 111.467437 -224.107248) (xy 111.513711 -224.08367)
			(xy 111.563104 -224.067622) (xy 111.614399 -224.059497) (xy 111.666333 -224.059497) (xy 111.717628 -224.067622)
			(xy 111.767021 -224.08367) (xy 111.813295 -224.107248) (xy 111.855311 -224.137774) (xy 111.892034 -224.174497)
			(xy 111.92256 -224.216513) (xy 111.946138 -224.262787) (xy 111.962186 -224.31218) (xy 111.970311 -224.363475)
			(xy 111.97082 -224.389442) (xy 112.249712 -224.389442) (xy 112.250174 -224.363991) (xy 112.25796 -224.313687)
			(xy 112.273368 -224.265174) (xy 112.296036 -224.219597) (xy 112.325425 -224.178036) (xy 112.360841 -224.141475)
			(xy 112.401446 -224.110778) (xy 112.446278 -224.086672) (xy 112.494277 -224.069728) (xy 112.519206 -224.064576)
			(xy 112.542066 -224.060258) (xy 112.745774 -223.707198) (xy 112.738154 -223.685354) (xy 112.729431 -223.658761)
			(xy 112.719974 -223.603606) (xy 112.719358 -223.575626) (xy 112.719867 -223.549659) (xy 112.727992 -223.498364)
			(xy 112.74404 -223.448971) (xy 112.767618 -223.402697) (xy 112.798144 -223.360681) (xy 112.834867 -223.323958)
			(xy 112.876883 -223.293432) (xy 112.923157 -223.269854) (xy 112.97255 -223.253806) (xy 113.023845 -223.245681)
			(xy 113.075779 -223.245681) (xy 113.127074 -223.253806) (xy 113.176467 -223.269854) (xy 113.222741 -223.293432)
			(xy 113.264757 -223.323958) (xy 113.30148 -223.360681) (xy 113.332006 -223.402697) (xy 113.355584 -223.448971)
			(xy 113.371632 -223.498364) (xy 113.379757 -223.549659) (xy 113.380266 -223.575626) (xy 113.379793 -223.601077)
			(xy 113.379713 -223.601593) (xy 113.659921 -223.601593) (xy 113.659921 -223.549659) (xy 113.668046 -223.498364)
			(xy 113.684094 -223.448971) (xy 113.707672 -223.402697) (xy 113.738198 -223.360681) (xy 113.774921 -223.323958)
			(xy 113.816937 -223.293432) (xy 113.863211 -223.269854) (xy 113.912604 -223.253806) (xy 113.963899 -223.245681)
			(xy 114.015833 -223.245681) (xy 114.067128 -223.253806) (xy 114.116521 -223.269854) (xy 114.162795 -223.293432)
			(xy 114.204811 -223.323958) (xy 114.241534 -223.360681) (xy 114.27206 -223.402697) (xy 114.295638 -223.448971)
			(xy 114.311686 -223.498364) (xy 114.319811 -223.549659) (xy 114.32032 -223.575626) (xy 114.319811 -223.601593)
			(xy 114.311686 -223.652888) (xy 114.295638 -223.702281) (xy 114.27206 -223.748555) (xy 114.241534 -223.790571)
			(xy 114.204811 -223.827294) (xy 114.162795 -223.85782) (xy 114.116521 -223.881398) (xy 114.067128 -223.897446)
			(xy 114.015833 -223.905571) (xy 113.963899 -223.905571) (xy 113.912604 -223.897446) (xy 113.863211 -223.881398)
			(xy 113.816937 -223.85782) (xy 113.774921 -223.827294) (xy 113.738198 -223.790571) (xy 113.707672 -223.748555)
			(xy 113.684094 -223.702281) (xy 113.668046 -223.652888) (xy 113.659921 -223.601593) (xy 113.379713 -223.601593)
			(xy 113.372011 -223.651381) (xy 113.356606 -223.699896) (xy 113.333941 -223.745473) (xy 113.304553 -223.787035)
			(xy 113.269137 -223.823597) (xy 113.228533 -223.854293) (xy 113.1837 -223.878398) (xy 113.135701 -223.895341)
			(xy 113.110772 -223.900492) (xy 113.087658 -223.90481) (xy 112.884204 -224.257616) (xy 112.891824 -224.279714)
			(xy 112.900566 -224.306301) (xy 112.91001 -224.361461) (xy 112.91062 -224.389442) (xy 113.189512 -224.389442)
			(xy 113.190021 -224.363475) (xy 113.198146 -224.31218) (xy 113.214194 -224.262787) (xy 113.237772 -224.216513)
			(xy 113.268298 -224.174497) (xy 113.305021 -224.137774) (xy 113.347037 -224.107248) (xy 113.393311 -224.08367)
			(xy 113.442704 -224.067622) (xy 113.493999 -224.059497) (xy 113.545933 -224.059497) (xy 113.597228 -224.067622)
			(xy 113.646621 -224.08367) (xy 113.692895 -224.107248) (xy 113.734911 -224.137774) (xy 113.771634 -224.174497)
			(xy 113.80216 -224.216513) (xy 113.825738 -224.262787) (xy 113.841786 -224.31218) (xy 113.849911 -224.363475)
			(xy 113.85042 -224.389442) (xy 114.129312 -224.389442) (xy 114.129774 -224.363991) (xy 114.13756 -224.313687)
			(xy 114.152968 -224.265174) (xy 114.175636 -224.219597) (xy 114.205025 -224.178036) (xy 114.240441 -224.141475)
			(xy 114.281046 -224.110778) (xy 114.325878 -224.086672) (xy 114.373877 -224.069728) (xy 114.398806 -224.064576)
			(xy 114.421666 -224.060258) (xy 114.625628 -223.706944) (xy 114.617754 -223.6851) (xy 114.609091 -223.658565)
			(xy 114.599773 -223.603534) (xy 114.599212 -223.575626) (xy 114.599721 -223.549659) (xy 114.607846 -223.498364)
			(xy 114.623894 -223.448971) (xy 114.647472 -223.402697) (xy 114.677998 -223.360681) (xy 114.714721 -223.323958)
			(xy 114.756737 -223.293432) (xy 114.803011 -223.269854) (xy 114.852404 -223.253806) (xy 114.903699 -223.245681)
			(xy 114.955633 -223.245681) (xy 115.006928 -223.253806) (xy 115.056321 -223.269854) (xy 115.102595 -223.293432)
			(xy 115.144611 -223.323958) (xy 115.181334 -223.360681) (xy 115.21186 -223.402697) (xy 115.235438 -223.448971)
			(xy 115.251486 -223.498364) (xy 115.259611 -223.549659) (xy 115.26012 -223.575626) (xy 115.259646 -223.601088)
			(xy 115.259568 -223.601593) (xy 115.539521 -223.601593) (xy 115.539521 -223.549659) (xy 115.547646 -223.498364)
			(xy 115.563694 -223.448971) (xy 115.587272 -223.402697) (xy 115.617798 -223.360681) (xy 115.654521 -223.323958)
			(xy 115.696537 -223.293432) (xy 115.742811 -223.269854) (xy 115.792204 -223.253806) (xy 115.843499 -223.245681)
			(xy 115.895433 -223.245681) (xy 115.946728 -223.253806) (xy 115.996121 -223.269854) (xy 116.042395 -223.293432)
			(xy 116.084411 -223.323958) (xy 116.121134 -223.360681) (xy 116.15166 -223.402697) (xy 116.175238 -223.448971)
			(xy 116.191286 -223.498364) (xy 116.199411 -223.549659) (xy 116.19992 -223.575626) (xy 116.199411 -223.601593)
			(xy 116.191286 -223.652888) (xy 116.175238 -223.702281) (xy 116.15166 -223.748555) (xy 116.121134 -223.790571)
			(xy 116.084411 -223.827294) (xy 116.042395 -223.85782) (xy 115.996121 -223.881398) (xy 115.946728 -223.897446)
			(xy 115.895433 -223.905571) (xy 115.843499 -223.905571) (xy 115.792204 -223.897446) (xy 115.742811 -223.881398)
			(xy 115.696537 -223.85782) (xy 115.654521 -223.827294) (xy 115.617798 -223.790571) (xy 115.587272 -223.748555)
			(xy 115.563694 -223.702281) (xy 115.547646 -223.652888) (xy 115.539521 -223.601593) (xy 115.259568 -223.601593)
			(xy 115.251844 -223.651411) (xy 115.236413 -223.699941) (xy 115.213719 -223.745529) (xy 115.184299 -223.787095)
			(xy 115.14885 -223.823656) (xy 115.108212 -223.854344) (xy 115.063346 -223.878434) (xy 115.015315 -223.895354)
			(xy 114.990372 -223.900492) (xy 114.967258 -223.90481) (xy 114.763804 -224.257616) (xy 114.771424 -224.279714)
			(xy 114.780166 -224.306301) (xy 114.78961 -224.361461) (xy 114.79022 -224.389442) (xy 115.069112 -224.389442)
			(xy 115.069621 -224.363475) (xy 115.077746 -224.31218) (xy 115.093794 -224.262787) (xy 115.117372 -224.216513)
			(xy 115.147898 -224.174497) (xy 115.184621 -224.137774) (xy 115.226637 -224.107248) (xy 115.272911 -224.08367)
			(xy 115.322304 -224.067622) (xy 115.373599 -224.059497) (xy 115.425533 -224.059497) (xy 115.476828 -224.067622)
			(xy 115.526221 -224.08367) (xy 115.572495 -224.107248) (xy 115.614511 -224.137774) (xy 115.651234 -224.174497)
			(xy 115.68176 -224.216513) (xy 115.705338 -224.262787) (xy 115.721386 -224.31218) (xy 115.729511 -224.363475)
			(xy 115.73002 -224.389442) (xy 116.008912 -224.389442) (xy 116.009374 -224.363991) (xy 116.01716 -224.313687)
			(xy 116.032568 -224.265174) (xy 116.055236 -224.219597) (xy 116.084625 -224.178036) (xy 116.120041 -224.141475)
			(xy 116.160646 -224.110778) (xy 116.205478 -224.086672) (xy 116.253477 -224.069728) (xy 116.278406 -224.064576)
			(xy 116.301266 -224.060258) (xy 116.504974 -223.707198) (xy 116.497354 -223.685354) (xy 116.488631 -223.658761)
			(xy 116.479174 -223.603606) (xy 116.478558 -223.575626) (xy 116.479067 -223.549659) (xy 116.487192 -223.498364)
			(xy 116.50324 -223.448971) (xy 116.526818 -223.402697) (xy 116.557344 -223.360681) (xy 116.594067 -223.323958)
			(xy 116.636083 -223.293432) (xy 116.682357 -223.269854) (xy 116.73175 -223.253806) (xy 116.783045 -223.245681)
			(xy 116.834979 -223.245681) (xy 116.886274 -223.253806) (xy 116.935667 -223.269854) (xy 116.981941 -223.293432)
			(xy 117.023957 -223.323958) (xy 117.06068 -223.360681) (xy 117.091206 -223.402697) (xy 117.114784 -223.448971)
			(xy 117.130832 -223.498364) (xy 117.138957 -223.549659) (xy 117.139466 -223.575626) (xy 117.138993 -223.601077)
			(xy 117.138913 -223.601593) (xy 117.419121 -223.601593) (xy 117.419121 -223.549659) (xy 117.427246 -223.498364)
			(xy 117.443294 -223.448971) (xy 117.466872 -223.402697) (xy 117.497398 -223.360681) (xy 117.534121 -223.323958)
			(xy 117.576137 -223.293432) (xy 117.622411 -223.269854) (xy 117.671804 -223.253806) (xy 117.723099 -223.245681)
			(xy 117.775033 -223.245681) (xy 117.826328 -223.253806) (xy 117.875721 -223.269854) (xy 117.921995 -223.293432)
			(xy 117.964011 -223.323958) (xy 118.000734 -223.360681) (xy 118.03126 -223.402697) (xy 118.054838 -223.448971)
			(xy 118.070886 -223.498364) (xy 118.079011 -223.549659) (xy 118.07952 -223.575626) (xy 118.079011 -223.601593)
			(xy 118.070886 -223.652888) (xy 118.054838 -223.702281) (xy 118.03126 -223.748555) (xy 118.000734 -223.790571)
			(xy 117.964011 -223.827294) (xy 117.921995 -223.85782) (xy 117.875721 -223.881398) (xy 117.826328 -223.897446)
			(xy 117.775033 -223.905571) (xy 117.723099 -223.905571) (xy 117.671804 -223.897446) (xy 117.622411 -223.881398)
			(xy 117.576137 -223.85782) (xy 117.534121 -223.827294) (xy 117.497398 -223.790571) (xy 117.466872 -223.748555)
			(xy 117.443294 -223.702281) (xy 117.427246 -223.652888) (xy 117.419121 -223.601593) (xy 117.138913 -223.601593)
			(xy 117.131211 -223.651381) (xy 117.115806 -223.699896) (xy 117.093141 -223.745473) (xy 117.063753 -223.787035)
			(xy 117.028337 -223.823597) (xy 116.987733 -223.854293) (xy 116.9429 -223.878398) (xy 116.894901 -223.895341)
			(xy 116.869972 -223.900492) (xy 116.846858 -223.90481) (xy 116.643404 -224.257616) (xy 116.651024 -224.279714)
			(xy 116.659766 -224.306301) (xy 116.66921 -224.361461) (xy 116.66982 -224.389442) (xy 116.948712 -224.389442)
			(xy 116.949221 -224.363475) (xy 116.957346 -224.31218) (xy 116.973394 -224.262787) (xy 116.996972 -224.216513)
			(xy 117.027498 -224.174497) (xy 117.064221 -224.137774) (xy 117.106237 -224.107248) (xy 117.152511 -224.08367)
			(xy 117.201904 -224.067622) (xy 117.253199 -224.059497) (xy 117.305133 -224.059497) (xy 117.356428 -224.067622)
			(xy 117.405821 -224.08367) (xy 117.452095 -224.107248) (xy 117.494111 -224.137774) (xy 117.530834 -224.174497)
			(xy 117.56136 -224.216513) (xy 117.584938 -224.262787) (xy 117.600986 -224.31218) (xy 117.609111 -224.363475)
			(xy 117.60962 -224.389442) (xy 117.888512 -224.389442) (xy 117.888974 -224.363991) (xy 117.89676 -224.313687)
			(xy 117.912168 -224.265174) (xy 117.934836 -224.219597) (xy 117.964225 -224.178036) (xy 117.999641 -224.141475)
			(xy 118.040246 -224.110778) (xy 118.085078 -224.086672) (xy 118.133077 -224.069728) (xy 118.158006 -224.064576)
			(xy 118.180866 -224.060258) (xy 118.384574 -223.707198) (xy 118.376954 -223.685354) (xy 118.368231 -223.658761)
			(xy 118.358774 -223.603606) (xy 118.358158 -223.575626) (xy 118.358667 -223.549659) (xy 118.366792 -223.498364)
			(xy 118.38284 -223.448971) (xy 118.406418 -223.402697) (xy 118.436944 -223.360681) (xy 118.473667 -223.323958)
			(xy 118.515683 -223.293432) (xy 118.561957 -223.269854) (xy 118.61135 -223.253806) (xy 118.662645 -223.245681)
			(xy 118.714579 -223.245681) (xy 118.765874 -223.253806) (xy 118.815267 -223.269854) (xy 118.861541 -223.293432)
			(xy 118.903557 -223.323958) (xy 118.94028 -223.360681) (xy 118.970806 -223.402697) (xy 118.994384 -223.448971)
			(xy 119.010432 -223.498364) (xy 119.018557 -223.549659) (xy 119.019066 -223.575626) (xy 119.018593 -223.601077)
			(xy 119.018513 -223.601593) (xy 119.298721 -223.601593) (xy 119.298721 -223.549659) (xy 119.306846 -223.498364)
			(xy 119.322894 -223.448971) (xy 119.346472 -223.402697) (xy 119.376998 -223.360681) (xy 119.413721 -223.323958)
			(xy 119.455737 -223.293432) (xy 119.502011 -223.269854) (xy 119.551404 -223.253806) (xy 119.602699 -223.245681)
			(xy 119.654633 -223.245681) (xy 119.705928 -223.253806) (xy 119.755321 -223.269854) (xy 119.801595 -223.293432)
			(xy 119.843611 -223.323958) (xy 119.880334 -223.360681) (xy 119.91086 -223.402697) (xy 119.934438 -223.448971)
			(xy 119.950486 -223.498364) (xy 119.958611 -223.549659) (xy 119.95912 -223.575626) (xy 119.958611 -223.601593)
			(xy 119.950486 -223.652888) (xy 119.934438 -223.702281) (xy 119.91086 -223.748555) (xy 119.880334 -223.790571)
			(xy 119.843611 -223.827294) (xy 119.801595 -223.85782) (xy 119.755321 -223.881398) (xy 119.705928 -223.897446)
			(xy 119.654633 -223.905571) (xy 119.602699 -223.905571) (xy 119.551404 -223.897446) (xy 119.502011 -223.881398)
			(xy 119.455737 -223.85782) (xy 119.413721 -223.827294) (xy 119.376998 -223.790571) (xy 119.346472 -223.748555)
			(xy 119.322894 -223.702281) (xy 119.306846 -223.652888) (xy 119.298721 -223.601593) (xy 119.018513 -223.601593)
			(xy 119.010811 -223.651381) (xy 118.995406 -223.699896) (xy 118.972741 -223.745473) (xy 118.943353 -223.787035)
			(xy 118.907937 -223.823597) (xy 118.867333 -223.854293) (xy 118.8225 -223.878398) (xy 118.774501 -223.895341)
			(xy 118.749572 -223.900492) (xy 118.726458 -223.90481) (xy 118.523004 -224.257616) (xy 118.530624 -224.279714)
			(xy 118.539366 -224.306301) (xy 118.54881 -224.361461) (xy 118.54942 -224.389442) (xy 118.828312 -224.389442)
			(xy 118.828821 -224.363475) (xy 118.836946 -224.31218) (xy 118.852994 -224.262787) (xy 118.876572 -224.216513)
			(xy 118.907098 -224.174497) (xy 118.943821 -224.137774) (xy 118.985837 -224.107248) (xy 119.032111 -224.08367)
			(xy 119.081504 -224.067622) (xy 119.132799 -224.059497) (xy 119.184733 -224.059497) (xy 119.236028 -224.067622)
			(xy 119.285421 -224.08367) (xy 119.331695 -224.107248) (xy 119.373711 -224.137774) (xy 119.410434 -224.174497)
			(xy 119.44096 -224.216513) (xy 119.464538 -224.262787) (xy 119.480586 -224.31218) (xy 119.488711 -224.363475)
			(xy 119.48922 -224.389442) (xy 119.768112 -224.389442) (xy 119.768574 -224.363991) (xy 119.77636 -224.313687)
			(xy 119.791768 -224.265174) (xy 119.814436 -224.219597) (xy 119.843825 -224.178036) (xy 119.879241 -224.141475)
			(xy 119.919846 -224.110778) (xy 119.964678 -224.086672) (xy 120.012677 -224.069728) (xy 120.037606 -224.064576)
			(xy 120.060466 -224.060258) (xy 120.264174 -223.707198) (xy 120.256554 -223.685354) (xy 120.247831 -223.658761)
			(xy 120.238374 -223.603606) (xy 120.237758 -223.575626) (xy 120.238267 -223.549659) (xy 120.246392 -223.498364)
			(xy 120.26244 -223.448971) (xy 120.286018 -223.402697) (xy 120.316544 -223.360681) (xy 120.353267 -223.323958)
			(xy 120.395283 -223.293432) (xy 120.441557 -223.269854) (xy 120.49095 -223.253806) (xy 120.542245 -223.245681)
			(xy 120.594179 -223.245681) (xy 120.645474 -223.253806) (xy 120.694867 -223.269854) (xy 120.741141 -223.293432)
			(xy 120.783157 -223.323958) (xy 120.81988 -223.360681) (xy 120.850406 -223.402697) (xy 120.873984 -223.448971)
			(xy 120.890032 -223.498364) (xy 120.898157 -223.549659) (xy 120.898666 -223.575626) (xy 120.898193 -223.601077)
			(xy 120.898113 -223.601593) (xy 121.178321 -223.601593) (xy 121.178321 -223.549659) (xy 121.186446 -223.498364)
			(xy 121.202494 -223.448971) (xy 121.226072 -223.402697) (xy 121.256598 -223.360681) (xy 121.293321 -223.323958)
			(xy 121.335337 -223.293432) (xy 121.381611 -223.269854) (xy 121.431004 -223.253806) (xy 121.482299 -223.245681)
			(xy 121.534233 -223.245681) (xy 121.585528 -223.253806) (xy 121.634921 -223.269854) (xy 121.681195 -223.293432)
			(xy 121.723211 -223.323958) (xy 121.759934 -223.360681) (xy 121.79046 -223.402697) (xy 121.814038 -223.448971)
			(xy 121.830086 -223.498364) (xy 121.838211 -223.549659) (xy 121.83872 -223.575626) (xy 121.838211 -223.601593)
			(xy 121.830086 -223.652888) (xy 121.814038 -223.702281) (xy 121.79046 -223.748555) (xy 121.759934 -223.790571)
			(xy 121.723211 -223.827294) (xy 121.681195 -223.85782) (xy 121.634921 -223.881398) (xy 121.585528 -223.897446)
			(xy 121.534233 -223.905571) (xy 121.482299 -223.905571) (xy 121.431004 -223.897446) (xy 121.381611 -223.881398)
			(xy 121.335337 -223.85782) (xy 121.293321 -223.827294) (xy 121.256598 -223.790571) (xy 121.226072 -223.748555)
			(xy 121.202494 -223.702281) (xy 121.186446 -223.652888) (xy 121.178321 -223.601593) (xy 120.898113 -223.601593)
			(xy 120.890411 -223.651381) (xy 120.875006 -223.699896) (xy 120.852341 -223.745473) (xy 120.822953 -223.787035)
			(xy 120.787537 -223.823597) (xy 120.746933 -223.854293) (xy 120.7021 -223.878398) (xy 120.654101 -223.895341)
			(xy 120.629172 -223.900492) (xy 120.606058 -223.90481) (xy 120.402604 -224.257616) (xy 120.410224 -224.279714)
			(xy 120.418966 -224.306301) (xy 120.42841 -224.361461) (xy 120.42902 -224.389442) (xy 120.707912 -224.389442)
			(xy 120.708421 -224.363475) (xy 120.716546 -224.31218) (xy 120.732594 -224.262787) (xy 120.756172 -224.216513)
			(xy 120.786698 -224.174497) (xy 120.823421 -224.137774) (xy 120.865437 -224.107248) (xy 120.911711 -224.08367)
			(xy 120.961104 -224.067622) (xy 121.012399 -224.059497) (xy 121.064333 -224.059497) (xy 121.115628 -224.067622)
			(xy 121.165021 -224.08367) (xy 121.211295 -224.107248) (xy 121.253311 -224.137774) (xy 121.290034 -224.174497)
			(xy 121.32056 -224.216513) (xy 121.344138 -224.262787) (xy 121.360186 -224.31218) (xy 121.368311 -224.363475)
			(xy 121.36882 -224.389442) (xy 121.647712 -224.389442) (xy 121.648174 -224.363991) (xy 121.65596 -224.313687)
			(xy 121.671368 -224.265174) (xy 121.694036 -224.219597) (xy 121.723425 -224.178036) (xy 121.758841 -224.141475)
			(xy 121.799446 -224.110778) (xy 121.844278 -224.086672) (xy 121.892277 -224.069728) (xy 121.917206 -224.064576)
			(xy 121.940066 -224.060258) (xy 122.143774 -223.707198) (xy 122.136154 -223.685354) (xy 122.127431 -223.658761)
			(xy 122.117974 -223.603606) (xy 122.117358 -223.575626) (xy 122.117867 -223.549659) (xy 122.125992 -223.498364)
			(xy 122.14204 -223.448971) (xy 122.165618 -223.402697) (xy 122.196144 -223.360681) (xy 122.232867 -223.323958)
			(xy 122.274883 -223.293432) (xy 122.321157 -223.269854) (xy 122.37055 -223.253806) (xy 122.421845 -223.245681)
			(xy 122.473779 -223.245681) (xy 122.525074 -223.253806) (xy 122.574467 -223.269854) (xy 122.620741 -223.293432)
			(xy 122.662757 -223.323958) (xy 122.69948 -223.360681) (xy 122.730006 -223.402697) (xy 122.753584 -223.448971)
			(xy 122.769632 -223.498364) (xy 122.777757 -223.549659) (xy 122.778266 -223.575626) (xy 122.777793 -223.601077)
			(xy 122.777713 -223.601593) (xy 123.057921 -223.601593) (xy 123.057921 -223.549659) (xy 123.066046 -223.498364)
			(xy 123.082094 -223.448971) (xy 123.105672 -223.402697) (xy 123.136198 -223.360681) (xy 123.172921 -223.323958)
			(xy 123.214937 -223.293432) (xy 123.261211 -223.269854) (xy 123.310604 -223.253806) (xy 123.361899 -223.245681)
			(xy 123.413833 -223.245681) (xy 123.465128 -223.253806) (xy 123.514521 -223.269854) (xy 123.560795 -223.293432)
			(xy 123.602811 -223.323958) (xy 123.639534 -223.360681) (xy 123.67006 -223.402697) (xy 123.693638 -223.448971)
			(xy 123.709686 -223.498364) (xy 123.717811 -223.549659) (xy 123.71832 -223.575626) (xy 123.717811 -223.601593)
			(xy 123.709686 -223.652888) (xy 123.693638 -223.702281) (xy 123.67006 -223.748555) (xy 123.639534 -223.790571)
			(xy 123.602811 -223.827294) (xy 123.560795 -223.85782) (xy 123.514521 -223.881398) (xy 123.465128 -223.897446)
			(xy 123.413833 -223.905571) (xy 123.361899 -223.905571) (xy 123.310604 -223.897446) (xy 123.261211 -223.881398)
			(xy 123.214937 -223.85782) (xy 123.172921 -223.827294) (xy 123.136198 -223.790571) (xy 123.105672 -223.748555)
			(xy 123.082094 -223.702281) (xy 123.066046 -223.652888) (xy 123.057921 -223.601593) (xy 122.777713 -223.601593)
			(xy 122.770011 -223.651381) (xy 122.754606 -223.699896) (xy 122.731941 -223.745473) (xy 122.702553 -223.787035)
			(xy 122.667137 -223.823597) (xy 122.626533 -223.854293) (xy 122.5817 -223.878398) (xy 122.533701 -223.895341)
			(xy 122.508772 -223.900492) (xy 122.485658 -223.90481) (xy 122.282204 -224.257616) (xy 122.289824 -224.279714)
			(xy 122.298566 -224.306301) (xy 122.30801 -224.361461) (xy 122.30862 -224.389442) (xy 122.587512 -224.389442)
			(xy 122.588021 -224.363475) (xy 122.596146 -224.31218) (xy 122.612194 -224.262787) (xy 122.635772 -224.216513)
			(xy 122.666298 -224.174497) (xy 122.703021 -224.137774) (xy 122.745037 -224.107248) (xy 122.791311 -224.08367)
			(xy 122.840704 -224.067622) (xy 122.891999 -224.059497) (xy 122.943933 -224.059497) (xy 122.995228 -224.067622)
			(xy 123.044621 -224.08367) (xy 123.090895 -224.107248) (xy 123.132911 -224.137774) (xy 123.169634 -224.174497)
			(xy 123.20016 -224.216513) (xy 123.223738 -224.262787) (xy 123.239786 -224.31218) (xy 123.247911 -224.363475)
			(xy 123.24842 -224.389442) (xy 123.527312 -224.389442) (xy 123.527774 -224.363991) (xy 123.53556 -224.313687)
			(xy 123.550968 -224.265174) (xy 123.573636 -224.219597) (xy 123.603025 -224.178036) (xy 123.638441 -224.141475)
			(xy 123.679046 -224.110778) (xy 123.723878 -224.086672) (xy 123.771877 -224.069728) (xy 123.796806 -224.064576)
			(xy 123.819666 -224.060258) (xy 124.023374 -223.707198) (xy 124.015754 -223.685354) (xy 124.007031 -223.658761)
			(xy 123.997574 -223.603606) (xy 123.996958 -223.575626) (xy 123.997467 -223.549659) (xy 124.005592 -223.498364)
			(xy 124.02164 -223.448971) (xy 124.045218 -223.402697) (xy 124.075744 -223.360681) (xy 124.112467 -223.323958)
			(xy 124.154483 -223.293432) (xy 124.200757 -223.269854) (xy 124.25015 -223.253806) (xy 124.301445 -223.245681)
			(xy 124.353379 -223.245681) (xy 124.404674 -223.253806) (xy 124.454067 -223.269854) (xy 124.500341 -223.293432)
			(xy 124.542357 -223.323958) (xy 124.57908 -223.360681) (xy 124.609606 -223.402697) (xy 124.633184 -223.448971)
			(xy 124.649232 -223.498364) (xy 124.657357 -223.549659) (xy 124.657866 -223.575626) (xy 124.657393 -223.601077)
			(xy 124.657313 -223.601593) (xy 124.937521 -223.601593) (xy 124.937521 -223.549659) (xy 124.945646 -223.498364)
			(xy 124.961694 -223.448971) (xy 124.985272 -223.402697) (xy 125.015798 -223.360681) (xy 125.052521 -223.323958)
			(xy 125.094537 -223.293432) (xy 125.140811 -223.269854) (xy 125.190204 -223.253806) (xy 125.241499 -223.245681)
			(xy 125.293433 -223.245681) (xy 125.344728 -223.253806) (xy 125.394121 -223.269854) (xy 125.440395 -223.293432)
			(xy 125.482411 -223.323958) (xy 125.519134 -223.360681) (xy 125.54966 -223.402697) (xy 125.573238 -223.448971)
			(xy 125.589286 -223.498364) (xy 125.597411 -223.549659) (xy 125.59792 -223.575626) (xy 125.597411 -223.601593)
			(xy 125.589286 -223.652888) (xy 125.573238 -223.702281) (xy 125.54966 -223.748555) (xy 125.519134 -223.790571)
			(xy 125.482411 -223.827294) (xy 125.440395 -223.85782) (xy 125.394121 -223.881398) (xy 125.344728 -223.897446)
			(xy 125.293433 -223.905571) (xy 125.241499 -223.905571) (xy 125.190204 -223.897446) (xy 125.140811 -223.881398)
			(xy 125.094537 -223.85782) (xy 125.052521 -223.827294) (xy 125.015798 -223.790571) (xy 124.985272 -223.748555)
			(xy 124.961694 -223.702281) (xy 124.945646 -223.652888) (xy 124.937521 -223.601593) (xy 124.657313 -223.601593)
			(xy 124.649611 -223.651381) (xy 124.634206 -223.699896) (xy 124.611541 -223.745473) (xy 124.582153 -223.787035)
			(xy 124.546737 -223.823597) (xy 124.506133 -223.854293) (xy 124.4613 -223.878398) (xy 124.413301 -223.895341)
			(xy 124.388372 -223.900492) (xy 124.365258 -223.90481) (xy 124.161804 -224.257616) (xy 124.169424 -224.279714)
			(xy 124.178166 -224.306301) (xy 124.18761 -224.361461) (xy 124.18822 -224.389442) (xy 124.187711 -224.415409)
			(xy 124.179586 -224.466704) (xy 124.163538 -224.516097) (xy 124.13996 -224.562371) (xy 124.109434 -224.604387)
			(xy 124.072711 -224.64111) (xy 124.030695 -224.671636) (xy 123.984421 -224.695214) (xy 123.935028 -224.711262)
			(xy 123.883733 -224.719387) (xy 123.831799 -224.719387) (xy 123.780504 -224.711262) (xy 123.731111 -224.695214)
			(xy 123.684837 -224.671636) (xy 123.642821 -224.64111) (xy 123.606098 -224.604387) (xy 123.575572 -224.562371)
			(xy 123.551994 -224.516097) (xy 123.535946 -224.466704) (xy 123.527821 -224.415409) (xy 123.527312 -224.389442)
			(xy 123.24842 -224.389442) (xy 123.247877 -224.417428) (xy 123.23842 -224.472596) (xy 123.229624 -224.49917)
			(xy 123.222004 -224.521268) (xy 123.425712 -224.874074) (xy 123.448572 -224.878392) (xy 123.473504 -224.883512)
			(xy 123.52149 -224.900483) (xy 123.566309 -224.924607) (xy 123.606902 -224.955314) (xy 123.642309 -224.991878)
			(xy 123.671696 -225.033436) (xy 123.694368 -225.079006) (xy 123.709789 -225.127512) (xy 123.717594 -225.177809)
			(xy 123.718066 -225.203258) (xy 123.717557 -225.229225) (xy 123.709432 -225.28052) (xy 123.693384 -225.329913)
			(xy 123.669806 -225.376187) (xy 123.63928 -225.418203) (xy 123.602557 -225.454926) (xy 123.560541 -225.485452)
			(xy 123.514267 -225.50903) (xy 123.464874 -225.525078) (xy 123.413579 -225.533203) (xy 123.361645 -225.533203)
			(xy 123.31035 -225.525078) (xy 123.260957 -225.50903) (xy 123.214683 -225.485452) (xy 123.172667 -225.454926)
			(xy 123.135944 -225.418203) (xy 123.105418 -225.376187) (xy 123.08184 -225.329913) (xy 123.065792 -225.28052)
			(xy 123.057667 -225.229225) (xy 123.057158 -225.203258) (xy 123.057697 -225.175271) (xy 123.067156 -225.120104)
			(xy 123.075954 -225.09353) (xy 123.083574 -225.071432) (xy 122.879866 -224.718626) (xy 122.857006 -224.714308)
			(xy 122.832086 -224.709131) (xy 122.7841 -224.692171) (xy 122.73928 -224.668057) (xy 122.698685 -224.637359)
			(xy 122.663275 -224.600802) (xy 122.633886 -224.55925) (xy 122.611212 -224.513684) (xy 122.59579 -224.465182)
			(xy 122.587984 -224.414889) (xy 122.587512 -224.389442) (xy 122.30862 -224.389442) (xy 122.308111 -224.415409)
			(xy 122.299986 -224.466704) (xy 122.283938 -224.516097) (xy 122.26036 -224.562371) (xy 122.229834 -224.604387)
			(xy 122.193111 -224.64111) (xy 122.151095 -224.671636) (xy 122.104821 -224.695214) (xy 122.055428 -224.711262)
			(xy 122.004133 -224.719387) (xy 121.952199 -224.719387) (xy 121.900904 -224.711262) (xy 121.851511 -224.695214)
			(xy 121.805237 -224.671636) (xy 121.763221 -224.64111) (xy 121.726498 -224.604387) (xy 121.695972 -224.562371)
			(xy 121.672394 -224.516097) (xy 121.656346 -224.466704) (xy 121.648221 -224.415409) (xy 121.647712 -224.389442)
			(xy 121.36882 -224.389442) (xy 121.368277 -224.417428) (xy 121.35882 -224.472596) (xy 121.350024 -224.49917)
			(xy 121.342404 -224.521268) (xy 121.546112 -224.874074) (xy 121.568972 -224.878392) (xy 121.593904 -224.883512)
			(xy 121.64189 -224.900483) (xy 121.686709 -224.924607) (xy 121.727302 -224.955314) (xy 121.762709 -224.991878)
			(xy 121.792096 -225.033436) (xy 121.814768 -225.079006) (xy 121.830189 -225.127512) (xy 121.837994 -225.177809)
			(xy 121.838466 -225.203258) (xy 121.837957 -225.229225) (xy 121.829832 -225.28052) (xy 121.813784 -225.329913)
			(xy 121.790206 -225.376187) (xy 121.75968 -225.418203) (xy 121.722957 -225.454926) (xy 121.680941 -225.485452)
			(xy 121.634667 -225.50903) (xy 121.585274 -225.525078) (xy 121.533979 -225.533203) (xy 121.482045 -225.533203)
			(xy 121.43075 -225.525078) (xy 121.381357 -225.50903) (xy 121.335083 -225.485452) (xy 121.293067 -225.454926)
			(xy 121.256344 -225.418203) (xy 121.225818 -225.376187) (xy 121.20224 -225.329913) (xy 121.186192 -225.28052)
			(xy 121.178067 -225.229225) (xy 121.177558 -225.203258) (xy 121.178097 -225.175271) (xy 121.187556 -225.120104)
			(xy 121.196354 -225.09353) (xy 121.203974 -225.071432) (xy 121.000266 -224.718626) (xy 120.977406 -224.714308)
			(xy 120.952486 -224.709131) (xy 120.9045 -224.692171) (xy 120.85968 -224.668057) (xy 120.819085 -224.637359)
			(xy 120.783675 -224.600802) (xy 120.754286 -224.55925) (xy 120.731612 -224.513684) (xy 120.71619 -224.465182)
			(xy 120.708384 -224.414889) (xy 120.707912 -224.389442) (xy 120.42902 -224.389442) (xy 120.428511 -224.415409)
			(xy 120.420386 -224.466704) (xy 120.404338 -224.516097) (xy 120.38076 -224.562371) (xy 120.350234 -224.604387)
			(xy 120.313511 -224.64111) (xy 120.271495 -224.671636) (xy 120.225221 -224.695214) (xy 120.175828 -224.711262)
			(xy 120.124533 -224.719387) (xy 120.072599 -224.719387) (xy 120.021304 -224.711262) (xy 119.971911 -224.695214)
			(xy 119.925637 -224.671636) (xy 119.883621 -224.64111) (xy 119.846898 -224.604387) (xy 119.816372 -224.562371)
			(xy 119.792794 -224.516097) (xy 119.776746 -224.466704) (xy 119.768621 -224.415409) (xy 119.768112 -224.389442)
			(xy 119.48922 -224.389442) (xy 119.488677 -224.417428) (xy 119.47922 -224.472596) (xy 119.470424 -224.49917)
			(xy 119.462804 -224.521268) (xy 119.666512 -224.874074) (xy 119.689372 -224.878392) (xy 119.714304 -224.883512)
			(xy 119.76229 -224.900483) (xy 119.807109 -224.924607) (xy 119.847702 -224.955314) (xy 119.883109 -224.991878)
			(xy 119.912496 -225.033436) (xy 119.935168 -225.079006) (xy 119.950589 -225.127512) (xy 119.958394 -225.177809)
			(xy 119.958866 -225.203258) (xy 119.958357 -225.229225) (xy 119.950232 -225.28052) (xy 119.934184 -225.329913)
			(xy 119.910606 -225.376187) (xy 119.88008 -225.418203) (xy 119.843357 -225.454926) (xy 119.801341 -225.485452)
			(xy 119.755067 -225.50903) (xy 119.705674 -225.525078) (xy 119.654379 -225.533203) (xy 119.602445 -225.533203)
			(xy 119.55115 -225.525078) (xy 119.501757 -225.50903) (xy 119.455483 -225.485452) (xy 119.413467 -225.454926)
			(xy 119.376744 -225.418203) (xy 119.346218 -225.376187) (xy 119.32264 -225.329913) (xy 119.306592 -225.28052)
			(xy 119.298467 -225.229225) (xy 119.297958 -225.203258) (xy 119.298497 -225.175271) (xy 119.307956 -225.120104)
			(xy 119.316754 -225.09353) (xy 119.324374 -225.071432) (xy 119.120666 -224.718626) (xy 119.097806 -224.714308)
			(xy 119.072886 -224.709131) (xy 119.0249 -224.692171) (xy 118.98008 -224.668057) (xy 118.939485 -224.637359)
			(xy 118.904075 -224.600802) (xy 118.874686 -224.55925) (xy 118.852012 -224.513684) (xy 118.83659 -224.465182)
			(xy 118.828784 -224.414889) (xy 118.828312 -224.389442) (xy 118.54942 -224.389442) (xy 118.548911 -224.415409)
			(xy 118.540786 -224.466704) (xy 118.524738 -224.516097) (xy 118.50116 -224.562371) (xy 118.470634 -224.604387)
			(xy 118.433911 -224.64111) (xy 118.391895 -224.671636) (xy 118.345621 -224.695214) (xy 118.296228 -224.711262)
			(xy 118.244933 -224.719387) (xy 118.192999 -224.719387) (xy 118.141704 -224.711262) (xy 118.092311 -224.695214)
			(xy 118.046037 -224.671636) (xy 118.004021 -224.64111) (xy 117.967298 -224.604387) (xy 117.936772 -224.562371)
			(xy 117.913194 -224.516097) (xy 117.897146 -224.466704) (xy 117.889021 -224.415409) (xy 117.888512 -224.389442)
			(xy 117.60962 -224.389442) (xy 117.609077 -224.417428) (xy 117.59962 -224.472596) (xy 117.590824 -224.49917)
			(xy 117.583204 -224.521268) (xy 117.786912 -224.874074) (xy 117.809772 -224.878392) (xy 117.834704 -224.883512)
			(xy 117.88269 -224.900483) (xy 117.927509 -224.924607) (xy 117.968102 -224.955314) (xy 118.003509 -224.991878)
			(xy 118.032896 -225.033436) (xy 118.055568 -225.079006) (xy 118.070989 -225.127512) (xy 118.078794 -225.177809)
			(xy 118.079266 -225.203258) (xy 118.078757 -225.229225) (xy 118.070632 -225.28052) (xy 118.054584 -225.329913)
			(xy 118.031006 -225.376187) (xy 118.00048 -225.418203) (xy 117.963757 -225.454926) (xy 117.921741 -225.485452)
			(xy 117.875467 -225.50903) (xy 117.826074 -225.525078) (xy 117.774779 -225.533203) (xy 117.722845 -225.533203)
			(xy 117.67155 -225.525078) (xy 117.622157 -225.50903) (xy 117.575883 -225.485452) (xy 117.533867 -225.454926)
			(xy 117.497144 -225.418203) (xy 117.466618 -225.376187) (xy 117.44304 -225.329913) (xy 117.426992 -225.28052)
			(xy 117.418867 -225.229225) (xy 117.418358 -225.203258) (xy 117.418897 -225.175271) (xy 117.428356 -225.120104)
			(xy 117.437154 -225.09353) (xy 117.444774 -225.071432) (xy 117.241066 -224.718626) (xy 117.218206 -224.714308)
			(xy 117.193286 -224.709131) (xy 117.1453 -224.692171) (xy 117.10048 -224.668057) (xy 117.059885 -224.637359)
			(xy 117.024475 -224.600802) (xy 116.995086 -224.55925) (xy 116.972412 -224.513684) (xy 116.95699 -224.465182)
			(xy 116.949184 -224.414889) (xy 116.948712 -224.389442) (xy 116.66982 -224.389442) (xy 116.669311 -224.415409)
			(xy 116.661186 -224.466704) (xy 116.645138 -224.516097) (xy 116.62156 -224.562371) (xy 116.591034 -224.604387)
			(xy 116.554311 -224.64111) (xy 116.512295 -224.671636) (xy 116.466021 -224.695214) (xy 116.416628 -224.711262)
			(xy 116.365333 -224.719387) (xy 116.313399 -224.719387) (xy 116.262104 -224.711262) (xy 116.212711 -224.695214)
			(xy 116.166437 -224.671636) (xy 116.124421 -224.64111) (xy 116.087698 -224.604387) (xy 116.057172 -224.562371)
			(xy 116.033594 -224.516097) (xy 116.017546 -224.466704) (xy 116.009421 -224.415409) (xy 116.008912 -224.389442)
			(xy 115.73002 -224.389442) (xy 115.729477 -224.417428) (xy 115.72002 -224.472596) (xy 115.711224 -224.49917)
			(xy 115.703604 -224.521268) (xy 115.907312 -224.874074) (xy 115.930172 -224.878392) (xy 115.955104 -224.883512)
			(xy 116.00309 -224.900483) (xy 116.047909 -224.924607) (xy 116.088502 -224.955314) (xy 116.123909 -224.991878)
			(xy 116.153296 -225.033436) (xy 116.175968 -225.079006) (xy 116.191389 -225.127512) (xy 116.199194 -225.177809)
			(xy 116.199666 -225.203258) (xy 116.199157 -225.229225) (xy 116.191032 -225.28052) (xy 116.174984 -225.329913)
			(xy 116.151406 -225.376187) (xy 116.12088 -225.418203) (xy 116.084157 -225.454926) (xy 116.042141 -225.485452)
			(xy 115.995867 -225.50903) (xy 115.946474 -225.525078) (xy 115.895179 -225.533203) (xy 115.843245 -225.533203)
			(xy 115.79195 -225.525078) (xy 115.742557 -225.50903) (xy 115.696283 -225.485452) (xy 115.654267 -225.454926)
			(xy 115.617544 -225.418203) (xy 115.587018 -225.376187) (xy 115.56344 -225.329913) (xy 115.547392 -225.28052)
			(xy 115.539267 -225.229225) (xy 115.538758 -225.203258) (xy 115.539297 -225.175271) (xy 115.548756 -225.120104)
			(xy 115.557554 -225.09353) (xy 115.565174 -225.071432) (xy 115.361466 -224.718626) (xy 115.338606 -224.714308)
			(xy 115.313686 -224.709131) (xy 115.2657 -224.692171) (xy 115.22088 -224.668057) (xy 115.180285 -224.637359)
			(xy 115.144875 -224.600802) (xy 115.115486 -224.55925) (xy 115.092812 -224.513684) (xy 115.07739 -224.465182)
			(xy 115.069584 -224.414889) (xy 115.069112 -224.389442) (xy 114.79022 -224.389442) (xy 114.789711 -224.415409)
			(xy 114.781586 -224.466704) (xy 114.765538 -224.516097) (xy 114.74196 -224.562371) (xy 114.711434 -224.604387)
			(xy 114.674711 -224.64111) (xy 114.632695 -224.671636) (xy 114.586421 -224.695214) (xy 114.537028 -224.711262)
			(xy 114.485733 -224.719387) (xy 114.433799 -224.719387) (xy 114.382504 -224.711262) (xy 114.333111 -224.695214)
			(xy 114.286837 -224.671636) (xy 114.244821 -224.64111) (xy 114.208098 -224.604387) (xy 114.177572 -224.562371)
			(xy 114.153994 -224.516097) (xy 114.137946 -224.466704) (xy 114.129821 -224.415409) (xy 114.129312 -224.389442)
			(xy 113.85042 -224.389442) (xy 113.849877 -224.417428) (xy 113.84042 -224.472596) (xy 113.831624 -224.49917)
			(xy 113.824004 -224.521268) (xy 114.027712 -224.874074) (xy 114.050572 -224.878392) (xy 114.075504 -224.883512)
			(xy 114.12349 -224.900483) (xy 114.168309 -224.924607) (xy 114.208902 -224.955314) (xy 114.244309 -224.991878)
			(xy 114.273696 -225.033436) (xy 114.296368 -225.079006) (xy 114.311789 -225.127512) (xy 114.319594 -225.177809)
			(xy 114.320066 -225.203258) (xy 114.319557 -225.229225) (xy 114.311432 -225.28052) (xy 114.295384 -225.329913)
			(xy 114.271806 -225.376187) (xy 114.24128 -225.418203) (xy 114.204557 -225.454926) (xy 114.162541 -225.485452)
			(xy 114.116267 -225.50903) (xy 114.066874 -225.525078) (xy 114.015579 -225.533203) (xy 113.963645 -225.533203)
			(xy 113.91235 -225.525078) (xy 113.862957 -225.50903) (xy 113.816683 -225.485452) (xy 113.774667 -225.454926)
			(xy 113.737944 -225.418203) (xy 113.707418 -225.376187) (xy 113.68384 -225.329913) (xy 113.667792 -225.28052)
			(xy 113.659667 -225.229225) (xy 113.659158 -225.203258) (xy 113.659697 -225.175271) (xy 113.669156 -225.120104)
			(xy 113.677954 -225.09353) (xy 113.685574 -225.071432) (xy 113.481866 -224.718626) (xy 113.459006 -224.714308)
			(xy 113.434086 -224.709131) (xy 113.3861 -224.692171) (xy 113.34128 -224.668057) (xy 113.300685 -224.637359)
			(xy 113.265275 -224.600802) (xy 113.235886 -224.55925) (xy 113.213212 -224.513684) (xy 113.19779 -224.465182)
			(xy 113.189984 -224.414889) (xy 113.189512 -224.389442) (xy 112.91062 -224.389442) (xy 112.910111 -224.415409)
			(xy 112.901986 -224.466704) (xy 112.885938 -224.516097) (xy 112.86236 -224.562371) (xy 112.831834 -224.604387)
			(xy 112.795111 -224.64111) (xy 112.753095 -224.671636) (xy 112.706821 -224.695214) (xy 112.657428 -224.711262)
			(xy 112.606133 -224.719387) (xy 112.554199 -224.719387) (xy 112.502904 -224.711262) (xy 112.453511 -224.695214)
			(xy 112.407237 -224.671636) (xy 112.365221 -224.64111) (xy 112.328498 -224.604387) (xy 112.297972 -224.562371)
			(xy 112.274394 -224.516097) (xy 112.258346 -224.466704) (xy 112.250221 -224.415409) (xy 112.249712 -224.389442)
			(xy 111.97082 -224.389442) (xy 111.970277 -224.417428) (xy 111.96082 -224.472596) (xy 111.952024 -224.49917)
			(xy 111.944404 -224.521268) (xy 112.148112 -224.874074) (xy 112.170972 -224.878392) (xy 112.195904 -224.883512)
			(xy 112.24389 -224.900483) (xy 112.288709 -224.924607) (xy 112.329302 -224.955314) (xy 112.364709 -224.991878)
			(xy 112.394096 -225.033436) (xy 112.416768 -225.079006) (xy 112.432189 -225.127512) (xy 112.439994 -225.177809)
			(xy 112.440466 -225.203258) (xy 112.439957 -225.229225) (xy 112.431832 -225.28052) (xy 112.415784 -225.329913)
			(xy 112.392206 -225.376187) (xy 112.36168 -225.418203) (xy 112.324957 -225.454926) (xy 112.282941 -225.485452)
			(xy 112.236667 -225.50903) (xy 112.187274 -225.525078) (xy 112.135979 -225.533203) (xy 112.084045 -225.533203)
			(xy 112.03275 -225.525078) (xy 111.983357 -225.50903) (xy 111.937083 -225.485452) (xy 111.895067 -225.454926)
			(xy 111.858344 -225.418203) (xy 111.827818 -225.376187) (xy 111.80424 -225.329913) (xy 111.788192 -225.28052)
			(xy 111.780067 -225.229225) (xy 111.779558 -225.203258) (xy 111.780097 -225.175271) (xy 111.789556 -225.120104)
			(xy 111.798354 -225.09353) (xy 111.805974 -225.071432) (xy 111.602266 -224.718626) (xy 111.579406 -224.714308)
			(xy 111.554486 -224.709131) (xy 111.5065 -224.692171) (xy 111.46168 -224.668057) (xy 111.421085 -224.637359)
			(xy 111.385675 -224.600802) (xy 111.356286 -224.55925) (xy 111.333612 -224.513684) (xy 111.31819 -224.465182)
			(xy 111.310384 -224.414889) (xy 111.309912 -224.389442) (xy 111.03102 -224.389442) (xy 111.030511 -224.415409)
			(xy 111.022386 -224.466704) (xy 111.006338 -224.516097) (xy 110.98276 -224.562371) (xy 110.952234 -224.604387)
			(xy 110.915511 -224.64111) (xy 110.873495 -224.671636) (xy 110.827221 -224.695214) (xy 110.777828 -224.711262)
			(xy 110.726533 -224.719387) (xy 110.674599 -224.719387) (xy 110.623304 -224.711262) (xy 110.573911 -224.695214)
			(xy 110.527637 -224.671636) (xy 110.485621 -224.64111) (xy 110.448898 -224.604387) (xy 110.418372 -224.562371)
			(xy 110.394794 -224.516097) (xy 110.378746 -224.466704) (xy 110.370621 -224.415409) (xy 110.370112 -224.389442)
			(xy 110.09122 -224.389442) (xy 110.090677 -224.417428) (xy 110.08122 -224.472596) (xy 110.072424 -224.49917)
			(xy 110.064804 -224.521268) (xy 110.268512 -224.874074) (xy 110.291372 -224.878392) (xy 110.316304 -224.883512)
			(xy 110.36429 -224.900483) (xy 110.409109 -224.924607) (xy 110.449702 -224.955314) (xy 110.485109 -224.991878)
			(xy 110.514496 -225.033436) (xy 110.537168 -225.079006) (xy 110.552589 -225.127512) (xy 110.560394 -225.177809)
			(xy 110.560866 -225.203258) (xy 110.560357 -225.229225) (xy 110.840267 -225.229225) (xy 110.840267 -225.177291)
			(xy 110.848392 -225.125996) (xy 110.86444 -225.076603) (xy 110.888018 -225.030329) (xy 110.918544 -224.988313)
			(xy 110.955267 -224.95159) (xy 110.997283 -224.921064) (xy 111.043557 -224.897486) (xy 111.09295 -224.881438)
			(xy 111.144245 -224.873313) (xy 111.196179 -224.873313) (xy 111.247474 -224.881438) (xy 111.296867 -224.897486)
			(xy 111.343141 -224.921064) (xy 111.385157 -224.95159) (xy 111.42188 -224.988313) (xy 111.452406 -225.030329)
			(xy 111.475984 -225.076603) (xy 111.492032 -225.125996) (xy 111.500157 -225.177291) (xy 111.500666 -225.203258)
			(xy 111.500157 -225.229225) (xy 111.492032 -225.28052) (xy 111.475984 -225.329913) (xy 111.452406 -225.376187)
			(xy 111.42188 -225.418203) (xy 111.385157 -225.454926) (xy 111.343141 -225.485452) (xy 111.296867 -225.50903)
			(xy 111.247474 -225.525078) (xy 111.196179 -225.533203) (xy 111.144245 -225.533203) (xy 111.09295 -225.525078)
			(xy 111.043557 -225.50903) (xy 110.997283 -225.485452) (xy 110.955267 -225.454926) (xy 110.918544 -225.418203)
			(xy 110.888018 -225.376187) (xy 110.86444 -225.329913) (xy 110.848392 -225.28052) (xy 110.840267 -225.229225)
			(xy 110.560357 -225.229225) (xy 110.552232 -225.28052) (xy 110.536184 -225.329913) (xy 110.512606 -225.376187)
			(xy 110.48208 -225.418203) (xy 110.445357 -225.454926) (xy 110.403341 -225.485452) (xy 110.357067 -225.50903)
			(xy 110.307674 -225.525078) (xy 110.256379 -225.533203) (xy 110.204445 -225.533203) (xy 110.15315 -225.525078)
			(xy 110.103757 -225.50903) (xy 110.057483 -225.485452) (xy 110.015467 -225.454926) (xy 109.978744 -225.418203)
			(xy 109.948218 -225.376187) (xy 109.92464 -225.329913) (xy 109.908592 -225.28052) (xy 109.900467 -225.229225)
			(xy 109.899958 -225.203258) (xy 109.900497 -225.175271) (xy 109.909956 -225.120104) (xy 109.918754 -225.09353)
			(xy 109.926374 -225.071432) (xy 109.722666 -224.718626) (xy 109.699806 -224.714308) (xy 109.674886 -224.709131)
			(xy 109.6269 -224.692171) (xy 109.58208 -224.668057) (xy 109.541485 -224.637359) (xy 109.506075 -224.600802)
			(xy 109.476686 -224.55925) (xy 109.454012 -224.513684) (xy 109.43859 -224.465182) (xy 109.430784 -224.414889)
			(xy 109.430312 -224.389442) (xy 109.15142 -224.389442) (xy 109.150911 -224.415409) (xy 109.142786 -224.466704)
			(xy 109.126738 -224.516097) (xy 109.10316 -224.562371) (xy 109.072634 -224.604387) (xy 109.035911 -224.64111)
			(xy 108.993895 -224.671636) (xy 108.947621 -224.695214) (xy 108.898228 -224.711262) (xy 108.846933 -224.719387)
			(xy 108.794999 -224.719387) (xy 108.743704 -224.711262) (xy 108.694311 -224.695214) (xy 108.648037 -224.671636)
			(xy 108.606021 -224.64111) (xy 108.569298 -224.604387) (xy 108.538772 -224.562371) (xy 108.515194 -224.516097)
			(xy 108.499146 -224.466704) (xy 108.491021 -224.415409) (xy 108.490512 -224.389442) (xy 108.21162 -224.389442)
			(xy 108.211077 -224.417428) (xy 108.20162 -224.472596) (xy 108.192824 -224.49917) (xy 108.185204 -224.521268)
			(xy 108.388912 -224.874074) (xy 108.411772 -224.878392) (xy 108.436704 -224.883512) (xy 108.48469 -224.900483)
			(xy 108.529509 -224.924607) (xy 108.570102 -224.955314) (xy 108.605509 -224.991878) (xy 108.634896 -225.033436)
			(xy 108.657568 -225.079006) (xy 108.672989 -225.127512) (xy 108.680794 -225.177809) (xy 108.681266 -225.203258)
			(xy 108.680757 -225.229225) (xy 108.672632 -225.28052) (xy 108.656584 -225.329913) (xy 108.633006 -225.376187)
			(xy 108.60248 -225.418203) (xy 108.565757 -225.454926) (xy 108.523741 -225.485452) (xy 108.477467 -225.50903)
			(xy 108.428074 -225.525078) (xy 108.376779 -225.533203) (xy 108.324845 -225.533203) (xy 108.27355 -225.525078)
			(xy 108.224157 -225.50903) (xy 108.177883 -225.485452) (xy 108.135867 -225.454926) (xy 108.099144 -225.418203)
			(xy 108.068618 -225.376187) (xy 108.04504 -225.329913) (xy 108.028992 -225.28052) (xy 108.020867 -225.229225)
			(xy 108.020358 -225.203258) (xy 108.020897 -225.175271) (xy 108.030356 -225.120104) (xy 108.039154 -225.09353)
			(xy 108.046774 -225.071432) (xy 107.843066 -224.718626) (xy 107.820206 -224.714308) (xy 107.795286 -224.709131)
			(xy 107.7473 -224.692171) (xy 107.70248 -224.668057) (xy 107.661885 -224.637359) (xy 107.626475 -224.600802)
			(xy 107.597086 -224.55925) (xy 107.574412 -224.513684) (xy 107.55899 -224.465182) (xy 107.551184 -224.414889)
			(xy 107.550712 -224.389442) (xy 107.27182 -224.389442) (xy 107.271311 -224.415409) (xy 107.263186 -224.466704)
			(xy 107.247138 -224.516097) (xy 107.22356 -224.562371) (xy 107.193034 -224.604387) (xy 107.156311 -224.64111)
			(xy 107.114295 -224.671636) (xy 107.068021 -224.695214) (xy 107.018628 -224.711262) (xy 106.967333 -224.719387)
			(xy 106.915399 -224.719387) (xy 106.864104 -224.711262) (xy 106.814711 -224.695214) (xy 106.768437 -224.671636)
			(xy 106.726421 -224.64111) (xy 106.689698 -224.604387) (xy 106.659172 -224.562371) (xy 106.635594 -224.516097)
			(xy 106.619546 -224.466704) (xy 106.611421 -224.415409) (xy 106.610912 -224.389442) (xy 106.33202 -224.389442)
			(xy 106.331477 -224.417428) (xy 106.32202 -224.472596) (xy 106.313224 -224.49917) (xy 106.305604 -224.521268)
			(xy 106.509312 -224.874074) (xy 106.532172 -224.878392) (xy 106.557104 -224.883512) (xy 106.60509 -224.900483)
			(xy 106.649909 -224.924607) (xy 106.690502 -224.955314) (xy 106.725909 -224.991878) (xy 106.755296 -225.033436)
			(xy 106.777968 -225.079006) (xy 106.793389 -225.127512) (xy 106.801194 -225.177809) (xy 106.801666 -225.203258)
			(xy 106.801157 -225.229225) (xy 106.793032 -225.28052) (xy 106.776984 -225.329913) (xy 106.753406 -225.376187)
			(xy 106.72288 -225.418203) (xy 106.686157 -225.454926) (xy 106.644141 -225.485452) (xy 106.597867 -225.50903)
			(xy 106.548474 -225.525078) (xy 106.497179 -225.533203) (xy 106.445245 -225.533203) (xy 106.39395 -225.525078)
			(xy 106.344557 -225.50903) (xy 106.298283 -225.485452) (xy 106.256267 -225.454926) (xy 106.219544 -225.418203)
			(xy 106.189018 -225.376187) (xy 106.16544 -225.329913) (xy 106.149392 -225.28052) (xy 106.141267 -225.229225)
			(xy 106.140758 -225.203258) (xy 106.141297 -225.175271) (xy 106.150756 -225.120104) (xy 106.159554 -225.09353)
			(xy 106.167174 -225.071432) (xy 105.963466 -224.718626) (xy 105.940606 -224.714308) (xy 105.915686 -224.709131)
			(xy 105.8677 -224.692171) (xy 105.82288 -224.668057) (xy 105.782285 -224.637359) (xy 105.746875 -224.600802)
			(xy 105.717486 -224.55925) (xy 105.694812 -224.513684) (xy 105.67939 -224.465182) (xy 105.671584 -224.414889)
			(xy 105.671112 -224.389442) (xy 105.39222 -224.389442) (xy 105.391711 -224.415409) (xy 105.383586 -224.466704)
			(xy 105.367538 -224.516097) (xy 105.34396 -224.562371) (xy 105.313434 -224.604387) (xy 105.276711 -224.64111)
			(xy 105.234695 -224.671636) (xy 105.188421 -224.695214) (xy 105.139028 -224.711262) (xy 105.087733 -224.719387)
			(xy 105.035799 -224.719387) (xy 104.984504 -224.711262) (xy 104.935111 -224.695214) (xy 104.888837 -224.671636)
			(xy 104.846821 -224.64111) (xy 104.810098 -224.604387) (xy 104.779572 -224.562371) (xy 104.755994 -224.516097)
			(xy 104.739946 -224.466704) (xy 104.731821 -224.415409) (xy 104.731312 -224.389442) (xy 104.731785 -224.363995)
			(xy 104.739593 -224.313704) (xy 104.755017 -224.265204) (xy 104.777692 -224.219641) (xy 104.807081 -224.178091)
			(xy 104.842491 -224.141535) (xy 104.883086 -224.110839) (xy 104.927905 -224.086727) (xy 104.975889 -224.069768)
			(xy 105.000806 -224.064576) (xy 105.023666 -224.060258) (xy 105.227374 -223.707198) (xy 105.219754 -223.685354)
			(xy 105.211889 -223.661629) (xy 105.202582 -223.612521) (xy 105.201212 -223.587564) (xy 105.199434 -223.538542)
			(xy 105.099612 -223.538542) (xy 105.099612 -223.687386) (xy 104.449118 -224.33788) (xy 104.45115 -224.361248)
			(xy 104.45242 -224.389442) (xy 104.451812 -224.417423) (xy 104.44237 -224.472584) (xy 104.433624 -224.49917)
			(xy 104.426004 -224.521268) (xy 104.629712 -224.874074) (xy 104.652572 -224.878392) (xy 104.677501 -224.883543)
			(xy 104.725502 -224.900485) (xy 104.770336 -224.92459) (xy 104.810942 -224.955286) (xy 104.846359 -224.991848)
			(xy 104.875749 -225.033409) (xy 104.898416 -225.078987) (xy 104.913823 -225.127502) (xy 104.921607 -225.177806)
			(xy 104.922066 -225.203258) (xy 104.921557 -225.229225) (xy 104.913432 -225.28052) (xy 104.897384 -225.329913)
			(xy 104.873806 -225.376187) (xy 104.84328 -225.418203) (xy 104.806557 -225.454926) (xy 104.764541 -225.485452)
			(xy 104.718267 -225.50903) (xy 104.668874 -225.525078) (xy 104.617579 -225.533203) (xy 104.565645 -225.533203)
			(xy 104.51435 -225.525078) (xy 104.464957 -225.50903) (xy 104.418683 -225.485452) (xy 104.376667 -225.454926)
			(xy 104.339944 -225.418203) (xy 104.309418 -225.376187) (xy 104.28584 -225.329913) (xy 104.269792 -225.28052)
			(xy 104.261667 -225.229225) (xy 104.261158 -225.203258) (xy 104.261767 -225.175277) (xy 104.271211 -225.120117)
			(xy 104.279954 -225.09353) (xy 104.287574 -225.071432) (xy 104.144572 -224.823274) (xy 104.137547 -224.81193)
			(xy 104.118662 -224.793094) (xy 104.095543 -224.779789) (xy 104.069768 -224.772925) (xy 104.043095 -224.77297)
			(xy 104.017343 -224.77992) (xy 103.994269 -224.7933) (xy 103.984552 -224.802446) (xy 103.942134 -224.844864)
			(xy 103.459788 -224.844864) (xy 103.03637 -225.268282) (xy 103.032814 -225.281998) (xy 103.026072 -225.307454)
			(xy 103.005617 -225.355977) (xy 102.977713 -225.400633) (xy 102.943067 -225.440289) (xy 102.902561 -225.473935)
			(xy 102.857223 -225.500718) (xy 102.832916 -225.510852) (xy 102.800658 -225.523552) (xy 102.800658 -225.688144)
			(xy 102.801172 -225.702614) (xy 102.809299 -225.730389) (xy 102.824888 -225.754771) (xy 102.84669 -225.773803)
			(xy 102.872953 -225.785959) (xy 102.901571 -225.790262) (xy 102.930248 -225.786368) (xy 102.956682 -225.774588)
			(xy 102.968044 -225.765614) (xy 102.986052 -225.750817) (xy 103.025444 -225.725904) (xy 103.067946 -225.706776)
			(xy 103.112715 -225.693811) (xy 103.158862 -225.687269) (xy 103.182166 -225.686874) (xy 103.208135 -225.687354)
			(xy 103.259434 -225.695474) (xy 103.308831 -225.71152) (xy 103.355109 -225.735096) (xy 103.397129 -225.765621)
			(xy 103.433857 -225.802345) (xy 103.464387 -225.844362) (xy 103.487967 -225.890638) (xy 103.504018 -225.940033)
			(xy 103.512143 -225.991331) (xy 103.512143 -226.043269) (xy 103.512139 -226.043295) (xy 103.792021 -226.043295)
			(xy 103.792021 -225.991361) (xy 103.800146 -225.940066) (xy 103.816194 -225.890673) (xy 103.839772 -225.844399)
			(xy 103.870298 -225.802383) (xy 103.907021 -225.76566) (xy 103.949037 -225.735134) (xy 103.995311 -225.711556)
			(xy 104.044704 -225.695508) (xy 104.095999 -225.687383) (xy 104.147933 -225.687383) (xy 104.199228 -225.695508)
			(xy 104.248621 -225.711556) (xy 104.294895 -225.735134) (xy 104.336911 -225.76566) (xy 104.373634 -225.802383)
			(xy 104.40416 -225.844399) (xy 104.427738 -225.890673) (xy 104.443786 -225.940066) (xy 104.451911 -225.991361)
			(xy 104.45242 -226.017328) (xy 104.451911 -226.043295) (xy 104.731821 -226.043295) (xy 104.731821 -225.991361)
			(xy 104.739946 -225.940066) (xy 104.755994 -225.890673) (xy 104.779572 -225.844399) (xy 104.810098 -225.802383)
			(xy 104.846821 -225.76566) (xy 104.888837 -225.735134) (xy 104.935111 -225.711556) (xy 104.984504 -225.695508)
			(xy 105.035799 -225.687383) (xy 105.087733 -225.687383) (xy 105.139028 -225.695508) (xy 105.188421 -225.711556)
			(xy 105.234695 -225.735134) (xy 105.276711 -225.76566) (xy 105.313434 -225.802383) (xy 105.34396 -225.844399)
			(xy 105.367538 -225.890673) (xy 105.383586 -225.940066) (xy 105.391711 -225.991361) (xy 105.39222 -226.017328)
			(xy 105.391711 -226.043295) (xy 105.671621 -226.043295) (xy 105.671621 -225.991361) (xy 105.679746 -225.940066)
			(xy 105.695794 -225.890673) (xy 105.719372 -225.844399) (xy 105.749898 -225.802383) (xy 105.786621 -225.76566)
			(xy 105.828637 -225.735134) (xy 105.874911 -225.711556) (xy 105.924304 -225.695508) (xy 105.975599 -225.687383)
			(xy 106.027533 -225.687383) (xy 106.078828 -225.695508) (xy 106.128221 -225.711556) (xy 106.174495 -225.735134)
			(xy 106.216511 -225.76566) (xy 106.253234 -225.802383) (xy 106.28376 -225.844399) (xy 106.307338 -225.890673)
			(xy 106.323386 -225.940066) (xy 106.331511 -225.991361) (xy 106.33202 -226.017328) (xy 106.331511 -226.043295)
			(xy 106.611421 -226.043295) (xy 106.611421 -225.991361) (xy 106.619546 -225.940066) (xy 106.635594 -225.890673)
			(xy 106.659172 -225.844399) (xy 106.689698 -225.802383) (xy 106.726421 -225.76566) (xy 106.768437 -225.735134)
			(xy 106.814711 -225.711556) (xy 106.864104 -225.695508) (xy 106.915399 -225.687383) (xy 106.967333 -225.687383)
			(xy 107.018628 -225.695508) (xy 107.068021 -225.711556) (xy 107.114295 -225.735134) (xy 107.156311 -225.76566)
			(xy 107.193034 -225.802383) (xy 107.22356 -225.844399) (xy 107.247138 -225.890673) (xy 107.263186 -225.940066)
			(xy 107.271311 -225.991361) (xy 107.27182 -226.017328) (xy 107.271311 -226.043295) (xy 107.551221 -226.043295)
			(xy 107.551221 -225.991361) (xy 107.559346 -225.940066) (xy 107.575394 -225.890673) (xy 107.598972 -225.844399)
			(xy 107.629498 -225.802383) (xy 107.666221 -225.76566) (xy 107.708237 -225.735134) (xy 107.754511 -225.711556)
			(xy 107.803904 -225.695508) (xy 107.855199 -225.687383) (xy 107.907133 -225.687383) (xy 107.958428 -225.695508)
			(xy 108.007821 -225.711556) (xy 108.054095 -225.735134) (xy 108.096111 -225.76566) (xy 108.132834 -225.802383)
			(xy 108.16336 -225.844399) (xy 108.186938 -225.890673) (xy 108.202986 -225.940066) (xy 108.211111 -225.991361)
			(xy 108.21162 -226.017328) (xy 108.211111 -226.043295) (xy 108.491021 -226.043295) (xy 108.491021 -225.991361)
			(xy 108.499146 -225.940066) (xy 108.515194 -225.890673) (xy 108.538772 -225.844399) (xy 108.569298 -225.802383)
			(xy 108.606021 -225.76566) (xy 108.648037 -225.735134) (xy 108.694311 -225.711556) (xy 108.743704 -225.695508)
			(xy 108.794999 -225.687383) (xy 108.846933 -225.687383) (xy 108.898228 -225.695508) (xy 108.947621 -225.711556)
			(xy 108.993895 -225.735134) (xy 109.035911 -225.76566) (xy 109.072634 -225.802383) (xy 109.10316 -225.844399)
			(xy 109.126738 -225.890673) (xy 109.142786 -225.940066) (xy 109.150911 -225.991361) (xy 109.15142 -226.017328)
			(xy 109.150911 -226.043295) (xy 109.430821 -226.043295) (xy 109.430821 -225.991361) (xy 109.438946 -225.940066)
			(xy 109.454994 -225.890673) (xy 109.478572 -225.844399) (xy 109.509098 -225.802383) (xy 109.545821 -225.76566)
			(xy 109.587837 -225.735134) (xy 109.634111 -225.711556) (xy 109.683504 -225.695508) (xy 109.734799 -225.687383)
			(xy 109.786733 -225.687383) (xy 109.838028 -225.695508) (xy 109.887421 -225.711556) (xy 109.933695 -225.735134)
			(xy 109.975711 -225.76566) (xy 110.012434 -225.802383) (xy 110.04296 -225.844399) (xy 110.066538 -225.890673)
			(xy 110.082586 -225.940066) (xy 110.090711 -225.991361) (xy 110.09122 -226.017328) (xy 110.090711 -226.043295)
			(xy 110.370621 -226.043295) (xy 110.370621 -225.991361) (xy 110.378746 -225.940066) (xy 110.394794 -225.890673)
			(xy 110.418372 -225.844399) (xy 110.448898 -225.802383) (xy 110.485621 -225.76566) (xy 110.527637 -225.735134)
			(xy 110.573911 -225.711556) (xy 110.623304 -225.695508) (xy 110.674599 -225.687383) (xy 110.726533 -225.687383)
			(xy 110.777828 -225.695508) (xy 110.827221 -225.711556) (xy 110.873495 -225.735134) (xy 110.915511 -225.76566)
			(xy 110.952234 -225.802383) (xy 110.98276 -225.844399) (xy 111.006338 -225.890673) (xy 111.022386 -225.940066)
			(xy 111.030511 -225.991361) (xy 111.03102 -226.017328) (xy 111.030511 -226.043295) (xy 111.310421 -226.043295)
			(xy 111.310421 -225.991361) (xy 111.318546 -225.940066) (xy 111.334594 -225.890673) (xy 111.358172 -225.844399)
			(xy 111.388698 -225.802383) (xy 111.425421 -225.76566) (xy 111.467437 -225.735134) (xy 111.513711 -225.711556)
			(xy 111.563104 -225.695508) (xy 111.614399 -225.687383) (xy 111.666333 -225.687383) (xy 111.717628 -225.695508)
			(xy 111.767021 -225.711556) (xy 111.813295 -225.735134) (xy 111.855311 -225.76566) (xy 111.892034 -225.802383)
			(xy 111.92256 -225.844399) (xy 111.946138 -225.890673) (xy 111.962186 -225.940066) (xy 111.970311 -225.991361)
			(xy 111.97082 -226.017328) (xy 111.970311 -226.043295) (xy 112.250221 -226.043295) (xy 112.250221 -225.991361)
			(xy 112.258346 -225.940066) (xy 112.274394 -225.890673) (xy 112.297972 -225.844399) (xy 112.328498 -225.802383)
			(xy 112.365221 -225.76566) (xy 112.407237 -225.735134) (xy 112.453511 -225.711556) (xy 112.502904 -225.695508)
			(xy 112.554199 -225.687383) (xy 112.606133 -225.687383) (xy 112.657428 -225.695508) (xy 112.706821 -225.711556)
			(xy 112.753095 -225.735134) (xy 112.795111 -225.76566) (xy 112.831834 -225.802383) (xy 112.86236 -225.844399)
			(xy 112.885938 -225.890673) (xy 112.901986 -225.940066) (xy 112.910111 -225.991361) (xy 112.91062 -226.017328)
			(xy 112.910111 -226.043295) (xy 113.190021 -226.043295) (xy 113.190021 -225.991361) (xy 113.198146 -225.940066)
			(xy 113.214194 -225.890673) (xy 113.237772 -225.844399) (xy 113.268298 -225.802383) (xy 113.305021 -225.76566)
			(xy 113.347037 -225.735134) (xy 113.393311 -225.711556) (xy 113.442704 -225.695508) (xy 113.493999 -225.687383)
			(xy 113.545933 -225.687383) (xy 113.597228 -225.695508) (xy 113.646621 -225.711556) (xy 113.692895 -225.735134)
			(xy 113.734911 -225.76566) (xy 113.771634 -225.802383) (xy 113.80216 -225.844399) (xy 113.825738 -225.890673)
			(xy 113.841786 -225.940066) (xy 113.849911 -225.991361) (xy 113.85042 -226.017328) (xy 113.849911 -226.043295)
			(xy 114.129821 -226.043295) (xy 114.129821 -225.991361) (xy 114.137946 -225.940066) (xy 114.153994 -225.890673)
			(xy 114.177572 -225.844399) (xy 114.208098 -225.802383) (xy 114.244821 -225.76566) (xy 114.286837 -225.735134)
			(xy 114.333111 -225.711556) (xy 114.382504 -225.695508) (xy 114.433799 -225.687383) (xy 114.485733 -225.687383)
			(xy 114.537028 -225.695508) (xy 114.586421 -225.711556) (xy 114.632695 -225.735134) (xy 114.674711 -225.76566)
			(xy 114.711434 -225.802383) (xy 114.74196 -225.844399) (xy 114.765538 -225.890673) (xy 114.781586 -225.940066)
			(xy 114.789711 -225.991361) (xy 114.79022 -226.017328) (xy 114.789711 -226.043295) (xy 115.069621 -226.043295)
			(xy 115.069621 -225.991361) (xy 115.077746 -225.940066) (xy 115.093794 -225.890673) (xy 115.117372 -225.844399)
			(xy 115.147898 -225.802383) (xy 115.184621 -225.76566) (xy 115.226637 -225.735134) (xy 115.272911 -225.711556)
			(xy 115.322304 -225.695508) (xy 115.373599 -225.687383) (xy 115.425533 -225.687383) (xy 115.476828 -225.695508)
			(xy 115.526221 -225.711556) (xy 115.572495 -225.735134) (xy 115.614511 -225.76566) (xy 115.651234 -225.802383)
			(xy 115.68176 -225.844399) (xy 115.705338 -225.890673) (xy 115.721386 -225.940066) (xy 115.729511 -225.991361)
			(xy 115.73002 -226.017328) (xy 115.729511 -226.043295) (xy 116.009421 -226.043295) (xy 116.009421 -225.991361)
			(xy 116.017546 -225.940066) (xy 116.033594 -225.890673) (xy 116.057172 -225.844399) (xy 116.087698 -225.802383)
			(xy 116.124421 -225.76566) (xy 116.166437 -225.735134) (xy 116.212711 -225.711556) (xy 116.262104 -225.695508)
			(xy 116.313399 -225.687383) (xy 116.365333 -225.687383) (xy 116.416628 -225.695508) (xy 116.466021 -225.711556)
			(xy 116.512295 -225.735134) (xy 116.554311 -225.76566) (xy 116.591034 -225.802383) (xy 116.62156 -225.844399)
			(xy 116.645138 -225.890673) (xy 116.661186 -225.940066) (xy 116.669311 -225.991361) (xy 116.66982 -226.017328)
			(xy 116.669311 -226.043295) (xy 116.949221 -226.043295) (xy 116.949221 -225.991361) (xy 116.957346 -225.940066)
			(xy 116.973394 -225.890673) (xy 116.996972 -225.844399) (xy 117.027498 -225.802383) (xy 117.064221 -225.76566)
			(xy 117.106237 -225.735134) (xy 117.152511 -225.711556) (xy 117.201904 -225.695508) (xy 117.253199 -225.687383)
			(xy 117.305133 -225.687383) (xy 117.356428 -225.695508) (xy 117.405821 -225.711556) (xy 117.452095 -225.735134)
			(xy 117.494111 -225.76566) (xy 117.530834 -225.802383) (xy 117.56136 -225.844399) (xy 117.584938 -225.890673)
			(xy 117.600986 -225.940066) (xy 117.609111 -225.991361) (xy 117.60962 -226.017328) (xy 117.609111 -226.043295)
			(xy 117.889021 -226.043295) (xy 117.889021 -225.991361) (xy 117.897146 -225.940066) (xy 117.913194 -225.890673)
			(xy 117.936772 -225.844399) (xy 117.967298 -225.802383) (xy 118.004021 -225.76566) (xy 118.046037 -225.735134)
			(xy 118.092311 -225.711556) (xy 118.141704 -225.695508) (xy 118.192999 -225.687383) (xy 118.244933 -225.687383)
			(xy 118.296228 -225.695508) (xy 118.345621 -225.711556) (xy 118.391895 -225.735134) (xy 118.433911 -225.76566)
			(xy 118.470634 -225.802383) (xy 118.50116 -225.844399) (xy 118.524738 -225.890673) (xy 118.540786 -225.940066)
			(xy 118.548911 -225.991361) (xy 118.54942 -226.017328) (xy 118.548911 -226.043295) (xy 118.828821 -226.043295)
			(xy 118.828821 -225.991361) (xy 118.836946 -225.940066) (xy 118.852994 -225.890673) (xy 118.876572 -225.844399)
			(xy 118.907098 -225.802383) (xy 118.943821 -225.76566) (xy 118.985837 -225.735134) (xy 119.032111 -225.711556)
			(xy 119.081504 -225.695508) (xy 119.132799 -225.687383) (xy 119.184733 -225.687383) (xy 119.236028 -225.695508)
			(xy 119.285421 -225.711556) (xy 119.331695 -225.735134) (xy 119.373711 -225.76566) (xy 119.410434 -225.802383)
			(xy 119.44096 -225.844399) (xy 119.464538 -225.890673) (xy 119.480586 -225.940066) (xy 119.488711 -225.991361)
			(xy 119.48922 -226.017328) (xy 119.488711 -226.043295) (xy 119.768621 -226.043295) (xy 119.768621 -225.991361)
			(xy 119.776746 -225.940066) (xy 119.792794 -225.890673) (xy 119.816372 -225.844399) (xy 119.846898 -225.802383)
			(xy 119.883621 -225.76566) (xy 119.925637 -225.735134) (xy 119.971911 -225.711556) (xy 120.021304 -225.695508)
			(xy 120.072599 -225.687383) (xy 120.124533 -225.687383) (xy 120.175828 -225.695508) (xy 120.225221 -225.711556)
			(xy 120.271495 -225.735134) (xy 120.313511 -225.76566) (xy 120.350234 -225.802383) (xy 120.38076 -225.844399)
			(xy 120.404338 -225.890673) (xy 120.420386 -225.940066) (xy 120.428511 -225.991361) (xy 120.42902 -226.017328)
			(xy 120.428511 -226.043295) (xy 120.708421 -226.043295) (xy 120.708421 -225.991361) (xy 120.716546 -225.940066)
			(xy 120.732594 -225.890673) (xy 120.756172 -225.844399) (xy 120.786698 -225.802383) (xy 120.823421 -225.76566)
			(xy 120.865437 -225.735134) (xy 120.911711 -225.711556) (xy 120.961104 -225.695508) (xy 121.012399 -225.687383)
			(xy 121.064333 -225.687383) (xy 121.115628 -225.695508) (xy 121.165021 -225.711556) (xy 121.211295 -225.735134)
			(xy 121.253311 -225.76566) (xy 121.290034 -225.802383) (xy 121.32056 -225.844399) (xy 121.344138 -225.890673)
			(xy 121.360186 -225.940066) (xy 121.368311 -225.991361) (xy 121.36882 -226.017328) (xy 121.368311 -226.043295)
			(xy 121.648221 -226.043295) (xy 121.648221 -225.991361) (xy 121.656346 -225.940066) (xy 121.672394 -225.890673)
			(xy 121.695972 -225.844399) (xy 121.726498 -225.802383) (xy 121.763221 -225.76566) (xy 121.805237 -225.735134)
			(xy 121.851511 -225.711556) (xy 121.900904 -225.695508) (xy 121.952199 -225.687383) (xy 122.004133 -225.687383)
			(xy 122.055428 -225.695508) (xy 122.104821 -225.711556) (xy 122.151095 -225.735134) (xy 122.193111 -225.76566)
			(xy 122.229834 -225.802383) (xy 122.26036 -225.844399) (xy 122.283938 -225.890673) (xy 122.299986 -225.940066)
			(xy 122.308111 -225.991361) (xy 122.30862 -226.017328) (xy 122.308111 -226.043295) (xy 122.299986 -226.09459)
			(xy 122.283938 -226.143983) (xy 122.26036 -226.190257) (xy 122.229834 -226.232273) (xy 122.193111 -226.268996)
			(xy 122.151095 -226.299522) (xy 122.104821 -226.3231) (xy 122.055428 -226.339148) (xy 122.004133 -226.347273)
			(xy 121.952199 -226.347273) (xy 121.900904 -226.339148) (xy 121.851511 -226.3231) (xy 121.805237 -226.299522)
			(xy 121.763221 -226.268996) (xy 121.726498 -226.232273) (xy 121.695972 -226.190257) (xy 121.672394 -226.143983)
			(xy 121.656346 -226.09459) (xy 121.648221 -226.043295) (xy 121.368311 -226.043295) (xy 121.360186 -226.09459)
			(xy 121.344138 -226.143983) (xy 121.32056 -226.190257) (xy 121.290034 -226.232273) (xy 121.253311 -226.268996)
			(xy 121.211295 -226.299522) (xy 121.165021 -226.3231) (xy 121.115628 -226.339148) (xy 121.064333 -226.347273)
			(xy 121.012399 -226.347273) (xy 120.961104 -226.339148) (xy 120.911711 -226.3231) (xy 120.865437 -226.299522)
			(xy 120.823421 -226.268996) (xy 120.786698 -226.232273) (xy 120.756172 -226.190257) (xy 120.732594 -226.143983)
			(xy 120.716546 -226.09459) (xy 120.708421 -226.043295) (xy 120.428511 -226.043295) (xy 120.420386 -226.09459)
			(xy 120.404338 -226.143983) (xy 120.38076 -226.190257) (xy 120.350234 -226.232273) (xy 120.313511 -226.268996)
			(xy 120.271495 -226.299522) (xy 120.225221 -226.3231) (xy 120.175828 -226.339148) (xy 120.124533 -226.347273)
			(xy 120.072599 -226.347273) (xy 120.021304 -226.339148) (xy 119.971911 -226.3231) (xy 119.925637 -226.299522)
			(xy 119.883621 -226.268996) (xy 119.846898 -226.232273) (xy 119.816372 -226.190257) (xy 119.792794 -226.143983)
			(xy 119.776746 -226.09459) (xy 119.768621 -226.043295) (xy 119.488711 -226.043295) (xy 119.480586 -226.09459)
			(xy 119.464538 -226.143983) (xy 119.44096 -226.190257) (xy 119.410434 -226.232273) (xy 119.373711 -226.268996)
			(xy 119.331695 -226.299522) (xy 119.285421 -226.3231) (xy 119.236028 -226.339148) (xy 119.184733 -226.347273)
			(xy 119.132799 -226.347273) (xy 119.081504 -226.339148) (xy 119.032111 -226.3231) (xy 118.985837 -226.299522)
			(xy 118.943821 -226.268996) (xy 118.907098 -226.232273) (xy 118.876572 -226.190257) (xy 118.852994 -226.143983)
			(xy 118.836946 -226.09459) (xy 118.828821 -226.043295) (xy 118.548911 -226.043295) (xy 118.540786 -226.09459)
			(xy 118.524738 -226.143983) (xy 118.50116 -226.190257) (xy 118.470634 -226.232273) (xy 118.433911 -226.268996)
			(xy 118.391895 -226.299522) (xy 118.345621 -226.3231) (xy 118.296228 -226.339148) (xy 118.244933 -226.347273)
			(xy 118.192999 -226.347273) (xy 118.141704 -226.339148) (xy 118.092311 -226.3231) (xy 118.046037 -226.299522)
			(xy 118.004021 -226.268996) (xy 117.967298 -226.232273) (xy 117.936772 -226.190257) (xy 117.913194 -226.143983)
			(xy 117.897146 -226.09459) (xy 117.889021 -226.043295) (xy 117.609111 -226.043295) (xy 117.600986 -226.09459)
			(xy 117.584938 -226.143983) (xy 117.56136 -226.190257) (xy 117.530834 -226.232273) (xy 117.494111 -226.268996)
			(xy 117.452095 -226.299522) (xy 117.405821 -226.3231) (xy 117.356428 -226.339148) (xy 117.305133 -226.347273)
			(xy 117.253199 -226.347273) (xy 117.201904 -226.339148) (xy 117.152511 -226.3231) (xy 117.106237 -226.299522)
			(xy 117.064221 -226.268996) (xy 117.027498 -226.232273) (xy 116.996972 -226.190257) (xy 116.973394 -226.143983)
			(xy 116.957346 -226.09459) (xy 116.949221 -226.043295) (xy 116.669311 -226.043295) (xy 116.661186 -226.09459)
			(xy 116.645138 -226.143983) (xy 116.62156 -226.190257) (xy 116.591034 -226.232273) (xy 116.554311 -226.268996)
			(xy 116.512295 -226.299522) (xy 116.466021 -226.3231) (xy 116.416628 -226.339148) (xy 116.365333 -226.347273)
			(xy 116.313399 -226.347273) (xy 116.262104 -226.339148) (xy 116.212711 -226.3231) (xy 116.166437 -226.299522)
			(xy 116.124421 -226.268996) (xy 116.087698 -226.232273) (xy 116.057172 -226.190257) (xy 116.033594 -226.143983)
			(xy 116.017546 -226.09459) (xy 116.009421 -226.043295) (xy 115.729511 -226.043295) (xy 115.721386 -226.09459)
			(xy 115.705338 -226.143983) (xy 115.68176 -226.190257) (xy 115.651234 -226.232273) (xy 115.614511 -226.268996)
			(xy 115.572495 -226.299522) (xy 115.526221 -226.3231) (xy 115.476828 -226.339148) (xy 115.425533 -226.347273)
			(xy 115.373599 -226.347273) (xy 115.322304 -226.339148) (xy 115.272911 -226.3231) (xy 115.226637 -226.299522)
			(xy 115.184621 -226.268996) (xy 115.147898 -226.232273) (xy 115.117372 -226.190257) (xy 115.093794 -226.143983)
			(xy 115.077746 -226.09459) (xy 115.069621 -226.043295) (xy 114.789711 -226.043295) (xy 114.781586 -226.09459)
			(xy 114.765538 -226.143983) (xy 114.74196 -226.190257) (xy 114.711434 -226.232273) (xy 114.674711 -226.268996)
			(xy 114.632695 -226.299522) (xy 114.586421 -226.3231) (xy 114.537028 -226.339148) (xy 114.485733 -226.347273)
			(xy 114.433799 -226.347273) (xy 114.382504 -226.339148) (xy 114.333111 -226.3231) (xy 114.286837 -226.299522)
			(xy 114.244821 -226.268996) (xy 114.208098 -226.232273) (xy 114.177572 -226.190257) (xy 114.153994 -226.143983)
			(xy 114.137946 -226.09459) (xy 114.129821 -226.043295) (xy 113.849911 -226.043295) (xy 113.841786 -226.09459)
			(xy 113.825738 -226.143983) (xy 113.80216 -226.190257) (xy 113.771634 -226.232273) (xy 113.734911 -226.268996)
			(xy 113.692895 -226.299522) (xy 113.646621 -226.3231) (xy 113.597228 -226.339148) (xy 113.545933 -226.347273)
			(xy 113.493999 -226.347273) (xy 113.442704 -226.339148) (xy 113.393311 -226.3231) (xy 113.347037 -226.299522)
			(xy 113.305021 -226.268996) (xy 113.268298 -226.232273) (xy 113.237772 -226.190257) (xy 113.214194 -226.143983)
			(xy 113.198146 -226.09459) (xy 113.190021 -226.043295) (xy 112.910111 -226.043295) (xy 112.901986 -226.09459)
			(xy 112.885938 -226.143983) (xy 112.86236 -226.190257) (xy 112.831834 -226.232273) (xy 112.795111 -226.268996)
			(xy 112.753095 -226.299522) (xy 112.706821 -226.3231) (xy 112.657428 -226.339148) (xy 112.606133 -226.347273)
			(xy 112.554199 -226.347273) (xy 112.502904 -226.339148) (xy 112.453511 -226.3231) (xy 112.407237 -226.299522)
			(xy 112.365221 -226.268996) (xy 112.328498 -226.232273) (xy 112.297972 -226.190257) (xy 112.274394 -226.143983)
			(xy 112.258346 -226.09459) (xy 112.250221 -226.043295) (xy 111.970311 -226.043295) (xy 111.962186 -226.09459)
			(xy 111.946138 -226.143983) (xy 111.92256 -226.190257) (xy 111.892034 -226.232273) (xy 111.855311 -226.268996)
			(xy 111.813295 -226.299522) (xy 111.767021 -226.3231) (xy 111.717628 -226.339148) (xy 111.666333 -226.347273)
			(xy 111.614399 -226.347273) (xy 111.563104 -226.339148) (xy 111.513711 -226.3231) (xy 111.467437 -226.299522)
			(xy 111.425421 -226.268996) (xy 111.388698 -226.232273) (xy 111.358172 -226.190257) (xy 111.334594 -226.143983)
			(xy 111.318546 -226.09459) (xy 111.310421 -226.043295) (xy 111.030511 -226.043295) (xy 111.022386 -226.09459)
			(xy 111.006338 -226.143983) (xy 110.98276 -226.190257) (xy 110.952234 -226.232273) (xy 110.915511 -226.268996)
			(xy 110.873495 -226.299522) (xy 110.827221 -226.3231) (xy 110.777828 -226.339148) (xy 110.726533 -226.347273)
			(xy 110.674599 -226.347273) (xy 110.623304 -226.339148) (xy 110.573911 -226.3231) (xy 110.527637 -226.299522)
			(xy 110.485621 -226.268996) (xy 110.448898 -226.232273) (xy 110.418372 -226.190257) (xy 110.394794 -226.143983)
			(xy 110.378746 -226.09459) (xy 110.370621 -226.043295) (xy 110.090711 -226.043295) (xy 110.082586 -226.09459)
			(xy 110.066538 -226.143983) (xy 110.04296 -226.190257) (xy 110.012434 -226.232273) (xy 109.975711 -226.268996)
			(xy 109.933695 -226.299522) (xy 109.887421 -226.3231) (xy 109.838028 -226.339148) (xy 109.786733 -226.347273)
			(xy 109.734799 -226.347273) (xy 109.683504 -226.339148) (xy 109.634111 -226.3231) (xy 109.587837 -226.299522)
			(xy 109.545821 -226.268996) (xy 109.509098 -226.232273) (xy 109.478572 -226.190257) (xy 109.454994 -226.143983)
			(xy 109.438946 -226.09459) (xy 109.430821 -226.043295) (xy 109.150911 -226.043295) (xy 109.142786 -226.09459)
			(xy 109.126738 -226.143983) (xy 109.10316 -226.190257) (xy 109.072634 -226.232273) (xy 109.035911 -226.268996)
			(xy 108.993895 -226.299522) (xy 108.947621 -226.3231) (xy 108.898228 -226.339148) (xy 108.846933 -226.347273)
			(xy 108.794999 -226.347273) (xy 108.743704 -226.339148) (xy 108.694311 -226.3231) (xy 108.648037 -226.299522)
			(xy 108.606021 -226.268996) (xy 108.569298 -226.232273) (xy 108.538772 -226.190257) (xy 108.515194 -226.143983)
			(xy 108.499146 -226.09459) (xy 108.491021 -226.043295) (xy 108.211111 -226.043295) (xy 108.202986 -226.09459)
			(xy 108.186938 -226.143983) (xy 108.16336 -226.190257) (xy 108.132834 -226.232273) (xy 108.096111 -226.268996)
			(xy 108.054095 -226.299522) (xy 108.007821 -226.3231) (xy 107.958428 -226.339148) (xy 107.907133 -226.347273)
			(xy 107.855199 -226.347273) (xy 107.803904 -226.339148) (xy 107.754511 -226.3231) (xy 107.708237 -226.299522)
			(xy 107.666221 -226.268996) (xy 107.629498 -226.232273) (xy 107.598972 -226.190257) (xy 107.575394 -226.143983)
			(xy 107.559346 -226.09459) (xy 107.551221 -226.043295) (xy 107.271311 -226.043295) (xy 107.263186 -226.09459)
			(xy 107.247138 -226.143983) (xy 107.22356 -226.190257) (xy 107.193034 -226.232273) (xy 107.156311 -226.268996)
			(xy 107.114295 -226.299522) (xy 107.068021 -226.3231) (xy 107.018628 -226.339148) (xy 106.967333 -226.347273)
			(xy 106.915399 -226.347273) (xy 106.864104 -226.339148) (xy 106.814711 -226.3231) (xy 106.768437 -226.299522)
			(xy 106.726421 -226.268996) (xy 106.689698 -226.232273) (xy 106.659172 -226.190257) (xy 106.635594 -226.143983)
			(xy 106.619546 -226.09459) (xy 106.611421 -226.043295) (xy 106.331511 -226.043295) (xy 106.323386 -226.09459)
			(xy 106.307338 -226.143983) (xy 106.28376 -226.190257) (xy 106.253234 -226.232273) (xy 106.216511 -226.268996)
			(xy 106.174495 -226.299522) (xy 106.128221 -226.3231) (xy 106.078828 -226.339148) (xy 106.027533 -226.347273)
			(xy 105.975599 -226.347273) (xy 105.924304 -226.339148) (xy 105.874911 -226.3231) (xy 105.828637 -226.299522)
			(xy 105.786621 -226.268996) (xy 105.749898 -226.232273) (xy 105.719372 -226.190257) (xy 105.695794 -226.143983)
			(xy 105.679746 -226.09459) (xy 105.671621 -226.043295) (xy 105.391711 -226.043295) (xy 105.383586 -226.09459)
			(xy 105.367538 -226.143983) (xy 105.34396 -226.190257) (xy 105.313434 -226.232273) (xy 105.276711 -226.268996)
			(xy 105.234695 -226.299522) (xy 105.188421 -226.3231) (xy 105.139028 -226.339148) (xy 105.087733 -226.347273)
			(xy 105.035799 -226.347273) (xy 104.984504 -226.339148) (xy 104.935111 -226.3231) (xy 104.888837 -226.299522)
			(xy 104.846821 -226.268996) (xy 104.810098 -226.232273) (xy 104.779572 -226.190257) (xy 104.755994 -226.143983)
			(xy 104.739946 -226.09459) (xy 104.731821 -226.043295) (xy 104.451911 -226.043295) (xy 104.443786 -226.09459)
			(xy 104.427738 -226.143983) (xy 104.40416 -226.190257) (xy 104.373634 -226.232273) (xy 104.336911 -226.268996)
			(xy 104.294895 -226.299522) (xy 104.248621 -226.3231) (xy 104.199228 -226.339148) (xy 104.147933 -226.347273)
			(xy 104.095999 -226.347273) (xy 104.044704 -226.339148) (xy 103.995311 -226.3231) (xy 103.949037 -226.299522)
			(xy 103.907021 -226.268996) (xy 103.870298 -226.232273) (xy 103.839772 -226.190257) (xy 103.816194 -226.143983)
			(xy 103.800146 -226.09459) (xy 103.792021 -226.043295) (xy 103.512139 -226.043295) (xy 103.504018 -226.094567)
			(xy 103.487967 -226.143962) (xy 103.464387 -226.190238) (xy 103.433857 -226.232255) (xy 103.397129 -226.268979)
			(xy 103.355109 -226.299504) (xy 103.308831 -226.32308) (xy 103.259434 -226.339126) (xy 103.208135 -226.347246)
			(xy 103.182166 -226.347782) (xy 103.158863 -226.34738) (xy 103.112719 -226.340829) (xy 103.067953 -226.327863)
			(xy 103.025451 -226.308737) (xy 102.986058 -226.283831) (xy 102.968044 -226.269042) (xy 102.956684 -226.260066)
			(xy 102.930254 -226.248281) (xy 102.901579 -226.244383) (xy 102.872962 -226.248685) (xy 102.846701 -226.260843)
			(xy 102.824904 -226.279879) (xy 102.809323 -226.304265) (xy 102.801209 -226.332043) (xy 102.800658 -226.346512)
			(xy 102.800658 -226.51085) (xy 102.832916 -226.52355) (xy 102.857269 -226.533677) (xy 102.902663 -226.560525)
			(xy 102.943217 -226.594241) (xy 102.977901 -226.633971) (xy 103.005835 -226.678704) (xy 103.026309 -226.727307)
			(xy 103.038804 -226.778544) (xy 103.043003 -226.831116) (xy 103.040924 -226.857111) (xy 103.322121 -226.857111)
			(xy 103.322121 -226.805177) (xy 103.330246 -226.753882) (xy 103.346294 -226.704489) (xy 103.369872 -226.658215)
			(xy 103.400398 -226.616199) (xy 103.437121 -226.579476) (xy 103.479137 -226.54895) (xy 103.525411 -226.525372)
			(xy 103.574804 -226.509324) (xy 103.626099 -226.501199) (xy 103.678033 -226.501199) (xy 103.729328 -226.509324)
			(xy 103.778721 -226.525372) (xy 103.824995 -226.54895) (xy 103.867011 -226.579476) (xy 103.903734 -226.616199)
			(xy 103.93426 -226.658215) (xy 103.957838 -226.704489) (xy 103.973886 -226.753882) (xy 103.982011 -226.805177)
			(xy 103.98252 -226.831144) (xy 103.982011 -226.857111) (xy 104.261921 -226.857111) (xy 104.261921 -226.805177)
			(xy 104.270046 -226.753882) (xy 104.286094 -226.704489) (xy 104.309672 -226.658215) (xy 104.340198 -226.616199)
			(xy 104.376921 -226.579476) (xy 104.418937 -226.54895) (xy 104.465211 -226.525372) (xy 104.514604 -226.509324)
			(xy 104.565899 -226.501199) (xy 104.617833 -226.501199) (xy 104.669128 -226.509324) (xy 104.718521 -226.525372)
			(xy 104.764795 -226.54895) (xy 104.806811 -226.579476) (xy 104.843534 -226.616199) (xy 104.87406 -226.658215)
			(xy 104.897638 -226.704489) (xy 104.913686 -226.753882) (xy 104.921811 -226.805177) (xy 104.92232 -226.831144)
			(xy 104.921811 -226.857111) (xy 105.201467 -226.857111) (xy 105.201467 -226.805177) (xy 105.209592 -226.753882)
			(xy 105.22564 -226.704489) (xy 105.249218 -226.658215) (xy 105.279744 -226.616199) (xy 105.316467 -226.579476)
			(xy 105.358483 -226.54895) (xy 105.404757 -226.525372) (xy 105.45415 -226.509324) (xy 105.505445 -226.501199)
			(xy 105.557379 -226.501199) (xy 105.608674 -226.509324) (xy 105.658067 -226.525372) (xy 105.704341 -226.54895)
			(xy 105.746357 -226.579476) (xy 105.78308 -226.616199) (xy 105.813606 -226.658215) (xy 105.837184 -226.704489)
			(xy 105.853232 -226.753882) (xy 105.861357 -226.805177) (xy 105.861866 -226.831144) (xy 105.861357 -226.857111)
			(xy 106.141521 -226.857111) (xy 106.141521 -226.805177) (xy 106.149646 -226.753882) (xy 106.165694 -226.704489)
			(xy 106.189272 -226.658215) (xy 106.219798 -226.616199) (xy 106.256521 -226.579476) (xy 106.298537 -226.54895)
			(xy 106.344811 -226.525372) (xy 106.394204 -226.509324) (xy 106.445499 -226.501199) (xy 106.497433 -226.501199)
			(xy 106.548728 -226.509324) (xy 106.598121 -226.525372) (xy 106.644395 -226.54895) (xy 106.686411 -226.579476)
			(xy 106.723134 -226.616199) (xy 106.75366 -226.658215) (xy 106.777238 -226.704489) (xy 106.793286 -226.753882)
			(xy 106.801411 -226.805177) (xy 106.80192 -226.831144) (xy 106.801411 -226.857111) (xy 107.081067 -226.857111)
			(xy 107.081067 -226.805177) (xy 107.089192 -226.753882) (xy 107.10524 -226.704489) (xy 107.128818 -226.658215)
			(xy 107.159344 -226.616199) (xy 107.196067 -226.579476) (xy 107.238083 -226.54895) (xy 107.284357 -226.525372)
			(xy 107.33375 -226.509324) (xy 107.385045 -226.501199) (xy 107.436979 -226.501199) (xy 107.488274 -226.509324)
			(xy 107.537667 -226.525372) (xy 107.583941 -226.54895) (xy 107.625957 -226.579476) (xy 107.66268 -226.616199)
			(xy 107.693206 -226.658215) (xy 107.716784 -226.704489) (xy 107.732832 -226.753882) (xy 107.740957 -226.805177)
			(xy 107.741466 -226.831144) (xy 107.740957 -226.857111) (xy 108.021121 -226.857111) (xy 108.021121 -226.805177)
			(xy 108.029246 -226.753882) (xy 108.045294 -226.704489) (xy 108.068872 -226.658215) (xy 108.099398 -226.616199)
			(xy 108.136121 -226.579476) (xy 108.178137 -226.54895) (xy 108.224411 -226.525372) (xy 108.273804 -226.509324)
			(xy 108.325099 -226.501199) (xy 108.377033 -226.501199) (xy 108.428328 -226.509324) (xy 108.477721 -226.525372)
			(xy 108.523995 -226.54895) (xy 108.566011 -226.579476) (xy 108.602734 -226.616199) (xy 108.63326 -226.658215)
			(xy 108.656838 -226.704489) (xy 108.672886 -226.753882) (xy 108.681011 -226.805177) (xy 108.68152 -226.831144)
			(xy 108.681011 -226.857111) (xy 108.960667 -226.857111) (xy 108.960667 -226.805177) (xy 108.968792 -226.753882)
			(xy 108.98484 -226.704489) (xy 109.008418 -226.658215) (xy 109.038944 -226.616199) (xy 109.075667 -226.579476)
			(xy 109.117683 -226.54895) (xy 109.163957 -226.525372) (xy 109.21335 -226.509324) (xy 109.264645 -226.501199)
			(xy 109.316579 -226.501199) (xy 109.367874 -226.509324) (xy 109.417267 -226.525372) (xy 109.463541 -226.54895)
			(xy 109.505557 -226.579476) (xy 109.54228 -226.616199) (xy 109.572806 -226.658215) (xy 109.596384 -226.704489)
			(xy 109.612432 -226.753882) (xy 109.620557 -226.805177) (xy 109.621066 -226.831144) (xy 109.620557 -226.857111)
			(xy 109.900721 -226.857111) (xy 109.900721 -226.805177) (xy 109.908846 -226.753882) (xy 109.924894 -226.704489)
			(xy 109.948472 -226.658215) (xy 109.978998 -226.616199) (xy 110.015721 -226.579476) (xy 110.057737 -226.54895)
			(xy 110.104011 -226.525372) (xy 110.153404 -226.509324) (xy 110.204699 -226.501199) (xy 110.256633 -226.501199)
			(xy 110.307928 -226.509324) (xy 110.357321 -226.525372) (xy 110.403595 -226.54895) (xy 110.445611 -226.579476)
			(xy 110.482334 -226.616199) (xy 110.51286 -226.658215) (xy 110.536438 -226.704489) (xy 110.552486 -226.753882)
			(xy 110.560611 -226.805177) (xy 110.56112 -226.831144) (xy 110.560611 -226.857111) (xy 110.840267 -226.857111)
			(xy 110.840267 -226.805177) (xy 110.848392 -226.753882) (xy 110.86444 -226.704489) (xy 110.888018 -226.658215)
			(xy 110.918544 -226.616199) (xy 110.955267 -226.579476) (xy 110.997283 -226.54895) (xy 111.043557 -226.525372)
			(xy 111.09295 -226.509324) (xy 111.144245 -226.501199) (xy 111.196179 -226.501199) (xy 111.247474 -226.509324)
			(xy 111.296867 -226.525372) (xy 111.343141 -226.54895) (xy 111.385157 -226.579476) (xy 111.42188 -226.616199)
			(xy 111.452406 -226.658215) (xy 111.475984 -226.704489) (xy 111.492032 -226.753882) (xy 111.500157 -226.805177)
			(xy 111.500666 -226.831144) (xy 111.500157 -226.857111) (xy 111.780321 -226.857111) (xy 111.780321 -226.805177)
			(xy 111.788446 -226.753882) (xy 111.804494 -226.704489) (xy 111.828072 -226.658215) (xy 111.858598 -226.616199)
			(xy 111.895321 -226.579476) (xy 111.937337 -226.54895) (xy 111.983611 -226.525372) (xy 112.033004 -226.509324)
			(xy 112.084299 -226.501199) (xy 112.136233 -226.501199) (xy 112.187528 -226.509324) (xy 112.236921 -226.525372)
			(xy 112.283195 -226.54895) (xy 112.325211 -226.579476) (xy 112.361934 -226.616199) (xy 112.39246 -226.658215)
			(xy 112.416038 -226.704489) (xy 112.432086 -226.753882) (xy 112.440211 -226.805177) (xy 112.44072 -226.831144)
			(xy 112.440211 -226.857111) (xy 112.719867 -226.857111) (xy 112.719867 -226.805177) (xy 112.727992 -226.753882)
			(xy 112.74404 -226.704489) (xy 112.767618 -226.658215) (xy 112.798144 -226.616199) (xy 112.834867 -226.579476)
			(xy 112.876883 -226.54895) (xy 112.923157 -226.525372) (xy 112.97255 -226.509324) (xy 113.023845 -226.501199)
			(xy 113.075779 -226.501199) (xy 113.127074 -226.509324) (xy 113.176467 -226.525372) (xy 113.222741 -226.54895)
			(xy 113.264757 -226.579476) (xy 113.30148 -226.616199) (xy 113.332006 -226.658215) (xy 113.355584 -226.704489)
			(xy 113.371632 -226.753882) (xy 113.379757 -226.805177) (xy 113.380266 -226.831144) (xy 113.379757 -226.857111)
			(xy 113.659921 -226.857111) (xy 113.659921 -226.805177) (xy 113.668046 -226.753882) (xy 113.684094 -226.704489)
			(xy 113.707672 -226.658215) (xy 113.738198 -226.616199) (xy 113.774921 -226.579476) (xy 113.816937 -226.54895)
			(xy 113.863211 -226.525372) (xy 113.912604 -226.509324) (xy 113.963899 -226.501199) (xy 114.015833 -226.501199)
			(xy 114.067128 -226.509324) (xy 114.116521 -226.525372) (xy 114.162795 -226.54895) (xy 114.204811 -226.579476)
			(xy 114.241534 -226.616199) (xy 114.27206 -226.658215) (xy 114.295638 -226.704489) (xy 114.311686 -226.753882)
			(xy 114.319811 -226.805177) (xy 114.32032 -226.831144) (xy 114.319811 -226.857111) (xy 114.599721 -226.857111)
			(xy 114.599721 -226.805177) (xy 114.607846 -226.753882) (xy 114.623894 -226.704489) (xy 114.647472 -226.658215)
			(xy 114.677998 -226.616199) (xy 114.714721 -226.579476) (xy 114.756737 -226.54895) (xy 114.803011 -226.525372)
			(xy 114.852404 -226.509324) (xy 114.903699 -226.501199) (xy 114.955633 -226.501199) (xy 115.006928 -226.509324)
			(xy 115.056321 -226.525372) (xy 115.102595 -226.54895) (xy 115.144611 -226.579476) (xy 115.181334 -226.616199)
			(xy 115.21186 -226.658215) (xy 115.235438 -226.704489) (xy 115.251486 -226.753882) (xy 115.259611 -226.805177)
			(xy 115.26012 -226.831144) (xy 115.259611 -226.857111) (xy 115.539521 -226.857111) (xy 115.539521 -226.805177)
			(xy 115.547646 -226.753882) (xy 115.563694 -226.704489) (xy 115.587272 -226.658215) (xy 115.617798 -226.616199)
			(xy 115.654521 -226.579476) (xy 115.696537 -226.54895) (xy 115.742811 -226.525372) (xy 115.792204 -226.509324)
			(xy 115.843499 -226.501199) (xy 115.895433 -226.501199) (xy 115.946728 -226.509324) (xy 115.996121 -226.525372)
			(xy 116.042395 -226.54895) (xy 116.084411 -226.579476) (xy 116.121134 -226.616199) (xy 116.15166 -226.658215)
			(xy 116.175238 -226.704489) (xy 116.191286 -226.753882) (xy 116.199411 -226.805177) (xy 116.19992 -226.831144)
			(xy 116.199411 -226.857111) (xy 116.479067 -226.857111) (xy 116.479067 -226.805177) (xy 116.487192 -226.753882)
			(xy 116.50324 -226.704489) (xy 116.526818 -226.658215) (xy 116.557344 -226.616199) (xy 116.594067 -226.579476)
			(xy 116.636083 -226.54895) (xy 116.682357 -226.525372) (xy 116.73175 -226.509324) (xy 116.783045 -226.501199)
			(xy 116.834979 -226.501199) (xy 116.886274 -226.509324) (xy 116.935667 -226.525372) (xy 116.981941 -226.54895)
			(xy 117.023957 -226.579476) (xy 117.06068 -226.616199) (xy 117.091206 -226.658215) (xy 117.114784 -226.704489)
			(xy 117.130832 -226.753882) (xy 117.138957 -226.805177) (xy 117.139466 -226.831144) (xy 117.138957 -226.857111)
			(xy 117.419121 -226.857111) (xy 117.419121 -226.805177) (xy 117.427246 -226.753882) (xy 117.443294 -226.704489)
			(xy 117.466872 -226.658215) (xy 117.497398 -226.616199) (xy 117.534121 -226.579476) (xy 117.576137 -226.54895)
			(xy 117.622411 -226.525372) (xy 117.671804 -226.509324) (xy 117.723099 -226.501199) (xy 117.775033 -226.501199)
			(xy 117.826328 -226.509324) (xy 117.875721 -226.525372) (xy 117.921995 -226.54895) (xy 117.964011 -226.579476)
			(xy 118.000734 -226.616199) (xy 118.03126 -226.658215) (xy 118.054838 -226.704489) (xy 118.070886 -226.753882)
			(xy 118.079011 -226.805177) (xy 118.07952 -226.831144) (xy 118.079011 -226.857111) (xy 118.358667 -226.857111)
			(xy 118.358667 -226.805177) (xy 118.366792 -226.753882) (xy 118.38284 -226.704489) (xy 118.406418 -226.658215)
			(xy 118.436944 -226.616199) (xy 118.473667 -226.579476) (xy 118.515683 -226.54895) (xy 118.561957 -226.525372)
			(xy 118.61135 -226.509324) (xy 118.662645 -226.501199) (xy 118.714579 -226.501199) (xy 118.765874 -226.509324)
			(xy 118.815267 -226.525372) (xy 118.861541 -226.54895) (xy 118.903557 -226.579476) (xy 118.94028 -226.616199)
			(xy 118.970806 -226.658215) (xy 118.994384 -226.704489) (xy 119.010432 -226.753882) (xy 119.018557 -226.805177)
			(xy 119.019066 -226.831144) (xy 119.018557 -226.857111) (xy 119.298721 -226.857111) (xy 119.298721 -226.805177)
			(xy 119.306846 -226.753882) (xy 119.322894 -226.704489) (xy 119.346472 -226.658215) (xy 119.376998 -226.616199)
			(xy 119.413721 -226.579476) (xy 119.455737 -226.54895) (xy 119.502011 -226.525372) (xy 119.551404 -226.509324)
			(xy 119.602699 -226.501199) (xy 119.654633 -226.501199) (xy 119.705928 -226.509324) (xy 119.755321 -226.525372)
			(xy 119.801595 -226.54895) (xy 119.843611 -226.579476) (xy 119.880334 -226.616199) (xy 119.91086 -226.658215)
			(xy 119.934438 -226.704489) (xy 119.950486 -226.753882) (xy 119.958611 -226.805177) (xy 119.95912 -226.831144)
			(xy 119.958611 -226.857111) (xy 120.238267 -226.857111) (xy 120.238267 -226.805177) (xy 120.246392 -226.753882)
			(xy 120.26244 -226.704489) (xy 120.286018 -226.658215) (xy 120.316544 -226.616199) (xy 120.353267 -226.579476)
			(xy 120.395283 -226.54895) (xy 120.441557 -226.525372) (xy 120.49095 -226.509324) (xy 120.542245 -226.501199)
			(xy 120.594179 -226.501199) (xy 120.645474 -226.509324) (xy 120.694867 -226.525372) (xy 120.741141 -226.54895)
			(xy 120.783157 -226.579476) (xy 120.81988 -226.616199) (xy 120.850406 -226.658215) (xy 120.873984 -226.704489)
			(xy 120.890032 -226.753882) (xy 120.898157 -226.805177) (xy 120.898666 -226.831144) (xy 120.898157 -226.857111)
			(xy 121.178321 -226.857111) (xy 121.178321 -226.805177) (xy 121.186446 -226.753882) (xy 121.202494 -226.704489)
			(xy 121.226072 -226.658215) (xy 121.256598 -226.616199) (xy 121.293321 -226.579476) (xy 121.335337 -226.54895)
			(xy 121.381611 -226.525372) (xy 121.431004 -226.509324) (xy 121.482299 -226.501199) (xy 121.534233 -226.501199)
			(xy 121.585528 -226.509324) (xy 121.634921 -226.525372) (xy 121.681195 -226.54895) (xy 121.723211 -226.579476)
			(xy 121.759934 -226.616199) (xy 121.79046 -226.658215) (xy 121.814038 -226.704489) (xy 121.830086 -226.753882)
			(xy 121.838211 -226.805177) (xy 121.83872 -226.831144) (xy 121.838211 -226.857111) (xy 121.830086 -226.908406)
			(xy 121.814038 -226.957799) (xy 121.79046 -227.004073) (xy 121.759934 -227.046089) (xy 121.723211 -227.082812)
			(xy 121.681195 -227.113338) (xy 121.634921 -227.136916) (xy 121.585528 -227.152964) (xy 121.534233 -227.161089)
			(xy 121.482299 -227.161089) (xy 121.431004 -227.152964) (xy 121.381611 -227.136916) (xy 121.335337 -227.113338)
			(xy 121.293321 -227.082812) (xy 121.256598 -227.046089) (xy 121.226072 -227.004073) (xy 121.202494 -226.957799)
			(xy 121.186446 -226.908406) (xy 121.178321 -226.857111) (xy 120.898157 -226.857111) (xy 120.890032 -226.908406)
			(xy 120.873984 -226.957799) (xy 120.850406 -227.004073) (xy 120.81988 -227.046089) (xy 120.783157 -227.082812)
			(xy 120.741141 -227.113338) (xy 120.694867 -227.136916) (xy 120.645474 -227.152964) (xy 120.594179 -227.161089)
			(xy 120.542245 -227.161089) (xy 120.49095 -227.152964) (xy 120.441557 -227.136916) (xy 120.395283 -227.113338)
			(xy 120.353267 -227.082812) (xy 120.316544 -227.046089) (xy 120.286018 -227.004073) (xy 120.26244 -226.957799)
			(xy 120.246392 -226.908406) (xy 120.238267 -226.857111) (xy 119.958611 -226.857111) (xy 119.950486 -226.908406)
			(xy 119.934438 -226.957799) (xy 119.91086 -227.004073) (xy 119.880334 -227.046089) (xy 119.843611 -227.082812)
			(xy 119.801595 -227.113338) (xy 119.755321 -227.136916) (xy 119.705928 -227.152964) (xy 119.654633 -227.161089)
			(xy 119.602699 -227.161089) (xy 119.551404 -227.152964) (xy 119.502011 -227.136916) (xy 119.455737 -227.113338)
			(xy 119.413721 -227.082812) (xy 119.376998 -227.046089) (xy 119.346472 -227.004073) (xy 119.322894 -226.957799)
			(xy 119.306846 -226.908406) (xy 119.298721 -226.857111) (xy 119.018557 -226.857111) (xy 119.010432 -226.908406)
			(xy 118.994384 -226.957799) (xy 118.970806 -227.004073) (xy 118.94028 -227.046089) (xy 118.903557 -227.082812)
			(xy 118.861541 -227.113338) (xy 118.815267 -227.136916) (xy 118.765874 -227.152964) (xy 118.714579 -227.161089)
			(xy 118.662645 -227.161089) (xy 118.61135 -227.152964) (xy 118.561957 -227.136916) (xy 118.515683 -227.113338)
			(xy 118.473667 -227.082812) (xy 118.436944 -227.046089) (xy 118.406418 -227.004073) (xy 118.38284 -226.957799)
			(xy 118.366792 -226.908406) (xy 118.358667 -226.857111) (xy 118.079011 -226.857111) (xy 118.070886 -226.908406)
			(xy 118.054838 -226.957799) (xy 118.03126 -227.004073) (xy 118.000734 -227.046089) (xy 117.964011 -227.082812)
			(xy 117.921995 -227.113338) (xy 117.875721 -227.136916) (xy 117.826328 -227.152964) (xy 117.775033 -227.161089)
			(xy 117.723099 -227.161089) (xy 117.671804 -227.152964) (xy 117.622411 -227.136916) (xy 117.576137 -227.113338)
			(xy 117.534121 -227.082812) (xy 117.497398 -227.046089) (xy 117.466872 -227.004073) (xy 117.443294 -226.957799)
			(xy 117.427246 -226.908406) (xy 117.419121 -226.857111) (xy 117.138957 -226.857111) (xy 117.130832 -226.908406)
			(xy 117.114784 -226.957799) (xy 117.091206 -227.004073) (xy 117.06068 -227.046089) (xy 117.023957 -227.082812)
			(xy 116.981941 -227.113338) (xy 116.935667 -227.136916) (xy 116.886274 -227.152964) (xy 116.834979 -227.161089)
			(xy 116.783045 -227.161089) (xy 116.73175 -227.152964) (xy 116.682357 -227.136916) (xy 116.636083 -227.113338)
			(xy 116.594067 -227.082812) (xy 116.557344 -227.046089) (xy 116.526818 -227.004073) (xy 116.50324 -226.957799)
			(xy 116.487192 -226.908406) (xy 116.479067 -226.857111) (xy 116.199411 -226.857111) (xy 116.191286 -226.908406)
			(xy 116.175238 -226.957799) (xy 116.15166 -227.004073) (xy 116.121134 -227.046089) (xy 116.084411 -227.082812)
			(xy 116.042395 -227.113338) (xy 115.996121 -227.136916) (xy 115.946728 -227.152964) (xy 115.895433 -227.161089)
			(xy 115.843499 -227.161089) (xy 115.792204 -227.152964) (xy 115.742811 -227.136916) (xy 115.696537 -227.113338)
			(xy 115.654521 -227.082812) (xy 115.617798 -227.046089) (xy 115.587272 -227.004073) (xy 115.563694 -226.957799)
			(xy 115.547646 -226.908406) (xy 115.539521 -226.857111) (xy 115.259611 -226.857111) (xy 115.251486 -226.908406)
			(xy 115.235438 -226.957799) (xy 115.21186 -227.004073) (xy 115.181334 -227.046089) (xy 115.144611 -227.082812)
			(xy 115.102595 -227.113338) (xy 115.056321 -227.136916) (xy 115.006928 -227.152964) (xy 114.955633 -227.161089)
			(xy 114.903699 -227.161089) (xy 114.852404 -227.152964) (xy 114.803011 -227.136916) (xy 114.756737 -227.113338)
			(xy 114.714721 -227.082812) (xy 114.677998 -227.046089) (xy 114.647472 -227.004073) (xy 114.623894 -226.957799)
			(xy 114.607846 -226.908406) (xy 114.599721 -226.857111) (xy 114.319811 -226.857111) (xy 114.311686 -226.908406)
			(xy 114.295638 -226.957799) (xy 114.27206 -227.004073) (xy 114.241534 -227.046089) (xy 114.204811 -227.082812)
			(xy 114.162795 -227.113338) (xy 114.116521 -227.136916) (xy 114.067128 -227.152964) (xy 114.015833 -227.161089)
			(xy 113.963899 -227.161089) (xy 113.912604 -227.152964) (xy 113.863211 -227.136916) (xy 113.816937 -227.113338)
			(xy 113.774921 -227.082812) (xy 113.738198 -227.046089) (xy 113.707672 -227.004073) (xy 113.684094 -226.957799)
			(xy 113.668046 -226.908406) (xy 113.659921 -226.857111) (xy 113.379757 -226.857111) (xy 113.371632 -226.908406)
			(xy 113.355584 -226.957799) (xy 113.332006 -227.004073) (xy 113.30148 -227.046089) (xy 113.264757 -227.082812)
			(xy 113.222741 -227.113338) (xy 113.176467 -227.136916) (xy 113.127074 -227.152964) (xy 113.075779 -227.161089)
			(xy 113.023845 -227.161089) (xy 112.97255 -227.152964) (xy 112.923157 -227.136916) (xy 112.876883 -227.113338)
			(xy 112.834867 -227.082812) (xy 112.798144 -227.046089) (xy 112.767618 -227.004073) (xy 112.74404 -226.957799)
			(xy 112.727992 -226.908406) (xy 112.719867 -226.857111) (xy 112.440211 -226.857111) (xy 112.432086 -226.908406)
			(xy 112.416038 -226.957799) (xy 112.39246 -227.004073) (xy 112.361934 -227.046089) (xy 112.325211 -227.082812)
			(xy 112.283195 -227.113338) (xy 112.236921 -227.136916) (xy 112.187528 -227.152964) (xy 112.136233 -227.161089)
			(xy 112.084299 -227.161089) (xy 112.033004 -227.152964) (xy 111.983611 -227.136916) (xy 111.937337 -227.113338)
			(xy 111.895321 -227.082812) (xy 111.858598 -227.046089) (xy 111.828072 -227.004073) (xy 111.804494 -226.957799)
			(xy 111.788446 -226.908406) (xy 111.780321 -226.857111) (xy 111.500157 -226.857111) (xy 111.492032 -226.908406)
			(xy 111.475984 -226.957799) (xy 111.452406 -227.004073) (xy 111.42188 -227.046089) (xy 111.385157 -227.082812)
			(xy 111.343141 -227.113338) (xy 111.296867 -227.136916) (xy 111.247474 -227.152964) (xy 111.196179 -227.161089)
			(xy 111.144245 -227.161089) (xy 111.09295 -227.152964) (xy 111.043557 -227.136916) (xy 110.997283 -227.113338)
			(xy 110.955267 -227.082812) (xy 110.918544 -227.046089) (xy 110.888018 -227.004073) (xy 110.86444 -226.957799)
			(xy 110.848392 -226.908406) (xy 110.840267 -226.857111) (xy 110.560611 -226.857111) (xy 110.552486 -226.908406)
			(xy 110.536438 -226.957799) (xy 110.51286 -227.004073) (xy 110.482334 -227.046089) (xy 110.445611 -227.082812)
			(xy 110.403595 -227.113338) (xy 110.357321 -227.136916) (xy 110.307928 -227.152964) (xy 110.256633 -227.161089)
			(xy 110.204699 -227.161089) (xy 110.153404 -227.152964) (xy 110.104011 -227.136916) (xy 110.057737 -227.113338)
			(xy 110.015721 -227.082812) (xy 109.978998 -227.046089) (xy 109.948472 -227.004073) (xy 109.924894 -226.957799)
			(xy 109.908846 -226.908406) (xy 109.900721 -226.857111) (xy 109.620557 -226.857111) (xy 109.612432 -226.908406)
			(xy 109.596384 -226.957799) (xy 109.572806 -227.004073) (xy 109.54228 -227.046089) (xy 109.505557 -227.082812)
			(xy 109.463541 -227.113338) (xy 109.417267 -227.136916) (xy 109.367874 -227.152964) (xy 109.316579 -227.161089)
			(xy 109.264645 -227.161089) (xy 109.21335 -227.152964) (xy 109.163957 -227.136916) (xy 109.117683 -227.113338)
			(xy 109.075667 -227.082812) (xy 109.038944 -227.046089) (xy 109.008418 -227.004073) (xy 108.98484 -226.957799)
			(xy 108.968792 -226.908406) (xy 108.960667 -226.857111) (xy 108.681011 -226.857111) (xy 108.672886 -226.908406)
			(xy 108.656838 -226.957799) (xy 108.63326 -227.004073) (xy 108.602734 -227.046089) (xy 108.566011 -227.082812)
			(xy 108.523995 -227.113338) (xy 108.477721 -227.136916) (xy 108.428328 -227.152964) (xy 108.377033 -227.161089)
			(xy 108.325099 -227.161089) (xy 108.273804 -227.152964) (xy 108.224411 -227.136916) (xy 108.178137 -227.113338)
			(xy 108.136121 -227.082812) (xy 108.099398 -227.046089) (xy 108.068872 -227.004073) (xy 108.045294 -226.957799)
			(xy 108.029246 -226.908406) (xy 108.021121 -226.857111) (xy 107.740957 -226.857111) (xy 107.732832 -226.908406)
			(xy 107.716784 -226.957799) (xy 107.693206 -227.004073) (xy 107.66268 -227.046089) (xy 107.625957 -227.082812)
			(xy 107.583941 -227.113338) (xy 107.537667 -227.136916) (xy 107.488274 -227.152964) (xy 107.436979 -227.161089)
			(xy 107.385045 -227.161089) (xy 107.33375 -227.152964) (xy 107.284357 -227.136916) (xy 107.238083 -227.113338)
			(xy 107.196067 -227.082812) (xy 107.159344 -227.046089) (xy 107.128818 -227.004073) (xy 107.10524 -226.957799)
			(xy 107.089192 -226.908406) (xy 107.081067 -226.857111) (xy 106.801411 -226.857111) (xy 106.793286 -226.908406)
			(xy 106.777238 -226.957799) (xy 106.75366 -227.004073) (xy 106.723134 -227.046089) (xy 106.686411 -227.082812)
			(xy 106.644395 -227.113338) (xy 106.598121 -227.136916) (xy 106.548728 -227.152964) (xy 106.497433 -227.161089)
			(xy 106.445499 -227.161089) (xy 106.394204 -227.152964) (xy 106.344811 -227.136916) (xy 106.298537 -227.113338)
			(xy 106.256521 -227.082812) (xy 106.219798 -227.046089) (xy 106.189272 -227.004073) (xy 106.165694 -226.957799)
			(xy 106.149646 -226.908406) (xy 106.141521 -226.857111) (xy 105.861357 -226.857111) (xy 105.853232 -226.908406)
			(xy 105.837184 -226.957799) (xy 105.813606 -227.004073) (xy 105.78308 -227.046089) (xy 105.746357 -227.082812)
			(xy 105.704341 -227.113338) (xy 105.658067 -227.136916) (xy 105.608674 -227.152964) (xy 105.557379 -227.161089)
			(xy 105.505445 -227.161089) (xy 105.45415 -227.152964) (xy 105.404757 -227.136916) (xy 105.358483 -227.113338)
			(xy 105.316467 -227.082812) (xy 105.279744 -227.046089) (xy 105.249218 -227.004073) (xy 105.22564 -226.957799)
			(xy 105.209592 -226.908406) (xy 105.201467 -226.857111) (xy 104.921811 -226.857111) (xy 104.913686 -226.908406)
			(xy 104.897638 -226.957799) (xy 104.87406 -227.004073) (xy 104.843534 -227.046089) (xy 104.806811 -227.082812)
			(xy 104.764795 -227.113338) (xy 104.718521 -227.136916) (xy 104.669128 -227.152964) (xy 104.617833 -227.161089)
			(xy 104.565899 -227.161089) (xy 104.514604 -227.152964) (xy 104.465211 -227.136916) (xy 104.418937 -227.113338)
			(xy 104.376921 -227.082812) (xy 104.340198 -227.046089) (xy 104.309672 -227.004073) (xy 104.286094 -226.957799)
			(xy 104.270046 -226.908406) (xy 104.261921 -226.857111) (xy 103.982011 -226.857111) (xy 103.973886 -226.908406)
			(xy 103.957838 -226.957799) (xy 103.93426 -227.004073) (xy 103.903734 -227.046089) (xy 103.867011 -227.082812)
			(xy 103.824995 -227.113338) (xy 103.778721 -227.136916) (xy 103.729328 -227.152964) (xy 103.678033 -227.161089)
			(xy 103.626099 -227.161089) (xy 103.574804 -227.152964) (xy 103.525411 -227.136916) (xy 103.479137 -227.113338)
			(xy 103.437121 -227.082812) (xy 103.400398 -227.046089) (xy 103.369872 -227.004073) (xy 103.346294 -226.957799)
			(xy 103.330246 -226.908406) (xy 103.322121 -226.857111) (xy 103.040924 -226.857111) (xy 103.038799 -226.883687)
			(xy 103.026299 -226.934924) (xy 103.00582 -226.983524) (xy 102.977882 -227.028255) (xy 102.943194 -227.067981)
			(xy 102.902636 -227.101694) (xy 102.85724 -227.128537) (xy 102.832916 -227.138738) (xy 102.800658 -227.151438)
			(xy 102.800658 -227.851208) (xy 102.958138 -228.008688) (xy 103.33228 -228.008688) (xy 103.519732 -227.821236)
			(xy 103.696516 -227.821236) (xy 103.711315 -227.820731) (xy 103.739671 -227.812245) (xy 103.764407 -227.795991)
			(xy 103.783448 -227.77333) (xy 103.795198 -227.746164) (xy 103.798671 -227.71677) (xy 103.796592 -227.70211)
			(xy 103.794241 -227.687939) (xy 103.791702 -227.659324) (xy 103.791512 -227.64496) (xy 103.792021 -227.618993)
			(xy 103.800146 -227.567698) (xy 103.816194 -227.518305) (xy 103.839772 -227.472031) (xy 103.870298 -227.430015)
			(xy 103.907021 -227.393292) (xy 103.949037 -227.362766) (xy 103.995311 -227.339188) (xy 104.044704 -227.32314)
			(xy 104.095999 -227.315015) (xy 104.147933 -227.315015) (xy 104.199228 -227.32314) (xy 104.248621 -227.339188)
			(xy 104.294895 -227.362766) (xy 104.336911 -227.393292) (xy 104.373634 -227.430015) (xy 104.40416 -227.472031)
			(xy 104.427738 -227.518305) (xy 104.443786 -227.567698) (xy 104.451911 -227.618993) (xy 104.45242 -227.64496)
			(xy 104.452247 -227.659324) (xy 104.449702 -227.68794) (xy 104.44734 -227.70211) (xy 104.445289 -227.716769)
			(xy 104.448761 -227.746152) (xy 104.460508 -227.773308) (xy 104.479545 -227.795957) (xy 104.504275 -227.812201)
			(xy 104.532622 -227.820676) (xy 104.547416 -227.821236) (xy 104.636316 -227.821236) (xy 104.651115 -227.820731)
			(xy 104.679471 -227.812245) (xy 104.704207 -227.795991) (xy 104.723248 -227.77333) (xy 104.734998 -227.746164)
			(xy 104.738471 -227.71677) (xy 104.736392 -227.70211) (xy 104.734041 -227.687939) (xy 104.731502 -227.659324)
			(xy 104.731312 -227.64496) (xy 104.731821 -227.618993) (xy 104.739946 -227.567698) (xy 104.755994 -227.518305)
			(xy 104.779572 -227.472031) (xy 104.810098 -227.430015) (xy 104.846821 -227.393292) (xy 104.888837 -227.362766)
			(xy 104.935111 -227.339188) (xy 104.984504 -227.32314) (xy 105.035799 -227.315015) (xy 105.087733 -227.315015)
			(xy 105.139028 -227.32314) (xy 105.188421 -227.339188) (xy 105.234695 -227.362766) (xy 105.276711 -227.393292)
			(xy 105.313434 -227.430015) (xy 105.34396 -227.472031) (xy 105.367538 -227.518305) (xy 105.383586 -227.567698)
			(xy 105.391711 -227.618993) (xy 105.39222 -227.64496) (xy 105.392093 -227.658869) (xy 105.389805 -227.686591)
			(xy 105.387648 -227.700332) (xy 105.385675 -227.714955) (xy 105.389258 -227.74423) (xy 105.401049 -227.771265)
			(xy 105.420065 -227.79381) (xy 105.444725 -227.80999) (xy 105.472978 -227.818457) (xy 105.487724 -227.81895)
			(xy 105.575608 -227.81895) (xy 105.590365 -227.818464) (xy 105.61865 -227.810042) (xy 105.643342 -227.793876)
			(xy 105.662373 -227.771319) (xy 105.674151 -227.744259) (xy 105.677691 -227.71496) (xy 105.675684 -227.700332)
			(xy 105.673515 -227.686593) (xy 105.671224 -227.658869) (xy 105.671112 -227.64496) (xy 105.671621 -227.618993)
			(xy 105.679746 -227.567698) (xy 105.695794 -227.518305) (xy 105.719372 -227.472031) (xy 105.749898 -227.430015)
			(xy 105.786621 -227.393292) (xy 105.828637 -227.362766) (xy 105.874911 -227.339188) (xy 105.924304 -227.32314)
			(xy 105.975599 -227.315015) (xy 106.027533 -227.315015) (xy 106.078828 -227.32314) (xy 106.128221 -227.339188)
			(xy 106.174495 -227.362766) (xy 106.216511 -227.393292) (xy 106.253234 -227.430015) (xy 106.28376 -227.472031)
			(xy 106.307338 -227.518305) (xy 106.323386 -227.567698) (xy 106.331511 -227.618993) (xy 106.33202 -227.64496)
			(xy 106.331893 -227.658869) (xy 106.329605 -227.686591) (xy 106.327448 -227.700332) (xy 106.325475 -227.714955)
			(xy 106.329058 -227.74423) (xy 106.340849 -227.771265) (xy 106.359865 -227.79381) (xy 106.384525 -227.80999)
			(xy 106.412778 -227.818457) (xy 106.427524 -227.81895) (xy 106.515408 -227.81895) (xy 106.530165 -227.818464)
			(xy 106.55845 -227.810042) (xy 106.583142 -227.793876) (xy 106.602173 -227.771319) (xy 106.613951 -227.744259)
			(xy 106.617491 -227.71496) (xy 106.615484 -227.700332) (xy 106.613315 -227.686593) (xy 106.611024 -227.658869)
			(xy 106.610912 -227.64496) (xy 106.611421 -227.618993) (xy 106.619546 -227.567698) (xy 106.635594 -227.518305)
			(xy 106.659172 -227.472031) (xy 106.689698 -227.430015) (xy 106.726421 -227.393292) (xy 106.768437 -227.362766)
			(xy 106.814711 -227.339188) (xy 106.864104 -227.32314) (xy 106.915399 -227.315015) (xy 106.967333 -227.315015)
			(xy 107.018628 -227.32314) (xy 107.068021 -227.339188) (xy 107.114295 -227.362766) (xy 107.156311 -227.393292)
			(xy 107.193034 -227.430015) (xy 107.22356 -227.472031) (xy 107.247138 -227.518305) (xy 107.263186 -227.567698)
			(xy 107.271311 -227.618993) (xy 107.27182 -227.64496) (xy 107.271693 -227.658869) (xy 107.269405 -227.686591)
			(xy 107.267248 -227.700332) (xy 107.265275 -227.714955) (xy 107.268858 -227.74423) (xy 107.280649 -227.771265)
			(xy 107.299665 -227.79381) (xy 107.324325 -227.80999) (xy 107.352578 -227.818457) (xy 107.367324 -227.81895)
			(xy 107.455208 -227.81895) (xy 107.469965 -227.818464) (xy 107.49825 -227.810042) (xy 107.522942 -227.793876)
			(xy 107.541973 -227.771319) (xy 107.553751 -227.744259) (xy 107.557291 -227.71496) (xy 107.555284 -227.700332)
			(xy 107.553115 -227.686593) (xy 107.550824 -227.658869) (xy 107.550712 -227.64496) (xy 107.551221 -227.618993)
			(xy 107.559346 -227.567698) (xy 107.575394 -227.518305) (xy 107.598972 -227.472031) (xy 107.629498 -227.430015)
			(xy 107.666221 -227.393292) (xy 107.708237 -227.362766) (xy 107.754511 -227.339188) (xy 107.803904 -227.32314)
			(xy 107.855199 -227.315015) (xy 107.907133 -227.315015) (xy 107.958428 -227.32314) (xy 108.007821 -227.339188)
			(xy 108.054095 -227.362766) (xy 108.096111 -227.393292) (xy 108.132834 -227.430015) (xy 108.16336 -227.472031)
			(xy 108.186938 -227.518305) (xy 108.202986 -227.567698) (xy 108.211111 -227.618993) (xy 108.21162 -227.64496)
			(xy 108.211493 -227.658869) (xy 108.209205 -227.686591) (xy 108.207048 -227.700332) (xy 108.205075 -227.714955)
			(xy 108.208658 -227.74423) (xy 108.220449 -227.771265) (xy 108.239465 -227.79381) (xy 108.264125 -227.80999)
			(xy 108.292378 -227.818457) (xy 108.307124 -227.81895) (xy 108.395008 -227.81895) (xy 108.409765 -227.818464)
			(xy 108.43805 -227.810042) (xy 108.462742 -227.793876) (xy 108.481773 -227.771319) (xy 108.493551 -227.744259)
			(xy 108.497091 -227.71496) (xy 108.495084 -227.700332) (xy 108.492915 -227.686593) (xy 108.490624 -227.658869)
			(xy 108.490512 -227.64496) (xy 108.491021 -227.618993) (xy 108.499146 -227.567698) (xy 108.515194 -227.518305)
			(xy 108.538772 -227.472031) (xy 108.569298 -227.430015) (xy 108.606021 -227.393292) (xy 108.648037 -227.362766)
			(xy 108.694311 -227.339188) (xy 108.743704 -227.32314) (xy 108.794999 -227.315015) (xy 108.846933 -227.315015)
			(xy 108.898228 -227.32314) (xy 108.947621 -227.339188) (xy 108.993895 -227.362766) (xy 109.035911 -227.393292)
			(xy 109.072634 -227.430015) (xy 109.10316 -227.472031) (xy 109.126738 -227.518305) (xy 109.142786 -227.567698)
			(xy 109.150911 -227.618993) (xy 109.15142 -227.64496) (xy 109.151293 -227.658869) (xy 109.149005 -227.686591)
			(xy 109.146848 -227.700332) (xy 109.144875 -227.714955) (xy 109.148458 -227.74423) (xy 109.160249 -227.771265)
			(xy 109.179265 -227.79381) (xy 109.203925 -227.80999) (xy 109.232178 -227.818457) (xy 109.246924 -227.81895)
			(xy 109.334808 -227.81895) (xy 109.349565 -227.818464) (xy 109.37785 -227.810042) (xy 109.402542 -227.793876)
			(xy 109.421573 -227.771319) (xy 109.433351 -227.744259) (xy 109.436891 -227.71496) (xy 109.434884 -227.700332)
			(xy 109.432715 -227.686593) (xy 109.430424 -227.658869) (xy 109.430312 -227.64496) (xy 109.430821 -227.618993)
			(xy 109.438946 -227.567698) (xy 109.454994 -227.518305) (xy 109.478572 -227.472031) (xy 109.509098 -227.430015)
			(xy 109.545821 -227.393292) (xy 109.587837 -227.362766) (xy 109.634111 -227.339188) (xy 109.683504 -227.32314)
			(xy 109.734799 -227.315015) (xy 109.786733 -227.315015) (xy 109.838028 -227.32314) (xy 109.887421 -227.339188)
			(xy 109.933695 -227.362766) (xy 109.975711 -227.393292) (xy 110.012434 -227.430015) (xy 110.04296 -227.472031)
			(xy 110.066538 -227.518305) (xy 110.082586 -227.567698) (xy 110.090711 -227.618993) (xy 110.09122 -227.64496)
			(xy 110.090849 -227.666787) (xy 110.090296 -227.670927) (xy 110.370621 -227.670927) (xy 110.370621 -227.618993)
			(xy 110.378746 -227.567698) (xy 110.394794 -227.518305) (xy 110.418372 -227.472031) (xy 110.448898 -227.430015)
			(xy 110.485621 -227.393292) (xy 110.527637 -227.362766) (xy 110.573911 -227.339188) (xy 110.623304 -227.32314)
			(xy 110.674599 -227.315015) (xy 110.726533 -227.315015) (xy 110.777828 -227.32314) (xy 110.827221 -227.339188)
			(xy 110.873495 -227.362766) (xy 110.915511 -227.393292) (xy 110.952234 -227.430015) (xy 110.98276 -227.472031)
			(xy 111.006338 -227.518305) (xy 111.022386 -227.567698) (xy 111.030511 -227.618993) (xy 111.03102 -227.64496)
			(xy 111.030511 -227.670927) (xy 111.310421 -227.670927) (xy 111.310421 -227.618993) (xy 111.318546 -227.567698)
			(xy 111.334594 -227.518305) (xy 111.358172 -227.472031) (xy 111.388698 -227.430015) (xy 111.425421 -227.393292)
			(xy 111.467437 -227.362766) (xy 111.513711 -227.339188) (xy 111.563104 -227.32314) (xy 111.614399 -227.315015)
			(xy 111.666333 -227.315015) (xy 111.717628 -227.32314) (xy 111.767021 -227.339188) (xy 111.813295 -227.362766)
			(xy 111.855311 -227.393292) (xy 111.892034 -227.430015) (xy 111.92256 -227.472031) (xy 111.946138 -227.518305)
			(xy 111.962186 -227.567698) (xy 111.970311 -227.618993) (xy 111.97082 -227.64496) (xy 111.970311 -227.670927)
			(xy 112.250221 -227.670927) (xy 112.250221 -227.618993) (xy 112.258346 -227.567698) (xy 112.274394 -227.518305)
			(xy 112.297972 -227.472031) (xy 112.328498 -227.430015) (xy 112.365221 -227.393292) (xy 112.407237 -227.362766)
			(xy 112.453511 -227.339188) (xy 112.502904 -227.32314) (xy 112.554199 -227.315015) (xy 112.606133 -227.315015)
			(xy 112.657428 -227.32314) (xy 112.706821 -227.339188) (xy 112.753095 -227.362766) (xy 112.795111 -227.393292)
			(xy 112.831834 -227.430015) (xy 112.86236 -227.472031) (xy 112.885938 -227.518305) (xy 112.901986 -227.567698)
			(xy 112.910111 -227.618993) (xy 112.91062 -227.64496) (xy 112.910111 -227.670927) (xy 113.190021 -227.670927)
			(xy 113.190021 -227.618993) (xy 113.198146 -227.567698) (xy 113.214194 -227.518305) (xy 113.237772 -227.472031)
			(xy 113.268298 -227.430015) (xy 113.305021 -227.393292) (xy 113.347037 -227.362766) (xy 113.393311 -227.339188)
			(xy 113.442704 -227.32314) (xy 113.493999 -227.315015) (xy 113.545933 -227.315015) (xy 113.597228 -227.32314)
			(xy 113.646621 -227.339188) (xy 113.692895 -227.362766) (xy 113.734911 -227.393292) (xy 113.771634 -227.430015)
			(xy 113.80216 -227.472031) (xy 113.825738 -227.518305) (xy 113.841786 -227.567698) (xy 113.849911 -227.618993)
			(xy 113.85042 -227.64496) (xy 113.849911 -227.670927) (xy 114.130075 -227.670927) (xy 114.130075 -227.618993)
			(xy 114.1382 -227.567698) (xy 114.154248 -227.518305) (xy 114.177826 -227.472031) (xy 114.208352 -227.430015)
			(xy 114.245075 -227.393292) (xy 114.287091 -227.362766) (xy 114.333365 -227.339188) (xy 114.382758 -227.32314)
			(xy 114.434053 -227.315015) (xy 114.485987 -227.315015) (xy 114.537282 -227.32314) (xy 114.586675 -227.339188)
			(xy 114.632949 -227.362766) (xy 114.674965 -227.393292) (xy 114.711688 -227.430015) (xy 114.742214 -227.472031)
			(xy 114.765792 -227.518305) (xy 114.78184 -227.567698) (xy 114.789965 -227.618993) (xy 114.790474 -227.64496)
			(xy 114.789965 -227.670927) (xy 115.069621 -227.670927) (xy 115.069621 -227.618993) (xy 115.077746 -227.567698)
			(xy 115.093794 -227.518305) (xy 115.117372 -227.472031) (xy 115.147898 -227.430015) (xy 115.184621 -227.393292)
			(xy 115.226637 -227.362766) (xy 115.272911 -227.339188) (xy 115.322304 -227.32314) (xy 115.373599 -227.315015)
			(xy 115.425533 -227.315015) (xy 115.476828 -227.32314) (xy 115.526221 -227.339188) (xy 115.572495 -227.362766)
			(xy 115.614511 -227.393292) (xy 115.651234 -227.430015) (xy 115.68176 -227.472031) (xy 115.705338 -227.518305)
			(xy 115.721386 -227.567698) (xy 115.729511 -227.618993) (xy 115.73002 -227.64496) (xy 115.729511 -227.670927)
			(xy 116.009421 -227.670927) (xy 116.009421 -227.618993) (xy 116.017546 -227.567698) (xy 116.033594 -227.518305)
			(xy 116.057172 -227.472031) (xy 116.087698 -227.430015) (xy 116.124421 -227.393292) (xy 116.166437 -227.362766)
			(xy 116.212711 -227.339188) (xy 116.262104 -227.32314) (xy 116.313399 -227.315015) (xy 116.365333 -227.315015)
			(xy 116.416628 -227.32314) (xy 116.466021 -227.339188) (xy 116.512295 -227.362766) (xy 116.554311 -227.393292)
			(xy 116.591034 -227.430015) (xy 116.62156 -227.472031) (xy 116.645138 -227.518305) (xy 116.661186 -227.567698)
			(xy 116.669311 -227.618993) (xy 116.66982 -227.64496) (xy 116.669311 -227.670927) (xy 116.949221 -227.670927)
			(xy 116.949221 -227.618993) (xy 116.957346 -227.567698) (xy 116.973394 -227.518305) (xy 116.996972 -227.472031)
			(xy 117.027498 -227.430015) (xy 117.064221 -227.393292) (xy 117.106237 -227.362766) (xy 117.152511 -227.339188)
			(xy 117.201904 -227.32314) (xy 117.253199 -227.315015) (xy 117.305133 -227.315015) (xy 117.356428 -227.32314)
			(xy 117.405821 -227.339188) (xy 117.452095 -227.362766) (xy 117.494111 -227.393292) (xy 117.530834 -227.430015)
			(xy 117.56136 -227.472031) (xy 117.584938 -227.518305) (xy 117.600986 -227.567698) (xy 117.609111 -227.618993)
			(xy 117.60962 -227.64496) (xy 117.609111 -227.670927) (xy 117.889021 -227.670927) (xy 117.889021 -227.618993)
			(xy 117.897146 -227.567698) (xy 117.913194 -227.518305) (xy 117.936772 -227.472031) (xy 117.967298 -227.430015)
			(xy 118.004021 -227.393292) (xy 118.046037 -227.362766) (xy 118.092311 -227.339188) (xy 118.141704 -227.32314)
			(xy 118.192999 -227.315015) (xy 118.244933 -227.315015) (xy 118.296228 -227.32314) (xy 118.345621 -227.339188)
			(xy 118.391895 -227.362766) (xy 118.433911 -227.393292) (xy 118.470634 -227.430015) (xy 118.50116 -227.472031)
			(xy 118.524738 -227.518305) (xy 118.540786 -227.567698) (xy 118.548911 -227.618993) (xy 118.54942 -227.64496)
			(xy 118.548911 -227.670927) (xy 118.828821 -227.670927) (xy 118.828821 -227.618993) (xy 118.836946 -227.567698)
			(xy 118.852994 -227.518305) (xy 118.876572 -227.472031) (xy 118.907098 -227.430015) (xy 118.943821 -227.393292)
			(xy 118.985837 -227.362766) (xy 119.032111 -227.339188) (xy 119.081504 -227.32314) (xy 119.132799 -227.315015)
			(xy 119.184733 -227.315015) (xy 119.236028 -227.32314) (xy 119.285421 -227.339188) (xy 119.331695 -227.362766)
			(xy 119.373711 -227.393292) (xy 119.410434 -227.430015) (xy 119.44096 -227.472031) (xy 119.464538 -227.518305)
			(xy 119.480586 -227.567698) (xy 119.488711 -227.618993) (xy 119.48922 -227.64496) (xy 119.488711 -227.670927)
			(xy 119.768621 -227.670927) (xy 119.768621 -227.618993) (xy 119.776746 -227.567698) (xy 119.792794 -227.518305)
			(xy 119.816372 -227.472031) (xy 119.846898 -227.430015) (xy 119.883621 -227.393292) (xy 119.925637 -227.362766)
			(xy 119.971911 -227.339188) (xy 120.021304 -227.32314) (xy 120.072599 -227.315015) (xy 120.124533 -227.315015)
			(xy 120.175828 -227.32314) (xy 120.225221 -227.339188) (xy 120.271495 -227.362766) (xy 120.313511 -227.393292)
			(xy 120.350234 -227.430015) (xy 120.38076 -227.472031) (xy 120.404338 -227.518305) (xy 120.420386 -227.567698)
			(xy 120.428511 -227.618993) (xy 120.42902 -227.64496) (xy 120.428511 -227.670927) (xy 120.708421 -227.670927)
			(xy 120.708421 -227.618993) (xy 120.716546 -227.567698) (xy 120.732594 -227.518305) (xy 120.756172 -227.472031)
			(xy 120.786698 -227.430015) (xy 120.823421 -227.393292) (xy 120.865437 -227.362766) (xy 120.911711 -227.339188)
			(xy 120.961104 -227.32314) (xy 121.012399 -227.315015) (xy 121.064333 -227.315015) (xy 121.115628 -227.32314)
			(xy 121.165021 -227.339188) (xy 121.211295 -227.362766) (xy 121.253311 -227.393292) (xy 121.290034 -227.430015)
			(xy 121.32056 -227.472031) (xy 121.344138 -227.518305) (xy 121.360186 -227.567698) (xy 121.368311 -227.618993)
			(xy 121.36882 -227.64496) (xy 121.368311 -227.670927) (xy 121.647967 -227.670927) (xy 121.647967 -227.618993)
			(xy 121.656092 -227.567698) (xy 121.67214 -227.518305) (xy 121.695718 -227.472031) (xy 121.726244 -227.430015)
			(xy 121.762967 -227.393292) (xy 121.804983 -227.362766) (xy 121.851257 -227.339188) (xy 121.90065 -227.32314)
			(xy 121.951945 -227.315015) (xy 122.003879 -227.315015) (xy 122.055174 -227.32314) (xy 122.104567 -227.339188)
			(xy 122.150841 -227.362766) (xy 122.192857 -227.393292) (xy 122.22958 -227.430015) (xy 122.260106 -227.472031)
			(xy 122.283684 -227.518305) (xy 122.299732 -227.567698) (xy 122.307857 -227.618993) (xy 122.308366 -227.64496)
			(xy 122.307857 -227.670927) (xy 122.299732 -227.722222) (xy 122.283684 -227.771615) (xy 122.260106 -227.817889)
			(xy 122.22958 -227.859905) (xy 122.192857 -227.896628) (xy 122.150841 -227.927154) (xy 122.104567 -227.950732)
			(xy 122.055174 -227.96678) (xy 122.003879 -227.974905) (xy 121.951945 -227.974905) (xy 121.90065 -227.96678)
			(xy 121.851257 -227.950732) (xy 121.804983 -227.927154) (xy 121.762967 -227.896628) (xy 121.726244 -227.859905)
			(xy 121.695718 -227.817889) (xy 121.67214 -227.771615) (xy 121.656092 -227.722222) (xy 121.647967 -227.670927)
			(xy 121.368311 -227.670927) (xy 121.360186 -227.722222) (xy 121.344138 -227.771615) (xy 121.32056 -227.817889)
			(xy 121.290034 -227.859905) (xy 121.253311 -227.896628) (xy 121.211295 -227.927154) (xy 121.165021 -227.950732)
			(xy 121.115628 -227.96678) (xy 121.064333 -227.974905) (xy 121.012399 -227.974905) (xy 120.961104 -227.96678)
			(xy 120.911711 -227.950732) (xy 120.865437 -227.927154) (xy 120.823421 -227.896628) (xy 120.786698 -227.859905)
			(xy 120.756172 -227.817889) (xy 120.732594 -227.771615) (xy 120.716546 -227.722222) (xy 120.708421 -227.670927)
			(xy 120.428511 -227.670927) (xy 120.420386 -227.722222) (xy 120.404338 -227.771615) (xy 120.38076 -227.817889)
			(xy 120.350234 -227.859905) (xy 120.313511 -227.896628) (xy 120.271495 -227.927154) (xy 120.225221 -227.950732)
			(xy 120.175828 -227.96678) (xy 120.124533 -227.974905) (xy 120.072599 -227.974905) (xy 120.021304 -227.96678)
			(xy 119.971911 -227.950732) (xy 119.925637 -227.927154) (xy 119.883621 -227.896628) (xy 119.846898 -227.859905)
			(xy 119.816372 -227.817889) (xy 119.792794 -227.771615) (xy 119.776746 -227.722222) (xy 119.768621 -227.670927)
			(xy 119.488711 -227.670927) (xy 119.480586 -227.722222) (xy 119.464538 -227.771615) (xy 119.44096 -227.817889)
			(xy 119.410434 -227.859905) (xy 119.373711 -227.896628) (xy 119.331695 -227.927154) (xy 119.285421 -227.950732)
			(xy 119.236028 -227.96678) (xy 119.184733 -227.974905) (xy 119.132799 -227.974905) (xy 119.081504 -227.96678)
			(xy 119.032111 -227.950732) (xy 118.985837 -227.927154) (xy 118.943821 -227.896628) (xy 118.907098 -227.859905)
			(xy 118.876572 -227.817889) (xy 118.852994 -227.771615) (xy 118.836946 -227.722222) (xy 118.828821 -227.670927)
			(xy 118.548911 -227.670927) (xy 118.540786 -227.722222) (xy 118.524738 -227.771615) (xy 118.50116 -227.817889)
			(xy 118.470634 -227.859905) (xy 118.433911 -227.896628) (xy 118.391895 -227.927154) (xy 118.345621 -227.950732)
			(xy 118.296228 -227.96678) (xy 118.244933 -227.974905) (xy 118.192999 -227.974905) (xy 118.141704 -227.96678)
			(xy 118.092311 -227.950732) (xy 118.046037 -227.927154) (xy 118.004021 -227.896628) (xy 117.967298 -227.859905)
			(xy 117.936772 -227.817889) (xy 117.913194 -227.771615) (xy 117.897146 -227.722222) (xy 117.889021 -227.670927)
			(xy 117.609111 -227.670927) (xy 117.600986 -227.722222) (xy 117.584938 -227.771615) (xy 117.56136 -227.817889)
			(xy 117.530834 -227.859905) (xy 117.494111 -227.896628) (xy 117.452095 -227.927154) (xy 117.405821 -227.950732)
			(xy 117.356428 -227.96678) (xy 117.305133 -227.974905) (xy 117.253199 -227.974905) (xy 117.201904 -227.96678)
			(xy 117.152511 -227.950732) (xy 117.106237 -227.927154) (xy 117.064221 -227.896628) (xy 117.027498 -227.859905)
			(xy 116.996972 -227.817889) (xy 116.973394 -227.771615) (xy 116.957346 -227.722222) (xy 116.949221 -227.670927)
			(xy 116.669311 -227.670927) (xy 116.661186 -227.722222) (xy 116.645138 -227.771615) (xy 116.62156 -227.817889)
			(xy 116.591034 -227.859905) (xy 116.554311 -227.896628) (xy 116.512295 -227.927154) (xy 116.466021 -227.950732)
			(xy 116.416628 -227.96678) (xy 116.365333 -227.974905) (xy 116.313399 -227.974905) (xy 116.262104 -227.96678)
			(xy 116.212711 -227.950732) (xy 116.166437 -227.927154) (xy 116.124421 -227.896628) (xy 116.087698 -227.859905)
			(xy 116.057172 -227.817889) (xy 116.033594 -227.771615) (xy 116.017546 -227.722222) (xy 116.009421 -227.670927)
			(xy 115.729511 -227.670927) (xy 115.721386 -227.722222) (xy 115.705338 -227.771615) (xy 115.68176 -227.817889)
			(xy 115.651234 -227.859905) (xy 115.614511 -227.896628) (xy 115.572495 -227.927154) (xy 115.526221 -227.950732)
			(xy 115.476828 -227.96678) (xy 115.425533 -227.974905) (xy 115.373599 -227.974905) (xy 115.322304 -227.96678)
			(xy 115.272911 -227.950732) (xy 115.226637 -227.927154) (xy 115.184621 -227.896628) (xy 115.147898 -227.859905)
			(xy 115.117372 -227.817889) (xy 115.093794 -227.771615) (xy 115.077746 -227.722222) (xy 115.069621 -227.670927)
			(xy 114.789965 -227.670927) (xy 114.78184 -227.722222) (xy 114.765792 -227.771615) (xy 114.742214 -227.817889)
			(xy 114.711688 -227.859905) (xy 114.674965 -227.896628) (xy 114.632949 -227.927154) (xy 114.586675 -227.950732)
			(xy 114.537282 -227.96678) (xy 114.485987 -227.974905) (xy 114.434053 -227.974905) (xy 114.382758 -227.96678)
			(xy 114.333365 -227.950732) (xy 114.287091 -227.927154) (xy 114.245075 -227.896628) (xy 114.208352 -227.859905)
			(xy 114.177826 -227.817889) (xy 114.154248 -227.771615) (xy 114.1382 -227.722222) (xy 114.130075 -227.670927)
			(xy 113.849911 -227.670927) (xy 113.841786 -227.722222) (xy 113.825738 -227.771615) (xy 113.80216 -227.817889)
			(xy 113.771634 -227.859905) (xy 113.734911 -227.896628) (xy 113.692895 -227.927154) (xy 113.646621 -227.950732)
			(xy 113.597228 -227.96678) (xy 113.545933 -227.974905) (xy 113.493999 -227.974905) (xy 113.442704 -227.96678)
			(xy 113.393311 -227.950732) (xy 113.347037 -227.927154) (xy 113.305021 -227.896628) (xy 113.268298 -227.859905)
			(xy 113.237772 -227.817889) (xy 113.214194 -227.771615) (xy 113.198146 -227.722222) (xy 113.190021 -227.670927)
			(xy 112.910111 -227.670927) (xy 112.901986 -227.722222) (xy 112.885938 -227.771615) (xy 112.86236 -227.817889)
			(xy 112.831834 -227.859905) (xy 112.795111 -227.896628) (xy 112.753095 -227.927154) (xy 112.706821 -227.950732)
			(xy 112.657428 -227.96678) (xy 112.606133 -227.974905) (xy 112.554199 -227.974905) (xy 112.502904 -227.96678)
			(xy 112.453511 -227.950732) (xy 112.407237 -227.927154) (xy 112.365221 -227.896628) (xy 112.328498 -227.859905)
			(xy 112.297972 -227.817889) (xy 112.274394 -227.771615) (xy 112.258346 -227.722222) (xy 112.250221 -227.670927)
			(xy 111.970311 -227.670927) (xy 111.962186 -227.722222) (xy 111.946138 -227.771615) (xy 111.92256 -227.817889)
			(xy 111.892034 -227.859905) (xy 111.855311 -227.896628) (xy 111.813295 -227.927154) (xy 111.767021 -227.950732)
			(xy 111.717628 -227.96678) (xy 111.666333 -227.974905) (xy 111.614399 -227.974905) (xy 111.563104 -227.96678)
			(xy 111.513711 -227.950732) (xy 111.467437 -227.927154) (xy 111.425421 -227.896628) (xy 111.388698 -227.859905)
			(xy 111.358172 -227.817889) (xy 111.334594 -227.771615) (xy 111.318546 -227.722222) (xy 111.310421 -227.670927)
			(xy 111.030511 -227.670927) (xy 111.022386 -227.722222) (xy 111.006338 -227.771615) (xy 110.98276 -227.817889)
			(xy 110.952234 -227.859905) (xy 110.915511 -227.896628) (xy 110.873495 -227.927154) (xy 110.827221 -227.950732)
			(xy 110.777828 -227.96678) (xy 110.726533 -227.974905) (xy 110.674599 -227.974905) (xy 110.623304 -227.96678)
			(xy 110.573911 -227.950732) (xy 110.527637 -227.927154) (xy 110.485621 -227.896628) (xy 110.448898 -227.859905)
			(xy 110.418372 -227.817889) (xy 110.394794 -227.771615) (xy 110.378746 -227.722222) (xy 110.370621 -227.670927)
			(xy 110.090296 -227.670927) (xy 110.08507 -227.710057) (xy 110.073661 -227.752194) (xy 110.065566 -227.772468)
			(xy 110.052612 -227.803964) (xy 110.525306 -228.276658) (xy 110.525306 -228.309424) (xy 110.530132 -228.319584)
			(xy 110.539851 -228.341531) (xy 110.553554 -228.387531) (xy 110.560455 -228.435031) (xy 110.560866 -228.45903)
			(xy 110.560457 -228.48303) (xy 110.560171 -228.484997) (xy 110.840521 -228.484997) (xy 110.840521 -228.433063)
			(xy 110.848646 -228.381768) (xy 110.864694 -228.332375) (xy 110.888272 -228.286101) (xy 110.918798 -228.244085)
			(xy 110.955521 -228.207362) (xy 110.997537 -228.176836) (xy 111.043811 -228.153258) (xy 111.093204 -228.13721)
			(xy 111.144499 -228.129085) (xy 111.196433 -228.129085) (xy 111.247728 -228.13721) (xy 111.297121 -228.153258)
			(xy 111.343395 -228.176836) (xy 111.385411 -228.207362) (xy 111.422134 -228.244085) (xy 111.45266 -228.286101)
			(xy 111.476238 -228.332375) (xy 111.492286 -228.381768) (xy 111.500411 -228.433063) (xy 111.50092 -228.45903)
			(xy 111.500411 -228.484997) (xy 111.780067 -228.484997) (xy 111.780067 -228.433063) (xy 111.788192 -228.381768)
			(xy 111.80424 -228.332375) (xy 111.827818 -228.286101) (xy 111.858344 -228.244085) (xy 111.895067 -228.207362)
			(xy 111.937083 -228.176836) (xy 111.983357 -228.153258) (xy 112.03275 -228.13721) (xy 112.084045 -228.129085)
			(xy 112.135979 -228.129085) (xy 112.187274 -228.13721) (xy 112.236667 -228.153258) (xy 112.282941 -228.176836)
			(xy 112.324957 -228.207362) (xy 112.36168 -228.244085) (xy 112.392206 -228.286101) (xy 112.415784 -228.332375)
			(xy 112.431832 -228.381768) (xy 112.439957 -228.433063) (xy 112.440466 -228.45903) (xy 112.439957 -228.484997)
			(xy 112.719867 -228.484997) (xy 112.719867 -228.433063) (xy 112.727992 -228.381768) (xy 112.74404 -228.332375)
			(xy 112.767618 -228.286101) (xy 112.798144 -228.244085) (xy 112.834867 -228.207362) (xy 112.876883 -228.176836)
			(xy 112.923157 -228.153258) (xy 112.97255 -228.13721) (xy 113.023845 -228.129085) (xy 113.075779 -228.129085)
			(xy 113.127074 -228.13721) (xy 113.176467 -228.153258) (xy 113.222741 -228.176836) (xy 113.264757 -228.207362)
			(xy 113.30148 -228.244085) (xy 113.332006 -228.286101) (xy 113.355584 -228.332375) (xy 113.371632 -228.381768)
			(xy 113.379757 -228.433063) (xy 113.380266 -228.45903) (xy 113.379757 -228.484997) (xy 113.659667 -228.484997)
			(xy 113.659667 -228.433063) (xy 113.667792 -228.381768) (xy 113.68384 -228.332375) (xy 113.707418 -228.286101)
			(xy 113.737944 -228.244085) (xy 113.774667 -228.207362) (xy 113.816683 -228.176836) (xy 113.862957 -228.153258)
			(xy 113.91235 -228.13721) (xy 113.963645 -228.129085) (xy 114.015579 -228.129085) (xy 114.066874 -228.13721)
			(xy 114.116267 -228.153258) (xy 114.162541 -228.176836) (xy 114.204557 -228.207362) (xy 114.24128 -228.244085)
			(xy 114.271806 -228.286101) (xy 114.295384 -228.332375) (xy 114.311432 -228.381768) (xy 114.319557 -228.433063)
			(xy 114.320066 -228.45903) (xy 114.319557 -228.484997) (xy 115.539267 -228.484997) (xy 115.539267 -228.433063)
			(xy 115.547392 -228.381768) (xy 115.56344 -228.332375) (xy 115.587018 -228.286101) (xy 115.617544 -228.244085)
			(xy 115.654267 -228.207362) (xy 115.696283 -228.176836) (xy 115.742557 -228.153258) (xy 115.79195 -228.13721)
			(xy 115.843245 -228.129085) (xy 115.895179 -228.129085) (xy 115.946474 -228.13721) (xy 115.995867 -228.153258)
			(xy 116.042141 -228.176836) (xy 116.084157 -228.207362) (xy 116.12088 -228.244085) (xy 116.151406 -228.286101)
			(xy 116.174984 -228.332375) (xy 116.191032 -228.381768) (xy 116.199157 -228.433063) (xy 116.199666 -228.45903)
			(xy 116.199157 -228.484997) (xy 117.418867 -228.484997) (xy 117.418867 -228.433063) (xy 117.426992 -228.381768)
			(xy 117.44304 -228.332375) (xy 117.466618 -228.286101) (xy 117.497144 -228.244085) (xy 117.533867 -228.207362)
			(xy 117.575883 -228.176836) (xy 117.622157 -228.153258) (xy 117.67155 -228.13721) (xy 117.722845 -228.129085)
			(xy 117.774779 -228.129085) (xy 117.826074 -228.13721) (xy 117.875467 -228.153258) (xy 117.921741 -228.176836)
			(xy 117.963757 -228.207362) (xy 118.00048 -228.244085) (xy 118.031006 -228.286101) (xy 118.054584 -228.332375)
			(xy 118.070632 -228.381768) (xy 118.078757 -228.433063) (xy 118.079266 -228.45903) (xy 118.078757 -228.484997)
			(xy 119.298467 -228.484997) (xy 119.298467 -228.433063) (xy 119.306592 -228.381768) (xy 119.32264 -228.332375)
			(xy 119.346218 -228.286101) (xy 119.376744 -228.244085) (xy 119.413467 -228.207362) (xy 119.455483 -228.176836)
			(xy 119.501757 -228.153258) (xy 119.55115 -228.13721) (xy 119.602445 -228.129085) (xy 119.654379 -228.129085)
			(xy 119.705674 -228.13721) (xy 119.755067 -228.153258) (xy 119.801341 -228.176836) (xy 119.843357 -228.207362)
			(xy 119.88008 -228.244085) (xy 119.910606 -228.286101) (xy 119.934184 -228.332375) (xy 119.950232 -228.381768)
			(xy 119.958357 -228.433063) (xy 119.958866 -228.45903) (xy 119.958357 -228.484997) (xy 120.238267 -228.484997)
			(xy 120.238267 -228.433063) (xy 120.246392 -228.381768) (xy 120.26244 -228.332375) (xy 120.286018 -228.286101)
			(xy 120.316544 -228.244085) (xy 120.353267 -228.207362) (xy 120.395283 -228.176836) (xy 120.441557 -228.153258)
			(xy 120.49095 -228.13721) (xy 120.542245 -228.129085) (xy 120.594179 -228.129085) (xy 120.645474 -228.13721)
			(xy 120.694867 -228.153258) (xy 120.741141 -228.176836) (xy 120.783157 -228.207362) (xy 120.81988 -228.244085)
			(xy 120.850406 -228.286101) (xy 120.873984 -228.332375) (xy 120.890032 -228.381768) (xy 120.898157 -228.433063)
			(xy 120.898666 -228.45903) (xy 120.898157 -228.484997) (xy 121.178067 -228.484997) (xy 121.178067 -228.433063)
			(xy 121.186192 -228.381768) (xy 121.20224 -228.332375) (xy 121.225818 -228.286101) (xy 121.256344 -228.244085)
			(xy 121.293067 -228.207362) (xy 121.335083 -228.176836) (xy 121.381357 -228.153258) (xy 121.43075 -228.13721)
			(xy 121.482045 -228.129085) (xy 121.533979 -228.129085) (xy 121.585274 -228.13721) (xy 121.634667 -228.153258)
			(xy 121.680941 -228.176836) (xy 121.722957 -228.207362) (xy 121.75968 -228.244085) (xy 121.790206 -228.286101)
			(xy 121.813784 -228.332375) (xy 121.829832 -228.381768) (xy 121.837957 -228.433063) (xy 121.838466 -228.45903)
			(xy 121.837957 -228.484997) (xy 122.117867 -228.484997) (xy 122.117867 -228.433063) (xy 122.125992 -228.381768)
			(xy 122.14204 -228.332375) (xy 122.165618 -228.286101) (xy 122.196144 -228.244085) (xy 122.232867 -228.207362)
			(xy 122.274883 -228.176836) (xy 122.321157 -228.153258) (xy 122.37055 -228.13721) (xy 122.421845 -228.129085)
			(xy 122.473779 -228.129085) (xy 122.525074 -228.13721) (xy 122.574467 -228.153258) (xy 122.620741 -228.176836)
			(xy 122.662757 -228.207362) (xy 122.69948 -228.244085) (xy 122.730006 -228.286101) (xy 122.753584 -228.332375)
			(xy 122.769632 -228.381768) (xy 122.777757 -228.433063) (xy 122.778266 -228.45903) (xy 122.777757 -228.484997)
			(xy 122.769632 -228.536292) (xy 122.753584 -228.585685) (xy 122.730006 -228.631959) (xy 122.69948 -228.673975)
			(xy 122.662757 -228.710698) (xy 122.620741 -228.741224) (xy 122.574467 -228.764802) (xy 122.525074 -228.78085)
			(xy 122.473779 -228.788975) (xy 122.421845 -228.788975) (xy 122.37055 -228.78085) (xy 122.321157 -228.764802)
			(xy 122.274883 -228.741224) (xy 122.232867 -228.710698) (xy 122.196144 -228.673975) (xy 122.165618 -228.631959)
			(xy 122.14204 -228.585685) (xy 122.125992 -228.536292) (xy 122.117867 -228.484997) (xy 121.837957 -228.484997)
			(xy 121.829832 -228.536292) (xy 121.813784 -228.585685) (xy 121.790206 -228.631959) (xy 121.75968 -228.673975)
			(xy 121.722957 -228.710698) (xy 121.680941 -228.741224) (xy 121.634667 -228.764802) (xy 121.585274 -228.78085)
			(xy 121.533979 -228.788975) (xy 121.482045 -228.788975) (xy 121.43075 -228.78085) (xy 121.381357 -228.764802)
			(xy 121.335083 -228.741224) (xy 121.293067 -228.710698) (xy 121.256344 -228.673975) (xy 121.225818 -228.631959)
			(xy 121.20224 -228.585685) (xy 121.186192 -228.536292) (xy 121.178067 -228.484997) (xy 120.898157 -228.484997)
			(xy 120.890032 -228.536292) (xy 120.873984 -228.585685) (xy 120.850406 -228.631959) (xy 120.81988 -228.673975)
			(xy 120.783157 -228.710698) (xy 120.741141 -228.741224) (xy 120.694867 -228.764802) (xy 120.645474 -228.78085)
			(xy 120.594179 -228.788975) (xy 120.542245 -228.788975) (xy 120.49095 -228.78085) (xy 120.441557 -228.764802)
			(xy 120.395283 -228.741224) (xy 120.353267 -228.710698) (xy 120.316544 -228.673975) (xy 120.286018 -228.631959)
			(xy 120.26244 -228.585685) (xy 120.246392 -228.536292) (xy 120.238267 -228.484997) (xy 119.958357 -228.484997)
			(xy 119.950232 -228.536292) (xy 119.934184 -228.585685) (xy 119.910606 -228.631959) (xy 119.88008 -228.673975)
			(xy 119.843357 -228.710698) (xy 119.801341 -228.741224) (xy 119.755067 -228.764802) (xy 119.705674 -228.78085)
			(xy 119.654379 -228.788975) (xy 119.602445 -228.788975) (xy 119.55115 -228.78085) (xy 119.501757 -228.764802)
			(xy 119.455483 -228.741224) (xy 119.413467 -228.710698) (xy 119.376744 -228.673975) (xy 119.346218 -228.631959)
			(xy 119.32264 -228.585685) (xy 119.306592 -228.536292) (xy 119.298467 -228.484997) (xy 118.078757 -228.484997)
			(xy 118.070632 -228.536292) (xy 118.054584 -228.585685) (xy 118.031006 -228.631959) (xy 118.00048 -228.673975)
			(xy 117.963757 -228.710698) (xy 117.921741 -228.741224) (xy 117.875467 -228.764802) (xy 117.826074 -228.78085)
			(xy 117.774779 -228.788975) (xy 117.722845 -228.788975) (xy 117.67155 -228.78085) (xy 117.622157 -228.764802)
			(xy 117.575883 -228.741224) (xy 117.533867 -228.710698) (xy 117.497144 -228.673975) (xy 117.466618 -228.631959)
			(xy 117.44304 -228.585685) (xy 117.426992 -228.536292) (xy 117.418867 -228.484997) (xy 116.199157 -228.484997)
			(xy 116.191032 -228.536292) (xy 116.174984 -228.585685) (xy 116.151406 -228.631959) (xy 116.12088 -228.673975)
			(xy 116.084157 -228.710698) (xy 116.042141 -228.741224) (xy 115.995867 -228.764802) (xy 115.946474 -228.78085)
			(xy 115.895179 -228.788975) (xy 115.843245 -228.788975) (xy 115.79195 -228.78085) (xy 115.742557 -228.764802)
			(xy 115.696283 -228.741224) (xy 115.654267 -228.710698) (xy 115.617544 -228.673975) (xy 115.587018 -228.631959)
			(xy 115.56344 -228.585685) (xy 115.547392 -228.536292) (xy 115.539267 -228.484997) (xy 114.319557 -228.484997)
			(xy 114.311432 -228.536292) (xy 114.295384 -228.585685) (xy 114.271806 -228.631959) (xy 114.24128 -228.673975)
			(xy 114.204557 -228.710698) (xy 114.162541 -228.741224) (xy 114.116267 -228.764802) (xy 114.066874 -228.78085)
			(xy 114.015579 -228.788975) (xy 113.963645 -228.788975) (xy 113.91235 -228.78085) (xy 113.862957 -228.764802)
			(xy 113.816683 -228.741224) (xy 113.774667 -228.710698) (xy 113.737944 -228.673975) (xy 113.707418 -228.631959)
			(xy 113.68384 -228.585685) (xy 113.667792 -228.536292) (xy 113.659667 -228.484997) (xy 113.379757 -228.484997)
			(xy 113.371632 -228.536292) (xy 113.355584 -228.585685) (xy 113.332006 -228.631959) (xy 113.30148 -228.673975)
			(xy 113.264757 -228.710698) (xy 113.222741 -228.741224) (xy 113.176467 -228.764802) (xy 113.127074 -228.78085)
			(xy 113.075779 -228.788975) (xy 113.023845 -228.788975) (xy 112.97255 -228.78085) (xy 112.923157 -228.764802)
			(xy 112.876883 -228.741224) (xy 112.834867 -228.710698) (xy 112.798144 -228.673975) (xy 112.767618 -228.631959)
			(xy 112.74404 -228.585685) (xy 112.727992 -228.536292) (xy 112.719867 -228.484997) (xy 112.439957 -228.484997)
			(xy 112.431832 -228.536292) (xy 112.415784 -228.585685) (xy 112.392206 -228.631959) (xy 112.36168 -228.673975)
			(xy 112.324957 -228.710698) (xy 112.282941 -228.741224) (xy 112.236667 -228.764802) (xy 112.187274 -228.78085)
			(xy 112.135979 -228.788975) (xy 112.084045 -228.788975) (xy 112.03275 -228.78085) (xy 111.983357 -228.764802)
			(xy 111.937083 -228.741224) (xy 111.895067 -228.710698) (xy 111.858344 -228.673975) (xy 111.827818 -228.631959)
			(xy 111.80424 -228.585685) (xy 111.788192 -228.536292) (xy 111.780067 -228.484997) (xy 111.500411 -228.484997)
			(xy 111.492286 -228.536292) (xy 111.476238 -228.585685) (xy 111.45266 -228.631959) (xy 111.422134 -228.673975)
			(xy 111.385411 -228.710698) (xy 111.343395 -228.741224) (xy 111.297121 -228.764802) (xy 111.247728 -228.78085)
			(xy 111.196433 -228.788975) (xy 111.144499 -228.788975) (xy 111.093204 -228.78085) (xy 111.043811 -228.764802)
			(xy 110.997537 -228.741224) (xy 110.955521 -228.710698) (xy 110.918798 -228.673975) (xy 110.888272 -228.631959)
			(xy 110.864694 -228.585685) (xy 110.848646 -228.536292) (xy 110.840521 -228.484997) (xy 110.560171 -228.484997)
			(xy 110.553556 -228.53053) (xy 110.53986 -228.576533) (xy 110.530132 -228.598476) (xy 110.525306 -228.608636)
			(xy 110.525306 -228.847142) (xy 110.5258 -228.861919) (xy 110.53425 -228.890238) (xy 110.55046 -228.914949)
			(xy 110.57307 -228.93398) (xy 110.600184 -228.945736) (xy 110.62953 -228.949231) (xy 110.644178 -228.947218)
			(xy 110.658164 -228.944945) (xy 110.686397 -228.94253) (xy 110.700566 -228.942392) (xy 110.726533 -228.942872)
			(xy 110.77783 -228.950992) (xy 110.827224 -228.967036) (xy 110.8735 -228.990611) (xy 110.915518 -229.021135)
			(xy 110.952243 -229.057856) (xy 110.982771 -229.099871) (xy 111.006351 -229.146145) (xy 111.0224 -229.195537)
			(xy 111.030525 -229.246833) (xy 111.030525 -229.298767) (xy 111.030518 -229.298813) (xy 111.310167 -229.298813)
			(xy 111.310167 -229.246879) (xy 111.318292 -229.195584) (xy 111.33434 -229.146191) (xy 111.357918 -229.099917)
			(xy 111.388444 -229.057901) (xy 111.425167 -229.021178) (xy 111.467183 -228.990652) (xy 111.513457 -228.967074)
			(xy 111.56285 -228.951026) (xy 111.614145 -228.942901) (xy 111.666079 -228.942901) (xy 111.717374 -228.951026)
			(xy 111.766767 -228.967074) (xy 111.813041 -228.990652) (xy 111.855057 -229.021178) (xy 111.89178 -229.057901)
			(xy 111.922306 -229.099917) (xy 111.945884 -229.146191) (xy 111.961932 -229.195584) (xy 111.970057 -229.246879)
			(xy 111.970566 -229.272846) (xy 111.970057 -229.298813) (xy 112.250221 -229.298813) (xy 112.250221 -229.246879)
			(xy 112.258346 -229.195584) (xy 112.274394 -229.146191) (xy 112.297972 -229.099917) (xy 112.328498 -229.057901)
			(xy 112.365221 -229.021178) (xy 112.407237 -228.990652) (xy 112.453511 -228.967074) (xy 112.502904 -228.951026)
			(xy 112.554199 -228.942901) (xy 112.606133 -228.942901) (xy 112.657428 -228.951026) (xy 112.706821 -228.967074)
			(xy 112.753095 -228.990652) (xy 112.795111 -229.021178) (xy 112.831834 -229.057901) (xy 112.86236 -229.099917)
			(xy 112.885938 -229.146191) (xy 112.901986 -229.195584) (xy 112.910111 -229.246879) (xy 112.91062 -229.272846)
			(xy 112.910111 -229.298813) (xy 113.190021 -229.298813) (xy 113.190021 -229.246879) (xy 113.198146 -229.195584)
			(xy 113.214194 -229.146191) (xy 113.237772 -229.099917) (xy 113.268298 -229.057901) (xy 113.305021 -229.021178)
			(xy 113.347037 -228.990652) (xy 113.393311 -228.967074) (xy 113.442704 -228.951026) (xy 113.493999 -228.942901)
			(xy 113.545933 -228.942901) (xy 113.597228 -228.951026) (xy 113.646621 -228.967074) (xy 113.692895 -228.990652)
			(xy 113.734911 -229.021178) (xy 113.771634 -229.057901) (xy 113.80216 -229.099917) (xy 113.825738 -229.146191)
			(xy 113.841786 -229.195584) (xy 113.849911 -229.246879) (xy 113.85042 -229.272846) (xy 113.849911 -229.298813)
			(xy 114.129821 -229.298813) (xy 114.129821 -229.246879) (xy 114.137946 -229.195584) (xy 114.153994 -229.146191)
			(xy 114.177572 -229.099917) (xy 114.208098 -229.057901) (xy 114.244821 -229.021178) (xy 114.286837 -228.990652)
			(xy 114.333111 -228.967074) (xy 114.382504 -228.951026) (xy 114.433799 -228.942901) (xy 114.485733 -228.942901)
			(xy 114.537028 -228.951026) (xy 114.586421 -228.967074) (xy 114.632695 -228.990652) (xy 114.674711 -229.021178)
			(xy 114.711434 -229.057901) (xy 114.74196 -229.099917) (xy 114.765538 -229.146191) (xy 114.781586 -229.195584)
			(xy 114.789711 -229.246879) (xy 114.79022 -229.272846) (xy 114.789711 -229.298813) (xy 115.069621 -229.298813)
			(xy 115.069621 -229.246879) (xy 115.077746 -229.195584) (xy 115.093794 -229.146191) (xy 115.117372 -229.099917)
			(xy 115.147898 -229.057901) (xy 115.184621 -229.021178) (xy 115.226637 -228.990652) (xy 115.272911 -228.967074)
			(xy 115.322304 -228.951026) (xy 115.373599 -228.942901) (xy 115.425533 -228.942901) (xy 115.476828 -228.951026)
			(xy 115.526221 -228.967074) (xy 115.572495 -228.990652) (xy 115.614511 -229.021178) (xy 115.651234 -229.057901)
			(xy 115.68176 -229.099917) (xy 115.705338 -229.146191) (xy 115.721386 -229.195584) (xy 115.729511 -229.246879)
			(xy 115.73002 -229.272846) (xy 115.729511 -229.298813) (xy 116.009421 -229.298813) (xy 116.009421 -229.246879)
			(xy 116.017546 -229.195584) (xy 116.033594 -229.146191) (xy 116.057172 -229.099917) (xy 116.087698 -229.057901)
			(xy 116.124421 -229.021178) (xy 116.166437 -228.990652) (xy 116.212711 -228.967074) (xy 116.262104 -228.951026)
			(xy 116.313399 -228.942901) (xy 116.365333 -228.942901) (xy 116.416628 -228.951026) (xy 116.466021 -228.967074)
			(xy 116.512295 -228.990652) (xy 116.554311 -229.021178) (xy 116.591034 -229.057901) (xy 116.62156 -229.099917)
			(xy 116.645138 -229.146191) (xy 116.661186 -229.195584) (xy 116.669311 -229.246879) (xy 116.66982 -229.272846)
			(xy 116.669311 -229.298813) (xy 116.949221 -229.298813) (xy 116.949221 -229.246879) (xy 116.957346 -229.195584)
			(xy 116.973394 -229.146191) (xy 116.996972 -229.099917) (xy 117.027498 -229.057901) (xy 117.064221 -229.021178)
			(xy 117.106237 -228.990652) (xy 117.152511 -228.967074) (xy 117.201904 -228.951026) (xy 117.253199 -228.942901)
			(xy 117.305133 -228.942901) (xy 117.356428 -228.951026) (xy 117.405821 -228.967074) (xy 117.452095 -228.990652)
			(xy 117.494111 -229.021178) (xy 117.530834 -229.057901) (xy 117.56136 -229.099917) (xy 117.584938 -229.146191)
			(xy 117.600986 -229.195584) (xy 117.609111 -229.246879) (xy 117.60962 -229.272846) (xy 117.609111 -229.298813)
			(xy 117.889021 -229.298813) (xy 117.889021 -229.246879) (xy 117.897146 -229.195584) (xy 117.913194 -229.146191)
			(xy 117.936772 -229.099917) (xy 117.967298 -229.057901) (xy 118.004021 -229.021178) (xy 118.046037 -228.990652)
			(xy 118.092311 -228.967074) (xy 118.141704 -228.951026) (xy 118.192999 -228.942901) (xy 118.244933 -228.942901)
			(xy 118.296228 -228.951026) (xy 118.345621 -228.967074) (xy 118.391895 -228.990652) (xy 118.433911 -229.021178)
			(xy 118.470634 -229.057901) (xy 118.50116 -229.099917) (xy 118.524738 -229.146191) (xy 118.540786 -229.195584)
			(xy 118.548911 -229.246879) (xy 118.54942 -229.272846) (xy 118.548911 -229.298813) (xy 118.828821 -229.298813)
			(xy 118.828821 -229.246879) (xy 118.836946 -229.195584) (xy 118.852994 -229.146191) (xy 118.876572 -229.099917)
			(xy 118.907098 -229.057901) (xy 118.943821 -229.021178) (xy 118.985837 -228.990652) (xy 119.032111 -228.967074)
			(xy 119.081504 -228.951026) (xy 119.132799 -228.942901) (xy 119.184733 -228.942901) (xy 119.236028 -228.951026)
			(xy 119.285421 -228.967074) (xy 119.331695 -228.990652) (xy 119.373711 -229.021178) (xy 119.410434 -229.057901)
			(xy 119.44096 -229.099917) (xy 119.464538 -229.146191) (xy 119.480586 -229.195584) (xy 119.488711 -229.246879)
			(xy 119.48922 -229.272846) (xy 119.488711 -229.298813) (xy 119.768621 -229.298813) (xy 119.768621 -229.246879)
			(xy 119.776746 -229.195584) (xy 119.792794 -229.146191) (xy 119.816372 -229.099917) (xy 119.846898 -229.057901)
			(xy 119.883621 -229.021178) (xy 119.925637 -228.990652) (xy 119.971911 -228.967074) (xy 120.021304 -228.951026)
			(xy 120.072599 -228.942901) (xy 120.124533 -228.942901) (xy 120.175828 -228.951026) (xy 120.225221 -228.967074)
			(xy 120.271495 -228.990652) (xy 120.313511 -229.021178) (xy 120.350234 -229.057901) (xy 120.38076 -229.099917)
			(xy 120.404338 -229.146191) (xy 120.420386 -229.195584) (xy 120.428511 -229.246879) (xy 120.42902 -229.272846)
			(xy 120.428511 -229.298813) (xy 120.708421 -229.298813) (xy 120.708421 -229.246879) (xy 120.716546 -229.195584)
			(xy 120.732594 -229.146191) (xy 120.756172 -229.099917) (xy 120.786698 -229.057901) (xy 120.823421 -229.021178)
			(xy 120.865437 -228.990652) (xy 120.911711 -228.967074) (xy 120.961104 -228.951026) (xy 121.012399 -228.942901)
			(xy 121.064333 -228.942901) (xy 121.115628 -228.951026) (xy 121.165021 -228.967074) (xy 121.211295 -228.990652)
			(xy 121.253311 -229.021178) (xy 121.290034 -229.057901) (xy 121.32056 -229.099917) (xy 121.344138 -229.146191)
			(xy 121.360186 -229.195584) (xy 121.368311 -229.246879) (xy 121.36882 -229.272846) (xy 121.368311 -229.298813)
			(xy 121.648221 -229.298813) (xy 121.648221 -229.246879) (xy 121.656346 -229.195584) (xy 121.672394 -229.146191)
			(xy 121.695972 -229.099917) (xy 121.726498 -229.057901) (xy 121.763221 -229.021178) (xy 121.805237 -228.990652)
			(xy 121.851511 -228.967074) (xy 121.900904 -228.951026) (xy 121.952199 -228.942901) (xy 122.004133 -228.942901)
			(xy 122.055428 -228.951026) (xy 122.104821 -228.967074) (xy 122.151095 -228.990652) (xy 122.193111 -229.021178)
			(xy 122.229834 -229.057901) (xy 122.26036 -229.099917) (xy 122.283938 -229.146191) (xy 122.299986 -229.195584)
			(xy 122.308111 -229.246879) (xy 122.30862 -229.272846) (xy 122.308111 -229.298813) (xy 122.299986 -229.350108)
			(xy 122.283938 -229.399501) (xy 122.26036 -229.445775) (xy 122.229834 -229.487791) (xy 122.193111 -229.524514)
			(xy 122.151095 -229.55504) (xy 122.104821 -229.578618) (xy 122.055428 -229.594666) (xy 122.004133 -229.602791)
			(xy 121.952199 -229.602791) (xy 121.900904 -229.594666) (xy 121.851511 -229.578618) (xy 121.805237 -229.55504)
			(xy 121.763221 -229.524514) (xy 121.726498 -229.487791) (xy 121.695972 -229.445775) (xy 121.672394 -229.399501)
			(xy 121.656346 -229.350108) (xy 121.648221 -229.298813) (xy 121.368311 -229.298813) (xy 121.360186 -229.350108)
			(xy 121.344138 -229.399501) (xy 121.32056 -229.445775) (xy 121.290034 -229.487791) (xy 121.253311 -229.524514)
			(xy 121.211295 -229.55504) (xy 121.165021 -229.578618) (xy 121.115628 -229.594666) (xy 121.064333 -229.602791)
			(xy 121.012399 -229.602791) (xy 120.961104 -229.594666) (xy 120.911711 -229.578618) (xy 120.865437 -229.55504)
			(xy 120.823421 -229.524514) (xy 120.786698 -229.487791) (xy 120.756172 -229.445775) (xy 120.732594 -229.399501)
			(xy 120.716546 -229.350108) (xy 120.708421 -229.298813) (xy 120.428511 -229.298813) (xy 120.420386 -229.350108)
			(xy 120.404338 -229.399501) (xy 120.38076 -229.445775) (xy 120.350234 -229.487791) (xy 120.313511 -229.524514)
			(xy 120.271495 -229.55504) (xy 120.225221 -229.578618) (xy 120.175828 -229.594666) (xy 120.124533 -229.602791)
			(xy 120.072599 -229.602791) (xy 120.021304 -229.594666) (xy 119.971911 -229.578618) (xy 119.925637 -229.55504)
			(xy 119.883621 -229.524514) (xy 119.846898 -229.487791) (xy 119.816372 -229.445775) (xy 119.792794 -229.399501)
			(xy 119.776746 -229.350108) (xy 119.768621 -229.298813) (xy 119.488711 -229.298813) (xy 119.480586 -229.350108)
			(xy 119.464538 -229.399501) (xy 119.44096 -229.445775) (xy 119.410434 -229.487791) (xy 119.373711 -229.524514)
			(xy 119.331695 -229.55504) (xy 119.285421 -229.578618) (xy 119.236028 -229.594666) (xy 119.184733 -229.602791)
			(xy 119.132799 -229.602791) (xy 119.081504 -229.594666) (xy 119.032111 -229.578618) (xy 118.985837 -229.55504)
			(xy 118.943821 -229.524514) (xy 118.907098 -229.487791) (xy 118.876572 -229.445775) (xy 118.852994 -229.399501)
			(xy 118.836946 -229.350108) (xy 118.828821 -229.298813) (xy 118.548911 -229.298813) (xy 118.540786 -229.350108)
			(xy 118.524738 -229.399501) (xy 118.50116 -229.445775) (xy 118.470634 -229.487791) (xy 118.433911 -229.524514)
			(xy 118.391895 -229.55504) (xy 118.345621 -229.578618) (xy 118.296228 -229.594666) (xy 118.244933 -229.602791)
			(xy 118.192999 -229.602791) (xy 118.141704 -229.594666) (xy 118.092311 -229.578618) (xy 118.046037 -229.55504)
			(xy 118.004021 -229.524514) (xy 117.967298 -229.487791) (xy 117.936772 -229.445775) (xy 117.913194 -229.399501)
			(xy 117.897146 -229.350108) (xy 117.889021 -229.298813) (xy 117.609111 -229.298813) (xy 117.600986 -229.350108)
			(xy 117.584938 -229.399501) (xy 117.56136 -229.445775) (xy 117.530834 -229.487791) (xy 117.494111 -229.524514)
			(xy 117.452095 -229.55504) (xy 117.405821 -229.578618) (xy 117.356428 -229.594666) (xy 117.305133 -229.602791)
			(xy 117.253199 -229.602791) (xy 117.201904 -229.594666) (xy 117.152511 -229.578618) (xy 117.106237 -229.55504)
			(xy 117.064221 -229.524514) (xy 117.027498 -229.487791) (xy 116.996972 -229.445775) (xy 116.973394 -229.399501)
			(xy 116.957346 -229.350108) (xy 116.949221 -229.298813) (xy 116.669311 -229.298813) (xy 116.661186 -229.350108)
			(xy 116.645138 -229.399501) (xy 116.62156 -229.445775) (xy 116.591034 -229.487791) (xy 116.554311 -229.524514)
			(xy 116.512295 -229.55504) (xy 116.466021 -229.578618) (xy 116.416628 -229.594666) (xy 116.365333 -229.602791)
			(xy 116.313399 -229.602791) (xy 116.262104 -229.594666) (xy 116.212711 -229.578618) (xy 116.166437 -229.55504)
			(xy 116.124421 -229.524514) (xy 116.087698 -229.487791) (xy 116.057172 -229.445775) (xy 116.033594 -229.399501)
			(xy 116.017546 -229.350108) (xy 116.009421 -229.298813) (xy 115.729511 -229.298813) (xy 115.721386 -229.350108)
			(xy 115.705338 -229.399501) (xy 115.68176 -229.445775) (xy 115.651234 -229.487791) (xy 115.614511 -229.524514)
			(xy 115.572495 -229.55504) (xy 115.526221 -229.578618) (xy 115.476828 -229.594666) (xy 115.425533 -229.602791)
			(xy 115.373599 -229.602791) (xy 115.322304 -229.594666) (xy 115.272911 -229.578618) (xy 115.226637 -229.55504)
			(xy 115.184621 -229.524514) (xy 115.147898 -229.487791) (xy 115.117372 -229.445775) (xy 115.093794 -229.399501)
			(xy 115.077746 -229.350108) (xy 115.069621 -229.298813) (xy 114.789711 -229.298813) (xy 114.781586 -229.350108)
			(xy 114.765538 -229.399501) (xy 114.74196 -229.445775) (xy 114.711434 -229.487791) (xy 114.674711 -229.524514)
			(xy 114.632695 -229.55504) (xy 114.586421 -229.578618) (xy 114.537028 -229.594666) (xy 114.485733 -229.602791)
			(xy 114.433799 -229.602791) (xy 114.382504 -229.594666) (xy 114.333111 -229.578618) (xy 114.286837 -229.55504)
			(xy 114.244821 -229.524514) (xy 114.208098 -229.487791) (xy 114.177572 -229.445775) (xy 114.153994 -229.399501)
			(xy 114.137946 -229.350108) (xy 114.129821 -229.298813) (xy 113.849911 -229.298813) (xy 113.841786 -229.350108)
			(xy 113.825738 -229.399501) (xy 113.80216 -229.445775) (xy 113.771634 -229.487791) (xy 113.734911 -229.524514)
			(xy 113.692895 -229.55504) (xy 113.646621 -229.578618) (xy 113.597228 -229.594666) (xy 113.545933 -229.602791)
			(xy 113.493999 -229.602791) (xy 113.442704 -229.594666) (xy 113.393311 -229.578618) (xy 113.347037 -229.55504)
			(xy 113.305021 -229.524514) (xy 113.268298 -229.487791) (xy 113.237772 -229.445775) (xy 113.214194 -229.399501)
			(xy 113.198146 -229.350108) (xy 113.190021 -229.298813) (xy 112.910111 -229.298813) (xy 112.901986 -229.350108)
			(xy 112.885938 -229.399501) (xy 112.86236 -229.445775) (xy 112.831834 -229.487791) (xy 112.795111 -229.524514)
			(xy 112.753095 -229.55504) (xy 112.706821 -229.578618) (xy 112.657428 -229.594666) (xy 112.606133 -229.602791)
			(xy 112.554199 -229.602791) (xy 112.502904 -229.594666) (xy 112.453511 -229.578618) (xy 112.407237 -229.55504)
			(xy 112.365221 -229.524514) (xy 112.328498 -229.487791) (xy 112.297972 -229.445775) (xy 112.274394 -229.399501)
			(xy 112.258346 -229.350108) (xy 112.250221 -229.298813) (xy 111.970057 -229.298813) (xy 111.961932 -229.350108)
			(xy 111.945884 -229.399501) (xy 111.922306 -229.445775) (xy 111.89178 -229.487791) (xy 111.855057 -229.524514)
			(xy 111.813041 -229.55504) (xy 111.766767 -229.578618) (xy 111.717374 -229.594666) (xy 111.666079 -229.602791)
			(xy 111.614145 -229.602791) (xy 111.56285 -229.594666) (xy 111.513457 -229.578618) (xy 111.467183 -229.55504)
			(xy 111.425167 -229.524514) (xy 111.388444 -229.487791) (xy 111.357918 -229.445775) (xy 111.33434 -229.399501)
			(xy 111.318292 -229.350108) (xy 111.310167 -229.298813) (xy 111.030518 -229.298813) (xy 111.0224 -229.350063)
			(xy 111.006351 -229.399455) (xy 110.982771 -229.445729) (xy 110.952243 -229.487744) (xy 110.915518 -229.524465)
			(xy 110.8735 -229.554989) (xy 110.827224 -229.578564) (xy 110.77783 -229.594608) (xy 110.726533 -229.602728)
			(xy 110.700566 -229.6033) (xy 110.686398 -229.603148) (xy 110.658166 -229.600731) (xy 110.644178 -229.598474)
			(xy 110.629534 -229.596454) (xy 110.600196 -229.599971) (xy 110.573091 -229.611737) (xy 110.550485 -229.630766)
			(xy 110.53427 -229.655467) (xy 110.525801 -229.683776) (xy 110.525306 -229.69855) (xy 110.525306 -229.937056)
			(xy 110.530132 -229.947216) (xy 110.539849 -229.969164) (xy 110.553548 -230.015164) (xy 110.560444 -230.062663)
			(xy 110.560866 -230.086662) (xy 110.560454 -230.110661) (xy 110.560168 -230.112629) (xy 110.840521 -230.112629)
			(xy 110.840521 -230.060695) (xy 110.848646 -230.0094) (xy 110.864694 -229.960007) (xy 110.888272 -229.913733)
			(xy 110.918798 -229.871717) (xy 110.955521 -229.834994) (xy 110.997537 -229.804468) (xy 111.043811 -229.78089)
			(xy 111.093204 -229.764842) (xy 111.144499 -229.756717) (xy 111.196433 -229.756717) (xy 111.247728 -229.764842)
			(xy 111.297121 -229.78089) (xy 111.343395 -229.804468) (xy 111.385411 -229.834994) (xy 111.422134 -229.871717)
			(xy 111.45266 -229.913733) (xy 111.476238 -229.960007) (xy 111.492286 -230.0094) (xy 111.500411 -230.060695)
			(xy 111.50092 -230.086662) (xy 111.500411 -230.112629) (xy 111.780321 -230.112629) (xy 111.780321 -230.060695)
			(xy 111.788446 -230.0094) (xy 111.804494 -229.960007) (xy 111.828072 -229.913733) (xy 111.858598 -229.871717)
			(xy 111.895321 -229.834994) (xy 111.937337 -229.804468) (xy 111.983611 -229.78089) (xy 112.033004 -229.764842)
			(xy 112.084299 -229.756717) (xy 112.136233 -229.756717) (xy 112.187528 -229.764842) (xy 112.236921 -229.78089)
			(xy 112.283195 -229.804468) (xy 112.325211 -229.834994) (xy 112.361934 -229.871717) (xy 112.39246 -229.913733)
			(xy 112.416038 -229.960007) (xy 112.432086 -230.0094) (xy 112.440211 -230.060695) (xy 112.44072 -230.086662)
			(xy 112.440211 -230.112629) (xy 112.720121 -230.112629) (xy 112.720121 -230.060695) (xy 112.728246 -230.0094)
			(xy 112.744294 -229.960007) (xy 112.767872 -229.913733) (xy 112.798398 -229.871717) (xy 112.835121 -229.834994)
			(xy 112.877137 -229.804468) (xy 112.923411 -229.78089) (xy 112.972804 -229.764842) (xy 113.024099 -229.756717)
			(xy 113.076033 -229.756717) (xy 113.127328 -229.764842) (xy 113.176721 -229.78089) (xy 113.222995 -229.804468)
			(xy 113.265011 -229.834994) (xy 113.301734 -229.871717) (xy 113.33226 -229.913733) (xy 113.355838 -229.960007)
			(xy 113.371886 -230.0094) (xy 113.380011 -230.060695) (xy 113.38052 -230.086662) (xy 113.380011 -230.112629)
			(xy 113.659921 -230.112629) (xy 113.659921 -230.060695) (xy 113.668046 -230.0094) (xy 113.684094 -229.960007)
			(xy 113.707672 -229.913733) (xy 113.738198 -229.871717) (xy 113.774921 -229.834994) (xy 113.816937 -229.804468)
			(xy 113.863211 -229.78089) (xy 113.912604 -229.764842) (xy 113.963899 -229.756717) (xy 114.015833 -229.756717)
			(xy 114.067128 -229.764842) (xy 114.116521 -229.78089) (xy 114.162795 -229.804468) (xy 114.204811 -229.834994)
			(xy 114.241534 -229.871717) (xy 114.27206 -229.913733) (xy 114.295638 -229.960007) (xy 114.311686 -230.0094)
			(xy 114.319811 -230.060695) (xy 114.32032 -230.086662) (xy 114.319811 -230.112629) (xy 114.599721 -230.112629)
			(xy 114.599721 -230.060695) (xy 114.607846 -230.0094) (xy 114.623894 -229.960007) (xy 114.647472 -229.913733)
			(xy 114.677998 -229.871717) (xy 114.714721 -229.834994) (xy 114.756737 -229.804468) (xy 114.803011 -229.78089)
			(xy 114.852404 -229.764842) (xy 114.903699 -229.756717) (xy 114.955633 -229.756717) (xy 115.006928 -229.764842)
			(xy 115.056321 -229.78089) (xy 115.102595 -229.804468) (xy 115.144611 -229.834994) (xy 115.181334 -229.871717)
			(xy 115.21186 -229.913733) (xy 115.235438 -229.960007) (xy 115.251486 -230.0094) (xy 115.259611 -230.060695)
			(xy 115.26012 -230.086662) (xy 115.259611 -230.112629) (xy 115.539267 -230.112629) (xy 115.539267 -230.060695)
			(xy 115.547392 -230.0094) (xy 115.56344 -229.960007) (xy 115.587018 -229.913733) (xy 115.617544 -229.871717)
			(xy 115.654267 -229.834994) (xy 115.696283 -229.804468) (xy 115.742557 -229.78089) (xy 115.79195 -229.764842)
			(xy 115.843245 -229.756717) (xy 115.895179 -229.756717) (xy 115.946474 -229.764842) (xy 115.995867 -229.78089)
			(xy 116.042141 -229.804468) (xy 116.084157 -229.834994) (xy 116.12088 -229.871717) (xy 116.151406 -229.913733)
			(xy 116.174984 -229.960007) (xy 116.191032 -230.0094) (xy 116.199157 -230.060695) (xy 116.199666 -230.086662)
			(xy 116.199157 -230.112629) (xy 116.479067 -230.112629) (xy 116.479067 -230.060695) (xy 116.487192 -230.0094)
			(xy 116.50324 -229.960007) (xy 116.526818 -229.913733) (xy 116.557344 -229.871717) (xy 116.594067 -229.834994)
			(xy 116.636083 -229.804468) (xy 116.682357 -229.78089) (xy 116.73175 -229.764842) (xy 116.783045 -229.756717)
			(xy 116.834979 -229.756717) (xy 116.886274 -229.764842) (xy 116.935667 -229.78089) (xy 116.981941 -229.804468)
			(xy 117.023957 -229.834994) (xy 117.06068 -229.871717) (xy 117.091206 -229.913733) (xy 117.114784 -229.960007)
			(xy 117.130832 -230.0094) (xy 117.138957 -230.060695) (xy 117.139466 -230.086662) (xy 117.138957 -230.112629)
			(xy 117.418867 -230.112629) (xy 117.418867 -230.060695) (xy 117.426992 -230.0094) (xy 117.44304 -229.960007)
			(xy 117.466618 -229.913733) (xy 117.497144 -229.871717) (xy 117.533867 -229.834994) (xy 117.575883 -229.804468)
			(xy 117.622157 -229.78089) (xy 117.67155 -229.764842) (xy 117.722845 -229.756717) (xy 117.774779 -229.756717)
			(xy 117.826074 -229.764842) (xy 117.875467 -229.78089) (xy 117.921741 -229.804468) (xy 117.963757 -229.834994)
			(xy 118.00048 -229.871717) (xy 118.031006 -229.913733) (xy 118.054584 -229.960007) (xy 118.070632 -230.0094)
			(xy 118.078757 -230.060695) (xy 118.079266 -230.086662) (xy 118.078757 -230.112629) (xy 118.358667 -230.112629)
			(xy 118.358667 -230.060695) (xy 118.366792 -230.0094) (xy 118.38284 -229.960007) (xy 118.406418 -229.913733)
			(xy 118.436944 -229.871717) (xy 118.473667 -229.834994) (xy 118.515683 -229.804468) (xy 118.561957 -229.78089)
			(xy 118.61135 -229.764842) (xy 118.662645 -229.756717) (xy 118.714579 -229.756717) (xy 118.765874 -229.764842)
			(xy 118.815267 -229.78089) (xy 118.861541 -229.804468) (xy 118.903557 -229.834994) (xy 118.94028 -229.871717)
			(xy 118.970806 -229.913733) (xy 118.994384 -229.960007) (xy 119.010432 -230.0094) (xy 119.018557 -230.060695)
			(xy 119.019066 -230.086662) (xy 119.018557 -230.112629) (xy 119.298467 -230.112629) (xy 119.298467 -230.060695)
			(xy 119.306592 -230.0094) (xy 119.32264 -229.960007) (xy 119.346218 -229.913733) (xy 119.376744 -229.871717)
			(xy 119.413467 -229.834994) (xy 119.455483 -229.804468) (xy 119.501757 -229.78089) (xy 119.55115 -229.764842)
			(xy 119.602445 -229.756717) (xy 119.654379 -229.756717) (xy 119.705674 -229.764842) (xy 119.755067 -229.78089)
			(xy 119.801341 -229.804468) (xy 119.843357 -229.834994) (xy 119.88008 -229.871717) (xy 119.910606 -229.913733)
			(xy 119.934184 -229.960007) (xy 119.950232 -230.0094) (xy 119.958357 -230.060695) (xy 119.958866 -230.086662)
			(xy 119.958357 -230.112629) (xy 120.238267 -230.112629) (xy 120.238267 -230.060695) (xy 120.246392 -230.0094)
			(xy 120.26244 -229.960007) (xy 120.286018 -229.913733) (xy 120.316544 -229.871717) (xy 120.353267 -229.834994)
			(xy 120.395283 -229.804468) (xy 120.441557 -229.78089) (xy 120.49095 -229.764842) (xy 120.542245 -229.756717)
			(xy 120.594179 -229.756717) (xy 120.645474 -229.764842) (xy 120.694867 -229.78089) (xy 120.741141 -229.804468)
			(xy 120.783157 -229.834994) (xy 120.81988 -229.871717) (xy 120.850406 -229.913733) (xy 120.873984 -229.960007)
			(xy 120.890032 -230.0094) (xy 120.898157 -230.060695) (xy 120.898666 -230.086662) (xy 120.898157 -230.112629)
			(xy 121.178067 -230.112629) (xy 121.178067 -230.060695) (xy 121.186192 -230.0094) (xy 121.20224 -229.960007)
			(xy 121.225818 -229.913733) (xy 121.256344 -229.871717) (xy 121.293067 -229.834994) (xy 121.335083 -229.804468)
			(xy 121.381357 -229.78089) (xy 121.43075 -229.764842) (xy 121.482045 -229.756717) (xy 121.533979 -229.756717)
			(xy 121.585274 -229.764842) (xy 121.634667 -229.78089) (xy 121.680941 -229.804468) (xy 121.722957 -229.834994)
			(xy 121.75968 -229.871717) (xy 121.790206 -229.913733) (xy 121.813784 -229.960007) (xy 121.829832 -230.0094)
			(xy 121.837957 -230.060695) (xy 121.838466 -230.086662) (xy 121.837957 -230.112629) (xy 121.829832 -230.163924)
			(xy 121.813784 -230.213317) (xy 121.790206 -230.259591) (xy 121.75968 -230.301607) (xy 121.722957 -230.33833)
			(xy 121.680941 -230.368856) (xy 121.634667 -230.392434) (xy 121.585274 -230.408482) (xy 121.533979 -230.416607)
			(xy 121.482045 -230.416607) (xy 121.43075 -230.408482) (xy 121.381357 -230.392434) (xy 121.335083 -230.368856)
			(xy 121.293067 -230.33833) (xy 121.256344 -230.301607) (xy 121.225818 -230.259591) (xy 121.20224 -230.213317)
			(xy 121.186192 -230.163924) (xy 121.178067 -230.112629) (xy 120.898157 -230.112629) (xy 120.890032 -230.163924)
			(xy 120.873984 -230.213317) (xy 120.850406 -230.259591) (xy 120.81988 -230.301607) (xy 120.783157 -230.33833)
			(xy 120.741141 -230.368856) (xy 120.694867 -230.392434) (xy 120.645474 -230.408482) (xy 120.594179 -230.416607)
			(xy 120.542245 -230.416607) (xy 120.49095 -230.408482) (xy 120.441557 -230.392434) (xy 120.395283 -230.368856)
			(xy 120.353267 -230.33833) (xy 120.316544 -230.301607) (xy 120.286018 -230.259591) (xy 120.26244 -230.213317)
			(xy 120.246392 -230.163924) (xy 120.238267 -230.112629) (xy 119.958357 -230.112629) (xy 119.950232 -230.163924)
			(xy 119.934184 -230.213317) (xy 119.910606 -230.259591) (xy 119.88008 -230.301607) (xy 119.843357 -230.33833)
			(xy 119.801341 -230.368856) (xy 119.755067 -230.392434) (xy 119.705674 -230.408482) (xy 119.654379 -230.416607)
			(xy 119.602445 -230.416607) (xy 119.55115 -230.408482) (xy 119.501757 -230.392434) (xy 119.455483 -230.368856)
			(xy 119.413467 -230.33833) (xy 119.376744 -230.301607) (xy 119.346218 -230.259591) (xy 119.32264 -230.213317)
			(xy 119.306592 -230.163924) (xy 119.298467 -230.112629) (xy 119.018557 -230.112629) (xy 119.010432 -230.163924)
			(xy 118.994384 -230.213317) (xy 118.970806 -230.259591) (xy 118.94028 -230.301607) (xy 118.903557 -230.33833)
			(xy 118.861541 -230.368856) (xy 118.815267 -230.392434) (xy 118.765874 -230.408482) (xy 118.714579 -230.416607)
			(xy 118.662645 -230.416607) (xy 118.61135 -230.408482) (xy 118.561957 -230.392434) (xy 118.515683 -230.368856)
			(xy 118.473667 -230.33833) (xy 118.436944 -230.301607) (xy 118.406418 -230.259591) (xy 118.38284 -230.213317)
			(xy 118.366792 -230.163924) (xy 118.358667 -230.112629) (xy 118.078757 -230.112629) (xy 118.070632 -230.163924)
			(xy 118.054584 -230.213317) (xy 118.031006 -230.259591) (xy 118.00048 -230.301607) (xy 117.963757 -230.33833)
			(xy 117.921741 -230.368856) (xy 117.875467 -230.392434) (xy 117.826074 -230.408482) (xy 117.774779 -230.416607)
			(xy 117.722845 -230.416607) (xy 117.67155 -230.408482) (xy 117.622157 -230.392434) (xy 117.575883 -230.368856)
			(xy 117.533867 -230.33833) (xy 117.497144 -230.301607) (xy 117.466618 -230.259591) (xy 117.44304 -230.213317)
			(xy 117.426992 -230.163924) (xy 117.418867 -230.112629) (xy 117.138957 -230.112629) (xy 117.130832 -230.163924)
			(xy 117.114784 -230.213317) (xy 117.091206 -230.259591) (xy 117.06068 -230.301607) (xy 117.023957 -230.33833)
			(xy 116.981941 -230.368856) (xy 116.935667 -230.392434) (xy 116.886274 -230.408482) (xy 116.834979 -230.416607)
			(xy 116.783045 -230.416607) (xy 116.73175 -230.408482) (xy 116.682357 -230.392434) (xy 116.636083 -230.368856)
			(xy 116.594067 -230.33833) (xy 116.557344 -230.301607) (xy 116.526818 -230.259591) (xy 116.50324 -230.213317)
			(xy 116.487192 -230.163924) (xy 116.479067 -230.112629) (xy 116.199157 -230.112629) (xy 116.191032 -230.163924)
			(xy 116.174984 -230.213317) (xy 116.151406 -230.259591) (xy 116.12088 -230.301607) (xy 116.084157 -230.33833)
			(xy 116.042141 -230.368856) (xy 115.995867 -230.392434) (xy 115.946474 -230.408482) (xy 115.895179 -230.416607)
			(xy 115.843245 -230.416607) (xy 115.79195 -230.408482) (xy 115.742557 -230.392434) (xy 115.696283 -230.368856)
			(xy 115.654267 -230.33833) (xy 115.617544 -230.301607) (xy 115.587018 -230.259591) (xy 115.56344 -230.213317)
			(xy 115.547392 -230.163924) (xy 115.539267 -230.112629) (xy 115.259611 -230.112629) (xy 115.251486 -230.163924)
			(xy 115.235438 -230.213317) (xy 115.21186 -230.259591) (xy 115.181334 -230.301607) (xy 115.144611 -230.33833)
			(xy 115.102595 -230.368856) (xy 115.056321 -230.392434) (xy 115.006928 -230.408482) (xy 114.955633 -230.416607)
			(xy 114.903699 -230.416607) (xy 114.852404 -230.408482) (xy 114.803011 -230.392434) (xy 114.756737 -230.368856)
			(xy 114.714721 -230.33833) (xy 114.677998 -230.301607) (xy 114.647472 -230.259591) (xy 114.623894 -230.213317)
			(xy 114.607846 -230.163924) (xy 114.599721 -230.112629) (xy 114.319811 -230.112629) (xy 114.311686 -230.163924)
			(xy 114.295638 -230.213317) (xy 114.27206 -230.259591) (xy 114.241534 -230.301607) (xy 114.204811 -230.33833)
			(xy 114.162795 -230.368856) (xy 114.116521 -230.392434) (xy 114.067128 -230.408482) (xy 114.015833 -230.416607)
			(xy 113.963899 -230.416607) (xy 113.912604 -230.408482) (xy 113.863211 -230.392434) (xy 113.816937 -230.368856)
			(xy 113.774921 -230.33833) (xy 113.738198 -230.301607) (xy 113.707672 -230.259591) (xy 113.684094 -230.213317)
			(xy 113.668046 -230.163924) (xy 113.659921 -230.112629) (xy 113.380011 -230.112629) (xy 113.371886 -230.163924)
			(xy 113.355838 -230.213317) (xy 113.33226 -230.259591) (xy 113.301734 -230.301607) (xy 113.265011 -230.33833)
			(xy 113.222995 -230.368856) (xy 113.176721 -230.392434) (xy 113.127328 -230.408482) (xy 113.076033 -230.416607)
			(xy 113.024099 -230.416607) (xy 112.972804 -230.408482) (xy 112.923411 -230.392434) (xy 112.877137 -230.368856)
			(xy 112.835121 -230.33833) (xy 112.798398 -230.301607) (xy 112.767872 -230.259591) (xy 112.744294 -230.213317)
			(xy 112.728246 -230.163924) (xy 112.720121 -230.112629) (xy 112.440211 -230.112629) (xy 112.432086 -230.163924)
			(xy 112.416038 -230.213317) (xy 112.39246 -230.259591) (xy 112.361934 -230.301607) (xy 112.325211 -230.33833)
			(xy 112.283195 -230.368856) (xy 112.236921 -230.392434) (xy 112.187528 -230.408482) (xy 112.136233 -230.416607)
			(xy 112.084299 -230.416607) (xy 112.033004 -230.408482) (xy 111.983611 -230.392434) (xy 111.937337 -230.368856)
			(xy 111.895321 -230.33833) (xy 111.858598 -230.301607) (xy 111.828072 -230.259591) (xy 111.804494 -230.213317)
			(xy 111.788446 -230.163924) (xy 111.780321 -230.112629) (xy 111.500411 -230.112629) (xy 111.492286 -230.163924)
			(xy 111.476238 -230.213317) (xy 111.45266 -230.259591) (xy 111.422134 -230.301607) (xy 111.385411 -230.33833)
			(xy 111.343395 -230.368856) (xy 111.297121 -230.392434) (xy 111.247728 -230.408482) (xy 111.196433 -230.416607)
			(xy 111.144499 -230.416607) (xy 111.093204 -230.408482) (xy 111.043811 -230.392434) (xy 110.997537 -230.368856)
			(xy 110.955521 -230.33833) (xy 110.918798 -230.301607) (xy 110.888272 -230.259591) (xy 110.864694 -230.213317)
			(xy 110.848646 -230.163924) (xy 110.840521 -230.112629) (xy 110.560168 -230.112629) (xy 110.553549 -230.158159)
			(xy 110.539849 -230.20416) (xy 110.530132 -230.226108) (xy 110.525306 -230.236268) (xy 110.525306 -230.474774)
			(xy 110.525804 -230.489548) (xy 110.53426 -230.517858) (xy 110.550471 -230.542561) (xy 110.573079 -230.561585)
			(xy 110.600188 -230.573337) (xy 110.629527 -230.576831) (xy 110.644178 -230.57485) (xy 110.658164 -230.572577)
			(xy 110.686397 -230.570163) (xy 110.700566 -230.570024) (xy 110.726539 -230.570504) (xy 110.777845 -230.578626)
			(xy 110.82725 -230.594674) (xy 110.873535 -230.618253) (xy 110.915562 -230.648783) (xy 110.952295 -230.685512)
			(xy 110.982829 -230.727536) (xy 111.006413 -230.773819) (xy 111.022466 -230.823221) (xy 111.030593 -230.874527)
			(xy 111.030593 -230.926445) (xy 111.310421 -230.926445) (xy 111.310421 -230.874511) (xy 111.318546 -230.823216)
			(xy 111.334594 -230.773823) (xy 111.358172 -230.727549) (xy 111.388698 -230.685533) (xy 111.425421 -230.64881)
			(xy 111.467437 -230.618284) (xy 111.513711 -230.594706) (xy 111.563104 -230.578658) (xy 111.614399 -230.570533)
			(xy 111.666333 -230.570533) (xy 111.717628 -230.578658) (xy 111.767021 -230.594706) (xy 111.813295 -230.618284)
			(xy 111.855311 -230.64881) (xy 111.892034 -230.685533) (xy 111.92256 -230.727549) (xy 111.946138 -230.773823)
			(xy 111.962186 -230.823216) (xy 111.970311 -230.874511) (xy 111.97082 -230.900478) (xy 111.970311 -230.926445)
			(xy 112.250221 -230.926445) (xy 112.250221 -230.874511) (xy 112.258346 -230.823216) (xy 112.274394 -230.773823)
			(xy 112.297972 -230.727549) (xy 112.328498 -230.685533) (xy 112.365221 -230.64881) (xy 112.407237 -230.618284)
			(xy 112.453511 -230.594706) (xy 112.502904 -230.578658) (xy 112.554199 -230.570533) (xy 112.606133 -230.570533)
			(xy 112.657428 -230.578658) (xy 112.706821 -230.594706) (xy 112.753095 -230.618284) (xy 112.795111 -230.64881)
			(xy 112.831834 -230.685533) (xy 112.86236 -230.727549) (xy 112.885938 -230.773823) (xy 112.901986 -230.823216)
			(xy 112.910111 -230.874511) (xy 112.91062 -230.900478) (xy 112.910111 -230.926445) (xy 113.190021 -230.926445)
			(xy 113.190021 -230.874511) (xy 113.198146 -230.823216) (xy 113.214194 -230.773823) (xy 113.237772 -230.727549)
			(xy 113.268298 -230.685533) (xy 113.305021 -230.64881) (xy 113.347037 -230.618284) (xy 113.393311 -230.594706)
			(xy 113.442704 -230.578658) (xy 113.493999 -230.570533) (xy 113.545933 -230.570533) (xy 113.597228 -230.578658)
			(xy 113.646621 -230.594706) (xy 113.692895 -230.618284) (xy 113.734911 -230.64881) (xy 113.771634 -230.685533)
			(xy 113.80216 -230.727549) (xy 113.825738 -230.773823) (xy 113.841786 -230.823216) (xy 113.849911 -230.874511)
			(xy 113.85042 -230.900478) (xy 113.849911 -230.926445) (xy 114.130075 -230.926445) (xy 114.130075 -230.874511)
			(xy 114.1382 -230.823216) (xy 114.154248 -230.773823) (xy 114.177826 -230.727549) (xy 114.208352 -230.685533)
			(xy 114.245075 -230.64881) (xy 114.287091 -230.618284) (xy 114.333365 -230.594706) (xy 114.382758 -230.578658)
			(xy 114.434053 -230.570533) (xy 114.485987 -230.570533) (xy 114.537282 -230.578658) (xy 114.586675 -230.594706)
			(xy 114.632949 -230.618284) (xy 114.674965 -230.64881) (xy 114.711688 -230.685533) (xy 114.742214 -230.727549)
			(xy 114.765792 -230.773823) (xy 114.78184 -230.823216) (xy 114.789965 -230.874511) (xy 114.790474 -230.900478)
			(xy 114.789965 -230.926445) (xy 115.069621 -230.926445) (xy 115.069621 -230.874511) (xy 115.077746 -230.823216)
			(xy 115.093794 -230.773823) (xy 115.117372 -230.727549) (xy 115.147898 -230.685533) (xy 115.184621 -230.64881)
			(xy 115.226637 -230.618284) (xy 115.272911 -230.594706) (xy 115.322304 -230.578658) (xy 115.373599 -230.570533)
			(xy 115.425533 -230.570533) (xy 115.476828 -230.578658) (xy 115.526221 -230.594706) (xy 115.572495 -230.618284)
			(xy 115.614511 -230.64881) (xy 115.651234 -230.685533) (xy 115.68176 -230.727549) (xy 115.705338 -230.773823)
			(xy 115.721386 -230.823216) (xy 115.729511 -230.874511) (xy 115.73002 -230.900478) (xy 115.729511 -230.926445)
			(xy 116.009421 -230.926445) (xy 116.009421 -230.874511) (xy 116.017546 -230.823216) (xy 116.033594 -230.773823)
			(xy 116.057172 -230.727549) (xy 116.087698 -230.685533) (xy 116.124421 -230.64881) (xy 116.166437 -230.618284)
			(xy 116.212711 -230.594706) (xy 116.262104 -230.578658) (xy 116.313399 -230.570533) (xy 116.365333 -230.570533)
			(xy 116.416628 -230.578658) (xy 116.466021 -230.594706) (xy 116.512295 -230.618284) (xy 116.554311 -230.64881)
			(xy 116.591034 -230.685533) (xy 116.62156 -230.727549) (xy 116.645138 -230.773823) (xy 116.661186 -230.823216)
			(xy 116.669311 -230.874511) (xy 116.66982 -230.900478) (xy 116.669311 -230.926445) (xy 116.949221 -230.926445)
			(xy 116.949221 -230.874511) (xy 116.957346 -230.823216) (xy 116.973394 -230.773823) (xy 116.996972 -230.727549)
			(xy 117.027498 -230.685533) (xy 117.064221 -230.64881) (xy 117.106237 -230.618284) (xy 117.152511 -230.594706)
			(xy 117.201904 -230.578658) (xy 117.253199 -230.570533) (xy 117.305133 -230.570533) (xy 117.356428 -230.578658)
			(xy 117.405821 -230.594706) (xy 117.452095 -230.618284) (xy 117.494111 -230.64881) (xy 117.530834 -230.685533)
			(xy 117.56136 -230.727549) (xy 117.584938 -230.773823) (xy 117.600986 -230.823216) (xy 117.609111 -230.874511)
			(xy 117.60962 -230.900478) (xy 117.609111 -230.926445) (xy 117.889021 -230.926445) (xy 117.889021 -230.874511)
			(xy 117.897146 -230.823216) (xy 117.913194 -230.773823) (xy 117.936772 -230.727549) (xy 117.967298 -230.685533)
			(xy 118.004021 -230.64881) (xy 118.046037 -230.618284) (xy 118.092311 -230.594706) (xy 118.141704 -230.578658)
			(xy 118.192999 -230.570533) (xy 118.244933 -230.570533) (xy 118.296228 -230.578658) (xy 118.345621 -230.594706)
			(xy 118.391895 -230.618284) (xy 118.433911 -230.64881) (xy 118.470634 -230.685533) (xy 118.50116 -230.727549)
			(xy 118.524738 -230.773823) (xy 118.540786 -230.823216) (xy 118.548911 -230.874511) (xy 118.54942 -230.900478)
			(xy 118.548911 -230.926445) (xy 118.828821 -230.926445) (xy 118.828821 -230.874511) (xy 118.836946 -230.823216)
			(xy 118.852994 -230.773823) (xy 118.876572 -230.727549) (xy 118.907098 -230.685533) (xy 118.943821 -230.64881)
			(xy 118.985837 -230.618284) (xy 119.032111 -230.594706) (xy 119.081504 -230.578658) (xy 119.132799 -230.570533)
			(xy 119.184733 -230.570533) (xy 119.236028 -230.578658) (xy 119.285421 -230.594706) (xy 119.331695 -230.618284)
			(xy 119.373711 -230.64881) (xy 119.410434 -230.685533) (xy 119.44096 -230.727549) (xy 119.464538 -230.773823)
			(xy 119.480586 -230.823216) (xy 119.488711 -230.874511) (xy 119.48922 -230.900478) (xy 119.488711 -230.926445)
			(xy 119.768621 -230.926445) (xy 119.768621 -230.874511) (xy 119.776746 -230.823216) (xy 119.792794 -230.773823)
			(xy 119.816372 -230.727549) (xy 119.846898 -230.685533) (xy 119.883621 -230.64881) (xy 119.925637 -230.618284)
			(xy 119.971911 -230.594706) (xy 120.021304 -230.578658) (xy 120.072599 -230.570533) (xy 120.124533 -230.570533)
			(xy 120.175828 -230.578658) (xy 120.225221 -230.594706) (xy 120.271495 -230.618284) (xy 120.313511 -230.64881)
			(xy 120.350234 -230.685533) (xy 120.38076 -230.727549) (xy 120.404338 -230.773823) (xy 120.420386 -230.823216)
			(xy 120.428511 -230.874511) (xy 120.42902 -230.900478) (xy 120.428511 -230.926445) (xy 120.708421 -230.926445)
			(xy 120.708421 -230.874511) (xy 120.716546 -230.823216) (xy 120.732594 -230.773823) (xy 120.756172 -230.727549)
			(xy 120.786698 -230.685533) (xy 120.823421 -230.64881) (xy 120.865437 -230.618284) (xy 120.911711 -230.594706)
			(xy 120.961104 -230.578658) (xy 121.012399 -230.570533) (xy 121.064333 -230.570533) (xy 121.115628 -230.578658)
			(xy 121.165021 -230.594706) (xy 121.211295 -230.618284) (xy 121.253311 -230.64881) (xy 121.290034 -230.685533)
			(xy 121.32056 -230.727549) (xy 121.344138 -230.773823) (xy 121.360186 -230.823216) (xy 121.368311 -230.874511)
			(xy 121.36882 -230.900478) (xy 121.368311 -230.926445) (xy 121.647967 -230.926445) (xy 121.647967 -230.874511)
			(xy 121.656092 -230.823216) (xy 121.67214 -230.773823) (xy 121.695718 -230.727549) (xy 121.726244 -230.685533)
			(xy 121.762967 -230.64881) (xy 121.804983 -230.618284) (xy 121.851257 -230.594706) (xy 121.90065 -230.578658)
			(xy 121.951945 -230.570533) (xy 122.003879 -230.570533) (xy 122.055174 -230.578658) (xy 122.104567 -230.594706)
			(xy 122.150841 -230.618284) (xy 122.192857 -230.64881) (xy 122.22958 -230.685533) (xy 122.260106 -230.727549)
			(xy 122.283684 -230.773823) (xy 122.299732 -230.823216) (xy 122.307857 -230.874511) (xy 122.308366 -230.900478)
			(xy 122.307857 -230.926445) (xy 122.299732 -230.97774) (xy 122.283684 -231.027133) (xy 122.260106 -231.073407)
			(xy 122.22958 -231.115423) (xy 122.192857 -231.152146) (xy 122.150841 -231.182672) (xy 122.104567 -231.20625)
			(xy 122.055174 -231.222298) (xy 122.003879 -231.230423) (xy 121.951945 -231.230423) (xy 121.90065 -231.222298)
			(xy 121.851257 -231.20625) (xy 121.804983 -231.182672) (xy 121.762967 -231.152146) (xy 121.726244 -231.115423)
			(xy 121.695718 -231.073407) (xy 121.67214 -231.027133) (xy 121.656092 -230.97774) (xy 121.647967 -230.926445)
			(xy 121.368311 -230.926445) (xy 121.360186 -230.97774) (xy 121.344138 -231.027133) (xy 121.32056 -231.073407)
			(xy 121.290034 -231.115423) (xy 121.253311 -231.152146) (xy 121.211295 -231.182672) (xy 121.165021 -231.20625)
			(xy 121.115628 -231.222298) (xy 121.064333 -231.230423) (xy 121.012399 -231.230423) (xy 120.961104 -231.222298)
			(xy 120.911711 -231.20625) (xy 120.865437 -231.182672) (xy 120.823421 -231.152146) (xy 120.786698 -231.115423)
			(xy 120.756172 -231.073407) (xy 120.732594 -231.027133) (xy 120.716546 -230.97774) (xy 120.708421 -230.926445)
			(xy 120.428511 -230.926445) (xy 120.420386 -230.97774) (xy 120.404338 -231.027133) (xy 120.38076 -231.073407)
			(xy 120.350234 -231.115423) (xy 120.313511 -231.152146) (xy 120.271495 -231.182672) (xy 120.225221 -231.20625)
			(xy 120.175828 -231.222298) (xy 120.124533 -231.230423) (xy 120.072599 -231.230423) (xy 120.021304 -231.222298)
			(xy 119.971911 -231.20625) (xy 119.925637 -231.182672) (xy 119.883621 -231.152146) (xy 119.846898 -231.115423)
			(xy 119.816372 -231.073407) (xy 119.792794 -231.027133) (xy 119.776746 -230.97774) (xy 119.768621 -230.926445)
			(xy 119.488711 -230.926445) (xy 119.480586 -230.97774) (xy 119.464538 -231.027133) (xy 119.44096 -231.073407)
			(xy 119.410434 -231.115423) (xy 119.373711 -231.152146) (xy 119.331695 -231.182672) (xy 119.285421 -231.20625)
			(xy 119.236028 -231.222298) (xy 119.184733 -231.230423) (xy 119.132799 -231.230423) (xy 119.081504 -231.222298)
			(xy 119.032111 -231.20625) (xy 118.985837 -231.182672) (xy 118.943821 -231.152146) (xy 118.907098 -231.115423)
			(xy 118.876572 -231.073407) (xy 118.852994 -231.027133) (xy 118.836946 -230.97774) (xy 118.828821 -230.926445)
			(xy 118.548911 -230.926445) (xy 118.540786 -230.97774) (xy 118.524738 -231.027133) (xy 118.50116 -231.073407)
			(xy 118.470634 -231.115423) (xy 118.433911 -231.152146) (xy 118.391895 -231.182672) (xy 118.345621 -231.20625)
			(xy 118.296228 -231.222298) (xy 118.244933 -231.230423) (xy 118.192999 -231.230423) (xy 118.141704 -231.222298)
			(xy 118.092311 -231.20625) (xy 118.046037 -231.182672) (xy 118.004021 -231.152146) (xy 117.967298 -231.115423)
			(xy 117.936772 -231.073407) (xy 117.913194 -231.027133) (xy 117.897146 -230.97774) (xy 117.889021 -230.926445)
			(xy 117.609111 -230.926445) (xy 117.600986 -230.97774) (xy 117.584938 -231.027133) (xy 117.56136 -231.073407)
			(xy 117.530834 -231.115423) (xy 117.494111 -231.152146) (xy 117.452095 -231.182672) (xy 117.405821 -231.20625)
			(xy 117.356428 -231.222298) (xy 117.305133 -231.230423) (xy 117.253199 -231.230423) (xy 117.201904 -231.222298)
			(xy 117.152511 -231.20625) (xy 117.106237 -231.182672) (xy 117.064221 -231.152146) (xy 117.027498 -231.115423)
			(xy 116.996972 -231.073407) (xy 116.973394 -231.027133) (xy 116.957346 -230.97774) (xy 116.949221 -230.926445)
			(xy 116.669311 -230.926445) (xy 116.661186 -230.97774) (xy 116.645138 -231.027133) (xy 116.62156 -231.073407)
			(xy 116.591034 -231.115423) (xy 116.554311 -231.152146) (xy 116.512295 -231.182672) (xy 116.466021 -231.20625)
			(xy 116.416628 -231.222298) (xy 116.365333 -231.230423) (xy 116.313399 -231.230423) (xy 116.262104 -231.222298)
			(xy 116.212711 -231.20625) (xy 116.166437 -231.182672) (xy 116.124421 -231.152146) (xy 116.087698 -231.115423)
			(xy 116.057172 -231.073407) (xy 116.033594 -231.027133) (xy 116.017546 -230.97774) (xy 116.009421 -230.926445)
			(xy 115.729511 -230.926445) (xy 115.721386 -230.97774) (xy 115.705338 -231.027133) (xy 115.68176 -231.073407)
			(xy 115.651234 -231.115423) (xy 115.614511 -231.152146) (xy 115.572495 -231.182672) (xy 115.526221 -231.20625)
			(xy 115.476828 -231.222298) (xy 115.425533 -231.230423) (xy 115.373599 -231.230423) (xy 115.322304 -231.222298)
			(xy 115.272911 -231.20625) (xy 115.226637 -231.182672) (xy 115.184621 -231.152146) (xy 115.147898 -231.115423)
			(xy 115.117372 -231.073407) (xy 115.093794 -231.027133) (xy 115.077746 -230.97774) (xy 115.069621 -230.926445)
			(xy 114.789965 -230.926445) (xy 114.78184 -230.97774) (xy 114.765792 -231.027133) (xy 114.742214 -231.073407)
			(xy 114.711688 -231.115423) (xy 114.674965 -231.152146) (xy 114.632949 -231.182672) (xy 114.586675 -231.20625)
			(xy 114.537282 -231.222298) (xy 114.485987 -231.230423) (xy 114.434053 -231.230423) (xy 114.382758 -231.222298)
			(xy 114.333365 -231.20625) (xy 114.287091 -231.182672) (xy 114.245075 -231.152146) (xy 114.208352 -231.115423)
			(xy 114.177826 -231.073407) (xy 114.154248 -231.027133) (xy 114.1382 -230.97774) (xy 114.130075 -230.926445)
			(xy 113.849911 -230.926445) (xy 113.841786 -230.97774) (xy 113.825738 -231.027133) (xy 113.80216 -231.073407)
			(xy 113.771634 -231.115423) (xy 113.734911 -231.152146) (xy 113.692895 -231.182672) (xy 113.646621 -231.20625)
			(xy 113.597228 -231.222298) (xy 113.545933 -231.230423) (xy 113.493999 -231.230423) (xy 113.442704 -231.222298)
			(xy 113.393311 -231.20625) (xy 113.347037 -231.182672) (xy 113.305021 -231.152146) (xy 113.268298 -231.115423)
			(xy 113.237772 -231.073407) (xy 113.214194 -231.027133) (xy 113.198146 -230.97774) (xy 113.190021 -230.926445)
			(xy 112.910111 -230.926445) (xy 112.901986 -230.97774) (xy 112.885938 -231.027133) (xy 112.86236 -231.073407)
			(xy 112.831834 -231.115423) (xy 112.795111 -231.152146) (xy 112.753095 -231.182672) (xy 112.706821 -231.20625)
			(xy 112.657428 -231.222298) (xy 112.606133 -231.230423) (xy 112.554199 -231.230423) (xy 112.502904 -231.222298)
			(xy 112.453511 -231.20625) (xy 112.407237 -231.182672) (xy 112.365221 -231.152146) (xy 112.328498 -231.115423)
			(xy 112.297972 -231.073407) (xy 112.274394 -231.027133) (xy 112.258346 -230.97774) (xy 112.250221 -230.926445)
			(xy 111.970311 -230.926445) (xy 111.962186 -230.97774) (xy 111.946138 -231.027133) (xy 111.92256 -231.073407)
			(xy 111.892034 -231.115423) (xy 111.855311 -231.152146) (xy 111.813295 -231.182672) (xy 111.767021 -231.20625)
			(xy 111.717628 -231.222298) (xy 111.666333 -231.230423) (xy 111.614399 -231.230423) (xy 111.563104 -231.222298)
			(xy 111.513711 -231.20625) (xy 111.467437 -231.182672) (xy 111.425421 -231.152146) (xy 111.388698 -231.115423)
			(xy 111.358172 -231.073407) (xy 111.334594 -231.027133) (xy 111.318546 -230.97774) (xy 111.310421 -230.926445)
			(xy 111.030593 -230.926445) (xy 111.030593 -230.926473) (xy 111.022466 -230.977779) (xy 111.006413 -231.027181)
			(xy 110.982829 -231.073464) (xy 110.952295 -231.115488) (xy 110.915562 -231.152217) (xy 110.873535 -231.182747)
			(xy 110.82725 -231.206326) (xy 110.777845 -231.222374) (xy 110.726539 -231.230496) (xy 110.700566 -231.230932)
			(xy 110.686398 -231.23078) (xy 110.658166 -231.228363) (xy 110.644178 -231.226106) (xy 110.629536 -231.224086)
			(xy 110.6002 -231.227603) (xy 110.573099 -231.239369) (xy 110.550498 -231.258399) (xy 110.53429 -231.283101)
			(xy 110.525829 -231.311409) (xy 110.525306 -231.326182) (xy 110.525306 -231.564434) (xy 110.530132 -231.574594)
			(xy 110.539918 -231.596613) (xy 110.553724 -231.642777) (xy 110.560683 -231.690456) (xy 110.56112 -231.714548)
			(xy 110.560702 -231.738641) (xy 110.560428 -231.740515) (xy 110.840267 -231.740515) (xy 110.840267 -231.688581)
			(xy 110.848392 -231.637286) (xy 110.86444 -231.587893) (xy 110.888018 -231.541619) (xy 110.918544 -231.499603)
			(xy 110.955267 -231.46288) (xy 110.997283 -231.432354) (xy 111.043557 -231.408776) (xy 111.09295 -231.392728)
			(xy 111.144245 -231.384603) (xy 111.196179 -231.384603) (xy 111.247474 -231.392728) (xy 111.296867 -231.408776)
			(xy 111.343141 -231.432354) (xy 111.385157 -231.46288) (xy 111.42188 -231.499603) (xy 111.452406 -231.541619)
			(xy 111.475984 -231.587893) (xy 111.492032 -231.637286) (xy 111.500157 -231.688581) (xy 111.500666 -231.714548)
			(xy 111.500157 -231.740515) (xy 111.780575 -231.740515) (xy 111.780575 -231.688581) (xy 111.7887 -231.637286)
			(xy 111.804748 -231.587893) (xy 111.828326 -231.541619) (xy 111.858852 -231.499603) (xy 111.895575 -231.46288)
			(xy 111.937591 -231.432354) (xy 111.983865 -231.408776) (xy 112.033258 -231.392728) (xy 112.084553 -231.384603)
			(xy 112.136487 -231.384603) (xy 112.187782 -231.392728) (xy 112.237175 -231.408776) (xy 112.283449 -231.432354)
			(xy 112.325465 -231.46288) (xy 112.362188 -231.499603) (xy 112.392714 -231.541619) (xy 112.416292 -231.587893)
			(xy 112.43234 -231.637286) (xy 112.440465 -231.688581) (xy 112.440974 -231.714548) (xy 112.440465 -231.740515)
			(xy 112.720375 -231.740515) (xy 112.720375 -231.688581) (xy 112.7285 -231.637286) (xy 112.744548 -231.587893)
			(xy 112.768126 -231.541619) (xy 112.798652 -231.499603) (xy 112.835375 -231.46288) (xy 112.877391 -231.432354)
			(xy 112.923665 -231.408776) (xy 112.973058 -231.392728) (xy 113.024353 -231.384603) (xy 113.076287 -231.384603)
			(xy 113.127582 -231.392728) (xy 113.176975 -231.408776) (xy 113.223249 -231.432354) (xy 113.265265 -231.46288)
			(xy 113.301988 -231.499603) (xy 113.332514 -231.541619) (xy 113.356092 -231.587893) (xy 113.37214 -231.637286)
			(xy 113.380265 -231.688581) (xy 113.380774 -231.714548) (xy 113.380265 -231.740515) (xy 113.660175 -231.740515)
			(xy 113.660175 -231.688581) (xy 113.6683 -231.637286) (xy 113.684348 -231.587893) (xy 113.707926 -231.541619)
			(xy 113.738452 -231.499603) (xy 113.775175 -231.46288) (xy 113.817191 -231.432354) (xy 113.863465 -231.408776)
			(xy 113.912858 -231.392728) (xy 113.964153 -231.384603) (xy 114.016087 -231.384603) (xy 114.067382 -231.392728)
			(xy 114.116775 -231.408776) (xy 114.163049 -231.432354) (xy 114.205065 -231.46288) (xy 114.241788 -231.499603)
			(xy 114.272314 -231.541619) (xy 114.295892 -231.587893) (xy 114.31194 -231.637286) (xy 114.320065 -231.688581)
			(xy 114.320574 -231.714548) (xy 114.320065 -231.740515) (xy 114.599467 -231.740515) (xy 114.599467 -231.688581)
			(xy 114.607592 -231.637286) (xy 114.62364 -231.587893) (xy 114.647218 -231.541619) (xy 114.677744 -231.499603)
			(xy 114.714467 -231.46288) (xy 114.756483 -231.432354) (xy 114.802757 -231.408776) (xy 114.85215 -231.392728)
			(xy 114.903445 -231.384603) (xy 114.955379 -231.384603) (xy 115.006674 -231.392728) (xy 115.056067 -231.408776)
			(xy 115.102341 -231.432354) (xy 115.144357 -231.46288) (xy 115.18108 -231.499603) (xy 115.211606 -231.541619)
			(xy 115.235184 -231.587893) (xy 115.251232 -231.637286) (xy 115.259357 -231.688581) (xy 115.259866 -231.714548)
			(xy 115.259357 -231.740515) (xy 115.539267 -231.740515) (xy 115.539267 -231.688581) (xy 115.547392 -231.637286)
			(xy 115.56344 -231.587893) (xy 115.587018 -231.541619) (xy 115.617544 -231.499603) (xy 115.654267 -231.46288)
			(xy 115.696283 -231.432354) (xy 115.742557 -231.408776) (xy 115.79195 -231.392728) (xy 115.843245 -231.384603)
			(xy 115.895179 -231.384603) (xy 115.946474 -231.392728) (xy 115.995867 -231.408776) (xy 116.042141 -231.432354)
			(xy 116.084157 -231.46288) (xy 116.12088 -231.499603) (xy 116.151406 -231.541619) (xy 116.174984 -231.587893)
			(xy 116.191032 -231.637286) (xy 116.199157 -231.688581) (xy 116.199666 -231.714548) (xy 116.199157 -231.740515)
			(xy 116.479067 -231.740515) (xy 116.479067 -231.688581) (xy 116.487192 -231.637286) (xy 116.50324 -231.587893)
			(xy 116.526818 -231.541619) (xy 116.557344 -231.499603) (xy 116.594067 -231.46288) (xy 116.636083 -231.432354)
			(xy 116.682357 -231.408776) (xy 116.73175 -231.392728) (xy 116.783045 -231.384603) (xy 116.834979 -231.384603)
			(xy 116.886274 -231.392728) (xy 116.935667 -231.408776) (xy 116.981941 -231.432354) (xy 117.023957 -231.46288)
			(xy 117.06068 -231.499603) (xy 117.091206 -231.541619) (xy 117.114784 -231.587893) (xy 117.130832 -231.637286)
			(xy 117.138957 -231.688581) (xy 117.139466 -231.714548) (xy 117.138957 -231.740515) (xy 117.418867 -231.740515)
			(xy 117.418867 -231.688581) (xy 117.426992 -231.637286) (xy 117.44304 -231.587893) (xy 117.466618 -231.541619)
			(xy 117.497144 -231.499603) (xy 117.533867 -231.46288) (xy 117.575883 -231.432354) (xy 117.622157 -231.408776)
			(xy 117.67155 -231.392728) (xy 117.722845 -231.384603) (xy 117.774779 -231.384603) (xy 117.826074 -231.392728)
			(xy 117.875467 -231.408776) (xy 117.921741 -231.432354) (xy 117.963757 -231.46288) (xy 118.00048 -231.499603)
			(xy 118.031006 -231.541619) (xy 118.054584 -231.587893) (xy 118.070632 -231.637286) (xy 118.078757 -231.688581)
			(xy 118.079266 -231.714548) (xy 118.078757 -231.740515) (xy 118.358667 -231.740515) (xy 118.358667 -231.688581)
			(xy 118.366792 -231.637286) (xy 118.38284 -231.587893) (xy 118.406418 -231.541619) (xy 118.436944 -231.499603)
			(xy 118.473667 -231.46288) (xy 118.515683 -231.432354) (xy 118.561957 -231.408776) (xy 118.61135 -231.392728)
			(xy 118.662645 -231.384603) (xy 118.714579 -231.384603) (xy 118.765874 -231.392728) (xy 118.815267 -231.408776)
			(xy 118.861541 -231.432354) (xy 118.903557 -231.46288) (xy 118.94028 -231.499603) (xy 118.970806 -231.541619)
			(xy 118.994384 -231.587893) (xy 119.010432 -231.637286) (xy 119.018557 -231.688581) (xy 119.019066 -231.714548)
			(xy 119.018557 -231.740515) (xy 119.298975 -231.740515) (xy 119.298975 -231.688581) (xy 119.3071 -231.637286)
			(xy 119.323148 -231.587893) (xy 119.346726 -231.541619) (xy 119.377252 -231.499603) (xy 119.413975 -231.46288)
			(xy 119.455991 -231.432354) (xy 119.502265 -231.408776) (xy 119.551658 -231.392728) (xy 119.602953 -231.384603)
			(xy 119.654887 -231.384603) (xy 119.706182 -231.392728) (xy 119.755575 -231.408776) (xy 119.801849 -231.432354)
			(xy 119.843865 -231.46288) (xy 119.880588 -231.499603) (xy 119.911114 -231.541619) (xy 119.934692 -231.587893)
			(xy 119.95074 -231.637286) (xy 119.958865 -231.688581) (xy 119.959374 -231.714548) (xy 119.958865 -231.740515)
			(xy 120.238267 -231.740515) (xy 120.238267 -231.688581) (xy 120.246392 -231.637286) (xy 120.26244 -231.587893)
			(xy 120.286018 -231.541619) (xy 120.316544 -231.499603) (xy 120.353267 -231.46288) (xy 120.395283 -231.432354)
			(xy 120.441557 -231.408776) (xy 120.49095 -231.392728) (xy 120.542245 -231.384603) (xy 120.594179 -231.384603)
			(xy 120.645474 -231.392728) (xy 120.694867 -231.408776) (xy 120.741141 -231.432354) (xy 120.783157 -231.46288)
			(xy 120.81988 -231.499603) (xy 120.850406 -231.541619) (xy 120.873984 -231.587893) (xy 120.890032 -231.637286)
			(xy 120.898157 -231.688581) (xy 120.898666 -231.714548) (xy 120.898157 -231.740515) (xy 121.178575 -231.740515)
			(xy 121.178575 -231.688581) (xy 121.1867 -231.637286) (xy 121.202748 -231.587893) (xy 121.226326 -231.541619)
			(xy 121.256852 -231.499603) (xy 121.293575 -231.46288) (xy 121.335591 -231.432354) (xy 121.381865 -231.408776)
			(xy 121.431258 -231.392728) (xy 121.482553 -231.384603) (xy 121.534487 -231.384603) (xy 121.585782 -231.392728)
			(xy 121.635175 -231.408776) (xy 121.681449 -231.432354) (xy 121.723465 -231.46288) (xy 121.760188 -231.499603)
			(xy 121.790714 -231.541619) (xy 121.814292 -231.587893) (xy 121.83034 -231.637286) (xy 121.838465 -231.688581)
			(xy 121.838974 -231.714548) (xy 121.838465 -231.740515) (xy 122.118121 -231.740515) (xy 122.118121 -231.688581)
			(xy 122.126246 -231.637286) (xy 122.142294 -231.587893) (xy 122.165872 -231.541619) (xy 122.196398 -231.499603)
			(xy 122.233121 -231.46288) (xy 122.275137 -231.432354) (xy 122.321411 -231.408776) (xy 122.370804 -231.392728)
			(xy 122.422099 -231.384603) (xy 122.474033 -231.384603) (xy 122.525328 -231.392728) (xy 122.574721 -231.408776)
			(xy 122.620995 -231.432354) (xy 122.663011 -231.46288) (xy 122.699734 -231.499603) (xy 122.73026 -231.541619)
			(xy 122.753838 -231.587893) (xy 122.769886 -231.637286) (xy 122.778011 -231.688581) (xy 122.77852 -231.714548)
			(xy 122.778011 -231.740515) (xy 122.769886 -231.79181) (xy 122.753838 -231.841203) (xy 122.73026 -231.887477)
			(xy 122.699734 -231.929493) (xy 122.663011 -231.966216) (xy 122.620995 -231.996742) (xy 122.574721 -232.02032)
			(xy 122.525328 -232.036368) (xy 122.474033 -232.044493) (xy 122.422099 -232.044493) (xy 122.370804 -232.036368)
			(xy 122.321411 -232.02032) (xy 122.275137 -231.996742) (xy 122.233121 -231.966216) (xy 122.196398 -231.929493)
			(xy 122.165872 -231.887477) (xy 122.142294 -231.841203) (xy 122.126246 -231.79181) (xy 122.118121 -231.740515)
			(xy 121.838465 -231.740515) (xy 121.83034 -231.79181) (xy 121.814292 -231.841203) (xy 121.790714 -231.887477)
			(xy 121.760188 -231.929493) (xy 121.723465 -231.966216) (xy 121.681449 -231.996742) (xy 121.635175 -232.02032)
			(xy 121.585782 -232.036368) (xy 121.534487 -232.044493) (xy 121.482553 -232.044493) (xy 121.431258 -232.036368)
			(xy 121.381865 -232.02032) (xy 121.335591 -231.996742) (xy 121.293575 -231.966216) (xy 121.256852 -231.929493)
			(xy 121.226326 -231.887477) (xy 121.202748 -231.841203) (xy 121.1867 -231.79181) (xy 121.178575 -231.740515)
			(xy 120.898157 -231.740515) (xy 120.890032 -231.79181) (xy 120.873984 -231.841203) (xy 120.850406 -231.887477)
			(xy 120.81988 -231.929493) (xy 120.783157 -231.966216) (xy 120.741141 -231.996742) (xy 120.694867 -232.02032)
			(xy 120.645474 -232.036368) (xy 120.594179 -232.044493) (xy 120.542245 -232.044493) (xy 120.49095 -232.036368)
			(xy 120.441557 -232.02032) (xy 120.395283 -231.996742) (xy 120.353267 -231.966216) (xy 120.316544 -231.929493)
			(xy 120.286018 -231.887477) (xy 120.26244 -231.841203) (xy 120.246392 -231.79181) (xy 120.238267 -231.740515)
			(xy 119.958865 -231.740515) (xy 119.95074 -231.79181) (xy 119.934692 -231.841203) (xy 119.911114 -231.887477)
			(xy 119.880588 -231.929493) (xy 119.843865 -231.966216) (xy 119.801849 -231.996742) (xy 119.755575 -232.02032)
			(xy 119.706182 -232.036368) (xy 119.654887 -232.044493) (xy 119.602953 -232.044493) (xy 119.551658 -232.036368)
			(xy 119.502265 -232.02032) (xy 119.455991 -231.996742) (xy 119.413975 -231.966216) (xy 119.377252 -231.929493)
			(xy 119.346726 -231.887477) (xy 119.323148 -231.841203) (xy 119.3071 -231.79181) (xy 119.298975 -231.740515)
			(xy 119.018557 -231.740515) (xy 119.010432 -231.79181) (xy 118.994384 -231.841203) (xy 118.970806 -231.887477)
			(xy 118.94028 -231.929493) (xy 118.903557 -231.966216) (xy 118.861541 -231.996742) (xy 118.815267 -232.02032)
			(xy 118.765874 -232.036368) (xy 118.714579 -232.044493) (xy 118.662645 -232.044493) (xy 118.61135 -232.036368)
			(xy 118.561957 -232.02032) (xy 118.515683 -231.996742) (xy 118.473667 -231.966216) (xy 118.436944 -231.929493)
			(xy 118.406418 -231.887477) (xy 118.38284 -231.841203) (xy 118.366792 -231.79181) (xy 118.358667 -231.740515)
			(xy 118.078757 -231.740515) (xy 118.070632 -231.79181) (xy 118.054584 -231.841203) (xy 118.031006 -231.887477)
			(xy 118.00048 -231.929493) (xy 117.963757 -231.966216) (xy 117.921741 -231.996742) (xy 117.875467 -232.02032)
			(xy 117.826074 -232.036368) (xy 117.774779 -232.044493) (xy 117.722845 -232.044493) (xy 117.67155 -232.036368)
			(xy 117.622157 -232.02032) (xy 117.575883 -231.996742) (xy 117.533867 -231.966216) (xy 117.497144 -231.929493)
			(xy 117.466618 -231.887477) (xy 117.44304 -231.841203) (xy 117.426992 -231.79181) (xy 117.418867 -231.740515)
			(xy 117.138957 -231.740515) (xy 117.130832 -231.79181) (xy 117.114784 -231.841203) (xy 117.091206 -231.887477)
			(xy 117.06068 -231.929493) (xy 117.023957 -231.966216) (xy 116.981941 -231.996742) (xy 116.935667 -232.02032)
			(xy 116.886274 -232.036368) (xy 116.834979 -232.044493) (xy 116.783045 -232.044493) (xy 116.73175 -232.036368)
			(xy 116.682357 -232.02032) (xy 116.636083 -231.996742) (xy 116.594067 -231.966216) (xy 116.557344 -231.929493)
			(xy 116.526818 -231.887477) (xy 116.50324 -231.841203) (xy 116.487192 -231.79181) (xy 116.479067 -231.740515)
			(xy 116.199157 -231.740515) (xy 116.191032 -231.79181) (xy 116.174984 -231.841203) (xy 116.151406 -231.887477)
			(xy 116.12088 -231.929493) (xy 116.084157 -231.966216) (xy 116.042141 -231.996742) (xy 115.995867 -232.02032)
			(xy 115.946474 -232.036368) (xy 115.895179 -232.044493) (xy 115.843245 -232.044493) (xy 115.79195 -232.036368)
			(xy 115.742557 -232.02032) (xy 115.696283 -231.996742) (xy 115.654267 -231.966216) (xy 115.617544 -231.929493)
			(xy 115.587018 -231.887477) (xy 115.56344 -231.841203) (xy 115.547392 -231.79181) (xy 115.539267 -231.740515)
			(xy 115.259357 -231.740515) (xy 115.251232 -231.79181) (xy 115.235184 -231.841203) (xy 115.211606 -231.887477)
			(xy 115.18108 -231.929493) (xy 115.144357 -231.966216) (xy 115.102341 -231.996742) (xy 115.056067 -232.02032)
			(xy 115.006674 -232.036368) (xy 114.955379 -232.044493) (xy 114.903445 -232.044493) (xy 114.85215 -232.036368)
			(xy 114.802757 -232.02032) (xy 114.756483 -231.996742) (xy 114.714467 -231.966216) (xy 114.677744 -231.929493)
			(xy 114.647218 -231.887477) (xy 114.62364 -231.841203) (xy 114.607592 -231.79181) (xy 114.599467 -231.740515)
			(xy 114.320065 -231.740515) (xy 114.31194 -231.79181) (xy 114.295892 -231.841203) (xy 114.272314 -231.887477)
			(xy 114.241788 -231.929493) (xy 114.205065 -231.966216) (xy 114.163049 -231.996742) (xy 114.116775 -232.02032)
			(xy 114.067382 -232.036368) (xy 114.016087 -232.044493) (xy 113.964153 -232.044493) (xy 113.912858 -232.036368)
			(xy 113.863465 -232.02032) (xy 113.817191 -231.996742) (xy 113.775175 -231.966216) (xy 113.738452 -231.929493)
			(xy 113.707926 -231.887477) (xy 113.684348 -231.841203) (xy 113.6683 -231.79181) (xy 113.660175 -231.740515)
			(xy 113.380265 -231.740515) (xy 113.37214 -231.79181) (xy 113.356092 -231.841203) (xy 113.332514 -231.887477)
			(xy 113.301988 -231.929493) (xy 113.265265 -231.966216) (xy 113.223249 -231.996742) (xy 113.176975 -232.02032)
			(xy 113.127582 -232.036368) (xy 113.076287 -232.044493) (xy 113.024353 -232.044493) (xy 112.973058 -232.036368)
			(xy 112.923665 -232.02032) (xy 112.877391 -231.996742) (xy 112.835375 -231.966216) (xy 112.798652 -231.929493)
			(xy 112.768126 -231.887477) (xy 112.744548 -231.841203) (xy 112.7285 -231.79181) (xy 112.720375 -231.740515)
			(xy 112.440465 -231.740515) (xy 112.43234 -231.79181) (xy 112.416292 -231.841203) (xy 112.392714 -231.887477)
			(xy 112.362188 -231.929493) (xy 112.325465 -231.966216) (xy 112.283449 -231.996742) (xy 112.237175 -232.02032)
			(xy 112.187782 -232.036368) (xy 112.136487 -232.044493) (xy 112.084553 -232.044493) (xy 112.033258 -232.036368)
			(xy 111.983865 -232.02032) (xy 111.937591 -231.996742) (xy 111.895575 -231.966216) (xy 111.858852 -231.929493)
			(xy 111.828326 -231.887477) (xy 111.804748 -231.841203) (xy 111.7887 -231.79181) (xy 111.780575 -231.740515)
			(xy 111.500157 -231.740515) (xy 111.492032 -231.79181) (xy 111.475984 -231.841203) (xy 111.452406 -231.887477)
			(xy 111.42188 -231.929493) (xy 111.385157 -231.966216) (xy 111.343141 -231.996742) (xy 111.296867 -232.02032)
			(xy 111.247474 -232.036368) (xy 111.196179 -232.044493) (xy 111.144245 -232.044493) (xy 111.09295 -232.036368)
			(xy 111.043557 -232.02032) (xy 110.997283 -231.996742) (xy 110.955267 -231.966216) (xy 110.918544 -231.929493)
			(xy 110.888018 -231.887477) (xy 110.86444 -231.841203) (xy 110.848392 -231.79181) (xy 110.840267 -231.740515)
			(xy 110.560428 -231.740515) (xy 110.553737 -231.786321) (xy 110.539919 -231.832482) (xy 110.530132 -231.854502)
			(xy 110.525306 -231.864662) (xy 110.525306 -232.10266) (xy 110.525802 -232.117435) (xy 110.534256 -232.145749)
			(xy 110.550466 -232.170456) (xy 110.573075 -232.189483) (xy 110.600186 -232.201236) (xy 110.629528 -232.204731)
			(xy 110.644178 -232.202736) (xy 110.658164 -232.200463) (xy 110.686397 -232.198049) (xy 110.700566 -232.19791)
			(xy 110.72654 -232.19839) (xy 110.777849 -232.206512) (xy 110.827255 -232.222561) (xy 110.873543 -232.246141)
			(xy 110.915571 -232.276673) (xy 110.952305 -232.313403) (xy 110.982841 -232.355428) (xy 111.006426 -232.401713)
			(xy 111.02248 -232.451118) (xy 111.030607 -232.502426) (xy 111.030607 -232.554331) (xy 111.310421 -232.554331)
			(xy 111.310421 -232.502397) (xy 111.318546 -232.451102) (xy 111.334594 -232.401709) (xy 111.358172 -232.355435)
			(xy 111.388698 -232.313419) (xy 111.425421 -232.276696) (xy 111.467437 -232.24617) (xy 111.513711 -232.222592)
			(xy 111.563104 -232.206544) (xy 111.614399 -232.198419) (xy 111.666333 -232.198419) (xy 111.717628 -232.206544)
			(xy 111.767021 -232.222592) (xy 111.813295 -232.24617) (xy 111.855311 -232.276696) (xy 111.892034 -232.313419)
			(xy 111.92256 -232.355435) (xy 111.946138 -232.401709) (xy 111.962186 -232.451102) (xy 111.970311 -232.502397)
			(xy 111.97082 -232.528364) (xy 111.970311 -232.554331) (xy 112.250221 -232.554331) (xy 112.250221 -232.502397)
			(xy 112.258346 -232.451102) (xy 112.274394 -232.401709) (xy 112.297972 -232.355435) (xy 112.328498 -232.313419)
			(xy 112.365221 -232.276696) (xy 112.407237 -232.24617) (xy 112.453511 -232.222592) (xy 112.502904 -232.206544)
			(xy 112.554199 -232.198419) (xy 112.606133 -232.198419) (xy 112.657428 -232.206544) (xy 112.706821 -232.222592)
			(xy 112.753095 -232.24617) (xy 112.795111 -232.276696) (xy 112.831834 -232.313419) (xy 112.86236 -232.355435)
			(xy 112.885938 -232.401709) (xy 112.901986 -232.451102) (xy 112.910111 -232.502397) (xy 112.91062 -232.528364)
			(xy 112.910111 -232.554331) (xy 113.190021 -232.554331) (xy 113.190021 -232.502397) (xy 113.198146 -232.451102)
			(xy 113.214194 -232.401709) (xy 113.237772 -232.355435) (xy 113.268298 -232.313419) (xy 113.305021 -232.276696)
			(xy 113.347037 -232.24617) (xy 113.393311 -232.222592) (xy 113.442704 -232.206544) (xy 113.493999 -232.198419)
			(xy 113.545933 -232.198419) (xy 113.597228 -232.206544) (xy 113.646621 -232.222592) (xy 113.692895 -232.24617)
			(xy 113.734911 -232.276696) (xy 113.771634 -232.313419) (xy 113.80216 -232.355435) (xy 113.825738 -232.401709)
			(xy 113.841786 -232.451102) (xy 113.849911 -232.502397) (xy 113.85042 -232.528364) (xy 113.849911 -232.554331)
			(xy 114.129821 -232.554331) (xy 114.129821 -232.502397) (xy 114.137946 -232.451102) (xy 114.153994 -232.401709)
			(xy 114.177572 -232.355435) (xy 114.208098 -232.313419) (xy 114.244821 -232.276696) (xy 114.286837 -232.24617)
			(xy 114.333111 -232.222592) (xy 114.382504 -232.206544) (xy 114.433799 -232.198419) (xy 114.485733 -232.198419)
			(xy 114.537028 -232.206544) (xy 114.586421 -232.222592) (xy 114.632695 -232.24617) (xy 114.674711 -232.276696)
			(xy 114.711434 -232.313419) (xy 114.74196 -232.355435) (xy 114.765538 -232.401709) (xy 114.781586 -232.451102)
			(xy 114.789711 -232.502397) (xy 114.79022 -232.528364) (xy 114.789711 -232.554331) (xy 115.069621 -232.554331)
			(xy 115.069621 -232.502397) (xy 115.077746 -232.451102) (xy 115.093794 -232.401709) (xy 115.117372 -232.355435)
			(xy 115.147898 -232.313419) (xy 115.184621 -232.276696) (xy 115.226637 -232.24617) (xy 115.272911 -232.222592)
			(xy 115.322304 -232.206544) (xy 115.373599 -232.198419) (xy 115.425533 -232.198419) (xy 115.476828 -232.206544)
			(xy 115.526221 -232.222592) (xy 115.572495 -232.24617) (xy 115.614511 -232.276696) (xy 115.651234 -232.313419)
			(xy 115.68176 -232.355435) (xy 115.705338 -232.401709) (xy 115.721386 -232.451102) (xy 115.729511 -232.502397)
			(xy 115.73002 -232.528364) (xy 115.729511 -232.554331) (xy 116.009421 -232.554331) (xy 116.009421 -232.502397)
			(xy 116.017546 -232.451102) (xy 116.033594 -232.401709) (xy 116.057172 -232.355435) (xy 116.087698 -232.313419)
			(xy 116.124421 -232.276696) (xy 116.166437 -232.24617) (xy 116.212711 -232.222592) (xy 116.262104 -232.206544)
			(xy 116.313399 -232.198419) (xy 116.365333 -232.198419) (xy 116.416628 -232.206544) (xy 116.466021 -232.222592)
			(xy 116.512295 -232.24617) (xy 116.554311 -232.276696) (xy 116.591034 -232.313419) (xy 116.62156 -232.355435)
			(xy 116.645138 -232.401709) (xy 116.661186 -232.451102) (xy 116.669311 -232.502397) (xy 116.66982 -232.528364)
			(xy 116.669311 -232.554331) (xy 116.949221 -232.554331) (xy 116.949221 -232.502397) (xy 116.957346 -232.451102)
			(xy 116.973394 -232.401709) (xy 116.996972 -232.355435) (xy 117.027498 -232.313419) (xy 117.064221 -232.276696)
			(xy 117.106237 -232.24617) (xy 117.152511 -232.222592) (xy 117.201904 -232.206544) (xy 117.253199 -232.198419)
			(xy 117.305133 -232.198419) (xy 117.356428 -232.206544) (xy 117.405821 -232.222592) (xy 117.452095 -232.24617)
			(xy 117.494111 -232.276696) (xy 117.530834 -232.313419) (xy 117.56136 -232.355435) (xy 117.584938 -232.401709)
			(xy 117.600986 -232.451102) (xy 117.609111 -232.502397) (xy 117.60962 -232.528364) (xy 117.609111 -232.554331)
			(xy 117.889021 -232.554331) (xy 117.889021 -232.502397) (xy 117.897146 -232.451102) (xy 117.913194 -232.401709)
			(xy 117.936772 -232.355435) (xy 117.967298 -232.313419) (xy 118.004021 -232.276696) (xy 118.046037 -232.24617)
			(xy 118.092311 -232.222592) (xy 118.141704 -232.206544) (xy 118.192999 -232.198419) (xy 118.244933 -232.198419)
			(xy 118.296228 -232.206544) (xy 118.345621 -232.222592) (xy 118.391895 -232.24617) (xy 118.433911 -232.276696)
			(xy 118.470634 -232.313419) (xy 118.50116 -232.355435) (xy 118.524738 -232.401709) (xy 118.540786 -232.451102)
			(xy 118.548911 -232.502397) (xy 118.54942 -232.528364) (xy 118.548911 -232.554331) (xy 118.828821 -232.554331)
			(xy 118.828821 -232.502397) (xy 118.836946 -232.451102) (xy 118.852994 -232.401709) (xy 118.876572 -232.355435)
			(xy 118.907098 -232.313419) (xy 118.943821 -232.276696) (xy 118.985837 -232.24617) (xy 119.032111 -232.222592)
			(xy 119.081504 -232.206544) (xy 119.132799 -232.198419) (xy 119.184733 -232.198419) (xy 119.236028 -232.206544)
			(xy 119.285421 -232.222592) (xy 119.331695 -232.24617) (xy 119.373711 -232.276696) (xy 119.410434 -232.313419)
			(xy 119.44096 -232.355435) (xy 119.464538 -232.401709) (xy 119.480586 -232.451102) (xy 119.488711 -232.502397)
			(xy 119.48922 -232.528364) (xy 119.488711 -232.554331) (xy 119.768367 -232.554331) (xy 119.768367 -232.502397)
			(xy 119.776492 -232.451102) (xy 119.79254 -232.401709) (xy 119.816118 -232.355435) (xy 119.846644 -232.313419)
			(xy 119.883367 -232.276696) (xy 119.925383 -232.24617) (xy 119.971657 -232.222592) (xy 120.02105 -232.206544)
			(xy 120.072345 -232.198419) (xy 120.124279 -232.198419) (xy 120.175574 -232.206544) (xy 120.224967 -232.222592)
			(xy 120.271241 -232.24617) (xy 120.313257 -232.276696) (xy 120.34998 -232.313419) (xy 120.380506 -232.355435)
			(xy 120.404084 -232.401709) (xy 120.420132 -232.451102) (xy 120.428257 -232.502397) (xy 120.428766 -232.528364)
			(xy 120.428257 -232.554331) (xy 120.708421 -232.554331) (xy 120.708421 -232.502397) (xy 120.716546 -232.451102)
			(xy 120.732594 -232.401709) (xy 120.756172 -232.355435) (xy 120.786698 -232.313419) (xy 120.823421 -232.276696)
			(xy 120.865437 -232.24617) (xy 120.911711 -232.222592) (xy 120.961104 -232.206544) (xy 121.012399 -232.198419)
			(xy 121.064333 -232.198419) (xy 121.115628 -232.206544) (xy 121.165021 -232.222592) (xy 121.211295 -232.24617)
			(xy 121.253311 -232.276696) (xy 121.290034 -232.313419) (xy 121.32056 -232.355435) (xy 121.344138 -232.401709)
			(xy 121.360186 -232.451102) (xy 121.368311 -232.502397) (xy 121.36882 -232.528364) (xy 121.368311 -232.554331)
			(xy 121.648221 -232.554331) (xy 121.648221 -232.502397) (xy 121.656346 -232.451102) (xy 121.672394 -232.401709)
			(xy 121.695972 -232.355435) (xy 121.726498 -232.313419) (xy 121.763221 -232.276696) (xy 121.805237 -232.24617)
			(xy 121.851511 -232.222592) (xy 121.900904 -232.206544) (xy 121.952199 -232.198419) (xy 122.004133 -232.198419)
			(xy 122.055428 -232.206544) (xy 122.104821 -232.222592) (xy 122.151095 -232.24617) (xy 122.193111 -232.276696)
			(xy 122.229834 -232.313419) (xy 122.26036 -232.355435) (xy 122.283938 -232.401709) (xy 122.299986 -232.451102)
			(xy 122.308111 -232.502397) (xy 122.30862 -232.528364) (xy 122.308111 -232.554331) (xy 122.299986 -232.605626)
			(xy 122.283938 -232.655019) (xy 122.26036 -232.701293) (xy 122.229834 -232.743309) (xy 122.193111 -232.780032)
			(xy 122.151095 -232.810558) (xy 122.104821 -232.834136) (xy 122.055428 -232.850184) (xy 122.004133 -232.858309)
			(xy 121.952199 -232.858309) (xy 121.900904 -232.850184) (xy 121.851511 -232.834136) (xy 121.805237 -232.810558)
			(xy 121.763221 -232.780032) (xy 121.726498 -232.743309) (xy 121.695972 -232.701293) (xy 121.672394 -232.655019)
			(xy 121.656346 -232.605626) (xy 121.648221 -232.554331) (xy 121.368311 -232.554331) (xy 121.360186 -232.605626)
			(xy 121.344138 -232.655019) (xy 121.32056 -232.701293) (xy 121.290034 -232.743309) (xy 121.253311 -232.780032)
			(xy 121.211295 -232.810558) (xy 121.165021 -232.834136) (xy 121.115628 -232.850184) (xy 121.064333 -232.858309)
			(xy 121.012399 -232.858309) (xy 120.961104 -232.850184) (xy 120.911711 -232.834136) (xy 120.865437 -232.810558)
			(xy 120.823421 -232.780032) (xy 120.786698 -232.743309) (xy 120.756172 -232.701293) (xy 120.732594 -232.655019)
			(xy 120.716546 -232.605626) (xy 120.708421 -232.554331) (xy 120.428257 -232.554331) (xy 120.420132 -232.605626)
			(xy 120.404084 -232.655019) (xy 120.380506 -232.701293) (xy 120.34998 -232.743309) (xy 120.313257 -232.780032)
			(xy 120.271241 -232.810558) (xy 120.224967 -232.834136) (xy 120.175574 -232.850184) (xy 120.124279 -232.858309)
			(xy 120.072345 -232.858309) (xy 120.02105 -232.850184) (xy 119.971657 -232.834136) (xy 119.925383 -232.810558)
			(xy 119.883367 -232.780032) (xy 119.846644 -232.743309) (xy 119.816118 -232.701293) (xy 119.79254 -232.655019)
			(xy 119.776492 -232.605626) (xy 119.768367 -232.554331) (xy 119.488711 -232.554331) (xy 119.480586 -232.605626)
			(xy 119.464538 -232.655019) (xy 119.44096 -232.701293) (xy 119.410434 -232.743309) (xy 119.373711 -232.780032)
			(xy 119.331695 -232.810558) (xy 119.285421 -232.834136) (xy 119.236028 -232.850184) (xy 119.184733 -232.858309)
			(xy 119.132799 -232.858309) (xy 119.081504 -232.850184) (xy 119.032111 -232.834136) (xy 118.985837 -232.810558)
			(xy 118.943821 -232.780032) (xy 118.907098 -232.743309) (xy 118.876572 -232.701293) (xy 118.852994 -232.655019)
			(xy 118.836946 -232.605626) (xy 118.828821 -232.554331) (xy 118.548911 -232.554331) (xy 118.540786 -232.605626)
			(xy 118.524738 -232.655019) (xy 118.50116 -232.701293) (xy 118.470634 -232.743309) (xy 118.433911 -232.780032)
			(xy 118.391895 -232.810558) (xy 118.345621 -232.834136) (xy 118.296228 -232.850184) (xy 118.244933 -232.858309)
			(xy 118.192999 -232.858309) (xy 118.141704 -232.850184) (xy 118.092311 -232.834136) (xy 118.046037 -232.810558)
			(xy 118.004021 -232.780032) (xy 117.967298 -232.743309) (xy 117.936772 -232.701293) (xy 117.913194 -232.655019)
			(xy 117.897146 -232.605626) (xy 117.889021 -232.554331) (xy 117.609111 -232.554331) (xy 117.600986 -232.605626)
			(xy 117.584938 -232.655019) (xy 117.56136 -232.701293) (xy 117.530834 -232.743309) (xy 117.494111 -232.780032)
			(xy 117.452095 -232.810558) (xy 117.405821 -232.834136) (xy 117.356428 -232.850184) (xy 117.305133 -232.858309)
			(xy 117.253199 -232.858309) (xy 117.201904 -232.850184) (xy 117.152511 -232.834136) (xy 117.106237 -232.810558)
			(xy 117.064221 -232.780032) (xy 117.027498 -232.743309) (xy 116.996972 -232.701293) (xy 116.973394 -232.655019)
			(xy 116.957346 -232.605626) (xy 116.949221 -232.554331) (xy 116.669311 -232.554331) (xy 116.661186 -232.605626)
			(xy 116.645138 -232.655019) (xy 116.62156 -232.701293) (xy 116.591034 -232.743309) (xy 116.554311 -232.780032)
			(xy 116.512295 -232.810558) (xy 116.466021 -232.834136) (xy 116.416628 -232.850184) (xy 116.365333 -232.858309)
			(xy 116.313399 -232.858309) (xy 116.262104 -232.850184) (xy 116.212711 -232.834136) (xy 116.166437 -232.810558)
			(xy 116.124421 -232.780032) (xy 116.087698 -232.743309) (xy 116.057172 -232.701293) (xy 116.033594 -232.655019)
			(xy 116.017546 -232.605626) (xy 116.009421 -232.554331) (xy 115.729511 -232.554331) (xy 115.721386 -232.605626)
			(xy 115.705338 -232.655019) (xy 115.68176 -232.701293) (xy 115.651234 -232.743309) (xy 115.614511 -232.780032)
			(xy 115.572495 -232.810558) (xy 115.526221 -232.834136) (xy 115.476828 -232.850184) (xy 115.425533 -232.858309)
			(xy 115.373599 -232.858309) (xy 115.322304 -232.850184) (xy 115.272911 -232.834136) (xy 115.226637 -232.810558)
			(xy 115.184621 -232.780032) (xy 115.147898 -232.743309) (xy 115.117372 -232.701293) (xy 115.093794 -232.655019)
			(xy 115.077746 -232.605626) (xy 115.069621 -232.554331) (xy 114.789711 -232.554331) (xy 114.781586 -232.605626)
			(xy 114.765538 -232.655019) (xy 114.74196 -232.701293) (xy 114.711434 -232.743309) (xy 114.674711 -232.780032)
			(xy 114.632695 -232.810558) (xy 114.586421 -232.834136) (xy 114.537028 -232.850184) (xy 114.485733 -232.858309)
			(xy 114.433799 -232.858309) (xy 114.382504 -232.850184) (xy 114.333111 -232.834136) (xy 114.286837 -232.810558)
			(xy 114.244821 -232.780032) (xy 114.208098 -232.743309) (xy 114.177572 -232.701293) (xy 114.153994 -232.655019)
			(xy 114.137946 -232.605626) (xy 114.129821 -232.554331) (xy 113.849911 -232.554331) (xy 113.841786 -232.605626)
			(xy 113.825738 -232.655019) (xy 113.80216 -232.701293) (xy 113.771634 -232.743309) (xy 113.734911 -232.780032)
			(xy 113.692895 -232.810558) (xy 113.646621 -232.834136) (xy 113.597228 -232.850184) (xy 113.545933 -232.858309)
			(xy 113.493999 -232.858309) (xy 113.442704 -232.850184) (xy 113.393311 -232.834136) (xy 113.347037 -232.810558)
			(xy 113.305021 -232.780032) (xy 113.268298 -232.743309) (xy 113.237772 -232.701293) (xy 113.214194 -232.655019)
			(xy 113.198146 -232.605626) (xy 113.190021 -232.554331) (xy 112.910111 -232.554331) (xy 112.901986 -232.605626)
			(xy 112.885938 -232.655019) (xy 112.86236 -232.701293) (xy 112.831834 -232.743309) (xy 112.795111 -232.780032)
			(xy 112.753095 -232.810558) (xy 112.706821 -232.834136) (xy 112.657428 -232.850184) (xy 112.606133 -232.858309)
			(xy 112.554199 -232.858309) (xy 112.502904 -232.850184) (xy 112.453511 -232.834136) (xy 112.407237 -232.810558)
			(xy 112.365221 -232.780032) (xy 112.328498 -232.743309) (xy 112.297972 -232.701293) (xy 112.274394 -232.655019)
			(xy 112.258346 -232.605626) (xy 112.250221 -232.554331) (xy 111.970311 -232.554331) (xy 111.962186 -232.605626)
			(xy 111.946138 -232.655019) (xy 111.92256 -232.701293) (xy 111.892034 -232.743309) (xy 111.855311 -232.780032)
			(xy 111.813295 -232.810558) (xy 111.767021 -232.834136) (xy 111.717628 -232.850184) (xy 111.666333 -232.858309)
			(xy 111.614399 -232.858309) (xy 111.563104 -232.850184) (xy 111.513711 -232.834136) (xy 111.467437 -232.810558)
			(xy 111.425421 -232.780032) (xy 111.388698 -232.743309) (xy 111.358172 -232.701293) (xy 111.334594 -232.655019)
			(xy 111.318546 -232.605626) (xy 111.310421 -232.554331) (xy 111.030607 -232.554331) (xy 111.030607 -232.554374)
			(xy 111.02248 -232.605682) (xy 111.006426 -232.655087) (xy 110.982841 -232.701372) (xy 110.952305 -232.743397)
			(xy 110.915571 -232.780127) (xy 110.873543 -232.810659) (xy 110.827255 -232.834239) (xy 110.777849 -232.850288)
			(xy 110.72654 -232.85841) (xy 110.700566 -232.858818) (xy 110.686398 -232.858666) (xy 110.658166 -232.856249)
			(xy 110.644178 -232.853992) (xy 110.629535 -232.851972) (xy 110.600198 -232.85549) (xy 110.573095 -232.867255)
			(xy 110.550493 -232.886285) (xy 110.534281 -232.910987) (xy 110.525817 -232.939295) (xy 110.525306 -232.954068)
			(xy 110.525306 -233.192066) (xy 110.530132 -233.202226) (xy 110.539922 -233.224244) (xy 110.553738 -233.270407)
			(xy 110.560707 -233.318087) (xy 110.56112 -233.34218) (xy 110.560699 -233.366273) (xy 110.560425 -233.368147)
			(xy 110.840267 -233.368147) (xy 110.840267 -233.316213) (xy 110.848392 -233.264918) (xy 110.86444 -233.215525)
			(xy 110.888018 -233.169251) (xy 110.918544 -233.127235) (xy 110.955267 -233.090512) (xy 110.997283 -233.059986)
			(xy 111.043557 -233.036408) (xy 111.09295 -233.02036) (xy 111.144245 -233.012235) (xy 111.196179 -233.012235)
			(xy 111.247474 -233.02036) (xy 111.296867 -233.036408) (xy 111.343141 -233.059986) (xy 111.385157 -233.090512)
			(xy 111.42188 -233.127235) (xy 111.452406 -233.169251) (xy 111.475984 -233.215525) (xy 111.492032 -233.264918)
			(xy 111.500157 -233.316213) (xy 111.500666 -233.34218) (xy 111.500157 -233.368147) (xy 111.780067 -233.368147)
			(xy 111.780067 -233.316213) (xy 111.788192 -233.264918) (xy 111.80424 -233.215525) (xy 111.827818 -233.169251)
			(xy 111.858344 -233.127235) (xy 111.895067 -233.090512) (xy 111.937083 -233.059986) (xy 111.983357 -233.036408)
			(xy 112.03275 -233.02036) (xy 112.084045 -233.012235) (xy 112.135979 -233.012235) (xy 112.187274 -233.02036)
			(xy 112.236667 -233.036408) (xy 112.282941 -233.059986) (xy 112.324957 -233.090512) (xy 112.36168 -233.127235)
			(xy 112.392206 -233.169251) (xy 112.415784 -233.215525) (xy 112.431832 -233.264918) (xy 112.439957 -233.316213)
			(xy 112.440466 -233.34218) (xy 112.439957 -233.368147) (xy 112.719867 -233.368147) (xy 112.719867 -233.316213)
			(xy 112.727992 -233.264918) (xy 112.74404 -233.215525) (xy 112.767618 -233.169251) (xy 112.798144 -233.127235)
			(xy 112.834867 -233.090512) (xy 112.876883 -233.059986) (xy 112.923157 -233.036408) (xy 112.97255 -233.02036)
			(xy 113.023845 -233.012235) (xy 113.075779 -233.012235) (xy 113.127074 -233.02036) (xy 113.176467 -233.036408)
			(xy 113.222741 -233.059986) (xy 113.264757 -233.090512) (xy 113.30148 -233.127235) (xy 113.332006 -233.169251)
			(xy 113.355584 -233.215525) (xy 113.371632 -233.264918) (xy 113.379757 -233.316213) (xy 113.380266 -233.34218)
			(xy 113.379757 -233.368147) (xy 113.659921 -233.368147) (xy 113.659921 -233.316213) (xy 113.668046 -233.264918)
			(xy 113.684094 -233.215525) (xy 113.707672 -233.169251) (xy 113.738198 -233.127235) (xy 113.774921 -233.090512)
			(xy 113.816937 -233.059986) (xy 113.863211 -233.036408) (xy 113.912604 -233.02036) (xy 113.963899 -233.012235)
			(xy 114.015833 -233.012235) (xy 114.067128 -233.02036) (xy 114.116521 -233.036408) (xy 114.162795 -233.059986)
			(xy 114.204811 -233.090512) (xy 114.241534 -233.127235) (xy 114.27206 -233.169251) (xy 114.295638 -233.215525)
			(xy 114.311686 -233.264918) (xy 114.319811 -233.316213) (xy 114.32032 -233.34218) (xy 114.319811 -233.368147)
			(xy 114.599467 -233.368147) (xy 114.599467 -233.316213) (xy 114.607592 -233.264918) (xy 114.62364 -233.215525)
			(xy 114.647218 -233.169251) (xy 114.677744 -233.127235) (xy 114.714467 -233.090512) (xy 114.756483 -233.059986)
			(xy 114.802757 -233.036408) (xy 114.85215 -233.02036) (xy 114.903445 -233.012235) (xy 114.955379 -233.012235)
			(xy 115.006674 -233.02036) (xy 115.056067 -233.036408) (xy 115.102341 -233.059986) (xy 115.144357 -233.090512)
			(xy 115.18108 -233.127235) (xy 115.211606 -233.169251) (xy 115.235184 -233.215525) (xy 115.251232 -233.264918)
			(xy 115.259357 -233.316213) (xy 115.259866 -233.34218) (xy 115.259357 -233.368147) (xy 115.539267 -233.368147)
			(xy 115.539267 -233.316213) (xy 115.547392 -233.264918) (xy 115.56344 -233.215525) (xy 115.587018 -233.169251)
			(xy 115.617544 -233.127235) (xy 115.654267 -233.090512) (xy 115.696283 -233.059986) (xy 115.742557 -233.036408)
			(xy 115.79195 -233.02036) (xy 115.843245 -233.012235) (xy 115.895179 -233.012235) (xy 115.946474 -233.02036)
			(xy 115.995867 -233.036408) (xy 116.042141 -233.059986) (xy 116.084157 -233.090512) (xy 116.12088 -233.127235)
			(xy 116.151406 -233.169251) (xy 116.174984 -233.215525) (xy 116.191032 -233.264918) (xy 116.199157 -233.316213)
			(xy 116.199666 -233.34218) (xy 116.199157 -233.368147) (xy 116.479067 -233.368147) (xy 116.479067 -233.316213)
			(xy 116.487192 -233.264918) (xy 116.50324 -233.215525) (xy 116.526818 -233.169251) (xy 116.557344 -233.127235)
			(xy 116.594067 -233.090512) (xy 116.636083 -233.059986) (xy 116.682357 -233.036408) (xy 116.73175 -233.02036)
			(xy 116.783045 -233.012235) (xy 116.834979 -233.012235) (xy 116.886274 -233.02036) (xy 116.935667 -233.036408)
			(xy 116.981941 -233.059986) (xy 117.023957 -233.090512) (xy 117.06068 -233.127235) (xy 117.091206 -233.169251)
			(xy 117.114784 -233.215525) (xy 117.130832 -233.264918) (xy 117.138957 -233.316213) (xy 117.139466 -233.34218)
			(xy 117.138957 -233.368147) (xy 117.418867 -233.368147) (xy 117.418867 -233.316213) (xy 117.426992 -233.264918)
			(xy 117.44304 -233.215525) (xy 117.466618 -233.169251) (xy 117.497144 -233.127235) (xy 117.533867 -233.090512)
			(xy 117.575883 -233.059986) (xy 117.622157 -233.036408) (xy 117.67155 -233.02036) (xy 117.722845 -233.012235)
			(xy 117.774779 -233.012235) (xy 117.826074 -233.02036) (xy 117.875467 -233.036408) (xy 117.921741 -233.059986)
			(xy 117.963757 -233.090512) (xy 118.00048 -233.127235) (xy 118.031006 -233.169251) (xy 118.054584 -233.215525)
			(xy 118.070632 -233.264918) (xy 118.078757 -233.316213) (xy 118.079266 -233.34218) (xy 118.078757 -233.368147)
			(xy 118.358667 -233.368147) (xy 118.358667 -233.316213) (xy 118.366792 -233.264918) (xy 118.38284 -233.215525)
			(xy 118.406418 -233.169251) (xy 118.436944 -233.127235) (xy 118.473667 -233.090512) (xy 118.515683 -233.059986)
			(xy 118.561957 -233.036408) (xy 118.61135 -233.02036) (xy 118.662645 -233.012235) (xy 118.714579 -233.012235)
			(xy 118.765874 -233.02036) (xy 118.815267 -233.036408) (xy 118.861541 -233.059986) (xy 118.903557 -233.090512)
			(xy 118.94028 -233.127235) (xy 118.970806 -233.169251) (xy 118.994384 -233.215525) (xy 119.010432 -233.264918)
			(xy 119.018557 -233.316213) (xy 119.019066 -233.34218) (xy 119.018557 -233.368147) (xy 119.298467 -233.368147)
			(xy 119.298467 -233.316213) (xy 119.306592 -233.264918) (xy 119.32264 -233.215525) (xy 119.346218 -233.169251)
			(xy 119.376744 -233.127235) (xy 119.413467 -233.090512) (xy 119.455483 -233.059986) (xy 119.501757 -233.036408)
			(xy 119.55115 -233.02036) (xy 119.602445 -233.012235) (xy 119.654379 -233.012235) (xy 119.705674 -233.02036)
			(xy 119.755067 -233.036408) (xy 119.801341 -233.059986) (xy 119.843357 -233.090512) (xy 119.88008 -233.127235)
			(xy 119.910606 -233.169251) (xy 119.934184 -233.215525) (xy 119.950232 -233.264918) (xy 119.958357 -233.316213)
			(xy 119.958866 -233.34218) (xy 119.958357 -233.368147) (xy 120.238267 -233.368147) (xy 120.238267 -233.316213)
			(xy 120.246392 -233.264918) (xy 120.26244 -233.215525) (xy 120.286018 -233.169251) (xy 120.316544 -233.127235)
			(xy 120.353267 -233.090512) (xy 120.395283 -233.059986) (xy 120.441557 -233.036408) (xy 120.49095 -233.02036)
			(xy 120.542245 -233.012235) (xy 120.594179 -233.012235) (xy 120.645474 -233.02036) (xy 120.694867 -233.036408)
			(xy 120.741141 -233.059986) (xy 120.783157 -233.090512) (xy 120.81988 -233.127235) (xy 120.850406 -233.169251)
			(xy 120.873984 -233.215525) (xy 120.890032 -233.264918) (xy 120.898157 -233.316213) (xy 120.898666 -233.34218)
			(xy 120.898157 -233.368147) (xy 121.178321 -233.368147) (xy 121.178321 -233.316213) (xy 121.186446 -233.264918)
			(xy 121.202494 -233.215525) (xy 121.226072 -233.169251) (xy 121.256598 -233.127235) (xy 121.293321 -233.090512)
			(xy 121.335337 -233.059986) (xy 121.381611 -233.036408) (xy 121.431004 -233.02036) (xy 121.482299 -233.012235)
			(xy 121.534233 -233.012235) (xy 121.585528 -233.02036) (xy 121.634921 -233.036408) (xy 121.681195 -233.059986)
			(xy 121.723211 -233.090512) (xy 121.759934 -233.127235) (xy 121.79046 -233.169251) (xy 121.814038 -233.215525)
			(xy 121.830086 -233.264918) (xy 121.838211 -233.316213) (xy 121.83872 -233.34218) (xy 121.838211 -233.368147)
			(xy 122.117867 -233.368147) (xy 122.117867 -233.316213) (xy 122.125992 -233.264918) (xy 122.14204 -233.215525)
			(xy 122.165618 -233.169251) (xy 122.196144 -233.127235) (xy 122.232867 -233.090512) (xy 122.274883 -233.059986)
			(xy 122.321157 -233.036408) (xy 122.37055 -233.02036) (xy 122.421845 -233.012235) (xy 122.473779 -233.012235)
			(xy 122.525074 -233.02036) (xy 122.574467 -233.036408) (xy 122.620741 -233.059986) (xy 122.662757 -233.090512)
			(xy 122.69948 -233.127235) (xy 122.730006 -233.169251) (xy 122.753584 -233.215525) (xy 122.769632 -233.264918)
			(xy 122.777757 -233.316213) (xy 122.778266 -233.34218) (xy 122.777757 -233.368147) (xy 122.769632 -233.419442)
			(xy 122.753584 -233.468835) (xy 122.730006 -233.515109) (xy 122.69948 -233.557125) (xy 122.662757 -233.593848)
			(xy 122.620741 -233.624374) (xy 122.574467 -233.647952) (xy 122.525074 -233.664) (xy 122.473779 -233.672125)
			(xy 122.421845 -233.672125) (xy 122.37055 -233.664) (xy 122.321157 -233.647952) (xy 122.274883 -233.624374)
			(xy 122.232867 -233.593848) (xy 122.196144 -233.557125) (xy 122.165618 -233.515109) (xy 122.14204 -233.468835)
			(xy 122.125992 -233.419442) (xy 122.117867 -233.368147) (xy 121.838211 -233.368147) (xy 121.830086 -233.419442)
			(xy 121.814038 -233.468835) (xy 121.79046 -233.515109) (xy 121.759934 -233.557125) (xy 121.723211 -233.593848)
			(xy 121.681195 -233.624374) (xy 121.634921 -233.647952) (xy 121.585528 -233.664) (xy 121.534233 -233.672125)
			(xy 121.482299 -233.672125) (xy 121.431004 -233.664) (xy 121.381611 -233.647952) (xy 121.335337 -233.624374)
			(xy 121.293321 -233.593848) (xy 121.256598 -233.557125) (xy 121.226072 -233.515109) (xy 121.202494 -233.468835)
			(xy 121.186446 -233.419442) (xy 121.178321 -233.368147) (xy 120.898157 -233.368147) (xy 120.890032 -233.419442)
			(xy 120.873984 -233.468835) (xy 120.850406 -233.515109) (xy 120.81988 -233.557125) (xy 120.783157 -233.593848)
			(xy 120.741141 -233.624374) (xy 120.694867 -233.647952) (xy 120.645474 -233.664) (xy 120.594179 -233.672125)
			(xy 120.542245 -233.672125) (xy 120.49095 -233.664) (xy 120.441557 -233.647952) (xy 120.395283 -233.624374)
			(xy 120.353267 -233.593848) (xy 120.316544 -233.557125) (xy 120.286018 -233.515109) (xy 120.26244 -233.468835)
			(xy 120.246392 -233.419442) (xy 120.238267 -233.368147) (xy 119.958357 -233.368147) (xy 119.950232 -233.419442)
			(xy 119.934184 -233.468835) (xy 119.910606 -233.515109) (xy 119.88008 -233.557125) (xy 119.843357 -233.593848)
			(xy 119.801341 -233.624374) (xy 119.755067 -233.647952) (xy 119.705674 -233.664) (xy 119.654379 -233.672125)
			(xy 119.602445 -233.672125) (xy 119.55115 -233.664) (xy 119.501757 -233.647952) (xy 119.455483 -233.624374)
			(xy 119.413467 -233.593848) (xy 119.376744 -233.557125) (xy 119.346218 -233.515109) (xy 119.32264 -233.468835)
			(xy 119.306592 -233.419442) (xy 119.298467 -233.368147) (xy 119.018557 -233.368147) (xy 119.010432 -233.419442)
			(xy 118.994384 -233.468835) (xy 118.970806 -233.515109) (xy 118.94028 -233.557125) (xy 118.903557 -233.593848)
			(xy 118.861541 -233.624374) (xy 118.815267 -233.647952) (xy 118.765874 -233.664) (xy 118.714579 -233.672125)
			(xy 118.662645 -233.672125) (xy 118.61135 -233.664) (xy 118.561957 -233.647952) (xy 118.515683 -233.624374)
			(xy 118.473667 -233.593848) (xy 118.436944 -233.557125) (xy 118.406418 -233.515109) (xy 118.38284 -233.468835)
			(xy 118.366792 -233.419442) (xy 118.358667 -233.368147) (xy 118.078757 -233.368147) (xy 118.070632 -233.419442)
			(xy 118.054584 -233.468835) (xy 118.031006 -233.515109) (xy 118.00048 -233.557125) (xy 117.963757 -233.593848)
			(xy 117.921741 -233.624374) (xy 117.875467 -233.647952) (xy 117.826074 -233.664) (xy 117.774779 -233.672125)
			(xy 117.722845 -233.672125) (xy 117.67155 -233.664) (xy 117.622157 -233.647952) (xy 117.575883 -233.624374)
			(xy 117.533867 -233.593848) (xy 117.497144 -233.557125) (xy 117.466618 -233.515109) (xy 117.44304 -233.468835)
			(xy 117.426992 -233.419442) (xy 117.418867 -233.368147) (xy 117.138957 -233.368147) (xy 117.130832 -233.419442)
			(xy 117.114784 -233.468835) (xy 117.091206 -233.515109) (xy 117.06068 -233.557125) (xy 117.023957 -233.593848)
			(xy 116.981941 -233.624374) (xy 116.935667 -233.647952) (xy 116.886274 -233.664) (xy 116.834979 -233.672125)
			(xy 116.783045 -233.672125) (xy 116.73175 -233.664) (xy 116.682357 -233.647952) (xy 116.636083 -233.624374)
			(xy 116.594067 -233.593848) (xy 116.557344 -233.557125) (xy 116.526818 -233.515109) (xy 116.50324 -233.468835)
			(xy 116.487192 -233.419442) (xy 116.479067 -233.368147) (xy 116.199157 -233.368147) (xy 116.191032 -233.419442)
			(xy 116.174984 -233.468835) (xy 116.151406 -233.515109) (xy 116.12088 -233.557125) (xy 116.084157 -233.593848)
			(xy 116.042141 -233.624374) (xy 115.995867 -233.647952) (xy 115.946474 -233.664) (xy 115.895179 -233.672125)
			(xy 115.843245 -233.672125) (xy 115.79195 -233.664) (xy 115.742557 -233.647952) (xy 115.696283 -233.624374)
			(xy 115.654267 -233.593848) (xy 115.617544 -233.557125) (xy 115.587018 -233.515109) (xy 115.56344 -233.468835)
			(xy 115.547392 -233.419442) (xy 115.539267 -233.368147) (xy 115.259357 -233.368147) (xy 115.251232 -233.419442)
			(xy 115.235184 -233.468835) (xy 115.211606 -233.515109) (xy 115.18108 -233.557125) (xy 115.144357 -233.593848)
			(xy 115.102341 -233.624374) (xy 115.056067 -233.647952) (xy 115.006674 -233.664) (xy 114.955379 -233.672125)
			(xy 114.903445 -233.672125) (xy 114.85215 -233.664) (xy 114.802757 -233.647952) (xy 114.756483 -233.624374)
			(xy 114.714467 -233.593848) (xy 114.677744 -233.557125) (xy 114.647218 -233.515109) (xy 114.62364 -233.468835)
			(xy 114.607592 -233.419442) (xy 114.599467 -233.368147) (xy 114.319811 -233.368147) (xy 114.311686 -233.419442)
			(xy 114.295638 -233.468835) (xy 114.27206 -233.515109) (xy 114.241534 -233.557125) (xy 114.204811 -233.593848)
			(xy 114.162795 -233.624374) (xy 114.116521 -233.647952) (xy 114.067128 -233.664) (xy 114.015833 -233.672125)
			(xy 113.963899 -233.672125) (xy 113.912604 -233.664) (xy 113.863211 -233.647952) (xy 113.816937 -233.624374)
			(xy 113.774921 -233.593848) (xy 113.738198 -233.557125) (xy 113.707672 -233.515109) (xy 113.684094 -233.468835)
			(xy 113.668046 -233.419442) (xy 113.659921 -233.368147) (xy 113.379757 -233.368147) (xy 113.371632 -233.419442)
			(xy 113.355584 -233.468835) (xy 113.332006 -233.515109) (xy 113.30148 -233.557125) (xy 113.264757 -233.593848)
			(xy 113.222741 -233.624374) (xy 113.176467 -233.647952) (xy 113.127074 -233.664) (xy 113.075779 -233.672125)
			(xy 113.023845 -233.672125) (xy 112.97255 -233.664) (xy 112.923157 -233.647952) (xy 112.876883 -233.624374)
			(xy 112.834867 -233.593848) (xy 112.798144 -233.557125) (xy 112.767618 -233.515109) (xy 112.74404 -233.468835)
			(xy 112.727992 -233.419442) (xy 112.719867 -233.368147) (xy 112.439957 -233.368147) (xy 112.431832 -233.419442)
			(xy 112.415784 -233.468835) (xy 112.392206 -233.515109) (xy 112.36168 -233.557125) (xy 112.324957 -233.593848)
			(xy 112.282941 -233.624374) (xy 112.236667 -233.647952) (xy 112.187274 -233.664) (xy 112.135979 -233.672125)
			(xy 112.084045 -233.672125) (xy 112.03275 -233.664) (xy 111.983357 -233.647952) (xy 111.937083 -233.624374)
			(xy 111.895067 -233.593848) (xy 111.858344 -233.557125) (xy 111.827818 -233.515109) (xy 111.80424 -233.468835)
			(xy 111.788192 -233.419442) (xy 111.780067 -233.368147) (xy 111.500157 -233.368147) (xy 111.492032 -233.419442)
			(xy 111.475984 -233.468835) (xy 111.452406 -233.515109) (xy 111.42188 -233.557125) (xy 111.385157 -233.593848)
			(xy 111.343141 -233.624374) (xy 111.296867 -233.647952) (xy 111.247474 -233.664) (xy 111.196179 -233.672125)
			(xy 111.144245 -233.672125) (xy 111.09295 -233.664) (xy 111.043557 -233.647952) (xy 110.997283 -233.624374)
			(xy 110.955267 -233.593848) (xy 110.918544 -233.557125) (xy 110.888018 -233.515109) (xy 110.86444 -233.468835)
			(xy 110.848392 -233.419442) (xy 110.840267 -233.368147) (xy 110.560425 -233.368147) (xy 110.55373 -233.41395)
			(xy 110.539908 -233.46011) (xy 110.530132 -233.482134) (xy 110.525306 -233.492294) (xy 110.525306 -233.730546)
			(xy 110.5258 -233.745322) (xy 110.534252 -233.77364) (xy 110.550461 -233.79835) (xy 110.573071 -233.817381)
			(xy 110.600185 -233.829136) (xy 110.629529 -233.832631) (xy 110.644178 -233.830622) (xy 110.658164 -233.828349)
			(xy 110.686397 -233.825935) (xy 110.700566 -233.825796) (xy 110.726533 -233.826276) (xy 110.777829 -233.834396)
			(xy 110.827222 -233.85044) (xy 110.873498 -233.874014) (xy 110.915515 -233.904538) (xy 110.95224 -233.941259)
			(xy 110.982768 -233.983273) (xy 111.006347 -234.029546) (xy 111.022396 -234.078938) (xy 111.030521 -234.130233)
			(xy 111.030521 -234.182167) (xy 111.030513 -234.182217) (xy 111.310421 -234.182217) (xy 111.310421 -234.130283)
			(xy 111.318546 -234.078988) (xy 111.334594 -234.029595) (xy 111.358172 -233.983321) (xy 111.388698 -233.941305)
			(xy 111.425421 -233.904582) (xy 111.467437 -233.874056) (xy 111.513711 -233.850478) (xy 111.563104 -233.83443)
			(xy 111.614399 -233.826305) (xy 111.666333 -233.826305) (xy 111.717628 -233.83443) (xy 111.767021 -233.850478)
			(xy 111.813295 -233.874056) (xy 111.855311 -233.904582) (xy 111.892034 -233.941305) (xy 111.92256 -233.983321)
			(xy 111.946138 -234.029595) (xy 111.962186 -234.078988) (xy 111.970311 -234.130283) (xy 111.97082 -234.15625)
			(xy 111.970311 -234.182217) (xy 112.250221 -234.182217) (xy 112.250221 -234.130283) (xy 112.258346 -234.078988)
			(xy 112.274394 -234.029595) (xy 112.297972 -233.983321) (xy 112.328498 -233.941305) (xy 112.365221 -233.904582)
			(xy 112.407237 -233.874056) (xy 112.453511 -233.850478) (xy 112.502904 -233.83443) (xy 112.554199 -233.826305)
			(xy 112.606133 -233.826305) (xy 112.657428 -233.83443) (xy 112.706821 -233.850478) (xy 112.753095 -233.874056)
			(xy 112.795111 -233.904582) (xy 112.831834 -233.941305) (xy 112.86236 -233.983321) (xy 112.885938 -234.029595)
			(xy 112.901986 -234.078988) (xy 112.910111 -234.130283) (xy 112.91062 -234.15625) (xy 112.910111 -234.182217)
			(xy 113.190021 -234.182217) (xy 113.190021 -234.130283) (xy 113.198146 -234.078988) (xy 113.214194 -234.029595)
			(xy 113.237772 -233.983321) (xy 113.268298 -233.941305) (xy 113.305021 -233.904582) (xy 113.347037 -233.874056)
			(xy 113.393311 -233.850478) (xy 113.442704 -233.83443) (xy 113.493999 -233.826305) (xy 113.545933 -233.826305)
			(xy 113.597228 -233.83443) (xy 113.646621 -233.850478) (xy 113.692895 -233.874056) (xy 113.734911 -233.904582)
			(xy 113.771634 -233.941305) (xy 113.80216 -233.983321) (xy 113.825738 -234.029595) (xy 113.841786 -234.078988)
			(xy 113.849911 -234.130283) (xy 113.85042 -234.15625) (xy 113.849911 -234.182217) (xy 114.129821 -234.182217)
			(xy 114.129821 -234.130283) (xy 114.137946 -234.078988) (xy 114.153994 -234.029595) (xy 114.177572 -233.983321)
			(xy 114.208098 -233.941305) (xy 114.244821 -233.904582) (xy 114.286837 -233.874056) (xy 114.333111 -233.850478)
			(xy 114.382504 -233.83443) (xy 114.433799 -233.826305) (xy 114.485733 -233.826305) (xy 114.537028 -233.83443)
			(xy 114.586421 -233.850478) (xy 114.632695 -233.874056) (xy 114.674711 -233.904582) (xy 114.711434 -233.941305)
			(xy 114.74196 -233.983321) (xy 114.765538 -234.029595) (xy 114.781586 -234.078988) (xy 114.789711 -234.130283)
			(xy 114.79022 -234.15625) (xy 114.789711 -234.182217) (xy 115.069621 -234.182217) (xy 115.069621 -234.130283)
			(xy 115.077746 -234.078988) (xy 115.093794 -234.029595) (xy 115.117372 -233.983321) (xy 115.147898 -233.941305)
			(xy 115.184621 -233.904582) (xy 115.226637 -233.874056) (xy 115.272911 -233.850478) (xy 115.322304 -233.83443)
			(xy 115.373599 -233.826305) (xy 115.425533 -233.826305) (xy 115.476828 -233.83443) (xy 115.526221 -233.850478)
			(xy 115.572495 -233.874056) (xy 115.614511 -233.904582) (xy 115.651234 -233.941305) (xy 115.68176 -233.983321)
			(xy 115.705338 -234.029595) (xy 115.721386 -234.078988) (xy 115.729511 -234.130283) (xy 115.73002 -234.15625)
			(xy 115.729511 -234.182217) (xy 116.009421 -234.182217) (xy 116.009421 -234.130283) (xy 116.017546 -234.078988)
			(xy 116.033594 -234.029595) (xy 116.057172 -233.983321) (xy 116.087698 -233.941305) (xy 116.124421 -233.904582)
			(xy 116.166437 -233.874056) (xy 116.212711 -233.850478) (xy 116.262104 -233.83443) (xy 116.313399 -233.826305)
			(xy 116.365333 -233.826305) (xy 116.416628 -233.83443) (xy 116.466021 -233.850478) (xy 116.512295 -233.874056)
			(xy 116.554311 -233.904582) (xy 116.591034 -233.941305) (xy 116.62156 -233.983321) (xy 116.645138 -234.029595)
			(xy 116.661186 -234.078988) (xy 116.669311 -234.130283) (xy 116.66982 -234.15625) (xy 116.669311 -234.182217)
			(xy 116.949221 -234.182217) (xy 116.949221 -234.130283) (xy 116.957346 -234.078988) (xy 116.973394 -234.029595)
			(xy 116.996972 -233.983321) (xy 117.027498 -233.941305) (xy 117.064221 -233.904582) (xy 117.106237 -233.874056)
			(xy 117.152511 -233.850478) (xy 117.201904 -233.83443) (xy 117.253199 -233.826305) (xy 117.305133 -233.826305)
			(xy 117.356428 -233.83443) (xy 117.405821 -233.850478) (xy 117.452095 -233.874056) (xy 117.494111 -233.904582)
			(xy 117.530834 -233.941305) (xy 117.56136 -233.983321) (xy 117.584938 -234.029595) (xy 117.600986 -234.078988)
			(xy 117.609111 -234.130283) (xy 117.60962 -234.15625) (xy 117.609111 -234.182217) (xy 117.889021 -234.182217)
			(xy 117.889021 -234.130283) (xy 117.897146 -234.078988) (xy 117.913194 -234.029595) (xy 117.936772 -233.983321)
			(xy 117.967298 -233.941305) (xy 118.004021 -233.904582) (xy 118.046037 -233.874056) (xy 118.092311 -233.850478)
			(xy 118.141704 -233.83443) (xy 118.192999 -233.826305) (xy 118.244933 -233.826305) (xy 118.296228 -233.83443)
			(xy 118.345621 -233.850478) (xy 118.391895 -233.874056) (xy 118.433911 -233.904582) (xy 118.470634 -233.941305)
			(xy 118.50116 -233.983321) (xy 118.524738 -234.029595) (xy 118.540786 -234.078988) (xy 118.548911 -234.130283)
			(xy 118.54942 -234.15625) (xy 118.548911 -234.182217) (xy 118.828821 -234.182217) (xy 118.828821 -234.130283)
			(xy 118.836946 -234.078988) (xy 118.852994 -234.029595) (xy 118.876572 -233.983321) (xy 118.907098 -233.941305)
			(xy 118.943821 -233.904582) (xy 118.985837 -233.874056) (xy 119.032111 -233.850478) (xy 119.081504 -233.83443)
			(xy 119.132799 -233.826305) (xy 119.184733 -233.826305) (xy 119.236028 -233.83443) (xy 119.285421 -233.850478)
			(xy 119.331695 -233.874056) (xy 119.373711 -233.904582) (xy 119.410434 -233.941305) (xy 119.44096 -233.983321)
			(xy 119.464538 -234.029595) (xy 119.480586 -234.078988) (xy 119.488711 -234.130283) (xy 119.48922 -234.15625)
			(xy 119.488711 -234.182217) (xy 119.768621 -234.182217) (xy 119.768621 -234.130283) (xy 119.776746 -234.078988)
			(xy 119.792794 -234.029595) (xy 119.816372 -233.983321) (xy 119.846898 -233.941305) (xy 119.883621 -233.904582)
			(xy 119.925637 -233.874056) (xy 119.971911 -233.850478) (xy 120.021304 -233.83443) (xy 120.072599 -233.826305)
			(xy 120.124533 -233.826305) (xy 120.175828 -233.83443) (xy 120.225221 -233.850478) (xy 120.271495 -233.874056)
			(xy 120.313511 -233.904582) (xy 120.350234 -233.941305) (xy 120.38076 -233.983321) (xy 120.404338 -234.029595)
			(xy 120.420386 -234.078988) (xy 120.428511 -234.130283) (xy 120.42902 -234.15625) (xy 120.428511 -234.182217)
			(xy 120.708167 -234.182217) (xy 120.708167 -234.130283) (xy 120.716292 -234.078988) (xy 120.73234 -234.029595)
			(xy 120.755918 -233.983321) (xy 120.786444 -233.941305) (xy 120.823167 -233.904582) (xy 120.865183 -233.874056)
			(xy 120.911457 -233.850478) (xy 120.96085 -233.83443) (xy 121.012145 -233.826305) (xy 121.064079 -233.826305)
			(xy 121.115374 -233.83443) (xy 121.164767 -233.850478) (xy 121.211041 -233.874056) (xy 121.253057 -233.904582)
			(xy 121.28978 -233.941305) (xy 121.320306 -233.983321) (xy 121.343884 -234.029595) (xy 121.359932 -234.078988)
			(xy 121.368057 -234.130283) (xy 121.368566 -234.15625) (xy 121.368057 -234.182217) (xy 121.648221 -234.182217)
			(xy 121.648221 -234.130283) (xy 121.656346 -234.078988) (xy 121.672394 -234.029595) (xy 121.695972 -233.983321)
			(xy 121.726498 -233.941305) (xy 121.763221 -233.904582) (xy 121.805237 -233.874056) (xy 121.851511 -233.850478)
			(xy 121.900904 -233.83443) (xy 121.952199 -233.826305) (xy 122.004133 -233.826305) (xy 122.055428 -233.83443)
			(xy 122.104821 -233.850478) (xy 122.151095 -233.874056) (xy 122.193111 -233.904582) (xy 122.229834 -233.941305)
			(xy 122.26036 -233.983321) (xy 122.283938 -234.029595) (xy 122.299986 -234.078988) (xy 122.308111 -234.130283)
			(xy 122.30862 -234.15625) (xy 122.308111 -234.182217) (xy 122.299986 -234.233512) (xy 122.283938 -234.282905)
			(xy 122.26036 -234.329179) (xy 122.229834 -234.371195) (xy 122.193111 -234.407918) (xy 122.151095 -234.438444)
			(xy 122.104821 -234.462022) (xy 122.055428 -234.47807) (xy 122.004133 -234.486195) (xy 121.952199 -234.486195)
			(xy 121.900904 -234.47807) (xy 121.851511 -234.462022) (xy 121.805237 -234.438444) (xy 121.763221 -234.407918)
			(xy 121.726498 -234.371195) (xy 121.695972 -234.329179) (xy 121.672394 -234.282905) (xy 121.656346 -234.233512)
			(xy 121.648221 -234.182217) (xy 121.368057 -234.182217) (xy 121.359932 -234.233512) (xy 121.343884 -234.282905)
			(xy 121.320306 -234.329179) (xy 121.28978 -234.371195) (xy 121.253057 -234.407918) (xy 121.211041 -234.438444)
			(xy 121.164767 -234.462022) (xy 121.115374 -234.47807) (xy 121.064079 -234.486195) (xy 121.012145 -234.486195)
			(xy 120.96085 -234.47807) (xy 120.911457 -234.462022) (xy 120.865183 -234.438444) (xy 120.823167 -234.407918)
			(xy 120.786444 -234.371195) (xy 120.755918 -234.329179) (xy 120.73234 -234.282905) (xy 120.716292 -234.233512)
			(xy 120.708167 -234.182217) (xy 120.428511 -234.182217) (xy 120.420386 -234.233512) (xy 120.404338 -234.282905)
			(xy 120.38076 -234.329179) (xy 120.350234 -234.371195) (xy 120.313511 -234.407918) (xy 120.271495 -234.438444)
			(xy 120.225221 -234.462022) (xy 120.175828 -234.47807) (xy 120.124533 -234.486195) (xy 120.072599 -234.486195)
			(xy 120.021304 -234.47807) (xy 119.971911 -234.462022) (xy 119.925637 -234.438444) (xy 119.883621 -234.407918)
			(xy 119.846898 -234.371195) (xy 119.816372 -234.329179) (xy 119.792794 -234.282905) (xy 119.776746 -234.233512)
			(xy 119.768621 -234.182217) (xy 119.488711 -234.182217) (xy 119.480586 -234.233512) (xy 119.464538 -234.282905)
			(xy 119.44096 -234.329179) (xy 119.410434 -234.371195) (xy 119.373711 -234.407918) (xy 119.331695 -234.438444)
			(xy 119.285421 -234.462022) (xy 119.236028 -234.47807) (xy 119.184733 -234.486195) (xy 119.132799 -234.486195)
			(xy 119.081504 -234.47807) (xy 119.032111 -234.462022) (xy 118.985837 -234.438444) (xy 118.943821 -234.407918)
			(xy 118.907098 -234.371195) (xy 118.876572 -234.329179) (xy 118.852994 -234.282905) (xy 118.836946 -234.233512)
			(xy 118.828821 -234.182217) (xy 118.548911 -234.182217) (xy 118.540786 -234.233512) (xy 118.524738 -234.282905)
			(xy 118.50116 -234.329179) (xy 118.470634 -234.371195) (xy 118.433911 -234.407918) (xy 118.391895 -234.438444)
			(xy 118.345621 -234.462022) (xy 118.296228 -234.47807) (xy 118.244933 -234.486195) (xy 118.192999 -234.486195)
			(xy 118.141704 -234.47807) (xy 118.092311 -234.462022) (xy 118.046037 -234.438444) (xy 118.004021 -234.407918)
			(xy 117.967298 -234.371195) (xy 117.936772 -234.329179) (xy 117.913194 -234.282905) (xy 117.897146 -234.233512)
			(xy 117.889021 -234.182217) (xy 117.609111 -234.182217) (xy 117.600986 -234.233512) (xy 117.584938 -234.282905)
			(xy 117.56136 -234.329179) (xy 117.530834 -234.371195) (xy 117.494111 -234.407918) (xy 117.452095 -234.438444)
			(xy 117.405821 -234.462022) (xy 117.356428 -234.47807) (xy 117.305133 -234.486195) (xy 117.253199 -234.486195)
			(xy 117.201904 -234.47807) (xy 117.152511 -234.462022) (xy 117.106237 -234.438444) (xy 117.064221 -234.407918)
			(xy 117.027498 -234.371195) (xy 116.996972 -234.329179) (xy 116.973394 -234.282905) (xy 116.957346 -234.233512)
			(xy 116.949221 -234.182217) (xy 116.669311 -234.182217) (xy 116.661186 -234.233512) (xy 116.645138 -234.282905)
			(xy 116.62156 -234.329179) (xy 116.591034 -234.371195) (xy 116.554311 -234.407918) (xy 116.512295 -234.438444)
			(xy 116.466021 -234.462022) (xy 116.416628 -234.47807) (xy 116.365333 -234.486195) (xy 116.313399 -234.486195)
			(xy 116.262104 -234.47807) (xy 116.212711 -234.462022) (xy 116.166437 -234.438444) (xy 116.124421 -234.407918)
			(xy 116.087698 -234.371195) (xy 116.057172 -234.329179) (xy 116.033594 -234.282905) (xy 116.017546 -234.233512)
			(xy 116.009421 -234.182217) (xy 115.729511 -234.182217) (xy 115.721386 -234.233512) (xy 115.705338 -234.282905)
			(xy 115.68176 -234.329179) (xy 115.651234 -234.371195) (xy 115.614511 -234.407918) (xy 115.572495 -234.438444)
			(xy 115.526221 -234.462022) (xy 115.476828 -234.47807) (xy 115.425533 -234.486195) (xy 115.373599 -234.486195)
			(xy 115.322304 -234.47807) (xy 115.272911 -234.462022) (xy 115.226637 -234.438444) (xy 115.184621 -234.407918)
			(xy 115.147898 -234.371195) (xy 115.117372 -234.329179) (xy 115.093794 -234.282905) (xy 115.077746 -234.233512)
			(xy 115.069621 -234.182217) (xy 114.789711 -234.182217) (xy 114.781586 -234.233512) (xy 114.765538 -234.282905)
			(xy 114.74196 -234.329179) (xy 114.711434 -234.371195) (xy 114.674711 -234.407918) (xy 114.632695 -234.438444)
			(xy 114.586421 -234.462022) (xy 114.537028 -234.47807) (xy 114.485733 -234.486195) (xy 114.433799 -234.486195)
			(xy 114.382504 -234.47807) (xy 114.333111 -234.462022) (xy 114.286837 -234.438444) (xy 114.244821 -234.407918)
			(xy 114.208098 -234.371195) (xy 114.177572 -234.329179) (xy 114.153994 -234.282905) (xy 114.137946 -234.233512)
			(xy 114.129821 -234.182217) (xy 113.849911 -234.182217) (xy 113.841786 -234.233512) (xy 113.825738 -234.282905)
			(xy 113.80216 -234.329179) (xy 113.771634 -234.371195) (xy 113.734911 -234.407918) (xy 113.692895 -234.438444)
			(xy 113.646621 -234.462022) (xy 113.597228 -234.47807) (xy 113.545933 -234.486195) (xy 113.493999 -234.486195)
			(xy 113.442704 -234.47807) (xy 113.393311 -234.462022) (xy 113.347037 -234.438444) (xy 113.305021 -234.407918)
			(xy 113.268298 -234.371195) (xy 113.237772 -234.329179) (xy 113.214194 -234.282905) (xy 113.198146 -234.233512)
			(xy 113.190021 -234.182217) (xy 112.910111 -234.182217) (xy 112.901986 -234.233512) (xy 112.885938 -234.282905)
			(xy 112.86236 -234.329179) (xy 112.831834 -234.371195) (xy 112.795111 -234.407918) (xy 112.753095 -234.438444)
			(xy 112.706821 -234.462022) (xy 112.657428 -234.47807) (xy 112.606133 -234.486195) (xy 112.554199 -234.486195)
			(xy 112.502904 -234.47807) (xy 112.453511 -234.462022) (xy 112.407237 -234.438444) (xy 112.365221 -234.407918)
			(xy 112.328498 -234.371195) (xy 112.297972 -234.329179) (xy 112.274394 -234.282905) (xy 112.258346 -234.233512)
			(xy 112.250221 -234.182217) (xy 111.970311 -234.182217) (xy 111.962186 -234.233512) (xy 111.946138 -234.282905)
			(xy 111.92256 -234.329179) (xy 111.892034 -234.371195) (xy 111.855311 -234.407918) (xy 111.813295 -234.438444)
			(xy 111.767021 -234.462022) (xy 111.717628 -234.47807) (xy 111.666333 -234.486195) (xy 111.614399 -234.486195)
			(xy 111.563104 -234.47807) (xy 111.513711 -234.462022) (xy 111.467437 -234.438444) (xy 111.425421 -234.407918)
			(xy 111.388698 -234.371195) (xy 111.358172 -234.329179) (xy 111.334594 -234.282905) (xy 111.318546 -234.233512)
			(xy 111.310421 -234.182217) (xy 111.030513 -234.182217) (xy 111.022396 -234.233462) (xy 111.006347 -234.282854)
			(xy 110.982768 -234.329127) (xy 110.95224 -234.371141) (xy 110.915515 -234.407862) (xy 110.873498 -234.438386)
			(xy 110.827222 -234.46196) (xy 110.777829 -234.478004) (xy 110.726533 -234.486124) (xy 110.700566 -234.486704)
			(xy 110.686398 -234.486552) (xy 110.658166 -234.484135) (xy 110.644178 -234.481878) (xy 110.629534 -234.479858)
			(xy 110.600196 -234.483375) (xy 110.573092 -234.495141) (xy 110.550487 -234.51417) (xy 110.534273 -234.538872)
			(xy 110.525805 -234.56718) (xy 110.525306 -234.581954) (xy 110.525306 -234.819444) (xy 110.530132 -234.829858)
			(xy 110.540008 -234.851898) (xy 110.553932 -234.898142) (xy 110.560972 -234.945922) (xy 110.560976 -234.994217)
			(xy 110.560709 -234.996033) (xy 110.840521 -234.996033) (xy 110.840521 -234.944099) (xy 110.848646 -234.892804)
			(xy 110.864694 -234.843411) (xy 110.888272 -234.797137) (xy 110.918798 -234.755121) (xy 110.955521 -234.718398)
			(xy 110.997537 -234.687872) (xy 111.043811 -234.664294) (xy 111.093204 -234.648246) (xy 111.144499 -234.640121)
			(xy 111.196433 -234.640121) (xy 111.247728 -234.648246) (xy 111.297121 -234.664294) (xy 111.343395 -234.687872)
			(xy 111.385411 -234.718398) (xy 111.422134 -234.755121) (xy 111.45266 -234.797137) (xy 111.476238 -234.843411)
			(xy 111.492286 -234.892804) (xy 111.500411 -234.944099) (xy 111.50092 -234.970066) (xy 111.500411 -234.996033)
			(xy 111.780321 -234.996033) (xy 111.780321 -234.944099) (xy 111.788446 -234.892804) (xy 111.804494 -234.843411)
			(xy 111.828072 -234.797137) (xy 111.858598 -234.755121) (xy 111.895321 -234.718398) (xy 111.937337 -234.687872)
			(xy 111.983611 -234.664294) (xy 112.033004 -234.648246) (xy 112.084299 -234.640121) (xy 112.136233 -234.640121)
			(xy 112.187528 -234.648246) (xy 112.236921 -234.664294) (xy 112.283195 -234.687872) (xy 112.325211 -234.718398)
			(xy 112.361934 -234.755121) (xy 112.39246 -234.797137) (xy 112.416038 -234.843411) (xy 112.432086 -234.892804)
			(xy 112.440211 -234.944099) (xy 112.44072 -234.970066) (xy 112.440211 -234.996033) (xy 112.720121 -234.996033)
			(xy 112.720121 -234.944099) (xy 112.728246 -234.892804) (xy 112.744294 -234.843411) (xy 112.767872 -234.797137)
			(xy 112.798398 -234.755121) (xy 112.835121 -234.718398) (xy 112.877137 -234.687872) (xy 112.923411 -234.664294)
			(xy 112.972804 -234.648246) (xy 113.024099 -234.640121) (xy 113.076033 -234.640121) (xy 113.127328 -234.648246)
			(xy 113.176721 -234.664294) (xy 113.222995 -234.687872) (xy 113.265011 -234.718398) (xy 113.301734 -234.755121)
			(xy 113.33226 -234.797137) (xy 113.355838 -234.843411) (xy 113.371886 -234.892804) (xy 113.380011 -234.944099)
			(xy 113.38052 -234.970066) (xy 113.380011 -234.996033) (xy 113.660175 -234.996033) (xy 113.660175 -234.944099)
			(xy 113.6683 -234.892804) (xy 113.684348 -234.843411) (xy 113.707926 -234.797137) (xy 113.738452 -234.755121)
			(xy 113.775175 -234.718398) (xy 113.817191 -234.687872) (xy 113.863465 -234.664294) (xy 113.912858 -234.648246)
			(xy 113.964153 -234.640121) (xy 114.016087 -234.640121) (xy 114.067382 -234.648246) (xy 114.116775 -234.664294)
			(xy 114.163049 -234.687872) (xy 114.205065 -234.718398) (xy 114.241788 -234.755121) (xy 114.272314 -234.797137)
			(xy 114.295892 -234.843411) (xy 114.31194 -234.892804) (xy 114.320065 -234.944099) (xy 114.320574 -234.970066)
			(xy 114.320065 -234.996033) (xy 121.178067 -234.996033) (xy 121.178067 -234.944099) (xy 121.186192 -234.892804)
			(xy 121.20224 -234.843411) (xy 121.225818 -234.797137) (xy 121.256344 -234.755121) (xy 121.293067 -234.718398)
			(xy 121.335083 -234.687872) (xy 121.381357 -234.664294) (xy 121.43075 -234.648246) (xy 121.482045 -234.640121)
			(xy 121.533979 -234.640121) (xy 121.585274 -234.648246) (xy 121.634667 -234.664294) (xy 121.680941 -234.687872)
			(xy 121.722957 -234.718398) (xy 121.75968 -234.755121) (xy 121.790206 -234.797137) (xy 121.813784 -234.843411)
			(xy 121.829832 -234.892804) (xy 121.837957 -234.944099) (xy 121.838466 -234.970066) (xy 121.837957 -234.996033)
			(xy 122.117867 -234.996033) (xy 122.117867 -234.944099) (xy 122.125992 -234.892804) (xy 122.14204 -234.843411)
			(xy 122.165618 -234.797137) (xy 122.196144 -234.755121) (xy 122.232867 -234.718398) (xy 122.274883 -234.687872)
			(xy 122.321157 -234.664294) (xy 122.37055 -234.648246) (xy 122.421845 -234.640121) (xy 122.473779 -234.640121)
			(xy 122.525074 -234.648246) (xy 122.574467 -234.664294) (xy 122.620741 -234.687872) (xy 122.662757 -234.718398)
			(xy 122.69948 -234.755121) (xy 122.730006 -234.797137) (xy 122.753584 -234.843411) (xy 122.769632 -234.892804)
			(xy 122.777757 -234.944099) (xy 122.778266 -234.970066) (xy 122.777757 -234.996033) (xy 122.769632 -235.047328)
			(xy 122.753584 -235.096721) (xy 122.730006 -235.142995) (xy 122.69948 -235.185011) (xy 122.662757 -235.221734)
			(xy 122.620741 -235.25226) (xy 122.574467 -235.275838) (xy 122.525074 -235.291886) (xy 122.473779 -235.300011)
			(xy 122.421845 -235.300011) (xy 122.37055 -235.291886) (xy 122.321157 -235.275838) (xy 122.274883 -235.25226)
			(xy 122.232867 -235.221734) (xy 122.196144 -235.185011) (xy 122.165618 -235.142995) (xy 122.14204 -235.096721)
			(xy 122.125992 -235.047328) (xy 122.117867 -234.996033) (xy 121.837957 -234.996033) (xy 121.829832 -235.047328)
			(xy 121.813784 -235.096721) (xy 121.790206 -235.142995) (xy 121.75968 -235.185011) (xy 121.722957 -235.221734)
			(xy 121.680941 -235.25226) (xy 121.634667 -235.275838) (xy 121.585274 -235.291886) (xy 121.533979 -235.300011)
			(xy 121.482045 -235.300011) (xy 121.43075 -235.291886) (xy 121.381357 -235.275838) (xy 121.335083 -235.25226)
			(xy 121.293067 -235.221734) (xy 121.256344 -235.185011) (xy 121.225818 -235.142995) (xy 121.20224 -235.096721)
			(xy 121.186192 -235.047328) (xy 121.178067 -234.996033) (xy 114.320065 -234.996033) (xy 114.31194 -235.047328)
			(xy 114.295892 -235.096721) (xy 114.272314 -235.142995) (xy 114.241788 -235.185011) (xy 114.205065 -235.221734)
			(xy 114.163049 -235.25226) (xy 114.116775 -235.275838) (xy 114.067382 -235.291886) (xy 114.016087 -235.300011)
			(xy 113.964153 -235.300011) (xy 113.912858 -235.291886) (xy 113.863465 -235.275838) (xy 113.817191 -235.25226)
			(xy 113.775175 -235.221734) (xy 113.738452 -235.185011) (xy 113.707926 -235.142995) (xy 113.684348 -235.096721)
			(xy 113.6683 -235.047328) (xy 113.660175 -234.996033) (xy 113.380011 -234.996033) (xy 113.371886 -235.047328)
			(xy 113.355838 -235.096721) (xy 113.33226 -235.142995) (xy 113.301734 -235.185011) (xy 113.265011 -235.221734)
			(xy 113.222995 -235.25226) (xy 113.176721 -235.275838) (xy 113.127328 -235.291886) (xy 113.076033 -235.300011)
			(xy 113.024099 -235.300011) (xy 112.972804 -235.291886) (xy 112.923411 -235.275838) (xy 112.877137 -235.25226)
			(xy 112.835121 -235.221734) (xy 112.798398 -235.185011) (xy 112.767872 -235.142995) (xy 112.744294 -235.096721)
			(xy 112.728246 -235.047328) (xy 112.720121 -234.996033) (xy 112.440211 -234.996033) (xy 112.432086 -235.047328)
			(xy 112.416038 -235.096721) (xy 112.39246 -235.142995) (xy 112.361934 -235.185011) (xy 112.325211 -235.221734)
			(xy 112.283195 -235.25226) (xy 112.236921 -235.275838) (xy 112.187528 -235.291886) (xy 112.136233 -235.300011)
			(xy 112.084299 -235.300011) (xy 112.033004 -235.291886) (xy 111.983611 -235.275838) (xy 111.937337 -235.25226)
			(xy 111.895321 -235.221734) (xy 111.858598 -235.185011) (xy 111.828072 -235.142995) (xy 111.804494 -235.096721)
			(xy 111.788446 -235.047328) (xy 111.780321 -234.996033) (xy 111.500411 -234.996033) (xy 111.492286 -235.047328)
			(xy 111.476238 -235.096721) (xy 111.45266 -235.142995) (xy 111.422134 -235.185011) (xy 111.385411 -235.221734)
			(xy 111.343395 -235.25226) (xy 111.297121 -235.275838) (xy 111.247728 -235.291886) (xy 111.196433 -235.300011)
			(xy 111.144499 -235.300011) (xy 111.093204 -235.291886) (xy 111.043811 -235.275838) (xy 110.997537 -235.25226)
			(xy 110.955521 -235.221734) (xy 110.918798 -235.185011) (xy 110.888272 -235.142995) (xy 110.864694 -235.096721)
			(xy 110.848646 -235.047328) (xy 110.840521 -234.996033) (xy 110.560709 -234.996033) (xy 110.553946 -235.041998)
			(xy 110.54003 -235.088245) (xy 110.530132 -235.110274) (xy 110.525306 -235.120688) (xy 110.525306 -235.358178)
			(xy 110.525805 -235.372951) (xy 110.534261 -235.401261) (xy 110.550472 -235.425963) (xy 110.57308 -235.444986)
			(xy 110.600188 -235.456737) (xy 110.629527 -235.460231) (xy 110.644178 -235.458254) (xy 110.658227 -235.455973)
			(xy 110.686588 -235.453559) (xy 110.70082 -235.453428) (xy 110.726787 -235.453939) (xy 110.77808 -235.462065)
			(xy 110.827471 -235.478116) (xy 110.873744 -235.501694) (xy 110.915758 -235.53222) (xy 110.952481 -235.568943)
			(xy 110.983007 -235.610958) (xy 111.006585 -235.65723) (xy 111.022635 -235.706622) (xy 111.030761 -235.757915)
			(xy 111.031274 -235.783882) (xy 111.030737 -235.809849) (xy 111.310675 -235.809849) (xy 111.310675 -235.757915)
			(xy 111.3188 -235.70662) (xy 111.334848 -235.657227) (xy 111.358426 -235.610953) (xy 111.388952 -235.568937)
			(xy 111.425675 -235.532214) (xy 111.467691 -235.501688) (xy 111.513965 -235.47811) (xy 111.563358 -235.462062)
			(xy 111.614653 -235.453937) (xy 111.666587 -235.453937) (xy 111.717882 -235.462062) (xy 111.767275 -235.47811)
			(xy 111.813549 -235.501688) (xy 111.855565 -235.532214) (xy 111.892288 -235.568937) (xy 111.922814 -235.610953)
			(xy 111.946392 -235.657227) (xy 111.96244 -235.70662) (xy 111.970565 -235.757915) (xy 111.971074 -235.783882)
			(xy 111.970565 -235.809849) (xy 112.250475 -235.809849) (xy 112.250475 -235.757915) (xy 112.2586 -235.70662)
			(xy 112.274648 -235.657227) (xy 112.298226 -235.610953) (xy 112.328752 -235.568937) (xy 112.365475 -235.532214)
			(xy 112.407491 -235.501688) (xy 112.453765 -235.47811) (xy 112.503158 -235.462062) (xy 112.554453 -235.453937)
			(xy 112.606387 -235.453937) (xy 112.657682 -235.462062) (xy 112.707075 -235.47811) (xy 112.753349 -235.501688)
			(xy 112.795365 -235.532214) (xy 112.832088 -235.568937) (xy 112.862614 -235.610953) (xy 112.886192 -235.657227)
			(xy 112.90224 -235.70662) (xy 112.910365 -235.757915) (xy 112.910874 -235.783882) (xy 112.910365 -235.809849)
			(xy 113.190275 -235.809849) (xy 113.190275 -235.757915) (xy 113.1984 -235.70662) (xy 113.214448 -235.657227)
			(xy 113.238026 -235.610953) (xy 113.268552 -235.568937) (xy 113.305275 -235.532214) (xy 113.347291 -235.501688)
			(xy 113.393565 -235.47811) (xy 113.442958 -235.462062) (xy 113.494253 -235.453937) (xy 113.546187 -235.453937)
			(xy 113.597482 -235.462062) (xy 113.646875 -235.47811) (xy 113.693149 -235.501688) (xy 113.735165 -235.532214)
			(xy 113.771888 -235.568937) (xy 113.802414 -235.610953) (xy 113.825992 -235.657227) (xy 113.84204 -235.70662)
			(xy 113.850165 -235.757915) (xy 113.850674 -235.783882) (xy 113.850165 -235.809849) (xy 114.130075 -235.809849)
			(xy 114.130075 -235.757915) (xy 114.1382 -235.70662) (xy 114.154248 -235.657227) (xy 114.177826 -235.610953)
			(xy 114.208352 -235.568937) (xy 114.245075 -235.532214) (xy 114.287091 -235.501688) (xy 114.333365 -235.47811)
			(xy 114.382758 -235.462062) (xy 114.434053 -235.453937) (xy 114.485987 -235.453937) (xy 114.537282 -235.462062)
			(xy 114.586675 -235.47811) (xy 114.632949 -235.501688) (xy 114.674965 -235.532214) (xy 114.711688 -235.568937)
			(xy 114.742214 -235.610953) (xy 114.765792 -235.657227) (xy 114.78184 -235.70662) (xy 114.789965 -235.757915)
			(xy 114.790474 -235.783882) (xy 114.789965 -235.809849) (xy 121.648221 -235.809849) (xy 121.648221 -235.757915)
			(xy 121.656346 -235.70662) (xy 121.672394 -235.657227) (xy 121.695972 -235.610953) (xy 121.726498 -235.568937)
			(xy 121.763221 -235.532214) (xy 121.805237 -235.501688) (xy 121.851511 -235.47811) (xy 121.900904 -235.462062)
			(xy 121.952199 -235.453937) (xy 122.004133 -235.453937) (xy 122.055428 -235.462062) (xy 122.104821 -235.47811)
			(xy 122.151095 -235.501688) (xy 122.193111 -235.532214) (xy 122.229834 -235.568937) (xy 122.26036 -235.610953)
			(xy 122.283938 -235.657227) (xy 122.299986 -235.70662) (xy 122.308111 -235.757915) (xy 122.30862 -235.783882)
			(xy 122.308111 -235.809849) (xy 122.299986 -235.861144) (xy 122.283938 -235.910537) (xy 122.26036 -235.956811)
			(xy 122.229834 -235.998827) (xy 122.193111 -236.03555) (xy 122.151095 -236.066076) (xy 122.104821 -236.089654)
			(xy 122.055428 -236.105702) (xy 122.004133 -236.113827) (xy 121.952199 -236.113827) (xy 121.900904 -236.105702)
			(xy 121.851511 -236.089654) (xy 121.805237 -236.066076) (xy 121.763221 -236.03555) (xy 121.726498 -235.998827)
			(xy 121.695972 -235.956811) (xy 121.672394 -235.910537) (xy 121.656346 -235.861144) (xy 121.648221 -235.809849)
			(xy 114.789965 -235.809849) (xy 114.78184 -235.861144) (xy 114.765792 -235.910537) (xy 114.742214 -235.956811)
			(xy 114.711688 -235.998827) (xy 114.674965 -236.03555) (xy 114.632949 -236.066076) (xy 114.586675 -236.089654)
			(xy 114.537282 -236.105702) (xy 114.485987 -236.113827) (xy 114.434053 -236.113827) (xy 114.382758 -236.105702)
			(xy 114.333365 -236.089654) (xy 114.287091 -236.066076) (xy 114.245075 -236.03555) (xy 114.208352 -235.998827)
			(xy 114.177826 -235.956811) (xy 114.154248 -235.910537) (xy 114.1382 -235.861144) (xy 114.130075 -235.809849)
			(xy 113.850165 -235.809849) (xy 113.84204 -235.861144) (xy 113.825992 -235.910537) (xy 113.802414 -235.956811)
			(xy 113.771888 -235.998827) (xy 113.735165 -236.03555) (xy 113.693149 -236.066076) (xy 113.646875 -236.089654)
			(xy 113.597482 -236.105702) (xy 113.546187 -236.113827) (xy 113.494253 -236.113827) (xy 113.442958 -236.105702)
			(xy 113.393565 -236.089654) (xy 113.347291 -236.066076) (xy 113.305275 -236.03555) (xy 113.268552 -235.998827)
			(xy 113.238026 -235.956811) (xy 113.214448 -235.910537) (xy 113.1984 -235.861144) (xy 113.190275 -235.809849)
			(xy 112.910365 -235.809849) (xy 112.90224 -235.861144) (xy 112.886192 -235.910537) (xy 112.862614 -235.956811)
			(xy 112.832088 -235.998827) (xy 112.795365 -236.03555) (xy 112.753349 -236.066076) (xy 112.707075 -236.089654)
			(xy 112.657682 -236.105702) (xy 112.606387 -236.113827) (xy 112.554453 -236.113827) (xy 112.503158 -236.105702)
			(xy 112.453765 -236.089654) (xy 112.407491 -236.066076) (xy 112.365475 -236.03555) (xy 112.328752 -235.998827)
			(xy 112.298226 -235.956811) (xy 112.274648 -235.910537) (xy 112.2586 -235.861144) (xy 112.250475 -235.809849)
			(xy 111.970565 -235.809849) (xy 111.96244 -235.861144) (xy 111.946392 -235.910537) (xy 111.922814 -235.956811)
			(xy 111.892288 -235.998827) (xy 111.855565 -236.03555) (xy 111.813549 -236.066076) (xy 111.767275 -236.089654)
			(xy 111.717882 -236.105702) (xy 111.666587 -236.113827) (xy 111.614653 -236.113827) (xy 111.563358 -236.105702)
			(xy 111.513965 -236.089654) (xy 111.467691 -236.066076) (xy 111.425675 -236.03555) (xy 111.388952 -235.998827)
			(xy 111.358426 -235.956811) (xy 111.334848 -235.910537) (xy 111.3188 -235.861144) (xy 111.310675 -235.809849)
			(xy 111.030737 -235.809849) (xy 111.030697 -235.811778) (xy 111.02134 -235.86678) (xy 111.002888 -235.919433)
			(xy 110.975863 -235.968243) (xy 110.958884 -235.990384) (xy 110.953378 -235.997892) (xy 110.947686 -236.015602)
			(xy 110.94872 -236.034175) (xy 110.956342 -236.051144) (xy 110.962694 -236.057948) (xy 111.171482 -236.266736)
			(xy 111.190532 -236.267752) (xy 111.217284 -236.269903) (xy 111.269622 -236.281777) (xy 111.31935 -236.301957)
			(xy 111.365162 -236.329912) (xy 111.385858 -236.347)
		)
		(stroke
			(width 0)
			(type solid)
		)
		(fill yes)
		(layer "In11.Cu")
		(net "PVCCINFAON_CPU1")
	)
	(gr_poly
		(pts
			(xy 155.863798 -371.985286) (xy 160.90138 -371.775228) (xy 160.944306 -371.765576) (xy 190.550546 -366.278922)
			(xy 191.11722 -365.712248) (xy 191.11722 -339.395308) (xy 185.8137 -334.091788) (xy 159.08274 -334.091788)
			(xy 156.65958 -331.668628) (xy 133.29412 -331.668628) (xy 131.64312 -330.017628) (xy 127.12192 -330.017628)
			(xy 123.43892 -326.334628) (xy 95.49638 -326.334628) (xy 92.23248 -329.598528) (xy 86.64448 -329.598528)
			(xy 85.26018 -330.982828) (xy 85.26018 -332.456028) (xy 84.49818 -333.218028) (xy 77.32522 -333.218028)
			(xy 76.367894 -334.175354) (xy 76.331914 -334.541368) (xy 93.012768 -334.541368) (xy 93.013254 -334.514117)
			(xy 93.02101 -334.460169) (xy 93.036365 -334.407874) (xy 93.059007 -334.358297) (xy 93.088473 -334.312447)
			(xy 93.124164 -334.271256) (xy 93.165355 -334.235565) (xy 93.211205 -334.206099) (xy 93.260782 -334.183457)
			(xy 93.313077 -334.168102) (xy 93.367025 -334.160346) (xy 93.421527 -334.160346) (xy 93.475475 -334.168102)
			(xy 93.52777 -334.183457) (xy 93.577347 -334.206099) (xy 93.623197 -334.235565) (xy 93.664388 -334.271256)
			(xy 93.700079 -334.312447) (xy 93.729545 -334.358297) (xy 93.752187 -334.407874) (xy 93.767542 -334.460169)
			(xy 93.775298 -334.514117) (xy 93.775784 -334.541368) (xy 93.775371 -334.567043) (xy 93.768491 -334.61793)
			(xy 93.75485 -334.667435) (xy 93.734695 -334.714664) (xy 93.70839 -334.758764) (xy 93.692726 -334.779112)
			(xy 93.683994 -334.790855) (xy 93.672944 -334.817938) (xy 93.670019 -334.847042) (xy 93.675461 -334.875781)
			(xy 93.688821 -334.901802) (xy 93.698568 -334.912716) (xy 93.718314 -334.934136) (xy 93.751715 -334.981866)
			(xy 93.777482 -335.034113) (xy 93.795016 -335.089668) (xy 93.803912 -335.147241) (xy 93.804486 -335.176368)
			(xy 101.201982 -335.176368) (xy 101.202409 -335.148996) (xy 101.210233 -335.094815) (xy 101.22573 -335.04231)
			(xy 101.248581 -334.992564) (xy 101.278316 -334.9466) (xy 101.295962 -334.92567) (xy 101.305233 -334.914367)
			(xy 101.317411 -334.887801) (xy 101.321579 -334.858876) (xy 101.317397 -334.829952) (xy 101.305206 -334.803392)
			(xy 101.295962 -334.792066) (xy 101.278334 -334.771125) (xy 101.248622 -334.725154) (xy 101.225784 -334.675409)
			(xy 101.21029 -334.62291) (xy 101.202458 -334.568736) (xy 101.201982 -334.541368) (xy 101.202468 -334.514117)
			(xy 101.210224 -334.460169) (xy 101.225579 -334.407874) (xy 101.248221 -334.358297) (xy 101.277687 -334.312447)
			(xy 101.313378 -334.271256) (xy 101.354569 -334.235565) (xy 101.400419 -334.206099) (xy 101.449996 -334.183457)
			(xy 101.502291 -334.168102) (xy 101.556239 -334.160346) (xy 101.610741 -334.160346) (xy 101.664689 -334.168102)
			(xy 101.716984 -334.183457) (xy 101.766561 -334.206099) (xy 101.812411 -334.235565) (xy 101.853602 -334.271256)
			(xy 101.889293 -334.312447) (xy 101.918759 -334.358297) (xy 101.941401 -334.407874) (xy 101.956756 -334.460169)
			(xy 101.964512 -334.514117) (xy 101.964998 -334.541368) (xy 101.964514 -334.568738) (xy 101.9567 -334.622916)
			(xy 101.941216 -334.675419) (xy 101.918378 -334.725166) (xy 101.888657 -334.771134) (xy 101.871018 -334.792066)
			(xy 101.861811 -334.803416) (xy 101.849628 -334.829965) (xy 101.845448 -334.858876) (xy 101.849614 -334.887788)
			(xy 101.861785 -334.914343) (xy 101.871018 -334.92567) (xy 101.888659 -334.9466) (xy 101.91837 -334.992574)
			(xy 101.941205 -335.042322) (xy 101.956696 -335.094823) (xy 101.964524 -335.148999) (xy 101.964998 -335.176368)
			(xy 109.362494 -335.176368) (xy 109.362943 -335.148997) (xy 109.370765 -335.094817) (xy 109.386258 -335.042314)
			(xy 109.409104 -334.992568) (xy 109.438831 -334.946601) (xy 109.456474 -334.92567) (xy 109.465744 -334.914367)
			(xy 109.477921 -334.887801) (xy 109.482088 -334.858876) (xy 109.477907 -334.829953) (xy 109.465717 -334.803393)
			(xy 109.456474 -334.792066) (xy 109.438848 -334.771123) (xy 109.409135 -334.725153) (xy 109.386297 -334.675408)
			(xy 109.370803 -334.62291) (xy 109.362971 -334.568736) (xy 109.362494 -334.541368) (xy 109.36298 -334.514117)
			(xy 109.370736 -334.460169) (xy 109.386091 -334.407874) (xy 109.408733 -334.358297) (xy 109.438199 -334.312447)
			(xy 109.47389 -334.271256) (xy 109.515081 -334.235565) (xy 109.560931 -334.206099) (xy 109.610508 -334.183457)
			(xy 109.662803 -334.168102) (xy 109.716751 -334.160346) (xy 109.771253 -334.160346) (xy 109.825201 -334.168102)
			(xy 109.877496 -334.183457) (xy 109.927073 -334.206099) (xy 109.972923 -334.235565) (xy 110.014114 -334.271256)
			(xy 110.049805 -334.312447) (xy 110.079271 -334.358297) (xy 110.101913 -334.407874) (xy 110.117268 -334.460169)
			(xy 110.125024 -334.514117) (xy 110.12551 -334.541368) (xy 110.125023 -334.568737) (xy 110.11721 -334.622916)
			(xy 110.101725 -334.675418) (xy 110.078888 -334.725165) (xy 110.049169 -334.771133) (xy 110.03153 -334.792066)
			(xy 110.022322 -334.803415) (xy 110.010137 -334.829965) (xy 110.005957 -334.858876) (xy 110.010123 -334.887789)
			(xy 110.022296 -334.914344) (xy 110.03153 -334.92567) (xy 110.049173 -334.946599) (xy 110.078883 -334.992573)
			(xy 110.101718 -335.042321) (xy 110.117208 -335.094823) (xy 110.125036 -335.148999) (xy 110.12551 -335.176368)
			(xy 117.523006 -335.176368) (xy 117.523452 -335.148997) (xy 117.531274 -335.094817) (xy 117.546768 -335.042314)
			(xy 117.569614 -334.992567) (xy 117.599343 -334.946601) (xy 117.616986 -334.92567) (xy 117.626255 -334.914366)
			(xy 117.63843 -334.8878) (xy 117.642597 -334.858876) (xy 117.638416 -334.829953) (xy 117.626228 -334.803393)
			(xy 117.616986 -334.792066) (xy 117.599362 -334.771122) (xy 117.569649 -334.725152) (xy 117.54681 -334.675408)
			(xy 117.531315 -334.62291) (xy 117.523483 -334.568736) (xy 117.523006 -334.541368) (xy 117.523492 -334.514117)
			(xy 117.531248 -334.460169) (xy 117.546603 -334.407874) (xy 117.569245 -334.358297) (xy 117.598711 -334.312447)
			(xy 117.634402 -334.271256) (xy 117.675593 -334.235565) (xy 117.721443 -334.206099) (xy 117.77102 -334.183457)
			(xy 117.823315 -334.168102) (xy 117.877263 -334.160346) (xy 117.931765 -334.160346) (xy 117.985713 -334.168102)
			(xy 118.038008 -334.183457) (xy 118.087585 -334.206099) (xy 118.133435 -334.235565) (xy 118.174626 -334.271256)
			(xy 118.210317 -334.312447) (xy 118.239783 -334.358297) (xy 118.262425 -334.407874) (xy 118.27778 -334.460169)
			(xy 118.285536 -334.514117) (xy 118.286022 -334.541368) (xy 118.285556 -334.568738) (xy 118.277741 -334.622918)
			(xy 118.262253 -334.675422) (xy 118.239411 -334.725169) (xy 118.209684 -334.771135) (xy 118.192042 -334.792066)
			(xy 118.182841 -334.803418) (xy 118.170666 -334.829968) (xy 118.16649 -334.858876) (xy 118.170653 -334.887785)
			(xy 118.182814 -334.914341) (xy 118.192042 -334.92567) (xy 118.209687 -334.946597) (xy 118.239397 -334.992572)
			(xy 118.262231 -335.042321) (xy 118.277721 -335.094822) (xy 118.285549 -335.148999) (xy 118.286022 -335.176368)
			(xy 118.285536 -335.203619) (xy 118.27778 -335.257567) (xy 118.262425 -335.309862) (xy 118.239783 -335.359439)
			(xy 118.210317 -335.405289) (xy 118.174626 -335.44648) (xy 118.133435 -335.482171) (xy 118.087585 -335.511637)
			(xy 118.038008 -335.534279) (xy 117.985713 -335.549634) (xy 117.931765 -335.55739) (xy 117.877263 -335.55739)
			(xy 117.823315 -335.549634) (xy 117.77102 -335.534279) (xy 117.721443 -335.511637) (xy 117.675593 -335.482171)
			(xy 117.634402 -335.44648) (xy 117.598711 -335.405289) (xy 117.569245 -335.359439) (xy 117.546603 -335.309862)
			(xy 117.531248 -335.257567) (xy 117.523492 -335.203619) (xy 117.523006 -335.176368) (xy 110.12551 -335.176368)
			(xy 110.125024 -335.203619) (xy 110.117268 -335.257567) (xy 110.101913 -335.309862) (xy 110.079271 -335.359439)
			(xy 110.049805 -335.405289) (xy 110.014114 -335.44648) (xy 109.972923 -335.482171) (xy 109.927073 -335.511637)
			(xy 109.877496 -335.534279) (xy 109.825201 -335.549634) (xy 109.771253 -335.55739) (xy 109.716751 -335.55739)
			(xy 109.662803 -335.549634) (xy 109.610508 -335.534279) (xy 109.560931 -335.511637) (xy 109.515081 -335.482171)
			(xy 109.47389 -335.44648) (xy 109.438199 -335.405289) (xy 109.408733 -335.359439) (xy 109.386091 -335.309862)
			(xy 109.370736 -335.257567) (xy 109.36298 -335.203619) (xy 109.362494 -335.176368) (xy 101.964998 -335.176368)
			(xy 101.964512 -335.203619) (xy 101.956756 -335.257567) (xy 101.941401 -335.309862) (xy 101.918759 -335.359439)
			(xy 101.889293 -335.405289) (xy 101.853602 -335.44648) (xy 101.812411 -335.482171) (xy 101.766561 -335.511637)
			(xy 101.716984 -335.534279) (xy 101.664689 -335.549634) (xy 101.610741 -335.55739) (xy 101.556239 -335.55739)
			(xy 101.502291 -335.549634) (xy 101.449996 -335.534279) (xy 101.400419 -335.511637) (xy 101.354569 -335.482171)
			(xy 101.313378 -335.44648) (xy 101.277687 -335.405289) (xy 101.248221 -335.359439) (xy 101.225579 -335.309862)
			(xy 101.210224 -335.257567) (xy 101.202468 -335.203619) (xy 101.201982 -335.176368) (xy 93.804486 -335.176368)
			(xy 93.804 -335.203619) (xy 93.796244 -335.257567) (xy 93.780889 -335.309862) (xy 93.758247 -335.359439)
			(xy 93.728781 -335.405289) (xy 93.69309 -335.44648) (xy 93.651899 -335.482171) (xy 93.606049 -335.511637)
			(xy 93.556472 -335.534279) (xy 93.504177 -335.549634) (xy 93.450229 -335.55739) (xy 93.395727 -335.55739)
			(xy 93.341779 -335.549634) (xy 93.289484 -335.534279) (xy 93.239907 -335.511637) (xy 93.194057 -335.482171)
			(xy 93.152866 -335.44648) (xy 93.117175 -335.405289) (xy 93.087709 -335.359439) (xy 93.065067 -335.309862)
			(xy 93.049712 -335.257567) (xy 93.041956 -335.203619) (xy 93.04147 -335.176368) (xy 93.041913 -335.150694)
			(xy 93.048788 -335.099809) (xy 93.062422 -335.050305) (xy 93.08257 -335.003075) (xy 93.108868 -334.958973)
			(xy 93.124528 -334.938624) (xy 93.133329 -334.926927) (xy 93.144376 -334.899827) (xy 93.147289 -334.870708)
			(xy 93.14183 -334.841957) (xy 93.128445 -334.815933) (xy 93.118686 -334.80502) (xy 93.098966 -334.783577)
			(xy 93.065559 -334.735854) (xy 93.039787 -334.683613) (xy 93.022246 -334.628063) (xy 93.013345 -334.570494)
			(xy 93.012768 -334.541368) (xy 76.331914 -334.541368) (xy 76.260452 -335.268316) (xy 76.25842 -335.288636)
			(xy 76.25842 -335.579) (xy 97.290117 -335.579) (xy 97.294285 -335.523384) (xy 97.306694 -335.469011)
			(xy 97.327068 -335.417094) (xy 97.354952 -335.368793) (xy 97.389723 -335.325188) (xy 97.430604 -335.287251)
			(xy 97.476682 -335.25583) (xy 97.526928 -335.231627) (xy 97.580221 -335.215183) (xy 97.635368 -335.206864)
			(xy 97.663254 -335.20634) (xy 97.690586 -335.206812) (xy 97.744666 -335.214781) (xy 97.797 -335.230569)
			(xy 97.846465 -335.253837) (xy 97.891997 -335.284084) (xy 97.932619 -335.320663) (xy 97.967459 -335.362786)
			(xy 97.982024 -335.385918) (xy 97.989942 -335.398145) (xy 98.011416 -335.417814) (xy 98.03757 -335.430618)
			(xy 98.066276 -335.435512) (xy 98.095196 -335.4321) (xy 98.10877 -335.426812) (xy 98.131987 -335.41734)
			(xy 98.180316 -335.403982) (xy 98.230003 -335.397247) (xy 98.255074 -335.39684) (xy 98.280144 -335.397251)
			(xy 98.329827 -335.404006) (xy 98.378161 -335.417343) (xy 98.401378 -335.426812) (xy 98.414951 -335.43207)
			(xy 98.443854 -335.435432) (xy 98.472533 -335.430519) (xy 98.498669 -335.417728) (xy 98.520144 -335.398094)
			(xy 98.528124 -335.385918) (xy 98.542693 -335.362787) (xy 98.577536 -335.320666) (xy 98.618159 -335.284087)
			(xy 98.66369 -335.253836) (xy 98.713152 -335.23056) (xy 98.765483 -335.21476) (xy 98.819562 -335.206774)
			(xy 98.874226 -335.206774) (xy 98.928305 -335.21476) (xy 98.980636 -335.23056) (xy 99.030098 -335.253836)
			(xy 99.075629 -335.284087) (xy 99.116252 -335.320666) (xy 99.151095 -335.362787) (xy 99.165664 -335.385918)
			(xy 99.173544 -335.398173) (xy 99.195028 -335.417842) (xy 99.221193 -335.430641) (xy 99.249908 -335.435529)
			(xy 99.278834 -335.432106) (xy 99.29241 -335.426812) (xy 99.315622 -335.417328) (xy 99.363954 -335.403974)
			(xy 99.413643 -335.397244) (xy 99.438714 -335.39684) (xy 99.465556 -335.397321) (xy 99.518683 -335.405026)
			(xy 99.570155 -335.420275) (xy 99.618906 -335.442752) (xy 99.663928 -335.471992) (xy 99.704287 -335.50739)
			(xy 99.73915 -335.548213) (xy 99.767794 -335.593616) (xy 99.789627 -335.642659) (xy 99.797362 -335.668366)
			(xy 99.802083 -335.682841) (xy 99.818592 -335.708398) (xy 99.841895 -335.72796) (xy 99.869926 -335.739792)
			(xy 99.900198 -335.742845) (xy 99.930026 -335.736849) (xy 99.943666 -335.730088) (xy 99.97181 -335.715451)
			(xy 100.031762 -335.694725) (xy 100.094321 -335.684228) (xy 100.126038 -335.683606) (xy 100.144057 -335.683825)
			(xy 100.179932 -335.687261) (xy 100.197666 -335.690464) (xy 100.212879 -335.692764) (xy 100.243427 -335.689245)
			(xy 100.271544 -335.676793) (xy 100.294679 -335.656537) (xy 100.310737 -335.630312) (xy 100.315014 -335.615534)
			(xy 100.3224 -335.588487) (xy 100.344032 -335.536761) (xy 100.372998 -335.488756) (xy 100.408676 -335.445505)
			(xy 100.450296 -335.407938) (xy 100.496965 -335.376865) (xy 100.547677 -335.352952) (xy 100.601342 -335.336716)
			(xy 100.656805 -335.328505) (xy 100.684838 -335.328006) (xy 100.712091 -335.328443) (xy 100.766041 -335.336205)
			(xy 100.818338 -335.351565) (xy 100.867916 -335.374212) (xy 100.913767 -335.403683) (xy 100.954957 -335.43938)
			(xy 100.990648 -335.480575) (xy 101.020113 -335.52643) (xy 101.042753 -335.576011) (xy 101.043631 -335.579)
			(xy 105.450617 -335.579) (xy 105.454785 -335.523383) (xy 105.467195 -335.469009) (xy 105.48757 -335.417091)
			(xy 105.515455 -335.36879) (xy 105.550227 -335.325183) (xy 105.591109 -335.287246) (xy 105.637189 -335.255826)
			(xy 105.687437 -335.231624) (xy 105.740731 -335.21518) (xy 105.79588 -335.206863) (xy 105.823766 -335.20634)
			(xy 105.851098 -335.206803) (xy 105.905179 -335.214774) (xy 105.957513 -335.230563) (xy 106.006978 -335.253832)
			(xy 106.05251 -335.284081) (xy 106.093132 -335.320661) (xy 106.127971 -335.362785) (xy 106.142536 -335.385918)
			(xy 106.150443 -335.398154) (xy 106.17192 -335.417823) (xy 106.198077 -335.430625) (xy 106.226786 -335.435517)
			(xy 106.255707 -335.432101) (xy 106.269282 -335.426812) (xy 106.292497 -335.417336) (xy 106.340827 -335.40398)
			(xy 106.390515 -335.397246) (xy 106.415586 -335.39684) (xy 106.440655 -335.397279) (xy 106.490337 -335.404022)
			(xy 106.538672 -335.417349) (xy 106.56189 -335.426812) (xy 106.575495 -335.431977) (xy 106.604381 -335.435359)
			(xy 106.63305 -335.430467) (xy 106.65918 -335.417697) (xy 106.680654 -335.398084) (xy 106.688636 -335.385918)
			(xy 106.703205 -335.362787) (xy 106.738048 -335.320666) (xy 106.778671 -335.284087) (xy 106.824202 -335.253836)
			(xy 106.873664 -335.23056) (xy 106.925995 -335.21476) (xy 106.980074 -335.206774) (xy 107.034738 -335.206774)
			(xy 107.088817 -335.21476) (xy 107.141148 -335.23056) (xy 107.19061 -335.253836) (xy 107.236141 -335.284087)
			(xy 107.276764 -335.320666) (xy 107.311607 -335.362787) (xy 107.326176 -335.385918) (xy 107.33414 -335.398113)
			(xy 107.355601 -335.417782) (xy 107.381743 -335.430589) (xy 107.410438 -335.435492) (xy 107.43935 -335.432092)
			(xy 107.452922 -335.426812) (xy 107.476132 -335.417324) (xy 107.524465 -335.403972) (xy 107.574154 -335.397244)
			(xy 107.599226 -335.39684) (xy 107.626068 -335.39731) (xy 107.679196 -335.405017) (xy 107.730668 -335.420268)
			(xy 107.779419 -335.442746) (xy 107.824441 -335.471988) (xy 107.8648 -335.507387) (xy 107.899663 -335.548211)
			(xy 107.928307 -335.593614) (xy 107.950139 -335.642658) (xy 107.957874 -335.668366) (xy 107.962579 -335.682847)
			(xy 107.979091 -335.708406) (xy 108.002398 -335.727968) (xy 108.030432 -335.7398) (xy 108.060707 -335.742851)
			(xy 108.090538 -335.736851) (xy 108.104178 -335.730088) (xy 108.13232 -335.715447) (xy 108.192273 -335.694722)
			(xy 108.254833 -335.684227) (xy 108.28655 -335.683606) (xy 108.304569 -335.683824) (xy 108.340444 -335.68726)
			(xy 108.358178 -335.690464) (xy 108.37339 -335.692776) (xy 108.403939 -335.689254) (xy 108.432056 -335.676799)
			(xy 108.455192 -335.65654) (xy 108.471249 -335.630313) (xy 108.475526 -335.615534) (xy 108.482901 -335.588483)
			(xy 108.504534 -335.536757) (xy 108.533502 -335.488751) (xy 108.56918 -335.4455) (xy 108.610802 -335.407934)
			(xy 108.657472 -335.37686) (xy 108.708186 -335.352949) (xy 108.761852 -335.336714) (xy 108.817316 -335.328504)
			(xy 108.84535 -335.328006) (xy 108.872602 -335.328502) (xy 108.926553 -335.336252) (xy 108.978851 -335.351603)
			(xy 109.028432 -335.37424) (xy 109.074286 -335.403705) (xy 109.115479 -335.439395) (xy 109.151174 -335.480585)
			(xy 109.180642 -335.526437) (xy 109.203285 -335.576015) (xy 109.204161 -335.579) (xy 113.611117 -335.579)
			(xy 113.615285 -335.523382) (xy 113.627696 -335.469007) (xy 113.648071 -335.417088) (xy 113.675957 -335.368786)
			(xy 113.710731 -335.325179) (xy 113.751615 -335.287242) (xy 113.797696 -335.255822) (xy 113.847945 -335.23162)
			(xy 113.901241 -335.215178) (xy 113.956391 -335.206863) (xy 113.984278 -335.20634) (xy 114.011611 -335.206794)
			(xy 114.065691 -335.214766) (xy 114.118026 -335.230557) (xy 114.167491 -335.253828) (xy 114.213023 -335.284078)
			(xy 114.253644 -335.320659) (xy 114.288483 -335.362784) (xy 114.303048 -335.385918) (xy 114.310943 -335.398162)
			(xy 114.332423 -335.417831) (xy 114.358584 -335.430632) (xy 114.387295 -335.435522) (xy 114.416219 -335.432103)
			(xy 114.429794 -335.426812) (xy 114.453008 -335.417333) (xy 114.501339 -335.403978) (xy 114.551027 -335.397245)
			(xy 114.576098 -335.39684) (xy 114.601167 -335.397276) (xy 114.65085 -335.40402) (xy 114.699184 -335.417348)
			(xy 114.722402 -335.426812) (xy 114.736003 -335.43199) (xy 114.764891 -335.435369) (xy 114.793561 -335.430474)
			(xy 114.819692 -335.417701) (xy 114.841166 -335.398085) (xy 114.849148 -335.385918) (xy 114.863717 -335.362787)
			(xy 114.89856 -335.320666) (xy 114.939183 -335.284087) (xy 114.984714 -335.253836) (xy 115.034176 -335.23056)
			(xy 115.086507 -335.21476) (xy 115.140586 -335.206774) (xy 115.19525 -335.206774) (xy 115.249329 -335.21476)
			(xy 115.30166 -335.23056) (xy 115.351122 -335.253836) (xy 115.396653 -335.284087) (xy 115.437276 -335.320666)
			(xy 115.472119 -335.362787) (xy 115.486688 -335.385918) (xy 115.49464 -335.398121) (xy 115.516105 -335.41779)
			(xy 115.54225 -335.430596) (xy 115.570948 -335.435497) (xy 115.599861 -335.432094) (xy 115.613434 -335.426812)
			(xy 115.636643 -335.41732) (xy 115.684976 -335.40397) (xy 115.734666 -335.397243) (xy 115.759738 -335.39684)
			(xy 115.78658 -335.3973) (xy 115.839709 -335.405008) (xy 115.891181 -335.420261) (xy 115.939933 -335.442741)
			(xy 115.984954 -335.471983) (xy 116.025313 -335.507383) (xy 116.060175 -335.548208) (xy 116.088819 -335.593613)
			(xy 116.110651 -335.642658) (xy 116.118386 -335.668366) (xy 116.123076 -335.682853) (xy 116.13959 -335.708413)
			(xy 116.1629 -335.727976) (xy 116.190938 -335.739807) (xy 116.221216 -335.742856) (xy 116.251049 -335.736853)
			(xy 116.26469 -335.730088) (xy 116.29283 -335.715442) (xy 116.352784 -335.69472) (xy 116.415345 -335.684226)
			(xy 116.447062 -335.683606) (xy 116.465081 -335.683822) (xy 116.500956 -335.687259) (xy 116.51869 -335.690464)
			(xy 116.5339 -335.692788) (xy 116.564451 -335.689263) (xy 116.592569 -335.676805) (xy 116.615704 -335.656543)
			(xy 116.631761 -335.630314) (xy 116.636038 -335.615534) (xy 116.643402 -335.58848) (xy 116.665036 -335.536753)
			(xy 116.694005 -335.488747) (xy 116.729685 -335.445495) (xy 116.771308 -335.407929) (xy 116.81798 -335.376856)
			(xy 116.868695 -335.352946) (xy 116.922362 -335.336711) (xy 116.977827 -335.328503) (xy 117.005862 -335.328006)
			(xy 117.033115 -335.328491) (xy 117.087065 -335.336243) (xy 117.139364 -335.351595) (xy 117.188945 -335.374234)
			(xy 117.234799 -335.403699) (xy 117.275992 -335.439391) (xy 117.311686 -335.480582) (xy 117.341155 -335.526434)
			(xy 117.363797 -335.576014) (xy 117.364674 -335.579) (xy 121.771617 -335.579) (xy 121.775785 -335.523381)
			(xy 121.788196 -335.469004) (xy 121.808573 -335.417085) (xy 121.83646 -335.368782) (xy 121.871235 -335.325175)
			(xy 121.91212 -335.287238) (xy 121.958203 -335.255818) (xy 122.008454 -335.231617) (xy 122.061751 -335.215176)
			(xy 122.116903 -335.206862) (xy 122.14479 -335.20634) (xy 122.172123 -335.206784) (xy 122.226204 -335.214758)
			(xy 122.278539 -335.230551) (xy 122.328004 -335.253823) (xy 122.373536 -335.284075) (xy 122.414157 -335.320657)
			(xy 122.448995 -335.362784) (xy 122.46356 -335.385918) (xy 122.471444 -335.39817) (xy 122.492927 -335.417839)
			(xy 122.519091 -335.430639) (xy 122.547805 -335.435527) (xy 122.57673 -335.432105) (xy 122.590306 -335.426812)
			(xy 122.613518 -335.417329) (xy 122.66185 -335.403975) (xy 122.711539 -335.397245) (xy 122.73661 -335.39684)
			(xy 122.761679 -335.397272) (xy 122.811362 -335.404018) (xy 122.859696 -335.417347) (xy 122.882914 -335.426812)
			(xy 122.89651 -335.432003) (xy 122.925401 -335.435379) (xy 122.954073 -335.430481) (xy 122.980204 -335.417706)
			(xy 123.001678 -335.398087) (xy 123.00966 -335.385918) (xy 123.024229 -335.362787) (xy 123.059072 -335.320666)
			(xy 123.099695 -335.284087) (xy 123.145226 -335.253836) (xy 123.194688 -335.23056) (xy 123.247019 -335.21476)
			(xy 123.301098 -335.206774) (xy 123.355762 -335.206774) (xy 123.409841 -335.21476) (xy 123.462172 -335.23056)
			(xy 123.511634 -335.253836) (xy 123.557165 -335.284087) (xy 123.597788 -335.320666) (xy 123.632631 -335.362787)
			(xy 123.6472 -335.385918) (xy 123.655141 -335.398129) (xy 123.676608 -335.417798) (xy 123.702757 -335.430603)
			(xy 123.731457 -335.435502) (xy 123.760373 -335.432096) (xy 123.773946 -335.426812) (xy 123.797154 -335.417317)
			(xy 123.845488 -335.403968) (xy 123.895178 -335.397242) (xy 123.92025 -335.39684) (xy 123.948136 -335.397416)
			(xy 124.003286 -335.405721) (xy 124.056582 -335.422155) (xy 124.106833 -335.446348) (xy 124.152917 -335.477762)
			(xy 124.193803 -335.515694) (xy 124.197205 -335.51996) (xy 170.076618 -335.51996) (xy 170.076618 -335.435264)
			(xy 170.084669 -335.35095) (xy 170.100698 -335.267784) (xy 170.124559 -335.186517) (xy 170.156038 -335.107887)
			(xy 170.194849 -335.032606) (xy 170.240639 -334.961354) (xy 170.292995 -334.894778) (xy 170.351443 -334.83348)
			(xy 170.415453 -334.778015) (xy 170.484445 -334.728886) (xy 170.557795 -334.686537) (xy 170.634838 -334.651353)
			(xy 170.714877 -334.623651) (xy 170.797186 -334.603683) (xy 170.881021 -334.59163) (xy 170.965622 -334.5876)
			(xy 171.050223 -334.59163) (xy 171.134058 -334.603683) (xy 171.216367 -334.623651) (xy 171.296406 -334.651353)
			(xy 171.373449 -334.686537) (xy 171.446799 -334.728886) (xy 171.515791 -334.778015) (xy 171.579801 -334.83348)
			(xy 171.638249 -334.894778) (xy 171.690605 -334.961354) (xy 171.736395 -335.032606) (xy 171.775206 -335.107887)
			(xy 171.806685 -335.186517) (xy 171.830546 -335.267784) (xy 171.846575 -335.35095) (xy 171.854626 -335.435264)
			(xy 171.85513 -335.477612) (xy 171.854626 -335.51996) (xy 171.85402 -335.52631) (xy 176.26736 -335.52631)
			(xy 176.26736 -335.441614) (xy 176.275411 -335.3573) (xy 176.29144 -335.274134) (xy 176.315301 -335.192867)
			(xy 176.34678 -335.114237) (xy 176.385591 -335.038956) (xy 176.431381 -334.967704) (xy 176.483737 -334.901128)
			(xy 176.542185 -334.83983) (xy 176.606195 -334.784365) (xy 176.675187 -334.735236) (xy 176.748537 -334.692887)
			(xy 176.82558 -334.657703) (xy 176.905619 -334.630001) (xy 176.987928 -334.610033) (xy 177.071763 -334.59798)
			(xy 177.156364 -334.59395) (xy 177.240965 -334.59798) (xy 177.3248 -334.610033) (xy 177.407109 -334.630001)
			(xy 177.487148 -334.657703) (xy 177.564191 -334.692887) (xy 177.637541 -334.735236) (xy 177.706533 -334.784365)
			(xy 177.770543 -334.83983) (xy 177.828991 -334.901128) (xy 177.881347 -334.967704) (xy 177.927137 -335.038956)
			(xy 177.965948 -335.114237) (xy 177.997427 -335.192867) (xy 178.021288 -335.274134) (xy 178.037317 -335.3573)
			(xy 178.045368 -335.441614) (xy 178.045872 -335.483962) (xy 178.045368 -335.52631) (xy 182.46496 -335.52631)
			(xy 182.46496 -335.441614) (xy 182.473011 -335.3573) (xy 182.48904 -335.274134) (xy 182.512901 -335.192867)
			(xy 182.54438 -335.114237) (xy 182.583191 -335.038956) (xy 182.628981 -334.967704) (xy 182.681337 -334.901128)
			(xy 182.739785 -334.83983) (xy 182.803795 -334.784365) (xy 182.872787 -334.735236) (xy 182.946137 -334.692887)
			(xy 183.02318 -334.657703) (xy 183.103219 -334.630001) (xy 183.185528 -334.610033) (xy 183.269363 -334.59798)
			(xy 183.353964 -334.59395) (xy 183.438565 -334.59798) (xy 183.5224 -334.610033) (xy 183.604709 -334.630001)
			(xy 183.684748 -334.657703) (xy 183.761791 -334.692887) (xy 183.835141 -334.735236) (xy 183.904133 -334.784365)
			(xy 183.968143 -334.83983) (xy 184.026591 -334.901128) (xy 184.078947 -334.967704) (xy 184.124737 -335.038956)
			(xy 184.163548 -335.114237) (xy 184.195027 -335.192867) (xy 184.218888 -335.274134) (xy 184.234917 -335.3573)
			(xy 184.242968 -335.441614) (xy 184.243472 -335.483962) (xy 184.242968 -335.52631) (xy 184.234917 -335.610624)
			(xy 184.218888 -335.69379) (xy 184.195027 -335.775057) (xy 184.163548 -335.853687) (xy 184.124737 -335.928968)
			(xy 184.078947 -336.00022) (xy 184.026591 -336.066796) (xy 183.968143 -336.128094) (xy 183.904133 -336.183559)
			(xy 183.835141 -336.232688) (xy 183.761791 -336.275037) (xy 183.684748 -336.310221) (xy 183.604709 -336.337923)
			(xy 183.5224 -336.357891) (xy 183.438565 -336.369944) (xy 183.353964 -336.373975) (xy 183.269363 -336.369944)
			(xy 183.185528 -336.357891) (xy 183.103219 -336.337923) (xy 183.02318 -336.310221) (xy 182.946137 -336.275037)
			(xy 182.872787 -336.232688) (xy 182.803795 -336.183559) (xy 182.739785 -336.128094) (xy 182.681337 -336.066796)
			(xy 182.628981 -336.00022) (xy 182.583191 -335.928968) (xy 182.54438 -335.853687) (xy 182.512901 -335.775057)
			(xy 182.48904 -335.69379) (xy 182.473011 -335.610624) (xy 182.46496 -335.52631) (xy 178.045368 -335.52631)
			(xy 178.037317 -335.610624) (xy 178.021288 -335.69379) (xy 177.997427 -335.775057) (xy 177.965948 -335.853687)
			(xy 177.927137 -335.928968) (xy 177.881347 -336.00022) (xy 177.828991 -336.066796) (xy 177.770543 -336.128094)
			(xy 177.706533 -336.183559) (xy 177.637541 -336.232688) (xy 177.564191 -336.275037) (xy 177.487148 -336.310221)
			(xy 177.407109 -336.337923) (xy 177.3248 -336.357891) (xy 177.240965 -336.369944) (xy 177.156364 -336.373975)
			(xy 177.071763 -336.369944) (xy 176.987928 -336.357891) (xy 176.905619 -336.337923) (xy 176.82558 -336.310221)
			(xy 176.748537 -336.275037) (xy 176.675187 -336.232688) (xy 176.606195 -336.183559) (xy 176.542185 -336.128094)
			(xy 176.483737 -336.066796) (xy 176.431381 -336.00022) (xy 176.385591 -335.928968) (xy 176.34678 -335.853687)
			(xy 176.315301 -335.775057) (xy 176.29144 -335.69379) (xy 176.275411 -335.610624) (xy 176.26736 -335.52631)
			(xy 171.85402 -335.52631) (xy 171.846575 -335.604274) (xy 171.830546 -335.68744) (xy 171.806685 -335.768707)
			(xy 171.775206 -335.847337) (xy 171.736395 -335.922618) (xy 171.690605 -335.99387) (xy 171.638249 -336.060446)
			(xy 171.579801 -336.121744) (xy 171.515791 -336.177209) (xy 171.446799 -336.226338) (xy 171.373449 -336.268687)
			(xy 171.296406 -336.303871) (xy 171.216367 -336.331573) (xy 171.134058 -336.351541) (xy 171.050223 -336.363594)
			(xy 170.965622 -336.367625) (xy 170.881021 -336.363594) (xy 170.797186 -336.351541) (xy 170.714877 -336.331573)
			(xy 170.634838 -336.303871) (xy 170.557795 -336.268687) (xy 170.484445 -336.226338) (xy 170.415453 -336.177209)
			(xy 170.351443 -336.121744) (xy 170.292995 -336.060446) (xy 170.240639 -335.99387) (xy 170.194849 -335.922618)
			(xy 170.156038 -335.847337) (xy 170.124559 -335.768707) (xy 170.100698 -335.68744) (xy 170.084669 -335.604274)
			(xy 170.076618 -335.51996) (xy 124.197205 -335.51996) (xy 124.228579 -335.559296) (xy 124.256467 -335.607595)
			(xy 124.276844 -335.659511) (xy 124.289256 -335.713884) (xy 124.293424 -335.7695) (xy 124.289256 -335.825116)
			(xy 124.276844 -335.879489) (xy 124.256467 -335.931405) (xy 124.228579 -335.979704) (xy 124.193803 -336.023306)
			(xy 124.152917 -336.061238) (xy 124.106833 -336.092652) (xy 124.056582 -336.116845) (xy 124.003286 -336.133279)
			(xy 123.948136 -336.141584) (xy 123.92025 -336.142076) (xy 123.892918 -336.141593) (xy 123.838839 -336.133625)
			(xy 123.786506 -336.117839) (xy 123.737042 -336.094572) (xy 123.691509 -336.064327) (xy 123.650887 -336.02775)
			(xy 123.616046 -335.985629) (xy 123.60148 -335.962498) (xy 123.593554 -335.950276) (xy 123.572084 -335.930605)
			(xy 123.545931 -335.9178) (xy 123.517226 -335.912904) (xy 123.488308 -335.916316) (xy 123.474734 -335.921604)
			(xy 123.451517 -335.931076) (xy 123.403188 -335.944433) (xy 123.353501 -335.951169) (xy 123.32843 -335.951576)
			(xy 123.30336 -335.951163) (xy 123.253677 -335.944409) (xy 123.205343 -335.931072) (xy 123.182126 -335.921604)
			(xy 123.168553 -335.916343) (xy 123.13965 -335.912979) (xy 123.110969 -335.917892) (xy 123.084834 -335.930685)
			(xy 123.063359 -335.950321) (xy 123.05538 -335.962498) (xy 123.040811 -335.985629) (xy 123.005968 -336.02775)
			(xy 122.965345 -336.064329) (xy 122.919814 -336.09458) (xy 122.870352 -336.117856) (xy 122.818021 -336.133656)
			(xy 122.763942 -336.141642) (xy 122.709278 -336.141642) (xy 122.655199 -336.133656) (xy 122.602868 -336.117856)
			(xy 122.553406 -336.09458) (xy 122.507875 -336.064329) (xy 122.467252 -336.02775) (xy 122.432409 -335.985629)
			(xy 122.41784 -335.962498) (xy 122.409952 -335.950248) (xy 122.388471 -335.930577) (xy 122.362308 -335.917776)
			(xy 122.333594 -335.912888) (xy 122.304669 -335.91631) (xy 122.291094 -335.921604) (xy 122.267882 -335.931088)
			(xy 122.21955 -335.944441) (xy 122.169861 -335.951171) (xy 122.14479 -335.951576) (xy 122.116903 -335.951138)
			(xy 122.061751 -335.942824) (xy 122.008454 -335.926383) (xy 121.958203 -335.902182) (xy 121.91212 -335.870762)
			(xy 121.871235 -335.832825) (xy 121.83646 -335.789218) (xy 121.808573 -335.740915) (xy 121.788196 -335.688996)
			(xy 121.775785 -335.634619) (xy 121.771617 -335.579) (xy 117.364674 -335.579) (xy 117.379152 -335.628311)
			(xy 117.386908 -335.682261) (xy 117.38737 -335.709514) (xy 117.386856 -335.737087) (xy 117.378914 -335.791658)
			(xy 117.3632 -335.844517) (xy 117.340039 -335.894564) (xy 117.309915 -335.940755) (xy 117.273454 -335.982127)
			(xy 117.25275 -336.000344) (xy 117.241835 -336.010226) (xy 117.225755 -336.034879) (xy 117.217369 -336.063092)
			(xy 117.217371 -336.092526) (xy 117.225763 -336.120737) (xy 117.241847 -336.145388) (xy 117.25275 -336.155284)
			(xy 117.273472 -336.173483) (xy 117.30994 -336.214855) (xy 117.34007 -336.261046) (xy 117.363235 -336.311095)
			(xy 117.378951 -336.363959) (xy 117.386892 -336.418534) (xy 117.38689 -336.473684) (xy 117.378947 -336.528259)
			(xy 117.363229 -336.581121) (xy 117.340061 -336.631169) (xy 117.331207 -336.644742) (xy 118.31396 -336.644742)
			(xy 118.318031 -336.58912) (xy 118.330157 -336.534683) (xy 118.35008 -336.482592) (xy 118.377376 -336.433957)
			(xy 118.411462 -336.389814) (xy 118.451611 -336.351105) (xy 118.496969 -336.318654) (xy 118.546569 -336.293153)
			(xy 118.599353 -336.275146) (xy 118.654196 -336.265016) (xy 118.70993 -336.262979) (xy 118.765367 -336.269079)
			(xy 118.819324 -336.283185) (xy 118.870653 -336.304997) (xy 118.918259 -336.334051) (xy 118.961127 -336.369726)
			(xy 118.998344 -336.411263) (xy 119.029117 -336.457776) (xy 119.052789 -336.508273) (xy 119.068857 -336.56168)
			(xy 119.076977 -336.616856) (xy 119.077486 -336.644742) (xy 119.076977 -336.672628) (xy 119.068857 -336.727804)
			(xy 119.052789 -336.781211) (xy 119.029117 -336.831708) (xy 118.998344 -336.878221) (xy 118.961127 -336.919758)
			(xy 118.918259 -336.955433) (xy 118.870653 -336.984487) (xy 118.819324 -337.006299) (xy 118.765367 -337.020405)
			(xy 118.70993 -337.026505) (xy 118.654196 -337.024468) (xy 118.599353 -337.014338) (xy 118.546569 -336.996331)
			(xy 118.496969 -336.97083) (xy 118.451611 -336.938379) (xy 118.411462 -336.89967) (xy 118.377376 -336.855527)
			(xy 118.35008 -336.806892) (xy 118.330157 -336.754801) (xy 118.318031 -336.700364) (xy 118.31396 -336.644742)
			(xy 117.331207 -336.644742) (xy 117.309929 -336.67736) (xy 117.273459 -336.71873) (xy 117.25275 -336.736944)
			(xy 117.241835 -336.746826) (xy 117.225755 -336.771479) (xy 117.217369 -336.799692) (xy 117.217371 -336.829126)
			(xy 117.225763 -336.857337) (xy 117.241847 -336.881988) (xy 117.25275 -336.891884) (xy 117.273467 -336.910089)
			(xy 117.309934 -336.95146) (xy 117.340065 -336.997652) (xy 117.363229 -337.047701) (xy 117.378945 -337.100564)
			(xy 117.386884 -337.155139) (xy 117.38737 -337.182714) (xy 117.386958 -337.209969) (xy 117.379845 -337.259422)
			(xy 117.522496 -337.259422) (xy 117.526567 -337.2038) (xy 117.538693 -337.149363) (xy 117.558616 -337.097272)
			(xy 117.585912 -337.048637) (xy 117.619998 -337.004494) (xy 117.660147 -336.965785) (xy 117.705505 -336.933334)
			(xy 117.755105 -336.907833) (xy 117.807889 -336.889826) (xy 117.862732 -336.879696) (xy 117.918466 -336.877659)
			(xy 117.973903 -336.883759) (xy 118.02786 -336.897865) (xy 118.079189 -336.919677) (xy 118.126795 -336.948731)
			(xy 118.169663 -336.984406) (xy 118.20688 -337.025943) (xy 118.237653 -337.072456) (xy 118.261325 -337.122953)
			(xy 118.277393 -337.17636) (xy 118.285513 -337.231536) (xy 118.286022 -337.259422) (xy 118.285513 -337.287308)
			(xy 118.277393 -337.342484) (xy 118.261325 -337.395891) (xy 118.237653 -337.446388) (xy 118.20688 -337.492901)
			(xy 118.169663 -337.534438) (xy 118.126795 -337.570113) (xy 118.079189 -337.599167) (xy 118.02786 -337.620979)
			(xy 117.973903 -337.635085) (xy 117.918466 -337.641185) (xy 117.862732 -337.639148) (xy 117.807889 -337.629018)
			(xy 117.755105 -337.611011) (xy 117.705505 -337.58551) (xy 117.660147 -337.553059) (xy 117.619998 -337.51435)
			(xy 117.585912 -337.470207) (xy 117.558616 -337.421572) (xy 117.538693 -337.369481) (xy 117.526567 -337.315044)
			(xy 117.522496 -337.259422) (xy 117.379845 -337.259422) (xy 117.379198 -337.263924) (xy 117.363838 -337.316225)
			(xy 117.341192 -337.365808) (xy 117.311718 -337.411663) (xy 117.276019 -337.452856) (xy 117.234821 -337.48855)
			(xy 117.188962 -337.518016) (xy 117.139376 -337.540657) (xy 117.087073 -337.556009) (xy 117.033117 -337.563762)
			(xy 117.005862 -337.564222) (xy 116.978006 -337.563717) (xy 116.922891 -337.555588) (xy 116.869541 -337.539539)
			(xy 116.819089 -337.515909) (xy 116.772605 -337.4852) (xy 116.731076 -337.448063) (xy 116.695383 -337.405287)
			(xy 116.666284 -337.357779) (xy 116.644395 -337.306547) (xy 116.6368 -337.279742) (xy 116.632472 -337.265645)
			(xy 116.617096 -337.240501) (xy 116.595191 -337.220783) (xy 116.568575 -337.208127) (xy 116.539455 -337.203582)
			(xy 116.524786 -337.205066) (xy 116.511769 -337.206735) (xy 116.485585 -337.208515) (xy 116.472462 -337.208622)
			(xy 116.458313 -337.208532) (xy 116.43009 -337.206495) (xy 116.416074 -337.204558) (xy 116.402721 -337.203043)
			(xy 116.376039 -337.206134) (xy 116.351092 -337.216091) (xy 116.329615 -337.232222) (xy 116.313101 -337.253406)
			(xy 116.302698 -337.27817) (xy 116.300504 -337.291426) (xy 116.296414 -337.318579) (xy 116.281442 -337.37141)
			(xy 116.259052 -337.42155) (xy 116.229705 -337.467961) (xy 116.194009 -337.509686) (xy 116.152699 -337.545863)
			(xy 116.106629 -337.575744) (xy 116.056752 -337.598712) (xy 116.004098 -337.614293) (xy 115.949754 -337.622165)
			(xy 115.922298 -337.622642) (xy 115.895048 -337.622124) (xy 115.841103 -337.614368) (xy 115.788811 -337.599015)
			(xy 115.739236 -337.576376) (xy 115.693388 -337.546912) (xy 115.652198 -337.511224) (xy 115.616507 -337.470038)
			(xy 115.58704 -337.424192) (xy 115.564397 -337.374619) (xy 115.549039 -337.322328) (xy 115.541278 -337.268384)
			(xy 115.54079 -337.241134) (xy 115.541283 -337.21356) (xy 115.54923 -337.158989) (xy 115.56495 -337.10613)
			(xy 115.588115 -337.056084) (xy 115.618243 -337.009893) (xy 115.654705 -336.968521) (xy 115.67541 -336.950304)
			(xy 115.686272 -336.94037) (xy 115.702343 -336.915729) (xy 115.71073 -336.887531) (xy 115.710736 -336.858113)
			(xy 115.702362 -336.829911) (xy 115.686301 -336.805263) (xy 115.67541 -336.795364) (xy 115.65468 -336.777173)
			(xy 115.618211 -336.7358) (xy 115.588081 -336.689606) (xy 115.564918 -336.639554) (xy 115.549206 -336.586688)
			(xy 115.541272 -336.53211) (xy 115.54079 -336.504534) (xy 115.541227 -336.478032) (xy 115.548576 -336.425541)
			(xy 115.563125 -336.374573) (xy 115.584592 -336.326111) (xy 115.612563 -336.281089) (xy 115.629182 -336.26044)
			(xy 115.638623 -336.248295) (xy 115.650406 -336.219894) (xy 115.653226 -336.189276) (xy 115.646829 -336.159201)
			(xy 115.631793 -336.13238) (xy 115.609472 -336.111232) (xy 115.595908 -336.103976) (xy 115.572209 -336.091892)
			(xy 115.528229 -336.061964) (xy 115.48895 -336.026088) (xy 115.45517 -335.984993) (xy 115.440968 -335.962498)
			(xy 115.433053 -335.950267) (xy 115.41158 -335.930597) (xy 115.385424 -335.917793) (xy 115.356717 -335.912899)
			(xy 115.327796 -335.916314) (xy 115.314222 -335.921604) (xy 115.291007 -335.931079) (xy 115.242677 -335.944436)
			(xy 115.192989 -335.95117) (xy 115.167918 -335.951576) (xy 115.142849 -335.951134) (xy 115.093167 -335.944392)
			(xy 115.044832 -335.931067) (xy 115.021614 -335.921604) (xy 115.008009 -335.916436) (xy 114.979123 -335.913053)
			(xy 114.950453 -335.917945) (xy 114.924323 -335.930716) (xy 114.902849 -335.950331) (xy 114.894868 -335.962498)
			(xy 114.880299 -335.985629) (xy 114.845456 -336.02775) (xy 114.804833 -336.064329) (xy 114.759302 -336.09458)
			(xy 114.70984 -336.117856) (xy 114.657509 -336.133656) (xy 114.60343 -336.141642) (xy 114.548766 -336.141642)
			(xy 114.494687 -336.133656) (xy 114.442356 -336.117856) (xy 114.392894 -336.09458) (xy 114.347363 -336.064329)
			(xy 114.30674 -336.02775) (xy 114.271897 -335.985629) (xy 114.257328 -335.962498) (xy 114.249451 -335.95024)
			(xy 114.227967 -335.930569) (xy 114.201801 -335.917769) (xy 114.173085 -335.912883) (xy 114.144158 -335.916308)
			(xy 114.130582 -335.921604) (xy 114.107371 -335.931092) (xy 114.059039 -335.944443) (xy 114.00935 -335.951172)
			(xy 113.984278 -335.951576) (xy 113.956391 -335.951137) (xy 113.901241 -335.942822) (xy 113.847945 -335.92638)
			(xy 113.797696 -335.902178) (xy 113.751615 -335.870758) (xy 113.710731 -335.832821) (xy 113.675957 -335.789214)
			(xy 113.648071 -335.740912) (xy 113.627696 -335.688993) (xy 113.615285 -335.634618) (xy 113.611117 -335.579)
			(xy 109.204161 -335.579) (xy 109.21864 -335.628312) (xy 109.226396 -335.682262) (xy 109.226858 -335.709514)
			(xy 109.226348 -335.737087) (xy 109.218406 -335.791659) (xy 109.202691 -335.844518) (xy 109.17953 -335.894565)
			(xy 109.149404 -335.940755) (xy 109.112943 -335.982128) (xy 109.092238 -336.000344) (xy 109.081324 -336.010227)
			(xy 109.065246 -336.03488) (xy 109.056861 -336.063093) (xy 109.056864 -336.092525) (xy 109.065254 -336.120737)
			(xy 109.081336 -336.145387) (xy 109.092238 -336.155284) (xy 109.11296 -336.173483) (xy 109.149429 -336.214854)
			(xy 109.179561 -336.261046) (xy 109.202726 -336.311095) (xy 109.218443 -336.363958) (xy 109.226384 -336.418534)
			(xy 109.226383 -336.473684) (xy 109.218439 -336.52826) (xy 109.20272 -336.581122) (xy 109.179552 -336.63117)
			(xy 109.170698 -336.644742) (xy 110.153448 -336.644742) (xy 110.157519 -336.58912) (xy 110.169645 -336.534683)
			(xy 110.189568 -336.482592) (xy 110.216864 -336.433957) (xy 110.25095 -336.389814) (xy 110.291099 -336.351105)
			(xy 110.336457 -336.318654) (xy 110.386057 -336.293153) (xy 110.438841 -336.275146) (xy 110.493684 -336.265016)
			(xy 110.549418 -336.262979) (xy 110.604855 -336.269079) (xy 110.658812 -336.283185) (xy 110.710141 -336.304997)
			(xy 110.757747 -336.334051) (xy 110.800615 -336.369726) (xy 110.837832 -336.411263) (xy 110.868605 -336.457776)
			(xy 110.892277 -336.508273) (xy 110.908345 -336.56168) (xy 110.916465 -336.616856) (xy 110.916974 -336.644742)
			(xy 110.916465 -336.672628) (xy 110.908345 -336.727804) (xy 110.892277 -336.781211) (xy 110.868605 -336.831708)
			(xy 110.837832 -336.878221) (xy 110.800615 -336.919758) (xy 110.757747 -336.955433) (xy 110.710141 -336.984487)
			(xy 110.658812 -337.006299) (xy 110.604855 -337.020405) (xy 110.549418 -337.026505) (xy 110.493684 -337.024468)
			(xy 110.438841 -337.014338) (xy 110.386057 -336.996331) (xy 110.336457 -336.97083) (xy 110.291099 -336.938379)
			(xy 110.25095 -336.89967) (xy 110.216864 -336.855527) (xy 110.189568 -336.806892) (xy 110.169645 -336.754801)
			(xy 110.157519 -336.700364) (xy 110.153448 -336.644742) (xy 109.170698 -336.644742) (xy 109.149418 -336.677361)
			(xy 109.112947 -336.71873) (xy 109.092238 -336.736944) (xy 109.081324 -336.746827) (xy 109.065246 -336.77148)
			(xy 109.056861 -336.799693) (xy 109.056864 -336.829125) (xy 109.065254 -336.857337) (xy 109.081336 -336.881987)
			(xy 109.092238 -336.891884) (xy 109.112952 -336.910092) (xy 109.149421 -336.951462) (xy 109.179551 -336.997653)
			(xy 109.202716 -337.047702) (xy 109.218433 -337.100564) (xy 109.226372 -337.155139) (xy 109.226858 -337.182714)
			(xy 109.226458 -337.20997) (xy 109.218698 -337.263925) (xy 109.216141 -337.27263) (xy 109.505494 -337.27263)
			(xy 109.509565 -337.217008) (xy 109.521691 -337.162571) (xy 109.541614 -337.11048) (xy 109.56891 -337.061845)
			(xy 109.602996 -337.017702) (xy 109.643145 -336.978993) (xy 109.688503 -336.946542) (xy 109.738103 -336.921041)
			(xy 109.790887 -336.903034) (xy 109.84573 -336.892904) (xy 109.901464 -336.890867) (xy 109.956901 -336.896967)
			(xy 110.010858 -336.911073) (xy 110.062187 -336.932885) (xy 110.109793 -336.961939) (xy 110.152661 -336.997614)
			(xy 110.189878 -337.039151) (xy 110.220651 -337.085664) (xy 110.244323 -337.136161) (xy 110.260391 -337.189568)
			(xy 110.268511 -337.244744) (xy 110.26902 -337.27263) (xy 110.268511 -337.300516) (xy 110.260391 -337.355692)
			(xy 110.244323 -337.409099) (xy 110.220651 -337.459596) (xy 110.189878 -337.506109) (xy 110.152661 -337.547646)
			(xy 110.109793 -337.583321) (xy 110.062187 -337.612375) (xy 110.010858 -337.634187) (xy 109.956901 -337.648293)
			(xy 109.901464 -337.654393) (xy 109.84573 -337.652356) (xy 109.790887 -337.642226) (xy 109.738103 -337.624219)
			(xy 109.688503 -337.598718) (xy 109.643145 -337.566267) (xy 109.602996 -337.527558) (xy 109.56891 -337.483415)
			(xy 109.541614 -337.43478) (xy 109.521691 -337.382689) (xy 109.509565 -337.328252) (xy 109.505494 -337.27263)
			(xy 109.216141 -337.27263) (xy 109.203337 -337.316227) (xy 109.18069 -337.365811) (xy 109.151216 -337.411667)
			(xy 109.115515 -337.45286) (xy 109.074315 -337.488554) (xy 109.028455 -337.51802) (xy 108.978867 -337.54066)
			(xy 108.926563 -337.556011) (xy 108.872606 -337.563763) (xy 108.84535 -337.564222) (xy 108.817494 -337.563728)
			(xy 108.762378 -337.555598) (xy 108.709028 -337.539546) (xy 108.658576 -337.515915) (xy 108.612092 -337.485204)
			(xy 108.570563 -337.448066) (xy 108.534871 -337.405289) (xy 108.505771 -337.35778) (xy 108.483883 -337.306548)
			(xy 108.476288 -337.279742) (xy 108.471972 -337.26564) (xy 108.456594 -337.240496) (xy 108.434686 -337.220778)
			(xy 108.408067 -337.208123) (xy 108.378944 -337.20358) (xy 108.364274 -337.205066) (xy 108.351258 -337.206736)
			(xy 108.325073 -337.208515) (xy 108.31195 -337.208622) (xy 108.297801 -337.208523) (xy 108.269578 -337.206492)
			(xy 108.255562 -337.204558) (xy 108.24221 -337.203031) (xy 108.215527 -337.206124) (xy 108.19058 -337.216084)
			(xy 108.169103 -337.232218) (xy 108.152589 -337.253404) (xy 108.142186 -337.278169) (xy 108.139992 -337.291426)
			(xy 108.135913 -337.318581) (xy 108.120941 -337.371413) (xy 108.09855 -337.421553) (xy 108.069202 -337.467965)
			(xy 108.033504 -337.509691) (xy 107.992193 -337.545867) (xy 107.946122 -337.575748) (xy 107.896244 -337.598716)
			(xy 107.843588 -337.614295) (xy 107.789242 -337.622166) (xy 107.761786 -337.622642) (xy 107.734536 -337.622135)
			(xy 107.680591 -337.614378) (xy 107.628298 -337.599023) (xy 107.578723 -337.576382) (xy 107.532875 -337.546918)
			(xy 107.491686 -337.511229) (xy 107.455994 -337.470041) (xy 107.426527 -337.424194) (xy 107.403884 -337.37462)
			(xy 107.388526 -337.322329) (xy 107.380766 -337.268384) (xy 107.380278 -337.241134) (xy 107.380775 -337.213561)
			(xy 107.388722 -337.15899) (xy 107.404441 -337.106131) (xy 107.427606 -337.056085) (xy 107.457732 -337.009894)
			(xy 107.494194 -336.968521) (xy 107.514898 -336.950304) (xy 107.525761 -336.940371) (xy 107.541834 -336.91573)
			(xy 107.550222 -336.887532) (xy 107.550228 -336.858112) (xy 107.541853 -336.82991) (xy 107.52579 -336.805262)
			(xy 107.514898 -336.795364) (xy 107.494166 -336.777176) (xy 107.457697 -336.735802) (xy 107.427568 -336.689607)
			(xy 107.404406 -336.639555) (xy 107.388694 -336.586688) (xy 107.38076 -336.53211) (xy 107.380278 -336.504534)
			(xy 107.380717 -336.478032) (xy 107.388067 -336.425541) (xy 107.402615 -336.374573) (xy 107.424081 -336.326111)
			(xy 107.452052 -336.281089) (xy 107.46867 -336.26044) (xy 107.478115 -336.248298) (xy 107.489899 -336.219896)
			(xy 107.49272 -336.189276) (xy 107.486322 -336.1592) (xy 107.471284 -336.132379) (xy 107.448961 -336.111232)
			(xy 107.435396 -336.103976) (xy 107.411695 -336.091896) (xy 107.367716 -336.061966) (xy 107.328437 -336.026089)
			(xy 107.294658 -335.984993) (xy 107.280456 -335.962498) (xy 107.272553 -335.950259) (xy 107.251076 -335.930588)
			(xy 107.224917 -335.917786) (xy 107.196207 -335.912894) (xy 107.167285 -335.916313) (xy 107.15371 -335.921604)
			(xy 107.130496 -335.931083) (xy 107.082165 -335.944438) (xy 107.032477 -335.95117) (xy 107.007406 -335.951576)
			(xy 106.982337 -335.951138) (xy 106.932655 -335.944394) (xy 106.88432 -335.931067) (xy 106.861102 -335.921604)
			(xy 106.847502 -335.916424) (xy 106.818613 -335.913043) (xy 106.789942 -335.917938) (xy 106.763811 -335.930712)
			(xy 106.742337 -335.95033) (xy 106.734356 -335.962498) (xy 106.719787 -335.985629) (xy 106.684944 -336.02775)
			(xy 106.644321 -336.064329) (xy 106.59879 -336.09458) (xy 106.549328 -336.117856) (xy 106.496997 -336.133656)
			(xy 106.442918 -336.141642) (xy 106.388254 -336.141642) (xy 106.334175 -336.133656) (xy 106.281844 -336.117856)
			(xy 106.232382 -336.09458) (xy 106.186851 -336.064329) (xy 106.146228 -336.02775) (xy 106.111385 -335.985629)
			(xy 106.096816 -335.962498) (xy 106.088856 -335.9503) (xy 106.067395 -335.930629) (xy 106.041251 -335.917821)
			(xy 106.012555 -335.912919) (xy 105.983642 -335.916322) (xy 105.97007 -335.921604) (xy 105.946861 -335.931095)
			(xy 105.898528 -335.944446) (xy 105.848838 -335.951173) (xy 105.823766 -335.951576) (xy 105.79588 -335.951137)
			(xy 105.740731 -335.94282) (xy 105.687437 -335.926376) (xy 105.637189 -335.902174) (xy 105.591109 -335.870754)
			(xy 105.550227 -335.832817) (xy 105.515455 -335.78921) (xy 105.48757 -335.740909) (xy 105.467195 -335.688991)
			(xy 105.454785 -335.634617) (xy 105.450617 -335.579) (xy 101.043631 -335.579) (xy 101.058107 -335.62831)
			(xy 101.065861 -335.682261) (xy 101.066346 -335.709514) (xy 101.06584 -335.737087) (xy 101.057898 -335.791659)
			(xy 101.042183 -335.844519) (xy 101.01902 -335.894566) (xy 100.988894 -335.940756) (xy 100.952431 -335.982128)
			(xy 100.931726 -336.000344) (xy 100.920813 -336.010227) (xy 100.904737 -336.034881) (xy 100.896353 -336.063093)
			(xy 100.896356 -336.092525) (xy 100.904745 -336.120736) (xy 100.920825 -336.145386) (xy 100.931726 -336.155284)
			(xy 100.952444 -336.173485) (xy 100.988906 -336.214859) (xy 101.01903 -336.261052) (xy 101.04219 -336.311101)
			(xy 101.057903 -336.363962) (xy 101.065842 -336.418535) (xy 101.06584 -336.473683) (xy 101.057899 -336.528256)
			(xy 101.042184 -336.581116) (xy 101.019021 -336.631164) (xy 101.010165 -336.644742) (xy 101.992936 -336.644742)
			(xy 101.997007 -336.58912) (xy 102.009133 -336.534683) (xy 102.029056 -336.482592) (xy 102.056352 -336.433957)
			(xy 102.090438 -336.389814) (xy 102.130587 -336.351105) (xy 102.175945 -336.318654) (xy 102.225545 -336.293153)
			(xy 102.278329 -336.275146) (xy 102.333172 -336.265016) (xy 102.388906 -336.262979) (xy 102.444343 -336.269079)
			(xy 102.4983 -336.283185) (xy 102.549629 -336.304997) (xy 102.597235 -336.334051) (xy 102.640103 -336.369726)
			(xy 102.67732 -336.411263) (xy 102.708093 -336.457776) (xy 102.731765 -336.508273) (xy 102.747833 -336.56168)
			(xy 102.755953 -336.616856) (xy 102.756462 -336.644742) (xy 102.755953 -336.672628) (xy 102.747833 -336.727804)
			(xy 102.731765 -336.781211) (xy 102.708093 -336.831708) (xy 102.67732 -336.878221) (xy 102.640103 -336.919758)
			(xy 102.597235 -336.955433) (xy 102.549629 -336.984487) (xy 102.4983 -337.006299) (xy 102.444343 -337.020405)
			(xy 102.388906 -337.026505) (xy 102.333172 -337.024468) (xy 102.278329 -337.014338) (xy 102.225545 -336.996331)
			(xy 102.175945 -336.97083) (xy 102.130587 -336.938379) (xy 102.090438 -336.89967) (xy 102.056352 -336.855527)
			(xy 102.029056 -336.806892) (xy 102.009133 -336.754801) (xy 101.997007 -336.700364) (xy 101.992936 -336.644742)
			(xy 101.010165 -336.644742) (xy 100.988895 -336.677355) (xy 100.952431 -336.718728) (xy 100.931726 -336.736944)
			(xy 100.920813 -336.746827) (xy 100.904737 -336.771481) (xy 100.896353 -336.799693) (xy 100.896356 -336.829125)
			(xy 100.904745 -336.857336) (xy 100.920825 -336.881986) (xy 100.931726 -336.891884) (xy 100.952438 -336.910094)
			(xy 100.988907 -336.951464) (xy 101.019038 -336.997654) (xy 101.042204 -337.047702) (xy 101.05792 -337.100565)
			(xy 101.06586 -337.155139) (xy 101.066346 -337.182714) (xy 101.065835 -337.209964) (xy 101.063837 -337.223862)
			(xy 101.236524 -337.223862) (xy 101.240595 -337.16824) (xy 101.252721 -337.113803) (xy 101.272644 -337.061712)
			(xy 101.29994 -337.013077) (xy 101.334026 -336.968934) (xy 101.374175 -336.930225) (xy 101.419533 -336.897774)
			(xy 101.469133 -336.872273) (xy 101.521917 -336.854266) (xy 101.57676 -336.844136) (xy 101.632494 -336.842099)
			(xy 101.687931 -336.848199) (xy 101.741888 -336.862305) (xy 101.793217 -336.884117) (xy 101.840823 -336.913171)
			(xy 101.883691 -336.948846) (xy 101.920908 -336.990383) (xy 101.951681 -337.036896) (xy 101.975353 -337.087393)
			(xy 101.991421 -337.1408) (xy 101.999541 -337.195976) (xy 102.00005 -337.223862) (xy 101.999541 -337.251748)
			(xy 101.991421 -337.306924) (xy 101.975353 -337.360331) (xy 101.951681 -337.410828) (xy 101.920908 -337.457341)
			(xy 101.883691 -337.498878) (xy 101.840823 -337.534553) (xy 101.793217 -337.563607) (xy 101.741888 -337.585419)
			(xy 101.687931 -337.599525) (xy 101.632494 -337.605625) (xy 101.57676 -337.603588) (xy 101.521917 -337.593458)
			(xy 101.469133 -337.575451) (xy 101.419533 -337.54995) (xy 101.374175 -337.517499) (xy 101.334026 -337.47879)
			(xy 101.29994 -337.434647) (xy 101.272644 -337.386012) (xy 101.252721 -337.333921) (xy 101.240595 -337.279484)
			(xy 101.236524 -337.223862) (xy 101.063837 -337.223862) (xy 101.058078 -337.263909) (xy 101.042723 -337.316201)
			(xy 101.020083 -337.365775) (xy 100.990619 -337.411624) (xy 100.95493 -337.452813) (xy 100.913743 -337.488504)
			(xy 100.867897 -337.517971) (xy 100.818323 -337.540615) (xy 100.766032 -337.555973) (xy 100.712088 -337.563734)
			(xy 100.684838 -337.564222) (xy 100.656985 -337.563648) (xy 100.601872 -337.555531) (xy 100.548524 -337.539491)
			(xy 100.498072 -337.515871) (xy 100.451588 -337.48517) (xy 100.410058 -337.448041) (xy 100.374364 -337.405272)
			(xy 100.345263 -337.357771) (xy 100.323372 -337.306545) (xy 100.315776 -337.279742) (xy 100.311472 -337.265636)
			(xy 100.296091 -337.24049) (xy 100.274181 -337.220772) (xy 100.247558 -337.208119) (xy 100.218433 -337.203579)
			(xy 100.203762 -337.205066) (xy 100.190746 -337.206737) (xy 100.164561 -337.208516) (xy 100.151438 -337.208622)
			(xy 100.137289 -337.208524) (xy 100.109066 -337.206493) (xy 100.09505 -337.204558) (xy 100.081699 -337.203018)
			(xy 100.055015 -337.206115) (xy 100.030067 -337.216077) (xy 100.00859 -337.232213) (xy 99.992076 -337.253401)
			(xy 99.981673 -337.278168) (xy 99.97948 -337.291426) (xy 99.975413 -337.318584) (xy 99.96044 -337.371416)
			(xy 99.938048 -337.421557) (xy 99.908699 -337.46797) (xy 99.873 -337.509695) (xy 99.831687 -337.545872)
			(xy 99.785615 -337.575752) (xy 99.735735 -337.598719) (xy 99.683078 -337.614298) (xy 99.628731 -337.622166)
			(xy 99.601274 -337.622642) (xy 99.574024 -337.622146) (xy 99.520078 -337.614387) (xy 99.467786 -337.599031)
			(xy 99.418211 -337.576389) (xy 99.372362 -337.546923) (xy 99.331173 -337.511233) (xy 99.295482 -337.470045)
			(xy 99.266015 -337.424197) (xy 99.243372 -337.374622) (xy 99.228014 -337.32233) (xy 99.220254 -337.268384)
			(xy 99.219766 -337.241134) (xy 99.220232 -337.213559) (xy 99.228181 -337.158985) (xy 99.243905 -337.106124)
			(xy 99.267075 -337.056078) (xy 99.297208 -337.009889) (xy 99.333678 -336.968519) (xy 99.354386 -336.950304)
			(xy 99.36525 -336.940371) (xy 99.381326 -336.915731) (xy 99.389714 -336.887532) (xy 99.389721 -336.858112)
			(xy 99.381344 -336.829909) (xy 99.365279 -336.805262) (xy 99.354386 -336.795364) (xy 99.333651 -336.777178)
			(xy 99.297184 -336.735804) (xy 99.267055 -336.689609) (xy 99.243893 -336.639556) (xy 99.228182 -336.586689)
			(xy 99.220248 -336.53211) (xy 99.219766 -336.504534) (xy 99.220208 -336.478033) (xy 99.227557 -336.425541)
			(xy 99.242105 -336.374574) (xy 99.26357 -336.326112) (xy 99.29154 -336.281089) (xy 99.308158 -336.26044)
			(xy 99.317607 -336.2483) (xy 99.329393 -336.219898) (xy 99.332214 -336.189277) (xy 99.325816 -336.159199)
			(xy 99.310776 -336.132377) (xy 99.28845 -336.111231) (xy 99.274884 -336.103976) (xy 99.251197 -336.091869)
			(xy 99.207215 -336.061949) (xy 99.167932 -336.026079) (xy 99.134148 -335.98499) (xy 99.119944 -335.962498)
			(xy 99.112052 -335.950251) (xy 99.090572 -335.93058) (xy 99.06441 -335.917779) (xy 99.035698 -335.912889)
			(xy 99.006773 -335.916311) (xy 98.993198 -335.921604) (xy 98.969986 -335.931087) (xy 98.921654 -335.94444)
			(xy 98.871965 -335.951171) (xy 98.846894 -335.951576) (xy 98.821825 -335.951142) (xy 98.772142 -335.944396)
			(xy 98.723808 -335.931068) (xy 98.70059 -335.921604) (xy 98.686994 -335.916411) (xy 98.658103 -335.913032)
			(xy 98.62943 -335.91793) (xy 98.603298 -335.930707) (xy 98.581825 -335.950328) (xy 98.573844 -335.962498)
			(xy 98.559275 -335.985629) (xy 98.524432 -336.02775) (xy 98.483809 -336.064329) (xy 98.438278 -336.09458)
			(xy 98.388816 -336.117856) (xy 98.336485 -336.133656) (xy 98.282406 -336.141642) (xy 98.227742 -336.141642)
			(xy 98.173663 -336.133656) (xy 98.121332 -336.117856) (xy 98.07187 -336.09458) (xy 98.026339 -336.064329)
			(xy 97.985716 -336.02775) (xy 97.950873 -335.985629) (xy 97.936304 -335.962498) (xy 97.928355 -335.950292)
			(xy 97.906891 -335.930621) (xy 97.880744 -335.917814) (xy 97.852045 -335.912914) (xy 97.823131 -335.91632)
			(xy 97.809558 -335.921604) (xy 97.78635 -335.931099) (xy 97.738016 -335.944448) (xy 97.688326 -335.951174)
			(xy 97.663254 -335.951576) (xy 97.635368 -335.951136) (xy 97.580221 -335.942817) (xy 97.526928 -335.926373)
			(xy 97.476682 -335.90217) (xy 97.430604 -335.870749) (xy 97.389723 -335.832812) (xy 97.354952 -335.789207)
			(xy 97.327068 -335.740906) (xy 97.306694 -335.688989) (xy 97.294285 -335.634616) (xy 97.290117 -335.579)
			(xy 76.25842 -335.579) (xy 76.25842 -336.644742) (xy 93.832424 -336.644742) (xy 93.836495 -336.58912)
			(xy 93.848621 -336.534683) (xy 93.868544 -336.482592) (xy 93.89584 -336.433957) (xy 93.929926 -336.389814)
			(xy 93.970075 -336.351105) (xy 94.015433 -336.318654) (xy 94.065033 -336.293153) (xy 94.117817 -336.275146)
			(xy 94.17266 -336.265016) (xy 94.228394 -336.262979) (xy 94.283831 -336.269079) (xy 94.337788 -336.283185)
			(xy 94.389117 -336.304997) (xy 94.436723 -336.334051) (xy 94.479591 -336.369726) (xy 94.516808 -336.411263)
			(xy 94.547581 -336.457776) (xy 94.571253 -336.508273) (xy 94.587321 -336.56168) (xy 94.595441 -336.616856)
			(xy 94.59595 -336.644742) (xy 94.595441 -336.672628) (xy 94.587321 -336.727804) (xy 94.571253 -336.781211)
			(xy 94.547581 -336.831708) (xy 94.516808 -336.878221) (xy 94.479591 -336.919758) (xy 94.436723 -336.955433)
			(xy 94.389117 -336.984487) (xy 94.337788 -337.006299) (xy 94.283831 -337.020405) (xy 94.228394 -337.026505)
			(xy 94.17266 -337.024468) (xy 94.117817 -337.014338) (xy 94.065033 -336.996331) (xy 94.015433 -336.97083)
			(xy 93.970075 -336.938379) (xy 93.929926 -336.89967) (xy 93.89584 -336.855527) (xy 93.868544 -336.806892)
			(xy 93.848621 -336.754801) (xy 93.836495 -336.700364) (xy 93.832424 -336.644742) (xy 76.25842 -336.644742)
			(xy 76.25842 -337.352894) (xy 93.189296 -337.352894) (xy 93.193367 -337.297272) (xy 93.205493 -337.242835)
			(xy 93.225416 -337.190744) (xy 93.252712 -337.142109) (xy 93.286798 -337.097966) (xy 93.326947 -337.059257)
			(xy 93.372305 -337.026806) (xy 93.421905 -337.001305) (xy 93.474689 -336.983298) (xy 93.529532 -336.973168)
			(xy 93.585266 -336.971131) (xy 93.640703 -336.977231) (xy 93.69466 -336.991337) (xy 93.745989 -337.013149)
			(xy 93.793595 -337.042203) (xy 93.836463 -337.077878) (xy 93.87368 -337.119415) (xy 93.904453 -337.165928)
			(xy 93.928125 -337.216425) (xy 93.944193 -337.269832) (xy 93.952313 -337.325008) (xy 93.952822 -337.352894)
			(xy 93.952313 -337.38078) (xy 93.944193 -337.435956) (xy 93.928125 -337.489363) (xy 93.904453 -337.53986)
			(xy 93.87368 -337.586373) (xy 93.836463 -337.62791) (xy 93.793595 -337.663585) (xy 93.745989 -337.692639)
			(xy 93.69466 -337.714451) (xy 93.640703 -337.728557) (xy 93.585266 -337.734657) (xy 93.529532 -337.73262)
			(xy 93.474689 -337.72249) (xy 93.421905 -337.704483) (xy 93.372305 -337.678982) (xy 93.326947 -337.646531)
			(xy 93.286798 -337.607822) (xy 93.252712 -337.563679) (xy 93.225416 -337.515044) (xy 93.205493 -337.462953)
			(xy 93.193367 -337.408516) (xy 93.189296 -337.352894) (xy 76.25842 -337.352894) (xy 76.25842 -338.671662)
			(xy 84.701634 -338.671662) (xy 84.70209 -338.644953) (xy 84.709554 -338.592057) (xy 84.724317 -338.540718)
			(xy 84.746092 -338.491938) (xy 84.774452 -338.446669) (xy 84.808845 -338.405794) (xy 84.848599 -338.370111)
			(xy 84.892938 -338.340318) (xy 84.916772 -338.328254) (xy 84.929938 -338.321345) (xy 84.951847 -338.301262)
			(xy 84.967048 -338.275722) (xy 84.974254 -338.246888) (xy 84.972856 -338.2172) (xy 84.962971 -338.189171)
			(xy 84.954618 -338.17687) (xy 84.937282 -338.152202) (xy 84.909765 -338.098558) (xy 84.891027 -338.041254)
			(xy 84.881534 -337.981717) (xy 84.880958 -337.951572) (xy 84.881444 -337.924321) (xy 84.8892 -337.870373)
			(xy 84.904555 -337.818078) (xy 84.927197 -337.768501) (xy 84.956663 -337.722651) (xy 84.992354 -337.68146)
			(xy 85.033545 -337.645769) (xy 85.079395 -337.616303) (xy 85.128972 -337.593661) (xy 85.181267 -337.578306)
			(xy 85.235215 -337.57055) (xy 85.289717 -337.57055) (xy 85.343665 -337.578306) (xy 85.39596 -337.593661)
			(xy 85.445537 -337.616303) (xy 85.491387 -337.645769) (xy 85.532578 -337.68146) (xy 85.568269 -337.722651)
			(xy 85.597735 -337.768501) (xy 85.620377 -337.818078) (xy 85.635732 -337.870373) (xy 85.643488 -337.924321)
			(xy 85.643974 -337.951572) (xy 85.643543 -337.978282) (xy 85.636074 -338.031178) (xy 85.621306 -338.082518)
			(xy 85.599528 -338.131298) (xy 85.571165 -338.176567) (xy 85.536769 -338.217441) (xy 85.497013 -338.253124)
			(xy 85.452672 -338.282917) (xy 85.428836 -338.29498) (xy 85.415646 -338.301849) (xy 85.393733 -338.32194)
			(xy 85.378532 -338.347489) (xy 85.371329 -338.376332) (xy 85.372735 -338.406028) (xy 85.382631 -338.434062)
			(xy 85.39099 -338.446364) (xy 85.408342 -338.471021) (xy 85.435855 -338.524669) (xy 85.454589 -338.581976)
			(xy 85.464077 -338.641516) (xy 85.46465 -338.671662) (xy 85.464164 -338.698913) (xy 85.456408 -338.752861)
			(xy 85.441053 -338.805156) (xy 85.418411 -338.854733) (xy 85.388945 -338.900583) (xy 85.353254 -338.941774)
			(xy 85.312063 -338.977465) (xy 85.293803 -338.9892) (xy 89.129495 -338.9892) (xy 89.133664 -338.933573)
			(xy 89.146078 -338.879188) (xy 89.16646 -338.827262) (xy 89.194353 -338.778953) (xy 89.229135 -338.735342)
			(xy 89.27003 -338.697402) (xy 89.316122 -338.665981) (xy 89.366383 -338.641782) (xy 89.419689 -338.625344)
			(xy 89.47485 -338.617036) (xy 89.502742 -338.616544) (xy 89.530074 -338.617024) (xy 89.584153 -338.624991)
			(xy 89.636488 -338.640777) (xy 89.685952 -338.664044) (xy 89.731485 -338.69429) (xy 89.772107 -338.730868)
			(xy 89.806946 -338.77299) (xy 89.821512 -338.796122) (xy 89.829441 -338.808342) (xy 89.850912 -338.82801)
			(xy 89.877063 -338.840814) (xy 89.905767 -338.845711) (xy 89.934684 -338.842302) (xy 89.948258 -338.837016)
			(xy 89.971464 -338.827517) (xy 90.019799 -338.814169) (xy 90.06949 -338.807445) (xy 90.094562 -338.807044)
			(xy 90.119632 -338.807458) (xy 90.169315 -338.814212) (xy 90.217649 -338.827548) (xy 90.240866 -338.837016)
			(xy 90.254444 -338.84226) (xy 90.283344 -338.845625) (xy 90.312022 -338.840714) (xy 90.338156 -338.827926)
			(xy 90.359631 -338.808296) (xy 90.367612 -338.796122) (xy 90.382181 -338.772991) (xy 90.417024 -338.73087)
			(xy 90.457647 -338.694291) (xy 90.503178 -338.66404) (xy 90.55264 -338.640764) (xy 90.604971 -338.624964)
			(xy 90.65905 -338.616978) (xy 90.713714 -338.616978) (xy 90.767793 -338.624964) (xy 90.820124 -338.640764)
			(xy 90.869586 -338.66404) (xy 90.915117 -338.694291) (xy 90.95574 -338.73087) (xy 90.990583 -338.772991)
			(xy 91.005152 -338.796122) (xy 91.013043 -338.808369) (xy 91.034524 -338.828038) (xy 91.060686 -338.840838)
			(xy 91.089398 -338.845727) (xy 91.118322 -338.842308) (xy 91.131898 -338.837016) (xy 91.155111 -338.827536)
			(xy 91.203442 -338.814181) (xy 91.253131 -338.807449) (xy 91.278202 -338.807044) (xy 91.30584 -338.807554)
			(xy 91.360507 -338.815747) (xy 91.413365 -338.831923) (xy 91.463254 -338.855727) (xy 91.509081 -338.886638)
			(xy 91.549841 -338.923978) (xy 91.584639 -338.966928) (xy 91.612713 -339.014545) (xy 91.633448 -339.065787)
			(xy 91.640406 -339.09254) (xy 91.644031 -339.105642) (xy 91.657168 -339.129428) (xy 91.676113 -339.148908)
			(xy 91.699525 -339.162702) (xy 91.725746 -339.169834) (xy 91.752919 -339.169798) (xy 91.779121 -339.162598)
			(xy 91.791028 -339.15604) (xy 91.813174 -339.143407) (xy 91.860126 -339.123531) (xy 91.909309 -339.110095)
			(xy 91.959845 -339.103339) (xy 91.985338 -339.102954) (xy 91.993466 -339.102954) (xy 92.008325 -339.102719)
			(xy 92.036942 -339.094758) (xy 92.062067 -339.078913) (xy 92.081582 -339.056521) (xy 92.093844 -339.029466)
			(xy 92.096336 -339.014816) (xy 92.100451 -338.987679) (xy 92.115458 -338.934885) (xy 92.137872 -338.884785)
			(xy 92.167232 -338.838412) (xy 92.202933 -338.796724) (xy 92.244237 -338.76058) (xy 92.290293 -338.730725)
			(xy 92.34015 -338.707776) (xy 92.392781 -338.692205) (xy 92.447099 -338.684334) (xy 92.474542 -338.683854)
			(xy 92.501793 -338.684339) (xy 92.555738 -338.6921) (xy 92.608031 -338.707458) (xy 92.657606 -338.730102)
			(xy 92.703454 -338.759569) (xy 92.744643 -338.79526) (xy 92.780334 -338.836449) (xy 92.8098 -338.882298)
			(xy 92.832443 -338.931873) (xy 92.847801 -338.984166) (xy 92.855562 -339.038111) (xy 92.85605 -339.065362)
			(xy 92.855523 -339.093963) (xy 92.846994 -339.150525) (xy 92.83012 -339.205182) (xy 92.80528 -339.256709)
			(xy 92.77303 -339.303952) (xy 92.734092 -339.345855) (xy 92.712032 -339.364066) (xy 92.701416 -339.373139)
			(xy 92.685125 -339.395806) (xy 92.675581 -339.422039) (xy 92.6735 -339.449875) (xy 92.679035 -339.477235)
			(xy 92.691773 -339.502074) (xy 92.710763 -339.522534) (xy 92.722446 -339.530182) (xy 92.746065 -339.545126)
			(xy 92.789079 -339.580814) (xy 92.826427 -339.622394) (xy 92.857311 -339.668977) (xy 92.881071 -339.719566)
			(xy 92.897198 -339.773079) (xy 92.905347 -339.828373) (xy 92.905834 -339.856318) (xy 92.905414 -339.882211)
			(xy 92.898413 -339.933522) (xy 92.884529 -339.983413) (xy 92.864018 -340.030964) (xy 92.837257 -340.075301)
			(xy 92.80474 -340.115605) (xy 92.7862 -340.133686) (xy 92.776099 -340.143826) (xy 92.761486 -340.16842)
			(xy 92.754279 -340.196106) (xy 92.755045 -340.224704) (xy 92.763725 -340.251964) (xy 92.779634 -340.27574)
			(xy 92.790264 -340.285324) (xy 92.811084 -340.303523) (xy 92.847757 -340.344909) (xy 92.878062 -340.391161)
			(xy 92.901364 -340.441308) (xy 92.917173 -340.494297) (xy 92.925157 -340.549014) (xy 92.925646 -340.576662)
			(xy 92.925087 -340.603911) (xy 92.917336 -340.657854) (xy 92.901988 -340.710145) (xy 92.879354 -340.759719)
			(xy 92.849895 -340.805568) (xy 92.814211 -340.846757) (xy 92.773029 -340.88245) (xy 92.727186 -340.911917)
			(xy 92.677616 -340.934561) (xy 92.625328 -340.94992) (xy 92.571386 -340.957681) (xy 92.544138 -340.95817)
			(xy 92.515061 -340.957651) (xy 92.45758 -340.948831) (xy 92.402103 -340.931388) (xy 92.349916 -340.905728)
			(xy 92.302229 -340.872445) (xy 92.260145 -340.83231) (xy 92.22464 -340.786252) (xy 92.196536 -340.73534)
			(xy 92.185998 -340.708234) (xy 92.180456 -340.694696) (xy 92.162994 -340.671244) (xy 92.1396 -340.653705)
			(xy 92.112194 -340.643518) (xy 92.083024 -340.641518) (xy 92.06865 -340.644226) (xy 92.048216 -340.648497)
			(xy 92.00672 -340.653077) (xy 91.985846 -340.65337) (xy 91.985338 -340.65337) (xy 91.971122 -340.65321)
			(xy 91.942772 -340.65105) (xy 91.928696 -340.649052) (xy 91.913365 -340.647367) (xy 91.882917 -340.652173)
			(xy 91.855285 -340.665837) (xy 91.832982 -340.687116) (xy 91.818036 -340.714076) (xy 91.814396 -340.729062)
			(xy 91.807912 -340.757296) (xy 91.787671 -340.811571) (xy 91.759458 -340.862163) (xy 91.723922 -340.907908)
			(xy 91.68188 -340.947757) (xy 91.634297 -340.980792) (xy 91.582268 -341.006255) (xy 91.526987 -341.023561)
			(xy 91.469725 -341.032311) (xy 91.440762 -341.032846) (xy 91.413512 -341.032358) (xy 91.359566 -341.024597)
			(xy 91.307274 -341.009239) (xy 91.257699 -340.986596) (xy 91.21185 -340.957129) (xy 91.170662 -340.921438)
			(xy 91.134971 -340.88025) (xy 91.105504 -340.834401) (xy 91.082861 -340.784826) (xy 91.067503 -340.732534)
			(xy 91.059742 -340.678588) (xy 91.059254 -340.651338) (xy 91.059727 -340.623764) (xy 91.067675 -340.56919)
			(xy 91.083398 -340.51633) (xy 91.106566 -340.466283) (xy 91.136698 -340.420094) (xy 91.173166 -340.378723)
			(xy 91.193874 -340.360508) (xy 91.204735 -340.350572) (xy 91.220813 -340.325933) (xy 91.229203 -340.297735)
			(xy 91.22921 -340.268314) (xy 91.220833 -340.240112) (xy 91.204768 -340.215465) (xy 91.193874 -340.205568)
			(xy 91.173139 -340.187383) (xy 91.136672 -340.146008) (xy 91.106543 -340.099812) (xy 91.083382 -340.049759)
			(xy 91.06767 -339.996893) (xy 91.059736 -339.942314) (xy 91.059254 -339.914738) (xy 91.059701 -339.888237)
			(xy 91.06705 -339.835746) (xy 91.081596 -339.784778) (xy 91.10306 -339.736316) (xy 91.131029 -339.691293)
			(xy 91.147646 -339.670644) (xy 91.157095 -339.658503) (xy 91.168883 -339.630101) (xy 91.171706 -339.59948)
			(xy 91.165308 -339.569401) (xy 91.150267 -339.542579) (xy 91.127939 -339.521434) (xy 91.114372 -339.51418)
			(xy 91.090684 -339.502075) (xy 91.046702 -339.472154) (xy 91.00742 -339.436284) (xy 90.973636 -339.395194)
			(xy 90.959432 -339.372702) (xy 90.951551 -339.360448) (xy 90.930068 -339.340776) (xy 90.903903 -339.327975)
			(xy 90.875188 -339.323088) (xy 90.846262 -339.326513) (xy 90.832686 -339.331808) (xy 90.809475 -339.341295)
			(xy 90.761143 -339.354647) (xy 90.711454 -339.361376) (xy 90.686382 -339.36178) (xy 90.661313 -339.361349)
			(xy 90.61163 -339.354603) (xy 90.563296 -339.341273) (xy 90.540078 -339.331808) (xy 90.526487 -339.3266)
			(xy 90.497593 -339.323225) (xy 90.468919 -339.328125) (xy 90.442786 -339.340906) (xy 90.421312 -339.36053)
			(xy 90.413332 -339.372702) (xy 90.398763 -339.395833) (xy 90.36392 -339.437954) (xy 90.323297 -339.474533)
			(xy 90.277766 -339.504784) (xy 90.228304 -339.52806) (xy 90.175973 -339.54386) (xy 90.121894 -339.551846)
			(xy 90.06723 -339.551846) (xy 90.013151 -339.54386) (xy 89.96082 -339.52806) (xy 89.911358 -339.504784)
			(xy 89.865827 -339.474533) (xy 89.825204 -339.437954) (xy 89.790361 -339.395833) (xy 89.775792 -339.372702)
			(xy 89.767854 -339.360488) (xy 89.746387 -339.340817) (xy 89.720237 -339.328011) (xy 89.691536 -339.323113)
			(xy 89.662619 -339.326522) (xy 89.649046 -339.331808) (xy 89.62584 -339.341307) (xy 89.577505 -339.354654)
			(xy 89.527814 -339.361379) (xy 89.502742 -339.36178) (xy 89.47485 -339.361364) (xy 89.419689 -339.353056)
			(xy 89.366383 -339.336618) (xy 89.316122 -339.312419) (xy 89.27003 -339.280998) (xy 89.229135 -339.243058)
			(xy 89.194353 -339.199447) (xy 89.16646 -339.151138) (xy 89.146078 -339.099212) (xy 89.133664 -339.044827)
			(xy 89.129495 -338.9892) (xy 85.293803 -338.9892) (xy 85.266213 -339.006931) (xy 85.216636 -339.029573)
			(xy 85.164341 -339.044928) (xy 85.110393 -339.052684) (xy 85.055891 -339.052684) (xy 85.001943 -339.044928)
			(xy 84.949648 -339.029573) (xy 84.900071 -339.006931) (xy 84.854221 -338.977465) (xy 84.81303 -338.941774)
			(xy 84.777339 -338.900583) (xy 84.747873 -338.854733) (xy 84.725231 -338.805156) (xy 84.709876 -338.752861)
			(xy 84.70212 -338.698913) (xy 84.701634 -338.671662) (xy 76.25842 -338.671662) (xy 76.25842 -340.054946)
			(xy 85.671912 -340.054946) (xy 85.675983 -339.999324) (xy 85.688109 -339.944887) (xy 85.708032 -339.892796)
			(xy 85.735328 -339.844161) (xy 85.769414 -339.800018) (xy 85.809563 -339.761309) (xy 85.854921 -339.728858)
			(xy 85.904521 -339.703357) (xy 85.957305 -339.68535) (xy 86.012148 -339.67522) (xy 86.067882 -339.673183)
			(xy 86.123319 -339.679283) (xy 86.177276 -339.693389) (xy 86.228605 -339.715201) (xy 86.276211 -339.744255)
			(xy 86.319079 -339.77993) (xy 86.356296 -339.821467) (xy 86.387069 -339.86798) (xy 86.410741 -339.918477)
			(xy 86.426809 -339.971884) (xy 86.434929 -340.02706) (xy 86.435438 -340.054946) (xy 86.434929 -340.082832)
			(xy 86.426809 -340.138008) (xy 86.410741 -340.191415) (xy 86.387069 -340.241912) (xy 86.356296 -340.288425)
			(xy 86.319079 -340.329962) (xy 86.276211 -340.365637) (xy 86.228605 -340.394691) (xy 86.177276 -340.416503)
			(xy 86.123319 -340.430609) (xy 86.067882 -340.436709) (xy 86.012148 -340.434672) (xy 85.957305 -340.424542)
			(xy 85.904521 -340.406535) (xy 85.854921 -340.381034) (xy 85.809563 -340.348583) (xy 85.769414 -340.309874)
			(xy 85.735328 -340.265731) (xy 85.708032 -340.217096) (xy 85.688109 -340.165005) (xy 85.675983 -340.110568)
			(xy 85.671912 -340.054946) (xy 76.25842 -340.054946) (xy 76.25842 -341.059262) (xy 85.007448 -341.059262)
			(xy 85.011519 -341.00364) (xy 85.023645 -340.949203) (xy 85.043568 -340.897112) (xy 85.070864 -340.848477)
			(xy 85.10495 -340.804334) (xy 85.145099 -340.765625) (xy 85.190457 -340.733174) (xy 85.240057 -340.707673)
			(xy 85.292841 -340.689666) (xy 85.347684 -340.679536) (xy 85.403418 -340.677499) (xy 85.458855 -340.683599)
			(xy 85.512812 -340.697705) (xy 85.564141 -340.719517) (xy 85.611747 -340.748571) (xy 85.654615 -340.784246)
			(xy 85.691832 -340.825783) (xy 85.722605 -340.872296) (xy 85.746277 -340.922793) (xy 85.762345 -340.9762)
			(xy 85.770465 -341.031376) (xy 85.770974 -341.059262) (xy 85.770465 -341.087148) (xy 85.762345 -341.142324)
			(xy 85.746277 -341.195731) (xy 85.722605 -341.246228) (xy 85.691832 -341.292741) (xy 85.654615 -341.334278)
			(xy 85.611747 -341.369953) (xy 85.564141 -341.399007) (xy 85.512812 -341.420819) (xy 85.458855 -341.434925)
			(xy 85.403418 -341.441025) (xy 85.347684 -341.438988) (xy 85.292841 -341.428858) (xy 85.240057 -341.410851)
			(xy 85.190457 -341.38535) (xy 85.145099 -341.352899) (xy 85.10495 -341.31419) (xy 85.070864 -341.270047)
			(xy 85.043568 -341.221412) (xy 85.023645 -341.169321) (xy 85.011519 -341.114884) (xy 85.007448 -341.059262)
			(xy 76.25842 -341.059262) (xy 76.25842 -344.386662) (xy 76.764134 -344.386662) (xy 76.76463 -344.358787)
			(xy 76.772738 -344.30363) (xy 76.78879 -344.250241) (xy 76.812445 -344.199758) (xy 76.843197 -344.153257)
			(xy 76.861416 -344.132154) (xy 76.870999 -344.120785) (xy 76.883633 -344.093879) (xy 76.887962 -344.064472)
			(xy 76.883617 -344.035068) (xy 76.870968 -344.008169) (xy 76.861416 -343.996772) (xy 76.843231 -343.975642)
			(xy 76.812482 -343.929145) (xy 76.788826 -343.878668) (xy 76.772767 -343.825287) (xy 76.764646 -343.770136)
			(xy 76.764134 -343.742264) (xy 76.76462 -343.715013) (xy 76.772376 -343.661065) (xy 76.787731 -343.60877)
			(xy 76.810373 -343.559193) (xy 76.839839 -343.513343) (xy 76.87553 -343.472152) (xy 76.916721 -343.436461)
			(xy 76.962571 -343.406995) (xy 77.012148 -343.384353) (xy 77.064443 -343.368998) (xy 77.118391 -343.361242)
			(xy 77.172893 -343.361242) (xy 77.226841 -343.368998) (xy 77.279136 -343.384353) (xy 77.328713 -343.406995)
			(xy 77.374563 -343.436461) (xy 77.415754 -343.472152) (xy 77.451445 -343.513343) (xy 77.480911 -343.559193)
			(xy 77.503553 -343.60877) (xy 77.518908 -343.661065) (xy 77.526664 -343.715013) (xy 77.52715 -343.742264)
			(xy 77.526649 -343.770139) (xy 77.518539 -343.825295) (xy 77.502486 -343.878683) (xy 77.478834 -343.929165)
			(xy 77.448085 -343.975667) (xy 77.429868 -343.996772) (xy 77.420413 -344.008221) (xy 77.407861 -344.035111)
			(xy 77.403551 -344.064472) (xy 77.407845 -344.093836) (xy 77.420383 -344.120733) (xy 77.429868 -344.132154)
			(xy 77.448078 -344.153263) (xy 77.478821 -344.199767) (xy 77.50247 -344.250249) (xy 77.518524 -344.303635)
			(xy 77.52664 -344.358788) (xy 77.52715 -344.386662) (xy 77.526664 -344.413913) (xy 77.518908 -344.467861)
			(xy 77.503553 -344.520156) (xy 77.480911 -344.569733) (xy 77.451445 -344.615583) (xy 77.415754 -344.656774)
			(xy 77.374563 -344.692465) (xy 77.328713 -344.721931) (xy 77.279136 -344.744573) (xy 77.226841 -344.759928)
			(xy 77.172893 -344.767684) (xy 77.118391 -344.767684) (xy 77.064443 -344.759928) (xy 77.012148 -344.744573)
			(xy 76.962571 -344.721931) (xy 76.916721 -344.692465) (xy 76.87553 -344.656774) (xy 76.839839 -344.615583)
			(xy 76.810373 -344.569733) (xy 76.787731 -344.520156) (xy 76.772376 -344.467861) (xy 76.76462 -344.413913)
			(xy 76.764134 -344.386662) (xy 76.25842 -344.386662) (xy 76.25842 -344.7799) (xy 80.968987 -344.7799)
			(xy 80.973156 -344.724273) (xy 80.98557 -344.669888) (xy 81.005951 -344.617961) (xy 81.033844 -344.569652)
			(xy 81.068626 -344.526041) (xy 81.109519 -344.4881) (xy 81.155611 -344.456678) (xy 81.205871 -344.432478)
			(xy 81.259178 -344.416039) (xy 81.314338 -344.407729) (xy 81.34223 -344.407236) (xy 81.369561 -344.407729)
			(xy 81.42364 -344.415694) (xy 81.475974 -344.431479) (xy 81.525438 -344.454743) (xy 81.570971 -344.484988)
			(xy 81.611594 -344.521563) (xy 81.646434 -344.563683) (xy 81.661 -344.586814) (xy 81.668942 -344.599025)
			(xy 81.690409 -344.618694) (xy 81.716557 -344.631499) (xy 81.745257 -344.636399) (xy 81.774173 -344.632992)
			(xy 81.787746 -344.627708) (xy 81.810954 -344.618212) (xy 81.859288 -344.604863) (xy 81.908978 -344.598138)
			(xy 81.93405 -344.597736) (xy 81.95912 -344.598155) (xy 82.008803 -344.604906) (xy 82.057137 -344.618241)
			(xy 82.080354 -344.627708) (xy 82.093935 -344.632943) (xy 82.122834 -344.63631) (xy 82.151511 -344.631403)
			(xy 82.177645 -344.618617) (xy 82.199119 -344.598987) (xy 82.2071 -344.586814) (xy 82.221669 -344.563683)
			(xy 82.256512 -344.521562) (xy 82.297135 -344.484983) (xy 82.342666 -344.454732) (xy 82.392128 -344.431456)
			(xy 82.444459 -344.415656) (xy 82.498538 -344.40767) (xy 82.553202 -344.40767) (xy 82.607281 -344.415656)
			(xy 82.659612 -344.431456) (xy 82.709074 -344.454732) (xy 82.754605 -344.484983) (xy 82.795228 -344.521562)
			(xy 82.830071 -344.563683) (xy 82.84464 -344.586814) (xy 82.852544 -344.599052) (xy 82.874021 -344.618721)
			(xy 82.90018 -344.631523) (xy 82.928889 -344.636415) (xy 82.957811 -344.632998) (xy 82.971386 -344.627708)
			(xy 82.994601 -344.618231) (xy 83.042931 -344.604875) (xy 83.092619 -344.598142) (xy 83.11769 -344.597736)
			(xy 83.144534 -344.598169) (xy 83.197667 -344.605873) (xy 83.249144 -344.621124) (xy 83.297899 -344.643605)
			(xy 83.342923 -344.67285) (xy 83.383283 -344.708255) (xy 83.418143 -344.749087) (xy 83.446783 -344.794498)
			(xy 83.468608 -344.843551) (xy 83.476338 -344.869262) (xy 83.480962 -344.883774) (xy 83.497487 -344.909342)
			(xy 83.520811 -344.928908) (xy 83.548863 -344.940736) (xy 83.579155 -344.943775) (xy 83.608998 -344.937758)
			(xy 83.622642 -344.930984) (xy 83.65079 -344.916355) (xy 83.71074 -344.895627) (xy 83.773298 -344.885126)
			(xy 83.805014 -344.884502) (xy 83.805268 -344.884502) (xy 83.828344 -344.884849) (xy 83.874159 -344.890427)
			(xy 83.918962 -344.901503) (xy 83.94065 -344.909394) (xy 83.954434 -344.914181) (xy 83.983516 -344.916438)
			(xy 84.012051 -344.910385) (xy 84.037712 -344.896514) (xy 84.058407 -344.875956) (xy 84.072448 -344.850388)
			(xy 84.076032 -344.836242) (xy 84.082655 -344.808282) (xy 84.103249 -344.754639) (xy 84.131655 -344.704692)
			(xy 84.167231 -344.65957) (xy 84.209172 -344.620294) (xy 84.25653 -344.587753) (xy 84.308232 -344.562682)
			(xy 84.363109 -344.545649) (xy 84.41992 -344.537039) (xy 84.44865 -344.536522) (xy 84.475903 -344.537002)
			(xy 84.529855 -344.544753) (xy 84.582154 -344.560104) (xy 84.631736 -344.582743) (xy 84.677591 -344.612208)
			(xy 84.718785 -344.647901) (xy 84.75448 -344.689093) (xy 84.783947 -344.734946) (xy 84.806589 -344.784527)
			(xy 84.821943 -344.836826) (xy 84.829697 -344.890777) (xy 84.830158 -344.91803) (xy 84.82972 -344.945401)
			(xy 84.821897 -344.999582) (xy 84.806402 -345.052086) (xy 84.783554 -345.101832) (xy 84.753822 -345.147798)
			(xy 84.736178 -345.168728) (xy 84.726914 -345.180034) (xy 84.714743 -345.2066) (xy 84.710577 -345.235523)
			(xy 84.714756 -345.264444) (xy 84.726939 -345.291004) (xy 84.736178 -345.302332) (xy 84.753795 -345.323282)
			(xy 84.783511 -345.369249) (xy 84.806352 -345.418992) (xy 84.821848 -345.471489) (xy 84.829681 -345.525662)
			(xy 84.830158 -345.55303) (xy 84.829659 -345.580604) (xy 84.821715 -345.635176) (xy 84.805998 -345.688035)
			(xy 84.782834 -345.738082) (xy 84.752707 -345.784272) (xy 84.716243 -345.825644) (xy 84.695538 -345.84386)
			(xy 84.684608 -345.853726) (xy 84.668531 -345.878384) (xy 84.660147 -345.906601) (xy 84.660153 -345.936037)
			(xy 84.668547 -345.964251) (xy 84.684633 -345.988903) (xy 84.695538 -345.9988) (xy 84.71626 -346.016999)
			(xy 84.752728 -346.058371) (xy 84.782858 -346.104564) (xy 84.806021 -346.154614) (xy 84.821736 -346.207479)
			(xy 84.829674 -346.262055) (xy 84.830158 -346.28963) (xy 84.829773 -346.316886) (xy 84.822011 -346.370842)
			(xy 84.806648 -346.423145) (xy 84.783998 -346.472728) (xy 84.754523 -346.518584) (xy 84.718821 -346.559777)
			(xy 84.67762 -346.595471) (xy 84.631758 -346.624937) (xy 84.58217 -346.647576) (xy 84.529864 -346.662928)
			(xy 84.475906 -346.670679) (xy 84.44865 -346.671138) (xy 84.420776 -346.670626) (xy 84.365624 -346.662506)
			(xy 84.31224 -346.646446) (xy 84.261761 -346.622788) (xy 84.215263 -346.592036) (xy 84.173735 -346.554845)
			(xy 84.138062 -346.512006) (xy 84.109002 -346.464432) (xy 84.097622 -346.438982) (xy 84.090901 -346.424856)
			(xy 84.070496 -346.40117) (xy 84.043891 -346.384752) (xy 84.013571 -346.377136) (xy 83.982366 -346.379032)
			(xy 83.967574 -346.384118) (xy 83.945612 -346.392165) (xy 83.900228 -346.403485) (xy 83.853801 -346.409176)
			(xy 83.830414 -346.409518) (xy 83.816265 -346.409423) (xy 83.788042 -346.407389) (xy 83.774026 -346.405454)
			(xy 83.760682 -346.403807) (xy 83.733981 -346.406912) (xy 83.709021 -346.41689) (xy 83.687538 -346.433048)
			(xy 83.671028 -346.454261) (xy 83.660638 -346.479053) (xy 83.658456 -346.492322) (xy 83.654312 -346.519466)
			(xy 83.639344 -346.572293) (xy 83.616959 -346.622429) (xy 83.587617 -346.668838) (xy 83.551926 -346.710563)
			(xy 83.510623 -346.74674) (xy 83.464561 -346.776623) (xy 83.41469 -346.799594) (xy 83.362042 -346.81518)
			(xy 83.307703 -346.823057) (xy 83.28025 -346.823538) (xy 83.253 -346.822998) (xy 83.199053 -346.815249)
			(xy 83.146759 -346.799901) (xy 83.097181 -346.777266) (xy 83.051329 -346.747806) (xy 83.010136 -346.71212)
			(xy 82.974442 -346.670935) (xy 82.944972 -346.62509) (xy 82.922327 -346.575517) (xy 82.906968 -346.523225)
			(xy 82.899207 -346.46928) (xy 82.898742 -346.44203) (xy 82.899214 -346.414456) (xy 82.907163 -346.359882)
			(xy 82.922886 -346.307022) (xy 82.946055 -346.256976) (xy 82.976187 -346.210786) (xy 83.012655 -346.169415)
			(xy 83.033362 -346.1512) (xy 83.044232 -346.141273) (xy 83.060311 -346.116632) (xy 83.068702 -346.088431)
			(xy 83.068707 -346.059008) (xy 83.060328 -346.030803) (xy 83.044258 -346.006157) (xy 83.033362 -345.99626)
			(xy 83.012669 -345.978029) (xy 82.976199 -345.936664) (xy 82.946066 -345.890478) (xy 82.922897 -345.840434)
			(xy 82.907176 -345.787575) (xy 82.899231 -345.733003) (xy 82.898742 -345.70543) (xy 82.899165 -345.678928)
			(xy 82.906516 -345.626435) (xy 82.921067 -345.575466) (xy 82.942537 -345.527005) (xy 82.970513 -345.481984)
			(xy 82.987134 -345.461336) (xy 82.996597 -345.449205) (xy 83.008386 -345.420799) (xy 83.011207 -345.390174)
			(xy 83.004807 -345.360093) (xy 82.989762 -345.33327) (xy 82.96743 -345.312125) (xy 82.95386 -345.304872)
			(xy 82.930169 -345.292774) (xy 82.886187 -345.26285) (xy 82.846906 -345.226979) (xy 82.813123 -345.185887)
			(xy 82.79892 -345.163394) (xy 82.790957 -345.151198) (xy 82.769496 -345.131528) (xy 82.743354 -345.11872)
			(xy 82.714658 -345.113817) (xy 82.685746 -345.117219) (xy 82.672174 -345.1225) (xy 82.648964 -345.13199)
			(xy 82.600631 -345.145341) (xy 82.550942 -345.152069) (xy 82.52587 -345.152472) (xy 82.500801 -345.152046)
			(xy 82.451118 -345.145297) (xy 82.402783 -345.131966) (xy 82.379566 -345.1225) (xy 82.365978 -345.117283)
			(xy 82.337083 -345.11391) (xy 82.308408 -345.118814) (xy 82.282275 -345.131596) (xy 82.2608 -345.151222)
			(xy 82.25282 -345.163394) (xy 82.238251 -345.186525) (xy 82.203408 -345.228646) (xy 82.162785 -345.265225)
			(xy 82.117254 -345.295476) (xy 82.067792 -345.318752) (xy 82.015461 -345.334552) (xy 81.961382 -345.342538)
			(xy 81.906718 -345.342538) (xy 81.852639 -345.334552) (xy 81.800308 -345.318752) (xy 81.750846 -345.295476)
			(xy 81.705315 -345.265225) (xy 81.664692 -345.228646) (xy 81.629849 -345.186525) (xy 81.61528 -345.163394)
			(xy 81.607355 -345.151171) (xy 81.585884 -345.131501) (xy 81.559731 -345.118696) (xy 81.531026 -345.113801)
			(xy 81.502108 -345.117212) (xy 81.488534 -345.1225) (xy 81.465317 -345.131971) (xy 81.416988 -345.145329)
			(xy 81.367301 -345.152065) (xy 81.34223 -345.152472) (xy 81.314338 -345.152071) (xy 81.259178 -345.143761)
			(xy 81.205871 -345.127322) (xy 81.155611 -345.103122) (xy 81.109519 -345.0717) (xy 81.068626 -345.033759)
			(xy 81.033844 -344.990148) (xy 81.005951 -344.941839) (xy 80.98557 -344.889912) (xy 80.973156 -344.835527)
			(xy 80.968987 -344.7799) (xy 76.25842 -344.7799) (xy 76.25842 -345.845638) (xy 77.5114 -345.845638)
			(xy 77.515471 -345.790016) (xy 77.527597 -345.735579) (xy 77.54752 -345.683488) (xy 77.574816 -345.634853)
			(xy 77.608902 -345.59071) (xy 77.649051 -345.552001) (xy 77.694409 -345.51955) (xy 77.744009 -345.494049)
			(xy 77.796793 -345.476042) (xy 77.851636 -345.465912) (xy 77.90737 -345.463875) (xy 77.962807 -345.469975)
			(xy 78.016764 -345.484081) (xy 78.068093 -345.505893) (xy 78.115699 -345.534947) (xy 78.158567 -345.570622)
			(xy 78.195784 -345.612159) (xy 78.226557 -345.658672) (xy 78.250229 -345.709169) (xy 78.266297 -345.762576)
			(xy 78.274417 -345.817752) (xy 78.274926 -345.845638) (xy 78.274417 -345.873524) (xy 78.266297 -345.9287)
			(xy 78.250229 -345.982107) (xy 78.226557 -346.032604) (xy 78.195784 -346.079117) (xy 78.158567 -346.120654)
			(xy 78.115699 -346.156329) (xy 78.068093 -346.185383) (xy 78.016764 -346.207195) (xy 77.962807 -346.221301)
			(xy 77.90737 -346.227401) (xy 77.851636 -346.225364) (xy 77.796793 -346.215234) (xy 77.744009 -346.197227)
			(xy 77.694409 -346.171726) (xy 77.649051 -346.139275) (xy 77.608902 -346.100566) (xy 77.574816 -346.056423)
			(xy 77.54752 -346.007788) (xy 77.527597 -345.955697) (xy 77.515471 -345.90126) (xy 77.5114 -345.845638)
			(xy 76.25842 -345.845638) (xy 76.25842 -346.825062) (xy 76.846936 -346.825062) (xy 76.851007 -346.76944)
			(xy 76.863133 -346.715003) (xy 76.883056 -346.662912) (xy 76.910352 -346.614277) (xy 76.944438 -346.570134)
			(xy 76.984587 -346.531425) (xy 77.029945 -346.498974) (xy 77.079545 -346.473473) (xy 77.132329 -346.455466)
			(xy 77.187172 -346.445336) (xy 77.242906 -346.443299) (xy 77.298343 -346.449399) (xy 77.3523 -346.463505)
			(xy 77.403629 -346.485317) (xy 77.451235 -346.514371) (xy 77.494103 -346.550046) (xy 77.53132 -346.591583)
			(xy 77.562093 -346.638096) (xy 77.585765 -346.688593) (xy 77.601833 -346.742) (xy 77.609953 -346.797176)
			(xy 77.610462 -346.825062) (xy 77.609953 -346.852948) (xy 77.601833 -346.908124) (xy 77.585765 -346.961531)
			(xy 77.562093 -347.012028) (xy 77.53132 -347.058541) (xy 77.494103 -347.100078) (xy 77.451235 -347.135753)
			(xy 77.403629 -347.164807) (xy 77.3523 -347.186619) (xy 77.298343 -347.200725) (xy 77.242906 -347.206825)
			(xy 77.187172 -347.204788) (xy 77.132329 -347.194658) (xy 77.079545 -347.176651) (xy 77.029945 -347.15115)
			(xy 76.984587 -347.118699) (xy 76.944438 -347.07999) (xy 76.910352 -347.035847) (xy 76.883056 -346.987212)
			(xy 76.863133 -346.935121) (xy 76.851007 -346.880684) (xy 76.846936 -346.825062) (xy 76.25842 -346.825062)
			(xy 76.25842 -347.439234) (xy 78.318106 -347.439234) (xy 78.318683 -347.409547) (xy 78.327877 -347.350889)
			(xy 78.346048 -347.294363) (xy 78.372757 -347.241335) (xy 78.407359 -347.193086) (xy 78.449019 -347.15078)
			(xy 78.472538 -347.132656) (xy 78.483121 -347.124203) (xy 78.499823 -347.102895) (xy 78.510339 -347.077947)
			(xy 78.513931 -347.051113) (xy 78.510346 -347.024278) (xy 78.499836 -346.999328) (xy 78.48314 -346.978016)
			(xy 78.472538 -346.969588) (xy 78.44903 -346.951449) (xy 78.407367 -346.909147) (xy 78.372762 -346.860901)
			(xy 78.346048 -346.807876) (xy 78.327872 -346.751353) (xy 78.318672 -346.692697) (xy 78.318106 -346.66301)
			(xy 78.318541 -346.635744) (xy 78.326303 -346.581768) (xy 78.341672 -346.529446) (xy 78.364333 -346.479846)
			(xy 78.393826 -346.433978) (xy 78.429548 -346.392776) (xy 78.470773 -346.357079) (xy 78.516661 -346.327616)
			(xy 78.566275 -346.304987) (xy 78.618606 -346.289651) (xy 78.672588 -346.281923) (xy 78.72712 -346.28196)
			(xy 78.781091 -346.28976) (xy 78.833401 -346.305164) (xy 78.882986 -346.32786) (xy 78.928834 -346.357384)
			(xy 78.970011 -346.393135) (xy 79.005679 -346.434385) (xy 79.03511 -346.480293) (xy 79.057706 -346.529923)
			(xy 79.073004 -346.582265) (xy 79.080695 -346.636251) (xy 79.081122 -346.663518) (xy 79.081122 -346.684854)
			(xy 79.18069 -346.784422) (xy 79.191664 -346.794693) (xy 79.218198 -346.808791) (xy 79.247684 -346.81457)
			(xy 79.277577 -346.811532) (xy 79.305297 -346.799938) (xy 79.328452 -346.78079) (xy 79.345043 -346.755739)
			(xy 79.349854 -346.741496) (xy 79.358106 -346.715604) (xy 79.380869 -346.66626) (xy 79.410402 -346.620643)
			(xy 79.446106 -346.579678) (xy 79.48726 -346.54419) (xy 79.533032 -346.514899) (xy 79.582495 -346.492397)
			(xy 79.634651 -346.477139) (xy 79.688443 -346.469433) (xy 79.715614 -346.468954) (xy 79.715868 -346.468954)
			(xy 79.741071 -346.469366) (xy 79.791039 -346.476001) (xy 79.839693 -346.489174) (xy 79.886184 -346.508654)
			(xy 79.908146 -346.521024) (xy 79.92109 -346.528106) (xy 79.949736 -346.535138) (xy 79.979196 -346.533688)
			(xy 80.007013 -346.523877) (xy 80.030865 -346.506525) (xy 80.048761 -346.483078) (xy 80.05445 -346.469462)
			(xy 80.065151 -346.442688) (xy 80.09344 -346.392448) (xy 80.12897 -346.34704) (xy 80.170931 -346.307498)
			(xy 80.218368 -346.274725) (xy 80.270197 -346.249466) (xy 80.325239 -346.232299) (xy 80.382238 -346.223613)
			(xy 80.411066 -346.223082) (xy 80.438318 -346.223587) (xy 80.492266 -346.231339) (xy 80.544563 -346.24669)
			(xy 80.594142 -346.269328) (xy 80.639995 -346.298792) (xy 80.681188 -346.334481) (xy 80.716882 -346.37567)
			(xy 80.746351 -346.421519) (xy 80.768994 -346.471096) (xy 80.784352 -346.52339) (xy 80.79211 -346.577338)
			(xy 80.792574 -346.60459) (xy 80.792574 -346.604844) (xy 80.792003 -346.634683) (xy 80.782685 -346.693629)
			(xy 80.774032 -346.722192) (xy 80.769931 -346.736084) (xy 80.769028 -346.765028) (xy 80.776304 -346.793057)
			(xy 80.791169 -346.817907) (xy 80.812425 -346.837573) (xy 80.838354 -346.850466) (xy 80.852518 -346.85351)
			(xy 80.878588 -346.858694) (xy 80.929091 -346.875263) (xy 80.976803 -346.898685) (xy 81.020801 -346.928505)
			(xy 81.060232 -346.964146) (xy 81.094332 -347.004918) (xy 81.122439 -347.050029) (xy 81.144009 -347.098607)
			(xy 81.158625 -347.149709) (xy 81.166003 -347.202346) (xy 81.166462 -347.228922) (xy 81.165976 -347.256173)
			(xy 81.15822 -347.310121) (xy 81.142865 -347.362416) (xy 81.120223 -347.411993) (xy 81.090757 -347.457843)
			(xy 81.055066 -347.499034) (xy 81.013875 -347.534725) (xy 80.968025 -347.564191) (xy 80.918448 -347.586833)
			(xy 80.866153 -347.602188) (xy 80.812205 -347.609944) (xy 80.757703 -347.609944) (xy 80.703755 -347.602188)
			(xy 80.65146 -347.586833) (xy 80.601883 -347.564191) (xy 80.556033 -347.534725) (xy 80.514842 -347.499034)
			(xy 80.479151 -347.457843) (xy 80.449685 -347.411993) (xy 80.427043 -347.362416) (xy 80.411688 -347.310121)
			(xy 80.403932 -347.256173) (xy 80.403446 -347.228922) (xy 80.403446 -347.228668) (xy 80.404023 -347.198829)
			(xy 80.413337 -347.139883) (xy 80.421988 -347.11132) (xy 80.426059 -347.097421) (xy 80.426964 -347.068483)
			(xy 80.419693 -347.040458) (xy 80.404833 -347.01561) (xy 80.383585 -346.995944) (xy 80.357663 -346.983049)
			(xy 80.343502 -346.980002) (xy 80.310662 -346.97342) (xy 80.24781 -346.950297) (xy 80.218534 -346.934028)
			(xy 80.205591 -346.926948) (xy 80.176946 -346.919925) (xy 80.147488 -346.921379) (xy 80.119674 -346.931189)
			(xy 80.095823 -346.948537) (xy 80.077923 -346.971977) (xy 80.07223 -346.98559) (xy 80.06152 -347.012361)
			(xy 80.033235 -347.062603) (xy 79.997708 -347.108013) (xy 79.955748 -347.147557) (xy 79.908313 -347.180331)
			(xy 79.856483 -347.20559) (xy 79.801441 -347.222757) (xy 79.744442 -347.23144) (xy 79.715614 -347.23197)
			(xy 79.685373 -347.231376) (xy 79.625652 -347.221812) (xy 79.596742 -347.21292) (xy 79.583569 -347.209018)
			(xy 79.556135 -347.2077) (xy 79.529343 -347.213744) (xy 79.505132 -347.226712) (xy 79.485254 -347.245666)
			(xy 79.471149 -347.269233) (xy 79.463837 -347.295707) (xy 79.463392 -347.30944) (xy 79.463392 -348.151196)
			(xy 79.462748 -348.176178) (xy 79.453013 -348.225183) (xy 79.433915 -348.271353) (xy 79.406186 -348.312916)
			(xy 79.38897 -348.331028) (xy 79.341472 -348.378526) (xy 79.341472 -348.62008) (xy 79.714598 -348.992952)
			(xy 84.486242 -348.992952) (xy 87.357204 -346.122244) (xy 87.375311 -346.105) (xy 87.416851 -346.077186)
			(xy 87.463019 -346.058009) (xy 87.512041 -346.048206) (xy 87.537036 -346.047568) (xy 97.824798 -346.047568)
			(xy 97.849795 -346.048192) (xy 97.898819 -346.057998) (xy 97.94499 -346.077175) (xy 97.986535 -346.104987)
			(xy 98.00463 -346.122244) (xy 98.970338 -347.087952) (xy 98.987549 -347.106071) (xy 99.015293 -347.147627)
			(xy 99.034404 -347.193794) (xy 99.044148 -347.242801) (xy 99.04476 -347.267784) (xy 99.04476 -349.269304)
			(xy 101.000306 -351.22485) (xy 101.055424 -351.169986) (xy 101.050344 -351.143316) (xy 101.048213 -351.131493)
			(xy 101.045924 -351.107577) (xy 101.045772 -351.095564) (xy 101.045772 -343.473278) (xy 100.12553 -342.553036)
			(xy 93.75902 -342.553036) (xy 92.240424 -344.071632) (xy 96.449892 -344.071632) (xy 96.449892 -343.986936)
			(xy 96.457943 -343.902622) (xy 96.473972 -343.819456) (xy 96.497833 -343.738189) (xy 96.529312 -343.659559)
			(xy 96.568123 -343.584278) (xy 96.613913 -343.513026) (xy 96.666269 -343.44645) (xy 96.724717 -343.385152)
			(xy 96.788727 -343.329687) (xy 96.857719 -343.280558) (xy 96.931069 -343.238209) (xy 97.008112 -343.203025)
			(xy 97.088151 -343.175323) (xy 97.17046 -343.155355) (xy 97.254295 -343.143302) (xy 97.338896 -343.139272)
			(xy 97.423497 -343.143302) (xy 97.507332 -343.155355) (xy 97.589641 -343.175323) (xy 97.66968 -343.203025)
			(xy 97.746723 -343.238209) (xy 97.820073 -343.280558) (xy 97.889065 -343.329687) (xy 97.953075 -343.385152)
			(xy 98.011523 -343.44645) (xy 98.063879 -343.513026) (xy 98.109669 -343.584278) (xy 98.14848 -343.659559)
			(xy 98.179959 -343.738189) (xy 98.20382 -343.819456) (xy 98.219849 -343.902622) (xy 98.2279 -343.986936)
			(xy 98.228404 -344.029284) (xy 98.974405 -344.029284) (xy 98.978441 -343.945837) (xy 98.990513 -343.863169)
			(xy 99.010506 -343.782052) (xy 99.038235 -343.703243) (xy 99.073441 -343.627478) (xy 99.115795 -343.555465)
			(xy 99.164901 -343.487876) (xy 99.220302 -343.425342) (xy 99.281479 -343.368447) (xy 99.347862 -343.317721)
			(xy 99.41883 -343.27364) (xy 99.493722 -343.236614) (xy 99.571838 -343.206988) (xy 99.652448 -343.18504)
			(xy 99.7348 -343.170975) (xy 99.818126 -343.164923) (xy 99.901646 -343.166942) (xy 99.984582 -343.177012)
			(xy 100.066158 -343.19504) (xy 100.145614 -343.220857) (xy 100.222207 -343.254222) (xy 100.295223 -343.294823)
			(xy 100.363979 -343.342282) (xy 100.427833 -343.396155) (xy 100.48619 -343.45594) (xy 100.538505 -343.521077)
			(xy 100.584288 -343.59096) (xy 100.623113 -343.664935) (xy 100.654618 -343.742312) (xy 100.678507 -343.822369)
			(xy 100.694558 -343.904357) (xy 100.702621 -343.987512) (xy 100.703126 -344.029284) (xy 100.702621 -344.071056)
			(xy 100.694558 -344.154211) (xy 100.678507 -344.236199) (xy 100.654618 -344.316256) (xy 100.623113 -344.393633)
			(xy 100.584288 -344.467608) (xy 100.538505 -344.537491) (xy 100.48619 -344.602628) (xy 100.427833 -344.662413)
			(xy 100.363979 -344.716286) (xy 100.295223 -344.763745) (xy 100.222207 -344.804346) (xy 100.145614 -344.837711)
			(xy 100.066158 -344.863528) (xy 99.984582 -344.881556) (xy 99.901646 -344.891626) (xy 99.818126 -344.893645)
			(xy 99.7348 -344.887593) (xy 99.652448 -344.873528) (xy 99.571838 -344.85158) (xy 99.493722 -344.821954)
			(xy 99.41883 -344.784928) (xy 99.347862 -344.740847) (xy 99.281479 -344.690121) (xy 99.220302 -344.633226)
			(xy 99.164901 -344.570692) (xy 99.115795 -344.503103) (xy 99.073441 -344.43109) (xy 99.038235 -344.355325)
			(xy 99.010506 -344.276516) (xy 98.990513 -344.195399) (xy 98.978441 -344.112731) (xy 98.974405 -344.029284)
			(xy 98.228404 -344.029284) (xy 98.2279 -344.071632) (xy 98.219849 -344.155946) (xy 98.20382 -344.239112)
			(xy 98.179959 -344.320379) (xy 98.14848 -344.399009) (xy 98.109669 -344.47429) (xy 98.063879 -344.545542)
			(xy 98.011523 -344.612118) (xy 97.953075 -344.673416) (xy 97.889065 -344.728881) (xy 97.820073 -344.77801)
			(xy 97.746723 -344.820359) (xy 97.66968 -344.855543) (xy 97.589641 -344.883245) (xy 97.507332 -344.903213)
			(xy 97.423497 -344.915266) (xy 97.338896 -344.919297) (xy 97.254295 -344.915266) (xy 97.17046 -344.903213)
			(xy 97.088151 -344.883245) (xy 97.008112 -344.855543) (xy 96.931069 -344.820359) (xy 96.857719 -344.77801)
			(xy 96.788727 -344.728881) (xy 96.724717 -344.673416) (xy 96.666269 -344.612118) (xy 96.613913 -344.545542)
			(xy 96.568123 -344.47429) (xy 96.529312 -344.399009) (xy 96.497833 -344.320379) (xy 96.473972 -344.239112)
			(xy 96.457943 -344.155946) (xy 96.449892 -344.071632) (xy 92.240424 -344.071632) (xy 91.822778 -344.489278)
			(xy 91.804694 -344.506529) (xy 91.763125 -344.534264) (xy 91.716947 -344.553363) (xy 91.667932 -344.563094)
			(xy 91.642946 -344.5637) (xy 88.056212 -344.5637) (xy 88.031231 -344.563049) (xy 87.982225 -344.553315)
			(xy 87.936056 -344.534219) (xy 87.894493 -344.506493) (xy 87.87638 -344.489278) (xy 86.824566 -343.437464)
			(xy 86.807363 -343.419337) (xy 86.779617 -343.377784) (xy 86.760504 -343.331619) (xy 86.750758 -343.282614)
			(xy 86.750144 -343.257632) (xy 86.750144 -342.015318) (xy 86.71814 -342.002618) (xy 86.691973 -341.991631)
			(xy 86.643008 -341.962937) (xy 86.598834 -341.927306) (xy 86.560427 -341.885524) (xy 86.528633 -341.838513)
			(xy 86.504156 -341.78731) (xy 86.487533 -341.733046) (xy 86.479134 -341.676918) (xy 86.478618 -341.648542)
			(xy 86.479196 -341.618855) (xy 86.488389 -341.560196) (xy 86.506559 -341.503671) (xy 86.533268 -341.450643)
			(xy 86.56787 -341.402394) (xy 86.609531 -341.360088) (xy 86.63305 -341.341964) (xy 86.643624 -341.333501)
			(xy 86.660324 -341.312195) (xy 86.670839 -341.28725) (xy 86.674432 -341.260418) (xy 86.670849 -341.233585)
			(xy 86.660342 -341.208636) (xy 86.64365 -341.187324) (xy 86.63305 -341.178896) (xy 86.609527 -341.160776)
			(xy 86.56787 -341.118467) (xy 86.533268 -341.070217) (xy 86.506558 -341.017189) (xy 86.488384 -340.960663)
			(xy 86.479184 -340.902005) (xy 86.478618 -340.872318) (xy 86.479028 -340.845051) (xy 86.48679 -340.791072)
			(xy 86.502159 -340.738748) (xy 86.52482 -340.689145) (xy 86.554313 -340.643274) (xy 86.590037 -340.60207)
			(xy 86.631263 -340.566372) (xy 86.677153 -340.536907) (xy 86.726769 -340.514276) (xy 86.779103 -340.49894)
			(xy 86.833087 -340.491211) (xy 86.887621 -340.491248) (xy 86.941594 -340.499048) (xy 86.993907 -340.514454)
			(xy 87.043494 -340.537151) (xy 87.089344 -340.566677) (xy 87.130523 -340.60243) (xy 87.166191 -340.643682)
			(xy 87.195623 -340.689592) (xy 87.218219 -340.739225) (xy 87.233518 -340.791569) (xy 87.241208 -340.845558)
			(xy 87.241634 -340.872826) (xy 87.241634 -340.894162) (xy 87.341202 -340.99373) (xy 87.352268 -341.003894)
			(xy 87.378777 -341.017996) (xy 87.408239 -341.023786) (xy 87.438113 -341.020763) (xy 87.465819 -341.009189)
			(xy 87.488965 -340.990063) (xy 87.505554 -340.965035) (xy 87.510366 -340.950804) (xy 87.518612 -340.92491)
			(xy 87.541376 -340.875565) (xy 87.570908 -340.829948) (xy 87.606613 -340.788982) (xy 87.647768 -340.753494)
			(xy 87.693541 -340.724204) (xy 87.743005 -340.701702) (xy 87.795162 -340.686445) (xy 87.848955 -340.67874)
			(xy 87.876126 -340.678262) (xy 87.87638 -340.678262) (xy 87.901584 -340.678667) (xy 87.951551 -340.685305)
			(xy 88.000206 -340.698479) (xy 88.046696 -340.717961) (xy 88.068658 -340.730332) (xy 88.081597 -340.737424)
			(xy 88.110245 -340.744453) (xy 88.139706 -340.743) (xy 88.167523 -340.733188) (xy 88.191376 -340.715834)
			(xy 88.209273 -340.692386) (xy 88.214962 -340.67877) (xy 88.225657 -340.651993) (xy 88.253946 -340.601753)
			(xy 88.289477 -340.556344) (xy 88.331439 -340.516802) (xy 88.378876 -340.484029) (xy 88.430707 -340.458771)
			(xy 88.48575 -340.441604) (xy 88.542749 -340.43292) (xy 88.571578 -340.43239) (xy 88.59883 -340.432876)
			(xy 88.65278 -340.44063) (xy 88.705078 -340.455983) (xy 88.754657 -340.478623) (xy 88.800511 -340.508088)
			(xy 88.841703 -340.54378) (xy 88.877397 -340.58497) (xy 88.906866 -340.630821) (xy 88.929509 -340.6804)
			(xy 88.944865 -340.732696) (xy 88.952623 -340.786646) (xy 88.953086 -340.813898) (xy 88.953086 -340.814152)
			(xy 88.952517 -340.843991) (xy 88.943197 -340.902937) (xy 88.934544 -340.9315) (xy 88.930537 -340.945417)
			(xy 88.929613 -340.974348) (xy 88.936868 -341.00237) (xy 88.951716 -341.027217) (xy 88.972956 -341.046881)
			(xy 88.998872 -341.059774) (xy 89.01303 -341.062818) (xy 89.039103 -341.067986) (xy 89.089607 -341.084557)
			(xy 89.13732 -341.107981) (xy 89.181318 -341.137803) (xy 89.220748 -341.173446) (xy 89.254847 -341.214219)
			(xy 89.282954 -341.259332) (xy 89.304524 -341.307912) (xy 89.319139 -341.359015) (xy 89.326516 -341.411654)
			(xy 89.326974 -341.43823) (xy 89.326488 -341.465481) (xy 89.318732 -341.519429) (xy 89.303377 -341.571724)
			(xy 89.280735 -341.621301) (xy 89.251269 -341.667151) (xy 89.215578 -341.708342) (xy 89.174387 -341.744033)
			(xy 89.128537 -341.773499) (xy 89.07896 -341.796141) (xy 89.026665 -341.811496) (xy 88.972717 -341.819252)
			(xy 88.918215 -341.819252) (xy 88.864267 -341.811496) (xy 88.811972 -341.796141) (xy 88.762395 -341.773499)
			(xy 88.716545 -341.744033) (xy 88.675354 -341.708342) (xy 88.639663 -341.667151) (xy 88.610197 -341.621301)
			(xy 88.587555 -341.571724) (xy 88.5722 -341.519429) (xy 88.564444 -341.465481) (xy 88.563958 -341.43823)
			(xy 88.563958 -341.437976) (xy 88.564536 -341.408137) (xy 88.57385 -341.349191) (xy 88.5825 -341.320628)
			(xy 88.586553 -341.306724) (xy 88.587459 -341.277789) (xy 88.580191 -341.249768) (xy 88.565335 -341.224921)
			(xy 88.544091 -341.205255) (xy 88.518173 -341.192358) (xy 88.504014 -341.18931) (xy 88.471175 -341.182725)
			(xy 88.408323 -341.159603) (xy 88.379046 -341.143336) (xy 88.366097 -341.136266) (xy 88.337454 -341.12924)
			(xy 88.307998 -341.130691) (xy 88.280185 -341.140499) (xy 88.256334 -341.157846) (xy 88.238434 -341.181286)
			(xy 88.232742 -341.194898) (xy 88.222026 -341.221666) (xy 88.193742 -341.271908) (xy 88.158215 -341.317317)
			(xy 88.116256 -341.356861) (xy 88.068821 -341.389635) (xy 88.016993 -341.414895) (xy 87.961952 -341.432062)
			(xy 87.904954 -341.440747) (xy 87.876126 -341.441278) (xy 87.875872 -341.441278) (xy 87.860307 -341.441113)
			(xy 87.82928 -341.43857) (xy 87.813896 -341.436198) (xy 87.799299 -341.434276) (xy 87.770097 -341.437938)
			(xy 87.743144 -341.449759) (xy 87.72067 -341.468761) (xy 87.704533 -341.493373) (xy 87.696068 -341.52156)
			(xy 87.695532 -341.536274) (xy 87.695532 -343.050114) (xy 88.31961 -343.674192) (xy 91.379548 -343.674192)
			(xy 93.31579 -341.73795) (xy 93.333891 -341.720719) (xy 93.375454 -341.692979) (xy 93.421626 -341.673874)
			(xy 93.470637 -341.664137) (xy 93.495622 -341.663528) (xy 100.388928 -341.663528) (xy 100.413911 -341.664147)
			(xy 100.462918 -341.673889) (xy 100.509088 -341.692994) (xy 100.550649 -341.72073) (xy 100.56876 -341.73795)
			(xy 101.860858 -343.030048) (xy 101.878071 -343.048166) (xy 101.905814 -343.089723) (xy 101.924923 -343.13589)
			(xy 101.934667 -343.184897) (xy 101.93528 -343.20988) (xy 101.93528 -350.831658) (xy 102.828344 -351.724468)
			(xy 102.839311 -351.734663) (xy 102.865704 -351.748773) (xy 102.895055 -351.75462) (xy 102.92484 -351.751701)
			(xy 102.952497 -351.740266) (xy 102.975647 -351.721299) (xy 102.992299 -351.696432) (xy 103.001021 -351.667803)
			(xy 103.001572 -351.65284) (xy 103.001572 -350.422464) (xy 103.787448 -349.636588) (xy 105.574084 -349.636588)
			(xy 105.574084 -348.949264) (xy 102.602792 -345.977972) (xy 102.585528 -345.959883) (xy 102.55772 -345.918336)
			(xy 102.538549 -345.872163) (xy 102.528752 -345.823137) (xy 102.528116 -345.79814) (xy 102.528116 -342.730074)
			(xy 100.168202 -340.37016) (xy 95.546926 -340.37016) (xy 95.52193 -340.369513) (xy 95.472908 -340.359713)
			(xy 95.426737 -340.340543) (xy 95.385191 -340.312738) (xy 95.367094 -340.295484) (xy 94.951042 -339.879432)
			(xy 94.93382 -339.861322) (xy 94.906079 -339.819763) (xy 94.886971 -339.773593) (xy 94.877231 -339.724584)
			(xy 94.87662 -339.6996) (xy 94.87662 -338.592922) (xy 94.84868 -338.578952) (xy 94.825387 -338.566692)
			(xy 94.782113 -338.536723) (xy 94.743368 -338.501092) (xy 94.709888 -338.460474) (xy 94.682306 -338.415641)
			(xy 94.661147 -338.367443) (xy 94.646813 -338.316795) (xy 94.639574 -338.264657) (xy 94.63913 -338.238338)
			(xy 94.639701 -338.20865) (xy 94.648894 -338.149991) (xy 94.667066 -338.093465) (xy 94.693776 -338.040437)
			(xy 94.72838 -337.992188) (xy 94.770042 -337.949884) (xy 94.793562 -337.93176) (xy 94.804147 -337.923306)
			(xy 94.820861 -337.902002) (xy 94.831386 -337.877054) (xy 94.834982 -337.850216) (xy 94.831395 -337.823376)
			(xy 94.820877 -337.798425) (xy 94.80417 -337.777116) (xy 94.793562 -337.768692) (xy 94.77004 -337.750571)
			(xy 94.728382 -337.708263) (xy 94.69378 -337.660013) (xy 94.667069 -337.606985) (xy 94.648895 -337.55046)
			(xy 94.639696 -337.491801) (xy 94.63913 -337.462114) (xy 94.639516 -337.434846) (xy 94.647279 -337.380866)
			(xy 94.662648 -337.328541) (xy 94.685311 -337.278937) (xy 94.714805 -337.233065) (xy 94.75053 -337.19186)
			(xy 94.791758 -337.156161) (xy 94.837648 -337.126696) (xy 94.887266 -337.104064) (xy 94.939601 -337.088728)
			(xy 94.993586 -337.080999) (xy 95.048121 -337.081036) (xy 95.102096 -337.088836) (xy 95.154411 -337.104242)
			(xy 95.203998 -337.12694) (xy 95.24985 -337.156466) (xy 95.29103 -337.19222) (xy 95.3267 -337.233473)
			(xy 95.356133 -337.279384) (xy 95.378729 -337.329018) (xy 95.394029 -337.381363) (xy 95.401719 -337.435354)
			(xy 95.402146 -337.462622) (xy 95.402146 -337.483958) (xy 95.501714 -337.583526) (xy 95.512767 -337.593706)
			(xy 95.539279 -337.607808) (xy 95.568745 -337.613596) (xy 95.598622 -337.610572) (xy 95.62633 -337.598994)
			(xy 95.649478 -337.579864) (xy 95.666066 -337.554833) (xy 95.670878 -337.5406) (xy 95.679111 -337.514701)
			(xy 95.701876 -337.465356) (xy 95.73141 -337.419739) (xy 95.767117 -337.378772) (xy 95.808273 -337.343285)
			(xy 95.854048 -337.313995) (xy 95.903514 -337.291495) (xy 95.955672 -337.276238) (xy 96.009466 -337.268535)
			(xy 96.036638 -337.268058) (xy 96.036892 -337.268058) (xy 96.062096 -337.268459) (xy 96.112064 -337.275098)
			(xy 96.160718 -337.288274) (xy 96.207208 -337.307756) (xy 96.22917 -337.320128) (xy 96.24216 -337.327118)
			(xy 96.270787 -337.334163) (xy 96.300234 -337.332729) (xy 96.328041 -337.322936) (xy 96.351888 -337.305602)
			(xy 96.369784 -337.282173) (xy 96.375474 -337.268566) (xy 96.386157 -337.241784) (xy 96.414448 -337.191543)
			(xy 96.44998 -337.146135) (xy 96.491944 -337.106593) (xy 96.539383 -337.07382) (xy 96.591215 -337.048563)
			(xy 96.64626 -337.031398) (xy 96.703261 -337.022716) (xy 96.73209 -337.022186) (xy 96.759342 -337.022665)
			(xy 96.813292 -337.03042) (xy 96.86559 -337.045775) (xy 96.915169 -337.068415) (xy 96.961022 -337.097882)
			(xy 97.002215 -337.133574) (xy 97.037909 -337.174765) (xy 97.067377 -337.220617) (xy 97.09002 -337.270195)
			(xy 97.105377 -337.322492) (xy 97.113134 -337.376442) (xy 97.113598 -337.403694) (xy 97.113598 -337.403948)
			(xy 97.113027 -337.433787) (xy 97.103709 -337.492733) (xy 97.095056 -337.521296) (xy 97.091124 -337.53523)
			(xy 97.090201 -337.564145) (xy 97.097449 -337.592153) (xy 97.112281 -337.616992) (xy 97.1335 -337.636657)
			(xy 97.159394 -337.64956) (xy 97.173542 -337.652614) (xy 97.199616 -337.657777) (xy 97.25012 -337.674349)
			(xy 97.297832 -337.697774) (xy 97.34183 -337.727597) (xy 97.38126 -337.763241) (xy 97.415359 -337.804014)
			(xy 97.443465 -337.849128) (xy 97.465035 -337.897707) (xy 97.47965 -337.948811) (xy 97.487027 -338.00145)
			(xy 97.487486 -338.028026) (xy 97.487 -338.055277) (xy 97.479244 -338.109225) (xy 97.463889 -338.16152)
			(xy 97.441247 -338.211097) (xy 97.411781 -338.256947) (xy 97.37609 -338.298138) (xy 97.334899 -338.333829)
			(xy 97.289049 -338.363295) (xy 97.239472 -338.385937) (xy 97.187177 -338.401292) (xy 97.133229 -338.409048)
			(xy 97.078727 -338.409048) (xy 97.024779 -338.401292) (xy 96.972484 -338.385937) (xy 96.922907 -338.363295)
			(xy 96.877057 -338.333829) (xy 96.835866 -338.298138) (xy 96.800175 -338.256947) (xy 96.770709 -338.211097)
			(xy 96.748067 -338.16152) (xy 96.732712 -338.109225) (xy 96.724956 -338.055277) (xy 96.72447 -338.028026)
			(xy 96.72447 -338.027772) (xy 96.725047 -337.997933) (xy 96.734361 -337.938987) (xy 96.743012 -337.910424)
			(xy 96.74706 -337.896519) (xy 96.747965 -337.867586) (xy 96.740696 -337.839565) (xy 96.725842 -337.81472)
			(xy 96.704599 -337.795054) (xy 96.678684 -337.782155) (xy 96.664526 -337.779106) (xy 96.631688 -337.772518)
			(xy 96.568835 -337.749399) (xy 96.539558 -337.733132) (xy 96.526602 -337.726078) (xy 96.497962 -337.71905)
			(xy 96.468508 -337.720499) (xy 96.440696 -337.730304) (xy 96.416846 -337.747648) (xy 96.398947 -337.771083)
			(xy 96.393254 -337.784694) (xy 96.382526 -337.811457) (xy 96.354243 -337.861698) (xy 96.318718 -337.907108)
			(xy 96.276761 -337.946651) (xy 96.229328 -337.979427) (xy 96.177501 -338.004687) (xy 96.122462 -338.021856)
			(xy 96.065465 -338.030542) (xy 96.036638 -338.031074) (xy 96.014981 -338.030742) (xy 95.97195 -338.025776)
			(xy 95.950786 -338.021168) (xy 95.935778 -338.018249) (xy 95.905298 -338.020442) (xy 95.876824 -338.031534)
			(xy 95.852892 -338.050538) (xy 95.835637 -338.075758) (xy 95.826596 -338.104949) (xy 95.826072 -338.120228)
			(xy 95.826072 -339.355684) (xy 95.931228 -339.46084) (xy 100.439728 -339.46084) (xy 100.464711 -339.461456)
			(xy 100.513719 -339.471198) (xy 100.559888 -339.490304) (xy 100.601449 -339.518041) (xy 100.61956 -339.535262)
			(xy 103.363014 -342.278716) (xy 103.380252 -342.296812) (xy 103.407992 -342.338375) (xy 103.427096 -342.38455)
			(xy 103.436829 -342.433563) (xy 103.437436 -342.458548) (xy 103.437436 -344.071632) (xy 104.010456 -344.071632)
			(xy 104.010456 -343.986936) (xy 104.018507 -343.902622) (xy 104.034536 -343.819456) (xy 104.058397 -343.738189)
			(xy 104.089876 -343.659559) (xy 104.128687 -343.584278) (xy 104.174477 -343.513026) (xy 104.226833 -343.44645)
			(xy 104.285281 -343.385152) (xy 104.349291 -343.329687) (xy 104.418283 -343.280558) (xy 104.491633 -343.238209)
			(xy 104.568676 -343.203025) (xy 104.648715 -343.175323) (xy 104.731024 -343.155355) (xy 104.814859 -343.143302)
			(xy 104.89946 -343.139272) (xy 104.984061 -343.143302) (xy 105.067896 -343.155355) (xy 105.150205 -343.175323)
			(xy 105.230244 -343.203025) (xy 105.307287 -343.238209) (xy 105.380637 -343.280558) (xy 105.449629 -343.329687)
			(xy 105.513639 -343.385152) (xy 105.572087 -343.44645) (xy 105.624443 -343.513026) (xy 105.670233 -343.584278)
			(xy 105.709044 -343.659559) (xy 105.740523 -343.738189) (xy 105.764384 -343.819456) (xy 105.780413 -343.902622)
			(xy 105.788464 -343.986936) (xy 105.788968 -344.029284) (xy 106.534969 -344.029284) (xy 106.539005 -343.945837)
			(xy 106.551077 -343.863169) (xy 106.57107 -343.782052) (xy 106.598799 -343.703243) (xy 106.634005 -343.627478)
			(xy 106.676359 -343.555465) (xy 106.725465 -343.487876) (xy 106.780866 -343.425342) (xy 106.842043 -343.368447)
			(xy 106.908426 -343.317721) (xy 106.979394 -343.27364) (xy 107.054286 -343.236614) (xy 107.132402 -343.206988)
			(xy 107.213012 -343.18504) (xy 107.295364 -343.170975) (xy 107.37869 -343.164923) (xy 107.46221 -343.166942)
			(xy 107.545146 -343.177012) (xy 107.626722 -343.19504) (xy 107.706178 -343.220857) (xy 107.782771 -343.254222)
			(xy 107.855787 -343.294823) (xy 107.924543 -343.342282) (xy 107.988397 -343.396155) (xy 108.046754 -343.45594)
			(xy 108.099069 -343.521077) (xy 108.144852 -343.59096) (xy 108.183677 -343.664935) (xy 108.215182 -343.742312)
			(xy 108.239071 -343.822369) (xy 108.255122 -343.904357) (xy 108.263185 -343.987512) (xy 108.26369 -344.029284)
			(xy 108.263185 -344.071056) (xy 108.255122 -344.154211) (xy 108.239071 -344.236199) (xy 108.215182 -344.316256)
			(xy 108.183677 -344.393633) (xy 108.144852 -344.467608) (xy 108.099069 -344.537491) (xy 108.046754 -344.602628)
			(xy 107.988397 -344.662413) (xy 107.924543 -344.716286) (xy 107.855787 -344.763745) (xy 107.782771 -344.804346)
			(xy 107.706178 -344.837711) (xy 107.626722 -344.863528) (xy 107.545146 -344.881556) (xy 107.46221 -344.891626)
			(xy 107.37869 -344.893645) (xy 107.295364 -344.887593) (xy 107.213012 -344.873528) (xy 107.132402 -344.85158)
			(xy 107.054286 -344.821954) (xy 106.979394 -344.784928) (xy 106.908426 -344.740847) (xy 106.842043 -344.690121)
			(xy 106.780866 -344.633226) (xy 106.725465 -344.570692) (xy 106.676359 -344.503103) (xy 106.634005 -344.43109)
			(xy 106.598799 -344.355325) (xy 106.57107 -344.276516) (xy 106.551077 -344.195399) (xy 106.539005 -344.112731)
			(xy 106.534969 -344.029284) (xy 105.788968 -344.029284) (xy 105.788464 -344.071632) (xy 105.780413 -344.155946)
			(xy 105.764384 -344.239112) (xy 105.740523 -344.320379) (xy 105.709044 -344.399009) (xy 105.670233 -344.47429)
			(xy 105.624443 -344.545542) (xy 105.572087 -344.612118) (xy 105.513639 -344.673416) (xy 105.449629 -344.728881)
			(xy 105.380637 -344.77801) (xy 105.307287 -344.820359) (xy 105.230244 -344.855543) (xy 105.150205 -344.883245)
			(xy 105.067896 -344.903213) (xy 104.984061 -344.915266) (xy 104.89946 -344.919297) (xy 104.814859 -344.915266)
			(xy 104.731024 -344.903213) (xy 104.648715 -344.883245) (xy 104.568676 -344.855543) (xy 104.491633 -344.820359)
			(xy 104.418283 -344.77801) (xy 104.349291 -344.728881) (xy 104.285281 -344.673416) (xy 104.226833 -344.612118)
			(xy 104.174477 -344.545542) (xy 104.128687 -344.47429) (xy 104.089876 -344.399009) (xy 104.058397 -344.320379)
			(xy 104.034536 -344.239112) (xy 104.018507 -344.155946) (xy 104.010456 -344.071632) (xy 103.437436 -344.071632)
			(xy 103.437436 -345.526614) (xy 106.433112 -348.52229) (xy 106.450358 -348.540394) (xy 106.47817 -348.581936)
			(xy 106.497345 -348.628105) (xy 106.507149 -348.677127) (xy 106.507788 -348.702122) (xy 106.507788 -350.16186)
			(xy 106.63174 -350.16186) (xy 106.63174 -347.467428) (xy 106.632388 -347.442433) (xy 106.642188 -347.39341)
			(xy 106.661358 -347.347239) (xy 106.689162 -347.305693) (xy 106.706416 -347.287596) (xy 107.864656 -346.129356)
			(xy 107.87888 -346.116148) (xy 107.880404 -346.114878) (xy 108.434632 -345.560396) (xy 108.434632 -343.404698)
			(xy 105.861866 -340.831932) (xy 104.445816 -340.831932) (xy 104.42082 -340.831299) (xy 104.371796 -340.821496)
			(xy 104.325625 -340.802322) (xy 104.284079 -340.774512) (xy 104.265984 -340.757256) (xy 103.115618 -339.60689)
			(xy 103.098372 -339.588802) (xy 103.070636 -339.547234) (xy 103.051536 -339.501058) (xy 103.041803 -339.452044)
			(xy 103.041196 -339.427058) (xy 103.041196 -338.5947) (xy 103.012748 -338.58073) (xy 102.989118 -338.56858)
			(xy 102.945162 -338.538729) (xy 102.905771 -338.503069) (xy 102.871708 -338.46229) (xy 102.843631 -338.417181)
			(xy 102.822082 -338.368612) (xy 102.807479 -338.317524) (xy 102.800103 -338.264905) (xy 102.799642 -338.238338)
			(xy 102.800208 -338.20865) (xy 102.809402 -338.149991) (xy 102.827574 -338.093464) (xy 102.854285 -338.040436)
			(xy 102.88889 -337.992187) (xy 102.930553 -337.949883) (xy 102.954074 -337.93176) (xy 102.964658 -337.923305)
			(xy 102.98137 -337.902001) (xy 102.991894 -337.877053) (xy 102.995489 -337.850216) (xy 102.991902 -337.823377)
			(xy 102.981386 -337.798426) (xy 102.964681 -337.777116) (xy 102.954074 -337.768692) (xy 102.930554 -337.750568)
			(xy 102.888895 -337.708261) (xy 102.854293 -337.660011) (xy 102.827582 -337.606984) (xy 102.809407 -337.550459)
			(xy 102.800208 -337.491801) (xy 102.799642 -337.462114) (xy 102.800205 -337.434853) (xy 102.807966 -337.380885)
			(xy 102.823331 -337.328572) (xy 102.845989 -337.278979) (xy 102.875476 -337.233118) (xy 102.911193 -337.191923)
			(xy 102.952411 -337.156232) (xy 102.99829 -337.126773) (xy 103.047897 -337.104147) (xy 103.10022 -337.088815)
			(xy 103.154192 -337.081088) (xy 103.208715 -337.081124) (xy 103.262677 -337.088923) (xy 103.31498 -337.104325)
			(xy 103.364556 -337.127017) (xy 103.410396 -337.156537) (xy 103.451567 -337.192282) (xy 103.487229 -337.233526)
			(xy 103.516655 -337.279426) (xy 103.539246 -337.329048) (xy 103.554542 -337.381382) (xy 103.562231 -337.43536)
			(xy 103.562658 -337.462622) (xy 103.562658 -337.483958) (xy 103.662226 -337.583526) (xy 103.673267 -337.59372)
			(xy 103.699782 -337.607821) (xy 103.729251 -337.613608) (xy 103.759131 -337.610581) (xy 103.78684 -337.599002)
			(xy 103.809989 -337.579869) (xy 103.826578 -337.554834) (xy 103.83139 -337.5406) (xy 103.839613 -337.514698)
			(xy 103.862378 -337.465352) (xy 103.891914 -337.419734) (xy 103.927622 -337.378768) (xy 103.96878 -337.343281)
			(xy 104.014555 -337.313991) (xy 104.064023 -337.291491) (xy 104.116182 -337.276236) (xy 104.169978 -337.268534)
			(xy 104.19715 -337.268058) (xy 104.197404 -337.268058) (xy 104.222608 -337.268453) (xy 104.272576 -337.275094)
			(xy 104.321231 -337.288271) (xy 104.36772 -337.307756) (xy 104.389682 -337.320128) (xy 104.402665 -337.327132)
			(xy 104.431295 -337.334175) (xy 104.460744 -337.332738) (xy 104.488552 -337.322943) (xy 104.5124 -337.305606)
			(xy 104.530296 -337.282174) (xy 104.535986 -337.268566) (xy 104.546659 -337.24178) (xy 104.574951 -337.191539)
			(xy 104.610485 -337.14613) (xy 104.65245 -337.106588) (xy 104.699891 -337.073816) (xy 104.751724 -337.04856)
			(xy 104.80677 -337.031396) (xy 104.863772 -337.022715) (xy 104.892602 -337.022186) (xy 104.919853 -337.022676)
			(xy 104.9738 -337.030433) (xy 105.026095 -337.045788) (xy 105.075671 -337.068429) (xy 105.121522 -337.097894)
			(xy 105.162712 -337.133586) (xy 105.198403 -337.174775) (xy 105.22787 -337.220625) (xy 105.250511 -337.270202)
			(xy 105.265867 -337.322496) (xy 105.273624 -337.376443) (xy 105.27411 -337.403694) (xy 105.27411 -337.403948)
			(xy 105.273539 -337.433787) (xy 105.26422 -337.492733) (xy 105.255568 -337.521296) (xy 105.251626 -337.535228)
			(xy 105.250703 -337.564145) (xy 105.257952 -337.592155) (xy 105.272786 -337.616995) (xy 105.294008 -337.63666)
			(xy 105.319904 -337.649562) (xy 105.334054 -337.652614) (xy 105.36013 -337.657768) (xy 105.410633 -337.674342)
			(xy 105.458346 -337.697768) (xy 105.502343 -337.727592) (xy 105.541773 -337.763237) (xy 105.575872 -337.804012)
			(xy 105.603978 -337.849126) (xy 105.625547 -337.897706) (xy 105.640162 -337.948811) (xy 105.647539 -338.001449)
			(xy 105.647998 -338.028026) (xy 105.647512 -338.055277) (xy 105.639756 -338.109225) (xy 105.624401 -338.16152)
			(xy 105.601759 -338.211097) (xy 105.572293 -338.256947) (xy 105.536602 -338.298138) (xy 105.495411 -338.333829)
			(xy 105.449561 -338.363295) (xy 105.399984 -338.385937) (xy 105.347689 -338.401292) (xy 105.293741 -338.409048)
			(xy 105.239239 -338.409048) (xy 105.185291 -338.401292) (xy 105.132996 -338.385937) (xy 105.083419 -338.363295)
			(xy 105.037569 -338.333829) (xy 104.996378 -338.298138) (xy 104.960687 -338.256947) (xy 104.931221 -338.211097)
			(xy 104.908579 -338.16152) (xy 104.893224 -338.109225) (xy 104.885468 -338.055277) (xy 104.884982 -338.028026)
			(xy 104.884982 -338.027772) (xy 104.885558 -337.997933) (xy 104.894873 -337.938987) (xy 104.903524 -337.910424)
			(xy 104.907562 -337.896517) (xy 104.908467 -337.867586) (xy 104.901199 -337.839567) (xy 104.886347 -337.814723)
			(xy 104.865107 -337.795057) (xy 104.839195 -337.782157) (xy 104.825038 -337.779106) (xy 104.7922 -337.772515)
			(xy 104.729347 -337.749398) (xy 104.70007 -337.733132) (xy 104.687106 -337.726092) (xy 104.65847 -337.719062)
			(xy 104.629018 -337.720509) (xy 104.601208 -337.730311) (xy 104.577358 -337.747652) (xy 104.559459 -337.771085)
			(xy 104.553766 -337.784694) (xy 104.543028 -337.811453) (xy 104.514746 -337.861693) (xy 104.479223 -337.907103)
			(xy 104.437267 -337.946647) (xy 104.389836 -337.979422) (xy 104.33801 -338.004683) (xy 104.282973 -338.021854)
			(xy 104.225977 -338.030542) (xy 104.19715 -338.031074) (xy 104.183319 -338.030941) (xy 104.155733 -338.028906)
			(xy 104.142032 -338.02701) (xy 104.132749 -338.026138) (xy 104.114584 -338.030257) (xy 104.099094 -338.040601)
			(xy 104.088329 -338.0558) (xy 104.083714 -338.073845) (xy 104.084374 -338.083144) (xy 104.086152 -338.112608)
			(xy 104.086152 -339.318854) (xy 104.709214 -339.941916) (xy 106.125264 -339.941916) (xy 106.150259 -339.942576)
			(xy 106.19928 -339.952373) (xy 106.245451 -339.97154) (xy 106.286998 -339.99934) (xy 106.305096 -340.016592)
			(xy 109.249972 -342.961468) (xy 109.267249 -342.979545) (xy 109.295056 -343.021096) (xy 109.314224 -343.067273)
			(xy 109.324016 -343.116302) (xy 109.324648 -343.1413) (xy 109.324648 -345.823794) (xy 109.324017 -345.84879)
			(xy 109.314212 -345.897814) (xy 109.295037 -345.943984) (xy 109.267228 -345.98553) (xy 109.249972 -346.003626)
			(xy 108.510324 -346.743528) (xy 108.5088 -346.745052) (xy 108.494322 -346.7608) (xy 107.523788 -347.731588)
			(xy 107.523788 -350.16186) (xy 107.644692 -350.16186) (xy 107.644692 -349.15856) (xy 107.645345 -349.133565)
			(xy 107.655141 -349.084542) (xy 107.674309 -349.038371) (xy 107.702114 -348.996824) (xy 107.719368 -348.978728)
			(xy 110.081568 -346.616274) (xy 110.081568 -340.831678) (xy 110.082178 -340.80668) (xy 110.091988 -340.757656)
			(xy 110.111169 -340.711485) (xy 110.138985 -340.669941) (xy 110.156244 -340.651846) (xy 111.249968 -339.557868)
			(xy 111.249968 -338.610448) (xy 111.215932 -338.59851) (xy 111.191337 -338.589509) (xy 111.144714 -338.565649)
			(xy 111.101793 -338.535635) (xy 111.063382 -338.500031) (xy 111.030203 -338.459507) (xy 111.002881 -338.414824)
			(xy 110.981928 -338.366824) (xy 110.96774 -338.316408) (xy 110.960583 -338.264525) (xy 110.960154 -338.238338)
			(xy 110.960715 -338.20865) (xy 110.969909 -338.14999) (xy 110.988082 -338.093463) (xy 111.014794 -338.040435)
			(xy 111.0494 -337.992187) (xy 111.091064 -337.949883) (xy 111.114586 -337.93176) (xy 111.125169 -337.923305)
			(xy 111.141879 -337.902) (xy 111.152402 -337.877052) (xy 111.155996 -337.850216) (xy 111.15241 -337.823378)
			(xy 111.141895 -337.798427) (xy 111.125192 -337.777117) (xy 111.114586 -337.768692) (xy 111.091069 -337.750565)
			(xy 111.049409 -337.708259) (xy 111.014806 -337.66001) (xy 110.988095 -337.606983) (xy 110.96992 -337.550459)
			(xy 110.96072 -337.491801) (xy 110.960154 -337.462114) (xy 110.960693 -337.434852) (xy 110.968454 -337.380882)
			(xy 110.98382 -337.328568) (xy 111.006478 -337.278974) (xy 111.035966 -337.233111) (xy 111.071684 -337.191914)
			(xy 111.112903 -337.156222) (xy 111.158785 -337.126763) (xy 111.208393 -337.104136) (xy 111.260717 -337.088803)
			(xy 111.314691 -337.081076) (xy 111.369216 -337.081112) (xy 111.42318 -337.088911) (xy 111.475484 -337.104314)
			(xy 111.525062 -337.127007) (xy 111.570904 -337.156527) (xy 111.612075 -337.192274) (xy 111.647738 -337.233518)
			(xy 111.677165 -337.27942) (xy 111.699757 -337.329044) (xy 111.715054 -337.381379) (xy 111.722743 -337.435359)
			(xy 111.72317 -337.462622) (xy 111.72317 -337.483958) (xy 111.822738 -337.583526) (xy 111.833766 -337.593734)
			(xy 111.860285 -337.607835) (xy 111.889758 -337.61362) (xy 111.919639 -337.610591) (xy 111.947351 -337.599009)
			(xy 111.970501 -337.579873) (xy 111.987091 -337.554836) (xy 111.991902 -337.5406) (xy 112.000114 -337.514694)
			(xy 112.022881 -337.465347) (xy 112.052417 -337.419729) (xy 112.088126 -337.378763) (xy 112.129286 -337.343276)
			(xy 112.175063 -337.313987) (xy 112.224532 -337.291488) (xy 112.276692 -337.276234) (xy 112.330489 -337.268533)
			(xy 112.357662 -337.268058) (xy 112.357916 -337.268058) (xy 112.38312 -337.268448) (xy 112.433088 -337.27509)
			(xy 112.481743 -337.288269) (xy 112.528232 -337.307755) (xy 112.550194 -337.320128) (xy 112.56317 -337.327146)
			(xy 112.591803 -337.334187) (xy 112.621253 -337.332748) (xy 112.649064 -337.322949) (xy 112.672912 -337.30561)
			(xy 112.690808 -337.282176) (xy 112.696498 -337.268566) (xy 112.707161 -337.241776) (xy 112.735454 -337.191534)
			(xy 112.770989 -337.146125) (xy 112.812956 -337.106583) (xy 112.860398 -337.073812) (xy 112.912233 -337.048556)
			(xy 112.96728 -337.031393) (xy 113.024284 -337.022714) (xy 113.053114 -337.022186) (xy 113.080365 -337.022665)
			(xy 113.134313 -337.030423) (xy 113.186608 -337.04578) (xy 113.236184 -337.068422) (xy 113.282034 -337.097889)
			(xy 113.323224 -337.133581) (xy 113.358916 -337.174772) (xy 113.388382 -337.220623) (xy 113.411023 -337.2702)
			(xy 113.426379 -337.322495) (xy 113.434136 -337.376443) (xy 113.434622 -337.403694) (xy 113.434622 -337.403948)
			(xy 113.43405 -337.433787) (xy 113.424732 -337.492733) (xy 113.41608 -337.521296) (xy 113.412129 -337.535225)
			(xy 113.411206 -337.564145) (xy 113.418455 -337.592157) (xy 113.433291 -337.616998) (xy 113.454516 -337.636663)
			(xy 113.480415 -337.649563) (xy 113.494566 -337.652614) (xy 113.520644 -337.657759) (xy 113.571147 -337.674334)
			(xy 113.61886 -337.697762) (xy 113.662857 -337.727588) (xy 113.702286 -337.763233) (xy 113.736384 -337.804009)
			(xy 113.76449 -337.849124) (xy 113.78606 -337.897705) (xy 113.800674 -337.94881) (xy 113.808051 -338.001449)
			(xy 113.80851 -338.028026) (xy 113.808024 -338.055277) (xy 113.800268 -338.109225) (xy 113.784913 -338.16152)
			(xy 113.762271 -338.211097) (xy 113.732805 -338.256947) (xy 113.697114 -338.298138) (xy 113.655923 -338.333829)
			(xy 113.610073 -338.363295) (xy 113.560496 -338.385937) (xy 113.508201 -338.401292) (xy 113.454253 -338.409048)
			(xy 113.399751 -338.409048) (xy 113.345803 -338.401292) (xy 113.293508 -338.385937) (xy 113.243931 -338.363295)
			(xy 113.198081 -338.333829) (xy 113.15689 -338.298138) (xy 113.121199 -338.256947) (xy 113.091733 -338.211097)
			(xy 113.069091 -338.16152) (xy 113.053736 -338.109225) (xy 113.04598 -338.055277) (xy 113.045494 -338.028026)
			(xy 113.045494 -338.027772) (xy 113.04607 -337.997933) (xy 113.055385 -337.938987) (xy 113.064036 -337.910424)
			(xy 113.068065 -337.896515) (xy 113.068969 -337.867586) (xy 113.061702 -337.839569) (xy 113.046852 -337.814725)
			(xy 113.025615 -337.79506) (xy 112.999706 -337.782158) (xy 112.98555 -337.779106) (xy 112.952713 -337.772512)
			(xy 112.889859 -337.749397) (xy 112.860582 -337.733132) (xy 112.847611 -337.726106) (xy 112.818977 -337.719074)
			(xy 112.789528 -337.720518) (xy 112.761719 -337.730318) (xy 112.73787 -337.747656) (xy 112.719971 -337.771086)
			(xy 112.714278 -337.784694) (xy 112.70353 -337.811448) (xy 112.67525 -337.861689) (xy 112.639727 -337.907098)
			(xy 112.597773 -337.946642) (xy 112.550343 -337.979418) (xy 112.498519 -338.00468) (xy 112.443483 -338.021851)
			(xy 112.386488 -338.030541) (xy 112.357662 -338.031074) (xy 112.344925 -338.030985) (xy 112.319503 -338.029336)
			(xy 112.306862 -338.027772) (xy 112.292474 -338.026381) (xy 112.263906 -338.030679) (xy 112.237692 -338.04282)
			(xy 112.215937 -338.061829) (xy 112.20039 -338.086178) (xy 112.192299 -338.113911) (xy 112.1918 -338.128356)
			(xy 112.1918 -339.775546) (xy 112.191153 -339.800542) (xy 112.181356 -339.849565) (xy 112.162186 -339.895736)
			(xy 112.134379 -339.937282) (xy 112.117124 -339.955378) (xy 110.975648 -341.096854) (xy 110.975648 -344.071632)
			(xy 111.7158 -344.071632) (xy 111.7158 -343.986936) (xy 111.723851 -343.902622) (xy 111.73988 -343.819456)
			(xy 111.763741 -343.738189) (xy 111.79522 -343.659559) (xy 111.834031 -343.584278) (xy 111.879821 -343.513026)
			(xy 111.932177 -343.44645) (xy 111.990625 -343.385152) (xy 112.054635 -343.329687) (xy 112.123627 -343.280558)
			(xy 112.196977 -343.238209) (xy 112.27402 -343.203025) (xy 112.354059 -343.175323) (xy 112.436368 -343.155355)
			(xy 112.520203 -343.143302) (xy 112.604804 -343.139272) (xy 112.689405 -343.143302) (xy 112.77324 -343.155355)
			(xy 112.855549 -343.175323) (xy 112.935588 -343.203025) (xy 113.012631 -343.238209) (xy 113.085981 -343.280558)
			(xy 113.154973 -343.329687) (xy 113.218983 -343.385152) (xy 113.277431 -343.44645) (xy 113.329787 -343.513026)
			(xy 113.375577 -343.584278) (xy 113.414388 -343.659559) (xy 113.445867 -343.738189) (xy 113.469728 -343.819456)
			(xy 113.485757 -343.902622) (xy 113.493808 -343.986936) (xy 113.494312 -344.029284) (xy 114.240313 -344.029284)
			(xy 114.244349 -343.945837) (xy 114.256421 -343.863169) (xy 114.276414 -343.782052) (xy 114.304143 -343.703243)
			(xy 114.339349 -343.627478) (xy 114.381703 -343.555465) (xy 114.430809 -343.487876) (xy 114.48621 -343.425342)
			(xy 114.547387 -343.368447) (xy 114.61377 -343.317721) (xy 114.684738 -343.27364) (xy 114.75963 -343.236614)
			(xy 114.837746 -343.206988) (xy 114.918356 -343.18504) (xy 115.000708 -343.170975) (xy 115.084034 -343.164923)
			(xy 115.167554 -343.166942) (xy 115.25049 -343.177012) (xy 115.332066 -343.19504) (xy 115.411522 -343.220857)
			(xy 115.488115 -343.254222) (xy 115.561131 -343.294823) (xy 115.629887 -343.342282) (xy 115.693741 -343.396155)
			(xy 115.752098 -343.45594) (xy 115.804413 -343.521077) (xy 115.850196 -343.59096) (xy 115.889021 -343.664935)
			(xy 115.920526 -343.742312) (xy 115.944415 -343.822369) (xy 115.960466 -343.904357) (xy 115.968529 -343.987512)
			(xy 115.969034 -344.029284) (xy 115.968529 -344.071056) (xy 115.960466 -344.154211) (xy 115.944415 -344.236199)
			(xy 115.920526 -344.316256) (xy 115.889021 -344.393633) (xy 115.850196 -344.467608) (xy 115.804413 -344.537491)
			(xy 115.752098 -344.602628) (xy 115.693741 -344.662413) (xy 115.629887 -344.716286) (xy 115.561131 -344.763745)
			(xy 115.488115 -344.804346) (xy 115.411522 -344.837711) (xy 115.332066 -344.863528) (xy 115.25049 -344.881556)
			(xy 115.167554 -344.891626) (xy 115.084034 -344.893645) (xy 115.000708 -344.887593) (xy 114.918356 -344.873528)
			(xy 114.837746 -344.85158) (xy 114.75963 -344.821954) (xy 114.684738 -344.784928) (xy 114.61377 -344.740847)
			(xy 114.547387 -344.690121) (xy 114.48621 -344.633226) (xy 114.430809 -344.570692) (xy 114.381703 -344.503103)
			(xy 114.339349 -344.43109) (xy 114.304143 -344.355325) (xy 114.276414 -344.276516) (xy 114.256421 -344.195399)
			(xy 114.244349 -344.112731) (xy 114.240313 -344.029284) (xy 113.494312 -344.029284) (xy 113.493808 -344.071632)
			(xy 113.485757 -344.155946) (xy 113.469728 -344.239112) (xy 113.445867 -344.320379) (xy 113.414388 -344.399009)
			(xy 113.375577 -344.47429) (xy 113.329787 -344.545542) (xy 113.277431 -344.612118) (xy 113.218983 -344.673416)
			(xy 113.154973 -344.728881) (xy 113.085981 -344.77801) (xy 113.012631 -344.820359) (xy 112.935588 -344.855543)
			(xy 112.855549 -344.883245) (xy 112.77324 -344.903213) (xy 112.689405 -344.915266) (xy 112.604804 -344.919297)
			(xy 112.520203 -344.915266) (xy 112.436368 -344.903213) (xy 112.354059 -344.883245) (xy 112.27402 -344.855543)
			(xy 112.196977 -344.820359) (xy 112.123627 -344.77801) (xy 112.054635 -344.728881) (xy 111.990625 -344.673416)
			(xy 111.932177 -344.612118) (xy 111.879821 -344.545542) (xy 111.834031 -344.47429) (xy 111.79522 -344.399009)
			(xy 111.763741 -344.320379) (xy 111.73988 -344.239112) (xy 111.723851 -344.155946) (xy 111.7158 -344.071632)
			(xy 110.975648 -344.071632) (xy 110.975648 -346.88145) (xy 110.975049 -346.906434) (xy 110.965302 -346.955443)
			(xy 110.946191 -347.001612) (xy 110.918449 -347.043172) (xy 110.901226 -347.061282) (xy 108.539788 -349.422974)
			(xy 108.539788 -350.16186) (xy 108.70184 -350.16186) (xy 108.707266 -350.154839) (xy 108.71896 -350.141491)
			(xy 108.725208 -350.13519) (xy 111.035592 -347.824806) (xy 111.053701 -347.807583) (xy 111.09526 -347.779839)
			(xy 111.14143 -347.760731) (xy 111.19044 -347.750993) (xy 111.215424 -347.750384) (xy 113.674398 -347.750384)
			(xy 116.7765 -344.648028) (xy 116.7765 -342.527128) (xy 116.777131 -342.502131) (xy 116.786934 -342.453107)
			(xy 116.806108 -342.406936) (xy 116.833919 -342.365391) (xy 116.851176 -342.347296) (xy 118.832122 -340.36635)
			(xy 118.838472 -340.360254) (xy 119.38508 -339.813392) (xy 119.38508 -338.603082) (xy 119.354092 -338.589874)
			(xy 119.328507 -338.578582) (xy 119.280682 -338.549595) (xy 119.237604 -338.513933) (xy 119.200197 -338.472362)
			(xy 119.169262 -338.425773) (xy 119.145463 -338.375166) (xy 119.129311 -338.321625) (xy 119.121152 -338.2663)
			(xy 119.120666 -338.238338) (xy 119.121223 -338.20865) (xy 119.130417 -338.149989) (xy 119.148591 -338.093463)
			(xy 119.175304 -338.040434) (xy 119.209911 -337.992186) (xy 119.251576 -337.949883) (xy 119.275098 -337.93176)
			(xy 119.28568 -337.923304) (xy 119.302388 -337.901999) (xy 119.312909 -337.877051) (xy 119.316503 -337.850216)
			(xy 119.312918 -337.823379) (xy 119.302404 -337.798428) (xy 119.285703 -337.777118) (xy 119.275098 -337.768692)
			(xy 119.251583 -337.750562) (xy 119.209923 -337.708256) (xy 119.175319 -337.660008) (xy 119.148607 -337.606982)
			(xy 119.130432 -337.550458) (xy 119.121232 -337.491801) (xy 119.120666 -337.462114) (xy 119.121191 -337.434864)
			(xy 119.128945 -337.380919) (xy 119.144297 -337.328627) (xy 119.166935 -337.279052) (xy 119.196397 -337.233202)
			(xy 119.232084 -337.192013) (xy 119.27327 -337.156321) (xy 119.319116 -337.126854) (xy 119.368689 -337.104211)
			(xy 119.42098 -337.088854) (xy 119.474924 -337.081094) (xy 119.502174 -337.080606) (xy 119.531472 -337.08114)
			(xy 119.589376 -337.090116) (xy 119.645229 -337.107831) (xy 119.697722 -337.13387) (xy 119.745621 -337.167622)
			(xy 119.787803 -337.208293) (xy 119.823277 -337.25493) (xy 119.851212 -337.306438) (xy 119.861584 -337.333844)
			(xy 119.865394 -337.344512) (xy 120.018302 -337.49742) (xy 120.028234 -337.506733) (xy 120.051899 -337.52018)
			(xy 120.078275 -337.526902) (xy 120.105489 -337.526423) (xy 120.131612 -337.518777) (xy 120.15479 -337.504506)
			(xy 120.173378 -337.484623) (xy 120.1801 -337.472782) (xy 120.192528 -337.449968) (xy 120.222628 -337.407624)
			(xy 120.258195 -337.369757) (xy 120.298572 -337.337065) (xy 120.34301 -337.310154) (xy 120.39069 -337.289522)
			(xy 120.440727 -337.275551) (xy 120.492198 -337.268498) (xy 120.518174 -337.268058) (xy 120.518428 -337.268058)
			(xy 120.543632 -337.268443) (xy 120.593601 -337.275086) (xy 120.642255 -337.288267) (xy 120.688745 -337.307754)
			(xy 120.710706 -337.320128) (xy 120.723675 -337.32716) (xy 120.75231 -337.334199) (xy 120.781763 -337.332757)
			(xy 120.809575 -337.322956) (xy 120.833424 -337.305614) (xy 120.85132 -337.282177) (xy 120.85701 -337.268566)
			(xy 120.867663 -337.241771) (xy 120.895957 -337.191529) (xy 120.931494 -337.14612) (xy 120.973462 -337.106579)
			(xy 121.020905 -337.073807) (xy 121.072742 -337.048553) (xy 121.127791 -337.031391) (xy 121.184795 -337.022713)
			(xy 121.213626 -337.022186) (xy 121.240878 -337.022654) (xy 121.294826 -337.030413) (xy 121.34712 -337.045772)
			(xy 121.396697 -337.068415) (xy 121.442547 -337.097884) (xy 121.483737 -337.133577) (xy 121.519428 -337.174769)
			(xy 121.548894 -337.22062) (xy 121.571535 -337.270198) (xy 121.586891 -337.322494) (xy 121.594648 -337.376442)
			(xy 121.595134 -337.403694) (xy 121.595134 -337.403948) (xy 121.594561 -337.433787) (xy 121.586832 -337.482688)
			(xy 123.707398 -337.482688) (xy 123.707925 -337.455116) (xy 123.715865 -337.400546) (xy 123.731578 -337.347687)
			(xy 123.754737 -337.297641) (xy 123.784858 -337.251449) (xy 123.821316 -337.210076) (xy 123.842018 -337.191858)
			(xy 123.852925 -337.18197) (xy 123.868994 -337.157316) (xy 123.877374 -337.129106) (xy 123.877372 -337.099678)
			(xy 123.868987 -337.071469) (xy 123.852915 -337.046818) (xy 123.842018 -337.036918) (xy 123.821316 -337.018697)
			(xy 123.784844 -336.977331) (xy 123.75471 -336.931143) (xy 123.731543 -336.881097) (xy 123.715825 -336.828236)
			(xy 123.707884 -336.773662) (xy 123.707398 -336.746088) (xy 123.707867 -336.718836) (xy 123.715625 -336.664888)
			(xy 123.730982 -336.612592) (xy 123.753625 -336.563014) (xy 123.783093 -336.517164) (xy 123.818786 -336.475974)
			(xy 123.859978 -336.440282) (xy 123.90583 -336.410816) (xy 123.955409 -336.388176) (xy 124.007705 -336.372821)
			(xy 124.061654 -336.365065) (xy 124.088906 -336.36458) (xy 124.089668 -336.36458) (xy 124.101639 -336.364688)
			(xy 124.125532 -336.366216) (xy 124.13742 -336.367628) (xy 124.151183 -336.36885) (xy 124.178509 -336.364881)
			(xy 124.203774 -336.353739) (xy 124.225132 -336.336237) (xy 124.241022 -336.313655) (xy 124.250284 -336.287641)
			(xy 124.25172 -336.273902) (xy 124.254288 -336.245371) (xy 124.26677 -336.189468) (xy 124.287472 -336.136059)
			(xy 124.315929 -336.086348) (xy 124.351502 -336.041452) (xy 124.393389 -336.002382) (xy 124.440649 -335.970016)
			(xy 124.492218 -335.945083) (xy 124.546936 -335.928143) (xy 124.603572 -335.919578) (xy 124.632212 -335.919064)
			(xy 124.650231 -335.919288) (xy 124.686106 -335.92272) (xy 124.70384 -335.925922) (xy 124.719042 -335.928328)
			(xy 124.749605 -335.924788) (xy 124.77773 -335.912312) (xy 124.800866 -335.89203) (xy 124.816917 -335.865781)
			(xy 124.821188 -335.850992) (xy 124.828636 -335.823962) (xy 124.850258 -335.772237) (xy 124.879215 -335.724232)
			(xy 124.914884 -335.68098) (xy 124.956497 -335.643411) (xy 125.003158 -335.612335) (xy 125.053864 -335.588419)
			(xy 125.107523 -335.57218) (xy 125.162981 -335.563965) (xy 125.191012 -335.563464) (xy 125.218262 -335.563967)
			(xy 125.272208 -335.571724) (xy 125.324501 -335.587079) (xy 125.374076 -335.60972) (xy 125.419925 -335.639185)
			(xy 125.461114 -335.674874) (xy 125.496806 -335.716062) (xy 125.526273 -335.76191) (xy 125.548915 -335.811484)
			(xy 125.564273 -335.863776) (xy 125.572032 -335.917722) (xy 125.57252 -335.944972) (xy 125.572028 -335.972546)
			(xy 125.56408 -336.027117) (xy 125.54836 -336.079976) (xy 125.525194 -336.130022) (xy 125.495067 -336.176212)
			(xy 125.458605 -336.217585) (xy 125.4379 -336.235802) (xy 125.427031 -336.245729) (xy 125.410958 -336.270371)
			(xy 125.402572 -336.298572) (xy 125.402566 -336.327992) (xy 125.410943 -336.356195) (xy 125.427007 -336.380843)
			(xy 125.4379 -336.390742) (xy 125.458577 -336.408988) (xy 125.495041 -336.450356) (xy 125.525168 -336.496542)
			(xy 125.548331 -336.546585) (xy 125.564048 -336.599441) (xy 125.57199 -336.65401) (xy 125.571993 -336.709154)
			(xy 125.564056 -336.763723) (xy 125.548344 -336.816581) (xy 125.525186 -336.866626) (xy 125.495063 -336.912816)
			(xy 125.458603 -336.954186) (xy 125.4379 -336.972402) (xy 125.427031 -336.982329) (xy 125.410958 -337.006971)
			(xy 125.402572 -337.035172) (xy 125.402566 -337.064592) (xy 125.410943 -337.092795) (xy 125.427007 -337.117443)
			(xy 125.4379 -337.127342) (xy 125.458586 -337.14558) (xy 125.495059 -337.186943) (xy 125.525194 -337.233127)
			(xy 125.548364 -337.28317) (xy 125.564086 -337.336028) (xy 125.572031 -337.390599) (xy 125.57252 -337.418172)
			(xy 125.572019 -337.445424) (xy 125.567394 -337.477608) (xy 170.050211 -337.477608) (xy 170.054233 -337.391888)
			(xy 170.066264 -337.30692) (xy 170.0862 -337.223453) (xy 170.113863 -337.142219) (xy 170.149012 -337.063933)
			(xy 170.191338 -336.989282) (xy 170.240467 -336.918923) (xy 170.29597 -336.853473) (xy 170.357357 -336.793509)
			(xy 170.42409 -336.739556) (xy 170.495582 -336.692089) (xy 170.571204 -336.651525) (xy 170.650293 -336.618221)
			(xy 170.732153 -336.592469) (xy 170.816064 -336.574496) (xy 170.90129 -336.56446) (xy 170.987082 -336.562448)
			(xy 171.072684 -336.568479) (xy 171.157346 -336.582499) (xy 171.240323 -336.604385) (xy 171.320886 -336.633946)
			(xy 171.398326 -336.67092) (xy 171.471965 -336.714984) (xy 171.541153 -336.76575) (xy 171.605284 -336.822771)
			(xy 171.663793 -336.885547) (xy 171.716166 -336.953527) (xy 171.761944 -337.026112) (xy 171.800724 -337.102664)
			(xy 171.832165 -337.182512) (xy 171.855991 -337.264953) (xy 171.871992 -337.349263) (xy 171.880027 -337.434701)
			(xy 171.88053 -337.477608) (xy 171.880456 -337.483958) (xy 176.240953 -337.483958) (xy 176.244975 -337.398238)
			(xy 176.257006 -337.31327) (xy 176.276942 -337.229803) (xy 176.304605 -337.148569) (xy 176.339754 -337.070283)
			(xy 176.38208 -336.995632) (xy 176.431209 -336.925273) (xy 176.486712 -336.859823) (xy 176.548099 -336.799859)
			(xy 176.614832 -336.745906) (xy 176.686324 -336.698439) (xy 176.761946 -336.657875) (xy 176.841035 -336.624571)
			(xy 176.922895 -336.598819) (xy 177.006806 -336.580846) (xy 177.092032 -336.57081) (xy 177.177824 -336.568798)
			(xy 177.263426 -336.574829) (xy 177.348088 -336.588849) (xy 177.431065 -336.610735) (xy 177.511628 -336.640296)
			(xy 177.589068 -336.67727) (xy 177.662707 -336.721334) (xy 177.731895 -336.7721) (xy 177.796026 -336.829121)
			(xy 177.854535 -336.891897) (xy 177.906908 -336.959877) (xy 177.952686 -337.032462) (xy 177.991466 -337.109014)
			(xy 178.022907 -337.188862) (xy 178.046733 -337.271303) (xy 178.062734 -337.355613) (xy 178.070769 -337.441051)
			(xy 178.071272 -337.483958) (xy 182.439056 -337.483958) (xy 182.439544 -337.441682) (xy 182.447346 -337.35749)
			(xy 182.462882 -337.274377) (xy 182.486021 -337.193053) (xy 182.516565 -337.11421) (xy 182.554253 -337.038522)
			(xy 182.598764 -336.966634) (xy 182.649718 -336.89916) (xy 182.706681 -336.836675) (xy 182.769166 -336.779712)
			(xy 182.83664 -336.728758) (xy 182.908528 -336.684247) (xy 182.984216 -336.646559) (xy 183.063059 -336.616015)
			(xy 183.144383 -336.592876) (xy 183.227496 -336.57734) (xy 183.311688 -336.569538) (xy 183.39624 -336.569538)
			(xy 183.480432 -336.57734) (xy 183.563545 -336.592876) (xy 183.644869 -336.616015) (xy 183.723712 -336.646559)
			(xy 183.7994 -336.684247) (xy 183.871288 -336.728758) (xy 183.938762 -336.779712) (xy 184.001247 -336.836675)
			(xy 184.05821 -336.89916) (xy 184.109164 -336.966634) (xy 184.153675 -337.038522) (xy 184.191363 -337.11421)
			(xy 184.221907 -337.193053) (xy 184.245046 -337.274377) (xy 184.260582 -337.35749) (xy 184.268384 -337.441682)
			(xy 184.268872 -337.483958) (xy 184.268338 -337.527902) (xy 184.259914 -337.615385) (xy 184.243138 -337.701657)
			(xy 184.218167 -337.785923) (xy 184.185229 -337.867405) (xy 184.144629 -337.945353) (xy 184.096741 -338.019048)
			(xy 184.042007 -338.087812) (xy 183.98093 -338.151009) (xy 183.914074 -338.208057) (xy 183.842055 -338.258431)
			(xy 183.804052 -338.280502) (xy 183.792022 -338.28775) (xy 183.772209 -338.307642) (xy 183.758568 -338.332181)
			(xy 183.752134 -338.35951) (xy 183.753394 -338.387557) (xy 183.762252 -338.414199) (xy 183.778037 -338.437416)
			(xy 183.799554 -338.455452) (xy 183.81218 -338.461604) (xy 183.839112 -338.474322) (xy 183.889 -338.506852)
			(xy 183.911494 -338.526374) (xy 183.922936 -338.536019) (xy 183.949979 -338.548799) (xy 183.979566 -338.553185)
			(xy 184.009153 -338.548799) (xy 184.036196 -338.536019) (xy 184.047638 -338.526374) (xy 184.068772 -338.507974)
			(xy 184.115402 -338.476901) (xy 184.16608 -338.452993) (xy 184.219713 -338.436765) (xy 184.275145 -338.428567)
			(xy 184.303162 -338.428076) (xy 184.303416 -338.428076) (xy 184.330787 -338.428514) (xy 184.384968 -338.436336)
			(xy 184.437473 -338.45183) (xy 184.487219 -338.474679) (xy 184.533184 -338.504411) (xy 184.554114 -338.522056)
			(xy 184.565442 -338.531292) (xy 184.591999 -338.543468) (xy 184.620916 -338.547641) (xy 184.649833 -338.543468)
			(xy 184.67639 -338.531292) (xy 184.687718 -338.522056) (xy 184.708664 -338.504435) (xy 184.754634 -338.474722)
			(xy 184.804378 -338.451883) (xy 184.856875 -338.436387) (xy 184.911048 -338.428553) (xy 184.938416 -338.428076)
			(xy 184.965667 -338.428563) (xy 185.019614 -338.436321) (xy 185.071908 -338.451677) (xy 185.121484 -338.474319)
			(xy 185.167333 -338.503786) (xy 185.208523 -338.539477) (xy 185.244214 -338.580667) (xy 185.273681 -338.626516)
			(xy 185.296323 -338.676092) (xy 185.311679 -338.728386) (xy 185.319437 -338.782333) (xy 185.319924 -338.809584)
			(xy 185.319467 -338.836955) (xy 185.31165 -338.891135) (xy 185.29616 -338.943639) (xy 185.273315 -338.993386)
			(xy 185.243587 -339.039351) (xy 185.225944 -339.060282) (xy 185.216727 -339.071623) (xy 185.204555 -339.098177)
			(xy 185.200381 -339.127088) (xy 185.204548 -339.156) (xy 185.216714 -339.182557) (xy 185.225944 -339.193886)
			(xy 185.24357 -339.214831) (xy 185.273298 -339.260796) (xy 185.296146 -339.31054) (xy 185.311645 -339.36304)
			(xy 185.319475 -339.417218) (xy 185.319477 -339.471958) (xy 185.31165 -339.526136) (xy 185.296154 -339.578637)
			(xy 185.273309 -339.628383) (xy 185.243585 -339.67435) (xy 185.225944 -339.695282) (xy 185.216727 -339.706623)
			(xy 185.204555 -339.733177) (xy 185.200381 -339.762088) (xy 185.204548 -339.791) (xy 185.216714 -339.817557)
			(xy 185.225944 -339.828886) (xy 185.24357 -339.849831) (xy 185.273298 -339.895796) (xy 185.296146 -339.94554)
			(xy 185.311645 -339.99804) (xy 185.319475 -340.052218) (xy 185.319477 -340.106958) (xy 185.31165 -340.161136)
			(xy 185.296154 -340.213637) (xy 185.273309 -340.263383) (xy 185.243585 -340.30935) (xy 185.225944 -340.330282)
			(xy 185.216727 -340.341623) (xy 185.204555 -340.368177) (xy 185.200381 -340.397088) (xy 185.204548 -340.426)
			(xy 185.216714 -340.452557) (xy 185.225944 -340.463886) (xy 185.24357 -340.484831) (xy 185.273298 -340.530796)
			(xy 185.296146 -340.58054) (xy 185.311645 -340.63304) (xy 185.319475 -340.687218) (xy 185.319477 -340.741958)
			(xy 185.31165 -340.796136) (xy 185.296154 -340.848637) (xy 185.273309 -340.898383) (xy 185.243585 -340.94435)
			(xy 185.225944 -340.965282) (xy 185.216727 -340.976623) (xy 185.204555 -341.003177) (xy 185.200381 -341.032088)
			(xy 185.204548 -341.061) (xy 185.216714 -341.087557) (xy 185.225944 -341.098886) (xy 185.24357 -341.119831)
			(xy 185.273298 -341.165796) (xy 185.296146 -341.21554) (xy 185.311645 -341.26804) (xy 185.319475 -341.322218)
			(xy 185.319477 -341.376958) (xy 185.31165 -341.431136) (xy 185.296154 -341.483637) (xy 185.273309 -341.533383)
			(xy 185.243585 -341.57935) (xy 185.225944 -341.600282) (xy 185.216727 -341.611623) (xy 185.204555 -341.638177)
			(xy 185.200381 -341.667088) (xy 185.204548 -341.696) (xy 185.216714 -341.722557) (xy 185.225944 -341.733886)
			(xy 185.24357 -341.754831) (xy 185.273298 -341.800796) (xy 185.296146 -341.85054) (xy 185.311645 -341.90304)
			(xy 185.319475 -341.957218) (xy 185.319477 -342.011958) (xy 185.31165 -342.066136) (xy 185.296154 -342.118637)
			(xy 185.273309 -342.168383) (xy 185.243585 -342.21435) (xy 185.225944 -342.235282) (xy 185.216727 -342.246623)
			(xy 185.204555 -342.273177) (xy 185.200381 -342.302088) (xy 185.204548 -342.331) (xy 185.216714 -342.357557)
			(xy 185.225944 -342.368886) (xy 185.243597 -342.389807) (xy 185.273306 -342.435783) (xy 185.296138 -342.485534)
			(xy 185.311626 -342.538037) (xy 185.319452 -342.592214) (xy 185.319924 -342.619584) (xy 185.319407 -342.646834)
			(xy 185.311653 -342.70078) (xy 185.296301 -342.753073) (xy 185.273663 -342.802649) (xy 185.2442 -342.848499)
			(xy 185.208511 -342.889689) (xy 185.167324 -342.92538) (xy 185.121477 -342.954847) (xy 185.071903 -342.97749)
			(xy 185.019611 -342.992846) (xy 184.965666 -343.000605) (xy 184.938416 -343.001092) (xy 184.911046 -343.000619)
			(xy 184.856867 -342.992803) (xy 184.804364 -342.977316) (xy 184.754617 -342.954475) (xy 184.70865 -342.924752)
			(xy 184.687718 -342.907112) (xy 184.67639 -342.897876) (xy 184.649833 -342.8857) (xy 184.620916 -342.881527)
			(xy 184.591999 -342.8857) (xy 184.565442 -342.897876) (xy 184.554114 -342.907112) (xy 184.533189 -342.92476)
			(xy 184.487214 -342.95447) (xy 184.437465 -342.977304) (xy 184.384963 -342.992793) (xy 184.330786 -343.000619)
			(xy 184.303416 -343.001092) (xy 184.303162 -343.001092) (xy 184.275147 -343.00058) (xy 184.219724 -342.992359)
			(xy 184.166096 -342.976127) (xy 184.115416 -342.952233) (xy 184.068772 -342.921191) (xy 184.047638 -342.902794)
			(xy 184.036196 -342.893149) (xy 184.009153 -342.880369) (xy 183.979566 -342.875983) (xy 183.949979 -342.880369)
			(xy 183.922936 -342.893149) (xy 183.911494 -342.902794) (xy 183.890382 -342.921221) (xy 183.843747 -342.952291)
			(xy 183.793063 -342.976194) (xy 183.739425 -342.992416) (xy 183.683989 -343.000605) (xy 183.65597 -343.001092)
			(xy 183.655716 -343.001092) (xy 183.628463 -343.00063) (xy 183.574511 -342.992875) (xy 183.522212 -342.97752)
			(xy 183.472631 -342.954878) (xy 183.426777 -342.92541) (xy 183.385584 -342.889716) (xy 183.34989 -342.848523)
			(xy 183.320422 -342.802669) (xy 183.29778 -342.753088) (xy 183.282425 -342.700789) (xy 183.27467 -342.646837)
			(xy 183.274208 -342.619584) (xy 183.274663 -342.592213) (xy 183.282483 -342.538034) (xy 183.297975 -342.48553)
			(xy 183.320819 -342.435784) (xy 183.350546 -342.389817) (xy 183.368188 -342.368886) (xy 183.377441 -342.357571)
			(xy 183.389618 -342.331009) (xy 183.393788 -342.302088) (xy 183.389611 -342.273168) (xy 183.377428 -342.246609)
			(xy 183.368188 -342.235282) (xy 183.350533 -342.214361) (xy 183.320812 -342.16839) (xy 183.29797 -342.118642)
			(xy 183.282477 -342.066138) (xy 183.27465 -342.011959) (xy 183.274652 -341.957217) (xy 183.282482 -341.903038)
			(xy 183.297979 -341.850535) (xy 183.320824 -341.800788) (xy 183.350548 -341.75482) (xy 183.368188 -341.733886)
			(xy 183.377441 -341.722571) (xy 183.389618 -341.696009) (xy 183.393788 -341.667088) (xy 183.389611 -341.638168)
			(xy 183.377428 -341.611609) (xy 183.368188 -341.600282) (xy 183.350533 -341.579361) (xy 183.320812 -341.53339)
			(xy 183.29797 -341.483642) (xy 183.282477 -341.431138) (xy 183.27465 -341.376959) (xy 183.274652 -341.322217)
			(xy 183.282482 -341.268038) (xy 183.297979 -341.215535) (xy 183.320824 -341.165788) (xy 183.350548 -341.11982)
			(xy 183.368188 -341.098886) (xy 183.377441 -341.087571) (xy 183.389618 -341.061009) (xy 183.393788 -341.032088)
			(xy 183.389611 -341.003168) (xy 183.377428 -340.976609) (xy 183.368188 -340.965282) (xy 183.350533 -340.944361)
			(xy 183.320812 -340.89839) (xy 183.29797 -340.848642) (xy 183.282477 -340.796138) (xy 183.27465 -340.741959)
			(xy 183.274652 -340.687217) (xy 183.282482 -340.633038) (xy 183.297979 -340.580535) (xy 183.320824 -340.530788)
			(xy 183.350548 -340.48482) (xy 183.368188 -340.463886) (xy 183.377441 -340.452571) (xy 183.389618 -340.426009)
			(xy 183.393788 -340.397088) (xy 183.389611 -340.368168) (xy 183.377428 -340.341609) (xy 183.368188 -340.330282)
			(xy 183.350533 -340.309361) (xy 183.320812 -340.26339) (xy 183.29797 -340.213642) (xy 183.282477 -340.161138)
			(xy 183.27465 -340.106959) (xy 183.274652 -340.052217) (xy 183.282482 -339.998038) (xy 183.297979 -339.945535)
			(xy 183.320824 -339.895788) (xy 183.350548 -339.84982) (xy 183.368188 -339.828886) (xy 183.377441 -339.817571)
			(xy 183.389618 -339.791009) (xy 183.393788 -339.762088) (xy 183.389611 -339.733168) (xy 183.377428 -339.706609)
			(xy 183.368188 -339.695282) (xy 183.350533 -339.674361) (xy 183.320812 -339.62839) (xy 183.29797 -339.578642)
			(xy 183.282477 -339.526138) (xy 183.27465 -339.471959) (xy 183.274652 -339.417217) (xy 183.282482 -339.363038)
			(xy 183.297979 -339.310535) (xy 183.320824 -339.260788) (xy 183.350548 -339.21482) (xy 183.368188 -339.193886)
			(xy 183.377441 -339.182571) (xy 183.389618 -339.156009) (xy 183.393788 -339.127088) (xy 183.389611 -339.098168)
			(xy 183.377428 -339.071609) (xy 183.368188 -339.060282) (xy 183.350572 -339.039331) (xy 183.320857 -338.993363)
			(xy 183.298017 -338.943621) (xy 183.28252 -338.891124) (xy 183.274686 -338.836952) (xy 183.274208 -338.809584)
			(xy 183.274668 -338.782851) (xy 183.282177 -338.729914) (xy 183.296991 -338.67854) (xy 183.318821 -338.629732)
			(xy 183.347239 -338.584443) (xy 183.364124 -338.563712) (xy 183.372832 -338.552699) (xy 183.384366 -338.527111)
			(xy 183.388505 -338.499351) (xy 183.384937 -338.471511) (xy 183.373932 -338.445692) (xy 183.356318 -338.423839)
			(xy 183.333425 -338.407602) (xy 183.306978 -338.398203) (xy 183.293004 -338.396834) (xy 183.250113 -338.393549)
			(xy 183.165193 -338.379781) (xy 183.081941 -338.358103) (xy 183.001091 -338.328705) (xy 182.923357 -338.291848)
			(xy 182.849427 -338.247857) (xy 182.779952 -338.19712) (xy 182.715547 -338.140086) (xy 182.65678 -338.077258)
			(xy 182.604169 -338.009191) (xy 182.558181 -337.936486) (xy 182.51922 -337.859785) (xy 182.487632 -337.779766)
			(xy 182.463694 -337.697135) (xy 182.447618 -337.612622) (xy 182.439547 -337.526972) (xy 182.439056 -337.483958)
			(xy 178.071272 -337.483958) (xy 178.070769 -337.526865) (xy 178.062734 -337.612303) (xy 178.046733 -337.696613)
			(xy 178.022907 -337.779054) (xy 177.991466 -337.858902) (xy 177.952686 -337.935454) (xy 177.906908 -338.008039)
			(xy 177.854535 -338.076019) (xy 177.796026 -338.138795) (xy 177.731895 -338.195816) (xy 177.662707 -338.246582)
			(xy 177.589068 -338.290646) (xy 177.511628 -338.32762) (xy 177.431065 -338.357181) (xy 177.348088 -338.379067)
			(xy 177.263426 -338.393087) (xy 177.177824 -338.399118) (xy 177.092032 -338.397106) (xy 177.006806 -338.38707)
			(xy 176.922895 -338.369097) (xy 176.841035 -338.343345) (xy 176.761946 -338.310041) (xy 176.686324 -338.269477)
			(xy 176.614832 -338.22201) (xy 176.548099 -338.168057) (xy 176.486712 -338.108093) (xy 176.431209 -338.042643)
			(xy 176.38208 -337.972284) (xy 176.339754 -337.897633) (xy 176.304605 -337.819347) (xy 176.276942 -337.738113)
			(xy 176.257006 -337.654646) (xy 176.244975 -337.569678) (xy 176.240953 -337.483958) (xy 171.880456 -337.483958)
			(xy 171.880027 -337.520515) (xy 171.871992 -337.605953) (xy 171.855991 -337.690263) (xy 171.832165 -337.772704)
			(xy 171.800724 -337.852552) (xy 171.761944 -337.929104) (xy 171.716166 -338.001689) (xy 171.663793 -338.069669)
			(xy 171.605284 -338.132445) (xy 171.541153 -338.189466) (xy 171.471965 -338.240232) (xy 171.398326 -338.284296)
			(xy 171.320886 -338.32127) (xy 171.240323 -338.350831) (xy 171.157346 -338.372717) (xy 171.072684 -338.386737)
			(xy 170.987082 -338.392768) (xy 170.90129 -338.390756) (xy 170.816064 -338.38072) (xy 170.732153 -338.362747)
			(xy 170.650293 -338.336995) (xy 170.571204 -338.303691) (xy 170.495582 -338.263127) (xy 170.42409 -338.21566)
			(xy 170.357357 -338.161707) (xy 170.29597 -338.101743) (xy 170.240467 -338.036293) (xy 170.191338 -337.965934)
			(xy 170.149012 -337.891283) (xy 170.113863 -337.812997) (xy 170.0862 -337.731763) (xy 170.066264 -337.648296)
			(xy 170.054233 -337.563328) (xy 170.050211 -337.477608) (xy 125.567394 -337.477608) (xy 125.564266 -337.499373)
			(xy 125.548914 -337.551669) (xy 125.526276 -337.601248) (xy 125.496812 -337.647101) (xy 125.461122 -337.688294)
			(xy 125.419933 -337.723988) (xy 125.374083 -337.753456) (xy 125.324506 -337.7761) (xy 125.272212 -337.791457)
			(xy 125.218264 -337.799216) (xy 125.191012 -337.79968) (xy 125.163156 -337.799161) (xy 125.10804 -337.791038)
			(xy 125.054689 -337.774993) (xy 125.004235 -337.751367) (xy 124.95775 -337.720659) (xy 124.916221 -337.683523)
			(xy 124.880528 -337.640747) (xy 124.85143 -337.593238) (xy 124.829543 -337.542006) (xy 124.82195 -337.5152)
			(xy 124.817696 -337.501077) (xy 124.802301 -337.475931) (xy 124.780378 -337.456216) (xy 124.753745 -337.443567)
			(xy 124.724611 -337.439033) (xy 124.709936 -337.440524) (xy 124.697109 -337.442177) (xy 124.671306 -337.443953)
			(xy 124.658374 -337.44408) (xy 124.657612 -337.44408) (xy 124.639981 -337.443844) (xy 124.604873 -337.440538)
			(xy 124.587508 -337.437476) (xy 124.573734 -337.435253) (xy 124.545948 -337.437699) (xy 124.519864 -337.447584)
			(xy 124.497434 -337.464166) (xy 124.480337 -337.486207) (xy 124.469852 -337.512055) (xy 124.467874 -337.525868)
			(xy 124.464232 -337.553444) (xy 124.450001 -337.607215) (xy 124.428107 -337.658348) (xy 124.399017 -337.705757)
			(xy 124.363347 -337.748436) (xy 124.321855 -337.78548) (xy 124.27542 -337.816102) (xy 124.225029 -337.839652)
			(xy 124.171752 -337.85563) (xy 124.116717 -337.863699) (xy 124.088906 -337.864196) (xy 124.061653 -337.863739)
			(xy 124.007701 -337.855983) (xy 123.955402 -337.840627) (xy 123.905821 -337.817984) (xy 123.859968 -337.788516)
			(xy 123.818775 -337.752821) (xy 123.783081 -337.711628) (xy 123.753613 -337.665773) (xy 123.730971 -337.616192)
			(xy 123.715616 -337.563893) (xy 123.707861 -337.509941) (xy 123.707398 -337.482688) (xy 121.586832 -337.482688)
			(xy 121.585244 -337.492733) (xy 121.576592 -337.521296) (xy 121.572631 -337.535223) (xy 121.571708 -337.564145)
			(xy 121.578958 -337.592158) (xy 121.593796 -337.617001) (xy 121.615023 -337.636665) (xy 121.640926 -337.649564)
			(xy 121.655078 -337.652614) (xy 121.681143 -337.657824) (xy 121.731646 -337.674388) (xy 121.779359 -337.697805)
			(xy 121.823358 -337.727622) (xy 121.86279 -337.76326) (xy 121.89689 -337.804029) (xy 121.924998 -337.849138)
			(xy 121.94657 -337.897714) (xy 121.961186 -337.948815) (xy 121.968563 -338.001451) (xy 121.969022 -338.028026)
			(xy 121.968536 -338.055277) (xy 121.96078 -338.109225) (xy 121.945425 -338.16152) (xy 121.922783 -338.211097)
			(xy 121.893317 -338.256947) (xy 121.857626 -338.298138) (xy 121.816435 -338.333829) (xy 121.770585 -338.363295)
			(xy 121.721008 -338.385937) (xy 121.668713 -338.401292) (xy 121.614765 -338.409048) (xy 121.560263 -338.409048)
			(xy 121.506315 -338.401292) (xy 121.45402 -338.385937) (xy 121.404443 -338.363295) (xy 121.358593 -338.333829)
			(xy 121.317402 -338.298138) (xy 121.281711 -338.256947) (xy 121.252245 -338.211097) (xy 121.229603 -338.16152)
			(xy 121.214248 -338.109225) (xy 121.206492 -338.055277) (xy 121.206006 -338.028026) (xy 121.206006 -338.027772)
			(xy 121.206581 -337.997933) (xy 121.215897 -337.938987) (xy 121.224548 -337.910424) (xy 121.228568 -337.896513)
			(xy 121.229471 -337.867586) (xy 121.222206 -337.83957) (xy 121.207357 -337.814728) (xy 121.186123 -337.795062)
			(xy 121.160217 -337.782159) (xy 121.146062 -337.779106) (xy 121.113226 -337.77251) (xy 121.050372 -337.749396)
			(xy 121.021094 -337.733132) (xy 121.008116 -337.72612) (xy 120.979485 -337.719086) (xy 120.950038 -337.720528)
			(xy 120.92223 -337.730325) (xy 120.898382 -337.74766) (xy 120.880483 -337.771087) (xy 120.87479 -337.784694)
			(xy 120.864116 -337.81148) (xy 120.835826 -337.861723) (xy 120.800294 -337.907134) (xy 120.758329 -337.946677)
			(xy 120.710889 -337.97945) (xy 120.659054 -338.004706) (xy 120.604007 -338.021869) (xy 120.547004 -338.030547)
			(xy 120.518174 -338.031074) (xy 120.491196 -338.03057) (xy 120.437782 -338.022927) (xy 120.411748 -338.015834)
			(xy 120.398682 -338.012488) (xy 120.371727 -338.011981) (xy 120.345579 -338.018548) (xy 120.322062 -338.031731)
			(xy 120.302817 -338.050612) (xy 120.289186 -338.073872) (xy 120.28212 -338.09989) (xy 120.2817 -338.11337)
			(xy 120.2817 -338.592922) (xy 125.683518 -338.592922) (xy 125.683518 -338.592668) (xy 125.684031 -338.564653)
			(xy 125.692252 -338.50923) (xy 125.708483 -338.455602) (xy 125.732376 -338.404922) (xy 125.763419 -338.358278)
			(xy 125.781816 -338.337144) (xy 125.791486 -338.325722) (xy 125.804259 -338.298671) (xy 125.808638 -338.269079)
			(xy 125.804246 -338.239489) (xy 125.791463 -338.212443) (xy 125.781816 -338.201) (xy 125.763377 -338.179898)
			(xy 125.732312 -338.133259) (xy 125.708412 -338.082572) (xy 125.692193 -338.028932) (xy 125.684004 -337.973495)
			(xy 125.683518 -337.945476) (xy 125.683518 -337.945222) (xy 125.684004 -337.917971) (xy 125.69176 -337.864023)
			(xy 125.707115 -337.811728) (xy 125.729757 -337.762151) (xy 125.759223 -337.716301) (xy 125.794914 -337.67511)
			(xy 125.836105 -337.639419) (xy 125.881955 -337.609953) (xy 125.931532 -337.587311) (xy 125.983827 -337.571956)
			(xy 126.037775 -337.5642) (xy 126.092277 -337.5642) (xy 126.146225 -337.571956) (xy 126.19852 -337.587311)
			(xy 126.248097 -337.609953) (xy 126.293947 -337.639419) (xy 126.335138 -337.67511) (xy 126.370829 -337.716301)
			(xy 126.400295 -337.762151) (xy 126.422937 -337.811728) (xy 126.438292 -337.864023) (xy 126.446048 -337.917971)
			(xy 126.446534 -337.945222) (xy 126.446534 -337.945476) (xy 126.446034 -337.973491) (xy 126.437808 -338.028915)
			(xy 126.421573 -338.082542) (xy 126.397677 -338.133221) (xy 126.366633 -338.179866) (xy 126.348236 -338.201)
			(xy 126.338617 -338.212462) (xy 126.325831 -338.239497) (xy 126.321439 -338.269079) (xy 126.325819 -338.298663)
			(xy 126.338594 -338.325703) (xy 126.348236 -338.337144) (xy 126.366641 -338.358275) (xy 126.397712 -338.404906)
			(xy 126.421619 -338.455585) (xy 126.437846 -338.509218) (xy 126.446043 -338.564651) (xy 126.446534 -338.592668)
			(xy 126.446534 -338.592922) (xy 126.446048 -338.620173) (xy 126.438292 -338.674121) (xy 126.422937 -338.726416)
			(xy 126.400295 -338.775993) (xy 126.370829 -338.821843) (xy 126.335138 -338.863034) (xy 126.293947 -338.898725)
			(xy 126.248097 -338.928191) (xy 126.19852 -338.950833) (xy 126.146225 -338.966188) (xy 126.092277 -338.973944)
			(xy 126.037775 -338.973944) (xy 125.983827 -338.966188) (xy 125.931532 -338.950833) (xy 125.881955 -338.928191)
			(xy 125.836105 -338.898725) (xy 125.794914 -338.863034) (xy 125.759223 -338.821843) (xy 125.729757 -338.775993)
			(xy 125.707115 -338.726416) (xy 125.69176 -338.674121) (xy 125.684004 -338.620173) (xy 125.683518 -338.592922)
			(xy 120.2817 -338.592922) (xy 120.2817 -338.9892) (xy 129.932095 -338.9892) (xy 129.936264 -338.933577)
			(xy 129.948676 -338.879196) (xy 129.969055 -338.827272) (xy 129.996944 -338.778966) (xy 130.031722 -338.735356)
			(xy 130.072612 -338.697416) (xy 130.118699 -338.665995) (xy 130.168955 -338.641793) (xy 130.222256 -338.625352)
			(xy 130.277412 -338.617039) (xy 130.305302 -338.616544) (xy 130.332635 -338.616977) (xy 130.386717 -338.624953)
			(xy 130.439052 -338.640747) (xy 130.488517 -338.664021) (xy 130.534049 -338.694275) (xy 130.57467 -338.730859)
			(xy 130.609508 -338.772987) (xy 130.624072 -338.796122) (xy 130.631944 -338.808383) (xy 130.65343 -338.828052)
			(xy 130.679597 -338.84085) (xy 130.708314 -338.845736) (xy 130.737242 -338.842311) (xy 130.750818 -338.837016)
			(xy 130.774029 -338.827529) (xy 130.822361 -338.814177) (xy 130.87205 -338.807448) (xy 130.897122 -338.807044)
			(xy 130.922191 -338.807471) (xy 130.971874 -338.814219) (xy 131.020209 -338.82755) (xy 131.043426 -338.837016)
			(xy 131.057019 -338.842218) (xy 131.085911 -338.845591) (xy 131.114584 -338.840691) (xy 131.140716 -338.827912)
			(xy 131.16219 -338.808292) (xy 131.170172 -338.796122) (xy 131.184741 -338.772991) (xy 131.219584 -338.73087)
			(xy 131.260207 -338.694291) (xy 131.305738 -338.66404) (xy 131.3552 -338.640764) (xy 131.407531 -338.624964)
			(xy 131.46161 -338.616978) (xy 131.516274 -338.616978) (xy 131.570353 -338.624964) (xy 131.622684 -338.640764)
			(xy 131.672146 -338.66404) (xy 131.717677 -338.694291) (xy 131.7583 -338.73087) (xy 131.793143 -338.772991)
			(xy 131.807712 -338.796122) (xy 131.815641 -338.808342) (xy 131.837112 -338.82801) (xy 131.863263 -338.840814)
			(xy 131.891967 -338.845711) (xy 131.920884 -338.842302) (xy 131.934458 -338.837016) (xy 131.957664 -338.827517)
			(xy 132.005999 -338.814169) (xy 132.05569 -338.807445) (xy 132.080762 -338.807044) (xy 132.105703 -338.807423)
			(xy 132.15514 -338.81407) (xy 132.203249 -338.827251) (xy 132.249171 -338.84673) (xy 132.292085 -338.872159)
			(xy 132.311902 -338.887308) (xy 132.3234 -338.89589) (xy 132.34993 -338.906786) (xy 132.378445 -338.909859)
			(xy 132.406688 -338.904866) (xy 132.432421 -338.892202) (xy 132.453607 -338.87287) (xy 132.461508 -338.860892)
			(xy 132.476508 -338.837421) (xy 132.512171 -338.794638) (xy 132.553678 -338.757497) (xy 132.600146 -338.726789)
			(xy 132.650587 -338.703166) (xy 132.703928 -338.687133) (xy 132.759033 -338.679028) (xy 132.786882 -338.67852)
			(xy 132.815037 -338.678965) (xy 132.870737 -338.687226) (xy 132.924618 -338.703587) (xy 132.975508 -338.727691)
			(xy 133.0223 -338.759016) (xy 133.06398 -338.796879) (xy 133.099639 -338.840459) (xy 133.128504 -338.888807)
			(xy 133.149947 -338.940874) (xy 133.157214 -338.96808) (xy 133.161562 -338.983021) (xy 133.177813 -339.009536)
			(xy 133.201287 -339.029935) (xy 133.229809 -339.042329) (xy 133.260739 -339.04557) (xy 133.276086 -339.04301)
			(xy 133.294808 -339.039458) (xy 133.332724 -339.035641) (xy 133.351778 -339.03539) (xy 133.352032 -339.03539)
			(xy 133.379282 -339.035882) (xy 133.433226 -339.043642) (xy 133.485516 -339.059) (xy 133.535089 -339.081643)
			(xy 133.580935 -339.11111) (xy 133.622122 -339.146801) (xy 133.657809 -339.18799) (xy 133.687273 -339.233839)
			(xy 133.709911 -339.283414) (xy 133.725265 -339.335706) (xy 133.73302 -339.38965) (xy 133.73302 -339.44415)
			(xy 133.725265 -339.498094) (xy 133.709911 -339.550386) (xy 133.687273 -339.599961) (xy 133.657809 -339.64581)
			(xy 133.622122 -339.686999) (xy 133.580935 -339.72269) (xy 133.535089 -339.752157) (xy 133.485516 -339.7748)
			(xy 133.433226 -339.790158) (xy 133.379282 -339.797918) (xy 133.352032 -339.798406) (xy 133.323878 -339.797929)
			(xy 133.26818 -339.78967) (xy 133.214302 -339.773313) (xy 133.163413 -339.749212) (xy 133.116621 -339.717892)
			(xy 133.074942 -339.680033) (xy 133.039281 -339.636457) (xy 133.010414 -339.588113) (xy 132.988968 -339.53605)
			(xy 132.9817 -339.508846) (xy 132.977428 -339.493877) (xy 132.961165 -339.467351) (xy 132.937673 -339.446949)
			(xy 132.909129 -339.434563) (xy 132.878181 -339.431342) (xy 132.862828 -339.433916) (xy 132.844045 -339.437484)
			(xy 132.806 -339.441301) (xy 132.786882 -339.441536) (xy 132.786628 -339.441536) (xy 132.760488 -339.441082)
			(xy 132.708697 -339.433949) (xy 132.658368 -339.419801) (xy 132.610447 -339.398902) (xy 132.565834 -339.371646)
			(xy 132.545328 -339.35543) (xy 132.533921 -339.346707) (xy 132.507553 -339.33537) (xy 132.47907 -339.331838)
			(xy 132.450732 -339.336391) (xy 132.424788 -339.348667) (xy 132.403298 -339.367692) (xy 132.395214 -339.37956)
			(xy 132.389483 -339.388432) (xy 132.377156 -339.405587) (xy 132.370576 -339.41385) (xy 132.361312 -339.426139)
			(xy 132.349909 -339.454705) (xy 132.347517 -339.485371) (xy 132.354353 -339.515361) (xy 132.369797 -339.541961)
			(xy 132.392453 -339.562764) (xy 132.406136 -339.569806) (xy 132.429267 -339.581168) (xy 132.472506 -339.609205)
			(xy 132.51157 -339.642817) (xy 132.545746 -339.681389) (xy 132.574408 -339.724217) (xy 132.597033 -339.770519)
			(xy 132.605526 -339.79485) (xy 132.610638 -339.808596) (xy 132.627402 -339.832642) (xy 132.650295 -339.850949)
			(xy 132.67744 -339.862015) (xy 132.706607 -339.864932) (xy 132.721096 -339.862668) (xy 132.738833 -339.859485)
			(xy 132.774706 -339.856046) (xy 132.792724 -339.85581) (xy 132.793486 -339.85581) (xy 132.820739 -339.856268)
			(xy 132.874691 -339.864024) (xy 132.92699 -339.879379) (xy 132.976572 -339.902021) (xy 133.022426 -339.931489)
			(xy 133.063619 -339.967184) (xy 133.099313 -340.008377) (xy 133.128781 -340.054232) (xy 133.151422 -340.103813)
			(xy 133.166777 -340.156113) (xy 133.174532 -340.210065) (xy 133.174994 -340.237318) (xy 133.17474 -340.247732)
			(xy 133.174877 -340.262098) (xy 133.18214 -340.28988) (xy 133.196844 -340.314545) (xy 133.21783 -340.334145)
			(xy 133.24344 -340.347133) (xy 133.271652 -340.352484) (xy 133.285992 -340.351618) (xy 133.322568 -340.34984)
			(xy 133.349826 -340.350205) (xy 133.403787 -340.357959) (xy 133.456095 -340.373314) (xy 133.505686 -340.395958)
			(xy 133.551549 -340.425429) (xy 133.59275 -340.461127) (xy 133.628452 -340.502326) (xy 133.657927 -340.548186)
			(xy 133.680575 -340.597775) (xy 133.695934 -340.650082) (xy 133.703693 -340.704042) (xy 133.703693 -340.758558)
			(xy 133.695934 -340.812518) (xy 133.680575 -340.864825) (xy 133.657927 -340.914414) (xy 133.628452 -340.960274)
			(xy 133.59275 -341.001473) (xy 133.551549 -341.037171) (xy 133.505686 -341.066642) (xy 133.456095 -341.089286)
			(xy 133.403787 -341.104641) (xy 133.349826 -341.112395) (xy 133.322568 -341.112856) (xy 133.311557 -341.112774)
			(xy 133.289572 -341.111506) (xy 133.278626 -341.110316) (xy 133.263768 -341.109077) (xy 133.234433 -341.114331)
			(xy 133.207865 -341.127834) (xy 133.18633 -341.148435) (xy 133.171663 -341.174379) (xy 133.167882 -341.188802)
			(xy 133.161046 -341.216549) (xy 133.140188 -341.269751) (xy 133.111632 -341.31925) (xy 133.076016 -341.363938)
			(xy 133.034138 -341.402819) (xy 132.986931 -341.435023) (xy 132.935451 -341.45983) (xy 132.880849 -341.476686)
			(xy 132.824344 -341.485215) (xy 132.795772 -341.485728) (xy 132.766784 -341.485202) (xy 132.709477 -341.476427)
			(xy 132.654157 -341.459083) (xy 132.602097 -341.433569) (xy 132.554497 -341.400472) (xy 132.512452 -341.360556)
			(xy 132.476929 -341.314737) (xy 132.448748 -341.264073) (xy 132.428556 -341.209727) (xy 132.416818 -341.152952)
			(xy 132.414772 -341.124032) (xy 132.413612 -341.109956) (xy 132.40452 -341.083227) (xy 132.388444 -341.060018)
			(xy 132.366618 -341.042109) (xy 132.340716 -341.030875) (xy 132.312727 -341.027177) (xy 132.298694 -341.028782)
			(xy 132.28493 -341.030679) (xy 132.257216 -341.032711) (xy 132.243322 -341.032846) (xy 132.216073 -341.032301)
			(xy 132.162129 -341.024549) (xy 132.109838 -341.009198) (xy 132.060264 -340.986563) (xy 132.014415 -340.957102)
			(xy 131.973226 -340.921417) (xy 131.937534 -340.880233) (xy 131.908066 -340.834389) (xy 131.885423 -340.784818)
			(xy 131.870064 -340.732529) (xy 131.862303 -340.678587) (xy 131.861814 -340.651338) (xy 131.862301 -340.623764)
			(xy 131.870248 -340.569192) (xy 131.885969 -340.516332) (xy 131.909135 -340.466286) (xy 131.939264 -340.420096)
			(xy 131.975728 -340.378724) (xy 131.996434 -340.360508) (xy 132.00729 -340.350569) (xy 132.023358 -340.325929)
			(xy 132.031742 -340.297733) (xy 132.03175 -340.268316) (xy 132.023378 -340.240116) (xy 132.007322 -340.215468)
			(xy 131.996434 -340.205568) (xy 131.975711 -340.18737) (xy 131.93924 -340.145999) (xy 131.909109 -340.099807)
			(xy 131.885945 -340.049756) (xy 131.870231 -339.996891) (xy 131.862296 -339.942314) (xy 131.861814 -339.914738)
			(xy 131.862248 -339.888236) (xy 131.869597 -339.835744) (xy 131.884146 -339.784776) (xy 131.905614 -339.736314)
			(xy 131.933586 -339.691292) (xy 131.950206 -339.670644) (xy 131.959669 -339.658512) (xy 131.971464 -339.630107)
			(xy 131.974288 -339.599481) (xy 131.967888 -339.569398) (xy 131.95284 -339.542574) (xy 131.930504 -339.521431)
			(xy 131.916932 -339.51418) (xy 131.893237 -339.502088) (xy 131.849257 -339.472162) (xy 131.809977 -339.436289)
			(xy 131.776195 -339.395196) (xy 131.761992 -339.372702) (xy 131.754054 -339.360488) (xy 131.732587 -339.340817)
			(xy 131.706437 -339.328011) (xy 131.677736 -339.323113) (xy 131.648819 -339.326522) (xy 131.635246 -339.331808)
			(xy 131.61204 -339.341307) (xy 131.563705 -339.354654) (xy 131.514014 -339.361379) (xy 131.488942 -339.36178)
			(xy 131.463872 -339.361362) (xy 131.414189 -339.35461) (xy 131.365855 -339.341275) (xy 131.342638 -339.331808)
			(xy 131.329062 -339.326558) (xy 131.30016 -339.323191) (xy 131.27148 -339.328102) (xy 131.245345 -339.340892)
			(xy 131.223871 -339.360526) (xy 131.215892 -339.372702) (xy 131.201323 -339.395833) (xy 131.16648 -339.437954)
			(xy 131.125857 -339.474533) (xy 131.080326 -339.504784) (xy 131.030864 -339.52806) (xy 130.978533 -339.54386)
			(xy 130.924454 -339.551846) (xy 130.86979 -339.551846) (xy 130.815711 -339.54386) (xy 130.76338 -339.52806)
			(xy 130.713918 -339.504784) (xy 130.668387 -339.474533) (xy 130.627764 -339.437954) (xy 130.592921 -339.395833)
			(xy 130.578352 -339.372702) (xy 130.570452 -339.360461) (xy 130.548974 -339.34079) (xy 130.522815 -339.327987)
			(xy 130.494104 -339.323096) (xy 130.465181 -339.326516) (xy 130.451606 -339.331808) (xy 130.428393 -339.341288)
			(xy 130.380061 -339.354643) (xy 130.330373 -339.361375) (xy 130.305302 -339.36178) (xy 130.277412 -339.361361)
			(xy 130.222256 -339.353048) (xy 130.168955 -339.336607) (xy 130.118699 -339.312405) (xy 130.072612 -339.280984)
			(xy 130.031722 -339.243044) (xy 129.996944 -339.199434) (xy 129.969055 -339.151128) (xy 129.948676 -339.099204)
			(xy 129.936264 -339.044823) (xy 129.932095 -338.9892) (xy 120.2817 -338.9892) (xy 120.2817 -340.054946)
			(xy 126.474472 -340.054946) (xy 126.478543 -339.999324) (xy 126.490669 -339.944887) (xy 126.510592 -339.892796)
			(xy 126.537888 -339.844161) (xy 126.571974 -339.800018) (xy 126.612123 -339.761309) (xy 126.657481 -339.728858)
			(xy 126.707081 -339.703357) (xy 126.759865 -339.68535) (xy 126.814708 -339.67522) (xy 126.870442 -339.673183)
			(xy 126.925879 -339.679283) (xy 126.979836 -339.693389) (xy 127.031165 -339.715201) (xy 127.078771 -339.744255)
			(xy 127.121639 -339.77993) (xy 127.158856 -339.821467) (xy 127.189629 -339.86798) (xy 127.213301 -339.918477)
			(xy 127.229369 -339.971884) (xy 127.237489 -340.02706) (xy 127.237998 -340.054946) (xy 127.237489 -340.082832)
			(xy 127.229369 -340.138008) (xy 127.213301 -340.191415) (xy 127.189629 -340.241912) (xy 127.158856 -340.288425)
			(xy 127.121639 -340.329962) (xy 127.078771 -340.365637) (xy 127.031165 -340.394691) (xy 126.979836 -340.416503)
			(xy 126.925879 -340.430609) (xy 126.870442 -340.436709) (xy 126.814708 -340.434672) (xy 126.759865 -340.424542)
			(xy 126.707081 -340.406535) (xy 126.657481 -340.381034) (xy 126.612123 -340.348583) (xy 126.571974 -340.309874)
			(xy 126.537888 -340.265731) (xy 126.510592 -340.217096) (xy 126.490669 -340.165005) (xy 126.478543 -340.110568)
			(xy 126.474472 -340.054946) (xy 120.2817 -340.054946) (xy 120.2817 -340.079584) (xy 120.281046 -340.104565)
			(xy 120.271314 -340.15357) (xy 120.252219 -340.19974) (xy 120.224493 -340.241303) (xy 120.207278 -340.259416)
			(xy 119.78568 -340.681056) (xy 125.683008 -340.681056) (xy 125.687079 -340.625434) (xy 125.699205 -340.570997)
			(xy 125.719128 -340.518906) (xy 125.746424 -340.470271) (xy 125.78051 -340.426128) (xy 125.820659 -340.387419)
			(xy 125.866017 -340.354968) (xy 125.915617 -340.329467) (xy 125.968401 -340.31146) (xy 126.023244 -340.30133)
			(xy 126.078978 -340.299293) (xy 126.134415 -340.305393) (xy 126.188372 -340.319499) (xy 126.239701 -340.341311)
			(xy 126.287307 -340.370365) (xy 126.330175 -340.40604) (xy 126.367392 -340.447577) (xy 126.398165 -340.49409)
			(xy 126.421837 -340.544587) (xy 126.437905 -340.597994) (xy 126.446025 -340.65317) (xy 126.446534 -340.681056)
			(xy 126.446025 -340.708942) (xy 126.437905 -340.764118) (xy 126.421837 -340.817525) (xy 126.398165 -340.868022)
			(xy 126.367392 -340.914535) (xy 126.330175 -340.956072) (xy 126.287307 -340.991747) (xy 126.239701 -341.020801)
			(xy 126.188372 -341.042613) (xy 126.134415 -341.056719) (xy 126.078978 -341.062819) (xy 126.023244 -341.060782)
			(xy 125.968401 -341.050652) (xy 125.915617 -341.032645) (xy 125.866017 -341.007144) (xy 125.820659 -340.974693)
			(xy 125.78051 -340.935984) (xy 125.746424 -340.891841) (xy 125.719128 -340.843206) (xy 125.699205 -340.791115)
			(xy 125.687079 -340.736678) (xy 125.683008 -340.681056) (xy 119.78568 -340.681056) (xy 117.673628 -342.79332)
			(xy 117.673628 -343.948696) (xy 119.176796 -343.948696) (xy 119.176796 -343.864) (xy 119.184847 -343.779686)
			(xy 119.200876 -343.69652) (xy 119.224737 -343.615253) (xy 119.256216 -343.536623) (xy 119.295027 -343.461342)
			(xy 119.340817 -343.39009) (xy 119.393173 -343.323514) (xy 119.451621 -343.262216) (xy 119.515631 -343.206751)
			(xy 119.584623 -343.157622) (xy 119.657973 -343.115273) (xy 119.735016 -343.080089) (xy 119.815055 -343.052387)
			(xy 119.897364 -343.032419) (xy 119.981199 -343.020366) (xy 120.0658 -343.016336) (xy 120.150401 -343.020366)
			(xy 120.234236 -343.032419) (xy 120.316545 -343.052387) (xy 120.396584 -343.080089) (xy 120.473627 -343.115273)
			(xy 120.546977 -343.157622) (xy 120.615969 -343.206751) (xy 120.679979 -343.262216) (xy 120.738427 -343.323514)
			(xy 120.790783 -343.39009) (xy 120.836573 -343.461342) (xy 120.875384 -343.536623) (xy 120.906863 -343.615253)
			(xy 120.930724 -343.69652) (xy 120.946753 -343.779686) (xy 120.954804 -343.864) (xy 120.955308 -343.906348)
			(xy 121.701309 -343.906348) (xy 121.705345 -343.822901) (xy 121.717417 -343.740233) (xy 121.73741 -343.659116)
			(xy 121.765139 -343.580307) (xy 121.800345 -343.504542) (xy 121.842699 -343.432529) (xy 121.891805 -343.36494)
			(xy 121.947206 -343.302406) (xy 122.008383 -343.245511) (xy 122.074766 -343.194785) (xy 122.145734 -343.150704)
			(xy 122.220626 -343.113678) (xy 122.298742 -343.084052) (xy 122.379352 -343.062104) (xy 122.461704 -343.048039)
			(xy 122.54503 -343.041987) (xy 122.62855 -343.044006) (xy 122.711486 -343.054076) (xy 122.793062 -343.072104)
			(xy 122.872518 -343.097921) (xy 122.949111 -343.131286) (xy 123.022127 -343.171887) (xy 123.090883 -343.219346)
			(xy 123.154737 -343.273219) (xy 123.213094 -343.333004) (xy 123.265409 -343.398141) (xy 123.311192 -343.468024)
			(xy 123.350017 -343.541999) (xy 123.381522 -343.619376) (xy 123.405411 -343.699433) (xy 123.421462 -343.781421)
			(xy 123.429525 -343.864576) (xy 123.43003 -343.906348) (xy 123.429525 -343.94812) (xy 123.421462 -344.031275)
			(xy 123.405411 -344.113263) (xy 123.381522 -344.19332) (xy 123.350017 -344.270697) (xy 123.311192 -344.344672)
			(xy 123.265409 -344.414555) (xy 123.213094 -344.479692) (xy 123.154737 -344.539477) (xy 123.090883 -344.59335)
			(xy 123.022127 -344.640809) (xy 122.949111 -344.68141) (xy 122.872518 -344.714775) (xy 122.793062 -344.740592)
			(xy 122.711486 -344.75862) (xy 122.62855 -344.76869) (xy 122.54503 -344.770709) (xy 122.461704 -344.764657)
			(xy 122.379352 -344.750592) (xy 122.298742 -344.728644) (xy 122.220626 -344.699018) (xy 122.145734 -344.661992)
			(xy 122.074766 -344.617911) (xy 122.008383 -344.567185) (xy 121.947206 -344.51029) (xy 121.891805 -344.447756)
			(xy 121.842699 -344.380167) (xy 121.800345 -344.308154) (xy 121.765139 -344.232389) (xy 121.73741 -344.15358)
			(xy 121.717417 -344.072463) (xy 121.705345 -343.989795) (xy 121.701309 -343.906348) (xy 120.955308 -343.906348)
			(xy 120.954804 -343.948696) (xy 120.946753 -344.03301) (xy 120.930724 -344.116176) (xy 120.906863 -344.197443)
			(xy 120.875384 -344.276073) (xy 120.836573 -344.351354) (xy 120.790783 -344.422606) (xy 120.738427 -344.489182)
			(xy 120.679979 -344.55048) (xy 120.615969 -344.605945) (xy 120.546977 -344.655074) (xy 120.473627 -344.697423)
			(xy 120.396584 -344.732607) (xy 120.316545 -344.760309) (xy 120.234236 -344.780277) (xy 120.150401 -344.79233)
			(xy 120.0658 -344.796361) (xy 119.981199 -344.79233) (xy 119.897364 -344.780277) (xy 119.815055 -344.760309)
			(xy 119.735016 -344.732607) (xy 119.657973 -344.697423) (xy 119.584623 -344.655074) (xy 119.515631 -344.605945)
			(xy 119.451621 -344.55048) (xy 119.393173 -344.489182) (xy 119.340817 -344.422606) (xy 119.295027 -344.351354)
			(xy 119.256216 -344.276073) (xy 119.224737 -344.197443) (xy 119.200876 -344.116176) (xy 119.184847 -344.03301)
			(xy 119.176796 -343.948696) (xy 117.673628 -343.948696) (xy 117.673628 -344.91422) (xy 117.673018 -344.939218)
			(xy 117.663208 -344.988242) (xy 117.644027 -345.034413) (xy 117.616211 -345.075958) (xy 117.598952 -345.094052)
			(xy 114.120422 -348.572582) (xy 114.10232 -348.589813) (xy 114.060758 -348.617551) (xy 114.014585 -348.636656)
			(xy 113.965574 -348.646394) (xy 113.94059 -348.647004) (xy 111.481616 -348.647004) (xy 110.140242 -349.988632)
			(xy 110.130119 -349.999655) (xy 110.116028 -350.026034) (xy 110.110191 -350.055365) (xy 110.113109 -350.085129)
			(xy 110.124531 -350.112768) (xy 110.143476 -350.135908) (xy 110.168316 -350.152562) (xy 110.196918 -350.161297)
			(xy 110.21187 -350.16186) (xy 110.978188 -350.16186) (xy 111.560356 -349.579946) (xy 111.578471 -349.56273)
			(xy 111.620029 -349.534988) (xy 111.666197 -349.515879) (xy 111.715205 -349.506136) (xy 111.740188 -349.505524)
			(xy 114.020346 -349.505524) (xy 117.293136 -346.232734) (xy 117.311258 -346.215525) (xy 117.352813 -346.187782)
			(xy 117.39898 -346.168671) (xy 117.447985 -346.158926) (xy 117.472968 -346.158312) (xy 124.96673 -346.158312)
			(xy 127.66294 -343.462102) (xy 127.66294 -342.03259) (xy 127.617982 -342.02751) (xy 127.590487 -342.023811)
			(xy 127.536919 -342.009375) (xy 127.486005 -341.987336) (xy 127.438818 -341.958159) (xy 127.396351 -341.922459)
			(xy 127.3595 -341.880987) (xy 127.329041 -341.834618) (xy 127.305615 -341.784327) (xy 127.289716 -341.731175)
			(xy 127.281678 -341.676281) (xy 127.281178 -341.648542) (xy 127.281772 -341.618856) (xy 127.290964 -341.560199)
			(xy 127.309132 -341.503674) (xy 127.335838 -341.450647) (xy 127.370437 -341.402397) (xy 127.412093 -341.360089)
			(xy 127.43561 -341.341964) (xy 127.446187 -341.333503) (xy 127.462893 -341.312198) (xy 127.473413 -341.287252)
			(xy 127.477007 -341.260418) (xy 127.473423 -341.233583) (xy 127.462912 -341.208633) (xy 127.446213 -341.187322)
			(xy 127.43561 -341.178896) (xy 127.4121 -341.16076) (xy 127.370439 -341.118456) (xy 127.335834 -341.07021)
			(xy 127.309121 -341.017184) (xy 127.290945 -340.960661) (xy 127.281744 -340.902005) (xy 127.281178 -340.872318)
			(xy 127.281669 -340.845054) (xy 127.28943 -340.79108) (xy 127.304796 -340.738762) (xy 127.327456 -340.689165)
			(xy 127.356946 -340.643299) (xy 127.392666 -340.602099) (xy 127.433888 -340.566404) (xy 127.479772 -340.536942)
			(xy 127.529383 -340.514314) (xy 127.581711 -340.49898) (xy 127.635689 -340.491252) (xy 127.690218 -340.491288)
			(xy 127.744186 -340.499088) (xy 127.796493 -340.514492) (xy 127.846074 -340.537186) (xy 127.891919 -340.566709)
			(xy 127.933094 -340.602458) (xy 127.968759 -340.643706) (xy 127.998188 -340.689611) (xy 128.020781 -340.739239)
			(xy 128.036078 -340.791578) (xy 128.043767 -340.845561) (xy 128.044194 -340.872826) (xy 128.044194 -340.894162)
			(xy 128.143762 -340.99373) (xy 128.154767 -341.003965) (xy 128.181293 -341.018063) (xy 128.21077 -341.023845)
			(xy 128.240656 -341.020812) (xy 128.268371 -341.009225) (xy 128.291524 -340.990085) (xy 128.308115 -340.965042)
			(xy 128.312926 -340.950804) (xy 128.321119 -340.924891) (xy 128.343887 -340.875544) (xy 128.373426 -340.829925)
			(xy 128.409137 -340.788958) (xy 128.450299 -340.753471) (xy 128.496079 -340.724183) (xy 128.54555 -340.701685)
			(xy 128.597713 -340.686433) (xy 128.651512 -340.678736) (xy 128.678686 -340.678262) (xy 128.67894 -340.678262)
			(xy 128.704144 -340.678641) (xy 128.754113 -340.685286) (xy 128.802768 -340.698469) (xy 128.849257 -340.717957)
			(xy 128.871218 -340.730332) (xy 128.88418 -340.737377) (xy 128.912819 -340.744413) (xy 128.942273 -340.742969)
			(xy 128.970086 -340.733165) (xy 128.993936 -340.715821) (xy 129.011832 -340.692382) (xy 129.017522 -340.67877)
			(xy 129.02825 -340.652008) (xy 129.056536 -340.601769) (xy 129.092062 -340.556361) (xy 129.134019 -340.516818)
			(xy 129.181451 -340.484043) (xy 129.233277 -340.458783) (xy 129.288315 -340.441612) (xy 129.345311 -340.432923)
			(xy 129.374138 -340.43239) (xy 129.40139 -340.432842) (xy 129.455339 -340.440604) (xy 129.507634 -340.455964)
			(xy 129.557211 -340.478609) (xy 129.603061 -340.508079) (xy 129.644251 -340.543774) (xy 129.679942 -340.584967)
			(xy 129.709408 -340.63082) (xy 129.732049 -340.6804) (xy 129.747404 -340.732696) (xy 129.75516 -340.786646)
			(xy 129.755646 -340.813898) (xy 129.755646 -340.814152) (xy 129.755074 -340.843991) (xy 129.745756 -340.902937)
			(xy 129.737104 -340.9315) (xy 129.733129 -340.945424) (xy 129.732206 -340.974348) (xy 129.739458 -341.002364)
			(xy 129.754299 -341.027207) (xy 129.77553 -341.046872) (xy 129.801436 -341.05977) (xy 129.81559 -341.062818)
			(xy 129.841657 -341.068015) (xy 129.892161 -341.084581) (xy 129.939874 -341.108) (xy 129.983873 -341.137818)
			(xy 130.023305 -341.173458) (xy 130.057405 -341.214228) (xy 130.085512 -341.259339) (xy 130.107083 -341.307916)
			(xy 130.121698 -341.359018) (xy 130.129076 -341.411654) (xy 130.129534 -341.43823) (xy 130.129048 -341.465481)
			(xy 130.121292 -341.519429) (xy 130.105937 -341.571724) (xy 130.083295 -341.621301) (xy 130.053829 -341.667151)
			(xy 130.018138 -341.708342) (xy 129.976947 -341.744033) (xy 129.931097 -341.773499) (xy 129.88152 -341.796141)
			(xy 129.829225 -341.811496) (xy 129.775277 -341.819252) (xy 129.720775 -341.819252) (xy 129.666827 -341.811496)
			(xy 129.614532 -341.796141) (xy 129.564955 -341.773499) (xy 129.519105 -341.744033) (xy 129.477914 -341.708342)
			(xy 129.442223 -341.667151) (xy 129.412757 -341.621301) (xy 129.390115 -341.571724) (xy 129.37476 -341.519429)
			(xy 129.367004 -341.465481) (xy 129.366518 -341.43823) (xy 129.366518 -341.437976) (xy 129.367094 -341.408137)
			(xy 129.376409 -341.349191) (xy 129.38506 -341.320628) (xy 129.389144 -341.306731) (xy 129.390052 -341.27779)
			(xy 129.382781 -341.249762) (xy 129.367918 -341.224911) (xy 129.346665 -341.205246) (xy 129.320738 -341.192354)
			(xy 129.306574 -341.18931) (xy 129.273733 -341.182734) (xy 129.210882 -341.159606) (xy 129.181606 -341.143336)
			(xy 129.168622 -341.136337) (xy 129.139993 -341.1293) (xy 129.110547 -341.130739) (xy 129.082741 -341.140534)
			(xy 129.058894 -341.157867) (xy 129.040995 -341.181292) (xy 129.035302 -341.194898) (xy 129.02462 -341.22168)
			(xy 128.996331 -341.271923) (xy 128.9608 -341.317334) (xy 128.918836 -341.356877) (xy 128.871397 -341.38965)
			(xy 128.819563 -341.414906) (xy 128.764518 -341.43207) (xy 128.707516 -341.44075) (xy 128.678686 -341.441278)
			(xy 128.664987 -341.441194) (xy 128.637655 -341.439284) (xy 128.624076 -341.437468) (xy 128.614801 -341.436604)
			(xy 128.59666 -341.440758) (xy 128.581191 -341.451105) (xy 128.570427 -341.466288) (xy 128.565782 -341.484309)
			(xy 128.566418 -341.493602) (xy 128.568196 -341.52332) (xy 128.568196 -342.619584) (xy 168.52519 -342.619584)
			(xy 168.525649 -342.592214) (xy 168.533469 -342.538034) (xy 168.54896 -342.485531) (xy 168.571803 -342.435784)
			(xy 168.601528 -342.389818) (xy 168.61917 -342.368886) (xy 168.628425 -342.357571) (xy 168.640604 -342.33101)
			(xy 168.644775 -342.302088) (xy 168.640597 -342.273167) (xy 168.628412 -342.246608) (xy 168.61917 -342.235282)
			(xy 168.601512 -342.214363) (xy 168.571784 -342.168394) (xy 168.548937 -342.118645) (xy 168.53344 -342.066141)
			(xy 168.525612 -342.01196) (xy 168.525614 -341.957216) (xy 168.533446 -341.903035) (xy 168.548946 -341.850532)
			(xy 168.571796 -341.800785) (xy 168.601526 -341.754818) (xy 168.61917 -341.733886) (xy 168.628425 -341.722571)
			(xy 168.640604 -341.69601) (xy 168.644775 -341.667088) (xy 168.640597 -341.638167) (xy 168.628412 -341.611608)
			(xy 168.61917 -341.600282) (xy 168.601512 -341.579363) (xy 168.571784 -341.533394) (xy 168.548937 -341.483645)
			(xy 168.53344 -341.431141) (xy 168.525612 -341.37696) (xy 168.525614 -341.322216) (xy 168.533446 -341.268035)
			(xy 168.548946 -341.215532) (xy 168.571796 -341.165785) (xy 168.601526 -341.119818) (xy 168.61917 -341.098886)
			(xy 168.628425 -341.087571) (xy 168.640604 -341.06101) (xy 168.644775 -341.032088) (xy 168.640597 -341.003167)
			(xy 168.628412 -340.976608) (xy 168.61917 -340.965282) (xy 168.601512 -340.944363) (xy 168.571784 -340.898394)
			(xy 168.548937 -340.848645) (xy 168.53344 -340.796141) (xy 168.525612 -340.74196) (xy 168.525614 -340.687216)
			(xy 168.533446 -340.633035) (xy 168.548946 -340.580532) (xy 168.571796 -340.530785) (xy 168.601526 -340.484818)
			(xy 168.61917 -340.463886) (xy 168.628425 -340.452571) (xy 168.640604 -340.42601) (xy 168.644775 -340.397088)
			(xy 168.640597 -340.368167) (xy 168.628412 -340.341608) (xy 168.61917 -340.330282) (xy 168.601512 -340.309363)
			(xy 168.571784 -340.263394) (xy 168.548937 -340.213645) (xy 168.53344 -340.161141) (xy 168.525612 -340.10696)
			(xy 168.525614 -340.052216) (xy 168.533446 -339.998035) (xy 168.548946 -339.945532) (xy 168.571796 -339.895785)
			(xy 168.601526 -339.849818) (xy 168.61917 -339.828886) (xy 168.628425 -339.817571) (xy 168.640604 -339.79101)
			(xy 168.644775 -339.762088) (xy 168.640597 -339.733167) (xy 168.628412 -339.706608) (xy 168.61917 -339.695282)
			(xy 168.601512 -339.674363) (xy 168.571784 -339.628394) (xy 168.548937 -339.578645) (xy 168.53344 -339.526141)
			(xy 168.525612 -339.47196) (xy 168.525614 -339.417216) (xy 168.533446 -339.363035) (xy 168.548946 -339.310532)
			(xy 168.571796 -339.260785) (xy 168.601526 -339.214818) (xy 168.61917 -339.193886) (xy 168.628425 -339.182571)
			(xy 168.640604 -339.15601) (xy 168.644775 -339.127088) (xy 168.640597 -339.098167) (xy 168.628412 -339.071608)
			(xy 168.61917 -339.060282) (xy 168.601551 -339.039334) (xy 168.571837 -338.993365) (xy 168.548998 -338.943621)
			(xy 168.533502 -338.891125) (xy 168.525668 -338.836952) (xy 168.52519 -338.809584) (xy 168.525663 -338.782332)
			(xy 168.533422 -338.728384) (xy 168.548779 -338.676089) (xy 168.571421 -338.626512) (xy 168.600889 -338.580662)
			(xy 168.636582 -338.539472) (xy 168.677773 -338.503781) (xy 168.723625 -338.474315) (xy 168.773203 -338.451674)
			(xy 168.825498 -338.436319) (xy 168.879446 -338.428562) (xy 168.906698 -338.428076) (xy 168.934069 -338.428525)
			(xy 168.98825 -338.436344) (xy 169.040754 -338.451836) (xy 169.0905 -338.474682) (xy 169.136466 -338.504412)
			(xy 169.157396 -338.522056) (xy 169.168724 -338.531292) (xy 169.195281 -338.543468) (xy 169.224198 -338.547641)
			(xy 169.253115 -338.543468) (xy 169.279672 -338.531292) (xy 169.291 -338.522056) (xy 169.311915 -338.504396)
			(xy 169.357893 -338.474689) (xy 169.407645 -338.451858) (xy 169.460149 -338.436371) (xy 169.514328 -338.428547)
			(xy 169.541698 -338.428076) (xy 169.541952 -338.428076) (xy 169.569967 -338.428588) (xy 169.62539 -338.43681)
			(xy 169.679017 -338.453043) (xy 169.729697 -338.476936) (xy 169.776342 -338.507978) (xy 169.797476 -338.526374)
			(xy 169.808918 -338.536019) (xy 169.835961 -338.548799) (xy 169.865548 -338.553185) (xy 169.895135 -338.548799)
			(xy 169.922178 -338.536019) (xy 169.93362 -338.526374) (xy 169.954761 -338.507982) (xy 170.001389 -338.476908)
			(xy 170.052066 -338.452999) (xy 170.105697 -338.436769) (xy 170.161127 -338.428569) (xy 170.189144 -338.428076)
			(xy 170.189398 -338.428076) (xy 170.216648 -338.42858) (xy 170.270595 -338.436335) (xy 170.322888 -338.451689)
			(xy 170.372464 -338.474329) (xy 170.418314 -338.503794) (xy 170.459504 -338.539483) (xy 170.495195 -338.580672)
			(xy 170.524662 -338.62652) (xy 170.547304 -338.676095) (xy 170.562661 -338.728388) (xy 170.570419 -338.782334)
			(xy 170.570906 -338.809584) (xy 170.570429 -338.836954) (xy 170.562614 -338.891132) (xy 170.547127 -338.943635)
			(xy 170.524288 -338.993382) (xy 170.494566 -339.03935) (xy 170.476926 -339.060282) (xy 170.467702 -339.07162)
			(xy 170.45552 -339.098173) (xy 170.451343 -339.127088) (xy 170.455513 -339.156003) (xy 170.467689 -339.18256)
			(xy 170.476926 -339.193886) (xy 170.494553 -339.214831) (xy 170.524282 -339.260795) (xy 170.547131 -339.310539)
			(xy 170.562631 -339.36304) (xy 170.570462 -339.417218) (xy 170.570464 -339.471958) (xy 170.562636 -339.526137)
			(xy 170.54714 -339.578638) (xy 170.524294 -339.628384) (xy 170.494568 -339.67435) (xy 170.476926 -339.695282)
			(xy 170.467702 -339.70662) (xy 170.45552 -339.733173) (xy 170.451343 -339.762088) (xy 170.455513 -339.791003)
			(xy 170.467689 -339.81756) (xy 170.476926 -339.828886) (xy 170.494553 -339.849831) (xy 170.524282 -339.895795)
			(xy 170.547131 -339.945539) (xy 170.562631 -339.99804) (xy 170.570462 -340.052218) (xy 170.570464 -340.106958)
			(xy 170.562636 -340.161137) (xy 170.54714 -340.213638) (xy 170.524294 -340.263384) (xy 170.494568 -340.30935)
			(xy 170.476926 -340.330282) (xy 170.467702 -340.34162) (xy 170.45552 -340.368173) (xy 170.451343 -340.397088)
			(xy 170.455513 -340.426003) (xy 170.467689 -340.45256) (xy 170.476926 -340.463886) (xy 170.494553 -340.484831)
			(xy 170.524282 -340.530795) (xy 170.547131 -340.580539) (xy 170.562631 -340.63304) (xy 170.570462 -340.687218)
			(xy 170.570464 -340.741958) (xy 170.562636 -340.796137) (xy 170.54714 -340.848638) (xy 170.524294 -340.898384)
			(xy 170.494568 -340.94435) (xy 170.476926 -340.965282) (xy 170.467702 -340.97662) (xy 170.45552 -341.003173)
			(xy 170.451343 -341.032088) (xy 170.455513 -341.061003) (xy 170.467689 -341.08756) (xy 170.476926 -341.098886)
			(xy 170.494553 -341.119831) (xy 170.524282 -341.165795) (xy 170.547131 -341.215539) (xy 170.562631 -341.26804)
			(xy 170.570462 -341.322218) (xy 170.570464 -341.376958) (xy 170.562636 -341.431137) (xy 170.54714 -341.483638)
			(xy 170.524294 -341.533384) (xy 170.494568 -341.57935) (xy 170.476926 -341.600282) (xy 170.467702 -341.61162)
			(xy 170.45552 -341.638173) (xy 170.451343 -341.667088) (xy 170.455513 -341.696003) (xy 170.467689 -341.72256)
			(xy 170.476926 -341.733886) (xy 170.494553 -341.754831) (xy 170.524282 -341.800795) (xy 170.547131 -341.850539)
			(xy 170.562631 -341.90304) (xy 170.570462 -341.957218) (xy 170.570464 -342.011958) (xy 170.562636 -342.066137)
			(xy 170.54714 -342.118638) (xy 170.524294 -342.168384) (xy 170.494568 -342.21435) (xy 170.476926 -342.235282)
			(xy 170.467702 -342.24662) (xy 170.45552 -342.273173) (xy 170.451343 -342.302088) (xy 170.455513 -342.331003)
			(xy 170.467689 -342.35756) (xy 170.476926 -342.368886) (xy 170.494576 -342.389809) (xy 170.524285 -342.435785)
			(xy 170.547119 -342.485535) (xy 170.562607 -342.538037) (xy 170.570433 -342.592214) (xy 170.570906 -342.619584)
			(xy 173.495462 -342.619584) (xy 173.495904 -342.592213) (xy 173.503725 -342.538032) (xy 173.519219 -342.485528)
			(xy 173.542067 -342.435781) (xy 173.571797 -342.389816) (xy 173.589442 -342.368886) (xy 173.598691 -342.357569)
			(xy 173.610861 -342.331007) (xy 173.615029 -342.302088) (xy 173.610854 -342.27317) (xy 173.598678 -342.246611)
			(xy 173.589442 -342.235282) (xy 173.571785 -342.214362) (xy 173.54206 -342.168393) (xy 173.519214 -342.118644)
			(xy 173.503719 -342.06614) (xy 173.495891 -342.011959) (xy 173.495893 -341.957216) (xy 173.503724 -341.903036)
			(xy 173.519223 -341.850533) (xy 173.542071 -341.800786) (xy 173.5718 -341.754818) (xy 173.589442 -341.733886)
			(xy 173.598691 -341.722569) (xy 173.610861 -341.696007) (xy 173.615029 -341.667088) (xy 173.610854 -341.63817)
			(xy 173.598678 -341.611611) (xy 173.589442 -341.600282) (xy 173.571785 -341.579362) (xy 173.54206 -341.533393)
			(xy 173.519214 -341.483644) (xy 173.503719 -341.43114) (xy 173.495891 -341.376959) (xy 173.495893 -341.322216)
			(xy 173.503724 -341.268036) (xy 173.519223 -341.215533) (xy 173.542071 -341.165786) (xy 173.5718 -341.119818)
			(xy 173.589442 -341.098886) (xy 173.598691 -341.087569) (xy 173.610861 -341.061007) (xy 173.615029 -341.032088)
			(xy 173.610854 -341.00317) (xy 173.598678 -340.976611) (xy 173.589442 -340.965282) (xy 173.571785 -340.944362)
			(xy 173.54206 -340.898393) (xy 173.519214 -340.848644) (xy 173.503719 -340.79614) (xy 173.495891 -340.741959)
			(xy 173.495893 -340.687216) (xy 173.503724 -340.633036) (xy 173.519223 -340.580533) (xy 173.542071 -340.530786)
			(xy 173.5718 -340.484818) (xy 173.589442 -340.463886) (xy 173.598691 -340.452569) (xy 173.610861 -340.426007)
			(xy 173.615029 -340.397088) (xy 173.610854 -340.36817) (xy 173.598678 -340.341611) (xy 173.589442 -340.330282)
			(xy 173.571785 -340.309362) (xy 173.54206 -340.263393) (xy 173.519214 -340.213644) (xy 173.503719 -340.16114)
			(xy 173.495891 -340.106959) (xy 173.495893 -340.052216) (xy 173.503724 -339.998036) (xy 173.519223 -339.945533)
			(xy 173.542071 -339.895786) (xy 173.5718 -339.849818) (xy 173.589442 -339.828886) (xy 173.598691 -339.817569)
			(xy 173.610861 -339.791007) (xy 173.615029 -339.762088) (xy 173.610854 -339.73317) (xy 173.598678 -339.706611)
			(xy 173.589442 -339.695282) (xy 173.571785 -339.674362) (xy 173.54206 -339.628393) (xy 173.519214 -339.578644)
			(xy 173.503719 -339.52614) (xy 173.495891 -339.471959) (xy 173.495893 -339.417216) (xy 173.503724 -339.363036)
			(xy 173.519223 -339.310533) (xy 173.542071 -339.260786) (xy 173.5718 -339.214818) (xy 173.589442 -339.193886)
			(xy 173.598691 -339.182569) (xy 173.610861 -339.156007) (xy 173.615029 -339.127088) (xy 173.610854 -339.09817)
			(xy 173.598678 -339.071611) (xy 173.589442 -339.060282) (xy 173.571834 -339.039324) (xy 173.542116 -338.993359)
			(xy 173.519274 -338.943618) (xy 173.503775 -338.891123) (xy 173.49594 -338.836952) (xy 173.495462 -338.809584)
			(xy 173.495963 -338.782334) (xy 173.503721 -338.728388) (xy 173.519076 -338.676095) (xy 173.541717 -338.62652)
			(xy 173.571182 -338.580671) (xy 173.606872 -338.539482) (xy 173.64806 -338.503791) (xy 173.693908 -338.474324)
			(xy 173.743482 -338.451681) (xy 173.795774 -338.436324) (xy 173.84972 -338.428564) (xy 173.87697 -338.428076)
			(xy 173.877224 -338.428076) (xy 173.905238 -338.428604) (xy 173.96066 -338.436823) (xy 174.014287 -338.453051)
			(xy 174.064968 -338.476941) (xy 174.111613 -338.507979) (xy 174.132748 -338.526374) (xy 174.14419 -338.536019)
			(xy 174.171233 -338.548799) (xy 174.20082 -338.553185) (xy 174.230407 -338.548799) (xy 174.25745 -338.536019)
			(xy 174.268892 -338.526374) (xy 174.290005 -338.507948) (xy 174.336641 -338.476879) (xy 174.387324 -338.452976)
			(xy 174.440962 -338.436754) (xy 174.496397 -338.428564) (xy 174.524416 -338.428076) (xy 174.52467 -338.428076)
			(xy 174.55204 -338.428541) (xy 174.60622 -338.436356) (xy 174.658724 -338.451845) (xy 174.708471 -338.474687)
			(xy 174.754437 -338.504413) (xy 174.775368 -338.522056) (xy 174.786696 -338.531292) (xy 174.813253 -338.543468)
			(xy 174.84217 -338.547641) (xy 174.871087 -338.543468) (xy 174.897644 -338.531292) (xy 174.908972 -338.522056)
			(xy 174.929898 -338.504409) (xy 174.975873 -338.4747) (xy 175.025622 -338.451866) (xy 175.078124 -338.436377)
			(xy 175.132301 -338.428549) (xy 175.15967 -338.428076) (xy 175.186921 -338.428583) (xy 175.24087 -338.436336)
			(xy 175.293166 -338.451687) (xy 175.342745 -338.474325) (xy 175.388597 -338.503788) (xy 175.42979 -338.539477)
			(xy 175.465484 -338.580666) (xy 175.494953 -338.626515) (xy 175.517597 -338.676091) (xy 175.532955 -338.728385)
			(xy 175.540714 -338.782333) (xy 175.541178 -338.809584) (xy 175.540708 -338.836954) (xy 175.532892 -338.891133)
			(xy 175.517404 -338.943637) (xy 175.494563 -338.993383) (xy 175.464839 -339.03935) (xy 175.447198 -339.060282)
			(xy 175.437977 -339.071621) (xy 175.425798 -339.098174) (xy 175.421622 -339.127088) (xy 175.425791 -339.156002)
			(xy 175.437964 -339.182559) (xy 175.447198 -339.193886) (xy 175.464822 -339.214832) (xy 175.494546 -339.260798)
			(xy 175.51739 -339.310542) (xy 175.532887 -339.363042) (xy 175.540716 -339.417218) (xy 175.540718 -339.471958)
			(xy 175.532892 -339.526134) (xy 175.517399 -339.578635) (xy 175.494557 -339.628381) (xy 175.464837 -339.674349)
			(xy 175.447198 -339.695282) (xy 175.437977 -339.706621) (xy 175.425798 -339.733174) (xy 175.421622 -339.762088)
			(xy 175.425791 -339.791002) (xy 175.437964 -339.817559) (xy 175.447198 -339.828886) (xy 175.464822 -339.849832)
			(xy 175.494546 -339.895798) (xy 175.51739 -339.945542) (xy 175.532887 -339.998042) (xy 175.540716 -340.052218)
			(xy 175.540718 -340.106958) (xy 175.532892 -340.161134) (xy 175.517399 -340.213635) (xy 175.494557 -340.263381)
			(xy 175.464837 -340.309349) (xy 175.447198 -340.330282) (xy 175.437977 -340.341621) (xy 175.425798 -340.368174)
			(xy 175.421622 -340.397088) (xy 175.425791 -340.426002) (xy 175.437964 -340.452559) (xy 175.447198 -340.463886)
			(xy 175.464822 -340.484832) (xy 175.494546 -340.530798) (xy 175.51739 -340.580542) (xy 175.532887 -340.633042)
			(xy 175.540716 -340.687218) (xy 175.540718 -340.741958) (xy 175.532892 -340.796134) (xy 175.517399 -340.848635)
			(xy 175.494557 -340.898381) (xy 175.464837 -340.944349) (xy 175.447198 -340.965282) (xy 175.437977 -340.976621)
			(xy 175.425798 -341.003174) (xy 175.421622 -341.032088) (xy 175.425791 -341.061002) (xy 175.437964 -341.087559)
			(xy 175.447198 -341.098886) (xy 175.464822 -341.119832) (xy 175.494546 -341.165798) (xy 175.51739 -341.215542)
			(xy 175.532887 -341.268042) (xy 175.540716 -341.322218) (xy 175.540718 -341.376958) (xy 175.532892 -341.431134)
			(xy 175.517399 -341.483635) (xy 175.494557 -341.533381) (xy 175.464837 -341.579349) (xy 175.447198 -341.600282)
			(xy 175.437977 -341.611621) (xy 175.425798 -341.638174) (xy 175.421622 -341.667088) (xy 175.425791 -341.696002)
			(xy 175.437964 -341.722559) (xy 175.447198 -341.733886) (xy 175.464822 -341.754832) (xy 175.494546 -341.800798)
			(xy 175.51739 -341.850542) (xy 175.532887 -341.903042) (xy 175.540716 -341.957218) (xy 175.540718 -342.011958)
			(xy 175.532892 -342.066134) (xy 175.517399 -342.118635) (xy 175.494557 -342.168381) (xy 175.464837 -342.214349)
			(xy 175.447198 -342.235282) (xy 175.437977 -342.246621) (xy 175.425798 -342.273174) (xy 175.421622 -342.302088)
			(xy 175.425791 -342.331002) (xy 175.437964 -342.357559) (xy 175.447198 -342.368886) (xy 175.464844 -342.389813)
			(xy 175.494555 -342.435787) (xy 175.517389 -342.485536) (xy 175.532879 -342.538038) (xy 175.540705 -342.592214)
			(xy 175.541178 -342.619584) (xy 178.20259 -342.619584) (xy 178.203049 -342.592214) (xy 178.210869 -342.538034)
			(xy 178.22636 -342.485531) (xy 178.249203 -342.435784) (xy 178.278928 -342.389818) (xy 178.29657 -342.368886)
			(xy 178.305825 -342.357571) (xy 178.318004 -342.33101) (xy 178.322175 -342.302088) (xy 178.317997 -342.273167)
			(xy 178.305812 -342.246608) (xy 178.29657 -342.235282) (xy 178.278912 -342.214363) (xy 178.249184 -342.168394)
			(xy 178.226337 -342.118645) (xy 178.21084 -342.066141) (xy 178.203012 -342.01196) (xy 178.203014 -341.957216)
			(xy 178.210846 -341.903035) (xy 178.226346 -341.850532) (xy 178.249196 -341.800785) (xy 178.278926 -341.754818)
			(xy 178.29657 -341.733886) (xy 178.305825 -341.722571) (xy 178.318004 -341.69601) (xy 178.322175 -341.667088)
			(xy 178.317997 -341.638167) (xy 178.305812 -341.611608) (xy 178.29657 -341.600282) (xy 178.278912 -341.579363)
			(xy 178.249184 -341.533394) (xy 178.226337 -341.483645) (xy 178.21084 -341.431141) (xy 178.203012 -341.37696)
			(xy 178.203014 -341.322216) (xy 178.210846 -341.268035) (xy 178.226346 -341.215532) (xy 178.249196 -341.165785)
			(xy 178.278926 -341.119818) (xy 178.29657 -341.098886) (xy 178.305825 -341.087571) (xy 178.318004 -341.06101)
			(xy 178.322175 -341.032088) (xy 178.317997 -341.003167) (xy 178.305812 -340.976608) (xy 178.29657 -340.965282)
			(xy 178.278912 -340.944363) (xy 178.249184 -340.898394) (xy 178.226337 -340.848645) (xy 178.21084 -340.796141)
			(xy 178.203012 -340.74196) (xy 178.203014 -340.687216) (xy 178.210846 -340.633035) (xy 178.226346 -340.580532)
			(xy 178.249196 -340.530785) (xy 178.278926 -340.484818) (xy 178.29657 -340.463886) (xy 178.305825 -340.452571)
			(xy 178.318004 -340.42601) (xy 178.322175 -340.397088) (xy 178.317997 -340.368167) (xy 178.305812 -340.341608)
			(xy 178.29657 -340.330282) (xy 178.278912 -340.309363) (xy 178.249184 -340.263394) (xy 178.226337 -340.213645)
			(xy 178.21084 -340.161141) (xy 178.203012 -340.10696) (xy 178.203014 -340.052216) (xy 178.210846 -339.998035)
			(xy 178.226346 -339.945532) (xy 178.249196 -339.895785) (xy 178.278926 -339.849818) (xy 178.29657 -339.828886)
			(xy 178.305825 -339.817571) (xy 178.318004 -339.79101) (xy 178.322175 -339.762088) (xy 178.317997 -339.733167)
			(xy 178.305812 -339.706608) (xy 178.29657 -339.695282) (xy 178.278912 -339.674363) (xy 178.249184 -339.628394)
			(xy 178.226337 -339.578645) (xy 178.21084 -339.526141) (xy 178.203012 -339.47196) (xy 178.203014 -339.417216)
			(xy 178.210846 -339.363035) (xy 178.226346 -339.310532) (xy 178.249196 -339.260785) (xy 178.278926 -339.214818)
			(xy 178.29657 -339.193886) (xy 178.305825 -339.182571) (xy 178.318004 -339.15601) (xy 178.322175 -339.127088)
			(xy 178.317997 -339.098167) (xy 178.305812 -339.071608) (xy 178.29657 -339.060282) (xy 178.278951 -339.039334)
			(xy 178.249237 -338.993365) (xy 178.226398 -338.943621) (xy 178.210902 -338.891125) (xy 178.203068 -338.836952)
			(xy 178.20259 -338.809584) (xy 178.203063 -338.782332) (xy 178.210822 -338.728384) (xy 178.226179 -338.676089)
			(xy 178.248821 -338.626512) (xy 178.278289 -338.580662) (xy 178.313982 -338.539472) (xy 178.355173 -338.503781)
			(xy 178.401025 -338.474315) (xy 178.450603 -338.451674) (xy 178.502898 -338.436319) (xy 178.556846 -338.428562)
			(xy 178.584098 -338.428076) (xy 178.611469 -338.428525) (xy 178.66565 -338.436344) (xy 178.718154 -338.451836)
			(xy 178.7679 -338.474682) (xy 178.813866 -338.504412) (xy 178.834796 -338.522056) (xy 178.846124 -338.531292)
			(xy 178.872681 -338.543468) (xy 178.901598 -338.547641) (xy 178.930515 -338.543468) (xy 178.957072 -338.531292)
			(xy 178.9684 -338.522056) (xy 178.989315 -338.504396) (xy 179.035293 -338.474689) (xy 179.085045 -338.451858)
			(xy 179.137549 -338.436371) (xy 179.191728 -338.428547) (xy 179.219098 -338.428076) (xy 179.219352 -338.428076)
			(xy 179.247367 -338.428588) (xy 179.30279 -338.43681) (xy 179.356417 -338.453043) (xy 179.407097 -338.476936)
			(xy 179.453742 -338.507978) (xy 179.474876 -338.526374) (xy 179.486318 -338.536019) (xy 179.513361 -338.548799)
			(xy 179.542948 -338.553185) (xy 179.572535 -338.548799) (xy 179.599578 -338.536019) (xy 179.61102 -338.526374)
			(xy 179.632161 -338.507982) (xy 179.678789 -338.476908) (xy 179.729466 -338.452999) (xy 179.783097 -338.436769)
			(xy 179.838527 -338.428569) (xy 179.866544 -338.428076) (xy 179.866798 -338.428076) (xy 179.894048 -338.42858)
			(xy 179.947995 -338.436335) (xy 180.000288 -338.451689) (xy 180.049864 -338.474329) (xy 180.095714 -338.503794)
			(xy 180.136904 -338.539483) (xy 180.172595 -338.580672) (xy 180.202062 -338.62652) (xy 180.224704 -338.676095)
			(xy 180.240061 -338.728388) (xy 180.247819 -338.782334) (xy 180.248306 -338.809584) (xy 180.247829 -338.836954)
			(xy 180.240014 -338.891132) (xy 180.224527 -338.943635) (xy 180.201688 -338.993382) (xy 180.171966 -339.03935)
			(xy 180.154326 -339.060282) (xy 180.145102 -339.07162) (xy 180.13292 -339.098173) (xy 180.128743 -339.127088)
			(xy 180.132913 -339.156003) (xy 180.145089 -339.18256) (xy 180.154326 -339.193886) (xy 180.171953 -339.214831)
			(xy 180.201682 -339.260795) (xy 180.224531 -339.310539) (xy 180.240031 -339.36304) (xy 180.247862 -339.417218)
			(xy 180.247864 -339.471958) (xy 180.240036 -339.526137) (xy 180.22454 -339.578638) (xy 180.201694 -339.628384)
			(xy 180.171968 -339.67435) (xy 180.154326 -339.695282) (xy 180.145102 -339.70662) (xy 180.13292 -339.733173)
			(xy 180.128743 -339.762088) (xy 180.132913 -339.791003) (xy 180.145089 -339.81756) (xy 180.154326 -339.828886)
			(xy 180.171953 -339.849831) (xy 180.201682 -339.895795) (xy 180.224531 -339.945539) (xy 180.240031 -339.99804)
			(xy 180.247862 -340.052218) (xy 180.247864 -340.106958) (xy 180.240036 -340.161137) (xy 180.22454 -340.213638)
			(xy 180.201694 -340.263384) (xy 180.171968 -340.30935) (xy 180.154326 -340.330282) (xy 180.145102 -340.34162)
			(xy 180.13292 -340.368173) (xy 180.128743 -340.397088) (xy 180.132913 -340.426003) (xy 180.145089 -340.45256)
			(xy 180.154326 -340.463886) (xy 180.171953 -340.484831) (xy 180.201682 -340.530795) (xy 180.224531 -340.580539)
			(xy 180.240031 -340.63304) (xy 180.247862 -340.687218) (xy 180.247864 -340.741958) (xy 180.240036 -340.796137)
			(xy 180.22454 -340.848638) (xy 180.201694 -340.898384) (xy 180.171968 -340.94435) (xy 180.154326 -340.965282)
			(xy 180.145102 -340.97662) (xy 180.13292 -341.003173) (xy 180.128743 -341.032088) (xy 180.132913 -341.061003)
			(xy 180.145089 -341.08756) (xy 180.154326 -341.098886) (xy 180.171953 -341.119831) (xy 180.201682 -341.165795)
			(xy 180.224531 -341.215539) (xy 180.240031 -341.26804) (xy 180.247862 -341.322218) (xy 180.247864 -341.376958)
			(xy 180.240036 -341.431137) (xy 180.22454 -341.483638) (xy 180.201694 -341.533384) (xy 180.171968 -341.57935)
			(xy 180.154326 -341.600282) (xy 180.145102 -341.61162) (xy 180.13292 -341.638173) (xy 180.128743 -341.667088)
			(xy 180.132913 -341.696003) (xy 180.145089 -341.72256) (xy 180.154326 -341.733886) (xy 180.171953 -341.754831)
			(xy 180.201682 -341.800795) (xy 180.224531 -341.850539) (xy 180.240031 -341.90304) (xy 180.247862 -341.957218)
			(xy 180.247864 -342.011958) (xy 180.240036 -342.066137) (xy 180.22454 -342.118638) (xy 180.201694 -342.168384)
			(xy 180.171968 -342.21435) (xy 180.154326 -342.235282) (xy 180.145102 -342.24662) (xy 180.13292 -342.273173)
			(xy 180.128743 -342.302088) (xy 180.132913 -342.331003) (xy 180.145089 -342.35756) (xy 180.154326 -342.368886)
			(xy 180.171976 -342.389809) (xy 180.201685 -342.435785) (xy 180.224519 -342.485535) (xy 180.240007 -342.538037)
			(xy 180.247833 -342.592214) (xy 180.248306 -342.619584) (xy 180.24783 -342.646837) (xy 180.240075 -342.700787)
			(xy 180.224721 -342.753085) (xy 180.20208 -342.802665) (xy 180.172614 -342.848518) (xy 180.136921 -342.889711)
			(xy 180.09573 -342.925405) (xy 180.049877 -342.954873) (xy 180.000298 -342.977516) (xy 179.948001 -342.992872)
			(xy 179.894051 -343.000629) (xy 179.866798 -343.001092) (xy 179.866544 -343.001092) (xy 179.838529 -343.000591)
			(xy 179.783105 -342.992367) (xy 179.729477 -342.976132) (xy 179.678798 -342.952237) (xy 179.632153 -342.921192)
			(xy 179.61102 -342.902794) (xy 179.599578 -342.893149) (xy 179.572535 -342.880369) (xy 179.542948 -342.875983)
			(xy 179.513361 -342.880369) (xy 179.486318 -342.893149) (xy 179.474876 -342.902794) (xy 179.453732 -342.921183)
			(xy 179.407105 -342.952258) (xy 179.35643 -342.976169) (xy 179.302799 -342.992399) (xy 179.247369 -343.000599)
			(xy 179.219352 -343.001092) (xy 179.219098 -343.001092) (xy 179.191728 -343.000629) (xy 179.137548 -342.992811)
			(xy 179.085045 -342.977321) (xy 179.035298 -342.954479) (xy 178.989332 -342.924753) (xy 178.9684 -342.907112)
			(xy 178.957072 -342.897876) (xy 178.930515 -342.8857) (xy 178.901598 -342.881527) (xy 178.872681 -342.8857)
			(xy 178.846124 -342.897876) (xy 178.834796 -342.907112) (xy 178.813878 -342.924768) (xy 178.767901 -342.954477)
			(xy 178.71815 -342.97731) (xy 178.665646 -342.992797) (xy 178.611468 -343.00062) (xy 178.584098 -343.001092)
			(xy 178.556844 -343.000646) (xy 178.502892 -342.992889) (xy 178.450593 -342.977532) (xy 178.401012 -342.954888)
			(xy 178.355158 -342.925418) (xy 178.313965 -342.889723) (xy 178.278271 -342.848528) (xy 178.248804 -342.802673)
			(xy 178.226162 -342.75309) (xy 178.210807 -342.70079) (xy 178.203052 -342.646838) (xy 178.20259 -342.619584)
			(xy 175.541178 -342.619584) (xy 175.54073 -342.646838) (xy 175.532974 -342.700791) (xy 175.517619 -342.753091)
			(xy 175.494976 -342.802673) (xy 175.465507 -342.848528) (xy 175.429811 -342.889721) (xy 175.388616 -342.925415)
			(xy 175.342761 -342.954883) (xy 175.293178 -342.977524) (xy 175.240877 -342.992877) (xy 175.186924 -343.000631)
			(xy 175.15967 -343.001092) (xy 175.132299 -343.000645) (xy 175.078119 -342.992823) (xy 175.025616 -342.97733)
			(xy 174.975869 -342.954484) (xy 174.929903 -342.924755) (xy 174.908972 -342.907112) (xy 174.897644 -342.897876)
			(xy 174.871087 -342.8857) (xy 174.84217 -342.881527) (xy 174.813253 -342.8857) (xy 174.786696 -342.897876)
			(xy 174.775368 -342.907112) (xy 174.754423 -342.924735) (xy 174.708453 -342.954448) (xy 174.658709 -342.977287)
			(xy 174.606211 -342.992782) (xy 174.552038 -343.000615) (xy 174.52467 -343.001092) (xy 174.524416 -343.001092)
			(xy 174.4964 -343.000608) (xy 174.440976 -342.992379) (xy 174.387348 -342.976141) (xy 174.336668 -342.952242)
			(xy 174.290025 -342.921194) (xy 174.268892 -342.902794) (xy 174.25745 -342.893149) (xy 174.230407 -342.880369)
			(xy 174.20082 -342.875983) (xy 174.171233 -342.880369) (xy 174.14419 -342.893149) (xy 174.132748 -342.902794)
			(xy 174.111615 -342.921196) (xy 174.064985 -342.952269) (xy 174.014307 -342.976178) (xy 173.960673 -342.992405)
			(xy 173.905241 -343.000601) (xy 173.877224 -343.001092) (xy 173.87697 -343.001092) (xy 173.849717 -343.00065)
			(xy 173.795767 -342.992889) (xy 173.743471 -342.977529) (xy 173.693892 -342.954883) (xy 173.648041 -342.925413)
			(xy 173.606851 -342.889717) (xy 173.57116 -342.848522) (xy 173.541694 -342.802667) (xy 173.519055 -342.753086)
			(xy 173.503701 -342.700788) (xy 173.495947 -342.646837) (xy 173.495462 -342.619584) (xy 170.570906 -342.619584)
			(xy 170.57043 -342.646837) (xy 170.562675 -342.700787) (xy 170.547321 -342.753085) (xy 170.52468 -342.802665)
			(xy 170.495214 -342.848518) (xy 170.459521 -342.889711) (xy 170.41833 -342.925405) (xy 170.372477 -342.954873)
			(xy 170.322898 -342.977516) (xy 170.270601 -342.992872) (xy 170.216651 -343.000629) (xy 170.189398 -343.001092)
			(xy 170.189144 -343.001092) (xy 170.161129 -343.000591) (xy 170.105705 -342.992367) (xy 170.052077 -342.976132)
			(xy 170.001398 -342.952237) (xy 169.954753 -342.921192) (xy 169.93362 -342.902794) (xy 169.922178 -342.893149)
			(xy 169.895135 -342.880369) (xy 169.865548 -342.875983) (xy 169.835961 -342.880369) (xy 169.808918 -342.893149)
			(xy 169.797476 -342.902794) (xy 169.776332 -342.921183) (xy 169.729705 -342.952258) (xy 169.67903 -342.976169)
			(xy 169.625399 -342.992399) (xy 169.569969 -343.000599) (xy 169.541952 -343.001092) (xy 169.541698 -343.001092)
			(xy 169.514328 -343.000629) (xy 169.460148 -342.992811) (xy 169.407645 -342.977321) (xy 169.357898 -342.954479)
			(xy 169.311932 -342.924753) (xy 169.291 -342.907112) (xy 169.279672 -342.897876) (xy 169.253115 -342.8857)
			(xy 169.224198 -342.881527) (xy 169.195281 -342.8857) (xy 169.168724 -342.897876) (xy 169.157396 -342.907112)
			(xy 169.136478 -342.924768) (xy 169.090501 -342.954477) (xy 169.04075 -342.97731) (xy 168.988246 -342.992797)
			(xy 168.934068 -343.00062) (xy 168.906698 -343.001092) (xy 168.879444 -343.000646) (xy 168.825492 -342.992889)
			(xy 168.773193 -342.977532) (xy 168.723612 -342.954888) (xy 168.677758 -342.925418) (xy 168.636565 -342.889723)
			(xy 168.600871 -342.848528) (xy 168.571404 -342.802673) (xy 168.548762 -342.75309) (xy 168.533407 -342.70079)
			(xy 168.525652 -342.646838) (xy 168.52519 -342.619584) (xy 128.568196 -342.619584) (xy 128.568196 -343.73185)
			(xy 128.567524 -343.756844) (xy 128.55773 -343.805865) (xy 128.538567 -343.852035) (xy 128.51077 -343.893584)
			(xy 128.49352 -343.911682) (xy 128.027938 -344.377264) (xy 133.84403 -344.377264) (xy 133.844468 -344.349893)
			(xy 133.852291 -344.295712) (xy 133.867787 -344.243208) (xy 133.890635 -344.193462) (xy 133.920366 -344.147497)
			(xy 133.93801 -344.126566) (xy 133.947281 -344.115264) (xy 133.959453 -344.088697) (xy 133.963618 -344.059773)
			(xy 133.959437 -344.030851) (xy 133.947251 -344.00429) (xy 133.93801 -343.992962) (xy 133.920388 -343.972016)
			(xy 133.890673 -343.926047) (xy 133.867834 -343.876303) (xy 133.852339 -343.823806) (xy 133.844506 -343.769632)
			(xy 133.84403 -343.742264) (xy 133.844516 -343.715013) (xy 133.852272 -343.661065) (xy 133.867627 -343.60877)
			(xy 133.890269 -343.559193) (xy 133.919735 -343.513343) (xy 133.955426 -343.472152) (xy 133.996617 -343.436461)
			(xy 134.042467 -343.406995) (xy 134.092044 -343.384353) (xy 134.144339 -343.368998) (xy 134.198287 -343.361242)
			(xy 134.252789 -343.361242) (xy 134.306737 -343.368998) (xy 134.359032 -343.384353) (xy 134.408609 -343.406995)
			(xy 134.454459 -343.436461) (xy 134.485224 -343.463118) (xy 143.511522 -343.463118) (xy 143.515593 -343.407496)
			(xy 143.527719 -343.353059) (xy 143.547642 -343.300968) (xy 143.574938 -343.252333) (xy 143.609024 -343.20819)
			(xy 143.649173 -343.169481) (xy 143.694531 -343.13703) (xy 143.744131 -343.111529) (xy 143.796915 -343.093522)
			(xy 143.851758 -343.083392) (xy 143.907492 -343.081355) (xy 143.962929 -343.087455) (xy 144.016886 -343.101561)
			(xy 144.068215 -343.123373) (xy 144.115821 -343.152427) (xy 144.158689 -343.188102) (xy 144.195906 -343.229639)
			(xy 144.226679 -343.276152) (xy 144.250351 -343.326649) (xy 144.266419 -343.380056) (xy 144.274539 -343.435232)
			(xy 144.275048 -343.463118) (xy 144.274539 -343.491004) (xy 144.26855 -343.531698) (xy 144.792952 -343.531698)
			(xy 144.797023 -343.476076) (xy 144.809149 -343.421639) (xy 144.829072 -343.369548) (xy 144.856368 -343.320913)
			(xy 144.890454 -343.27677) (xy 144.930603 -343.238061) (xy 144.975961 -343.20561) (xy 145.025561 -343.180109)
			(xy 145.078345 -343.162102) (xy 145.133188 -343.151972) (xy 145.188922 -343.149935) (xy 145.244359 -343.156035)
			(xy 145.298316 -343.170141) (xy 145.349645 -343.191953) (xy 145.397251 -343.221007) (xy 145.440119 -343.256682)
			(xy 145.477336 -343.298219) (xy 145.508109 -343.344732) (xy 145.531781 -343.395229) (xy 145.547849 -343.448636)
			(xy 145.555969 -343.503812) (xy 145.556478 -343.531698) (xy 145.555969 -343.559584) (xy 145.547849 -343.61476)
			(xy 145.531781 -343.668167) (xy 145.508109 -343.718664) (xy 145.477336 -343.765177) (xy 145.440119 -343.806714)
			(xy 145.397251 -343.842389) (xy 145.349645 -343.871443) (xy 145.298316 -343.893255) (xy 145.244359 -343.907361)
			(xy 145.188922 -343.913461) (xy 145.133188 -343.911424) (xy 145.078345 -343.901294) (xy 145.025561 -343.883287)
			(xy 144.975961 -343.857786) (xy 144.930603 -343.825335) (xy 144.890454 -343.786626) (xy 144.856368 -343.742483)
			(xy 144.829072 -343.693848) (xy 144.809149 -343.641757) (xy 144.797023 -343.58732) (xy 144.792952 -343.531698)
			(xy 144.26855 -343.531698) (xy 144.266419 -343.54618) (xy 144.250351 -343.599587) (xy 144.226679 -343.650084)
			(xy 144.195906 -343.696597) (xy 144.158689 -343.738134) (xy 144.115821 -343.773809) (xy 144.068215 -343.802863)
			(xy 144.016886 -343.824675) (xy 143.962929 -343.838781) (xy 143.907492 -343.844881) (xy 143.851758 -343.842844)
			(xy 143.796915 -343.832714) (xy 143.744131 -343.814707) (xy 143.694531 -343.789206) (xy 143.649173 -343.756755)
			(xy 143.609024 -343.718046) (xy 143.574938 -343.673903) (xy 143.547642 -343.625268) (xy 143.527719 -343.573177)
			(xy 143.515593 -343.51874) (xy 143.511522 -343.463118) (xy 134.485224 -343.463118) (xy 134.49565 -343.472152)
			(xy 134.531341 -343.513343) (xy 134.560807 -343.559193) (xy 134.583449 -343.60877) (xy 134.598804 -343.661065)
			(xy 134.60656 -343.715013) (xy 134.607046 -343.742264) (xy 134.606572 -343.769634) (xy 134.598758 -343.823813)
			(xy 134.583272 -343.876317) (xy 134.560431 -343.926064) (xy 134.530707 -343.972031) (xy 134.513066 -343.992962)
			(xy 134.503867 -344.004316) (xy 134.491689 -344.030865) (xy 134.487511 -344.059773) (xy 134.491674 -344.088683)
			(xy 134.503837 -344.115238) (xy 134.513066 -344.126566) (xy 134.530697 -344.147504) (xy 134.560411 -344.193475)
			(xy 134.583249 -344.243221) (xy 134.598742 -344.29572) (xy 134.606572 -344.349895) (xy 134.607046 -344.377264)
			(xy 134.60656 -344.404515) (xy 134.598804 -344.458463) (xy 134.583449 -344.510758) (xy 134.560807 -344.560335)
			(xy 134.531341 -344.606185) (xy 134.49565 -344.647376) (xy 134.454459 -344.683067) (xy 134.408609 -344.712533)
			(xy 134.359032 -344.735175) (xy 134.306737 -344.75053) (xy 134.252789 -344.758286) (xy 134.198287 -344.758286)
			(xy 134.144339 -344.75053) (xy 134.092044 -344.735175) (xy 134.042467 -344.712533) (xy 133.996617 -344.683067)
			(xy 133.955426 -344.647376) (xy 133.919735 -344.606185) (xy 133.890269 -344.560335) (xy 133.867627 -344.510758)
			(xy 133.852272 -344.458463) (xy 133.844516 -344.404515) (xy 133.84403 -344.377264) (xy 128.027938 -344.377264)
			(xy 127.625302 -344.7799) (xy 138.092587 -344.7799) (xy 138.096756 -344.724274) (xy 138.109169 -344.669891)
			(xy 138.129549 -344.617966) (xy 138.15744 -344.569658) (xy 138.19222 -344.526046) (xy 138.233112 -344.488106)
			(xy 138.279202 -344.456684) (xy 138.32946 -344.432482) (xy 138.382764 -344.416042) (xy 138.437923 -344.40773)
			(xy 138.465814 -344.407236) (xy 138.493148 -344.407663) (xy 138.547229 -344.41564) (xy 138.599565 -344.431436)
			(xy 138.649029 -344.454711) (xy 138.694561 -344.484966) (xy 138.735182 -344.52155) (xy 138.77002 -344.563679)
			(xy 138.784584 -344.586814) (xy 138.792541 -344.599014) (xy 138.814004 -344.618683) (xy 138.840148 -344.63149)
			(xy 138.868845 -344.636392) (xy 138.897758 -344.63299) (xy 138.91133 -344.627708) (xy 138.934539 -344.618217)
			(xy 138.982873 -344.604867) (xy 139.032562 -344.598139) (xy 139.057634 -344.597736) (xy 139.082703 -344.59816)
			(xy 139.132386 -344.604909) (xy 139.180721 -344.618242) (xy 139.203938 -344.627708) (xy 139.217525 -344.632926)
			(xy 139.246421 -344.636297) (xy 139.275096 -344.631393) (xy 139.301229 -344.618611) (xy 139.322703 -344.598986)
			(xy 139.330684 -344.586814) (xy 139.345253 -344.563683) (xy 139.380096 -344.521562) (xy 139.420719 -344.484983)
			(xy 139.46625 -344.454732) (xy 139.515712 -344.431456) (xy 139.568043 -344.415656) (xy 139.622122 -344.40767)
			(xy 139.676786 -344.40767) (xy 139.730865 -344.415656) (xy 139.783196 -344.431456) (xy 139.832658 -344.454732)
			(xy 139.878189 -344.484983) (xy 139.918812 -344.521562) (xy 139.953655 -344.563683) (xy 139.968224 -344.586814)
			(xy 139.976143 -344.599041) (xy 139.997616 -344.61871) (xy 140.023771 -344.631514) (xy 140.052476 -344.636408)
			(xy 140.081396 -344.632996) (xy 140.09497 -344.627708) (xy 140.118187 -344.618236) (xy 140.166516 -344.604878)
			(xy 140.216203 -344.598143) (xy 140.241274 -344.597736) (xy 140.268118 -344.598183) (xy 140.32125 -344.605885)
			(xy 140.372727 -344.621134) (xy 140.421482 -344.643612) (xy 140.466505 -344.672856) (xy 140.506866 -344.70826)
			(xy 140.541726 -344.74909) (xy 140.570366 -344.7945) (xy 140.592192 -344.843551) (xy 140.599922 -344.869262)
			(xy 140.604566 -344.883766) (xy 140.621088 -344.909332) (xy 140.644408 -344.928897) (xy 140.672456 -344.940726)
			(xy 140.702743 -344.943768) (xy 140.732583 -344.937755) (xy 140.746226 -344.930984) (xy 140.774377 -344.916361)
			(xy 140.834326 -344.89563) (xy 140.896882 -344.885128) (xy 140.928598 -344.884502) (xy 140.946617 -344.884727)
			(xy 140.982492 -344.888158) (xy 141.000226 -344.89136) (xy 141.015432 -344.893723) (xy 141.045988 -344.890188)
			(xy 141.074107 -344.877721) (xy 141.097243 -344.85745) (xy 141.113299 -344.831213) (xy 141.117574 -344.81643)
			(xy 141.124994 -344.789393) (xy 141.146623 -344.737669) (xy 141.175586 -344.689666) (xy 141.21126 -344.646416)
			(xy 141.252876 -344.608849) (xy 141.29954 -344.577774) (xy 141.350247 -344.55386) (xy 141.403907 -344.53762)
			(xy 141.459366 -344.529404) (xy 141.487398 -344.528902) (xy 141.514651 -344.529357) (xy 141.568603 -344.537114)
			(xy 141.620902 -344.55247) (xy 141.670482 -344.575113) (xy 141.716336 -344.604582) (xy 141.757529 -344.640277)
			(xy 141.793223 -344.68147) (xy 141.82269 -344.727325) (xy 141.845332 -344.776906) (xy 141.860688 -344.829205)
			(xy 141.868443 -344.883157) (xy 141.868906 -344.91041) (xy 141.868376 -344.937982) (xy 141.860437 -344.992552)
			(xy 141.844724 -345.045411) (xy 141.821566 -345.095457) (xy 141.791445 -345.141648) (xy 141.754988 -345.183022)
			(xy 141.734286 -345.20124) (xy 141.72338 -345.211129) (xy 141.707311 -345.235783) (xy 141.69893 -345.263992)
			(xy 141.698932 -345.293421) (xy 141.707317 -345.321629) (xy 141.723389 -345.34628) (xy 141.734286 -345.35618)
			(xy 141.755002 -345.374385) (xy 141.791467 -345.415757) (xy 141.821594 -345.461948) (xy 141.844757 -345.511997)
			(xy 141.860472 -345.564859) (xy 141.868412 -345.619432) (xy 141.868411 -345.674581) (xy 141.860469 -345.729154)
			(xy 141.844752 -345.782016) (xy 141.843402 -345.784932) (xy 144.561812 -345.784932) (xy 144.565883 -345.72931)
			(xy 144.578009 -345.674873) (xy 144.597932 -345.622782) (xy 144.625228 -345.574147) (xy 144.659314 -345.530004)
			(xy 144.699463 -345.491295) (xy 144.744821 -345.458844) (xy 144.794421 -345.433343) (xy 144.847205 -345.415336)
			(xy 144.902048 -345.405206) (xy 144.957782 -345.403169) (xy 145.013219 -345.409269) (xy 145.067176 -345.423375)
			(xy 145.118505 -345.445187) (xy 145.166111 -345.474241) (xy 145.208979 -345.509916) (xy 145.246196 -345.551453)
			(xy 145.276969 -345.597966) (xy 145.300641 -345.648463) (xy 145.316709 -345.70187) (xy 145.324829 -345.757046)
			(xy 145.325338 -345.784932) (xy 145.324829 -345.812818) (xy 145.316709 -345.867994) (xy 145.300641 -345.921401)
			(xy 145.276969 -345.971898) (xy 145.246196 -346.018411) (xy 145.208979 -346.059948) (xy 145.166111 -346.095623)
			(xy 145.118505 -346.124677) (xy 145.067176 -346.146489) (xy 145.013219 -346.160595) (xy 144.957782 -346.166695)
			(xy 144.902048 -346.164658) (xy 144.847205 -346.154528) (xy 144.794421 -346.136521) (xy 144.744821 -346.11102)
			(xy 144.699463 -346.078569) (xy 144.659314 -346.03986) (xy 144.625228 -345.995717) (xy 144.597932 -345.947082)
			(xy 144.578009 -345.894991) (xy 144.565883 -345.840554) (xy 144.561812 -345.784932) (xy 141.843402 -345.784932)
			(xy 141.821588 -345.832063) (xy 141.791459 -345.878254) (xy 141.754993 -345.919625) (xy 141.734286 -345.93784)
			(xy 141.72338 -345.947729) (xy 141.707311 -345.972383) (xy 141.69893 -346.000592) (xy 141.698932 -346.030021)
			(xy 141.707317 -346.058229) (xy 141.723389 -346.08288) (xy 141.734286 -346.09278) (xy 141.754988 -346.111001)
			(xy 141.791459 -346.152368) (xy 141.821593 -346.198555) (xy 141.844761 -346.248601) (xy 141.860479 -346.301462)
			(xy 141.86842 -346.356036) (xy 141.868906 -346.38361) (xy 141.868432 -346.410862) (xy 141.860674 -346.46481)
			(xy 141.845317 -346.517105) (xy 141.822675 -346.566682) (xy 141.793207 -346.612533) (xy 141.757514 -346.653723)
			(xy 141.716323 -346.689414) (xy 141.670472 -346.71888) (xy 141.620894 -346.741521) (xy 141.568598 -346.756876)
			(xy 141.51465 -346.764632) (xy 141.487398 -346.765118) (xy 141.459543 -346.764584) (xy 141.404429 -346.75646)
			(xy 141.35108 -346.740415) (xy 141.300628 -346.716789) (xy 141.254143 -346.686084) (xy 141.212614 -346.64895)
			(xy 141.17692 -346.606177) (xy 141.14782 -346.558672) (xy 141.125931 -346.507442) (xy 141.118336 -346.480638)
			(xy 141.114074 -346.466517) (xy 141.098685 -346.441368) (xy 141.076764 -346.42165) (xy 141.050131 -346.409)
			(xy 141.020997 -346.404469) (xy 141.006322 -346.405962) (xy 140.993305 -346.407627) (xy 140.967121 -346.40941)
			(xy 140.953998 -346.409518) (xy 140.939849 -346.409424) (xy 140.911626 -346.40739) (xy 140.89761 -346.405454)
			(xy 140.884268 -346.403791) (xy 140.857565 -346.406899) (xy 140.832604 -346.416882) (xy 140.811121 -346.433043)
			(xy 140.794611 -346.454258) (xy 140.784222 -346.479052) (xy 140.78204 -346.492322) (xy 140.777912 -346.519469)
			(xy 140.762943 -346.572297) (xy 140.740556 -346.622434) (xy 140.711213 -346.668844) (xy 140.67552 -346.710569)
			(xy 140.634215 -346.746746) (xy 140.588151 -346.776628) (xy 140.538278 -346.799598) (xy 140.485628 -346.815183)
			(xy 140.431288 -346.823058) (xy 140.403834 -346.823538) (xy 140.376583 -346.823013) (xy 140.322636 -346.815262)
			(xy 140.270341 -346.799911) (xy 140.220763 -346.777275) (xy 140.174911 -346.747813) (xy 140.133719 -346.712126)
			(xy 140.098025 -346.67094) (xy 140.068556 -346.625093) (xy 140.045911 -346.575519) (xy 140.030552 -346.523226)
			(xy 140.022791 -346.469281) (xy 140.022326 -346.44203) (xy 140.022803 -346.414456) (xy 140.030752 -346.359883)
			(xy 140.046474 -346.307023) (xy 140.069642 -346.256977) (xy 140.099773 -346.210787) (xy 140.136239 -346.169416)
			(xy 140.156946 -346.1512) (xy 140.167817 -346.141273) (xy 140.183899 -346.116633) (xy 140.192291 -346.088431)
			(xy 140.192296 -346.059007) (xy 140.183915 -346.030802) (xy 140.167843 -346.006156) (xy 140.156946 -345.99626)
			(xy 140.13627 -345.978011) (xy 140.099795 -345.936651) (xy 140.069657 -345.89047) (xy 140.046485 -345.840429)
			(xy 140.030762 -345.787573) (xy 140.022815 -345.733003) (xy 140.022326 -345.70543) (xy 140.022752 -345.678928)
			(xy 140.030103 -345.626435) (xy 140.044654 -345.575467) (xy 140.066123 -345.527005) (xy 140.094098 -345.481984)
			(xy 140.110718 -345.461336) (xy 140.120186 -345.449208) (xy 140.131978 -345.420802) (xy 140.1348 -345.390175)
			(xy 140.128399 -345.360092) (xy 140.113351 -345.333268) (xy 140.091015 -345.312124) (xy 140.077444 -345.304872)
			(xy 140.05375 -345.292778) (xy 140.009769 -345.262853) (xy 139.970489 -345.22698) (xy 139.936707 -345.185888)
			(xy 139.922504 -345.163394) (xy 139.914556 -345.151187) (xy 139.893091 -345.131517) (xy 139.866945 -345.11871)
			(xy 139.838245 -345.11381) (xy 139.809331 -345.117216) (xy 139.795758 -345.1225) (xy 139.77255 -345.131995)
			(xy 139.724216 -345.145344) (xy 139.674526 -345.15207) (xy 139.649454 -345.152472) (xy 139.624385 -345.152051)
			(xy 139.574701 -345.1453) (xy 139.526367 -345.131967) (xy 139.50315 -345.1225) (xy 139.489568 -345.117266)
			(xy 139.46067 -345.113897) (xy 139.431992 -345.118804) (xy 139.405858 -345.13159) (xy 139.384384 -345.15122)
			(xy 139.376404 -345.163394) (xy 139.361835 -345.186525) (xy 139.326992 -345.228646) (xy 139.286369 -345.265225)
			(xy 139.240838 -345.295476) (xy 139.191376 -345.318752) (xy 139.139045 -345.334552) (xy 139.084966 -345.342538)
			(xy 139.030302 -345.342538) (xy 138.976223 -345.334552) (xy 138.923892 -345.318752) (xy 138.87443 -345.295476)
			(xy 138.828899 -345.265225) (xy 138.788276 -345.228646) (xy 138.753433 -345.186525) (xy 138.738864 -345.163394)
			(xy 138.730954 -345.15116) (xy 138.709479 -345.13149) (xy 138.683322 -345.118687) (xy 138.654614 -345.113794)
			(xy 138.625692 -345.11721) (xy 138.612118 -345.1225) (xy 138.588903 -345.131976) (xy 138.540573 -345.145332)
			(xy 138.490885 -345.152066) (xy 138.465814 -345.152472) (xy 138.437923 -345.15207) (xy 138.382764 -345.143758)
			(xy 138.32946 -345.127318) (xy 138.279202 -345.103116) (xy 138.233112 -345.071694) (xy 138.19222 -345.033754)
			(xy 138.15744 -344.990143) (xy 138.129549 -344.941834) (xy 138.109169 -344.889909) (xy 138.096756 -344.835526)
			(xy 138.092587 -344.7799) (xy 127.625302 -344.7799) (xy 126.559564 -345.845638) (xy 134.634984 -345.845638)
			(xy 134.639055 -345.790016) (xy 134.651181 -345.735579) (xy 134.671104 -345.683488) (xy 134.6984 -345.634853)
			(xy 134.732486 -345.59071) (xy 134.772635 -345.552001) (xy 134.817993 -345.51955) (xy 134.867593 -345.494049)
			(xy 134.920377 -345.476042) (xy 134.97522 -345.465912) (xy 135.030954 -345.463875) (xy 135.086391 -345.469975)
			(xy 135.140348 -345.484081) (xy 135.191677 -345.505893) (xy 135.239283 -345.534947) (xy 135.282151 -345.570622)
			(xy 135.319368 -345.612159) (xy 135.350141 -345.658672) (xy 135.373813 -345.709169) (xy 135.389881 -345.762576)
			(xy 135.398001 -345.817752) (xy 135.39851 -345.845638) (xy 135.398001 -345.873524) (xy 135.389881 -345.9287)
			(xy 135.373813 -345.982107) (xy 135.350141 -346.032604) (xy 135.319368 -346.079117) (xy 135.282151 -346.120654)
			(xy 135.239283 -346.156329) (xy 135.191677 -346.185383) (xy 135.140348 -346.207195) (xy 135.086391 -346.221301)
			(xy 135.030954 -346.227401) (xy 134.97522 -346.225364) (xy 134.920377 -346.215234) (xy 134.867593 -346.197227)
			(xy 134.817993 -346.171726) (xy 134.772635 -346.139275) (xy 134.732486 -346.100566) (xy 134.6984 -346.056423)
			(xy 134.671104 -346.007788) (xy 134.651181 -345.955697) (xy 134.639055 -345.90126) (xy 134.634984 -345.845638)
			(xy 126.559564 -345.845638) (xy 125.895354 -346.509848) (xy 133.965948 -346.509848) (xy 133.970019 -346.454226)
			(xy 133.982145 -346.399789) (xy 134.002068 -346.347698) (xy 134.029364 -346.299063) (xy 134.06345 -346.25492)
			(xy 134.103599 -346.216211) (xy 134.148957 -346.18376) (xy 134.198557 -346.158259) (xy 134.251341 -346.140252)
			(xy 134.306184 -346.130122) (xy 134.361918 -346.128085) (xy 134.417355 -346.134185) (xy 134.471312 -346.148291)
			(xy 134.522641 -346.170103) (xy 134.570247 -346.199157) (xy 134.613115 -346.234832) (xy 134.650332 -346.276369)
			(xy 134.681105 -346.322882) (xy 134.704777 -346.373379) (xy 134.720845 -346.426786) (xy 134.728965 -346.481962)
			(xy 134.729474 -346.509848) (xy 134.728965 -346.537734) (xy 134.720845 -346.59291) (xy 134.704777 -346.646317)
			(xy 134.681105 -346.696814) (xy 134.650332 -346.743327) (xy 134.613115 -346.784864) (xy 134.570247 -346.820539)
			(xy 134.522641 -346.849593) (xy 134.471312 -346.871405) (xy 134.417355 -346.885511) (xy 134.361918 -346.891611)
			(xy 134.306184 -346.889574) (xy 134.251341 -346.879444) (xy 134.198557 -346.861437) (xy 134.148957 -346.835936)
			(xy 134.103599 -346.803485) (xy 134.06345 -346.764776) (xy 134.029364 -346.720633) (xy 134.002068 -346.671998)
			(xy 133.982145 -346.619907) (xy 133.970019 -346.56547) (xy 133.965948 -346.509848) (xy 125.895354 -346.509848)
			(xy 125.431804 -346.973398) (xy 125.413697 -346.990624) (xy 125.372138 -347.018367) (xy 125.325967 -347.037474)
			(xy 125.276956 -347.047212) (xy 125.251972 -347.04782) (xy 117.75821 -347.04782) (xy 114.469926 -350.336104)
			(xy 114.451856 -350.353389) (xy 114.410302 -350.381193) (xy 114.364123 -350.400359) (xy 114.315093 -350.410149)
			(xy 114.290094 -350.41078) (xy 112.577372 -350.41078) (xy 112.56243 -350.41146) (xy 112.533851 -350.420208)
			(xy 112.509031 -350.436857) (xy 112.490096 -350.459982) (xy 112.483263 -350.476496) (xy 115.595396 -350.476496)
			(xy 115.595396 -350.3918) (xy 115.603447 -350.307486) (xy 115.619476 -350.22432) (xy 115.643337 -350.143053)
			(xy 115.674816 -350.064423) (xy 115.713627 -349.989142) (xy 115.759417 -349.91789) (xy 115.811773 -349.851314)
			(xy 115.870221 -349.790016) (xy 115.934231 -349.734551) (xy 116.003223 -349.685422) (xy 116.076573 -349.643073)
			(xy 116.153616 -349.607889) (xy 116.233655 -349.580187) (xy 116.315964 -349.560219) (xy 116.399799 -349.548166)
			(xy 116.4844 -349.544136) (xy 116.569001 -349.548166) (xy 116.652836 -349.560219) (xy 116.735145 -349.580187)
			(xy 116.815184 -349.607889) (xy 116.892227 -349.643073) (xy 116.965577 -349.685422) (xy 117.034569 -349.734551)
			(xy 117.098579 -349.790016) (xy 117.157027 -349.851314) (xy 117.209383 -349.91789) (xy 117.255173 -349.989142)
			(xy 117.293984 -350.064423) (xy 117.325463 -350.143053) (xy 117.349324 -350.22432) (xy 117.365353 -350.307486)
			(xy 117.373404 -350.3918) (xy 117.373908 -350.434148) (xy 118.119909 -350.434148) (xy 118.123945 -350.350701)
			(xy 118.136017 -350.268033) (xy 118.15601 -350.186916) (xy 118.183739 -350.108107) (xy 118.218945 -350.032342)
			(xy 118.261299 -349.960329) (xy 118.310405 -349.89274) (xy 118.365806 -349.830206) (xy 118.426983 -349.773311)
			(xy 118.493366 -349.722585) (xy 118.564334 -349.678504) (xy 118.639226 -349.641478) (xy 118.717342 -349.611852)
			(xy 118.797952 -349.589904) (xy 118.880304 -349.575839) (xy 118.96363 -349.569787) (xy 119.04715 -349.571806)
			(xy 119.130086 -349.581876) (xy 119.211662 -349.599904) (xy 119.291118 -349.625721) (xy 119.367711 -349.659086)
			(xy 119.440727 -349.699687) (xy 119.509483 -349.747146) (xy 119.573337 -349.801019) (xy 119.631694 -349.860804)
			(xy 119.684009 -349.925941) (xy 119.729792 -349.995824) (xy 119.768617 -350.069799) (xy 119.800122 -350.147176)
			(xy 119.824011 -350.227233) (xy 119.840062 -350.309221) (xy 119.848125 -350.392376) (xy 119.84863 -350.434148)
			(xy 119.848125 -350.47592) (xy 119.840062 -350.559075) (xy 119.824011 -350.641063) (xy 119.800122 -350.72112)
			(xy 119.768617 -350.798497) (xy 119.729792 -350.872472) (xy 119.684009 -350.942355) (xy 119.631694 -351.007492)
			(xy 119.573337 -351.067277) (xy 119.509483 -351.12115) (xy 119.440727 -351.168609) (xy 119.367711 -351.20921)
			(xy 119.291118 -351.242575) (xy 119.211662 -351.268392) (xy 119.130086 -351.28642) (xy 119.04715 -351.29649)
			(xy 118.96363 -351.298509) (xy 118.880304 -351.292457) (xy 118.797952 -351.278392) (xy 118.717342 -351.256444)
			(xy 118.639226 -351.226818) (xy 118.564334 -351.189792) (xy 118.493366 -351.145711) (xy 118.426983 -351.094985)
			(xy 118.365806 -351.03809) (xy 118.310405 -350.975556) (xy 118.261299 -350.907967) (xy 118.218945 -350.835954)
			(xy 118.183739 -350.760189) (xy 118.15601 -350.68138) (xy 118.136017 -350.600263) (xy 118.123945 -350.517595)
			(xy 118.119909 -350.434148) (xy 117.373908 -350.434148) (xy 117.373404 -350.476496) (xy 117.365353 -350.56081)
			(xy 117.349324 -350.643976) (xy 117.325463 -350.725243) (xy 117.293984 -350.803873) (xy 117.255173 -350.879154)
			(xy 117.209383 -350.950406) (xy 117.157027 -351.016982) (xy 117.098579 -351.07828) (xy 117.034569 -351.133745)
			(xy 116.965577 -351.182874) (xy 116.892227 -351.225223) (xy 116.815184 -351.260407) (xy 116.735145 -351.288109)
			(xy 116.652836 -351.308077) (xy 116.569001 -351.32013) (xy 116.4844 -351.324161) (xy 116.399799 -351.32013)
			(xy 116.315964 -351.308077) (xy 116.233655 -351.288109) (xy 116.153616 -351.260407) (xy 116.076573 -351.225223)
			(xy 116.003223 -351.182874) (xy 115.934231 -351.133745) (xy 115.870221 -351.07828) (xy 115.811773 -351.016982)
			(xy 115.759417 -350.950406) (xy 115.713627 -350.879154) (xy 115.674816 -350.803873) (xy 115.643337 -350.725243)
			(xy 115.619476 -350.643976) (xy 115.603447 -350.56081) (xy 115.595396 -350.476496) (xy 112.483263 -350.476496)
			(xy 112.478669 -350.487599) (xy 112.475731 -350.517342) (xy 112.481532 -350.546662) (xy 112.495576 -350.573044)
			(xy 112.505744 -350.584008) (xy 112.72774 -350.806258) (xy 113.806478 -351.884488) (xy 121.234962 -351.884488)
			(xy 125.551184 -347.56852) (xy 125.569296 -347.551282) (xy 125.610835 -347.523467) (xy 125.657001 -347.504289)
			(xy 125.706021 -347.494484) (xy 125.731016 -347.493844) (xy 132.940298 -347.493844) (xy 132.965294 -347.494475)
			(xy 133.014318 -347.50428) (xy 133.060488 -347.523455) (xy 133.102034 -347.551264) (xy 133.12013 -347.56852)
			(xy 133.870954 -348.319344) (xy 135.552688 -348.319344) (xy 135.82396 -348.047818) (xy 135.82396 -347.823536)
			(xy 135.779256 -347.818202) (xy 135.751729 -347.814475) (xy 135.698065 -347.800144) (xy 135.647045 -347.778182)
			(xy 135.59975 -347.749054) (xy 135.557179 -347.713375) (xy 135.520231 -347.6719) (xy 135.489689 -347.625505)
			(xy 135.466197 -347.575172) (xy 135.450253 -347.521964) (xy 135.442193 -347.467007) (xy 135.44169 -347.439234)
			(xy 135.442274 -347.409547) (xy 135.451467 -347.35089) (xy 135.469637 -347.294364) (xy 135.496345 -347.241337)
			(xy 135.530946 -347.193087) (xy 135.572604 -347.150781) (xy 135.596122 -347.132656) (xy 135.606706 -347.124204)
			(xy 135.623411 -347.102896) (xy 135.633929 -347.077948) (xy 135.637521 -347.051113) (xy 135.633936 -347.024277)
			(xy 135.623424 -346.999326) (xy 135.606725 -346.978015) (xy 135.596122 -346.969588) (xy 135.572611 -346.951453)
			(xy 135.530949 -346.90915) (xy 135.496344 -346.860903) (xy 135.469631 -346.807878) (xy 135.451455 -346.751354)
			(xy 135.442256 -346.692697) (xy 135.44169 -346.66301) (xy 135.442157 -346.635745) (xy 135.449919 -346.581771)
			(xy 135.465287 -346.529452) (xy 135.487948 -346.479854) (xy 135.517439 -346.433988) (xy 135.55316 -346.392787)
			(xy 135.594383 -346.357093) (xy 135.640268 -346.327631) (xy 135.689881 -346.305002) (xy 135.74221 -346.289668)
			(xy 135.796189 -346.28194) (xy 135.850718 -346.281976) (xy 135.904687 -346.289776) (xy 135.956996 -346.30518)
			(xy 136.006578 -346.327875) (xy 136.052424 -346.357398) (xy 136.0936 -346.393147) (xy 136.129266 -346.434395)
			(xy 136.158696 -346.480301) (xy 136.18129 -346.529929) (xy 136.196588 -346.582268) (xy 136.204279 -346.636253)
			(xy 136.204706 -346.663518) (xy 136.204706 -346.684854) (xy 136.304274 -346.784422) (xy 136.315264 -346.794674)
			(xy 136.341794 -346.808773) (xy 136.371276 -346.814555) (xy 136.401166 -346.811519) (xy 136.428883 -346.799929)
			(xy 136.452037 -346.780784) (xy 136.468627 -346.755737) (xy 136.473438 -346.741496) (xy 136.481704 -346.715609)
			(xy 136.504466 -346.666265) (xy 136.533997 -346.62065) (xy 136.5697 -346.579684) (xy 136.610852 -346.544196)
			(xy 136.656622 -346.514905) (xy 136.706083 -346.492402) (xy 136.758237 -346.477142) (xy 136.812028 -346.469434)
			(xy 136.839198 -346.468954) (xy 136.839452 -346.468954) (xy 136.864655 -346.469373) (xy 136.914622 -346.476006)
			(xy 136.963277 -346.489177) (xy 137.009767 -346.508655) (xy 137.03173 -346.521024) (xy 137.044684 -346.528087)
			(xy 137.073326 -346.535122) (xy 137.102783 -346.533675) (xy 137.130598 -346.523868) (xy 137.154449 -346.506519)
			(xy 137.172345 -346.483076) (xy 137.178034 -346.469462) (xy 137.188748 -346.442694) (xy 137.217036 -346.392454)
			(xy 137.252564 -346.347046) (xy 137.294524 -346.307505) (xy 137.341958 -346.27473) (xy 137.393785 -346.249471)
			(xy 137.448825 -346.232302) (xy 137.505822 -346.223614) (xy 137.53465 -346.223082) (xy 137.561901 -346.223602)
			(xy 137.61585 -346.231352) (xy 137.668146 -346.246701) (xy 137.717725 -346.269337) (xy 137.763578 -346.298799)
			(xy 137.804771 -346.334487) (xy 137.840465 -346.375674) (xy 137.869934 -346.421522) (xy 137.892578 -346.471098)
			(xy 137.907936 -346.523392) (xy 137.915694 -346.577339) (xy 137.916158 -346.60459) (xy 137.916158 -346.604844)
			(xy 137.915584 -346.634683) (xy 137.906268 -346.693629) (xy 137.897616 -346.722192) (xy 137.893528 -346.736087)
			(xy 137.892626 -346.765028) (xy 137.8999 -346.793054) (xy 137.914763 -346.817903) (xy 137.936014 -346.837569)
			(xy 137.961939 -346.850464) (xy 137.976102 -346.85351) (xy 138.002169 -346.858706) (xy 138.052672 -346.875273)
			(xy 138.100385 -346.898693) (xy 138.144384 -346.928511) (xy 138.183815 -346.964151) (xy 138.217914 -347.004921)
			(xy 138.246022 -347.050032) (xy 138.267593 -347.098609) (xy 138.282209 -347.14971) (xy 138.289587 -347.202347)
			(xy 138.290046 -347.228922) (xy 138.28956 -347.256173) (xy 138.281804 -347.310121) (xy 138.266449 -347.362416)
			(xy 138.243807 -347.411993) (xy 138.214341 -347.457843) (xy 138.17865 -347.499034) (xy 138.137459 -347.534725)
			(xy 138.091609 -347.564191) (xy 138.042032 -347.586833) (xy 137.989737 -347.602188) (xy 137.935789 -347.609944)
			(xy 137.881287 -347.609944) (xy 137.827339 -347.602188) (xy 137.775044 -347.586833) (xy 137.725467 -347.564191)
			(xy 137.679617 -347.534725) (xy 137.638426 -347.499034) (xy 137.602735 -347.457843) (xy 137.573269 -347.411993)
			(xy 137.550627 -347.362416) (xy 137.535272 -347.310121) (xy 137.527516 -347.256173) (xy 137.52703 -347.228922)
			(xy 137.52703 -347.228668) (xy 137.527607 -347.198829) (xy 137.536922 -347.139883) (xy 137.545572 -347.11132)
			(xy 137.549656 -347.097423) (xy 137.550561 -347.068483) (xy 137.543289 -347.040456) (xy 137.528427 -347.015606)
			(xy 137.507175 -346.995941) (xy 137.481249 -346.983047) (xy 137.467086 -346.980002) (xy 137.434246 -346.973424)
			(xy 137.371394 -346.950298) (xy 137.342118 -346.934028) (xy 137.329125 -346.927047) (xy 137.3005 -346.920009)
			(xy 137.271058 -346.921446) (xy 137.243253 -346.931237) (xy 137.219407 -346.948565) (xy 137.201508 -346.971986)
			(xy 137.195814 -346.98559) (xy 137.185117 -347.012366) (xy 137.156831 -347.062609) (xy 137.121302 -347.10802)
			(xy 137.07934 -347.147563) (xy 137.031903 -347.180337) (xy 136.980071 -347.205595) (xy 136.925028 -347.22276)
			(xy 136.868027 -347.231441) (xy 136.839198 -347.23197) (xy 136.82376 -347.23178) (xy 136.792989 -347.22924)
			(xy 136.77773 -347.22689) (xy 136.768503 -347.225838) (xy 136.750347 -347.229677) (xy 136.734732 -347.239704)
			(xy 136.723686 -347.254616) (xy 136.718646 -347.272476) (xy 136.719056 -347.281754) (xy 136.720072 -347.30563)
			(xy 136.720072 -348.313756) (xy 136.71947 -348.33874) (xy 136.709723 -348.387748) (xy 136.690612 -348.433917)
			(xy 136.662872 -348.475478) (xy 136.64565 -348.493588) (xy 135.998458 -349.14078) (xy 135.980371 -349.158046)
			(xy 135.938823 -349.185855) (xy 135.89265 -349.205026) (xy 135.843623 -349.214821) (xy 135.818626 -349.215456)
			(xy 133.605016 -349.215456) (xy 133.58002 -349.214816) (xy 133.530997 -349.205014) (xy 133.484827 -349.185842)
			(xy 133.44328 -349.158035) (xy 133.425184 -349.14078) (xy 132.67436 -348.389956) (xy 125.996954 -348.389956)
			(xy 121.680732 -352.706178) (xy 121.662626 -352.723404) (xy 121.621064 -352.751143) (xy 121.574894 -352.770249)
			(xy 121.525884 -352.779989) (xy 121.5009 -352.7806) (xy 114.118644 -352.7806) (xy 114.118644 -353.32797)
			(xy 114.132834 -353.351028) (xy 114.155227 -353.40032) (xy 114.170418 -353.452285) (xy 114.178102 -353.505878)
			(xy 114.178588 -353.532948) (xy 114.178097 -353.560016) (xy 114.170389 -353.613601) (xy 114.155191 -353.665561)
			(xy 114.132807 -353.714854) (xy 114.118644 -353.737926) (xy 114.118644 -354.551742) (xy 114.137475 -354.57613)
			(xy 114.167856 -354.629733) (xy 114.179096 -354.658422) (xy 114.182906 -354.668836) (xy 114.201956 -354.687886)
			(xy 116.286026 -354.687886) (xy 116.286472 -354.661506) (xy 116.293727 -354.609248) (xy 116.30811 -354.558488)
			(xy 116.329348 -354.510192) (xy 116.357036 -354.465282) (xy 116.390646 -354.424613) (xy 116.429536 -354.388961)
			(xy 116.472967 -354.359006) (xy 116.496338 -354.346764) (xy 116.508712 -354.340085) (xy 116.529447 -354.321108)
			(xy 116.544213 -354.29719) (xy 116.551887 -354.270148) (xy 116.551885 -354.242039) (xy 116.544208 -354.214999)
			(xy 116.529439 -354.191082) (xy 116.508701 -354.172108) (xy 116.496338 -354.165408) (xy 116.472948 -354.153203)
			(xy 116.429525 -354.123234) (xy 116.390642 -354.087572) (xy 116.357039 -354.046897) (xy 116.329355 -354.001983)
			(xy 116.308118 -353.953686) (xy 116.293731 -353.902924) (xy 116.28647 -353.850666) (xy 116.286026 -353.824286)
			(xy 116.286512 -353.797035) (xy 116.294268 -353.743087) (xy 116.309623 -353.690792) (xy 116.332265 -353.641215)
			(xy 116.361731 -353.595365) (xy 116.397422 -353.554174) (xy 116.438613 -353.518483) (xy 116.484463 -353.489017)
			(xy 116.53404 -353.466375) (xy 116.586335 -353.45102) (xy 116.640283 -353.443264) (xy 116.694785 -353.443264)
			(xy 116.748733 -353.45102) (xy 116.801028 -353.466375) (xy 116.850605 -353.489017) (xy 116.896455 -353.518483)
			(xy 116.937646 -353.554174) (xy 116.973337 -353.595365) (xy 117.002803 -353.641215) (xy 117.011358 -353.659948)
			(xy 165.655242 -353.659948) (xy 165.659313 -353.604326) (xy 165.671439 -353.549889) (xy 165.691362 -353.497798)
			(xy 165.718658 -353.449163) (xy 165.752744 -353.40502) (xy 165.792893 -353.366311) (xy 165.838251 -353.33386)
			(xy 165.887851 -353.308359) (xy 165.940635 -353.290352) (xy 165.995478 -353.280222) (xy 166.051212 -353.278185)
			(xy 166.106649 -353.284285) (xy 166.160606 -353.298391) (xy 166.211935 -353.320203) (xy 166.259541 -353.349257)
			(xy 166.302409 -353.384932) (xy 166.339626 -353.426469) (xy 166.370399 -353.472982) (xy 166.394071 -353.523479)
			(xy 166.410139 -353.576886) (xy 166.418259 -353.632062) (xy 166.418768 -353.659948) (xy 166.418259 -353.687834)
			(xy 166.410139 -353.74301) (xy 166.394071 -353.796417) (xy 166.370399 -353.846914) (xy 166.339626 -353.893427)
			(xy 166.302409 -353.934964) (xy 166.259541 -353.970639) (xy 166.211935 -353.999693) (xy 166.160606 -354.021505)
			(xy 166.106649 -354.035611) (xy 166.051212 -354.041711) (xy 165.995478 -354.039674) (xy 165.940635 -354.029544)
			(xy 165.887851 -354.011537) (xy 165.838251 -353.986036) (xy 165.792893 -353.953585) (xy 165.752744 -353.914876)
			(xy 165.718658 -353.870733) (xy 165.691362 -353.822098) (xy 165.671439 -353.770007) (xy 165.659313 -353.71557)
			(xy 165.655242 -353.659948) (xy 117.011358 -353.659948) (xy 117.025445 -353.690792) (xy 117.0408 -353.743087)
			(xy 117.048556 -353.797035) (xy 117.049042 -353.824286) (xy 117.048618 -353.850666) (xy 117.041355 -353.902923)
			(xy 117.026965 -353.953683) (xy 117.005723 -354.001977) (xy 116.978032 -354.046886) (xy 116.944421 -354.087554)
			(xy 116.90553 -354.123207) (xy 116.862101 -354.153164) (xy 116.83873 -354.165408) (xy 116.826384 -354.172131)
			(xy 116.805657 -354.191103) (xy 116.790897 -354.215013) (xy 116.783225 -354.242044) (xy 116.783223 -354.270143)
			(xy 116.790892 -354.297175) (xy 116.805649 -354.321087) (xy 116.826374 -354.340062) (xy 116.83873 -354.346764)
			(xy 116.862101 -354.359004) (xy 116.905524 -354.388967) (xy 116.944409 -354.424623) (xy 116.978014 -354.465293)
			(xy 117.005701 -354.510202) (xy 117.026941 -354.558495) (xy 117.041331 -354.609252) (xy 117.048414 -354.6602)
			(xy 165.673276 -354.6602) (xy 165.677347 -354.604578) (xy 165.689473 -354.550141) (xy 165.709396 -354.49805)
			(xy 165.736692 -354.449415) (xy 165.770778 -354.405272) (xy 165.810927 -354.366563) (xy 165.856285 -354.334112)
			(xy 165.905885 -354.308611) (xy 165.958669 -354.290604) (xy 166.013512 -354.280474) (xy 166.069246 -354.278437)
			(xy 166.124683 -354.284537) (xy 166.17864 -354.298643) (xy 166.229969 -354.320455) (xy 166.277575 -354.349509)
			(xy 166.320443 -354.385184) (xy 166.35766 -354.426721) (xy 166.388433 -354.473234) (xy 166.412105 -354.523731)
			(xy 166.428173 -354.577138) (xy 166.436293 -354.632314) (xy 166.436802 -354.6602) (xy 166.436293 -354.688086)
			(xy 166.428173 -354.743262) (xy 166.412105 -354.796669) (xy 166.388433 -354.847166) (xy 166.35766 -354.893679)
			(xy 166.320443 -354.935216) (xy 166.277575 -354.970891) (xy 166.229969 -354.999945) (xy 166.180704 -355.02088)
			(xy 168.06799 -355.02088) (xy 168.06799 -355.020626) (xy 168.068485 -354.992611) (xy 168.076711 -354.937187)
			(xy 168.092947 -354.883559) (xy 168.116844 -354.83288) (xy 168.14789 -354.786235) (xy 168.166288 -354.765102)
			(xy 168.175903 -354.753637) (xy 168.188686 -354.726603) (xy 168.193077 -354.697022) (xy 168.188699 -354.66744)
			(xy 168.175928 -354.6404) (xy 168.166288 -354.628958) (xy 168.147888 -354.607823) (xy 168.116815 -354.561194)
			(xy 168.092907 -354.510516) (xy 168.076679 -354.456883) (xy 168.068481 -354.401451) (xy 168.06799 -354.373434)
			(xy 168.06799 -354.37318) (xy 168.068476 -354.345929) (xy 168.076232 -354.291981) (xy 168.091587 -354.239686)
			(xy 168.114229 -354.190109) (xy 168.143695 -354.144259) (xy 168.179386 -354.103068) (xy 168.220577 -354.067377)
			(xy 168.266427 -354.037911) (xy 168.316004 -354.015269) (xy 168.368299 -353.999914) (xy 168.422247 -353.992158)
			(xy 168.476749 -353.992158) (xy 168.530697 -353.999914) (xy 168.582992 -354.015269) (xy 168.632569 -354.037911)
			(xy 168.678419 -354.067377) (xy 168.71961 -354.103068) (xy 168.755301 -354.144259) (xy 168.784767 -354.190109)
			(xy 168.807409 -354.239686) (xy 168.822764 -354.291981) (xy 168.83052 -354.345929) (xy 168.831006 -354.37318)
			(xy 168.831006 -354.373434) (xy 168.830488 -354.401448) (xy 168.822268 -354.456872) (xy 168.806037 -354.510499)
			(xy 168.782145 -354.561179) (xy 168.751104 -354.607824) (xy 168.732708 -354.628958) (xy 168.728189 -354.634292)
			(xy 176.045366 -354.634292) (xy 176.049437 -354.57867) (xy 176.061563 -354.524233) (xy 176.081486 -354.472142)
			(xy 176.108782 -354.423507) (xy 176.142868 -354.379364) (xy 176.183017 -354.340655) (xy 176.228375 -354.308204)
			(xy 176.277975 -354.282703) (xy 176.330759 -354.264696) (xy 176.385602 -354.254566) (xy 176.441336 -354.252529)
			(xy 176.496773 -354.258629) (xy 176.55073 -354.272735) (xy 176.602059 -354.294547) (xy 176.649665 -354.323601)
			(xy 176.692533 -354.359276) (xy 176.72975 -354.400813) (xy 176.760523 -354.447326) (xy 176.784195 -354.497823)
			(xy 176.800263 -354.55123) (xy 176.808383 -354.606406) (xy 176.808892 -354.634292) (xy 176.808383 -354.662178)
			(xy 176.800263 -354.717354) (xy 176.784195 -354.770761) (xy 176.760523 -354.821258) (xy 176.72975 -354.867771)
			(xy 176.692533 -354.909308) (xy 176.649665 -354.944983) (xy 176.602059 -354.974037) (xy 176.55073 -354.995849)
			(xy 176.496773 -355.009955) (xy 176.455195 -355.01453) (xy 177.756312 -355.01453) (xy 177.756793 -354.98716)
			(xy 177.764607 -354.932982) (xy 177.780092 -354.880479) (xy 177.802931 -354.830732) (xy 177.832652 -354.784764)
			(xy 177.850292 -354.763832) (xy 177.859501 -354.752483) (xy 177.871683 -354.725934) (xy 177.875861 -354.697023)
			(xy 177.871695 -354.66811) (xy 177.859525 -354.641555) (xy 177.850292 -354.630228) (xy 177.832651 -354.609297)
			(xy 177.80294 -354.563324) (xy 177.780104 -354.513576) (xy 177.764614 -354.461075) (xy 177.756786 -354.406899)
			(xy 177.756312 -354.37953) (xy 177.756798 -354.352279) (xy 177.764554 -354.298331) (xy 177.779909 -354.246036)
			(xy 177.802551 -354.196459) (xy 177.832017 -354.150609) (xy 177.867708 -354.109418) (xy 177.908899 -354.073727)
			(xy 177.954749 -354.044261) (xy 178.004326 -354.021619) (xy 178.056621 -354.006264) (xy 178.110569 -353.998508)
			(xy 178.165071 -353.998508) (xy 178.219019 -354.006264) (xy 178.271314 -354.021619) (xy 178.320891 -354.044261)
			(xy 178.366741 -354.073727) (xy 178.407932 -354.109418) (xy 178.443623 -354.150609) (xy 178.473089 -354.196459)
			(xy 178.495731 -354.246036) (xy 178.511086 -354.298331) (xy 178.518842 -354.352279) (xy 178.519328 -354.37953)
			(xy 178.518897 -354.406902) (xy 178.511073 -354.461083) (xy 178.495577 -354.513587) (xy 178.472727 -354.563334)
			(xy 178.442994 -354.609298) (xy 178.425348 -354.630228) (xy 178.419106 -354.637848) (xy 185.603386 -354.637848)
			(xy 185.607457 -354.582226) (xy 185.619583 -354.527789) (xy 185.639506 -354.475698) (xy 185.666802 -354.427063)
			(xy 185.700888 -354.38292) (xy 185.741037 -354.344211) (xy 185.786395 -354.31176) (xy 185.835995 -354.286259)
			(xy 185.888779 -354.268252) (xy 185.943622 -354.258122) (xy 185.999356 -354.256085) (xy 186.054793 -354.262185)
			(xy 186.10875 -354.276291) (xy 186.160079 -354.298103) (xy 186.207685 -354.327157) (xy 186.250553 -354.362832)
			(xy 186.28777 -354.404369) (xy 186.318543 -354.450882) (xy 186.342215 -354.501379) (xy 186.358283 -354.554786)
			(xy 186.366403 -354.609962) (xy 186.366912 -354.637848) (xy 186.366403 -354.665734) (xy 186.358283 -354.72091)
			(xy 186.342215 -354.774317) (xy 186.318543 -354.824814) (xy 186.28777 -354.871327) (xy 186.250553 -354.912864)
			(xy 186.207685 -354.948539) (xy 186.160079 -354.977593) (xy 186.10875 -354.999405) (xy 186.054793 -355.013511)
			(xy 185.999356 -355.019611) (xy 185.943622 -355.017574) (xy 185.888779 -355.007444) (xy 185.835995 -354.989437)
			(xy 185.786395 -354.963936) (xy 185.741037 -354.931485) (xy 185.700888 -354.892776) (xy 185.666802 -354.848633)
			(xy 185.639506 -354.799998) (xy 185.619583 -354.747907) (xy 185.607457 -354.69347) (xy 185.603386 -354.637848)
			(xy 178.419106 -354.637848) (xy 178.416086 -354.641535) (xy 178.403918 -354.668101) (xy 178.399754 -354.697023)
			(xy 178.403931 -354.725942) (xy 178.416111 -354.752503) (xy 178.425348 -354.763832) (xy 178.442961 -354.784786)
			(xy 178.472678 -354.830752) (xy 178.49552 -354.880494) (xy 178.511017 -354.93299) (xy 178.518851 -354.987162)
			(xy 178.519328 -355.01453) (xy 178.518842 -355.041781) (xy 178.511086 -355.095729) (xy 178.495731 -355.148024)
			(xy 178.473089 -355.197601) (xy 178.443623 -355.243451) (xy 178.407932 -355.284642) (xy 178.366741 -355.320333)
			(xy 178.320891 -355.349799) (xy 178.271314 -355.372441) (xy 178.219019 -355.387796) (xy 178.165071 -355.395552)
			(xy 178.110569 -355.395552) (xy 178.056621 -355.387796) (xy 178.004326 -355.372441) (xy 177.954749 -355.349799)
			(xy 177.908899 -355.320333) (xy 177.867708 -355.284642) (xy 177.832017 -355.243451) (xy 177.802551 -355.197601)
			(xy 177.779909 -355.148024) (xy 177.764554 -355.095729) (xy 177.756798 -355.041781) (xy 177.756312 -355.01453)
			(xy 176.455195 -355.01453) (xy 176.441336 -355.016055) (xy 176.385602 -355.014018) (xy 176.330759 -355.003888)
			(xy 176.277975 -354.985881) (xy 176.228375 -354.96038) (xy 176.183017 -354.927929) (xy 176.142868 -354.88922)
			(xy 176.108782 -354.845077) (xy 176.081486 -354.796442) (xy 176.061563 -354.744351) (xy 176.049437 -354.689914)
			(xy 176.045366 -354.634292) (xy 168.728189 -354.634292) (xy 168.723034 -354.640377) (xy 168.710259 -354.667429)
			(xy 168.705879 -354.697022) (xy 168.710272 -354.726614) (xy 168.723059 -354.75366) (xy 168.732708 -354.765102)
			(xy 168.751136 -354.786214) (xy 168.782205 -354.832849) (xy 168.806108 -354.883533) (xy 168.822329 -354.937171)
			(xy 168.830519 -354.992607) (xy 168.831006 -355.020626) (xy 168.831006 -355.02088) (xy 168.83052 -355.048131)
			(xy 168.822764 -355.102079) (xy 168.807409 -355.154374) (xy 168.784767 -355.203951) (xy 168.755301 -355.249801)
			(xy 168.71961 -355.290992) (xy 168.678419 -355.326683) (xy 168.632569 -355.356149) (xy 168.582992 -355.378791)
			(xy 168.530697 -355.394146) (xy 168.476749 -355.401902) (xy 168.422247 -355.401902) (xy 168.368299 -355.394146)
			(xy 168.316004 -355.378791) (xy 168.266427 -355.356149) (xy 168.220577 -355.326683) (xy 168.179386 -355.290992)
			(xy 168.143695 -355.249801) (xy 168.114229 -355.203951) (xy 168.091587 -355.154374) (xy 168.076232 -355.102079)
			(xy 168.068476 -355.048131) (xy 168.06799 -355.02088) (xy 166.180704 -355.02088) (xy 166.17864 -355.021757)
			(xy 166.124683 -355.035863) (xy 166.069246 -355.041963) (xy 166.013512 -355.039926) (xy 165.958669 -355.029796)
			(xy 165.905885 -355.011789) (xy 165.856285 -354.986288) (xy 165.810927 -354.953837) (xy 165.770778 -354.915128)
			(xy 165.736692 -354.870985) (xy 165.709396 -354.82235) (xy 165.689473 -354.770259) (xy 165.677347 -354.715822)
			(xy 165.673276 -354.6602) (xy 117.048414 -354.6602) (xy 117.048596 -354.661507) (xy 117.049042 -354.687886)
			(xy 117.048556 -354.715137) (xy 117.0408 -354.769085) (xy 117.025445 -354.82138) (xy 117.002803 -354.870957)
			(xy 116.973337 -354.916807) (xy 116.937646 -354.957998) (xy 116.896455 -354.993689) (xy 116.850605 -355.023155)
			(xy 116.801028 -355.045797) (xy 116.748733 -355.061152) (xy 116.694785 -355.068908) (xy 116.640283 -355.068908)
			(xy 116.586335 -355.061152) (xy 116.53404 -355.045797) (xy 116.484463 -355.023155) (xy 116.438613 -354.993689)
			(xy 116.397422 -354.957998) (xy 116.361731 -354.916807) (xy 116.332265 -354.870957) (xy 116.309623 -354.82138)
			(xy 116.294268 -354.769085) (xy 116.286512 -354.715137) (xy 116.286026 -354.687886) (xy 114.201956 -354.687886)
			(xy 114.69624 -355.18217) (xy 117.96852 -355.18217) (xy 117.972591 -355.126548) (xy 117.984717 -355.072111)
			(xy 118.00464 -355.02002) (xy 118.031936 -354.971385) (xy 118.066022 -354.927242) (xy 118.106171 -354.888533)
			(xy 118.151529 -354.856082) (xy 118.201129 -354.830581) (xy 118.253913 -354.812574) (xy 118.308756 -354.802444)
			(xy 118.36449 -354.800407) (xy 118.419927 -354.806507) (xy 118.473884 -354.820613) (xy 118.525213 -354.842425)
			(xy 118.572819 -354.871479) (xy 118.615687 -354.907154) (xy 118.652904 -354.948691) (xy 118.683677 -354.995204)
			(xy 118.707349 -355.045701) (xy 118.723417 -355.099108) (xy 118.731537 -355.154284) (xy 118.732046 -355.18217)
			(xy 118.731537 -355.210056) (xy 118.723417 -355.265232) (xy 118.707349 -355.318639) (xy 118.683677 -355.369136)
			(xy 118.652904 -355.415649) (xy 118.615687 -355.457186) (xy 118.572819 -355.492861) (xy 118.525213 -355.521915)
			(xy 118.473884 -355.543727) (xy 118.419927 -355.557833) (xy 118.36449 -355.563933) (xy 118.308756 -355.561896)
			(xy 118.253913 -355.551766) (xy 118.201129 -355.533759) (xy 118.151529 -355.508258) (xy 118.106171 -355.475807)
			(xy 118.066022 -355.437098) (xy 118.031936 -355.392955) (xy 118.00464 -355.34432) (xy 117.984717 -355.292229)
			(xy 117.972591 -355.237792) (xy 117.96852 -355.18217) (xy 114.69624 -355.18217) (xy 114.93881 -355.42474)
			(xy 115.151154 -355.42474) (xy 115.176149 -355.425399) (xy 115.225171 -355.435195) (xy 115.271342 -355.454362)
			(xy 115.312889 -355.482164) (xy 115.330986 -355.499416) (xy 115.773962 -355.942392) (xy 116.343682 -355.942392)
			(xy 116.347753 -355.88677) (xy 116.359879 -355.832333) (xy 116.379802 -355.780242) (xy 116.407098 -355.731607)
			(xy 116.441184 -355.687464) (xy 116.481333 -355.648755) (xy 116.526691 -355.616304) (xy 116.576291 -355.590803)
			(xy 116.629075 -355.572796) (xy 116.683918 -355.562666) (xy 116.739652 -355.560629) (xy 116.795089 -355.566729)
			(xy 116.849046 -355.580835) (xy 116.900375 -355.602647) (xy 116.947981 -355.631701) (xy 116.990849 -355.667376)
			(xy 117.0181 -355.69779) (xy 120.263664 -355.69779) (xy 120.267735 -355.642168) (xy 120.279861 -355.587731)
			(xy 120.299784 -355.53564) (xy 120.32708 -355.487005) (xy 120.361166 -355.442862) (xy 120.401315 -355.404153)
			(xy 120.446673 -355.371702) (xy 120.496273 -355.346201) (xy 120.549057 -355.328194) (xy 120.6039 -355.318064)
			(xy 120.659634 -355.316027) (xy 120.715071 -355.322127) (xy 120.769028 -355.336233) (xy 120.820357 -355.358045)
			(xy 120.867963 -355.387099) (xy 120.904013 -355.4171) (xy 172.316679 -355.4171) (xy 172.320847 -355.361492)
			(xy 172.333255 -355.307126) (xy 172.353627 -355.255216) (xy 172.381508 -355.206922) (xy 172.416275 -355.163323)
			(xy 172.457152 -355.125392) (xy 172.503225 -355.093977) (xy 172.553465 -355.069779) (xy 172.606751 -355.053339)
			(xy 172.661892 -355.045025) (xy 172.689774 -355.044502) (xy 172.717106 -355.044977) (xy 172.771185 -355.052948)
			(xy 172.823518 -355.068736) (xy 172.872982 -355.092004) (xy 172.918514 -355.122251) (xy 172.959137 -355.158828)
			(xy 172.993977 -355.200949) (xy 173.008544 -355.22408) (xy 173.016453 -355.236315) (xy 173.037926 -355.255989)
			(xy 173.064084 -355.268794) (xy 173.092794 -355.273686) (xy 173.121716 -355.270266) (xy 173.13529 -355.264974)
			(xy 173.158503 -355.255494) (xy 173.206835 -355.24214) (xy 173.256523 -355.235408) (xy 173.281594 -355.235002)
			(xy 173.306663 -355.235442) (xy 173.356345 -355.242185) (xy 173.40468 -355.255511) (xy 173.427898 -355.264974)
			(xy 173.441482 -355.270214) (xy 173.470388 -355.273597) (xy 173.499075 -355.268699) (xy 173.52522 -355.255916)
			(xy 173.546704 -355.236283) (xy 173.554644 -355.22408) (xy 173.569213 -355.200949) (xy 173.604056 -355.158828)
			(xy 173.644679 -355.122249) (xy 173.69021 -355.091998) (xy 173.739672 -355.068722) (xy 173.792003 -355.052922)
			(xy 173.846082 -355.044936) (xy 173.900746 -355.044936) (xy 173.954825 -355.052922) (xy 174.007156 -355.068722)
			(xy 174.056618 -355.091998) (xy 174.102149 -355.122249) (xy 174.142772 -355.158828) (xy 174.177615 -355.200949)
			(xy 174.192184 -355.22408) (xy 174.20015 -355.236274) (xy 174.221608 -355.255948) (xy 174.24775 -355.268758)
			(xy 174.276446 -355.273661) (xy 174.305358 -355.270257) (xy 174.31893 -355.264974) (xy 174.342139 -355.255482)
			(xy 174.390472 -355.242132) (xy 174.440162 -355.235405) (xy 174.465234 -355.235002) (xy 174.492078 -355.23542)
			(xy 174.545211 -355.24313) (xy 174.596686 -355.258385) (xy 174.64544 -355.280868) (xy 174.690463 -355.310116)
			(xy 174.730823 -355.345522) (xy 174.765683 -355.386354) (xy 174.794323 -355.431765) (xy 174.81615 -355.480817)
			(xy 174.823882 -355.506528) (xy 174.828594 -355.521008) (xy 174.845101 -355.546571) (xy 174.868405 -355.566137)
			(xy 174.896439 -355.577971) (xy 174.926716 -355.58102) (xy 174.956547 -355.575016) (xy 174.970186 -355.56825)
			(xy 174.998325 -355.553603) (xy 175.05828 -355.532881) (xy 175.120841 -355.522389) (xy 175.152558 -355.521768)
			(xy 175.170577 -355.521985) (xy 175.206452 -355.525422) (xy 175.224186 -355.528626) (xy 175.239394 -355.530974)
			(xy 175.269951 -355.527449) (xy 175.298072 -355.514987) (xy 175.321208 -355.494718) (xy 175.337261 -355.46848)
			(xy 175.341534 -355.453696) (xy 175.348943 -355.426655) (xy 175.370568 -355.374927) (xy 175.399529 -355.32692)
			(xy 175.435203 -355.283666) (xy 175.476821 -355.246098) (xy 175.523487 -355.215023) (xy 175.574199 -355.191111)
			(xy 175.627863 -355.174875) (xy 175.683325 -355.166666) (xy 175.711358 -355.166168) (xy 175.738609 -355.166694)
			(xy 175.792556 -355.174445) (xy 175.844851 -355.189794) (xy 175.89443 -355.21243) (xy 175.940282 -355.241892)
			(xy 175.981474 -355.277579) (xy 176.017169 -355.318765) (xy 176.046638 -355.364612) (xy 176.069282 -355.414187)
			(xy 176.070138 -355.4171) (xy 182.004979 -355.4171) (xy 182.009147 -355.36149) (xy 182.021556 -355.307122)
			(xy 182.04193 -355.25521) (xy 182.069813 -355.206915) (xy 182.104582 -355.163315) (xy 182.145461 -355.125384)
			(xy 182.191537 -355.09397) (xy 182.241781 -355.069773) (xy 182.29507 -355.053335) (xy 182.350213 -355.045023)
			(xy 182.378096 -355.044502) (xy 182.405428 -355.044959) (xy 182.459508 -355.052933) (xy 182.511842 -355.068725)
			(xy 182.561306 -355.091995) (xy 182.606838 -355.122245) (xy 182.64746 -355.158824) (xy 182.6823 -355.200947)
			(xy 182.696866 -355.22408) (xy 182.704754 -355.23633) (xy 182.726233 -355.256004) (xy 182.752397 -355.268807)
			(xy 182.781111 -355.273695) (xy 182.810037 -355.27027) (xy 182.823612 -355.264974) (xy 182.846823 -355.255487)
			(xy 182.895155 -355.242135) (xy 182.944844 -355.235406) (xy 182.969916 -355.235002) (xy 182.994985 -355.235435)
			(xy 183.044668 -355.242181) (xy 183.093002 -355.25551) (xy 183.11622 -355.264974) (xy 183.129796 -355.270237)
			(xy 183.158706 -355.273615) (xy 183.187396 -355.268712) (xy 183.213543 -355.255923) (xy 183.235026 -355.236286)
			(xy 183.242966 -355.22408) (xy 183.257535 -355.200949) (xy 183.292378 -355.158828) (xy 183.333001 -355.122249)
			(xy 183.378532 -355.091998) (xy 183.427994 -355.068722) (xy 183.480325 -355.052922) (xy 183.534404 -355.044936)
			(xy 183.589068 -355.044936) (xy 183.643147 -355.052922) (xy 183.695478 -355.068722) (xy 183.74494 -355.091998)
			(xy 183.790471 -355.122249) (xy 183.831094 -355.158828) (xy 183.865937 -355.200949) (xy 183.880506 -355.22408)
			(xy 183.888451 -355.236289) (xy 183.909915 -355.255963) (xy 183.936063 -355.268771) (xy 183.964764 -355.27367)
			(xy 183.99368 -355.270261) (xy 184.007252 -355.264974) (xy 184.030458 -355.255475) (xy 184.078793 -355.242128)
			(xy 184.128484 -355.235403) (xy 184.153556 -355.235002) (xy 184.180398 -355.23549) (xy 184.233527 -355.243189)
			(xy 184.285002 -355.258433) (xy 184.333755 -355.280907) (xy 184.378778 -355.310146) (xy 184.419139 -355.345544)
			(xy 184.454001 -355.386368) (xy 184.482643 -355.431774) (xy 184.504471 -355.48082) (xy 184.512204 -355.506528)
			(xy 184.516888 -355.521018) (xy 184.533399 -355.546585) (xy 184.55671 -355.566152) (xy 184.58475 -355.577984)
			(xy 184.615032 -355.58103) (xy 184.644867 -355.575019) (xy 184.658508 -355.56825) (xy 184.686661 -355.553631)
			(xy 184.746609 -355.5329) (xy 184.809164 -355.522395) (xy 184.84088 -355.521768) (xy 184.8589 -355.521982)
			(xy 184.894774 -355.525421) (xy 184.912508 -355.528626) (xy 184.927714 -355.530997) (xy 184.958273 -355.527466)
			(xy 184.986395 -355.514998) (xy 185.009532 -355.494724) (xy 185.025584 -355.468482) (xy 185.029856 -355.453696)
			(xy 185.037245 -355.426649) (xy 185.058872 -355.374919) (xy 185.087835 -355.326911) (xy 185.123511 -355.283658)
			(xy 185.165131 -355.24609) (xy 185.211801 -355.215015) (xy 185.262515 -355.191104) (xy 185.316182 -355.174871)
			(xy 185.371646 -355.166664) (xy 185.39968 -355.166168) (xy 185.42693 -355.166697) (xy 185.480875 -355.17445)
			(xy 185.533167 -355.189801) (xy 185.582742 -355.212438) (xy 185.628592 -355.2419) (xy 185.669782 -355.277587)
			(xy 185.705473 -355.318773) (xy 185.734941 -355.364619) (xy 185.757583 -355.414192) (xy 185.772941 -355.466482)
			(xy 185.7807 -355.520426) (xy 185.781188 -355.547676) (xy 185.78071 -355.57525) (xy 185.772761 -355.629823)
			(xy 185.757038 -355.682682) (xy 185.733871 -355.732729) (xy 185.70374 -355.778918) (xy 185.667274 -355.82029)
			(xy 185.646568 -355.838506) (xy 185.635698 -355.848431) (xy 185.61963 -355.873075) (xy 185.611247 -355.901275)
			(xy 185.611243 -355.930694) (xy 185.619617 -355.958897) (xy 185.635678 -355.983546) (xy 185.646568 -355.993446)
			(xy 185.667251 -356.011687) (xy 185.703717 -356.053054) (xy 185.733847 -356.09924) (xy 185.757012 -356.149284)
			(xy 185.77273 -356.202142) (xy 185.780673 -356.256712) (xy 185.780675 -356.311857) (xy 185.772737 -356.366428)
			(xy 185.757023 -356.419287) (xy 185.733862 -356.469333) (xy 185.703736 -356.515521) (xy 185.667273 -356.556891)
			(xy 185.646568 -356.575106) (xy 185.635698 -356.585031) (xy 185.61963 -356.609675) (xy 185.611247 -356.637875)
			(xy 185.611243 -356.667294) (xy 185.619617 -356.695497) (xy 185.635678 -356.720146) (xy 185.646568 -356.730046)
			(xy 185.66725 -356.748289) (xy 185.703724 -356.78965) (xy 185.73386 -356.835833) (xy 185.757032 -356.885875)
			(xy 185.772754 -356.938732) (xy 185.7807 -356.993303) (xy 185.781188 -357.020876) (xy 185.780722 -357.048129)
			(xy 185.772968 -357.102081) (xy 185.757614 -357.15438) (xy 185.734973 -357.203961) (xy 185.705506 -357.249816)
			(xy 185.669812 -357.291009) (xy 185.628619 -357.326703) (xy 185.582765 -357.356171) (xy 185.533184 -357.378813)
			(xy 185.480885 -357.394167) (xy 185.426933 -357.401922) (xy 185.39968 -357.402384) (xy 185.371824 -357.401891)
			(xy 185.316706 -357.393764) (xy 185.263355 -357.377715) (xy 185.212901 -357.354085) (xy 185.166416 -357.323374)
			(xy 185.124887 -357.286235) (xy 185.089195 -357.243456) (xy 185.060097 -357.195945) (xy 185.038211 -357.144711)
			(xy 185.030618 -357.117904) (xy 185.026394 -357.10377) (xy 185.010993 -357.078621) (xy 184.989063 -357.058905)
			(xy 184.962422 -357.046259) (xy 184.933281 -357.041732) (xy 184.918604 -357.043228) (xy 184.905587 -357.044895)
			(xy 184.879403 -357.046676) (xy 184.86628 -357.046784) (xy 184.852131 -357.046693) (xy 184.823908 -357.044657)
			(xy 184.809892 -357.04272) (xy 184.79654 -357.041169) (xy 184.769851 -357.044258) (xy 184.744897 -357.054218)
			(xy 184.723417 -357.070357) (xy 184.706905 -357.091552) (xy 184.696509 -357.116327) (xy 184.694322 -357.129588)
			(xy 184.690263 -357.156746) (xy 184.675284 -357.209576) (xy 184.652888 -357.259714) (xy 184.623536 -357.306124)
			(xy 184.587835 -357.347847) (xy 184.546523 -357.384023) (xy 184.500452 -357.413903) (xy 184.450573 -357.436871)
			(xy 184.397918 -357.452452) (xy 184.343572 -357.460326) (xy 184.316116 -357.460804) (xy 184.288863 -357.46033)
			(xy 184.234913 -357.452575) (xy 184.182615 -357.437221) (xy 184.133034 -357.41458) (xy 184.087181 -357.385113)
			(xy 184.045988 -357.34942) (xy 184.010294 -357.308229) (xy 183.980826 -357.262376) (xy 183.958184 -357.212797)
			(xy 183.942828 -357.160499) (xy 183.935071 -357.106549) (xy 183.934608 -357.079296) (xy 183.935068 -357.051721)
			(xy 183.943021 -356.997148) (xy 183.958747 -356.944288) (xy 183.981918 -356.894242) (xy 184.012052 -356.848052)
			(xy 184.04852 -356.806682) (xy 184.069228 -356.788466) (xy 184.080126 -356.77857) (xy 184.096194 -356.753918)
			(xy 184.104574 -356.72571) (xy 184.104573 -356.696284) (xy 184.096191 -356.668078) (xy 184.080123 -356.643426)
			(xy 184.069228 -356.633526) (xy 184.048532 -356.615298) (xy 184.012059 -356.573934) (xy 183.981924 -356.527748)
			(xy 183.958756 -356.477703) (xy 183.943037 -356.424843) (xy 183.935094 -356.37027) (xy 183.934608 -356.342696)
			(xy 183.935076 -356.316195) (xy 183.942417 -356.263705) (xy 183.956958 -356.212737) (xy 183.978418 -356.164275)
			(xy 184.006384 -356.119251) (xy 184.023 -356.098602) (xy 184.032398 -356.086423) (xy 184.0442 -356.058034)
			(xy 184.047035 -356.027421) (xy 184.040647 -355.997347) (xy 184.025613 -355.970529) (xy 184.003291 -355.949389)
			(xy 183.989726 -355.942138) (xy 183.96604 -355.93003) (xy 183.922058 -355.900108) (xy 183.882776 -355.864239)
			(xy 183.848991 -355.823151) (xy 183.834786 -355.80066) (xy 183.826864 -355.788436) (xy 183.80539 -355.76877)
			(xy 183.779237 -355.755968) (xy 183.750533 -355.751072) (xy 183.721614 -355.754481) (xy 183.70804 -355.759766)
			(xy 183.684836 -355.76927) (xy 183.6365 -355.782615) (xy 183.586808 -355.789337) (xy 183.561736 -355.789738)
			(xy 183.536666 -355.789326) (xy 183.486983 -355.782572) (xy 183.438649 -355.769235) (xy 183.415432 -355.759766)
			(xy 183.401852 -355.754528) (xy 183.372954 -355.751164) (xy 183.344277 -355.756074) (xy 183.318144 -355.76886)
			(xy 183.296668 -355.788488) (xy 183.288686 -355.80066) (xy 183.274117 -355.823791) (xy 183.239274 -355.865912)
			(xy 183.198651 -355.902491) (xy 183.15312 -355.932742) (xy 183.103658 -355.956018) (xy 183.051327 -355.971818)
			(xy 182.997248 -355.979804) (xy 182.942584 -355.979804) (xy 182.888505 -355.971818) (xy 182.836174 -355.956018)
			(xy 182.786712 -355.932742) (xy 182.741181 -355.902491) (xy 182.700558 -355.865912) (xy 182.665715 -355.823791)
			(xy 182.651146 -355.80066) (xy 182.643262 -355.788408) (xy 182.621778 -355.768742) (xy 182.595614 -355.755943)
			(xy 182.566901 -355.751055) (xy 182.537976 -355.754474) (xy 182.5244 -355.759766) (xy 182.501189 -355.769251)
			(xy 182.452856 -355.782603) (xy 182.403167 -355.789333) (xy 182.378096 -355.789738) (xy 182.350213 -355.789177)
			(xy 182.29507 -355.780865) (xy 182.241781 -355.764427) (xy 182.191537 -355.74023) (xy 182.145461 -355.708816)
			(xy 182.104582 -355.670885) (xy 182.069813 -355.627285) (xy 182.04193 -355.57899) (xy 182.021556 -355.527078)
			(xy 182.009147 -355.47271) (xy 182.004979 -355.4171) (xy 176.070138 -355.4171) (xy 176.084641 -355.466479)
			(xy 176.092401 -355.520425) (xy 176.092866 -355.547676) (xy 176.092396 -355.575251) (xy 176.084446 -355.629824)
			(xy 176.068722 -355.682684) (xy 176.045553 -355.73273) (xy 176.015421 -355.77892) (xy 175.978953 -355.820291)
			(xy 175.958246 -355.838506) (xy 175.947369 -355.848427) (xy 175.931289 -355.873069) (xy 175.922898 -355.901272)
			(xy 175.922894 -355.930697) (xy 175.931276 -355.958903) (xy 175.947348 -355.98355) (xy 175.958246 -355.993446)
			(xy 175.97893 -356.011686) (xy 176.015398 -356.053052) (xy 176.04553 -356.099239) (xy 176.068696 -356.149282)
			(xy 176.084415 -356.202141) (xy 176.092358 -356.256712) (xy 176.092361 -356.311857) (xy 176.084422 -356.366429)
			(xy 176.068707 -356.419288) (xy 176.045545 -356.469334) (xy 176.036694 -356.482904) (xy 178.547266 -356.482904)
			(xy 178.551337 -356.427282) (xy 178.563463 -356.372845) (xy 178.583386 -356.320754) (xy 178.610682 -356.272119)
			(xy 178.644768 -356.227976) (xy 178.684917 -356.189267) (xy 178.730275 -356.156816) (xy 178.779875 -356.131315)
			(xy 178.832659 -356.113308) (xy 178.887502 -356.103178) (xy 178.943236 -356.101141) (xy 178.998673 -356.107241)
			(xy 179.05263 -356.121347) (xy 179.103959 -356.143159) (xy 179.151565 -356.172213) (xy 179.194433 -356.207888)
			(xy 179.23165 -356.249425) (xy 179.262423 -356.295938) (xy 179.286095 -356.346435) (xy 179.302163 -356.399842)
			(xy 179.310283 -356.455018) (xy 179.310792 -356.482904) (xy 179.310283 -356.51079) (xy 179.302163 -356.565966)
			(xy 179.286095 -356.619373) (xy 179.262423 -356.66987) (xy 179.23165 -356.716383) (xy 179.194433 -356.75792)
			(xy 179.151565 -356.793595) (xy 179.103959 -356.822649) (xy 179.05263 -356.844461) (xy 178.998673 -356.858567)
			(xy 178.943236 -356.864667) (xy 178.887502 -356.86263) (xy 178.832659 -356.8525) (xy 178.779875 -356.834493)
			(xy 178.730275 -356.808992) (xy 178.684917 -356.776541) (xy 178.644768 -356.737832) (xy 178.610682 -356.693689)
			(xy 178.583386 -356.645054) (xy 178.563463 -356.592963) (xy 178.551337 -356.538526) (xy 178.547266 -356.482904)
			(xy 176.036694 -356.482904) (xy 176.015417 -356.515523) (xy 175.978952 -356.556892) (xy 175.958246 -356.575106)
			(xy 175.947369 -356.585027) (xy 175.931289 -356.609669) (xy 175.922898 -356.637872) (xy 175.922894 -356.667297)
			(xy 175.931276 -356.695503) (xy 175.947348 -356.72015) (xy 175.958246 -356.730046) (xy 175.978943 -356.748272)
			(xy 176.015413 -356.789639) (xy 176.045546 -356.835826) (xy 176.068713 -356.885871) (xy 176.084433 -356.93873)
			(xy 176.092378 -356.993302) (xy 176.092866 -357.020876) (xy 176.092422 -357.04813) (xy 176.084667 -357.102084)
			(xy 176.069312 -357.154385) (xy 176.04667 -357.203968) (xy 176.0172 -357.249823) (xy 175.981504 -357.291017)
			(xy 175.940308 -357.326711) (xy 175.894452 -357.356178) (xy 175.844868 -357.378819) (xy 175.792566 -357.394171)
			(xy 175.738612 -357.401924) (xy 175.711358 -357.402384) (xy 175.683501 -357.401911) (xy 175.628383 -357.393781)
			(xy 175.575031 -357.377729) (xy 175.524577 -357.354095) (xy 175.478092 -357.323382) (xy 175.436563 -357.286241)
			(xy 175.400871 -357.24346) (xy 175.371774 -357.195948) (xy 175.349889 -357.144711) (xy 175.342296 -357.117904)
			(xy 175.337994 -357.103798) (xy 175.322609 -357.078656) (xy 175.300697 -357.058941) (xy 175.274076 -357.046287)
			(xy 175.244953 -357.041743) (xy 175.230282 -357.043228) (xy 175.217265 -357.044897) (xy 175.191081 -357.046677)
			(xy 175.177958 -357.046784) (xy 175.163809 -357.046695) (xy 175.135586 -357.044658) (xy 175.12157 -357.04272)
			(xy 175.10822 -357.041147) (xy 175.081529 -357.044241) (xy 175.056574 -357.054206) (xy 175.035094 -357.070349)
			(xy 175.018582 -357.091547) (xy 175.008187 -357.116326) (xy 175.006 -357.129588) (xy 175.001962 -357.15675)
			(xy 174.986983 -357.209582) (xy 174.964584 -357.259721) (xy 174.935231 -357.306132) (xy 174.899527 -357.347855)
			(xy 174.858212 -357.384031) (xy 174.812138 -357.41391) (xy 174.762257 -357.436877) (xy 174.709599 -357.452457)
			(xy 174.655251 -357.460327) (xy 174.627794 -357.460804) (xy 174.600542 -357.460328) (xy 174.546594 -357.45257)
			(xy 174.494299 -357.437214) (xy 174.444721 -357.414572) (xy 174.398871 -357.385105) (xy 174.357681 -357.349412)
			(xy 174.321989 -357.308221) (xy 174.292523 -357.26237) (xy 174.269882 -357.212792) (xy 174.254528 -357.160496)
			(xy 174.246772 -357.106548) (xy 174.246286 -357.079296) (xy 174.246754 -357.051722) (xy 174.254707 -356.997149)
			(xy 174.270432 -356.944289) (xy 174.293601 -356.894244) (xy 174.323733 -356.848054) (xy 174.3602 -356.806682)
			(xy 174.380906 -356.788466) (xy 174.391806 -356.778571) (xy 174.407877 -356.753919) (xy 174.41626 -356.725711)
			(xy 174.416259 -356.696284) (xy 174.407875 -356.668076) (xy 174.391803 -356.643425) (xy 174.380906 -356.633526)
			(xy 174.360205 -356.615303) (xy 174.323734 -356.573937) (xy 174.2936 -356.52775) (xy 174.270433 -356.477704)
			(xy 174.254714 -356.424843) (xy 174.246772 -356.37027) (xy 174.246286 -356.342696) (xy 174.246759 -356.316196)
			(xy 174.2541 -356.263705) (xy 174.26864 -356.212738) (xy 174.290099 -356.164275) (xy 174.318063 -356.119252)
			(xy 174.334678 -356.098602) (xy 174.344049 -356.086407) (xy 174.355839 -356.058023) (xy 174.35867 -356.027419)
			(xy 174.352287 -355.997354) (xy 174.337266 -355.97054) (xy 174.31496 -355.949395) (xy 174.301404 -355.942138)
			(xy 174.277714 -355.930037) (xy 174.233734 -355.900113) (xy 174.194453 -355.864242) (xy 174.160669 -355.823152)
			(xy 174.146464 -355.80066) (xy 174.138563 -355.788421) (xy 174.117083 -355.768755) (xy 174.090924 -355.755954)
			(xy 174.062215 -355.751063) (xy 174.033293 -355.754477) (xy 174.019718 -355.759766) (xy 173.996504 -355.769246)
			(xy 173.948173 -355.7826) (xy 173.898485 -355.789332) (xy 173.873414 -355.789738) (xy 173.848345 -355.7893)
			(xy 173.798662 -355.782557) (xy 173.750328 -355.76923) (xy 173.72711 -355.759766) (xy 173.713502 -355.75461)
			(xy 173.684618 -355.751229) (xy 173.655952 -355.756121) (xy 173.629823 -355.768887) (xy 173.608347 -355.788496)
			(xy 173.600364 -355.80066) (xy 173.585795 -355.823791) (xy 173.550952 -355.865912) (xy 173.510329 -355.902491)
			(xy 173.464798 -355.932742) (xy 173.415336 -355.956018) (xy 173.363005 -355.971818) (xy 173.308926 -355.979804)
			(xy 173.254262 -355.979804) (xy 173.200183 -355.971818) (xy 173.147852 -355.956018) (xy 173.09839 -355.932742)
			(xy 173.052859 -355.902491) (xy 173.012236 -355.865912) (xy 172.977393 -355.823791) (xy 172.962824 -355.80066)
			(xy 172.954866 -355.788462) (xy 172.933402 -355.768796) (xy 172.907258 -355.75599) (xy 172.878563 -355.751087)
			(xy 172.849651 -355.754487) (xy 172.836078 -355.759766) (xy 172.812869 -355.769258) (xy 172.764536 -355.782607)
			(xy 172.714846 -355.789335) (xy 172.689774 -355.789738) (xy 172.661892 -355.789175) (xy 172.606751 -355.780861)
			(xy 172.553465 -355.764421) (xy 172.503225 -355.740223) (xy 172.457152 -355.708808) (xy 172.416275 -355.670877)
			(xy 172.381508 -355.627278) (xy 172.353627 -355.578984) (xy 172.333255 -355.527074) (xy 172.320847 -355.472708)
			(xy 172.316679 -355.4171) (xy 120.904013 -355.4171) (xy 120.910831 -355.422774) (xy 120.948048 -355.464311)
			(xy 120.978821 -355.510824) (xy 121.002493 -355.561321) (xy 121.018561 -355.614728) (xy 121.026681 -355.669904)
			(xy 121.02719 -355.69779) (xy 121.026681 -355.725676) (xy 121.018561 -355.780852) (xy 121.002493 -355.834259)
			(xy 120.978821 -355.884756) (xy 120.948048 -355.931269) (xy 120.910831 -355.972806) (xy 120.867963 -356.008481)
			(xy 120.82476 -356.034848) (xy 122.442222 -356.034848) (xy 122.446293 -355.979226) (xy 122.458419 -355.924789)
			(xy 122.478342 -355.872698) (xy 122.505638 -355.824063) (xy 122.539724 -355.77992) (xy 122.579873 -355.741211)
			(xy 122.625231 -355.70876) (xy 122.674831 -355.683259) (xy 122.727615 -355.665252) (xy 122.782458 -355.655122)
			(xy 122.838192 -355.653085) (xy 122.893629 -355.659185) (xy 122.947586 -355.673291) (xy 122.998915 -355.695103)
			(xy 123.046521 -355.724157) (xy 123.089389 -355.759832) (xy 123.126606 -355.801369) (xy 123.157379 -355.847882)
			(xy 123.181051 -355.898379) (xy 123.197119 -355.951786) (xy 123.205239 -356.006962) (xy 123.205748 -356.034848)
			(xy 123.205239 -356.062734) (xy 123.197119 -356.11791) (xy 123.181051 -356.171317) (xy 123.157379 -356.221814)
			(xy 123.126606 -356.268327) (xy 123.089389 -356.309864) (xy 123.046521 -356.345539) (xy 122.998915 -356.374593)
			(xy 122.947586 -356.396405) (xy 122.893629 -356.410511) (xy 122.838192 -356.416611) (xy 122.782458 -356.414574)
			(xy 122.727615 -356.404444) (xy 122.674831 -356.386437) (xy 122.625231 -356.360936) (xy 122.579873 -356.328485)
			(xy 122.539724 -356.289776) (xy 122.505638 -356.245633) (xy 122.478342 -356.196998) (xy 122.458419 -356.144907)
			(xy 122.446293 -356.09047) (xy 122.442222 -356.034848) (xy 120.82476 -356.034848) (xy 120.820357 -356.037535)
			(xy 120.769028 -356.059347) (xy 120.715071 -356.073453) (xy 120.659634 -356.079553) (xy 120.6039 -356.077516)
			(xy 120.549057 -356.067386) (xy 120.496273 -356.049379) (xy 120.446673 -356.023878) (xy 120.401315 -355.991427)
			(xy 120.361166 -355.952718) (xy 120.32708 -355.908575) (xy 120.299784 -355.85994) (xy 120.279861 -355.807849)
			(xy 120.267735 -355.753412) (xy 120.263664 -355.69779) (xy 117.0181 -355.69779) (xy 117.028066 -355.708913)
			(xy 117.058839 -355.755426) (xy 117.082511 -355.805923) (xy 117.098579 -355.85933) (xy 117.106699 -355.914506)
			(xy 117.107208 -355.942392) (xy 117.106699 -355.970278) (xy 117.098579 -356.025454) (xy 117.082511 -356.078861)
			(xy 117.058839 -356.129358) (xy 117.028066 -356.175871) (xy 116.990849 -356.217408) (xy 116.947981 -356.253083)
			(xy 116.900375 -356.282137) (xy 116.849046 -356.303949) (xy 116.795089 -356.318055) (xy 116.739652 -356.324155)
			(xy 116.683918 -356.322118) (xy 116.629075 -356.311988) (xy 116.576291 -356.293981) (xy 116.526691 -356.26848)
			(xy 116.481333 -356.236029) (xy 116.441184 -356.19732) (xy 116.407098 -356.153177) (xy 116.379802 -356.104542)
			(xy 116.359879 -356.052451) (xy 116.347753 -355.998014) (xy 116.343682 -355.942392) (xy 115.773962 -355.942392)
			(xy 116.314474 -356.482904) (xy 168.858944 -356.482904) (xy 168.863015 -356.427282) (xy 168.875141 -356.372845)
			(xy 168.895064 -356.320754) (xy 168.92236 -356.272119) (xy 168.956446 -356.227976) (xy 168.996595 -356.189267)
			(xy 169.041953 -356.156816) (xy 169.091553 -356.131315) (xy 169.144337 -356.113308) (xy 169.19918 -356.103178)
			(xy 169.254914 -356.101141) (xy 169.310351 -356.107241) (xy 169.364308 -356.121347) (xy 169.415637 -356.143159)
			(xy 169.463243 -356.172213) (xy 169.506111 -356.207888) (xy 169.543328 -356.249425) (xy 169.574101 -356.295938)
			(xy 169.597773 -356.346435) (xy 169.613841 -356.399842) (xy 169.621961 -356.455018) (xy 169.62247 -356.482904)
			(xy 169.621961 -356.51079) (xy 169.613841 -356.565966) (xy 169.597773 -356.619373) (xy 169.574101 -356.66987)
			(xy 169.543328 -356.716383) (xy 169.506111 -356.75792) (xy 169.463243 -356.793595) (xy 169.415637 -356.822649)
			(xy 169.364308 -356.844461) (xy 169.310351 -356.858567) (xy 169.254914 -356.864667) (xy 169.19918 -356.86263)
			(xy 169.144337 -356.8525) (xy 169.091553 -356.834493) (xy 169.041953 -356.808992) (xy 168.996595 -356.776541)
			(xy 168.956446 -356.737832) (xy 168.92236 -356.693689) (xy 168.895064 -356.645054) (xy 168.875141 -356.592963)
			(xy 168.863015 -356.538526) (xy 168.858944 -356.482904) (xy 116.314474 -356.482904) (xy 116.81079 -356.97922)
			(xy 122.843796 -356.97922) (xy 122.847867 -356.923598) (xy 122.859993 -356.869161) (xy 122.879916 -356.81707)
			(xy 122.907212 -356.768435) (xy 122.941298 -356.724292) (xy 122.981447 -356.685583) (xy 123.026805 -356.653132)
			(xy 123.076405 -356.627631) (xy 123.129189 -356.609624) (xy 123.184032 -356.599494) (xy 123.239766 -356.597457)
			(xy 123.295203 -356.603557) (xy 123.34916 -356.617663) (xy 123.400489 -356.639475) (xy 123.448095 -356.668529)
			(xy 123.490963 -356.704204) (xy 123.52818 -356.745741) (xy 123.558953 -356.792254) (xy 123.582625 -356.842751)
			(xy 123.598693 -356.896158) (xy 123.606813 -356.951334) (xy 123.607322 -356.97922) (xy 123.606813 -357.007106)
			(xy 123.598693 -357.062282) (xy 123.582625 -357.115689) (xy 123.558953 -357.166186) (xy 123.52818 -357.212699)
			(xy 123.490963 -357.254236) (xy 123.448095 -357.289911) (xy 123.400489 -357.318965) (xy 123.34916 -357.340777)
			(xy 123.295203 -357.354883) (xy 123.239766 -357.360983) (xy 123.184032 -357.358946) (xy 123.129189 -357.348816)
			(xy 123.076405 -357.330809) (xy 123.026805 -357.305308) (xy 122.981447 -357.272857) (xy 122.941298 -357.234148)
			(xy 122.907212 -357.190005) (xy 122.879916 -357.14137) (xy 122.859993 -357.089279) (xy 122.847867 -357.034842)
			(xy 122.843796 -356.97922) (xy 116.81079 -356.97922) (xy 117.96268 -358.13111) (xy 119.248426 -358.13111)
			(xy 119.252499 -358.075451) (xy 119.264634 -358.020978) (xy 119.28457 -357.968852) (xy 119.311884 -357.920184)
			(xy 119.345992 -357.876012) (xy 119.386169 -357.837277) (xy 119.431557 -357.804805) (xy 119.481189 -357.779287)
			(xy 119.534009 -357.761268) (xy 119.588888 -357.751131) (xy 119.644659 -357.749093) (xy 119.700133 -357.755196)
			(xy 119.754126 -357.769312) (xy 119.805489 -357.791139) (xy 119.853127 -357.820212) (xy 119.896023 -357.855911)
			(xy 119.933265 -357.897475) (xy 119.964059 -357.944019) (xy 119.987747 -357.99455) (xy 120.003825 -358.047992)
			(xy 120.011951 -358.103206) (xy 120.012414 -358.12857) (xy 122.04522 -358.12857) (xy 122.049291 -358.072948)
			(xy 122.061417 -358.018511) (xy 122.08134 -357.96642) (xy 122.108636 -357.917785) (xy 122.142722 -357.873642)
			(xy 122.182871 -357.834933) (xy 122.228229 -357.802482) (xy 122.277829 -357.776981) (xy 122.330613 -357.758974)
			(xy 122.385456 -357.748844) (xy 122.44119 -357.746807) (xy 122.496627 -357.752907) (xy 122.550584 -357.767013)
			(xy 122.601913 -357.788825) (xy 122.649519 -357.817879) (xy 122.692387 -357.853554) (xy 122.729604 -357.895091)
			(xy 122.760377 -357.941604) (xy 122.784049 -357.992101) (xy 122.800117 -358.045508) (xy 122.808237 -358.100684)
			(xy 122.808746 -358.12857) (xy 122.808237 -358.156456) (xy 122.800117 -358.211632) (xy 122.784049 -358.265039)
			(xy 122.760377 -358.315536) (xy 122.729604 -358.362049) (xy 122.692387 -358.403586) (xy 122.649519 -358.439261)
			(xy 122.601913 -358.468315) (xy 122.550584 -358.490127) (xy 122.496627 -358.504233) (xy 122.44119 -358.510333)
			(xy 122.385456 -358.508296) (xy 122.330613 -358.498166) (xy 122.277829 -358.480159) (xy 122.228229 -358.454658)
			(xy 122.182871 -358.422207) (xy 122.142722 -358.383498) (xy 122.108636 -358.339355) (xy 122.08134 -358.29072)
			(xy 122.061417 -358.238629) (xy 122.049291 -358.184192) (xy 122.04522 -358.12857) (xy 120.012414 -358.12857)
			(xy 120.01246 -358.13111) (xy 120.011951 -358.159014) (xy 120.003825 -358.214228) (xy 119.987747 -358.26767)
			(xy 119.964059 -358.318201) (xy 119.933265 -358.364745) (xy 119.896023 -358.406309) (xy 119.853127 -358.442008)
			(xy 119.805489 -358.471081) (xy 119.754126 -358.492908) (xy 119.700133 -358.507024) (xy 119.644659 -358.513127)
			(xy 119.588888 -358.511089) (xy 119.534009 -358.500952) (xy 119.481189 -358.482933) (xy 119.431557 -358.457415)
			(xy 119.386169 -358.424943) (xy 119.345992 -358.386208) (xy 119.311884 -358.342036) (xy 119.28457 -358.293368)
			(xy 119.264634 -358.241242) (xy 119.252499 -358.186769) (xy 119.248426 -358.13111) (xy 117.96268 -358.13111)
			(xy 118.358666 -358.527096) (xy 118.375903 -358.545192) (xy 118.403641 -358.586757) (xy 118.422744 -358.632931)
			(xy 118.43248 -358.681943) (xy 118.433088 -358.706928) (xy 118.433088 -358.964484) (xy 122.787916 -358.964484)
			(xy 122.791987 -358.908862) (xy 122.804113 -358.854425) (xy 122.824036 -358.802334) (xy 122.851332 -358.753699)
			(xy 122.885418 -358.709556) (xy 122.925567 -358.670847) (xy 122.970925 -358.638396) (xy 123.020525 -358.612895)
			(xy 123.073309 -358.594888) (xy 123.128152 -358.584758) (xy 123.183886 -358.582721) (xy 123.239323 -358.588821)
			(xy 123.29328 -358.602927) (xy 123.344609 -358.624739) (xy 123.392215 -358.653793) (xy 123.435083 -358.689468)
			(xy 123.4723 -358.731005) (xy 123.503073 -358.777518) (xy 123.526745 -358.828015) (xy 123.542813 -358.881422)
			(xy 123.550933 -358.936598) (xy 123.551442 -358.964484) (xy 123.550933 -358.99237) (xy 123.542813 -359.047546)
			(xy 123.526745 -359.100953) (xy 123.503073 -359.15145) (xy 123.4723 -359.197963) (xy 123.435083 -359.2395)
			(xy 123.392215 -359.275175) (xy 123.344609 -359.304229) (xy 123.29328 -359.326041) (xy 123.239323 -359.340147)
			(xy 123.183886 -359.346247) (xy 123.128152 -359.34421) (xy 123.073309 -359.33408) (xy 123.020525 -359.316073)
			(xy 122.970925 -359.290572) (xy 122.925567 -359.258121) (xy 122.885418 -359.219412) (xy 122.851332 -359.175269)
			(xy 122.824036 -359.126634) (xy 122.804113 -359.074543) (xy 122.791987 -359.020106) (xy 122.787916 -358.964484)
			(xy 118.433088 -358.964484) (xy 118.433088 -360.2736) (xy 118.713248 -360.2736) (xy 118.717321 -360.217941)
			(xy 118.729456 -360.163468) (xy 118.749392 -360.111342) (xy 118.776706 -360.062674) (xy 118.810814 -360.018502)
			(xy 118.850991 -359.979767) (xy 118.896379 -359.947295) (xy 118.946011 -359.921777) (xy 118.998831 -359.903758)
			(xy 119.05371 -359.893621) (xy 119.109481 -359.891583) (xy 119.164955 -359.897686) (xy 119.218948 -359.911802)
			(xy 119.270311 -359.933629) (xy 119.317949 -359.962702) (xy 119.360845 -359.998401) (xy 119.398087 -360.039965)
			(xy 119.428881 -360.086509) (xy 119.452569 -360.13704) (xy 119.468647 -360.190482) (xy 119.476773 -360.245696)
			(xy 119.477282 -360.2736) (xy 119.476773 -360.301504) (xy 119.468647 -360.356718) (xy 119.452569 -360.41016)
			(xy 119.428881 -360.460691) (xy 119.398087 -360.507235) (xy 119.360845 -360.548799) (xy 119.317949 -360.584498)
			(xy 119.270311 -360.613571) (xy 119.218948 -360.635398) (xy 119.164955 -360.649514) (xy 119.109481 -360.655617)
			(xy 119.05371 -360.653579) (xy 118.998831 -360.643442) (xy 118.946011 -360.625423) (xy 118.896379 -360.599905)
			(xy 118.850991 -360.567433) (xy 118.810814 -360.528698) (xy 118.776706 -360.484526) (xy 118.749392 -360.435858)
			(xy 118.729456 -360.383732) (xy 118.717321 -360.329259) (xy 118.713248 -360.2736) (xy 118.433088 -360.2736)
			(xy 118.433088 -360.680508) (xy 128.966466 -360.680508) (xy 128.970537 -360.624886) (xy 128.982663 -360.570449)
			(xy 129.002586 -360.518358) (xy 129.029882 -360.469723) (xy 129.063968 -360.42558) (xy 129.104117 -360.386871)
			(xy 129.149475 -360.35442) (xy 129.199075 -360.328919) (xy 129.251859 -360.310912) (xy 129.306702 -360.300782)
			(xy 129.362436 -360.298745) (xy 129.417873 -360.304845) (xy 129.47183 -360.318951) (xy 129.523159 -360.340763)
			(xy 129.570765 -360.369817) (xy 129.613633 -360.405492) (xy 129.65085 -360.447029) (xy 129.681623 -360.493542)
			(xy 129.705295 -360.544039) (xy 129.721363 -360.597446) (xy 129.729483 -360.652622) (xy 129.729992 -360.680508)
			(xy 129.729483 -360.708394) (xy 129.721363 -360.76357) (xy 129.705295 -360.816977) (xy 129.681623 -360.867474)
			(xy 129.65085 -360.913987) (xy 129.613633 -360.955524) (xy 129.570765 -360.991199) (xy 129.523159 -361.020253)
			(xy 129.47183 -361.042065) (xy 129.417873 -361.056171) (xy 129.362436 -361.062271) (xy 129.306702 -361.060234)
			(xy 129.251859 -361.050104) (xy 129.199075 -361.032097) (xy 129.149475 -361.006596) (xy 129.104117 -360.974145)
			(xy 129.063968 -360.935436) (xy 129.029882 -360.891293) (xy 129.002586 -360.842658) (xy 128.982663 -360.790567)
			(xy 128.970537 -360.73613) (xy 128.966466 -360.680508) (xy 118.433088 -360.680508) (xy 118.433088 -362.097066)
			(xy 128.08534 -362.097066) (xy 128.089411 -362.041444) (xy 128.101537 -361.987007) (xy 128.12146 -361.934916)
			(xy 128.148756 -361.886281) (xy 128.182842 -361.842138) (xy 128.222991 -361.803429) (xy 128.268349 -361.770978)
			(xy 128.317949 -361.745477) (xy 128.370733 -361.72747) (xy 128.425576 -361.71734) (xy 128.48131 -361.715303)
			(xy 128.536747 -361.721403) (xy 128.590704 -361.735509) (xy 128.642033 -361.757321) (xy 128.689639 -361.786375)
			(xy 128.732507 -361.82205) (xy 128.769724 -361.863587) (xy 128.800497 -361.9101) (xy 128.824169 -361.960597)
			(xy 128.840237 -362.014004) (xy 128.848357 -362.06918) (xy 128.848866 -362.097066) (xy 128.848357 -362.124952)
			(xy 128.840237 -362.180128) (xy 128.824169 -362.233535) (xy 128.800497 -362.284032) (xy 128.769724 -362.330545)
			(xy 128.732507 -362.372082) (xy 128.689639 -362.407757) (xy 128.642033 -362.436811) (xy 128.590704 -362.458623)
			(xy 128.536747 -362.472729) (xy 128.48131 -362.478829) (xy 128.425576 -362.476792) (xy 128.370733 -362.466662)
			(xy 128.317949 -362.448655) (xy 128.268349 -362.423154) (xy 128.222991 -362.390703) (xy 128.182842 -362.351994)
			(xy 128.148756 -362.307851) (xy 128.12146 -362.259216) (xy 128.101537 -362.207125) (xy 128.089411 -362.152688)
			(xy 128.08534 -362.097066) (xy 118.433088 -362.097066) (xy 118.433088 -362.27893) (xy 119.21998 -363.065568)
			(xy 120.251728 -363.065568) (xy 120.508522 -362.809028) (xy 120.526619 -362.791773) (xy 120.568163 -362.763962)
			(xy 120.614334 -362.744788) (xy 120.663358 -362.734989) (xy 120.688354 -362.734352) (xy 131.284218 -362.734352)
			(xy 136.14527 -357.873554) (xy 136.163381 -357.856333) (xy 136.20494 -357.828591) (xy 136.251109 -357.809483)
			(xy 136.300118 -357.799743) (xy 136.325102 -357.799132) (xy 168.162224 -357.799132) (xy 168.175656 -357.798645)
			(xy 168.201592 -357.791653) (xy 168.224804 -357.778134) (xy 168.243684 -357.759025) (xy 168.256921 -357.735651)
			(xy 168.263599 -357.709632) (xy 168.263254 -357.682772) (xy 168.255911 -357.656933) (xy 168.249346 -357.645208)
			(xy 168.236432 -357.622881) (xy 168.216109 -357.575475) (xy 168.202352 -357.525765) (xy 168.195413 -357.474655)
			(xy 168.19499 -357.448866) (xy 168.195446 -357.421614) (xy 168.203207 -357.367665) (xy 168.218567 -357.31537)
			(xy 168.241212 -357.265793) (xy 168.270681 -357.219943) (xy 168.306376 -357.178753) (xy 168.347568 -357.143062)
			(xy 168.393421 -357.113596) (xy 168.443 -357.090955) (xy 168.495297 -357.0756) (xy 168.549246 -357.067844)
			(xy 168.576498 -357.067358) (xy 168.603514 -357.067851) (xy 168.657007 -357.075474) (xy 168.708888 -357.090569)
			(xy 168.758121 -357.112832) (xy 168.803721 -357.141819) (xy 168.844774 -357.17695) (xy 168.88046 -357.217521)
			(xy 168.910065 -357.262722) (xy 168.932996 -357.311647) (xy 168.948795 -357.363319) (xy 168.953434 -357.389938)
			(xy 168.956003 -357.403729) (xy 168.967624 -357.429249) (xy 168.985753 -357.450642) (xy 169.009021 -357.466293)
			(xy 169.03567 -357.475019) (xy 169.063688 -357.476163) (xy 169.090959 -357.469636) (xy 169.115425 -357.455933)
			(xy 169.125646 -357.446326) (xy 169.451528 -357.120444) (xy 169.469625 -357.103189) (xy 169.511168 -357.075377)
			(xy 169.557339 -357.056203) (xy 169.606364 -357.046404) (xy 169.63136 -357.045768) (xy 169.762932 -357.045768)
			(xy 169.781106 -357.026157) (xy 169.82199 -356.9917) (xy 169.867283 -356.963287) (xy 169.916099 -356.941474)
			(xy 169.967481 -356.926689) (xy 170.020424 -356.91922) (xy 170.047158 -356.918768) (xy 170.074409 -356.919294)
			(xy 170.128356 -356.927045) (xy 170.180651 -356.942394) (xy 170.23023 -356.96503) (xy 170.276082 -356.994492)
			(xy 170.317274 -357.030179) (xy 170.352969 -357.071365) (xy 170.382438 -357.117212) (xy 170.405082 -357.166787)
			(xy 170.420441 -357.219079) (xy 170.428201 -357.273025) (xy 170.428341 -357.281226) (xy 171.290996 -357.281226)
			(xy 171.291482 -357.253975) (xy 171.299238 -357.200027) (xy 171.314593 -357.147732) (xy 171.337235 -357.098155)
			(xy 171.366701 -357.052305) (xy 171.402392 -357.011114) (xy 171.443583 -356.975423) (xy 171.489433 -356.945957)
			(xy 171.53901 -356.923315) (xy 171.591305 -356.90796) (xy 171.645253 -356.900204) (xy 171.699755 -356.900204)
			(xy 171.753703 -356.90796) (xy 171.805998 -356.923315) (xy 171.855575 -356.945957) (xy 171.901425 -356.975423)
			(xy 171.942616 -357.011114) (xy 171.978307 -357.052305) (xy 172.007773 -357.098155) (xy 172.030415 -357.147732)
			(xy 172.04577 -357.200027) (xy 172.053526 -357.253975) (xy 172.054012 -357.281226) (xy 172.05377 -357.299893)
			(xy 172.050079 -357.337044) (xy 172.046646 -357.355394) (xy 172.044279 -357.369658) (xy 172.046811 -357.398451)
			(xy 172.057314 -357.425379) (xy 172.074943 -357.448283) (xy 172.098287 -357.465328) (xy 172.125472 -357.475145)
			(xy 172.139864 -357.476552) (xy 172.168516 -357.478943) (xy 172.224682 -357.491225) (xy 172.278369 -357.511796)
			(xy 172.328362 -357.54019) (xy 172.373528 -357.575762) (xy 172.412846 -357.61771) (xy 172.445425 -357.665081)
			(xy 172.470528 -357.716805) (xy 172.487586 -357.771709) (xy 172.496212 -357.828551) (xy 172.496734 -357.857298)
			(xy 172.496248 -357.884549) (xy 172.488492 -357.938497) (xy 172.473137 -357.990792) (xy 172.450495 -358.040369)
			(xy 172.421029 -358.086219) (xy 172.385338 -358.12741) (xy 172.344147 -358.163101) (xy 172.298297 -358.192567)
			(xy 172.24872 -358.215209) (xy 172.196425 -358.230564) (xy 172.142477 -358.23832) (xy 172.087975 -358.23832)
			(xy 172.034027 -358.230564) (xy 171.981732 -358.215209) (xy 171.932155 -358.192567) (xy 171.886305 -358.163101)
			(xy 171.845114 -358.12741) (xy 171.809423 -358.086219) (xy 171.779957 -358.040369) (xy 171.757315 -357.990792)
			(xy 171.74196 -357.938497) (xy 171.734204 -357.884549) (xy 171.733718 -357.857298) (xy 171.733956 -357.838631)
			(xy 171.737645 -357.801479) (xy 171.741084 -357.78313) (xy 171.743398 -357.76886) (xy 171.740872 -357.740075)
			(xy 171.730379 -357.713153) (xy 171.71276 -357.690251) (xy 171.689428 -357.673205) (xy 171.662253 -357.663383)
			(xy 171.647866 -357.661972) (xy 171.619211 -357.659618) (xy 171.563046 -357.647326) (xy 171.50936 -357.626748)
			(xy 171.459369 -357.598348) (xy 171.414205 -357.562771) (xy 171.374888 -357.520821) (xy 171.34231 -357.473447)
			(xy 171.317207 -357.421722) (xy 171.300148 -357.366816) (xy 171.291519 -357.309973) (xy 171.290996 -357.281226)
			(xy 170.428341 -357.281226) (xy 170.428666 -357.300276) (xy 170.428216 -357.325613) (xy 170.421511 -357.375842)
			(xy 170.408216 -357.424741) (xy 170.388565 -357.47145) (xy 170.362903 -357.515146) (xy 170.331683 -357.555061)
			(xy 170.313858 -357.573072) (xy 170.30443 -357.582799) (xy 170.290719 -357.606154) (xy 170.283619 -357.632289)
			(xy 170.283627 -357.659371) (xy 170.290743 -357.685502) (xy 170.304467 -357.708849) (xy 170.313858 -357.718614)
			(xy 170.331685 -357.736625) (xy 170.362915 -357.776536) (xy 170.388585 -357.820231) (xy 170.408243 -357.86694)
			(xy 170.421543 -357.91584) (xy 170.428252 -357.966071) (xy 170.428546 -357.984044) (xy 170.68114 -357.984044)
			(xy 170.685211 -357.928422) (xy 170.697337 -357.873985) (xy 170.71726 -357.821894) (xy 170.744556 -357.773259)
			(xy 170.778642 -357.729116) (xy 170.818791 -357.690407) (xy 170.864149 -357.657956) (xy 170.913749 -357.632455)
			(xy 170.966533 -357.614448) (xy 171.021376 -357.604318) (xy 171.07711 -357.602281) (xy 171.132547 -357.608381)
			(xy 171.186504 -357.622487) (xy 171.237833 -357.644299) (xy 171.285439 -357.673353) (xy 171.328307 -357.709028)
			(xy 171.365524 -357.750565) (xy 171.396297 -357.797078) (xy 171.419969 -357.847575) (xy 171.436037 -357.900982)
			(xy 171.444157 -357.956158) (xy 171.444666 -357.984044) (xy 171.444157 -358.01193) (xy 171.436037 -358.067106)
			(xy 171.419969 -358.120513) (xy 171.396297 -358.17101) (xy 171.365524 -358.217523) (xy 171.328307 -358.25906)
			(xy 171.285439 -358.294735) (xy 171.237833 -358.323789) (xy 171.186504 -358.345601) (xy 171.132547 -358.359707)
			(xy 171.07711 -358.365807) (xy 171.021376 -358.36377) (xy 170.966533 -358.35364) (xy 170.913749 -358.335633)
			(xy 170.864149 -358.310132) (xy 170.818791 -358.277681) (xy 170.778642 -358.238972) (xy 170.744556 -358.194829)
			(xy 170.71726 -358.146194) (xy 170.697337 -358.094103) (xy 170.685211 -358.039666) (xy 170.68114 -357.984044)
			(xy 170.428546 -357.984044) (xy 170.428666 -357.99141) (xy 170.428254 -358.018665) (xy 170.420495 -358.07262)
			(xy 170.405135 -358.124921) (xy 170.382489 -358.174505) (xy 170.353016 -358.22036) (xy 170.317317 -358.261553)
			(xy 170.276118 -358.297247) (xy 170.230259 -358.326714) (xy 170.180673 -358.349354) (xy 170.128369 -358.364706)
			(xy 170.074413 -358.372458) (xy 170.047158 -358.372918) (xy 170.020413 -358.372471) (xy 169.967451 -358.364976)
			(xy 169.916055 -358.350153) (xy 169.867236 -358.328293) (xy 169.82195 -358.299825) (xy 169.781087 -358.265308)
			(xy 169.762932 -358.245664) (xy 169.61358 -358.245664) (xy 169.245026 -358.614218) (xy 169.226913 -358.631437)
			(xy 169.185355 -358.65918) (xy 169.139186 -358.678289) (xy 169.090178 -358.68803) (xy 169.065194 -358.68864)
			(xy 136.600184 -358.68864) (xy 131.701032 -363.587792) (xy 131.682958 -363.605072) (xy 131.641406 -363.632878)
			(xy 131.595228 -363.652045) (xy 131.546198 -363.661836) (xy 131.5212 -363.662468) (xy 120.926098 -363.662468)
			(xy 120.669304 -363.919008) (xy 120.651202 -363.936257) (xy 120.609659 -363.964068) (xy 120.56349 -363.983243)
			(xy 120.514468 -363.993045) (xy 120.489472 -363.993684) (xy 118.915942 -363.993684) (xy 118.890947 -363.99302)
			(xy 118.841926 -363.983224) (xy 118.795756 -363.964059) (xy 118.754208 -363.936259) (xy 118.73611 -363.919008)
			(xy 117.60073 -362.783628) (xy 117.583504 -362.765522) (xy 117.555764 -362.723961) (xy 117.536658 -362.67779)
			(xy 117.526918 -362.62878) (xy 117.526308 -362.603796) (xy 117.526308 -358.977438) (xy 115.685316 -357.1367)
			(xy 115.674376 -357.126477) (xy 115.647976 -357.112376) (xy 115.618622 -357.106538) (xy 115.588836 -357.109464)
			(xy 115.561179 -357.120902) (xy 115.538027 -357.139869) (xy 115.521371 -357.164736) (xy 115.512643 -357.193364)
			(xy 115.512088 -357.208328) (xy 115.512088 -359.382822) (xy 116.061996 -359.382822) (xy 116.066067 -359.3272)
			(xy 116.078193 -359.272763) (xy 116.098116 -359.220672) (xy 116.125412 -359.172037) (xy 116.159498 -359.127894)
			(xy 116.199647 -359.089185) (xy 116.245005 -359.056734) (xy 116.294605 -359.031233) (xy 116.347389 -359.013226)
			(xy 116.402232 -359.003096) (xy 116.457966 -359.001059) (xy 116.513403 -359.007159) (xy 116.56736 -359.021265)
			(xy 116.618689 -359.043077) (xy 116.666295 -359.072131) (xy 116.709163 -359.107806) (xy 116.74638 -359.149343)
			(xy 116.777153 -359.195856) (xy 116.800825 -359.246353) (xy 116.816893 -359.29976) (xy 116.825013 -359.354936)
			(xy 116.825522 -359.382822) (xy 116.825013 -359.410708) (xy 116.816893 -359.465884) (xy 116.800825 -359.519291)
			(xy 116.777153 -359.569788) (xy 116.74638 -359.616301) (xy 116.709163 -359.657838) (xy 116.666295 -359.693513)
			(xy 116.618689 -359.722567) (xy 116.56736 -359.744379) (xy 116.513403 -359.758485) (xy 116.457966 -359.764585)
			(xy 116.402232 -359.762548) (xy 116.347389 -359.752418) (xy 116.294605 -359.734411) (xy 116.245005 -359.70891)
			(xy 116.199647 -359.676459) (xy 116.159498 -359.63775) (xy 116.125412 -359.593607) (xy 116.098116 -359.544972)
			(xy 116.078193 -359.492881) (xy 116.066067 -359.438444) (xy 116.061996 -359.382822) (xy 115.512088 -359.382822)
			(xy 115.512088 -363.208824) (xy 115.512607 -363.22257) (xy 115.520004 -363.249049) (xy 115.534202 -363.272593)
			(xy 115.554169 -363.291492) (xy 115.578457 -363.304376) (xy 115.605303 -363.310308) (xy 115.632758 -363.308859)
			(xy 115.65883 -363.300133) (xy 115.681627 -363.284764) (xy 115.690904 -363.27461) (xy 115.709093 -363.25396)
			(xy 115.750421 -363.217627) (xy 115.796542 -363.187612) (xy 115.846499 -363.164538) (xy 115.899255 -363.148885)
			(xy 115.953712 -363.140979) (xy 115.981226 -363.140498) (xy 116.008476 -363.140974) (xy 116.062422 -363.148733)
			(xy 116.114715 -363.164091) (xy 116.164289 -363.186734) (xy 116.210137 -363.216201) (xy 116.251325 -363.251893)
			(xy 116.287014 -363.293084) (xy 116.316479 -363.338933) (xy 116.339118 -363.38851) (xy 116.354472 -363.440803)
			(xy 116.362228 -363.49475) (xy 116.362228 -363.54925) (xy 116.354472 -363.603197) (xy 116.339118 -363.65549)
			(xy 116.316479 -363.705067) (xy 116.287014 -363.750916) (xy 116.251325 -363.792107) (xy 116.210137 -363.827799)
			(xy 116.164289 -363.857266) (xy 116.114715 -363.879909) (xy 116.062422 -363.895267) (xy 116.008476 -363.903026)
			(xy 115.981226 -363.903514) (xy 115.953712 -363.903042) (xy 115.899255 -363.895134) (xy 115.846501 -363.879478)
			(xy 115.796546 -363.856401) (xy 115.750428 -363.82638) (xy 115.709106 -363.790041) (xy 115.690904 -363.769402)
			(xy 115.681499 -363.758992) (xy 115.658185 -363.743401) (xy 115.63151 -363.734739) (xy 115.603484 -363.733659)
			(xy 115.576221 -363.740242) (xy 115.551776 -363.753992) (xy 115.531992 -363.773872) (xy 115.524788 -363.785912)
			(xy 115.549499 -363.793258) (xy 115.596707 -363.813965) (xy 115.640437 -363.841261) (xy 115.679776 -363.874575)
			(xy 115.713902 -363.913212) (xy 115.742102 -363.956365) (xy 115.763787 -364.003131) (xy 115.778504 -364.052536)
			(xy 115.785946 -364.103545) (xy 115.786408 -364.12932) (xy 115.78584 -364.155823) (xy 115.777973 -364.208243)
			(xy 115.762428 -364.258919) (xy 115.739551 -364.306735) (xy 115.709844 -364.350635) (xy 115.673964 -364.389652)
			(xy 115.6327 -364.422925) (xy 115.586965 -364.44972) (xy 115.537765 -364.469446) (xy 115.512088 -364.47603)
			(xy 115.512088 -364.679738) (xy 115.488974 -364.702852) (xy 119.224042 -364.702852) (xy 119.228113 -364.64723)
			(xy 119.240239 -364.592793) (xy 119.260162 -364.540702) (xy 119.287458 -364.492067) (xy 119.321544 -364.447924)
			(xy 119.361693 -364.409215) (xy 119.407051 -364.376764) (xy 119.456651 -364.351263) (xy 119.509435 -364.333256)
			(xy 119.564278 -364.323126) (xy 119.620012 -364.321089) (xy 119.675449 -364.327189) (xy 119.729406 -364.341295)
			(xy 119.780735 -364.363107) (xy 119.828341 -364.392161) (xy 119.871209 -364.427836) (xy 119.908426 -364.469373)
			(xy 119.939199 -364.515886) (xy 119.962871 -364.566383) (xy 119.978939 -364.61979) (xy 119.987059 -364.674966)
			(xy 119.987568 -364.702852) (xy 119.987059 -364.730738) (xy 119.978939 -364.785914) (xy 119.962871 -364.839321)
			(xy 119.939199 -364.889818) (xy 119.908426 -364.936331) (xy 119.871209 -364.977868) (xy 119.828341 -365.013543)
			(xy 119.780735 -365.042597) (xy 119.729406 -365.064409) (xy 119.675449 -365.078515) (xy 119.620012 -365.084615)
			(xy 119.564278 -365.082578) (xy 119.509435 -365.072448) (xy 119.456651 -365.054441) (xy 119.407051 -365.02894)
			(xy 119.361693 -364.996489) (xy 119.321544 -364.95778) (xy 119.287458 -364.913637) (xy 119.260162 -364.865002)
			(xy 119.240239 -364.812911) (xy 119.228113 -364.758474) (xy 119.224042 -364.702852) (xy 115.488974 -364.702852)
			(xy 114.62639 -365.565436) (xy 110.6043 -365.565436) (xy 110.594902 -365.604044) (xy 110.58772 -365.63134)
			(xy 110.566367 -365.683587) (xy 110.53755 -365.732119) (xy 110.501898 -365.775876) (xy 110.46019 -365.813905)
			(xy 110.413335 -365.845374) (xy 110.362355 -365.869598) (xy 110.308363 -365.886047) (xy 110.252537 -365.894364)
			(xy 110.224316 -365.894874) (xy 110.197062 -365.89443) (xy 110.143109 -365.886674) (xy 110.090808 -365.871318)
			(xy 110.041226 -365.848675) (xy 109.995371 -365.819206) (xy 109.954177 -365.78351) (xy 109.918484 -365.742314)
			(xy 109.889016 -365.696458) (xy 109.866375 -365.646875) (xy 109.851022 -365.594574) (xy 109.843269 -365.54062)
			(xy 109.842808 -365.513366) (xy 109.843062 -365.496856) (xy 109.844078 -365.474504) (xy 109.655864 -365.28629)
			(xy 109.644868 -365.276132) (xy 109.618483 -365.26203) (xy 109.589141 -365.256187) (xy 109.559367 -365.259106)
			(xy 109.531718 -365.270534) (xy 109.508573 -365.28949) (xy 109.491921 -365.314345) (xy 109.483192 -365.34296)
			(xy 109.482636 -365.357918) (xy 109.482636 -365.703358) (xy 110.227618 -366.44834) (xy 118.798086 -366.44834)
			(xy 121.284492 -363.962188) (xy 121.302595 -363.944941) (xy 121.344138 -363.917129) (xy 121.390307 -363.897954)
			(xy 121.439328 -363.888151) (xy 121.464324 -363.887512) (xy 132.601462 -363.887512) (xy 136.51357 -359.975658)
			(xy 136.531681 -359.958437) (xy 136.57324 -359.930695) (xy 136.619409 -359.911587) (xy 136.668418 -359.901847)
			(xy 136.693402 -359.901236) (xy 172.639228 -359.901236) (xy 173.525688 -359.014776) (xy 173.543791 -358.997529)
			(xy 173.585334 -358.969718) (xy 173.631503 -358.950543) (xy 173.680525 -358.94074) (xy 173.70552 -358.9401)
			(xy 174.980346 -358.9401) (xy 175.17237 -358.74833) (xy 175.185324 -358.73436) (xy 175.93564 -357.984044)
			(xy 175.953732 -357.966783) (xy 175.995277 -357.938972) (xy 176.04145 -357.9198) (xy 176.090475 -357.910003)
			(xy 176.115472 -357.909368) (xy 177.928778 -357.909368) (xy 177.943858 -357.908809) (xy 177.972698 -357.899978)
			(xy 177.997701 -357.88311) (xy 178.016688 -357.859674) (xy 178.028001 -357.831715) (xy 178.030656 -357.80167)
			(xy 178.024421 -357.77216) (xy 178.009839 -357.745758) (xy 177.99939 -357.73487) (xy 177.981361 -357.716848)
			(xy 177.949801 -357.676813) (xy 177.923852 -357.632933) (xy 177.903974 -357.58599) (xy 177.890523 -357.536818)
			(xy 177.883736 -357.486293) (xy 177.883312 -357.460804) (xy 177.883759 -357.43355) (xy 177.891516 -357.379598)
			(xy 177.906873 -357.327298) (xy 177.929516 -357.277717) (xy 177.958986 -357.231863) (xy 177.994681 -357.19067)
			(xy 178.035876 -357.154976) (xy 178.081731 -357.125508) (xy 178.131313 -357.102867) (xy 178.183613 -357.087513)
			(xy 178.237566 -357.079758) (xy 178.26482 -357.079296) (xy 178.293648 -357.079879) (xy 178.350645 -357.088572)
			(xy 178.405685 -357.105741) (xy 178.457515 -357.130996) (xy 178.504956 -357.163761) (xy 178.546927 -357.203291)
			(xy 178.582473 -357.248686) (xy 178.610784 -357.298912) (xy 178.631217 -357.352826) (xy 178.643305 -357.4092)
			(xy 178.645566 -357.437944) (xy 178.646876 -357.452498) (xy 178.656851 -357.479956) (xy 178.67419 -357.503468)
			(xy 178.697474 -357.521112) (xy 178.724799 -357.531444) (xy 178.753932 -357.533621) (xy 178.782489 -357.527464)
			(xy 178.808137 -357.513477) (xy 178.818794 -357.503476) (xy 179.20208 -357.120444) (xy 179.220197 -357.103212)
			(xy 179.261734 -357.075395) (xy 179.307898 -357.056215) (xy 179.356917 -357.046409) (xy 179.381912 -357.045768)
			(xy 179.450492 -357.045768) (xy 179.465224 -357.031036) (xy 179.486809 -357.010117) (xy 179.535381 -356.974708)
			(xy 179.588906 -356.947357) (xy 179.64606 -356.928743) (xy 179.705426 -356.919325) (xy 179.73548 -356.918768)
			(xy 179.76273 -356.919297) (xy 179.816675 -356.92705) (xy 179.868967 -356.942401) (xy 179.918542 -356.965038)
			(xy 179.964392 -356.9945) (xy 180.005582 -357.030187) (xy 180.041273 -357.071373) (xy 180.070741 -357.117219)
			(xy 180.093383 -357.166792) (xy 180.108741 -357.219082) (xy 180.1165 -357.273026) (xy 180.116647 -357.281226)
			(xy 180.979318 -357.281226) (xy 180.979804 -357.253975) (xy 180.98756 -357.200027) (xy 181.002915 -357.147732)
			(xy 181.025557 -357.098155) (xy 181.055023 -357.052305) (xy 181.090714 -357.011114) (xy 181.131905 -356.975423)
			(xy 181.177755 -356.945957) (xy 181.227332 -356.923315) (xy 181.279627 -356.90796) (xy 181.333575 -356.900204)
			(xy 181.388077 -356.900204) (xy 181.442025 -356.90796) (xy 181.49432 -356.923315) (xy 181.543897 -356.945957)
			(xy 181.589747 -356.975423) (xy 181.630938 -357.011114) (xy 181.666629 -357.052305) (xy 181.696095 -357.098155)
			(xy 181.718737 -357.147732) (xy 181.734092 -357.200027) (xy 181.741848 -357.253975) (xy 181.742334 -357.281226)
			(xy 181.742101 -357.299893) (xy 181.738409 -357.337045) (xy 181.734968 -357.355394) (xy 181.73258 -357.369656)
			(xy 181.735113 -357.398452) (xy 181.745618 -357.425384) (xy 181.763252 -357.44829) (xy 181.786601 -357.465334)
			(xy 181.813792 -357.475148) (xy 181.828186 -357.476552) (xy 181.85684 -357.478924) (xy 181.913006 -357.49121)
			(xy 181.966693 -357.511783) (xy 182.016686 -357.540179) (xy 182.061852 -357.575754) (xy 182.10117 -357.617703)
			(xy 182.133748 -357.665077) (xy 182.158851 -357.716802) (xy 182.175908 -357.771707) (xy 182.184534 -357.828551)
			(xy 182.185056 -357.857298) (xy 182.18457 -357.884549) (xy 182.176814 -357.938497) (xy 182.161459 -357.990792)
			(xy 182.138817 -358.040369) (xy 182.109351 -358.086219) (xy 182.07366 -358.12741) (xy 182.032469 -358.163101)
			(xy 181.986619 -358.192567) (xy 181.937042 -358.215209) (xy 181.884747 -358.230564) (xy 181.830799 -358.23832)
			(xy 181.776297 -358.23832) (xy 181.722349 -358.230564) (xy 181.670054 -358.215209) (xy 181.620477 -358.192567)
			(xy 181.574627 -358.163101) (xy 181.533436 -358.12741) (xy 181.497745 -358.086219) (xy 181.468279 -358.040369)
			(xy 181.445637 -357.990792) (xy 181.430282 -357.938497) (xy 181.422526 -357.884549) (xy 181.42204 -357.857298)
			(xy 181.422277 -357.838631) (xy 181.425967 -357.801479) (xy 181.429406 -357.78313) (xy 181.431793 -357.768867)
			(xy 181.429265 -357.740068) (xy 181.418763 -357.713134) (xy 181.401128 -357.690227) (xy 181.377777 -357.673184)
			(xy 181.350583 -357.663373) (xy 181.336188 -357.661972) (xy 181.307535 -357.659599) (xy 181.25137 -357.64731)
			(xy 181.197685 -357.626735) (xy 181.147693 -357.598338) (xy 181.102528 -357.562763) (xy 181.063211 -357.520815)
			(xy 181.030633 -357.473442) (xy 181.00553 -357.421719) (xy 180.98847 -357.366815) (xy 180.979841 -357.309973)
			(xy 180.979318 -357.281226) (xy 180.116647 -357.281226) (xy 180.116988 -357.300276) (xy 180.116428 -357.32872)
			(xy 180.107979 -357.384978) (xy 180.091264 -357.439356) (xy 180.066654 -357.490646) (xy 180.034696 -357.53771)
			(xy 179.9961 -357.579502) (xy 179.97424 -357.59771) (xy 179.96281 -357.6077) (xy 179.945787 -357.632808)
			(xy 179.93688 -357.661806) (xy 179.936872 -357.692141) (xy 179.945764 -357.721144) (xy 179.962774 -357.746261)
			(xy 179.97424 -357.756206) (xy 179.99611 -357.774404) (xy 180.034716 -357.816194) (xy 180.066681 -357.863258)
			(xy 180.091296 -357.914551) (xy 180.108014 -357.968932) (xy 180.110284 -357.984044) (xy 180.369462 -357.984044)
			(xy 180.373533 -357.928422) (xy 180.385659 -357.873985) (xy 180.405582 -357.821894) (xy 180.432878 -357.773259)
			(xy 180.466964 -357.729116) (xy 180.507113 -357.690407) (xy 180.552471 -357.657956) (xy 180.602071 -357.632455)
			(xy 180.654855 -357.614448) (xy 180.709698 -357.604318) (xy 180.765432 -357.602281) (xy 180.820869 -357.608381)
			(xy 180.874826 -357.622487) (xy 180.926155 -357.644299) (xy 180.973761 -357.673353) (xy 181.016629 -357.709028)
			(xy 181.053846 -357.750565) (xy 181.084619 -357.797078) (xy 181.108291 -357.847575) (xy 181.124359 -357.900982)
			(xy 181.132479 -357.956158) (xy 181.132988 -357.984044) (xy 181.132479 -358.01193) (xy 181.124359 -358.067106)
			(xy 181.108291 -358.120513) (xy 181.084619 -358.17101) (xy 181.053846 -358.217523) (xy 181.016629 -358.25906)
			(xy 180.973761 -358.294735) (xy 180.926155 -358.323789) (xy 180.874826 -358.345601) (xy 180.820869 -358.359707)
			(xy 180.765432 -358.365807) (xy 180.709698 -358.36377) (xy 180.654855 -358.35364) (xy 180.602071 -358.335633)
			(xy 180.552471 -358.310132) (xy 180.507113 -358.277681) (xy 180.466964 -358.238972) (xy 180.432878 -358.194829)
			(xy 180.405582 -358.146194) (xy 180.385659 -358.094103) (xy 180.373533 -358.039666) (xy 180.369462 -357.984044)
			(xy 180.110284 -357.984044) (xy 180.116464 -358.025193) (xy 180.116988 -358.05364) (xy 180.116559 -358.080893)
			(xy 180.108797 -358.134844) (xy 180.093436 -358.187141) (xy 180.070788 -358.23672) (xy 180.041316 -358.282571)
			(xy 180.005619 -358.323761) (xy 179.964423 -358.359452) (xy 179.918567 -358.388917) (xy 179.868985 -358.411557)
			(xy 179.816685 -358.42691) (xy 179.762733 -358.434664) (xy 179.73548 -358.435148) (xy 179.708746 -358.434678)
			(xy 179.655801 -358.427222) (xy 179.604416 -358.412445) (xy 179.555598 -358.390636) (xy 179.510305 -358.362223)
			(xy 179.469423 -358.327764) (xy 179.451254 -358.308148) (xy 179.301902 -358.308148) (xy 178.883818 -358.725978)
			(xy 178.865718 -358.74321) (xy 178.824154 -358.770949) (xy 178.777982 -358.790053) (xy 178.728971 -358.799791)
			(xy 178.703986 -358.8004) (xy 176.379378 -358.8004) (xy 175.814736 -359.365042) (xy 175.803814 -359.375456)
			(xy 175.802544 -359.376472) (xy 175.423576 -359.75544) (xy 175.405475 -359.77269) (xy 175.363933 -359.800504)
			(xy 175.317763 -359.81968) (xy 175.26874 -359.82948) (xy 175.243744 -359.830116) (xy 173.968918 -359.830116)
			(xy 173.082458 -360.716322) (xy 173.064332 -360.733526) (xy 173.022779 -360.761272) (xy 172.976614 -360.780385)
			(xy 172.927608 -360.790131) (xy 172.902626 -360.790744) (xy 137.079482 -360.790744) (xy 135.56742 -362.302806)
			(xy 144.555972 -362.302806) (xy 144.555972 -361.820968) (xy 144.556472 -361.785307) (xy 144.564458 -361.714433)
			(xy 144.580328 -361.644898) (xy 144.603885 -361.577578) (xy 144.63483 -361.513319) (xy 144.672776 -361.452928)
			(xy 144.717245 -361.397166) (xy 144.767678 -361.346733) (xy 144.82344 -361.302264) (xy 144.883831 -361.264318)
			(xy 144.94809 -361.233373) (xy 145.01541 -361.209816) (xy 145.084945 -361.193946) (xy 145.155819 -361.18596)
			(xy 145.227141 -361.18596) (xy 145.298015 -361.193946) (xy 145.36755 -361.209816) (xy 145.43487 -361.233373)
			(xy 145.499129 -361.264318) (xy 145.55952 -361.302264) (xy 145.615282 -361.346733) (xy 145.665715 -361.397166)
			(xy 145.710184 -361.452928) (xy 145.74813 -361.513319) (xy 145.779075 -361.577578) (xy 145.802632 -361.644898)
			(xy 145.806295 -361.660948) (xy 145.977862 -361.660948) (xy 145.981933 -361.605326) (xy 145.994059 -361.550889)
			(xy 146.013982 -361.498798) (xy 146.041278 -361.450163) (xy 146.075364 -361.40602) (xy 146.115513 -361.367311)
			(xy 146.160871 -361.33486) (xy 146.210471 -361.309359) (xy 146.263255 -361.291352) (xy 146.318098 -361.281222)
			(xy 146.373832 -361.279185) (xy 146.429269 -361.285285) (xy 146.483226 -361.299391) (xy 146.534555 -361.321203)
			(xy 146.582161 -361.350257) (xy 146.625029 -361.385932) (xy 146.662246 -361.427469) (xy 146.693019 -361.473982)
			(xy 146.716691 -361.524479) (xy 146.732759 -361.577886) (xy 146.740879 -361.633062) (xy 146.741388 -361.660948)
			(xy 146.740879 -361.688834) (xy 146.732759 -361.74401) (xy 146.716691 -361.797417) (xy 146.693019 -361.847914)
			(xy 146.662246 -361.894427) (xy 146.625029 -361.935964) (xy 146.582161 -361.971639) (xy 146.534555 -362.000693)
			(xy 146.483226 -362.022505) (xy 146.429269 -362.036611) (xy 146.373832 -362.042711) (xy 146.318098 -362.040674)
			(xy 146.263255 -362.030544) (xy 146.210471 -362.012537) (xy 146.160871 -361.987036) (xy 146.115513 -361.954585)
			(xy 146.075364 -361.915876) (xy 146.041278 -361.871733) (xy 146.013982 -361.823098) (xy 145.994059 -361.771007)
			(xy 145.981933 -361.71657) (xy 145.977862 -361.660948) (xy 145.806295 -361.660948) (xy 145.818502 -361.714433)
			(xy 145.826488 -361.785307) (xy 145.826988 -361.820968) (xy 145.826988 -362.039662) (xy 146.099276 -362.312204)
			(xy 163.63696 -362.312204) (xy 163.672577 -362.312686) (xy 163.743361 -362.320685) (xy 163.812806 -362.336552)
			(xy 163.88004 -362.360089) (xy 163.944219 -362.391) (xy 164.004536 -362.428897) (xy 164.060235 -362.473304)
			(xy 164.085778 -362.498132) (xy 164.199316 -362.61167) (xy 165.871652 -362.61167) (xy 165.872125 -362.585292)
			(xy 165.879381 -362.533037) (xy 165.893763 -362.482279) (xy 165.914999 -362.433985) (xy 165.942682 -362.389075)
			(xy 165.976287 -362.348406) (xy 166.015172 -362.312752) (xy 166.058596 -362.282793) (xy 166.081964 -362.270548)
			(xy 166.094349 -362.263891) (xy 166.115081 -362.244908) (xy 166.129843 -362.220985) (xy 166.137514 -362.193942)
			(xy 166.13751 -362.165831) (xy 166.129833 -362.13879) (xy 166.115064 -362.114872) (xy 166.094327 -362.095894)
			(xy 166.081964 -362.089192) (xy 166.058615 -362.076913) (xy 166.015193 -362.046954) (xy 165.976308 -362.011304)
			(xy 165.942702 -361.970639) (xy 165.915013 -361.925736) (xy 165.893768 -361.877449) (xy 165.879373 -361.826697)
			(xy 165.872102 -361.774447) (xy 165.871652 -361.74807) (xy 165.872138 -361.720819) (xy 165.879894 -361.666871)
			(xy 165.895249 -361.614576) (xy 165.917891 -361.564999) (xy 165.947357 -361.519149) (xy 165.983048 -361.477958)
			(xy 166.024239 -361.442267) (xy 166.070089 -361.412801) (xy 166.119666 -361.390159) (xy 166.171961 -361.374804)
			(xy 166.225909 -361.367048) (xy 166.280411 -361.367048) (xy 166.334359 -361.374804) (xy 166.386654 -361.390159)
			(xy 166.436231 -361.412801) (xy 166.482081 -361.442267) (xy 166.523272 -361.477958) (xy 166.558801 -361.518962)
			(xy 175.165258 -361.518962) (xy 175.165781 -361.489792) (xy 175.174688 -361.432135) (xy 175.192271 -361.376507)
			(xy 175.218122 -361.324205) (xy 175.251636 -361.276451) (xy 175.292033 -361.234359) (xy 175.314864 -361.216194)
			(xy 175.325211 -361.207738) (xy 175.341501 -361.186567) (xy 175.351744 -361.161896) (xy 175.355241 -361.135413)
			(xy 175.351751 -361.10893) (xy 175.341514 -361.084257) (xy 175.32523 -361.063081) (xy 175.314864 -361.05465)
			(xy 175.292028 -361.036491) (xy 175.251629 -360.994402) (xy 175.218116 -360.946647) (xy 175.192271 -360.894343)
			(xy 175.1747 -360.838712) (xy 175.165812 -360.781052) (xy 175.165258 -360.751882) (xy 175.165761 -360.724632)
			(xy 175.173519 -360.670687) (xy 175.188875 -360.618394) (xy 175.211515 -360.568819) (xy 175.24098 -360.52297)
			(xy 175.27667 -360.481781) (xy 175.317858 -360.44609) (xy 175.363705 -360.416623) (xy 175.413279 -360.39398)
			(xy 175.465571 -360.378622) (xy 175.519516 -360.370862) (xy 175.546766 -360.370374) (xy 175.575683 -360.370889)
			(xy 175.632856 -360.379614) (xy 175.688056 -360.396871) (xy 175.740019 -360.422263) (xy 175.787552 -360.455209)
			(xy 175.829567 -360.494953) (xy 175.847756 -360.51744) (xy 175.857653 -360.529245) (xy 175.882977 -360.546764)
			(xy 175.91237 -360.55594) (xy 175.943162 -360.55594) (xy 175.972555 -360.546764) (xy 175.997879 -360.529245)
			(xy 176.007776 -360.51744) (xy 176.025991 -360.494976) (xy 176.068004 -360.455238) (xy 176.115534 -360.422296)
			(xy 176.167491 -360.396903) (xy 176.222685 -360.379643) (xy 176.279851 -360.370911) (xy 176.308766 -360.370374)
			(xy 176.337312 -360.37093) (xy 176.393765 -360.379443) (xy 176.44832 -360.396269) (xy 176.499761 -360.421033)
			(xy 176.52365 -360.436668) (xy 176.534772 -360.443765) (xy 176.559632 -360.452568) (xy 176.585919 -360.45469)
			(xy 176.61187 -360.449989) (xy 176.635742 -360.438781) (xy 176.655935 -360.421817) (xy 176.663858 -360.411268)
			(xy 176.679265 -360.390252) (xy 176.714864 -360.352198) (xy 176.75531 -360.31934) (xy 176.799849 -360.29229)
			(xy 176.847654 -360.27155) (xy 176.897835 -360.257507) (xy 176.949461 -360.25042) (xy 176.975516 -360.249978)
			(xy 177.004432 -360.250527) (xy 177.061603 -360.259246) (xy 177.116803 -360.276496) (xy 177.168765 -360.301881)
			(xy 177.2163 -360.334821) (xy 177.258316 -360.37456) (xy 177.276506 -360.397044) (xy 177.286403 -360.408849)
			(xy 177.311727 -360.426368) (xy 177.34112 -360.435544) (xy 177.371912 -360.435544) (xy 177.401305 -360.426368)
			(xy 177.426629 -360.408849) (xy 177.436526 -360.397044) (xy 177.454713 -360.374557) (xy 177.496733 -360.33482)
			(xy 177.544268 -360.30188) (xy 177.59623 -360.276492) (xy 177.651429 -360.259237) (xy 177.7086 -360.250511)
			(xy 177.737516 -360.249978) (xy 177.764767 -360.250463) (xy 177.818714 -360.258221) (xy 177.871008 -360.273578)
			(xy 177.920584 -360.29622) (xy 177.966434 -360.325686) (xy 178.007624 -360.361378) (xy 178.043315 -360.402568)
			(xy 178.072781 -360.448417) (xy 178.095423 -360.497994) (xy 178.110779 -360.550288) (xy 178.118537 -360.604235)
			(xy 178.119024 -360.631486) (xy 178.118573 -360.657529) (xy 178.111489 -360.70913) (xy 178.097451 -360.759287)
			(xy 178.076719 -360.807069) (xy 178.04968 -360.851586) (xy 178.016836 -360.89201) (xy 177.99812 -360.910124)
			(xy 177.988141 -360.920052) (xy 177.973673 -360.94419) (xy 177.966332 -360.971357) (xy 177.966673 -360.999497)
			(xy 177.97467 -361.026479) (xy 177.989718 -361.050259) (xy 177.999898 -361.059984) (xy 178.019495 -361.07813)
			(xy 178.053888 -361.118993) (xy 178.082244 -361.164254) (xy 178.104009 -361.213028) (xy 178.118757 -361.264362)
			(xy 178.1262 -361.317251) (xy 178.126644 -361.343956) (xy 178.126102 -361.371724) (xy 178.118056 -361.426674)
			(xy 178.102127 -361.479877) (xy 178.078653 -361.530208) (xy 178.048129 -361.576604) (xy 178.011201 -361.618083)
			(xy 177.990246 -361.63631) (xy 177.979642 -361.645881) (xy 177.963652 -361.66953) (xy 177.954852 -361.696687)
			(xy 177.953933 -361.725219) (xy 177.960967 -361.752886) (xy 177.975402 -361.777515) (xy 177.98542 -361.787694)
			(xy 178.003747 -361.805801) (xy 178.035923 -361.846035) (xy 178.062396 -361.890231) (xy 178.082685 -361.937585)
			(xy 178.096422 -361.987238) (xy 178.103357 -362.038287) (xy 178.103784 -362.064046) (xy 178.10329 -362.091415)
			(xy 178.09548 -362.145593) (xy 178.079997 -362.198096) (xy 178.057162 -362.247844) (xy 178.027443 -362.293812)
			(xy 178.009804 -362.314744) (xy 178.000523 -362.326038) (xy 177.98835 -362.352608) (xy 177.984186 -362.381535)
			(xy 177.98837 -362.410459) (xy 178.00056 -362.437021) (xy 178.009804 -362.448348) (xy 178.027488 -362.469245)
			(xy 178.057209 -362.51522) (xy 178.08005 -362.564972) (xy 178.095541 -362.617479) (xy 178.103365 -362.671662)
			(xy 178.10336 -362.726407) (xy 178.095526 -362.780589) (xy 178.080025 -362.833093) (xy 178.057176 -362.882841)
			(xy 178.027447 -362.928811) (xy 178.009804 -362.949744) (xy 178.000523 -362.961038) (xy 177.98835 -362.987608)
			(xy 177.984186 -363.016535) (xy 177.98837 -363.045459) (xy 178.00056 -363.072021) (xy 178.009804 -363.083348)
			(xy 178.027433 -363.104288) (xy 178.057146 -363.150259) (xy 178.059513 -363.155414) (xy 179.144926 -363.155414)
			(xy 179.144926 -363.070718) (xy 179.152977 -362.986404) (xy 179.169006 -362.903238) (xy 179.192867 -362.821971)
			(xy 179.224346 -362.743341) (xy 179.263157 -362.66806) (xy 179.308947 -362.596808) (xy 179.361303 -362.530232)
			(xy 179.419751 -362.468934) (xy 179.483761 -362.413469) (xy 179.552753 -362.36434) (xy 179.626103 -362.321991)
			(xy 179.703146 -362.286807) (xy 179.783185 -362.259105) (xy 179.865494 -362.239137) (xy 179.949329 -362.227084)
			(xy 180.03393 -362.223054) (xy 180.118531 -362.227084) (xy 180.202366 -362.239137) (xy 180.284675 -362.259105)
			(xy 180.364714 -362.286807) (xy 180.441757 -362.321991) (xy 180.515107 -362.36434) (xy 180.584099 -362.413469)
			(xy 180.648109 -362.468934) (xy 180.706557 -362.530232) (xy 180.758913 -362.596808) (xy 180.804703 -362.66806)
			(xy 180.843514 -362.743341) (xy 180.874993 -362.821971) (xy 180.898854 -362.903238) (xy 180.914883 -362.986404)
			(xy 180.922934 -363.070718) (xy 180.923438 -363.113066) (xy 181.669439 -363.113066) (xy 181.673475 -363.029619)
			(xy 181.685547 -362.946951) (xy 181.70554 -362.865834) (xy 181.733269 -362.787025) (xy 181.768475 -362.71126)
			(xy 181.810829 -362.639247) (xy 181.859935 -362.571658) (xy 181.915336 -362.509124) (xy 181.976513 -362.452229)
			(xy 182.042896 -362.401503) (xy 182.113864 -362.357422) (xy 182.188756 -362.320396) (xy 182.266872 -362.29077)
			(xy 182.347482 -362.268822) (xy 182.429834 -362.254757) (xy 182.51316 -362.248705) (xy 182.59668 -362.250724)
			(xy 182.679616 -362.260794) (xy 182.761192 -362.278822) (xy 182.840648 -362.304639) (xy 182.917241 -362.338004)
			(xy 182.990257 -362.378605) (xy 183.059013 -362.426064) (xy 183.122867 -362.479937) (xy 183.181224 -362.539722)
			(xy 183.233539 -362.604859) (xy 183.279322 -362.674742) (xy 183.318147 -362.748717) (xy 183.349652 -362.826094)
			(xy 183.373541 -362.906151) (xy 183.389592 -362.988139) (xy 183.397655 -363.071294) (xy 183.39816 -363.113066)
			(xy 183.397655 -363.154838) (xy 183.389592 -363.237993) (xy 183.373541 -363.319981) (xy 183.349652 -363.400038)
			(xy 183.318147 -363.477415) (xy 183.279322 -363.55139) (xy 183.233539 -363.621273) (xy 183.181224 -363.68641)
			(xy 183.122867 -363.746195) (xy 183.059013 -363.800068) (xy 182.990257 -363.847527) (xy 182.917241 -363.888128)
			(xy 182.840648 -363.921493) (xy 182.761192 -363.94731) (xy 182.679616 -363.965338) (xy 182.59668 -363.975408)
			(xy 182.51316 -363.977427) (xy 182.429834 -363.971375) (xy 182.347482 -363.95731) (xy 182.266872 -363.935362)
			(xy 182.188756 -363.905736) (xy 182.113864 -363.86871) (xy 182.042896 -363.824629) (xy 181.976513 -363.773903)
			(xy 181.915336 -363.717008) (xy 181.859935 -363.654474) (xy 181.810829 -363.586885) (xy 181.768475 -363.514872)
			(xy 181.733269 -363.439107) (xy 181.70554 -363.360298) (xy 181.685547 -363.279181) (xy 181.673475 -363.196513)
			(xy 181.669439 -363.113066) (xy 180.923438 -363.113066) (xy 180.922934 -363.155414) (xy 180.914883 -363.239728)
			(xy 180.898854 -363.322894) (xy 180.874993 -363.404161) (xy 180.843514 -363.482791) (xy 180.804703 -363.558072)
			(xy 180.758913 -363.629324) (xy 180.706557 -363.6959) (xy 180.648109 -363.757198) (xy 180.584099 -363.812663)
			(xy 180.515107 -363.861792) (xy 180.441757 -363.904141) (xy 180.364714 -363.939325) (xy 180.284675 -363.967027)
			(xy 180.202366 -363.986995) (xy 180.118531 -363.999048) (xy 180.03393 -364.003079) (xy 179.949329 -363.999048)
			(xy 179.865494 -363.986995) (xy 179.783185 -363.967027) (xy 179.703146 -363.939325) (xy 179.626103 -363.904141)
			(xy 179.552753 -363.861792) (xy 179.483761 -363.812663) (xy 179.419751 -363.757198) (xy 179.361303 -363.6959)
			(xy 179.308947 -363.629324) (xy 179.263157 -363.558072) (xy 179.224346 -363.482791) (xy 179.192867 -363.404161)
			(xy 179.169006 -363.322894) (xy 179.152977 -363.239728) (xy 179.144926 -363.155414) (xy 178.059513 -363.155414)
			(xy 178.079984 -363.200004) (xy 178.095477 -363.252503) (xy 178.103308 -363.306677) (xy 178.103784 -363.334046)
			(xy 178.103365 -363.361299) (xy 178.095601 -363.415251) (xy 178.080239 -363.467548) (xy 178.057591 -363.517127)
			(xy 178.028118 -363.562979) (xy 177.992419 -363.604169) (xy 177.951222 -363.63986) (xy 177.905366 -363.669325)
			(xy 177.855783 -363.691964) (xy 177.803482 -363.707316) (xy 177.74953 -363.71507) (xy 177.722276 -363.715554)
			(xy 177.69336 -363.714998) (xy 177.63619 -363.706279) (xy 177.580991 -363.68903) (xy 177.529029 -363.663645)
			(xy 177.481494 -363.630708) (xy 177.439477 -363.590971) (xy 177.421286 -363.568488) (xy 177.411389 -363.556683)
			(xy 177.386065 -363.539164) (xy 177.356672 -363.529988) (xy 177.32588 -363.529988) (xy 177.296487 -363.539164)
			(xy 177.271163 -363.556683) (xy 177.261266 -363.568488) (xy 177.243091 -363.590985) (xy 177.201068 -363.63072)
			(xy 177.15353 -363.663658) (xy 177.101566 -363.689044) (xy 177.046365 -363.706297) (xy 176.989193 -363.715022)
			(xy 176.960276 -363.715554) (xy 176.933026 -363.715045) (xy 176.879082 -363.707286) (xy 176.82679 -363.69193)
			(xy 176.777216 -363.66929) (xy 176.731368 -363.639825) (xy 176.690179 -363.604136) (xy 176.654488 -363.56295)
			(xy 176.625021 -363.517103) (xy 176.602377 -363.46753) (xy 176.587019 -363.41524) (xy 176.579257 -363.361296)
			(xy 176.578768 -363.334046) (xy 176.579244 -363.306676) (xy 176.587057 -363.252497) (xy 176.602543 -363.199993)
			(xy 176.625383 -363.150246) (xy 176.655107 -363.104279) (xy 176.672748 -363.083348) (xy 176.681937 -363.071986)
			(xy 176.694114 -363.04544) (xy 176.698293 -363.016535) (xy 176.694133 -362.987627) (xy 176.681975 -362.961073)
			(xy 176.672748 -362.949744) (xy 176.655151 -362.928775) (xy 176.625423 -362.882814) (xy 176.602574 -362.833074)
			(xy 176.587073 -362.780577) (xy 176.57924 -362.726403) (xy 176.579235 -362.671666) (xy 176.587058 -362.617491)
			(xy 176.60255 -362.564991) (xy 176.62539 -362.515247) (xy 176.65511 -362.46928) (xy 176.672748 -362.448348)
			(xy 176.681937 -362.436986) (xy 176.694114 -362.41044) (xy 176.698293 -362.381535) (xy 176.694133 -362.352627)
			(xy 176.681975 -362.326073) (xy 176.672748 -362.314744) (xy 176.655124 -362.2938) (xy 176.625408 -362.247831)
			(xy 176.602568 -362.198087) (xy 176.587074 -362.145589) (xy 176.579243 -362.091414) (xy 176.578768 -362.064046)
			(xy 176.578999 -362.044991) (xy 176.582819 -362.007073) (xy 176.586388 -361.988354) (xy 176.588705 -361.97488)
			(xy 176.586854 -361.947611) (xy 176.577837 -361.92181) (xy 176.562301 -361.899324) (xy 176.541357 -361.881763)
			(xy 176.516507 -361.870386) (xy 176.489529 -361.866007) (xy 176.462355 -361.868939) (xy 176.449482 -361.873546)
			(xy 176.427016 -361.882082) (xy 176.380475 -361.894068) (xy 176.332796 -361.900107) (xy 176.308766 -361.90047)
			(xy 176.27985 -361.899916) (xy 176.22268 -361.891196) (xy 176.167482 -361.873946) (xy 176.115519 -361.848561)
			(xy 176.067985 -361.815623) (xy 176.025967 -361.775887) (xy 176.007776 -361.753404) (xy 175.997879 -361.741599)
			(xy 175.972555 -361.72408) (xy 175.943162 -361.714904) (xy 175.91237 -361.714904) (xy 175.882977 -361.72408)
			(xy 175.857653 -361.741599) (xy 175.847756 -361.753404) (xy 175.829591 -361.775909) (xy 175.787566 -361.815643)
			(xy 175.740025 -361.848579) (xy 175.688059 -361.873964) (xy 175.632857 -361.891215) (xy 175.575684 -361.899938)
			(xy 175.546766 -361.90047) (xy 175.519511 -361.900077) (xy 175.465555 -361.892314) (xy 175.413254 -361.876952)
			(xy 175.363671 -361.854303) (xy 175.317816 -361.824827) (xy 175.276623 -361.789126) (xy 175.240929 -361.747926)
			(xy 175.211463 -361.702066) (xy 175.188823 -361.652479) (xy 175.173471 -361.600174) (xy 175.165718 -361.546218)
			(xy 175.165258 -361.518962) (xy 166.558801 -361.518962) (xy 166.558963 -361.519149) (xy 166.588429 -361.564999)
			(xy 166.611071 -361.614576) (xy 166.626426 -361.666871) (xy 166.634182 -361.720819) (xy 166.634668 -361.74807)
			(xy 166.634272 -361.774451) (xy 166.627009 -361.826712) (xy 166.612618 -361.877474) (xy 166.591373 -361.92577)
			(xy 166.563678 -361.97068) (xy 166.530062 -362.011347) (xy 166.491166 -362.046998) (xy 166.44773 -362.076951)
			(xy 166.424356 -362.089192) (xy 166.412022 -362.095936) (xy 166.391291 -362.114903) (xy 166.376527 -362.138809)
			(xy 166.368852 -362.165838) (xy 166.368848 -362.193935) (xy 166.376517 -362.220966) (xy 166.391274 -362.244876)
			(xy 166.411999 -362.263848) (xy 166.424356 -362.270548) (xy 166.447727 -362.282788) (xy 166.491148 -362.312753)
			(xy 166.530032 -362.34841) (xy 166.563637 -362.38908) (xy 166.591323 -362.433988) (xy 166.612564 -362.482281)
			(xy 166.626954 -362.533037) (xy 166.634221 -362.585291) (xy 166.634668 -362.61167) (xy 166.634182 -362.638921)
			(xy 166.626426 -362.692869) (xy 166.611071 -362.745164) (xy 166.588429 -362.794741) (xy 166.558963 -362.840591)
			(xy 166.523272 -362.881782) (xy 166.482081 -362.917473) (xy 166.436231 -362.946939) (xy 166.386654 -362.969581)
			(xy 166.334359 -362.984936) (xy 166.280411 -362.992692) (xy 166.225909 -362.992692) (xy 166.171961 -362.984936)
			(xy 166.119666 -362.969581) (xy 166.070089 -362.946939) (xy 166.024239 -362.917473) (xy 165.983048 -362.881782)
			(xy 165.947357 -362.840591) (xy 165.917891 -362.794741) (xy 165.895249 -362.745164) (xy 165.879894 -362.692869)
			(xy 165.872138 -362.638921) (xy 165.871652 -362.61167) (xy 164.199316 -362.61167) (xy 165.722808 -364.135162)
			(xy 165.747658 -364.160682) (xy 165.792055 -364.216389) (xy 165.828142 -364.273846) (xy 169.455338 -364.273846)
			(xy 169.455875 -364.24493) (xy 169.464598 -364.187759) (xy 169.481851 -364.13256) (xy 169.507239 -364.080597)
			(xy 169.54018 -364.033063) (xy 169.579919 -363.991046) (xy 169.602404 -363.972856) (xy 169.614161 -363.962907)
			(xy 169.631677 -363.937597) (xy 169.640856 -363.908218) (xy 169.640864 -363.877438) (xy 169.631702 -363.848054)
			(xy 169.614201 -363.822734) (xy 169.602404 -363.812836) (xy 169.579939 -363.794624) (xy 169.540202 -363.752608)
			(xy 169.507261 -363.705078) (xy 169.481869 -363.653121) (xy 169.464609 -363.597927) (xy 169.455876 -363.540761)
			(xy 169.455338 -363.511846) (xy 169.455822 -363.484476) (xy 169.463634 -363.430298) (xy 169.479118 -363.377794)
			(xy 169.501956 -363.328047) (xy 169.531678 -363.28208) (xy 169.549318 -363.261148) (xy 169.558509 -363.249787)
			(xy 169.57069 -363.223241) (xy 169.57487 -363.194335) (xy 169.570709 -363.165426) (xy 169.558547 -363.138872)
			(xy 169.549318 -363.127544) (xy 169.531723 -363.106575) (xy 169.501997 -363.060613) (xy 169.479149 -363.010873)
			(xy 169.46365 -362.958376) (xy 169.455817 -362.904203) (xy 169.455812 -362.849466) (xy 169.463635 -362.795292)
			(xy 169.479125 -362.742792) (xy 169.501963 -362.693048) (xy 169.531681 -362.647081) (xy 169.549318 -362.626148)
			(xy 169.558509 -362.614787) (xy 169.57069 -362.588241) (xy 169.57487 -362.559335) (xy 169.570709 -362.530426)
			(xy 169.558547 -362.503872) (xy 169.549318 -362.492544) (xy 169.531689 -362.471604) (xy 169.501975 -362.425634)
			(xy 169.479137 -362.375888) (xy 169.463643 -362.323389) (xy 169.455813 -362.269215) (xy 169.455338 -362.241846)
			(xy 169.455798 -362.214592) (xy 169.46355 -362.160639) (xy 169.478903 -362.108338) (xy 169.501543 -362.058755)
			(xy 169.531011 -362.012899) (xy 169.566705 -361.971705) (xy 169.607899 -361.936011) (xy 169.653755 -361.906543)
			(xy 169.703338 -361.883903) (xy 169.755639 -361.86855) (xy 169.809592 -361.860798) (xy 169.836846 -361.860338)
			(xy 169.864216 -361.860826) (xy 169.918394 -361.868637) (xy 169.970897 -361.884121) (xy 170.020645 -361.906958)
			(xy 170.066612 -361.936678) (xy 170.087544 -361.954318) (xy 170.098872 -361.963554) (xy 170.125429 -361.97573)
			(xy 170.154346 -361.979903) (xy 170.183263 -361.97573) (xy 170.20982 -361.963554) (xy 170.221148 -361.954318)
			(xy 170.242091 -361.936693) (xy 170.288061 -361.906978) (xy 170.337805 -361.884139) (xy 170.390304 -361.868645)
			(xy 170.444478 -361.860814) (xy 170.471846 -361.860338) (xy 170.500762 -361.860881) (xy 170.557933 -361.869602)
			(xy 170.613132 -361.886855) (xy 170.665094 -361.912242) (xy 170.712628 -361.945182) (xy 170.754646 -361.98492)
			(xy 170.772836 -362.007404) (xy 170.782733 -362.019209) (xy 170.808057 -362.036728) (xy 170.83745 -362.045904)
			(xy 170.868242 -362.045904) (xy 170.897635 -362.036728) (xy 170.922959 -362.019209) (xy 170.932856 -362.007404)
			(xy 170.951073 -361.984942) (xy 170.993087 -361.945206) (xy 171.040617 -361.912264) (xy 171.092573 -361.886872)
			(xy 171.147766 -361.869611) (xy 171.204932 -361.860876) (xy 171.233846 -361.860338) (xy 171.2611 -361.860735)
			(xy 171.315054 -361.868499) (xy 171.367353 -361.883862) (xy 171.416933 -361.906512) (xy 171.462786 -361.935988)
			(xy 171.503977 -361.971688) (xy 171.539668 -362.012888) (xy 171.569132 -362.058747) (xy 171.59177 -362.108333)
			(xy 171.60712 -362.160636) (xy 171.614871 -362.214591) (xy 171.615354 -362.241846) (xy 171.614867 -362.269216)
			(xy 171.607056 -362.323394) (xy 171.591573 -362.375898) (xy 171.568735 -362.425645) (xy 171.539014 -362.471612)
			(xy 171.521374 -362.492544) (xy 171.512095 -362.503839) (xy 171.499926 -362.530409) (xy 171.495763 -362.559335)
			(xy 171.499946 -362.588258) (xy 171.512133 -362.61482) (xy 171.521374 -362.626148) (xy 171.532804 -362.639864)
			(xy 171.542155 -362.650819) (xy 171.565655 -362.667446) (xy 171.592863 -362.676855) (xy 171.621615 -362.678296)
			(xy 171.649627 -362.671655) (xy 171.674673 -362.657461) (xy 171.694761 -362.63684) (xy 171.701968 -362.62437)
			(xy 171.716343 -362.59857) (xy 171.751735 -362.551293) (xy 171.793987 -362.510033) (xy 171.842091 -362.475774)
			(xy 171.894898 -362.449334) (xy 171.951148 -362.431345) (xy 172.009498 -362.422236) (xy 172.039026 -362.421678)
			(xy 172.066277 -362.422154) (xy 172.120225 -362.429913) (xy 172.172519 -362.445271) (xy 172.222095 -362.467914)
			(xy 172.267945 -362.497382) (xy 172.309134 -362.533074) (xy 172.344825 -362.574265) (xy 172.374292 -362.620115)
			(xy 172.396933 -362.669693) (xy 172.412289 -362.721987) (xy 172.420047 -362.775935) (xy 172.420534 -362.803186)
			(xy 172.420076 -362.830557) (xy 172.412259 -362.884737) (xy 172.396769 -362.937241) (xy 172.373925 -362.986987)
			(xy 172.344197 -363.032953) (xy 172.326554 -363.053884) (xy 172.317334 -363.065223) (xy 172.305161 -363.091777)
			(xy 172.300988 -363.120689) (xy 172.305155 -363.149602) (xy 172.317323 -363.176159) (xy 172.326554 -363.187488)
			(xy 172.344182 -363.208431) (xy 172.373909 -363.254397) (xy 172.396756 -363.304141) (xy 172.412254 -363.356642)
			(xy 172.420084 -363.410819) (xy 172.420086 -363.46556) (xy 172.412259 -363.519737) (xy 172.396763 -363.572239)
			(xy 172.373919 -363.621985) (xy 172.344194 -363.667952) (xy 172.326554 -363.688884) (xy 172.317334 -363.700223)
			(xy 172.305161 -363.726777) (xy 172.300988 -363.755689) (xy 172.305155 -363.784602) (xy 172.317323 -363.811159)
			(xy 172.326554 -363.822488) (xy 172.344194 -363.84342) (xy 172.373907 -363.889392) (xy 172.396744 -363.939139)
			(xy 172.412234 -363.99164) (xy 172.420061 -364.045817) (xy 172.420534 -364.073186) (xy 172.420009 -364.100436)
			(xy 172.412255 -364.154381) (xy 172.396903 -364.206673) (xy 172.377828 -364.248446) (xy 172.820838 -364.248446)
			(xy 172.821375 -364.21953) (xy 172.830098 -364.162359) (xy 172.847351 -364.10716) (xy 172.872739 -364.055197)
			(xy 172.90568 -364.007663) (xy 172.945419 -363.965646) (xy 172.967904 -363.947456) (xy 172.979661 -363.937507)
			(xy 172.997177 -363.912197) (xy 173.006356 -363.882818) (xy 173.006364 -363.852038) (xy 172.997202 -363.822654)
			(xy 172.979701 -363.797334) (xy 172.967904 -363.787436) (xy 172.945439 -363.769224) (xy 172.905702 -363.727208)
			(xy 172.872761 -363.679678) (xy 172.847369 -363.627721) (xy 172.830109 -363.572527) (xy 172.821376 -363.515361)
			(xy 172.820838 -363.486446) (xy 172.821322 -363.459076) (xy 172.829134 -363.404898) (xy 172.844618 -363.352394)
			(xy 172.867456 -363.302647) (xy 172.897178 -363.25668) (xy 172.914818 -363.235748) (xy 172.924009 -363.224387)
			(xy 172.93619 -363.197841) (xy 172.94037 -363.168935) (xy 172.936209 -363.140026) (xy 172.924047 -363.113472)
			(xy 172.914818 -363.102144) (xy 172.897223 -363.081175) (xy 172.867497 -363.035213) (xy 172.844649 -362.985473)
			(xy 172.82915 -362.932976) (xy 172.821317 -362.878803) (xy 172.821312 -362.824066) (xy 172.829135 -362.769892)
			(xy 172.844625 -362.717392) (xy 172.867463 -362.667648) (xy 172.897181 -362.621681) (xy 172.914818 -362.600748)
			(xy 172.924009 -362.589387) (xy 172.93619 -362.562841) (xy 172.94037 -362.533935) (xy 172.936209 -362.505026)
			(xy 172.924047 -362.478472) (xy 172.914818 -362.467144) (xy 172.897189 -362.446204) (xy 172.867475 -362.400234)
			(xy 172.844637 -362.350488) (xy 172.829143 -362.297989) (xy 172.821313 -362.243815) (xy 172.820838 -362.216446)
			(xy 172.821324 -362.189195) (xy 172.82908 -362.135247) (xy 172.844435 -362.082952) (xy 172.867077 -362.033375)
			(xy 172.896543 -361.987525) (xy 172.932234 -361.946334) (xy 172.973425 -361.910643) (xy 173.019275 -361.881177)
			(xy 173.068852 -361.858535) (xy 173.121147 -361.84318) (xy 173.175095 -361.835424) (xy 173.229597 -361.835424)
			(xy 173.283545 -361.84318) (xy 173.33584 -361.858535) (xy 173.385417 -361.881177) (xy 173.431267 -361.910643)
			(xy 173.472458 -361.946334) (xy 173.508149 -361.987525) (xy 173.537615 -362.033375) (xy 173.560257 -362.082952)
			(xy 173.575612 -362.135247) (xy 173.583368 -362.189195) (xy 173.583854 -362.216446) (xy 173.583367 -362.243816)
			(xy 173.575556 -362.297994) (xy 173.560073 -362.350498) (xy 173.537235 -362.400245) (xy 173.507514 -362.446212)
			(xy 173.489874 -362.467144) (xy 173.480595 -362.478439) (xy 173.468426 -362.505009) (xy 173.464263 -362.533935)
			(xy 173.468446 -362.562858) (xy 173.480633 -362.58942) (xy 173.489874 -362.600748) (xy 173.50756 -362.621644)
			(xy 173.537283 -362.667618) (xy 173.560125 -362.717371) (xy 173.575618 -362.769878) (xy 173.583442 -362.824062)
			(xy 173.583437 -362.878807) (xy 173.575603 -362.932989) (xy 173.560101 -362.985494) (xy 173.537249 -363.035242)
			(xy 173.507518 -363.081211) (xy 173.489874 -363.102144) (xy 173.480595 -363.113439) (xy 173.468426 -363.140009)
			(xy 173.464263 -363.168935) (xy 173.468446 -363.197858) (xy 173.480633 -363.22442) (xy 173.489874 -363.235748)
			(xy 173.507498 -363.256692) (xy 173.537213 -363.302661) (xy 173.560052 -363.352406) (xy 173.575547 -363.404904)
			(xy 173.583378 -363.459078) (xy 173.583854 -363.486446) (xy 173.583314 -363.515362) (xy 173.574592 -363.572533)
			(xy 173.55734 -363.627733) (xy 173.531952 -363.679695) (xy 173.499012 -363.727229) (xy 173.459273 -363.769246)
			(xy 173.436788 -363.787436) (xy 173.424939 -363.797285) (xy 173.407427 -363.822623) (xy 173.398258 -363.852028)
			(xy 173.398267 -363.882829) (xy 173.407452 -363.912229) (xy 173.424978 -363.937557) (xy 173.436788 -363.947456)
			(xy 173.459248 -363.965675) (xy 173.498985 -364.007688) (xy 173.531927 -364.055217) (xy 173.55732 -364.107173)
			(xy 173.574581 -364.162366) (xy 173.583316 -364.219532) (xy 173.583854 -364.248446) (xy 173.583368 -364.275697)
			(xy 173.575612 -364.329645) (xy 173.560257 -364.38194) (xy 173.537615 -364.431517) (xy 173.508149 -364.477367)
			(xy 173.472458 -364.518558) (xy 173.431267 -364.554249) (xy 173.385417 -364.583715) (xy 173.33584 -364.606357)
			(xy 173.283545 -364.621712) (xy 173.229597 -364.629468) (xy 173.175095 -364.629468) (xy 173.121147 -364.621712)
			(xy 173.068852 -364.606357) (xy 173.019275 -364.583715) (xy 172.973425 -364.554249) (xy 172.932234 -364.518558)
			(xy 172.896543 -364.477367) (xy 172.867077 -364.431517) (xy 172.844435 -364.38194) (xy 172.82908 -364.329645)
			(xy 172.821324 -364.275697) (xy 172.820838 -364.248446) (xy 172.377828 -364.248446) (xy 172.374265 -364.256248)
			(xy 172.344803 -364.302098) (xy 172.309116 -364.343287) (xy 172.26793 -364.378979) (xy 172.222084 -364.408446)
			(xy 172.172511 -364.431089) (xy 172.12022 -364.446446) (xy 172.066276 -364.454206) (xy 172.039026 -364.454694)
			(xy 172.038772 -364.454694) (xy 172.008683 -364.454159) (xy 171.949254 -364.444695) (xy 171.892046 -364.426021)
			(xy 171.838478 -364.3986) (xy 171.789877 -364.363112) (xy 171.768262 -364.342172) (xy 171.757249 -364.331965)
			(xy 171.730832 -364.31774) (xy 171.701418 -364.311816) (xy 171.671553 -364.314704) (xy 171.64382 -364.326156)
			(xy 171.620618 -364.34518) (xy 171.603954 -364.370131) (xy 171.599098 -364.384336) (xy 171.590828 -364.410127)
			(xy 171.567947 -364.459219) (xy 171.538357 -364.504584) (xy 171.502652 -364.545312) (xy 171.461549 -364.580584)
			(xy 171.415873 -364.609692) (xy 171.366542 -364.632053) (xy 171.314545 -364.647216) (xy 171.260927 -364.654878)
			(xy 171.233846 -364.655354) (xy 171.204929 -364.65482) (xy 171.147758 -364.646097) (xy 171.092559 -364.628843)
			(xy 171.040597 -364.603455) (xy 170.993063 -364.570513) (xy 170.951046 -364.530773) (xy 170.932856 -364.508288)
			(xy 170.922959 -364.496483) (xy 170.897635 -364.478964) (xy 170.868242 -364.469788) (xy 170.83745 -364.469788)
			(xy 170.808057 -364.478964) (xy 170.782733 -364.496483) (xy 170.772836 -364.508288) (xy 170.754622 -364.530752)
			(xy 170.712607 -364.570489) (xy 170.665077 -364.60343) (xy 170.61312 -364.628822) (xy 170.557927 -364.646083)
			(xy 170.500761 -364.654816) (xy 170.471846 -364.655354) (xy 170.444476 -364.654872) (xy 170.390297 -364.64706)
			(xy 170.337794 -364.631575) (xy 170.288047 -364.608737) (xy 170.24208 -364.579014) (xy 170.221148 -364.561374)
			(xy 170.20982 -364.552138) (xy 170.183263 -364.539962) (xy 170.154346 -364.535789) (xy 170.125429 -364.539962)
			(xy 170.098872 -364.552138) (xy 170.087544 -364.561374) (xy 170.066603 -364.579002) (xy 170.020633 -364.608716)
			(xy 169.970888 -364.631555) (xy 169.918389 -364.647048) (xy 169.864215 -364.654879) (xy 169.836846 -364.655354)
			(xy 169.809598 -364.654779) (xy 169.755656 -364.64703) (xy 169.703366 -364.631683) (xy 169.653792 -364.609051)
			(xy 169.607943 -364.579594) (xy 169.566754 -364.543911) (xy 169.531062 -364.50273) (xy 169.501593 -364.456889)
			(xy 169.478949 -364.407321) (xy 169.46359 -364.355034) (xy 169.455827 -364.301094) (xy 169.455338 -364.273846)
			(xy 165.828142 -364.273846) (xy 165.829942 -364.276712) (xy 165.860844 -364.340895) (xy 165.884373 -364.408132)
			(xy 165.900233 -364.477578) (xy 165.908226 -364.548363) (xy 165.908736 -364.58398) (xy 165.908736 -365.647986)
			(xy 168.368726 -368.107722) (xy 168.393587 -368.133293) (xy 168.438068 -368.189042) (xy 168.476026 -368.249422)
			(xy 168.506983 -368.313673) (xy 168.53055 -368.380987) (xy 168.54643 -368.450517) (xy 168.554423 -368.521388)
			(xy 168.554908 -368.557048) (xy 168.554453 -368.59271) (xy 168.546462 -368.663586) (xy 168.530587 -368.733121)
			(xy 168.507026 -368.800442) (xy 168.476076 -368.864701) (xy 168.438126 -368.925091) (xy 168.393653 -368.980853)
			(xy 168.343217 -369.031285) (xy 168.287452 -369.075754) (xy 168.227059 -369.113699) (xy 168.162797 -369.144644)
			(xy 168.095475 -369.1682) (xy 168.025938 -369.184071) (xy 167.955062 -369.192056) (xy 167.9194 -369.192556)
			(xy 167.883738 -369.192112) (xy 167.812861 -369.184122) (xy 167.743327 -369.168243) (xy 167.676008 -369.144675)
			(xy 167.611753 -369.113713) (xy 167.551371 -369.075749) (xy 167.495622 -369.03126) (xy 167.470074 -369.006374)
			(xy 164.824156 -366.360456) (xy 164.799326 -366.334916) (xy 164.754926 -366.279214) (xy 164.717035 -366.218895)
			(xy 164.686129 -366.154716) (xy 164.662597 -366.087482) (xy 164.646734 -366.018037) (xy 164.638739 -365.947254)
			(xy 164.638228 -365.911638) (xy 164.638228 -364.847632) (xy 163.373308 -363.582712) (xy 145.835624 -363.582712)
			(xy 145.800009 -363.582171) (xy 145.729227 -363.574182) (xy 145.659783 -363.558324) (xy 145.59255 -363.534796)
			(xy 145.52837 -363.503895) (xy 145.468052 -363.466006) (xy 145.41235 -363.421608) (xy 145.386806 -363.396784)
			(xy 144.742154 -362.752132) (xy 144.717267 -362.726586) (xy 144.672789 -362.670832) (xy 144.634834 -362.610447)
			(xy 144.60388 -362.546192) (xy 144.580318 -362.478874) (xy 144.564442 -362.409341) (xy 144.556454 -362.338467)
			(xy 144.555972 -362.302806) (xy 135.56742 -362.302806) (xy 133.118098 -364.752128) (xy 133.100001 -364.769383)
			(xy 133.058456 -364.797192) (xy 133.012285 -364.816365) (xy 132.963262 -364.826166) (xy 132.938266 -364.826804)
			(xy 121.734326 -364.826804) (xy 120.813226 -365.747808) (xy 132.860799 -365.747808) (xy 132.864835 -365.664361)
			(xy 132.876907 -365.581693) (xy 132.8969 -365.500576) (xy 132.924629 -365.421767) (xy 132.959835 -365.346002)
			(xy 133.002189 -365.273989) (xy 133.051295 -365.2064) (xy 133.106696 -365.143866) (xy 133.167873 -365.086971)
			(xy 133.234256 -365.036245) (xy 133.305224 -364.992164) (xy 133.380116 -364.955138) (xy 133.458232 -364.925512)
			(xy 133.538842 -364.903564) (xy 133.621194 -364.889499) (xy 133.70452 -364.883447) (xy 133.78804 -364.885466)
			(xy 133.870976 -364.895536) (xy 133.952552 -364.913564) (xy 134.032008 -364.939381) (xy 134.108601 -364.972746)
			(xy 134.181617 -365.013347) (xy 134.250373 -365.060806) (xy 134.314227 -365.114679) (xy 134.372584 -365.174464)
			(xy 134.424899 -365.239601) (xy 134.470682 -365.309484) (xy 134.509507 -365.383459) (xy 134.541012 -365.460836)
			(xy 134.564901 -365.540893) (xy 134.580952 -365.622881) (xy 134.589015 -365.706036) (xy 134.58952 -365.747808)
			(xy 134.589015 -365.78958) (xy 134.580952 -365.872735) (xy 134.564901 -365.954723) (xy 134.541012 -366.03478)
			(xy 134.528065 -366.066578) (xy 138.60324 -366.066578) (xy 138.607206 -365.982047) (xy 138.619071 -365.89826)
			(xy 138.638729 -365.815951) (xy 138.666009 -365.735845) (xy 138.70067 -365.658646) (xy 138.742408 -365.585031)
			(xy 138.790855 -365.515648) (xy 138.845587 -365.451107) (xy 138.906123 -365.391975) (xy 138.971929 -365.338771)
			(xy 139.042429 -365.291963) (xy 139.117001 -365.251962) (xy 139.194992 -365.21912) (xy 139.275716 -365.193726)
			(xy 139.358463 -365.176003) (xy 139.442505 -365.166105) (xy 139.527106 -365.164122) (xy 139.61152 -365.170069)
			(xy 139.695007 -365.183894) (xy 139.776832 -365.205477) (xy 139.856276 -365.234627) (xy 139.932642 -365.271088)
			(xy 140.005258 -365.31454) (xy 140.073486 -365.364601) (xy 140.136726 -365.420831) (xy 140.194423 -365.482736)
			(xy 140.24607 -365.549772) (xy 140.291212 -365.621349) (xy 140.329454 -365.696839) (xy 140.360458 -365.775578)
			(xy 140.383953 -365.856875) (xy 140.399732 -365.940014) (xy 140.407656 -366.024266) (xy 140.408152 -366.066578)
			(xy 143.68324 -366.066578) (xy 143.687206 -365.982047) (xy 143.699071 -365.89826) (xy 143.718729 -365.815951)
			(xy 143.746009 -365.735845) (xy 143.78067 -365.658646) (xy 143.822408 -365.585031) (xy 143.870855 -365.515648)
			(xy 143.925587 -365.451107) (xy 143.986123 -365.391975) (xy 144.051929 -365.338771) (xy 144.122429 -365.291963)
			(xy 144.197001 -365.251962) (xy 144.274992 -365.21912) (xy 144.355716 -365.193726) (xy 144.438463 -365.176003)
			(xy 144.522505 -365.166105) (xy 144.607106 -365.164122) (xy 144.69152 -365.170069) (xy 144.775007 -365.183894)
			(xy 144.856832 -365.205477) (xy 144.936276 -365.234627) (xy 145.012642 -365.271088) (xy 145.085258 -365.31454)
			(xy 145.153486 -365.364601) (xy 145.216726 -365.420831) (xy 145.274423 -365.482736) (xy 145.32607 -365.549772)
			(xy 145.371212 -365.621349) (xy 145.409454 -365.696839) (xy 145.440458 -365.775578) (xy 145.463953 -365.856875)
			(xy 145.479732 -365.940014) (xy 145.487656 -366.024266) (xy 145.488152 -366.066578) (xy 145.487656 -366.10889)
			(xy 145.479732 -366.193142) (xy 145.463953 -366.276281) (xy 145.440458 -366.357578) (xy 145.409454 -366.436317)
			(xy 145.371212 -366.511807) (xy 145.32607 -366.583384) (xy 145.274423 -366.65042) (xy 145.216726 -366.712325)
			(xy 145.153486 -366.768555) (xy 145.085258 -366.818616) (xy 145.012642 -366.862068) (xy 144.936276 -366.898529)
			(xy 144.856832 -366.927679) (xy 144.775007 -366.949262) (xy 144.69152 -366.963087) (xy 144.607106 -366.969034)
			(xy 144.522505 -366.967051) (xy 144.438463 -366.957153) (xy 144.355716 -366.93943) (xy 144.274992 -366.914036)
			(xy 144.197001 -366.881194) (xy 144.122429 -366.841193) (xy 144.051929 -366.794385) (xy 143.986123 -366.741181)
			(xy 143.925587 -366.682049) (xy 143.870855 -366.617508) (xy 143.822408 -366.548125) (xy 143.78067 -366.47451)
			(xy 143.746009 -366.397311) (xy 143.718729 -366.317205) (xy 143.699071 -366.234896) (xy 143.687206 -366.151109)
			(xy 143.68324 -366.066578) (xy 140.408152 -366.066578) (xy 140.407656 -366.10889) (xy 140.399732 -366.193142)
			(xy 140.383953 -366.276281) (xy 140.360458 -366.357578) (xy 140.329454 -366.436317) (xy 140.291212 -366.511807)
			(xy 140.24607 -366.583384) (xy 140.194423 -366.65042) (xy 140.136726 -366.712325) (xy 140.073486 -366.768555)
			(xy 140.005258 -366.818616) (xy 139.932642 -366.862068) (xy 139.856276 -366.898529) (xy 139.776832 -366.927679)
			(xy 139.695007 -366.949262) (xy 139.61152 -366.963087) (xy 139.527106 -366.969034) (xy 139.442505 -366.967051)
			(xy 139.358463 -366.957153) (xy 139.275716 -366.93943) (xy 139.194992 -366.914036) (xy 139.117001 -366.881194)
			(xy 139.042429 -366.841193) (xy 138.971929 -366.794385) (xy 138.906123 -366.741181) (xy 138.845587 -366.682049)
			(xy 138.790855 -366.617508) (xy 138.742408 -366.548125) (xy 138.70067 -366.47451) (xy 138.666009 -366.397311)
			(xy 138.638729 -366.317205) (xy 138.619071 -366.234896) (xy 138.607206 -366.151109) (xy 138.60324 -366.066578)
			(xy 134.528065 -366.066578) (xy 134.509507 -366.112157) (xy 134.470682 -366.186132) (xy 134.424899 -366.256015)
			(xy 134.372584 -366.321152) (xy 134.314227 -366.380937) (xy 134.250373 -366.43481) (xy 134.181617 -366.482269)
			(xy 134.108601 -366.52287) (xy 134.032008 -366.556235) (xy 133.952552 -366.582052) (xy 133.870976 -366.60008)
			(xy 133.78804 -366.61015) (xy 133.70452 -366.612169) (xy 133.621194 -366.606117) (xy 133.538842 -366.592052)
			(xy 133.458232 -366.570104) (xy 133.380116 -366.540478) (xy 133.305224 -366.503452) (xy 133.234256 -366.459371)
			(xy 133.167873 -366.408645) (xy 133.106696 -366.35175) (xy 133.051295 -366.289216) (xy 133.002189 -366.221627)
			(xy 132.959835 -366.149614) (xy 132.924629 -366.073849) (xy 132.8969 -365.99504) (xy 132.876907 -365.913923)
			(xy 132.864835 -365.831255) (xy 132.860799 -365.747808) (xy 120.813226 -365.747808) (xy 119.297196 -367.26368)
			(xy 119.279093 -367.280928) (xy 119.237551 -367.30874) (xy 119.191382 -367.327916) (xy 119.14236 -367.337718)
			(xy 119.117364 -367.338356) (xy 109.96422 -367.338356) (xy 109.939224 -367.337714) (xy 109.890202 -367.327912)
			(xy 109.844031 -367.308741) (xy 109.802484 -367.280935) (xy 109.784388 -367.26368) (xy 109.14634 -366.625632)
			(xy 109.136044 -366.616072) (xy 109.111533 -366.602372) (xy 109.084215 -366.595874) (xy 109.056161 -366.597073)
			(xy 109.029497 -366.605877) (xy 109.006244 -366.621618) (xy 108.988165 -366.643104) (xy 108.97663 -366.668706)
			(xy 108.974128 -366.682528) (xy 108.969642 -366.709319) (xy 108.95409 -366.761365) (xy 108.931318 -366.81068)
			(xy 108.901784 -366.856269) (xy 108.866085 -366.89721) (xy 108.824943 -366.932677) (xy 108.779188 -366.961953)
			(xy 108.729745 -366.984447) (xy 108.677613 -366.999705) (xy 108.623844 -367.007417) (xy 108.596684 -367.007902)
			(xy 108.570305 -367.007443) (xy 108.518048 -367.000188) (xy 108.467289 -366.985805) (xy 108.418994 -366.964569)
			(xy 108.374084 -366.936883) (xy 108.333415 -366.903276) (xy 108.297762 -366.864388) (xy 108.267805 -366.82096)
			(xy 108.255562 -366.79759) (xy 108.24886 -366.785231) (xy 108.229885 -366.764503) (xy 108.205971 -366.749741)
			(xy 108.178935 -366.742069) (xy 108.150833 -366.742069) (xy 108.123797 -366.749741) (xy 108.099883 -366.764503)
			(xy 108.080908 -366.785231) (xy 108.074206 -366.79759) (xy 108.061972 -366.820965) (xy 108.032009 -366.86439)
			(xy 107.996354 -366.903276) (xy 107.955683 -366.936882) (xy 107.910773 -366.964569) (xy 107.862479 -366.985808)
			(xy 107.81172 -367.000196) (xy 107.759463 -367.007458) (xy 107.733084 -367.007902) (xy 107.705833 -367.007427)
			(xy 107.651886 -366.999669) (xy 107.599593 -366.984312) (xy 107.550017 -366.961669) (xy 107.504167 -366.932202)
			(xy 107.462978 -366.89651) (xy 107.427288 -366.85532) (xy 107.397823 -366.809469) (xy 107.375183 -366.759892)
			(xy 107.359828 -366.707598) (xy 107.352072 -366.653651) (xy 107.352072 -366.599149) (xy 107.359828 -366.545202)
			(xy 107.375183 -366.492908) (xy 107.397823 -366.443331) (xy 107.427288 -366.39748) (xy 107.462978 -366.35629)
			(xy 107.504167 -366.320598) (xy 107.550017 -366.291131) (xy 107.599593 -366.268488) (xy 107.651886 -366.253131)
			(xy 107.705833 -366.245373) (xy 107.733084 -366.244886) (xy 107.759465 -366.245296) (xy 107.811723 -366.252559)
			(xy 107.862484 -366.26695) (xy 107.910779 -366.288195) (xy 107.955688 -366.315887) (xy 107.996356 -366.3495)
			(xy 108.032008 -366.388394) (xy 108.061963 -366.431826) (xy 108.074206 -366.455198) (xy 108.080908 -366.467557)
			(xy 108.099883 -366.488285) (xy 108.123797 -366.503047) (xy 108.150833 -366.510719) (xy 108.178935 -366.510719)
			(xy 108.205971 -366.503047) (xy 108.229885 -366.488285) (xy 108.24886 -366.467557) (xy 108.255562 -366.455198)
			(xy 108.267815 -366.431834) (xy 108.297776 -366.38841) (xy 108.333429 -366.349524) (xy 108.374097 -366.315917)
			(xy 108.419004 -366.28823) (xy 108.467296 -366.266988) (xy 108.518052 -366.252598) (xy 108.570306 -366.245332)
			(xy 108.596684 -366.244886) (xy 108.607504 -366.244985) (xy 108.629107 -366.246255) (xy 108.639864 -366.247426)
			(xy 108.664248 -366.25022) (xy 108.717588 -366.19688) (xy 108.667296 -366.146588) (xy 108.650041 -366.128492)
			(xy 108.62223 -366.086947) (xy 108.603057 -366.040776) (xy 108.593257 -365.991752) (xy 108.59262 -365.966756)
			(xy 108.59262 -363.494066) (xy 107.254294 -362.155486) (xy 107.237059 -362.137388) (xy 107.209318 -362.095825)
			(xy 107.190213 -362.049652) (xy 107.180479 -362.000639) (xy 107.179872 -361.975654) (xy 107.179872 -356.280466)
			(xy 107.180475 -356.255482) (xy 107.19022 -356.206473) (xy 107.20933 -356.160303) (xy 107.237071 -356.118743)
			(xy 107.254294 -356.100634) (xy 108.596938 -354.757736) (xy 108.607112 -354.746756) (xy 108.621205 -354.720367)
			(xy 108.627041 -354.691024) (xy 108.624119 -354.66125) (xy 108.612689 -354.633603) (xy 108.593734 -354.610457)
			(xy 108.568881 -354.593802) (xy 108.540267 -354.585068) (xy 108.52531 -354.584508) (xy 107.526836 -354.584508)
			(xy 105.93959 -356.1715) (xy 105.921492 -356.188754) (xy 105.879948 -356.216564) (xy 105.833778 -356.235738)
			(xy 105.784754 -356.245538) (xy 105.759758 -356.246176) (xy 104.859074 -356.246176) (xy 104.834077 -356.245556)
			(xy 104.785054 -356.235747) (xy 104.738883 -356.216568) (xy 104.697338 -356.188757) (xy 104.679242 -356.1715)
			(xy 98.22307 -349.715328) (xy 98.20585 -349.697216) (xy 98.178108 -349.655658) (xy 98.158999 -349.609488)
			(xy 98.149259 -349.56048) (xy 98.148648 -349.535496) (xy 98.148648 -347.533976) (xy 97.558606 -346.944188)
			(xy 87.803228 -346.944188) (xy 84.932266 -349.814896) (xy 84.914178 -349.83216) (xy 84.87263 -349.859969)
			(xy 84.826457 -349.87914) (xy 84.777431 -349.888937) (xy 84.752434 -349.889572) (xy 79.448406 -349.889572)
			(xy 79.42341 -349.888934) (xy 79.374388 -349.87913) (xy 79.328217 -349.859957) (xy 79.28667 -349.832151)
			(xy 79.268574 -349.814896) (xy 78.519782 -349.066104) (xy 78.502553 -349.048) (xy 78.474811 -349.006439)
			(xy 78.455706 -348.960267) (xy 78.445968 -348.911256) (xy 78.44536 -348.886272) (xy 78.44536 -347.72346)
			(xy 78.425745 -347.705277) (xy 78.391242 -347.664411) (xy 78.362782 -347.619128) (xy 78.340923 -347.570315)
			(xy 78.326091 -347.518929) (xy 78.318579 -347.465975) (xy 78.318106 -347.439234) (xy 76.25842 -347.439234)
			(xy 76.25842 -350.505014) (xy 76.530962 -350.505014) (xy 76.531383 -350.478634) (xy 76.538647 -350.426376)
			(xy 76.553037 -350.375617) (xy 76.57428 -350.327322) (xy 76.601971 -350.282413) (xy 76.635582 -350.241745)
			(xy 76.674473 -350.206093) (xy 76.717903 -350.176136) (xy 76.741274 -350.163892) (xy 76.75362 -350.157169)
			(xy 76.774345 -350.138196) (xy 76.789105 -350.114286) (xy 76.796777 -350.087256) (xy 76.796779 -350.059157)
			(xy 76.78911 -350.032125) (xy 76.774353 -350.008213) (xy 76.75363 -349.989238) (xy 76.741274 -349.982536)
			(xy 76.717904 -349.970295) (xy 76.67448 -349.940332) (xy 76.635596 -349.904676) (xy 76.60199 -349.864006)
			(xy 76.574303 -349.819098) (xy 76.553063 -349.770805) (xy 76.538673 -349.720048) (xy 76.531408 -349.667793)
			(xy 76.530962 -349.641414) (xy 76.531448 -349.614163) (xy 76.539204 -349.560215) (xy 76.554559 -349.50792)
			(xy 76.577201 -349.458343) (xy 76.606667 -349.412493) (xy 76.642358 -349.371302) (xy 76.683549 -349.335611)
			(xy 76.729399 -349.306145) (xy 76.778976 -349.283503) (xy 76.831271 -349.268148) (xy 76.885219 -349.260392)
			(xy 76.939721 -349.260392) (xy 76.993669 -349.268148) (xy 77.045964 -349.283503) (xy 77.095541 -349.306145)
			(xy 77.141391 -349.335611) (xy 77.182582 -349.371302) (xy 77.218273 -349.412493) (xy 77.247739 -349.458343)
			(xy 77.270381 -349.50792) (xy 77.285736 -349.560215) (xy 77.293492 -349.614163) (xy 77.293978 -349.641414)
			(xy 77.29353 -349.667794) (xy 77.286275 -349.720051) (xy 77.271892 -349.770812) (xy 77.250654 -349.819107)
			(xy 77.222967 -349.864018) (xy 77.189357 -349.904686) (xy 77.150467 -349.940338) (xy 77.107037 -349.970294)
			(xy 77.083666 -349.982536) (xy 77.071292 -349.989214) (xy 77.050555 -350.008192) (xy 77.035789 -350.03211)
			(xy 77.028115 -350.059152) (xy 77.028117 -350.087261) (xy 77.035794 -350.114302) (xy 77.050563 -350.138218)
			(xy 77.071302 -350.157193) (xy 77.083666 -350.163892) (xy 77.107058 -350.176095) (xy 77.15048 -350.206064)
			(xy 77.189363 -350.241727) (xy 77.222966 -350.282402) (xy 77.25065 -350.327316) (xy 77.271887 -350.375614)
			(xy 77.286273 -350.426375) (xy 77.293534 -350.478634) (xy 77.29388 -350.499172) (xy 88.330532 -350.499172)
			(xy 88.33109 -350.470256) (xy 88.339809 -350.413086) (xy 88.357058 -350.357888) (xy 88.382442 -350.305926)
			(xy 88.41538 -350.258391) (xy 88.455115 -350.216373) (xy 88.477598 -350.198182) (xy 88.48943 -350.188315)
			(xy 88.506945 -350.162982) (xy 88.516117 -350.133582) (xy 88.516112 -350.102784) (xy 88.50693 -350.073387)
			(xy 88.489406 -350.04806) (xy 88.477598 -350.038162) (xy 88.455096 -350.019993) (xy 88.415362 -349.977969)
			(xy 88.382425 -349.930429) (xy 88.35704 -349.878463) (xy 88.339788 -349.823262) (xy 88.331064 -349.766089)
			(xy 88.330532 -349.737172) (xy 88.330929 -349.709917) (xy 88.338691 -349.655961) (xy 88.354052 -349.60366)
			(xy 88.376701 -349.554077) (xy 88.406176 -349.508222) (xy 88.441876 -349.467028) (xy 88.483076 -349.431335)
			(xy 88.528936 -349.401868) (xy 88.578523 -349.379229) (xy 88.630828 -349.363876) (xy 88.684785 -349.356124)
			(xy 88.71204 -349.355664) (xy 88.712294 -349.355664) (xy 88.738495 -349.356104) (xy 88.790401 -349.363294)
			(xy 88.840836 -349.377513) (xy 88.888855 -349.398493) (xy 88.91143 -349.411798) (xy 88.921042 -349.417123)
			(xy 88.942853 -349.419676) (xy 88.963746 -349.412914) (xy 88.979926 -349.398067) (xy 88.988453 -349.377831)
			(xy 88.988646 -349.36684) (xy 88.988392 -349.353632) (xy 88.988456 -349.342494) (xy 88.989728 -349.320255)
			(xy 88.990932 -349.309182) (xy 88.992189 -349.294211) (xy 88.986907 -349.264651) (xy 88.973257 -349.237904)
			(xy 88.952417 -349.216283) (xy 88.926191 -349.201657) (xy 88.896845 -349.19529) (xy 88.866916 -349.197734)
			(xy 88.852756 -349.202756) (xy 88.830293 -349.2113) (xy 88.78375 -349.223283) (xy 88.73607 -349.229319)
			(xy 88.71204 -349.22968) (xy 88.684783 -349.229276) (xy 88.630824 -349.221523) (xy 88.578517 -349.206169)
			(xy 88.528929 -349.183527) (xy 88.483067 -349.154058) (xy 88.441866 -349.118362) (xy 88.406166 -349.077165)
			(xy 88.376692 -349.031307) (xy 88.354045 -348.98172) (xy 88.338686 -348.929415) (xy 88.330927 -348.875457)
			(xy 88.330927 -348.820943) (xy 88.338686 -348.766985) (xy 88.354045 -348.71468) (xy 88.376692 -348.665093)
			(xy 88.406166 -348.619235) (xy 88.441866 -348.578038) (xy 88.483067 -348.542342) (xy 88.528929 -348.512873)
			(xy 88.578517 -348.490231) (xy 88.630824 -348.474877) (xy 88.684783 -348.467124) (xy 88.71204 -348.466664)
			(xy 88.736204 -348.467041) (xy 88.784147 -348.473135) (xy 88.830936 -348.485233) (xy 88.853518 -348.493842)
			(xy 88.868007 -348.499123) (xy 88.89874 -348.501541) (xy 88.928796 -348.494686) (xy 88.955441 -348.479182)
			(xy 88.976252 -348.456438) (xy 88.989334 -348.428524) (xy 88.991948 -348.413324) (xy 88.996023 -348.386221)
			(xy 89.011078 -348.333521) (xy 89.033522 -348.283519) (xy 89.062893 -348.237245) (xy 89.098585 -348.195651)
			(xy 89.139864 -348.159596) (xy 89.18588 -348.129821) (xy 89.235683 -348.106939) (xy 89.28825 -348.091423)
			(xy 89.342496 -348.083591) (xy 89.3699 -348.083124) (xy 89.398817 -348.083633) (xy 89.455989 -348.092363)
			(xy 89.511189 -348.109622) (xy 89.563151 -348.135015) (xy 89.610684 -348.167961) (xy 89.6527 -348.207704)
			(xy 89.67089 -348.23019) (xy 89.680787 -348.241995) (xy 89.706111 -348.259514) (xy 89.735504 -348.26869)
			(xy 89.766296 -348.26869) (xy 89.795689 -348.259514) (xy 89.821013 -348.241995) (xy 89.83091 -348.23019)
			(xy 89.849093 -348.2077) (xy 89.891115 -348.167965) (xy 89.938651 -348.135027) (xy 89.990614 -348.10964)
			(xy 90.045813 -348.092385) (xy 90.102984 -348.083658) (xy 90.1319 -348.083124) (xy 90.159154 -348.083546)
			(xy 90.213106 -348.091303) (xy 90.265405 -348.106659) (xy 90.314986 -348.129302) (xy 90.360841 -348.158771)
			(xy 90.402034 -348.194466) (xy 90.437729 -348.235659) (xy 90.467198 -348.281514) (xy 90.489841 -348.331095)
			(xy 90.505197 -348.383394) (xy 90.512954 -348.437346) (xy 90.512954 -348.491854) (xy 90.509949 -348.512757)
			(xy 90.715215 -348.512757) (xy 90.715215 -348.458243) (xy 90.722974 -348.404283) (xy 90.738333 -348.351976)
			(xy 90.760981 -348.302388) (xy 90.790456 -348.256528) (xy 90.826157 -348.21533) (xy 90.867359 -348.179633)
			(xy 90.913222 -348.150163) (xy 90.962812 -348.12752) (xy 91.01512 -348.112166) (xy 91.06908 -348.104412)
			(xy 91.096338 -348.103952) (xy 91.125254 -348.104495) (xy 91.182425 -348.113217) (xy 91.237624 -348.130468)
			(xy 91.289586 -348.155855) (xy 91.337121 -348.188795) (xy 91.379138 -348.228534) (xy 91.397328 -348.251018)
			(xy 91.407225 -348.262823) (xy 91.432549 -348.280342) (xy 91.461942 -348.289518) (xy 91.492734 -348.289518)
			(xy 91.522127 -348.280342) (xy 91.547451 -348.262823) (xy 91.557348 -348.251018) (xy 91.574101 -348.230235)
			(xy 91.612455 -348.193105) (xy 91.655609 -348.161683) (xy 91.702723 -348.136584) (xy 91.752875 -348.118298)
			(xy 91.805086 -348.107181) (xy 91.858338 -348.103451) (xy 91.91159 -348.107181) (xy 91.963801 -348.118298)
			(xy 92.013953 -348.136584) (xy 92.061067 -348.161683) (xy 92.104221 -348.193105) (xy 92.142575 -348.230235)
			(xy 92.159328 -348.251018) (xy 92.169225 -348.262823) (xy 92.194549 -348.280342) (xy 92.223942 -348.289518)
			(xy 92.254734 -348.289518) (xy 92.284127 -348.280342) (xy 92.309451 -348.262823) (xy 92.319348 -348.251018)
			(xy 92.336101 -348.230235) (xy 92.374455 -348.193105) (xy 92.417609 -348.161683) (xy 92.464723 -348.136584)
			(xy 92.514875 -348.118298) (xy 92.567086 -348.107181) (xy 92.620338 -348.103451) (xy 92.67359 -348.107181)
			(xy 92.725801 -348.118298) (xy 92.775953 -348.136584) (xy 92.823067 -348.161683) (xy 92.866221 -348.193105)
			(xy 92.904575 -348.230235) (xy 92.921328 -348.251018) (xy 92.931225 -348.262823) (xy 92.956549 -348.280342)
			(xy 92.985942 -348.289518) (xy 93.016734 -348.289518) (xy 93.046127 -348.280342) (xy 93.071451 -348.262823)
			(xy 93.081348 -348.251018) (xy 93.099573 -348.228563) (xy 93.141585 -348.188825) (xy 93.189113 -348.155882)
			(xy 93.241067 -348.130489) (xy 93.296259 -348.113227) (xy 93.353424 -348.104491) (xy 93.382338 -348.103952)
			(xy 93.410905 -348.104492) (xy 93.467399 -348.113024) (xy 93.521992 -348.129875) (xy 93.573466 -348.15467)
			(xy 93.620672 -348.186857) (xy 93.662557 -348.225716) (xy 93.680788 -348.247716) (xy 93.690372 -348.258945)
			(xy 93.714608 -348.275783) (xy 93.742643 -348.284996) (xy 93.772143 -348.285814) (xy 93.800646 -348.278172)
			(xy 93.825779 -348.262704) (xy 93.835982 -348.252034) (xy 93.854145 -348.232411) (xy 93.895029 -348.197953)
			(xy 93.940324 -348.16954) (xy 93.989143 -348.147728) (xy 94.040528 -348.132946) (xy 94.093473 -348.125482)
			(xy 94.120208 -348.125034) (xy 94.149123 -348.125606) (xy 94.206292 -348.134322) (xy 94.261491 -348.151568)
			(xy 94.313453 -348.17695) (xy 94.360988 -348.209885) (xy 94.403007 -348.249618) (xy 94.421198 -348.2721)
			(xy 94.431095 -348.283905) (xy 94.456419 -348.301424) (xy 94.485812 -348.3106) (xy 94.516604 -348.3106)
			(xy 94.545997 -348.301424) (xy 94.571321 -348.283905) (xy 94.581218 -348.2721) (xy 94.599399 -348.249608)
			(xy 94.641421 -348.209873) (xy 94.688958 -348.176935) (xy 94.740921 -348.151548) (xy 94.79612 -348.134294)
			(xy 94.853291 -348.125568) (xy 94.882208 -348.125034) (xy 94.909462 -348.125436) (xy 94.963415 -348.133195)
			(xy 95.015714 -348.148552) (xy 95.065296 -348.171196) (xy 95.11115 -348.200666) (xy 95.152344 -348.236362)
			(xy 95.188039 -348.277556) (xy 95.217508 -348.323411) (xy 95.240151 -348.372993) (xy 95.255507 -348.425293)
			(xy 95.263264 -348.479246) (xy 95.263264 -348.512752) (xy 95.383338 -348.512752) (xy 95.383338 -348.458248)
			(xy 95.391094 -348.404299) (xy 95.406448 -348.352003) (xy 95.429088 -348.302424) (xy 95.458553 -348.256571)
			(xy 95.494242 -348.215378) (xy 95.535431 -348.179683) (xy 95.58128 -348.150212) (xy 95.630856 -348.127565)
			(xy 95.68315 -348.112204) (xy 95.737098 -348.104441) (xy 95.76435 -348.103952) (xy 95.793267 -348.104486)
			(xy 95.850438 -348.113209) (xy 95.905637 -348.130463) (xy 95.9576 -348.155851) (xy 96.005134 -348.188793)
			(xy 96.04715 -348.228533) (xy 96.06534 -348.251018) (xy 96.075237 -348.262823) (xy 96.100561 -348.280342)
			(xy 96.129954 -348.289518) (xy 96.160746 -348.289518) (xy 96.190139 -348.280342) (xy 96.215463 -348.262823)
			(xy 96.22536 -348.251018) (xy 96.243578 -348.228557) (xy 96.285592 -348.18882) (xy 96.333121 -348.155878)
			(xy 96.385077 -348.130485) (xy 96.44027 -348.113224) (xy 96.497436 -348.10449) (xy 96.52635 -348.103952)
			(xy 96.553602 -348.104492) (xy 96.607553 -348.112242) (xy 96.659851 -348.127592) (xy 96.709433 -348.15023)
			(xy 96.755287 -348.179693) (xy 96.796482 -348.215383) (xy 96.832177 -348.256573) (xy 96.861646 -348.302423)
			(xy 96.88429 -348.352002) (xy 96.899647 -348.404298) (xy 96.907405 -348.458248) (xy 96.907405 -348.512752)
			(xy 96.899647 -348.566702) (xy 96.88429 -348.618998) (xy 96.861646 -348.668577) (xy 96.832177 -348.714427)
			(xy 96.796482 -348.755617) (xy 96.755287 -348.791307) (xy 96.709433 -348.82077) (xy 96.659851 -348.843408)
			(xy 96.607553 -348.858758) (xy 96.553602 -348.866508) (xy 96.52635 -348.866968) (xy 96.497434 -348.866426)
			(xy 96.440263 -348.857704) (xy 96.385064 -348.840451) (xy 96.333102 -348.815064) (xy 96.285568 -348.782124)
			(xy 96.24355 -348.742386) (xy 96.22536 -348.719902) (xy 96.215463 -348.708097) (xy 96.190139 -348.690578)
			(xy 96.160746 -348.681402) (xy 96.129954 -348.681402) (xy 96.100561 -348.690578) (xy 96.075237 -348.708097)
			(xy 96.06534 -348.719902) (xy 96.047127 -348.742367) (xy 96.005112 -348.782103) (xy 95.957581 -348.815044)
			(xy 95.905624 -348.840436) (xy 95.850431 -348.857696) (xy 95.793265 -348.86643) (xy 95.76435 -348.866968)
			(xy 95.737098 -348.866559) (xy 95.68315 -348.858796) (xy 95.630856 -348.843435) (xy 95.58128 -348.820788)
			(xy 95.535431 -348.791317) (xy 95.494242 -348.755622) (xy 95.458553 -348.714429) (xy 95.429088 -348.668576)
			(xy 95.406448 -348.618997) (xy 95.391094 -348.566701) (xy 95.383338 -348.512752) (xy 95.263264 -348.512752)
			(xy 95.263264 -348.533754) (xy 95.255507 -348.587707) (xy 95.240151 -348.640007) (xy 95.217508 -348.689589)
			(xy 95.188039 -348.735444) (xy 95.152344 -348.776638) (xy 95.11115 -348.812334) (xy 95.065296 -348.841804)
			(xy 95.015714 -348.864448) (xy 94.963415 -348.879805) (xy 94.909462 -348.887564) (xy 94.882208 -348.88805)
			(xy 94.85329 -348.887545) (xy 94.796118 -348.878816) (xy 94.740918 -348.861556) (xy 94.688956 -348.836162)
			(xy 94.641422 -348.803216) (xy 94.599407 -348.763471) (xy 94.581218 -348.740984) (xy 94.571321 -348.729179)
			(xy 94.545997 -348.71166) (xy 94.516604 -348.702484) (xy 94.485812 -348.702484) (xy 94.456419 -348.71166)
			(xy 94.431095 -348.729179) (xy 94.421198 -348.740984) (xy 94.403004 -348.763465) (xy 94.360985 -348.803201)
			(xy 94.313451 -348.836141) (xy 94.26149 -348.86153) (xy 94.206293 -348.878786) (xy 94.149124 -348.887515)
			(xy 94.120208 -348.88805) (xy 94.091642 -348.887476) (xy 94.03515 -348.878952) (xy 93.980557 -348.862107)
			(xy 93.929083 -348.837318) (xy 93.881876 -348.805137) (xy 93.83999 -348.766284) (xy 93.821758 -348.744286)
			(xy 93.812126 -348.733102) (xy 93.787903 -348.716262) (xy 93.75988 -348.707045) (xy 93.730391 -348.706217)
			(xy 93.701895 -348.713849) (xy 93.676767 -348.729304) (xy 93.666564 -348.739968) (xy 93.648379 -348.759569)
			(xy 93.607499 -348.794029) (xy 93.562209 -348.822445) (xy 93.513395 -348.84426) (xy 93.462014 -348.859047)
			(xy 93.409071 -348.866516) (xy 93.382338 -348.866968) (xy 93.353422 -348.866435) (xy 93.29625 -348.85771)
			(xy 93.241051 -348.840456) (xy 93.189089 -348.815068) (xy 93.141555 -348.782126) (xy 93.099538 -348.742387)
			(xy 93.081348 -348.719902) (xy 93.071451 -348.708097) (xy 93.046127 -348.690578) (xy 93.016734 -348.681402)
			(xy 92.985942 -348.681402) (xy 92.956549 -348.690578) (xy 92.931225 -348.708097) (xy 92.921328 -348.719902)
			(xy 92.904575 -348.740685) (xy 92.866221 -348.777815) (xy 92.823067 -348.809237) (xy 92.775953 -348.834336)
			(xy 92.725801 -348.852622) (xy 92.67359 -348.863739) (xy 92.620338 -348.867469) (xy 92.567086 -348.863739)
			(xy 92.514875 -348.852622) (xy 92.464723 -348.834336) (xy 92.417609 -348.809237) (xy 92.374455 -348.777815)
			(xy 92.336101 -348.740685) (xy 92.319348 -348.719902) (xy 92.309451 -348.708097) (xy 92.284127 -348.690578)
			(xy 92.254734 -348.681402) (xy 92.223942 -348.681402) (xy 92.194549 -348.690578) (xy 92.169225 -348.708097)
			(xy 92.159328 -348.719902) (xy 92.142575 -348.740685) (xy 92.104221 -348.777815) (xy 92.061067 -348.809237)
			(xy 92.013953 -348.834336) (xy 91.963801 -348.852622) (xy 91.91159 -348.863739) (xy 91.858338 -348.867469)
			(xy 91.805086 -348.863739) (xy 91.752875 -348.852622) (xy 91.702723 -348.834336) (xy 91.655609 -348.809237)
			(xy 91.612455 -348.777815) (xy 91.574101 -348.740685) (xy 91.557348 -348.719902) (xy 91.547451 -348.708097)
			(xy 91.522127 -348.690578) (xy 91.492734 -348.681402) (xy 91.461942 -348.681402) (xy 91.432549 -348.690578)
			(xy 91.407225 -348.708097) (xy 91.397328 -348.719902) (xy 91.379122 -348.742372) (xy 91.337105 -348.782108)
			(xy 91.289573 -348.815049) (xy 91.237615 -348.840439) (xy 91.18242 -348.857699) (xy 91.125253 -348.866431)
			(xy 91.096338 -348.866968) (xy 91.06908 -348.866588) (xy 91.01512 -348.858834) (xy 90.962812 -348.84348)
			(xy 90.913222 -348.820837) (xy 90.867359 -348.791367) (xy 90.826157 -348.75567) (xy 90.790456 -348.714472)
			(xy 90.760981 -348.668612) (xy 90.738333 -348.619024) (xy 90.722974 -348.566717) (xy 90.715215 -348.512757)
			(xy 90.509949 -348.512757) (xy 90.505197 -348.545806) (xy 90.489841 -348.598105) (xy 90.467198 -348.647686)
			(xy 90.437729 -348.693541) (xy 90.402034 -348.734734) (xy 90.360841 -348.770429) (xy 90.314986 -348.799898)
			(xy 90.265405 -348.822541) (xy 90.213106 -348.837897) (xy 90.159154 -348.845654) (xy 90.1319 -348.84614)
			(xy 90.102982 -348.845644) (xy 90.045809 -348.836914) (xy 89.990608 -348.819653) (xy 89.938646 -348.794257)
			(xy 89.891113 -348.761308) (xy 89.849098 -348.721562) (xy 89.83091 -348.699074) (xy 89.821013 -348.687269)
			(xy 89.795689 -348.66975) (xy 89.766296 -348.660574) (xy 89.735504 -348.660574) (xy 89.706111 -348.66975)
			(xy 89.680787 -348.687269) (xy 89.67089 -348.699074) (xy 89.652698 -348.721557) (xy 89.610679 -348.761293)
			(xy 89.563145 -348.794233) (xy 89.511184 -348.819622) (xy 89.455986 -348.836878) (xy 89.398816 -348.845606)
			(xy 89.3699 -348.84614) (xy 89.369646 -348.84614) (xy 89.343446 -348.845681) (xy 89.291541 -348.838497)
			(xy 89.241105 -348.824284) (xy 89.193086 -348.803309) (xy 89.17051 -348.790006) (xy 89.160875 -348.784726)
			(xy 89.139075 -348.782162) (xy 89.118188 -348.788913) (xy 89.102011 -348.80375) (xy 89.093486 -348.823978)
			(xy 89.093294 -348.834964) (xy 89.093548 -348.848172) (xy 89.093485 -348.85931) (xy 89.092212 -348.881549)
			(xy 89.091008 -348.892622) (xy 89.089693 -348.907591) (xy 89.094978 -348.937162) (xy 89.108636 -348.963917)
			(xy 89.129485 -348.985543) (xy 89.155724 -349.000168) (xy 89.185082 -349.00653) (xy 89.215021 -349.004077)
			(xy 89.229184 -348.999048) (xy 89.251653 -348.990521) (xy 89.298193 -348.978532) (xy 89.34587 -348.972489)
			(xy 89.3699 -348.972124) (xy 89.398817 -348.972633) (xy 89.455989 -348.981363) (xy 89.511189 -348.998622)
			(xy 89.563151 -349.024015) (xy 89.610684 -349.056961) (xy 89.6527 -349.096704) (xy 89.67089 -349.11919)
			(xy 89.680787 -349.130995) (xy 89.706111 -349.148514) (xy 89.735504 -349.15769) (xy 89.766296 -349.15769)
			(xy 89.795689 -349.148514) (xy 89.821013 -349.130995) (xy 89.83091 -349.11919) (xy 89.849093 -349.0967)
			(xy 89.891115 -349.056965) (xy 89.938651 -349.024027) (xy 89.990614 -348.99864) (xy 90.045813 -348.981385)
			(xy 90.102984 -348.972658) (xy 90.1319 -348.972124) (xy 90.159154 -348.972555) (xy 90.213108 -348.980313)
			(xy 90.265408 -348.995671) (xy 90.314991 -349.018316) (xy 90.360845 -349.047787) (xy 90.402039 -349.083484)
			(xy 90.437733 -349.12468) (xy 90.4672 -349.170537) (xy 90.48984 -349.220122) (xy 90.505194 -349.272423)
			(xy 90.512947 -349.326378) (xy 90.513408 -349.353632) (xy 90.512876 -349.382549) (xy 90.504154 -349.439721)
			(xy 90.486902 -349.494921) (xy 90.461513 -349.546884) (xy 90.42857 -349.594417) (xy 90.388828 -349.636433)
			(xy 90.366342 -349.654622) (xy 90.354502 -349.664483) (xy 90.33698 -349.689815) (xy 90.327805 -349.719219)
			(xy 90.327811 -349.750021) (xy 90.336997 -349.779421) (xy 90.354529 -349.804746) (xy 90.366342 -349.814642)
			(xy 90.387156 -349.831358) (xy 90.424287 -349.869715) (xy 90.455708 -349.912875) (xy 90.480807 -349.959992)
			(xy 90.499092 -350.010149) (xy 90.510206 -350.062365) (xy 90.513933 -350.11562) (xy 90.512473 -350.13646)
			(xy 90.71483 -350.13646) (xy 90.71538 -350.107544) (xy 90.724101 -350.050374) (xy 90.741352 -349.995175)
			(xy 90.766737 -349.943213) (xy 90.799676 -349.895678) (xy 90.839412 -349.853661) (xy 90.861896 -349.83547)
			(xy 90.87374 -349.825616) (xy 90.891256 -349.80028) (xy 90.900426 -349.770876) (xy 90.900419 -349.740075)
			(xy 90.891234 -349.710676) (xy 90.873706 -349.685348) (xy 90.861896 -349.67545) (xy 90.839436 -349.657232)
			(xy 90.799699 -349.615218) (xy 90.766758 -349.567688) (xy 90.741365 -349.515732) (xy 90.724104 -349.46054)
			(xy 90.715369 -349.403374) (xy 90.71483 -349.37446) (xy 90.715241 -349.347206) (xy 90.723004 -349.293254)
			(xy 90.738366 -349.240955) (xy 90.761014 -349.191375) (xy 90.790488 -349.145523) (xy 90.826188 -349.104332)
			(xy 90.867386 -349.068642) (xy 90.913244 -349.039177) (xy 90.962828 -349.016538) (xy 91.01513 -349.001187)
			(xy 91.069084 -348.993435) (xy 91.096338 -348.992952) (xy 91.125254 -348.993495) (xy 91.182425 -349.002217)
			(xy 91.237624 -349.019468) (xy 91.289586 -349.044855) (xy 91.337121 -349.077795) (xy 91.379138 -349.117534)
			(xy 91.397328 -349.140018) (xy 91.407225 -349.151823) (xy 91.432549 -349.169342) (xy 91.461942 -349.178518)
			(xy 91.492734 -349.178518) (xy 91.522127 -349.169342) (xy 91.547451 -349.151823) (xy 91.557348 -349.140018)
			(xy 91.574101 -349.119235) (xy 91.612455 -349.082105) (xy 91.655609 -349.050683) (xy 91.702723 -349.025584)
			(xy 91.752875 -349.007298) (xy 91.805086 -348.996181) (xy 91.858338 -348.992451) (xy 91.91159 -348.996181)
			(xy 91.963801 -349.007298) (xy 92.013953 -349.025584) (xy 92.061067 -349.050683) (xy 92.104221 -349.082105)
			(xy 92.142575 -349.119235) (xy 92.159328 -349.140018) (xy 92.169225 -349.151823) (xy 92.194549 -349.169342)
			(xy 92.223942 -349.178518) (xy 92.254734 -349.178518) (xy 92.284127 -349.169342) (xy 92.309451 -349.151823)
			(xy 92.319348 -349.140018) (xy 92.336101 -349.119235) (xy 92.374455 -349.082105) (xy 92.417609 -349.050683)
			(xy 92.464723 -349.025584) (xy 92.514875 -349.007298) (xy 92.567086 -348.996181) (xy 92.620338 -348.992451)
			(xy 92.67359 -348.996181) (xy 92.725801 -349.007298) (xy 92.775953 -349.025584) (xy 92.823067 -349.050683)
			(xy 92.866221 -349.082105) (xy 92.904575 -349.119235) (xy 92.921328 -349.140018) (xy 92.931225 -349.151823)
			(xy 92.956549 -349.169342) (xy 92.985942 -349.178518) (xy 93.016734 -349.178518) (xy 93.046127 -349.169342)
			(xy 93.071451 -349.151823) (xy 93.081348 -349.140018) (xy 93.099573 -349.117563) (xy 93.141585 -349.077825)
			(xy 93.189113 -349.044882) (xy 93.241067 -349.019489) (xy 93.296259 -349.002227) (xy 93.353424 -348.993491)
			(xy 93.382338 -348.992952) (xy 93.410905 -348.993492) (xy 93.467399 -349.002024) (xy 93.521992 -349.018875)
			(xy 93.573466 -349.04367) (xy 93.620672 -349.075857) (xy 93.662557 -349.114716) (xy 93.680788 -349.136716)
			(xy 93.690372 -349.147945) (xy 93.714608 -349.164783) (xy 93.742643 -349.173996) (xy 93.772143 -349.174814)
			(xy 93.800646 -349.167172) (xy 93.825779 -349.151704) (xy 93.835982 -349.141034) (xy 93.854145 -349.121411)
			(xy 93.895029 -349.086953) (xy 93.940324 -349.05854) (xy 93.989143 -349.036728) (xy 94.040528 -349.021946)
			(xy 94.093473 -349.014482) (xy 94.120208 -349.014034) (xy 94.149123 -349.014606) (xy 94.206292 -349.023322)
			(xy 94.261491 -349.040568) (xy 94.313453 -349.06595) (xy 94.360988 -349.098885) (xy 94.403007 -349.138618)
			(xy 94.421198 -349.1611) (xy 94.431095 -349.172905) (xy 94.456419 -349.190424) (xy 94.485812 -349.1996)
			(xy 94.516604 -349.1996) (xy 94.545997 -349.190424) (xy 94.571321 -349.172905) (xy 94.581218 -349.1611)
			(xy 94.599399 -349.138608) (xy 94.641421 -349.098873) (xy 94.688958 -349.065935) (xy 94.740921 -349.040548)
			(xy 94.79612 -349.023294) (xy 94.853291 -349.014568) (xy 94.882208 -349.014034) (xy 94.909463 -349.014448)
			(xy 94.963418 -349.022207) (xy 95.015719 -349.037566) (xy 95.065302 -349.060213) (xy 95.111157 -349.089686)
			(xy 95.152351 -349.125385) (xy 95.188044 -349.166583) (xy 95.217511 -349.212442) (xy 95.240151 -349.262028)
			(xy 95.255503 -349.314331) (xy 95.263256 -349.368287) (xy 95.263716 -349.395542) (xy 95.26314 -349.424984)
			(xy 95.254075 -349.483167) (xy 95.236182 -349.539267) (xy 95.209886 -349.591954) (xy 95.17581 -349.639978)
			(xy 95.134764 -349.682198) (xy 95.11157 -349.700342) (xy 95.101069 -349.708669) (xy 95.084553 -349.729767)
			(xy 95.074096 -349.754435) (xy 95.070417 -349.780975) (xy 95.073771 -349.807558) (xy 95.083926 -349.832353)
			(xy 95.100182 -349.853651) (xy 95.110554 -349.86214) (xy 95.133163 -349.880342) (xy 95.173168 -349.922394)
			(xy 95.20634 -349.970022) (xy 95.231914 -350.022125) (xy 95.249298 -350.077501) (xy 95.258093 -350.134872)
			(xy 95.258123 -350.136475) (xy 95.382291 -350.136475) (xy 95.386025 -350.083218) (xy 95.397148 -350.031001)
			(xy 95.415441 -349.980845) (xy 95.440549 -349.933729) (xy 95.471979 -349.890574) (xy 95.50912 -349.852222)
			(xy 95.529908 -349.83547) (xy 95.541751 -349.825615) (xy 95.559264 -349.800279) (xy 95.568434 -349.770875)
			(xy 95.568426 -349.740076) (xy 95.559243 -349.710677) (xy 95.541717 -349.685349) (xy 95.529908 -349.67545)
			(xy 95.50745 -349.657229) (xy 95.467713 -349.615216) (xy 95.434771 -349.567687) (xy 95.409378 -349.515732)
			(xy 95.392116 -349.460539) (xy 95.383381 -349.403374) (xy 95.382842 -349.37446) (xy 95.383218 -349.347204)
			(xy 95.390982 -349.293247) (xy 95.406345 -349.240945) (xy 95.428996 -349.191361) (xy 95.458473 -349.145506)
			(xy 95.494176 -349.104312) (xy 95.535378 -349.068619) (xy 95.58124 -349.039153) (xy 95.630829 -349.016514)
			(xy 95.683135 -349.001162) (xy 95.737094 -348.993411) (xy 95.76435 -348.992952) (xy 95.793267 -348.993486)
			(xy 95.850438 -349.002209) (xy 95.905637 -349.019463) (xy 95.9576 -349.044851) (xy 96.005134 -349.077793)
			(xy 96.04715 -349.117533) (xy 96.06534 -349.140018) (xy 96.075237 -349.151823) (xy 96.100561 -349.169342)
			(xy 96.129954 -349.178518) (xy 96.160746 -349.178518) (xy 96.190139 -349.169342) (xy 96.215463 -349.151823)
			(xy 96.22536 -349.140018) (xy 96.243578 -349.117557) (xy 96.285592 -349.07782) (xy 96.333121 -349.044878)
			(xy 96.385077 -349.019485) (xy 96.44027 -349.002224) (xy 96.497436 -348.99349) (xy 96.52635 -348.992952)
			(xy 96.5536 -348.993502) (xy 96.607546 -349.001251) (xy 96.659839 -349.016598) (xy 96.709417 -349.039232)
			(xy 96.755268 -349.068691) (xy 96.79646 -349.104376) (xy 96.832155 -349.14556) (xy 96.861625 -349.191404)
			(xy 96.88427 -349.240976) (xy 96.89963 -349.293266) (xy 96.907392 -349.34721) (xy 96.907858 -349.37446)
			(xy 96.907327 -349.403377) (xy 96.898603 -349.460548) (xy 96.881348 -349.515747) (xy 96.855959 -349.567709)
			(xy 96.823017 -349.615243) (xy 96.783277 -349.65726) (xy 96.760792 -349.67545) (xy 96.749029 -349.685392)
			(xy 96.731514 -349.710704) (xy 96.722336 -349.740085) (xy 96.722329 -349.770866) (xy 96.731493 -349.800251)
			(xy 96.748995 -349.825572) (xy 96.760792 -349.83547) (xy 96.781538 -349.852269) (xy 96.818672 -349.890615)
			(xy 96.850097 -349.933763) (xy 96.875201 -349.980871) (xy 96.893491 -350.031019) (xy 96.904612 -350.083227)
			(xy 96.908345 -350.136475) (xy 96.904619 -350.189724) (xy 96.893505 -350.241934) (xy 96.875221 -350.292084)
			(xy 96.850124 -350.339195) (xy 96.818704 -350.382347) (xy 96.781574 -350.420698) (xy 96.760792 -350.43745)
			(xy 96.749029 -350.447392) (xy 96.731514 -350.472704) (xy 96.722336 -350.502085) (xy 96.722329 -350.532866)
			(xy 96.731493 -350.562251) (xy 96.748995 -350.587572) (xy 96.760792 -350.59747) (xy 96.783259 -350.61568)
			(xy 96.822996 -350.657696) (xy 96.855937 -350.705226) (xy 96.881328 -350.757184) (xy 96.898588 -350.812378)
			(xy 96.907321 -350.869545) (xy 96.907858 -350.89846) (xy 96.907407 -350.925714) (xy 96.899655 -350.979668)
			(xy 96.884301 -351.031969) (xy 96.86166 -351.081553) (xy 96.832191 -351.127408) (xy 96.796496 -351.168603)
			(xy 96.7553 -351.204297) (xy 96.709444 -351.233764) (xy 96.65986 -351.256405) (xy 96.607558 -351.271757)
			(xy 96.553604 -351.279508) (xy 96.52635 -351.279968) (xy 96.497434 -351.279426) (xy 96.440263 -351.270704)
			(xy 96.385064 -351.253451) (xy 96.333102 -351.228064) (xy 96.285568 -351.195124) (xy 96.24355 -351.155386)
			(xy 96.22536 -351.132902) (xy 96.215463 -351.121097) (xy 96.190139 -351.103578) (xy 96.160746 -351.094402)
			(xy 96.129954 -351.094402) (xy 96.100561 -351.103578) (xy 96.075237 -351.121097) (xy 96.06534 -351.132902)
			(xy 96.047127 -351.155367) (xy 96.005112 -351.195103) (xy 95.957581 -351.228044) (xy 95.905624 -351.253436)
			(xy 95.850431 -351.270696) (xy 95.793265 -351.27943) (xy 95.76435 -351.279968) (xy 95.737097 -351.279498)
			(xy 95.683144 -351.271747) (xy 95.630844 -351.256395) (xy 95.581261 -351.233756) (xy 95.535406 -351.204289)
			(xy 95.494211 -351.168596) (xy 95.458517 -351.127402) (xy 95.429049 -351.081548) (xy 95.406408 -351.031966)
			(xy 95.391055 -350.979666) (xy 95.383303 -350.925713) (xy 95.382842 -350.89846) (xy 95.383387 -350.869544)
			(xy 95.392108 -350.812373) (xy 95.40936 -350.757174) (xy 95.434746 -350.705212) (xy 95.467686 -350.657678)
			(xy 95.507424 -350.61566) (xy 95.529908 -350.59747) (xy 95.541751 -350.587615) (xy 95.559264 -350.562279)
			(xy 95.568434 -350.532875) (xy 95.568426 -350.502076) (xy 95.559243 -350.472677) (xy 95.541717 -350.447349)
			(xy 95.529908 -350.43745) (xy 95.509083 -350.420745) (xy 95.471948 -350.382388) (xy 95.440522 -350.339229)
			(xy 95.415421 -350.29211) (xy 95.397134 -350.241951) (xy 95.386018 -350.189733) (xy 95.382291 -350.136475)
			(xy 95.258123 -350.136475) (xy 95.258636 -350.163892) (xy 95.25815 -350.191143) (xy 95.250394 -350.245091)
			(xy 95.235039 -350.297386) (xy 95.212397 -350.346963) (xy 95.182931 -350.392813) (xy 95.14724 -350.434004)
			(xy 95.106049 -350.469695) (xy 95.060199 -350.499161) (xy 95.010622 -350.521803) (xy 94.958327 -350.537158)
			(xy 94.904379 -350.544914) (xy 94.849877 -350.544914) (xy 94.795929 -350.537158) (xy 94.743634 -350.521803)
			(xy 94.694057 -350.499161) (xy 94.648207 -350.469695) (xy 94.607016 -350.434004) (xy 94.571325 -350.392813)
			(xy 94.541859 -350.346963) (xy 94.519217 -350.297386) (xy 94.503862 -350.245091) (xy 94.496106 -350.191143)
			(xy 94.49562 -350.163892) (xy 94.496134 -350.134447) (xy 94.50521 -350.076261) (xy 94.523114 -350.020159)
			(xy 94.549422 -349.967472) (xy 94.583509 -349.91945) (xy 94.624567 -349.877233) (xy 94.647766 -349.859092)
			(xy 94.65823 -349.850724) (xy 94.67474 -349.829634) (xy 94.685196 -349.804975) (xy 94.688878 -349.778445)
			(xy 94.685532 -349.751871) (xy 94.675388 -349.727082) (xy 94.659146 -349.705784) (xy 94.648782 -349.697294)
			(xy 94.63008 -349.682385) (xy 94.596195 -349.648631) (xy 94.581218 -349.629984) (xy 94.571321 -349.618179)
			(xy 94.545997 -349.60066) (xy 94.516604 -349.591484) (xy 94.485812 -349.591484) (xy 94.456419 -349.60066)
			(xy 94.431095 -349.618179) (xy 94.421198 -349.629984) (xy 94.403004 -349.652465) (xy 94.360985 -349.692201)
			(xy 94.313451 -349.725141) (xy 94.26149 -349.75053) (xy 94.206293 -349.767786) (xy 94.149124 -349.776515)
			(xy 94.120208 -349.77705) (xy 94.091642 -349.776476) (xy 94.03515 -349.767952) (xy 93.980557 -349.751107)
			(xy 93.929083 -349.726318) (xy 93.881876 -349.694137) (xy 93.83999 -349.655284) (xy 93.821758 -349.633286)
			(xy 93.812126 -349.622102) (xy 93.787903 -349.605262) (xy 93.75988 -349.596045) (xy 93.730391 -349.595217)
			(xy 93.701895 -349.602849) (xy 93.676767 -349.618304) (xy 93.666564 -349.628968) (xy 93.648379 -349.648569)
			(xy 93.607499 -349.683029) (xy 93.562209 -349.711445) (xy 93.513395 -349.73326) (xy 93.462014 -349.748047)
			(xy 93.409071 -349.755516) (xy 93.382338 -349.755968) (xy 93.353422 -349.755435) (xy 93.29625 -349.74671)
			(xy 93.241051 -349.729456) (xy 93.189089 -349.704068) (xy 93.141555 -349.671126) (xy 93.099538 -349.631387)
			(xy 93.081348 -349.608902) (xy 93.071451 -349.597097) (xy 93.046127 -349.579578) (xy 93.016734 -349.570402)
			(xy 92.985942 -349.570402) (xy 92.956549 -349.579578) (xy 92.931225 -349.597097) (xy 92.921328 -349.608902)
			(xy 92.904575 -349.629685) (xy 92.866221 -349.666815) (xy 92.823067 -349.698237) (xy 92.775953 -349.723336)
			(xy 92.725801 -349.741622) (xy 92.67359 -349.752739) (xy 92.620338 -349.756469) (xy 92.567086 -349.752739)
			(xy 92.514875 -349.741622) (xy 92.464723 -349.723336) (xy 92.417609 -349.698237) (xy 92.374455 -349.666815)
			(xy 92.336101 -349.629685) (xy 92.319348 -349.608902) (xy 92.309451 -349.597097) (xy 92.284127 -349.579578)
			(xy 92.254734 -349.570402) (xy 92.223942 -349.570402) (xy 92.194549 -349.579578) (xy 92.169225 -349.597097)
			(xy 92.159328 -349.608902) (xy 92.142575 -349.629685) (xy 92.104221 -349.666815) (xy 92.061067 -349.698237)
			(xy 92.013953 -349.723336) (xy 91.963801 -349.741622) (xy 91.91159 -349.752739) (xy 91.858338 -349.756469)
			(xy 91.805086 -349.752739) (xy 91.752875 -349.741622) (xy 91.702723 -349.723336) (xy 91.655609 -349.698237)
			(xy 91.612455 -349.666815) (xy 91.574101 -349.629685) (xy 91.557348 -349.608902) (xy 91.547451 -349.597097)
			(xy 91.522127 -349.579578) (xy 91.492734 -349.570402) (xy 91.461942 -349.570402) (xy 91.432549 -349.579578)
			(xy 91.407225 -349.597097) (xy 91.397328 -349.608902) (xy 91.382552 -349.627303) (xy 91.34918 -349.660673)
			(xy 91.33078 -349.67545) (xy 91.319018 -349.685393) (xy 91.301506 -349.710705) (xy 91.292329 -349.740086)
			(xy 91.292321 -349.770865) (xy 91.301484 -349.80025) (xy 91.318984 -349.825571) (xy 91.33078 -349.83547)
			(xy 91.353245 -349.853683) (xy 91.392982 -349.895698) (xy 91.425924 -349.943228) (xy 91.451316 -349.995185)
			(xy 91.468576 -350.050379) (xy 91.477309 -350.107545) (xy 91.477846 -350.13646) (xy 91.47736 -350.163711)
			(xy 91.469604 -350.217659) (xy 91.454249 -350.269954) (xy 91.431607 -350.319531) (xy 91.402141 -350.365381)
			(xy 91.36645 -350.406572) (xy 91.325259 -350.442263) (xy 91.279409 -350.471729) (xy 91.229832 -350.494371)
			(xy 91.177537 -350.509726) (xy 91.123589 -350.517482) (xy 91.069087 -350.517482) (xy 91.015139 -350.509726)
			(xy 90.962844 -350.494371) (xy 90.913267 -350.471729) (xy 90.867417 -350.442263) (xy 90.826226 -350.406572)
			(xy 90.790535 -350.365381) (xy 90.761069 -350.319531) (xy 90.738427 -350.269954) (xy 90.723072 -350.217659)
			(xy 90.715316 -350.163711) (xy 90.71483 -350.13646) (xy 90.512473 -350.13646) (xy 90.510201 -350.168874)
			(xy 90.499081 -350.221089) (xy 90.480791 -350.271244) (xy 90.455688 -350.318359) (xy 90.424262 -350.361515)
			(xy 90.387127 -350.399869) (xy 90.366342 -350.416622) (xy 90.354502 -350.426483) (xy 90.33698 -350.451815)
			(xy 90.327805 -350.481219) (xy 90.327811 -350.512021) (xy 90.336997 -350.541421) (xy 90.354529 -350.566746)
			(xy 90.366342 -350.576642) (xy 90.388854 -350.594799) (xy 90.428586 -350.636827) (xy 90.46152 -350.684369)
			(xy 90.486903 -350.736337) (xy 90.504154 -350.79154) (xy 90.512876 -350.848714) (xy 90.513408 -350.877632)
			(xy 90.512952 -350.904884) (xy 90.505191 -350.958833) (xy 90.489832 -351.011128) (xy 90.467187 -351.060705)
			(xy 90.437717 -351.106556) (xy 90.402023 -351.147746) (xy 90.36083 -351.183437) (xy 90.314977 -351.212902)
			(xy 90.265398 -351.235543) (xy 90.213102 -351.250898) (xy 90.159152 -351.258654) (xy 90.1319 -351.25914)
			(xy 90.102982 -351.258644) (xy 90.045809 -351.249914) (xy 89.990608 -351.232653) (xy 89.938646 -351.207257)
			(xy 89.891113 -351.174308) (xy 89.849098 -351.134562) (xy 89.83091 -351.112074) (xy 89.821013 -351.100269)
			(xy 89.795689 -351.08275) (xy 89.766296 -351.073574) (xy 89.735504 -351.073574) (xy 89.706111 -351.08275)
			(xy 89.680787 -351.100269) (xy 89.67089 -351.112074) (xy 89.652698 -351.134557) (xy 89.610679 -351.174293)
			(xy 89.563145 -351.207233) (xy 89.511184 -351.232622) (xy 89.455986 -351.249878) (xy 89.398816 -351.258606)
			(xy 89.3699 -351.25914) (xy 89.342694 -351.258661) (xy 89.288835 -351.250917) (xy 89.236622 -351.235599)
			(xy 89.187116 -351.21302) (xy 89.141319 -351.183636) (xy 89.100161 -351.148044) (xy 89.064477 -351.106966)
			(xy 89.03499 -351.061235) (xy 89.0123 -351.011779) (xy 88.996866 -350.959601) (xy 88.992456 -350.93275)
			(xy 88.989721 -350.91765) (xy 88.976444 -350.889996) (xy 88.955567 -350.867522) (xy 88.928965 -350.852247)
			(xy 88.89903 -350.845546) (xy 88.868455 -350.84802) (xy 88.854026 -350.853248) (xy 88.831378 -350.861945)
			(xy 88.784423 -350.874154) (xy 88.736298 -350.880304) (xy 88.71204 -350.88068) (xy 88.684787 -350.880207)
			(xy 88.630835 -350.872455) (xy 88.578535 -350.857103) (xy 88.528954 -350.834463) (xy 88.483099 -350.804996)
			(xy 88.441905 -350.769303) (xy 88.406211 -350.728111) (xy 88.376743 -350.682257) (xy 88.354101 -350.632676)
			(xy 88.338747 -350.580377) (xy 88.330993 -350.526425) (xy 88.330532 -350.499172) (xy 77.29388 -350.499172)
			(xy 77.293978 -350.505014) (xy 77.293492 -350.532265) (xy 77.285736 -350.586213) (xy 77.270381 -350.638508)
			(xy 77.247739 -350.688085) (xy 77.218273 -350.733935) (xy 77.182582 -350.775126) (xy 77.141391 -350.810817)
			(xy 77.095541 -350.840283) (xy 77.045964 -350.862925) (xy 76.993669 -350.87828) (xy 76.939721 -350.886036)
			(xy 76.885219 -350.886036) (xy 76.831271 -350.87828) (xy 76.778976 -350.862925) (xy 76.729399 -350.840283)
			(xy 76.683549 -350.810817) (xy 76.642358 -350.775126) (xy 76.606667 -350.733935) (xy 76.577201 -350.688085)
			(xy 76.554559 -350.638508) (xy 76.539204 -350.586213) (xy 76.531448 -350.532265) (xy 76.530962 -350.505014)
			(xy 76.25842 -350.505014) (xy 76.25842 -351.879408) (xy 78.126336 -356.487984) (xy 81.632806 -359.994454)
			(xy 87.567516 -359.994454) (xy 87.568039 -359.964944) (xy 87.577109 -359.906626) (xy 87.595057 -359.850402)
			(xy 87.621454 -359.797615) (xy 87.655669 -359.749525) (xy 87.696885 -359.707282) (xy 87.72017 -359.689146)
			(xy 87.731669 -359.679895) (xy 87.749252 -359.65621) (xy 87.759335 -359.628487) (xy 87.761075 -359.59904)
			(xy 87.754328 -359.570324) (xy 87.739657 -359.544732) (xy 87.729314 -359.534206) (xy 87.710907 -359.516162)
			(xy 87.678669 -359.475943) (xy 87.652144 -359.431746) (xy 87.631817 -359.384378) (xy 87.618058 -359.334703)
			(xy 87.611119 -359.283627) (xy 87.610696 -359.257854) (xy 87.611135 -359.230601) (xy 87.618898 -359.176652)
			(xy 87.634259 -359.124356) (xy 87.656906 -359.074778) (xy 87.686377 -359.028928) (xy 87.722074 -358.987738)
			(xy 87.763268 -358.952047) (xy 87.809122 -358.922582) (xy 87.858703 -358.899942) (xy 87.911001 -358.884587)
			(xy 87.964951 -358.876831) (xy 87.992204 -358.876346) (xy 88.020942 -358.876882) (xy 88.077768 -358.885504)
			(xy 88.132658 -358.902552) (xy 88.18437 -358.92764) (xy 88.231734 -358.960201) (xy 88.253062 -358.97947)
			(xy 88.264929 -358.989692) (xy 88.293199 -359.003124) (xy 88.324209 -359.007369) (xy 88.35505 -359.002028)
			(xy 88.382827 -358.987604) (xy 88.394286 -358.97693) (xy 88.403382 -358.96806) (xy 88.422574 -358.951408)
			(xy 88.43264 -358.943656) (xy 88.444447 -358.933923) (xy 88.462142 -358.908978) (xy 88.471662 -358.879914)
			(xy 88.472154 -358.849335) (xy 88.463574 -358.81998) (xy 88.44669 -358.794479) (xy 88.43518 -358.784398)
			(xy 88.413773 -358.766185) (xy 88.376036 -358.724534) (xy 88.344817 -358.677798) (xy 88.320791 -358.626987)
			(xy 88.30448 -358.573202) (xy 88.296234 -358.517606) (xy 88.295734 -358.489504) (xy 88.296173 -358.463163)
			(xy 88.303428 -358.410981) (xy 88.317788 -358.360293) (xy 88.338978 -358.31206) (xy 88.366598 -358.267197)
			(xy 88.400123 -358.226557) (xy 88.438915 -358.190911) (xy 88.460326 -358.17556) (xy 88.472459 -358.166357)
			(xy 88.491238 -358.142411) (xy 88.502137 -358.113999) (xy 88.504189 -358.083637) (xy 88.497214 -358.054017)
			(xy 88.481828 -358.027762) (xy 88.470994 -358.017064) (xy 88.451748 -357.998917) (xy 88.417965 -357.958213)
			(xy 88.390127 -357.913234) (xy 88.368767 -357.864841) (xy 88.354294 -357.813962) (xy 88.346986 -357.761573)
			(xy 88.346534 -357.735124) (xy 88.347047 -357.707644) (xy 88.354936 -357.653254) (xy 88.370553 -357.600559)
			(xy 88.393575 -357.550654) (xy 88.423525 -357.504572) (xy 88.459782 -357.463268) (xy 88.501594 -357.427598)
			(xy 88.524588 -357.412544) (xy 88.536216 -357.404727) (xy 88.554933 -357.383886) (xy 88.567286 -357.358745)
			(xy 88.572344 -357.331193) (xy 88.569727 -357.303304) (xy 88.559632 -357.277174) (xy 88.542819 -357.254769)
			(xy 88.531954 -357.24592) (xy 88.509103 -357.227703) (xy 88.468635 -357.185548) (xy 88.435063 -357.137719)
			(xy 88.409171 -357.085333) (xy 88.391564 -357.029614) (xy 88.382653 -356.971862) (xy 88.382094 -356.942644)
			(xy 88.382629 -356.913474) (xy 88.391536 -356.855819) (xy 88.409119 -356.800192) (xy 88.434968 -356.747892)
			(xy 88.468479 -356.700137) (xy 88.508871 -356.658042) (xy 88.5317 -356.639876) (xy 88.54349 -356.630122)
			(xy 88.561192 -356.605185) (xy 88.570719 -356.576125) (xy 88.571214 -356.545548) (xy 88.562635 -356.516195)
			(xy 88.54575 -356.490697) (xy 88.53424 -356.480618) (xy 88.512834 -356.462404) (xy 88.475099 -356.420752)
			(xy 88.443881 -356.374015) (xy 88.419855 -356.323205) (xy 88.403543 -356.269421) (xy 88.395295 -356.213826)
			(xy 88.394794 -356.185724) (xy 88.395234 -356.15908) (xy 88.40264 -356.106308) (xy 88.417325 -356.055083)
			(xy 88.439004 -356.006404) (xy 88.467252 -355.961219) (xy 88.50152 -355.920409) (xy 88.521032 -355.90226)
			(xy 88.530713 -355.892925) (xy 88.545327 -355.870366) (xy 88.553537 -355.844771) (xy 88.554773 -355.81792)
			(xy 88.548948 -355.791679) (xy 88.536467 -355.767873) (xy 88.527636 -355.757734) (xy 88.508665 -355.736462)
			(xy 88.476607 -355.689336) (xy 88.451906 -355.637971) (xy 88.435109 -355.583507) (xy 88.42659 -355.527151)
			(xy 88.426036 -355.498654) (xy 88.426435 -355.4714) (xy 88.434199 -355.417446) (xy 88.449562 -355.365147)
			(xy 88.472212 -355.315567) (xy 88.501687 -355.269715) (xy 88.537388 -355.228524) (xy 88.578587 -355.192833)
			(xy 88.624446 -355.163369) (xy 88.674032 -355.140731) (xy 88.726335 -355.12538) (xy 88.78029 -355.117629)
			(xy 88.807544 -355.117146) (xy 88.834954 -355.117634) (xy 88.889209 -355.125473) (xy 88.941784 -355.140999)
			(xy 88.991595 -355.163892) (xy 89.037615 -355.193679) (xy 89.078897 -355.229748) (xy 89.097104 -355.250242)
			(xy 89.106461 -355.260357) (xy 89.12933 -355.275699) (xy 89.155469 -355.284364) (xy 89.182974 -355.285721)
			(xy 89.20984 -355.279669) (xy 89.234107 -355.266652) (xy 89.254008 -355.247617) (xy 89.261442 -355.236018)
			(xy 89.276312 -355.212088) (xy 89.31195 -355.168457) (xy 89.353619 -355.130542) (xy 89.400412 -355.099171)
			(xy 89.451312 -355.075025) (xy 89.50521 -355.058629) (xy 89.560934 -355.050342) (xy 89.589102 -355.049836)
			(xy 89.61802 -355.050339) (xy 89.675192 -355.05907) (xy 89.730392 -355.07633) (xy 89.782354 -355.101724)
			(xy 89.829887 -355.134671) (xy 89.871903 -355.174415) (xy 89.890092 -355.196902) (xy 89.899989 -355.208707)
			(xy 89.925313 -355.226226) (xy 89.954706 -355.235402) (xy 89.985498 -355.235402) (xy 90.014891 -355.226226)
			(xy 90.040215 -355.208707) (xy 90.050112 -355.196902) (xy 90.066865 -355.176119) (xy 90.105219 -355.138989)
			(xy 90.148373 -355.107567) (xy 90.195487 -355.082468) (xy 90.245639 -355.064182) (xy 90.29785 -355.053065)
			(xy 90.351102 -355.049335) (xy 90.404354 -355.053065) (xy 90.456565 -355.064182) (xy 90.506717 -355.082468)
			(xy 90.553831 -355.107567) (xy 90.596985 -355.138989) (xy 90.635339 -355.176119) (xy 90.652092 -355.196902)
			(xy 90.661989 -355.208707) (xy 90.687313 -355.226226) (xy 90.716706 -355.235402) (xy 90.747498 -355.235402)
			(xy 90.776891 -355.226226) (xy 90.802215 -355.208707) (xy 90.812112 -355.196902) (xy 90.830297 -355.174413)
			(xy 90.872318 -355.134678) (xy 90.919854 -355.10174) (xy 90.971816 -355.076352) (xy 91.027015 -355.059097)
			(xy 91.084186 -355.05037) (xy 91.113102 -355.049836) (xy 91.142411 -355.05037) (xy 91.200337 -355.059342)
			(xy 91.256208 -355.077074) (xy 91.308707 -355.103148) (xy 91.356596 -355.13695) (xy 91.398748 -355.177684)
			(xy 91.416886 -355.200712) (xy 91.426627 -355.212609) (xy 91.451624 -355.230485) (xy 91.48081 -355.240107)
			(xy 91.511537 -355.240603) (xy 91.541018 -355.231927) (xy 91.566578 -355.214866) (xy 91.576652 -355.203252)
			(xy 91.594896 -355.181695) (xy 91.636601 -355.143621) (xy 91.683463 -355.112111) (xy 91.734459 -355.087854)
			(xy 91.788474 -355.07138) (xy 91.844327 -355.063049) (xy 91.872562 -355.062536) (xy 91.901479 -355.063068)
			(xy 91.95865 -355.071792) (xy 92.013849 -355.089047) (xy 92.065811 -355.114436) (xy 92.113345 -355.147377)
			(xy 92.155362 -355.187117) (xy 92.173552 -355.209602) (xy 92.183449 -355.221407) (xy 92.208773 -355.238926)
			(xy 92.238166 -355.248102) (xy 92.268958 -355.248102) (xy 92.298351 -355.238926) (xy 92.323675 -355.221407)
			(xy 92.333572 -355.209602) (xy 92.350325 -355.188819) (xy 92.388679 -355.151689) (xy 92.431833 -355.120267)
			(xy 92.478947 -355.095168) (xy 92.529099 -355.076882) (xy 92.58131 -355.065765) (xy 92.634562 -355.062035)
			(xy 92.687814 -355.065765) (xy 92.740025 -355.076882) (xy 92.790177 -355.095168) (xy 92.837291 -355.120267)
			(xy 92.880445 -355.151689) (xy 92.918799 -355.188819) (xy 92.935552 -355.209602) (xy 92.945449 -355.221407)
			(xy 92.970773 -355.238926) (xy 93.000166 -355.248102) (xy 93.030958 -355.248102) (xy 93.060351 -355.238926)
			(xy 93.085675 -355.221407) (xy 93.095572 -355.209602) (xy 93.112325 -355.188819) (xy 93.150679 -355.151689)
			(xy 93.193833 -355.120267) (xy 93.240947 -355.095168) (xy 93.291099 -355.076882) (xy 93.34331 -355.065765)
			(xy 93.396562 -355.062035) (xy 93.449814 -355.065765) (xy 93.502025 -355.076882) (xy 93.552177 -355.095168)
			(xy 93.599291 -355.120267) (xy 93.642445 -355.151689) (xy 93.680799 -355.188819) (xy 93.697552 -355.209602)
			(xy 93.707449 -355.221407) (xy 93.732773 -355.238926) (xy 93.762166 -355.248102) (xy 93.792958 -355.248102)
			(xy 93.822351 -355.238926) (xy 93.847675 -355.221407) (xy 93.857572 -355.209602) (xy 93.874325 -355.188819)
			(xy 93.912679 -355.151689) (xy 93.955833 -355.120267) (xy 94.002947 -355.095168) (xy 94.053099 -355.076882)
			(xy 94.10531 -355.065765) (xy 94.158562 -355.062035) (xy 94.211814 -355.065765) (xy 94.264025 -355.076882)
			(xy 94.314177 -355.095168) (xy 94.361291 -355.120267) (xy 94.404445 -355.151689) (xy 94.442799 -355.188819)
			(xy 94.459552 -355.209602) (xy 94.469449 -355.221407) (xy 94.494773 -355.238926) (xy 94.524166 -355.248102)
			(xy 94.554958 -355.248102) (xy 94.584351 -355.238926) (xy 94.609675 -355.221407) (xy 94.619572 -355.209602)
			(xy 94.637779 -355.187132) (xy 94.679796 -355.147396) (xy 94.727327 -355.114456) (xy 94.779285 -355.089065)
			(xy 94.83448 -355.071805) (xy 94.891647 -355.063073) (xy 94.920562 -355.062536) (xy 94.946814 -355.062978)
			(xy 94.998823 -355.070162) (xy 95.049354 -355.084412) (xy 95.097454 -355.10546) (xy 95.142211 -355.132907)
			(xy 95.182779 -355.166235) (xy 95.218392 -355.204813) (xy 95.233744 -355.226112) (xy 95.242108 -355.237325)
			(xy 95.263733 -355.255051) (xy 95.289357 -355.266248) (xy 95.317056 -355.270076) (xy 95.344755 -355.266248)
			(xy 95.370379 -355.255051) (xy 95.392004 -355.237325) (xy 95.400368 -355.226112) (xy 95.415735 -355.204826)
			(xy 95.451355 -355.166259) (xy 95.491925 -355.132939) (xy 95.536679 -355.105493) (xy 95.584773 -355.084441)
			(xy 95.635297 -355.070179) (xy 95.6873 -355.062976) (xy 95.71355 -355.062536) (xy 95.742466 -355.063076)
			(xy 95.799637 -355.071799) (xy 95.854836 -355.089052) (xy 95.906798 -355.114439) (xy 95.954333 -355.147379)
			(xy 95.99635 -355.187118) (xy 96.01454 -355.209602) (xy 96.024437 -355.221407) (xy 96.049761 -355.238926)
			(xy 96.079154 -355.248102) (xy 96.109946 -355.248102) (xy 96.139339 -355.238926) (xy 96.164663 -355.221407)
			(xy 96.17456 -355.209602) (xy 96.192774 -355.187138) (xy 96.234789 -355.147402) (xy 96.282319 -355.11446)
			(xy 96.334276 -355.089068) (xy 96.389469 -355.071808) (xy 96.446635 -355.063074) (xy 96.47555 -355.062536)
			(xy 96.502804 -355.063002) (xy 96.556757 -355.070753) (xy 96.609057 -355.086105) (xy 96.65864 -355.108745)
			(xy 96.704496 -355.138212) (xy 96.74569 -355.173906) (xy 96.781384 -355.2151) (xy 96.810852 -355.260955)
			(xy 96.833493 -355.310537) (xy 96.848845 -355.362837) (xy 96.856598 -355.41679) (xy 96.857058 -355.444044)
			(xy 96.856516 -355.47296) (xy 96.847794 -355.530131) (xy 96.830542 -355.58533) (xy 96.805155 -355.637292)
			(xy 96.772215 -355.684827) (xy 96.732476 -355.726844) (xy 96.709992 -355.745034) (xy 96.698145 -355.754885)
			(xy 96.680632 -355.780222) (xy 96.671463 -355.809627) (xy 96.671471 -355.840427) (xy 96.680655 -355.869827)
			(xy 96.698182 -355.895155) (xy 96.709992 -355.905054) (xy 96.730821 -355.921754) (xy 96.767956 -355.960111)
			(xy 96.799382 -356.003272) (xy 96.824483 -356.050391) (xy 96.84277 -356.10055) (xy 96.853885 -356.152769)
			(xy 96.857612 -356.206027) (xy 96.853878 -356.259285) (xy 96.842755 -356.311502) (xy 96.824461 -356.361658)
			(xy 96.799353 -356.408774) (xy 96.767921 -356.45193) (xy 96.73078 -356.490282) (xy 96.709992 -356.507034)
			(xy 96.698145 -356.516885) (xy 96.680632 -356.542222) (xy 96.671463 -356.571627) (xy 96.671471 -356.602427)
			(xy 96.680655 -356.631827) (xy 96.698182 -356.657155) (xy 96.709992 -356.667054) (xy 96.730821 -356.683754)
			(xy 96.767956 -356.722111) (xy 96.799382 -356.765272) (xy 96.824483 -356.812391) (xy 96.84277 -356.86255)
			(xy 96.853885 -356.914769) (xy 96.857612 -356.968027) (xy 96.853878 -357.021285) (xy 96.842755 -357.073502)
			(xy 96.824461 -357.123658) (xy 96.799353 -357.170774) (xy 96.767921 -357.21393) (xy 96.73078 -357.252282)
			(xy 96.709992 -357.269034) (xy 96.698145 -357.278885) (xy 96.680632 -357.304222) (xy 96.671463 -357.333627)
			(xy 96.671471 -357.364427) (xy 96.680655 -357.393827) (xy 96.698182 -357.419155) (xy 96.709992 -357.429054)
			(xy 96.730821 -357.445754) (xy 96.767956 -357.484111) (xy 96.799382 -357.527272) (xy 96.824483 -357.574391)
			(xy 96.84277 -357.62455) (xy 96.853885 -357.676769) (xy 96.857612 -357.730027) (xy 96.853878 -357.783285)
			(xy 96.842755 -357.835502) (xy 96.824461 -357.885658) (xy 96.799353 -357.932774) (xy 96.767921 -357.97593)
			(xy 96.73078 -358.014282) (xy 96.709992 -358.031034) (xy 96.698145 -358.040885) (xy 96.680632 -358.066222)
			(xy 96.671463 -358.095627) (xy 96.671471 -358.126427) (xy 96.680655 -358.155827) (xy 96.698182 -358.181155)
			(xy 96.709992 -358.191054) (xy 96.730821 -358.207754) (xy 96.767956 -358.246111) (xy 96.799382 -358.289272)
			(xy 96.824483 -358.336391) (xy 96.84277 -358.38655) (xy 96.853885 -358.438769) (xy 96.857612 -358.492027)
			(xy 96.853878 -358.545285) (xy 96.842755 -358.597502) (xy 96.824461 -358.647658) (xy 96.799353 -358.694774)
			(xy 96.767921 -358.73793) (xy 96.73078 -358.776282) (xy 96.709992 -358.793034) (xy 96.698145 -358.802885)
			(xy 96.680632 -358.828222) (xy 96.671463 -358.857627) (xy 96.671471 -358.888427) (xy 96.680655 -358.917827)
			(xy 96.698182 -358.943155) (xy 96.709992 -358.953054) (xy 96.729131 -358.968448) (xy 96.763674 -359.003367)
			(xy 96.793431 -359.042444) (xy 96.806004 -359.063544) (xy 96.813045 -359.074858) (xy 96.831859 -359.093715)
			(xy 96.854915 -359.107054) (xy 96.88064 -359.113965) (xy 96.907277 -359.113976) (xy 96.933007 -359.107086)
			(xy 96.956075 -359.093766) (xy 96.96577 -359.084626) (xy 98.208084 -357.842566) (xy 98.208084 -355.33457)
			(xy 98.208538 -355.30545) (xy 98.216137 -355.247707) (xy 98.231212 -355.191452) (xy 98.253507 -355.137648)
			(xy 98.282639 -355.087217) (xy 98.318109 -355.041023) (xy 98.338386 -355.020118) (xy 99.194366 -354.164138)
			(xy 99.215251 -354.14384) (xy 99.261453 -354.10838) (xy 99.31189 -354.079257) (xy 99.365697 -354.056967)
			(xy 99.421954 -354.041892) (xy 99.479697 -354.034291) (xy 99.508818 -354.033836) (xy 100.343716 -354.033836)
			(xy 100.372837 -354.034284) (xy 100.43058 -354.041882) (xy 100.486836 -354.056957) (xy 100.540641 -354.079253)
			(xy 100.591071 -354.108387) (xy 100.637264 -354.143859) (xy 100.658168 -354.164138) (xy 100.953157 -354.459032)
			(xy 101.443534 -354.459032) (xy 101.447605 -354.40341) (xy 101.459731 -354.348973) (xy 101.479654 -354.296882)
			(xy 101.50695 -354.248247) (xy 101.541036 -354.204104) (xy 101.581185 -354.165395) (xy 101.626543 -354.132944)
			(xy 101.676143 -354.107443) (xy 101.728927 -354.089436) (xy 101.78377 -354.079306) (xy 101.839504 -354.077269)
			(xy 101.894941 -354.083369) (xy 101.948898 -354.097475) (xy 102.000227 -354.119287) (xy 102.047833 -354.148341)
			(xy 102.090701 -354.184016) (xy 102.127918 -354.225553) (xy 102.158691 -354.272066) (xy 102.182363 -354.322563)
			(xy 102.198431 -354.37597) (xy 102.206551 -354.431146) (xy 102.20706 -354.459032) (xy 102.206551 -354.486918)
			(xy 102.198431 -354.542094) (xy 102.182363 -354.595501) (xy 102.158691 -354.645998) (xy 102.127918 -354.692511)
			(xy 102.090701 -354.734048) (xy 102.047833 -354.769723) (xy 102.000227 -354.798777) (xy 101.948898 -354.820589)
			(xy 101.894941 -354.834695) (xy 101.839504 -354.840795) (xy 101.78377 -354.838758) (xy 101.728927 -354.828628)
			(xy 101.676143 -354.810621) (xy 101.626543 -354.78512) (xy 101.581185 -354.752669) (xy 101.541036 -354.71396)
			(xy 101.50695 -354.669817) (xy 101.479654 -354.621182) (xy 101.459731 -354.569091) (xy 101.447605 -354.514654)
			(xy 101.443534 -354.459032) (xy 100.953157 -354.459032) (xy 101.448108 -354.953824) (xy 101.874066 -354.953824)
			(xy 101.904475 -354.954253) (xy 101.964728 -354.96253) (xy 102.023292 -354.978935) (xy 102.079076 -355.003162)
			(xy 102.131042 -355.03476) (xy 102.178221 -355.073139) (xy 102.219735 -355.117586) (xy 102.254809 -355.167272)
			(xy 102.282791 -355.221271) (xy 102.303158 -355.278577) (xy 102.315533 -355.338123) (xy 102.319684 -355.3988)
			(xy 102.315533 -355.459477) (xy 102.303158 -355.519023) (xy 102.282791 -355.576329) (xy 102.254809 -355.630328)
			(xy 102.219735 -355.680014) (xy 102.178221 -355.724461) (xy 102.131042 -355.76284) (xy 102.079076 -355.794438)
			(xy 102.023292 -355.818665) (xy 101.964728 -355.83507) (xy 101.904475 -355.843347) (xy 101.874066 -355.84384)
			(xy 101.263958 -355.84384) (xy 101.234833 -355.843333) (xy 101.177088 -355.835676) (xy 101.120835 -355.82055)
			(xy 101.067037 -355.798214) (xy 101.016612 -355.76905) (xy 100.970424 -355.733556) (xy 100.949506 -355.713284)
			(xy 100.344986 -355.109018) (xy 100.333953 -355.098632) (xy 100.307244 -355.084349) (xy 100.27752 -355.078533)
			(xy 100.247398 -355.081696) (xy 100.21953 -355.09356) (xy 100.196371 -355.113079) (xy 100.179959 -355.138535)
			(xy 100.175314 -355.15296) (xy 100.167377 -355.179192) (xy 100.144923 -355.229188) (xy 100.115545 -355.275456)
			(xy 100.079848 -355.317043) (xy 100.038567 -355.353093) (xy 99.992552 -355.382865) (xy 99.942749 -355.405745)
			(xy 99.890185 -355.421262) (xy 99.835941 -355.429096) (xy 99.808538 -355.429566) (xy 99.779062 -355.429007)
			(xy 99.720812 -355.419943) (xy 99.664649 -355.402026) (xy 99.611912 -355.375681) (xy 99.563855 -355.341537)
			(xy 99.521623 -355.300406) (xy 99.503484 -355.277166) (xy 99.494425 -355.26578) (xy 99.471138 -355.248349)
			(xy 99.443882 -355.23819) (xy 99.414868 -355.236125) (xy 99.386448 -355.242323) (xy 99.360928 -355.256281)
			(xy 99.350322 -355.266244) (xy 99.097592 -355.51872) (xy 99.097592 -356.164642) (xy 99.098117 -356.179715)
			(xy 99.106931 -356.208543) (xy 99.12378 -356.233541) (xy 99.147193 -356.25253) (xy 99.175131 -356.263855)
			(xy 99.205158 -356.266528) (xy 99.22002 -356.263956) (xy 99.239048 -356.260281) (xy 99.277604 -356.256341)
			(xy 99.296982 -356.256082) (xy 99.297236 -356.256082) (xy 99.324485 -356.256591) (xy 99.361556 -356.261924)
			(xy 103.482392 -356.261924) (xy 103.486463 -356.206302) (xy 103.498589 -356.151865) (xy 103.518512 -356.099774)
			(xy 103.545808 -356.051139) (xy 103.579894 -356.006996) (xy 103.620043 -355.968287) (xy 103.665401 -355.935836)
			(xy 103.715001 -355.910335) (xy 103.767785 -355.892328) (xy 103.822628 -355.882198) (xy 103.878362 -355.880161)
			(xy 103.933799 -355.886261) (xy 103.987756 -355.900367) (xy 104.039085 -355.922179) (xy 104.086691 -355.951233)
			(xy 104.129559 -355.986908) (xy 104.166776 -356.028445) (xy 104.197549 -356.074958) (xy 104.221221 -356.125455)
			(xy 104.237289 -356.178862) (xy 104.245409 -356.234038) (xy 104.245918 -356.261924) (xy 104.245409 -356.28981)
			(xy 104.237289 -356.344986) (xy 104.221221 -356.398393) (xy 104.197549 -356.44889) (xy 104.166776 -356.495403)
			(xy 104.129559 -356.53694) (xy 104.086691 -356.572615) (xy 104.039085 -356.601669) (xy 103.987756 -356.623481)
			(xy 103.933799 -356.637587) (xy 103.878362 -356.643687) (xy 103.822628 -356.64165) (xy 103.767785 -356.63152)
			(xy 103.715001 -356.613513) (xy 103.665401 -356.588012) (xy 103.620043 -356.555561) (xy 103.579894 -356.516852)
			(xy 103.545808 -356.472709) (xy 103.518512 -356.424074) (xy 103.498589 -356.371983) (xy 103.486463 -356.317546)
			(xy 103.482392 -356.261924) (xy 99.361556 -356.261924) (xy 99.378427 -356.264351) (xy 99.430716 -356.279709)
			(xy 99.480287 -356.302352) (xy 99.526132 -356.331818) (xy 99.567317 -356.367509) (xy 99.603004 -356.408697)
			(xy 99.632466 -356.454544) (xy 99.655104 -356.504118) (xy 99.670456 -356.556408) (xy 99.678212 -356.610351)
			(xy 99.678212 -356.664849) (xy 99.670456 -356.718792) (xy 99.655104 -356.771082) (xy 99.632466 -356.820656)
			(xy 99.603004 -356.866503) (xy 99.567317 -356.907691) (xy 99.526132 -356.943382) (xy 99.480287 -356.972848)
			(xy 99.430716 -356.995491) (xy 99.378427 -357.010849) (xy 99.324485 -357.018609) (xy 99.297236 -357.019098)
			(xy 99.263693 -357.018395) (xy 99.197645 -357.00664) (xy 99.165918 -356.99573) (xy 99.157536 -356.992682)
			(xy 99.097592 -356.992682) (xy 99.097592 -357.058722) (xy 99.09805 -357.073798) (xy 99.106885 -357.102628)
			(xy 99.123749 -357.127624) (xy 99.147174 -357.14661) (xy 99.17512 -357.157933) (xy 99.205154 -357.160607)
			(xy 99.22002 -357.158036) (xy 99.239048 -357.154361) (xy 99.277604 -357.150421) (xy 99.296982 -357.150162)
			(xy 99.297236 -357.150162) (xy 99.324487 -357.150644) (xy 99.378433 -357.158405) (xy 99.430726 -357.173763)
			(xy 99.480301 -357.196406) (xy 99.52615 -357.225873) (xy 99.567339 -357.261565) (xy 99.60303 -357.302755)
			(xy 99.632497 -357.348604) (xy 99.655139 -357.39818) (xy 99.670496 -357.450473) (xy 99.678256 -357.504419)
			(xy 99.678744 -357.53167) (xy 99.678744 -357.532432) (xy 99.67835 -357.556511) (xy 99.67224 -357.604281)
			(xy 99.666552 -357.627682) (xy 99.663517 -357.640613) (xy 99.663672 -357.667169) (xy 99.670672 -357.692786)
			(xy 99.684044 -357.715731) (xy 99.702881 -357.73445) (xy 99.72591 -357.747676) (xy 99.751571 -357.754514)
			(xy 99.76485 -357.754936) (xy 100.246942 -357.754936) (xy 101.520752 -356.481126) (xy 101.541641 -356.460832)
			(xy 101.587843 -356.425373) (xy 101.638279 -356.396249) (xy 101.692085 -356.373958) (xy 101.748341 -356.358882)
			(xy 101.806084 -356.35128) (xy 101.835204 -356.350824) (xy 101.864331 -356.351264) (xy 101.922087 -356.358866)
			(xy 101.978357 -356.373939) (xy 102.032179 -356.396225) (xy 102.082634 -356.425344) (xy 102.128857 -356.460797)
			(xy 102.170059 -356.501979) (xy 102.205535 -356.548185) (xy 102.234678 -356.598625) (xy 102.256991 -356.652436)
			(xy 102.272092 -356.708699) (xy 102.279722 -356.766451) (xy 102.280212 -356.795578) (xy 102.279736 -356.824704)
			(xy 102.272074 -356.882451) (xy 102.256942 -356.938705) (xy 102.2346 -356.992503) (xy 102.205431 -357.042927)
			(xy 102.169931 -357.089113) (xy 102.149656 -357.11003) (xy 102.084124 -357.175816) (xy 102.074115 -357.186531)
			(xy 102.060121 -357.212283) (xy 102.054027 -357.240951) (xy 102.056339 -357.270168) (xy 102.066863 -357.297521)
			(xy 102.084732 -357.320752) (xy 102.096316 -357.32974) (xy 102.120278 -357.347734) (xy 102.163594 -357.389145)
			(xy 102.200958 -357.435996) (xy 102.231692 -357.48744) (xy 102.255242 -357.542544) (xy 102.27118 -357.600311)
			(xy 102.279218 -357.659695) (xy 102.279704 -357.689658) (xy 102.279218 -357.718784) (xy 102.271558 -357.77653)
			(xy 102.256428 -357.832784) (xy 102.234089 -357.886582) (xy 102.20492 -357.937006) (xy 102.169422 -357.983193)
			(xy 102.149148 -358.00411) (xy 101.931981 -358.221277) (xy 103.496811 -358.221277) (xy 103.504564 -358.167319)
			(xy 103.519917 -358.115013) (xy 103.542559 -358.065425) (xy 103.572026 -358.019564) (xy 103.607721 -357.978364)
			(xy 103.648916 -357.942663) (xy 103.694772 -357.913188) (xy 103.744356 -357.890539) (xy 103.796659 -357.875177)
			(xy 103.850616 -357.867415) (xy 103.877872 -357.86695) (xy 103.894015 -357.867093) (xy 103.926189 -357.869764)
			(xy 103.942134 -357.872284) (xy 103.956157 -357.874251) (xy 103.9843 -357.871191) (xy 104.01052 -357.860522)
			(xy 104.032803 -357.843063) (xy 104.049435 -357.820157) (xy 104.059139 -357.793564) (xy 104.061168 -357.765328)
			(xy 104.05872 -357.75138) (xy 104.054913 -357.732111) (xy 104.050845 -357.693042) (xy 104.050592 -357.673402)
			(xy 104.051053 -357.646149) (xy 104.05881 -357.592198) (xy 104.074166 -357.539899) (xy 104.096808 -357.490319)
			(xy 104.126276 -357.444465) (xy 104.16197 -357.403272) (xy 104.203163 -357.367578) (xy 104.249016 -357.33811)
			(xy 104.298596 -357.315467) (xy 104.350894 -357.300111) (xy 104.404846 -357.292353) (xy 104.459352 -357.292353)
			(xy 104.513303 -357.30011) (xy 104.565601 -357.315466) (xy 104.615182 -357.338109) (xy 104.661035 -357.367577)
			(xy 104.702228 -357.40327) (xy 104.737922 -357.444463) (xy 104.767391 -357.490317) (xy 104.790033 -357.539897)
			(xy 104.805389 -357.592195) (xy 104.813147 -357.646146) (xy 104.813147 -357.700652) (xy 104.80539 -357.754604)
			(xy 104.790034 -357.806902) (xy 104.767391 -357.856482) (xy 104.737923 -357.902336) (xy 104.702229 -357.943529)
			(xy 104.661036 -357.979223) (xy 104.615183 -358.008691) (xy 104.565602 -358.031333) (xy 104.513304 -358.04669)
			(xy 104.459353 -358.054447) (xy 104.4321 -358.05491) (xy 104.415957 -358.054772) (xy 104.383783 -358.052097)
			(xy 104.367838 -358.049576) (xy 104.353814 -358.047629) (xy 104.325679 -358.050694) (xy 104.299465 -358.061365)
			(xy 104.277187 -358.07882) (xy 104.260555 -358.10172) (xy 104.250848 -358.128305) (xy 104.248811 -358.156533)
			(xy 104.251252 -358.17048) (xy 104.255053 -358.18975) (xy 104.259125 -358.228818) (xy 104.25938 -358.248458)
			(xy 104.25899 -358.275714) (xy 104.251238 -358.329672) (xy 104.235886 -358.381978) (xy 104.213246 -358.431566)
			(xy 104.183779 -358.477428) (xy 104.148086 -358.518629) (xy 104.106892 -358.554332) (xy 104.061036 -358.583808)
			(xy 104.011452 -358.606458) (xy 103.95915 -358.621821) (xy 103.905193 -358.629584) (xy 103.850681 -358.62959)
			(xy 103.796723 -358.621837) (xy 103.744418 -358.606484) (xy 103.694829 -358.583844) (xy 103.648968 -358.554376)
			(xy 103.607767 -358.518682) (xy 103.572066 -358.477488) (xy 103.54259 -358.431632) (xy 103.51994 -358.382048)
			(xy 103.504578 -358.329745) (xy 103.496815 -358.275789) (xy 103.496811 -358.221277) (xy 101.931981 -358.221277)
			(xy 101.105716 -359.047542) (xy 101.084791 -359.067797) (xy 101.038597 -359.103261) (xy 100.988169 -359.132392)
			(xy 100.93437 -359.154689) (xy 100.87812 -359.169773) (xy 100.820382 -359.177384) (xy 100.791264 -359.177844)
			(xy 100.472748 -359.177844) (xy 100.462592 -359.188004) (xy 104.05313 -359.188004) (xy 104.057201 -359.132382)
			(xy 104.069327 -359.077945) (xy 104.08925 -359.025854) (xy 104.116546 -358.977219) (xy 104.150632 -358.933076)
			(xy 104.190781 -358.894367) (xy 104.236139 -358.861916) (xy 104.285739 -358.836415) (xy 104.338523 -358.818408)
			(xy 104.393366 -358.808278) (xy 104.4491 -358.806241) (xy 104.504537 -358.812341) (xy 104.558494 -358.826447)
			(xy 104.609823 -358.848259) (xy 104.657429 -358.877313) (xy 104.700297 -358.912988) (xy 104.737514 -358.954525)
			(xy 104.768287 -359.001038) (xy 104.791959 -359.051535) (xy 104.808027 -359.104942) (xy 104.816147 -359.160118)
			(xy 104.816656 -359.188004) (xy 104.816147 -359.21589) (xy 104.808027 -359.271066) (xy 104.791959 -359.324473)
			(xy 104.768287 -359.37497) (xy 104.737514 -359.421483) (xy 104.700297 -359.46302) (xy 104.657429 -359.498695)
			(xy 104.609823 -359.527749) (xy 104.558494 -359.549561) (xy 104.504537 -359.563667) (xy 104.4491 -359.569767)
			(xy 104.393366 -359.56773) (xy 104.338523 -359.5576) (xy 104.285739 -359.539593) (xy 104.236139 -359.514092)
			(xy 104.190781 -359.481641) (xy 104.150632 -359.442932) (xy 104.116546 -359.398789) (xy 104.08925 -359.350154)
			(xy 104.069327 -359.298063) (xy 104.057201 -359.243626) (xy 104.05313 -359.188004) (xy 100.462592 -359.188004)
			(xy 99.757992 -359.892854) (xy 99.747756 -359.904018) (xy 99.733591 -359.930764) (xy 99.727879 -359.960486)
			(xy 99.730528 -359.985056) (xy 101.469696 -359.985056) (xy 101.473767 -359.929434) (xy 101.485893 -359.874997)
			(xy 101.505816 -359.822906) (xy 101.533112 -359.774271) (xy 101.567198 -359.730128) (xy 101.607347 -359.691419)
			(xy 101.652705 -359.658968) (xy 101.702305 -359.633467) (xy 101.755089 -359.61546) (xy 101.809932 -359.60533)
			(xy 101.865666 -359.603293) (xy 101.921103 -359.609393) (xy 101.97506 -359.623499) (xy 102.026389 -359.645311)
			(xy 102.073995 -359.674365) (xy 102.116863 -359.71004) (xy 102.15408 -359.751577) (xy 102.184853 -359.79809)
			(xy 102.208525 -359.848587) (xy 102.224593 -359.901994) (xy 102.232713 -359.95717) (xy 102.233222 -359.985056)
			(xy 102.232713 -360.012942) (xy 102.224593 -360.068118) (xy 102.208525 -360.121525) (xy 102.184853 -360.172022)
			(xy 102.155123 -360.216958) (xy 103.98963 -360.216958) (xy 103.993701 -360.161336) (xy 104.005827 -360.106899)
			(xy 104.02575 -360.054808) (xy 104.053046 -360.006173) (xy 104.087132 -359.96203) (xy 104.127281 -359.923321)
			(xy 104.172639 -359.89087) (xy 104.222239 -359.865369) (xy 104.275023 -359.847362) (xy 104.329866 -359.837232)
			(xy 104.3856 -359.835195) (xy 104.441037 -359.841295) (xy 104.494994 -359.855401) (xy 104.546323 -359.877213)
			(xy 104.593929 -359.906267) (xy 104.636797 -359.941942) (xy 104.674014 -359.983479) (xy 104.704787 -360.029992)
			(xy 104.728459 -360.080489) (xy 104.744527 -360.133896) (xy 104.752647 -360.189072) (xy 104.753156 -360.216958)
			(xy 104.752647 -360.244844) (xy 104.744527 -360.30002) (xy 104.728459 -360.353427) (xy 104.704787 -360.403924)
			(xy 104.674014 -360.450437) (xy 104.636797 -360.491974) (xy 104.593929 -360.527649) (xy 104.546323 -360.556703)
			(xy 104.494994 -360.578515) (xy 104.441037 -360.592621) (xy 104.3856 -360.598721) (xy 104.329866 -360.596684)
			(xy 104.275023 -360.586554) (xy 104.222239 -360.568547) (xy 104.172639 -360.543046) (xy 104.127281 -360.510595)
			(xy 104.087132 -360.471886) (xy 104.053046 -360.427743) (xy 104.02575 -360.379108) (xy 104.005827 -360.327017)
			(xy 103.993701 -360.27258) (xy 103.98963 -360.216958) (xy 102.155123 -360.216958) (xy 102.15408 -360.218535)
			(xy 102.116863 -360.260072) (xy 102.073995 -360.295747) (xy 102.026389 -360.324801) (xy 101.97506 -360.346613)
			(xy 101.921103 -360.360719) (xy 101.865666 -360.366819) (xy 101.809932 -360.364782) (xy 101.755089 -360.354652)
			(xy 101.702305 -360.336645) (xy 101.652705 -360.311144) (xy 101.607347 -360.278693) (xy 101.567198 -360.239984)
			(xy 101.533112 -360.195841) (xy 101.505816 -360.147206) (xy 101.485893 -360.095115) (xy 101.473767 -360.040678)
			(xy 101.469696 -359.985056) (xy 99.730528 -359.985056) (xy 99.731123 -359.990577) (xy 99.743036 -360.018399)
			(xy 99.762575 -360.041513) (xy 99.788026 -360.057891) (xy 99.802442 -360.062526) (xy 99.828785 -360.070447)
			(xy 99.879062 -360.092759) (xy 99.925613 -360.122062) (xy 99.967473 -360.157748) (xy 100.003771 -360.199077)
			(xy 100.033757 -360.245191) (xy 100.056808 -360.295135) (xy 100.072445 -360.347871) (xy 100.080345 -360.402307)
			(xy 100.080826 -360.42981) (xy 100.080332 -360.457061) (xy 100.072574 -360.511007) (xy 100.057219 -360.563301)
			(xy 100.034578 -360.612877) (xy 100.005112 -360.658726) (xy 99.969422 -360.699916) (xy 99.928233 -360.735607)
			(xy 99.882384 -360.765074) (xy 99.832808 -360.787716) (xy 99.780515 -360.803072) (xy 99.726569 -360.810831)
			(xy 99.699318 -360.811318) (xy 99.673858 -360.810928) (xy 99.62339 -360.804155) (xy 99.574272 -360.790729)
			(xy 99.527377 -360.770886) (xy 99.483539 -360.744981) (xy 99.443537 -360.713474) (xy 99.425506 -360.695494)
			(xy 99.414625 -360.68502) (xy 99.388223 -360.67039) (xy 99.358695 -360.664123) (xy 99.328626 -360.666766)
			(xy 99.300645 -360.678089) (xy 99.2772 -360.697101) (xy 99.26034 -360.722139) (xy 99.251541 -360.751013)
			(xy 99.251008 -360.766106) (xy 99.251008 -361.952032) (xy 102.011732 -361.952032) (xy 102.015803 -361.89641)
			(xy 102.027929 -361.841973) (xy 102.047852 -361.789882) (xy 102.075148 -361.741247) (xy 102.109234 -361.697104)
			(xy 102.149383 -361.658395) (xy 102.194741 -361.625944) (xy 102.244341 -361.600443) (xy 102.297125 -361.582436)
			(xy 102.351968 -361.572306) (xy 102.407702 -361.570269) (xy 102.463139 -361.576369) (xy 102.517096 -361.590475)
			(xy 102.568425 -361.612287) (xy 102.616031 -361.641341) (xy 102.658899 -361.677016) (xy 102.696116 -361.718553)
			(xy 102.726889 -361.765066) (xy 102.750561 -361.815563) (xy 102.766629 -361.86897) (xy 102.774749 -361.924146)
			(xy 102.775188 -361.948222) (xy 103.776778 -361.948222) (xy 103.780849 -361.8926) (xy 103.792975 -361.838163)
			(xy 103.812898 -361.786072) (xy 103.840194 -361.737437) (xy 103.87428 -361.693294) (xy 103.914429 -361.654585)
			(xy 103.959787 -361.622134) (xy 104.009387 -361.596633) (xy 104.062171 -361.578626) (xy 104.117014 -361.568496)
			(xy 104.172748 -361.566459) (xy 104.228185 -361.572559) (xy 104.282142 -361.586665) (xy 104.333471 -361.608477)
			(xy 104.381077 -361.637531) (xy 104.423945 -361.673206) (xy 104.461162 -361.714743) (xy 104.491935 -361.761256)
			(xy 104.515607 -361.811753) (xy 104.531675 -361.86516) (xy 104.539795 -361.920336) (xy 104.540304 -361.948222)
			(xy 104.539795 -361.976108) (xy 104.531675 -362.031284) (xy 104.515607 -362.084691) (xy 104.491935 -362.135188)
			(xy 104.461162 -362.181701) (xy 104.423945 -362.223238) (xy 104.381077 -362.258913) (xy 104.333471 -362.287967)
			(xy 104.282142 -362.309779) (xy 104.229145 -362.323634) (xy 105.517186 -362.323634) (xy 105.521257 -362.268012)
			(xy 105.533383 -362.213575) (xy 105.553306 -362.161484) (xy 105.580602 -362.112849) (xy 105.614688 -362.068706)
			(xy 105.654837 -362.029997) (xy 105.700195 -361.997546) (xy 105.749795 -361.972045) (xy 105.802579 -361.954038)
			(xy 105.857422 -361.943908) (xy 105.913156 -361.941871) (xy 105.968593 -361.947971) (xy 106.02255 -361.962077)
			(xy 106.073879 -361.983889) (xy 106.121485 -362.012943) (xy 106.164353 -362.048618) (xy 106.20157 -362.090155)
			(xy 106.232343 -362.136668) (xy 106.256015 -362.187165) (xy 106.272083 -362.240572) (xy 106.280203 -362.295748)
			(xy 106.280712 -362.323634) (xy 106.280203 -362.35152) (xy 106.272083 -362.406696) (xy 106.256015 -362.460103)
			(xy 106.232343 -362.5106) (xy 106.20157 -362.557113) (xy 106.164353 -362.59865) (xy 106.121485 -362.634325)
			(xy 106.073879 -362.663379) (xy 106.02255 -362.685191) (xy 105.968593 -362.699297) (xy 105.913156 -362.705397)
			(xy 105.857422 -362.70336) (xy 105.802579 -362.69323) (xy 105.749795 -362.675223) (xy 105.700195 -362.649722)
			(xy 105.654837 -362.617271) (xy 105.614688 -362.578562) (xy 105.580602 -362.534419) (xy 105.553306 -362.485784)
			(xy 105.533383 -362.433693) (xy 105.521257 -362.379256) (xy 105.517186 -362.323634) (xy 104.229145 -362.323634)
			(xy 104.228185 -362.323885) (xy 104.172748 -362.329985) (xy 104.117014 -362.327948) (xy 104.062171 -362.317818)
			(xy 104.009387 -362.299811) (xy 103.959787 -362.27431) (xy 103.914429 -362.241859) (xy 103.87428 -362.20315)
			(xy 103.840194 -362.159007) (xy 103.812898 -362.110372) (xy 103.792975 -362.058281) (xy 103.780849 -362.003844)
			(xy 103.776778 -361.948222) (xy 102.775188 -361.948222) (xy 102.775258 -361.952032) (xy 102.774749 -361.979918)
			(xy 102.766629 -362.035094) (xy 102.750561 -362.088501) (xy 102.726889 -362.138998) (xy 102.696116 -362.185511)
			(xy 102.658899 -362.227048) (xy 102.616031 -362.262723) (xy 102.568425 -362.291777) (xy 102.517096 -362.313589)
			(xy 102.463139 -362.327695) (xy 102.407702 -362.333795) (xy 102.351968 -362.331758) (xy 102.297125 -362.321628)
			(xy 102.244341 -362.303621) (xy 102.194741 -362.27812) (xy 102.149383 -362.245669) (xy 102.109234 -362.20696)
			(xy 102.075148 -362.162817) (xy 102.047852 -362.114182) (xy 102.027929 -362.062091) (xy 102.015803 -362.007654)
			(xy 102.011732 -361.952032) (xy 99.251008 -361.952032) (xy 99.251008 -363.148372) (xy 106.262676 -363.148372)
			(xy 106.266747 -363.09275) (xy 106.278873 -363.038313) (xy 106.298796 -362.986222) (xy 106.326092 -362.937587)
			(xy 106.360178 -362.893444) (xy 106.400327 -362.854735) (xy 106.445685 -362.822284) (xy 106.495285 -362.796783)
			(xy 106.548069 -362.778776) (xy 106.602912 -362.768646) (xy 106.658646 -362.766609) (xy 106.714083 -362.772709)
			(xy 106.76804 -362.786815) (xy 106.819369 -362.808627) (xy 106.866975 -362.837681) (xy 106.909843 -362.873356)
			(xy 106.94706 -362.914893) (xy 106.977833 -362.961406) (xy 107.001505 -363.011903) (xy 107.017573 -363.06531)
			(xy 107.025693 -363.120486) (xy 107.026202 -363.148372) (xy 107.025693 -363.176258) (xy 107.017573 -363.231434)
			(xy 107.001505 -363.284841) (xy 106.977833 -363.335338) (xy 106.94706 -363.381851) (xy 106.909843 -363.423388)
			(xy 106.866975 -363.459063) (xy 106.819369 -363.488117) (xy 106.76804 -363.509929) (xy 106.714083 -363.524035)
			(xy 106.658646 -363.530135) (xy 106.602912 -363.528098) (xy 106.548069 -363.517968) (xy 106.495285 -363.499961)
			(xy 106.445685 -363.47446) (xy 106.400327 -363.442009) (xy 106.360178 -363.4033) (xy 106.326092 -363.359157)
			(xy 106.298796 -363.310522) (xy 106.278873 -363.258431) (xy 106.266747 -363.203994) (xy 106.262676 -363.148372)
			(xy 99.251008 -363.148372) (xy 99.251008 -363.271562) (xy 99.29368 -363.278166) (xy 99.320292 -363.282786)
			(xy 99.371934 -363.298617) (xy 99.420827 -363.321573) (xy 99.465995 -363.351193) (xy 99.506535 -363.386887)
			(xy 99.541636 -363.427941) (xy 99.570598 -363.473534) (xy 99.592841 -363.522755) (xy 99.607922 -363.574621)
			(xy 99.615538 -363.628095) (xy 99.615707 -363.63783) (xy 104.371646 -363.63783) (xy 104.375717 -363.582208)
			(xy 104.387843 -363.527771) (xy 104.407766 -363.47568) (xy 104.435062 -363.427045) (xy 104.469148 -363.382902)
			(xy 104.509297 -363.344193) (xy 104.554655 -363.311742) (xy 104.604255 -363.286241) (xy 104.657039 -363.268234)
			(xy 104.711882 -363.258104) (xy 104.767616 -363.256067) (xy 104.823053 -363.262167) (xy 104.87701 -363.276273)
			(xy 104.928339 -363.298085) (xy 104.975945 -363.327139) (xy 105.018813 -363.362814) (xy 105.05603 -363.404351)
			(xy 105.086803 -363.450864) (xy 105.110475 -363.501361) (xy 105.126543 -363.554768) (xy 105.134663 -363.609944)
			(xy 105.135172 -363.63783) (xy 105.134663 -363.665716) (xy 105.126543 -363.720892) (xy 105.110475 -363.774299)
			(xy 105.086803 -363.824796) (xy 105.05603 -363.871309) (xy 105.018813 -363.912846) (xy 104.975945 -363.948521)
			(xy 104.928339 -363.977575) (xy 104.87701 -363.999387) (xy 104.823053 -364.013493) (xy 104.767616 -364.019593)
			(xy 104.711882 -364.017556) (xy 104.657039 -364.007426) (xy 104.604255 -363.989419) (xy 104.554655 -363.963918)
			(xy 104.509297 -363.931467) (xy 104.469148 -363.892758) (xy 104.435062 -363.848615) (xy 104.407766 -363.79998)
			(xy 104.387843 -363.747889) (xy 104.375717 -363.693452) (xy 104.371646 -363.63783) (xy 99.615707 -363.63783)
			(xy 99.616006 -363.655102) (xy 99.615524 -363.682353) (xy 99.607767 -363.736301) (xy 99.592412 -363.788596)
			(xy 99.56977 -363.838174) (xy 99.540304 -363.884024) (xy 99.504612 -363.925214) (xy 99.463421 -363.960906)
			(xy 99.41757 -363.990372) (xy 99.367993 -364.013013) (xy 99.315697 -364.028368) (xy 99.261749 -364.036124)
			(xy 99.234498 -364.03661) (xy 99.206365 -364.036087) (xy 99.150705 -364.027846) (xy 99.096861 -364.011515)
			(xy 99.046002 -363.987449) (xy 98.999232 -363.956168) (xy 98.957567 -363.918354) (xy 98.93935 -363.89691)
			(xy 98.929981 -363.886287) (xy 98.906709 -363.870166) (xy 98.879903 -363.86106) (xy 98.851627 -363.859669)
			(xy 98.824057 -363.8661) (xy 98.799315 -363.879859) (xy 98.788982 -363.889544) (xy 98.27387 -364.404402)
			(xy 98.252959 -364.424672) (xy 98.206763 -364.460136) (xy 98.156332 -364.489265) (xy 98.10253 -364.511561)
			(xy 98.046277 -364.526641) (xy 97.988537 -364.534247) (xy 97.959418 -364.534704) (xy 97.930295 -364.534281)
			(xy 97.872549 -364.52668) (xy 97.816288 -364.511606) (xy 97.762477 -364.489317) (xy 97.712035 -364.460194)
			(xy 97.665827 -364.424736) (xy 97.624643 -364.383549) (xy 97.589188 -364.337338) (xy 97.560069 -364.286895)
			(xy 97.537783 -364.233082) (xy 97.522713 -364.17682) (xy 97.515117 -364.119073) (xy 97.514664 -364.08995)
			(xy 97.515082 -364.060828) (xy 97.522684 -364.003083) (xy 97.537766 -363.946826) (xy 97.560067 -363.893022)
			(xy 97.589207 -363.842592) (xy 97.624685 -363.796401) (xy 97.644966 -363.775498) (xy 97.972626 -363.447584)
			(xy 97.93732 -363.41177) (xy 97.917366 -363.390927) (xy 97.88251 -363.344943) (xy 97.853896 -363.294836)
			(xy 97.832007 -363.241446) (xy 97.817211 -363.185674) (xy 97.809757 -363.128455) (xy 97.809304 -363.099604)
			(xy 97.809304 -359.744772) (xy 97.80878 -359.729772) (xy 97.800088 -359.701059) (xy 97.783431 -359.676108)
			(xy 97.760246 -359.65707) (xy 97.732531 -359.645586) (xy 97.702676 -359.642647) (xy 97.673253 -359.648505)
			(xy 97.646801 -359.662655) (xy 97.635822 -359.67289) (xy 97.59696 -359.711498) (xy 97.59696 -362.833412)
			(xy 97.596441 -362.863799) (xy 97.588166 -362.924006) (xy 97.57177 -362.982525) (xy 97.547558 -363.038267)
			(xy 97.515981 -363.090192) (xy 97.477628 -363.137335) (xy 97.433213 -363.178816) (xy 97.383563 -363.213862)
			(xy 97.329603 -363.241822) (xy 97.272339 -363.262174) (xy 97.212837 -363.274538) (xy 97.152206 -363.278686)
			(xy 97.091575 -363.274538) (xy 97.032073 -363.262174) (xy 96.974809 -363.241822) (xy 96.920849 -363.213862)
			(xy 96.871199 -363.178816) (xy 96.826784 -363.137335) (xy 96.788431 -363.090192) (xy 96.756854 -363.038267)
			(xy 96.732642 -362.982525) (xy 96.716246 -362.924006) (xy 96.707971 -362.863799) (xy 96.707452 -362.833412)
			(xy 96.707452 -359.719118) (xy 96.707013 -359.705717) (xy 96.700018 -359.679844) (xy 96.68653 -359.656682)
			(xy 96.66748 -359.637828) (xy 96.644181 -359.624581) (xy 96.618236 -359.617853) (xy 96.591435 -359.618108)
			(xy 96.57842 -359.621328) (xy 96.553225 -359.62798) (xy 96.501605 -359.635114) (xy 96.47555 -359.635552)
			(xy 96.446634 -359.635016) (xy 96.389462 -359.626293) (xy 96.334263 -359.60904) (xy 96.282301 -359.583652)
			(xy 96.234767 -359.55071) (xy 96.19275 -359.510971) (xy 96.17456 -359.488486) (xy 96.164663 -359.476681)
			(xy 96.139339 -359.459162) (xy 96.109946 -359.449986) (xy 96.079154 -359.449986) (xy 96.049761 -359.459162)
			(xy 96.024437 -359.476681) (xy 96.01454 -359.488486) (xy 95.999762 -359.506885) (xy 95.966391 -359.540256)
			(xy 95.947992 -359.555034) (xy 95.936145 -359.564885) (xy 95.918632 -359.590222) (xy 95.909463 -359.619627)
			(xy 95.909471 -359.650427) (xy 95.918655 -359.679827) (xy 95.936182 -359.705155) (xy 95.947992 -359.715054)
			(xy 95.970452 -359.733273) (xy 96.010189 -359.775287) (xy 96.043131 -359.822816) (xy 96.068523 -359.874772)
			(xy 96.085785 -359.929964) (xy 96.09452 -359.98713) (xy 96.095058 -360.016044) (xy 96.094686 -360.0433)
			(xy 96.086922 -360.097257) (xy 96.071557 -360.14956) (xy 96.048906 -360.199143) (xy 96.019429 -360.244999)
			(xy 95.983726 -360.286192) (xy 95.942523 -360.321885) (xy 95.896661 -360.351351) (xy 95.847072 -360.37399)
			(xy 95.794765 -360.389342) (xy 95.740806 -360.397093) (xy 95.71355 -360.397552) (xy 95.687299 -360.397106)
			(xy 95.635289 -360.389924) (xy 95.584757 -360.375674) (xy 95.536658 -360.354627) (xy 95.491901 -360.32718)
			(xy 95.451332 -360.293853) (xy 95.415719 -360.255275) (xy 95.400368 -360.233976) (xy 95.392004 -360.222763)
			(xy 95.370379 -360.205037) (xy 95.344755 -360.19384) (xy 95.317056 -360.190012) (xy 95.289357 -360.19384)
			(xy 95.263733 -360.205037) (xy 95.242108 -360.222763) (xy 95.233744 -360.233976) (xy 95.218366 -360.255254)
			(xy 95.182748 -360.293821) (xy 95.14218 -360.327143) (xy 95.097428 -360.35459) (xy 95.049336 -360.375643)
			(xy 94.998813 -360.389907) (xy 94.946811 -360.397111) (xy 94.920562 -360.397552) (xy 94.892056 -360.397013)
			(xy 94.835678 -360.388524) (xy 94.781192 -360.37174) (xy 94.729809 -360.347035) (xy 94.682675 -360.31496)
			(xy 94.640838 -360.276228) (xy 94.62262 -360.254296) (xy 94.61269 -360.242603) (xy 94.587311 -360.225391)
			(xy 94.557967 -360.216484) (xy 94.527302 -360.216686) (xy 94.498078 -360.225979) (xy 94.472927 -360.243524)
			(xy 94.463108 -360.255312) (xy 94.444916 -360.277794) (xy 94.402896 -360.317529) (xy 94.355361 -360.350468)
			(xy 94.3034 -360.375856) (xy 94.248203 -360.393113) (xy 94.191034 -360.401843) (xy 94.162118 -360.402378)
			(xy 94.132824 -360.401817) (xy 94.074926 -360.392855) (xy 94.019076 -360.375156) (xy 93.966585 -360.349134)
			(xy 93.918685 -360.315399) (xy 93.876499 -360.274744) (xy 93.858334 -360.251756) (xy 93.849905 -360.241474)
			(xy 93.828885 -360.225217) (xy 93.804384 -360.214928) (xy 93.778059 -360.211303) (xy 93.751689 -360.214588)
			(xy 93.727058 -360.22456) (xy 93.70583 -360.240545) (xy 93.697298 -360.25074) (xy 93.679113 -360.27319)
			(xy 93.637118 -360.312862) (xy 93.589619 -360.345747) (xy 93.537703 -360.371091) (xy 93.482559 -360.388314)
			(xy 93.425448 -360.397022) (xy 93.396562 -360.397552) (xy 93.367646 -360.397008) (xy 93.310475 -360.388287)
			(xy 93.255276 -360.371035) (xy 93.203314 -360.345648) (xy 93.155779 -360.312709) (xy 93.113762 -360.27297)
			(xy 93.095572 -360.250486) (xy 93.085675 -360.238681) (xy 93.060351 -360.221162) (xy 93.030958 -360.211986)
			(xy 93.000166 -360.211986) (xy 92.970773 -360.221162) (xy 92.945449 -360.238681) (xy 92.935552 -360.250486)
			(xy 92.918799 -360.271269) (xy 92.880445 -360.308399) (xy 92.837291 -360.339821) (xy 92.790177 -360.36492)
			(xy 92.740025 -360.383206) (xy 92.687814 -360.394323) (xy 92.634562 -360.398053) (xy 92.58131 -360.394323)
			(xy 92.529099 -360.383206) (xy 92.478947 -360.36492) (xy 92.431833 -360.339821) (xy 92.388679 -360.308399)
			(xy 92.350325 -360.271269) (xy 92.333572 -360.250486) (xy 92.323675 -360.238681) (xy 92.298351 -360.221162)
			(xy 92.268958 -360.211986) (xy 92.238166 -360.211986) (xy 92.208773 -360.221162) (xy 92.183449 -360.238681)
			(xy 92.173552 -360.250486) (xy 92.156799 -360.271269) (xy 92.118445 -360.308399) (xy 92.075291 -360.339821)
			(xy 92.028177 -360.36492) (xy 91.978025 -360.383206) (xy 91.925814 -360.394323) (xy 91.872562 -360.398053)
			(xy 91.81931 -360.394323) (xy 91.767099 -360.383206) (xy 91.716947 -360.36492) (xy 91.669833 -360.339821)
			(xy 91.626679 -360.308399) (xy 91.588325 -360.271269) (xy 91.571572 -360.250486) (xy 91.561675 -360.238681)
			(xy 91.536351 -360.221162) (xy 91.506958 -360.211986) (xy 91.476166 -360.211986) (xy 91.446773 -360.221162)
			(xy 91.421449 -360.238681) (xy 91.411552 -360.250486) (xy 91.393328 -360.272942) (xy 91.351316 -360.312679)
			(xy 91.303788 -360.345622) (xy 91.251833 -360.371015) (xy 91.196641 -360.388277) (xy 91.139476 -360.397013)
			(xy 91.110562 -360.397552) (xy 91.084492 -360.397123) (xy 91.03284 -360.39001) (xy 90.982635 -360.375936)
			(xy 90.934812 -360.355161) (xy 90.890261 -360.328073) (xy 90.84981 -360.295175) (xy 90.81421 -360.25708)
			(xy 90.784126 -360.214495) (xy 90.771726 -360.191558) (xy 90.764913 -360.179441) (xy 90.745946 -360.159136)
			(xy 90.722205 -360.1447) (xy 90.695449 -360.137204) (xy 90.667663 -360.137204) (xy 90.640907 -360.1447)
			(xy 90.617166 -360.159136) (xy 90.598199 -360.179441) (xy 90.591386 -360.191558) (xy 90.578996 -360.214503)
			(xy 90.548924 -360.257102) (xy 90.51333 -360.295209) (xy 90.472879 -360.328114) (xy 90.428324 -360.355203)
			(xy 90.380494 -360.375973) (xy 90.330282 -360.390036) (xy 90.278622 -360.397131) (xy 90.25255 -360.397552)
			(xy 90.22617 -360.397098) (xy 90.173911 -360.389833) (xy 90.123153 -360.375435) (xy 90.074863 -360.354179)
			(xy 90.029964 -360.326471) (xy 89.989312 -360.292839) (xy 89.953683 -360.253925) (xy 89.938352 -360.232452)
			(xy 89.930165 -360.221296) (xy 89.908954 -360.203541) (xy 89.883751 -360.192138) (xy 89.856412 -360.187927)
			(xy 89.828946 -360.191218) (xy 89.803376 -360.201768) (xy 89.78158 -360.218802) (xy 89.772998 -360.229658)
			(xy 89.754877 -360.253141) (xy 89.712594 -360.294738) (xy 89.664381 -360.329286) (xy 89.6114 -360.355953)
			(xy 89.55493 -360.374095) (xy 89.496331 -360.383274) (xy 89.466674 -360.383836) (xy 89.440711 -360.38336)
			(xy 89.389265 -360.376319) (xy 89.339247 -360.36237) (xy 89.291582 -360.341771) (xy 89.247148 -360.314902)
			(xy 89.206765 -360.282259) (xy 89.17118 -360.244444) (xy 89.141048 -360.202155) (xy 89.1286 -360.179366)
			(xy 89.121978 -360.16751) (xy 89.103535 -360.147587) (xy 89.080488 -360.133238) (xy 89.054472 -360.12548)
			(xy 89.02733 -360.124862) (xy 89.000988 -360.131428) (xy 88.977312 -360.144712) (xy 88.95798 -360.163774)
			(xy 88.9508 -360.175302) (xy 88.936041 -360.199594) (xy 88.900425 -360.243892) (xy 88.858631 -360.282415)
			(xy 88.811584 -360.314311) (xy 88.760326 -360.338875) (xy 88.705991 -360.355562) (xy 88.649782 -360.364004)
			(xy 88.621362 -360.364532) (xy 88.592623 -360.364023) (xy 88.535795 -360.355395) (xy 88.480904 -360.338341)
			(xy 88.429193 -360.313247) (xy 88.381831 -360.28068) (xy 88.360504 -360.261408) (xy 88.348663 -360.251155)
			(xy 88.320383 -360.237729) (xy 88.289366 -360.233492) (xy 88.258521 -360.23884) (xy 88.23074 -360.253271)
			(xy 88.21928 -360.263948) (xy 88.197682 -360.284801) (xy 88.149147 -360.320133) (xy 88.095675 -360.347424)
			(xy 88.038588 -360.366001) (xy 87.979295 -360.375403) (xy 87.949278 -360.375962) (xy 87.949024 -360.375962)
			(xy 87.92177 -360.375522) (xy 87.867815 -360.367767) (xy 87.815514 -360.352412) (xy 87.765931 -360.329769)
			(xy 87.720076 -360.300299) (xy 87.678882 -360.264603) (xy 87.643188 -360.223407) (xy 87.613721 -360.177549)
			(xy 87.59108 -360.127965) (xy 87.575728 -360.075663) (xy 87.567976 -360.021708) (xy 87.567516 -359.994454)
			(xy 81.632806 -359.994454) (xy 83.62442 -361.986068) (xy 83.693254 -362.010706) (xy 89.913367 -364.555849)
			(xy 98.876386 -364.555849) (xy 98.876386 -364.501351) (xy 98.884141 -364.447408) (xy 98.899494 -364.395118)
			(xy 98.922131 -364.345545) (xy 98.951593 -364.299697) (xy 98.987279 -364.258509) (xy 99.028464 -364.222818)
			(xy 99.074308 -364.193351) (xy 99.123879 -364.170708) (xy 99.176167 -364.15535) (xy 99.230109 -364.147589)
			(xy 99.257358 -364.1471) (xy 99.283582 -364.147509) (xy 99.335533 -364.154713) (xy 99.386009 -364.168963)
			(xy 99.434058 -364.189991) (xy 99.478774 -364.2174) (xy 99.519316 -364.250675) (xy 99.554919 -364.289188)
			(xy 99.584913 -364.332214) (xy 99.59721 -364.35538) (xy 99.604539 -364.368759) (xy 99.625777 -364.390643)
			(xy 99.652525 -364.405289) (xy 99.682403 -364.411393) (xy 99.712753 -364.408413) (xy 99.740873 -364.396614)
			(xy 99.764262 -364.377045) (xy 99.772978 -364.364524) (xy 99.788181 -364.342039) (xy 99.823848 -364.301132)
			(xy 99.864955 -364.265695) (xy 99.91067 -364.236444) (xy 99.960071 -364.213969) (xy 100.012159 -364.198724)
			(xy 100.065882 -364.191018) (xy 100.093018 -364.190534) (xy 100.120271 -364.190937) (xy 100.174223 -364.198697)
			(xy 100.226521 -364.214055) (xy 100.276102 -364.2367) (xy 100.321955 -364.26617) (xy 100.363148 -364.301865)
			(xy 100.398841 -364.343059) (xy 100.428309 -364.388914) (xy 100.439674 -364.4138) (xy 106.12069 -364.4138)
			(xy 106.124761 -364.358178) (xy 106.136887 -364.303741) (xy 106.15681 -364.25165) (xy 106.184106 -364.203015)
			(xy 106.218192 -364.158872) (xy 106.258341 -364.120163) (xy 106.303699 -364.087712) (xy 106.353299 -364.062211)
			(xy 106.406083 -364.044204) (xy 106.460926 -364.034074) (xy 106.51666 -364.032037) (xy 106.572097 -364.038137)
			(xy 106.626054 -364.052243) (xy 106.677383 -364.074055) (xy 106.724989 -364.103109) (xy 106.767857 -364.138784)
			(xy 106.805074 -364.180321) (xy 106.835847 -364.226834) (xy 106.859519 -364.277331) (xy 106.869398 -364.310168)
			(xy 107.575602 -364.310168) (xy 107.579673 -364.254546) (xy 107.591799 -364.200109) (xy 107.611722 -364.148018)
			(xy 107.639018 -364.099383) (xy 107.673104 -364.05524) (xy 107.713253 -364.016531) (xy 107.758611 -363.98408)
			(xy 107.808211 -363.958579) (xy 107.860995 -363.940572) (xy 107.915838 -363.930442) (xy 107.971572 -363.928405)
			(xy 108.027009 -363.934505) (xy 108.080966 -363.948611) (xy 108.132295 -363.970423) (xy 108.179901 -363.999477)
			(xy 108.222769 -364.035152) (xy 108.259986 -364.076689) (xy 108.290759 -364.123202) (xy 108.314431 -364.173699)
			(xy 108.330499 -364.227106) (xy 108.338619 -364.282282) (xy 108.339128 -364.310168) (xy 108.338619 -364.338054)
			(xy 108.330499 -364.39323) (xy 108.314431 -364.446637) (xy 108.290759 -364.497134) (xy 108.259986 -364.543647)
			(xy 108.222769 -364.585184) (xy 108.179901 -364.620859) (xy 108.132295 -364.649913) (xy 108.080966 -364.671725)
			(xy 108.027009 -364.685831) (xy 107.971572 -364.691931) (xy 107.915838 -364.689894) (xy 107.860995 -364.679764)
			(xy 107.808211 -364.661757) (xy 107.758611 -364.636256) (xy 107.713253 -364.603805) (xy 107.673104 -364.565096)
			(xy 107.639018 -364.520953) (xy 107.611722 -364.472318) (xy 107.591799 -364.420227) (xy 107.579673 -364.36579)
			(xy 107.575602 -364.310168) (xy 106.869398 -364.310168) (xy 106.875587 -364.330738) (xy 106.883707 -364.385914)
			(xy 106.884216 -364.4138) (xy 106.883707 -364.441686) (xy 106.875587 -364.496862) (xy 106.859519 -364.550269)
			(xy 106.835847 -364.600766) (xy 106.805074 -364.647279) (xy 106.767857 -364.688816) (xy 106.724989 -364.724491)
			(xy 106.677383 -364.753545) (xy 106.626054 -364.775357) (xy 106.572097 -364.789463) (xy 106.51666 -364.795563)
			(xy 106.460926 -364.793526) (xy 106.406083 -364.783396) (xy 106.353299 -364.765389) (xy 106.303699 -364.739888)
			(xy 106.258341 -364.707437) (xy 106.218192 -364.668728) (xy 106.184106 -364.624585) (xy 106.15681 -364.57595)
			(xy 106.136887 -364.523859) (xy 106.124761 -364.469422) (xy 106.12069 -364.4138) (xy 100.439674 -364.4138)
			(xy 100.450951 -364.438495) (xy 100.466307 -364.490794) (xy 100.474064 -364.544747) (xy 100.474064 -364.599253)
			(xy 100.466307 -364.653206) (xy 100.450951 -364.705505) (xy 100.428309 -364.755086) (xy 100.398841 -364.800941)
			(xy 100.363148 -364.842135) (xy 100.321955 -364.87783) (xy 100.276102 -364.9073) (xy 100.226521 -364.929945)
			(xy 100.174223 -364.945303) (xy 100.120271 -364.953063) (xy 100.093018 -364.95355) (xy 100.066795 -364.953133)
			(xy 100.014845 -364.945928) (xy 99.964371 -364.931677) (xy 99.916323 -364.910649) (xy 99.871607 -364.883241)
			(xy 99.831065 -364.849968) (xy 99.795461 -364.811457) (xy 99.765465 -364.768435) (xy 99.753166 -364.74527)
			(xy 99.745729 -364.731955) (xy 99.724517 -364.710068) (xy 99.697791 -364.695415) (xy 99.667931 -364.6893)
			(xy 99.637597 -364.692269) (xy 99.609489 -364.704056) (xy 99.58611 -364.723612) (xy 99.577398 -364.736126)
			(xy 99.562228 -364.758633) (xy 99.526553 -364.799537) (xy 99.48544 -364.834971) (xy 99.439719 -364.864219)
			(xy 99.390314 -364.886691) (xy 99.338222 -364.901931) (xy 99.284496 -364.909633) (xy 99.257358 -364.910116)
			(xy 99.230109 -364.909611) (xy 99.176167 -364.90185) (xy 99.123879 -364.886492) (xy 99.074308 -364.863849)
			(xy 99.028464 -364.834382) (xy 98.987279 -364.798691) (xy 98.951593 -364.757503) (xy 98.922131 -364.711655)
			(xy 98.899494 -364.662082) (xy 98.884141 -364.609792) (xy 98.876386 -364.555849) (xy 89.913367 -364.555849)
			(xy 91.341569 -365.14024) (xy 106.985814 -365.14024) (xy 106.989885 -365.084618) (xy 107.002011 -365.030181)
			(xy 107.021934 -364.97809) (xy 107.04923 -364.929455) (xy 107.083316 -364.885312) (xy 107.123465 -364.846603)
			(xy 107.168823 -364.814152) (xy 107.218423 -364.788651) (xy 107.271207 -364.770644) (xy 107.32605 -364.760514)
			(xy 107.381784 -364.758477) (xy 107.437221 -364.764577) (xy 107.491178 -364.778683) (xy 107.542507 -364.800495)
			(xy 107.590113 -364.829549) (xy 107.632981 -364.865224) (xy 107.670198 -364.906761) (xy 107.700971 -364.953274)
			(xy 107.724643 -365.003771) (xy 107.740711 -365.057178) (xy 107.748831 -365.112354) (xy 107.74934 -365.14024)
			(xy 107.748831 -365.168126) (xy 107.740711 -365.223302) (xy 107.724643 -365.276709) (xy 107.700971 -365.327206)
			(xy 107.670198 -365.373719) (xy 107.632981 -365.415256) (xy 107.590113 -365.450931) (xy 107.542507 -365.479985)
			(xy 107.491178 -365.501797) (xy 107.437221 -365.515903) (xy 107.381784 -365.522003) (xy 107.32605 -365.519966)
			(xy 107.271207 -365.509836) (xy 107.218423 -365.491829) (xy 107.168823 -365.466328) (xy 107.123465 -365.433877)
			(xy 107.083316 -365.395168) (xy 107.04923 -365.351025) (xy 107.021934 -365.30239) (xy 107.002011 -365.250299)
			(xy 106.989885 -365.195862) (xy 106.985814 -365.14024) (xy 91.341569 -365.14024) (xy 92.446512 -365.59236)
			(xy 100.41077 -365.59236) (xy 100.414841 -365.536738) (xy 100.426967 -365.482301) (xy 100.44689 -365.43021)
			(xy 100.474186 -365.381575) (xy 100.508272 -365.337432) (xy 100.548421 -365.298723) (xy 100.593779 -365.266272)
			(xy 100.643379 -365.240771) (xy 100.696163 -365.222764) (xy 100.751006 -365.212634) (xy 100.80674 -365.210597)
			(xy 100.862177 -365.216697) (xy 100.916134 -365.230803) (xy 100.967463 -365.252615) (xy 101.015069 -365.281669)
			(xy 101.057937 -365.317344) (xy 101.095154 -365.358881) (xy 101.125927 -365.405394) (xy 101.149599 -365.455891)
			(xy 101.165667 -365.509298) (xy 101.173787 -365.564474) (xy 101.174296 -365.59236) (xy 101.173787 -365.620246)
			(xy 101.165667 -365.675422) (xy 101.149599 -365.728829) (xy 101.125927 -365.779326) (xy 101.095154 -365.825839)
			(xy 101.057937 -365.867376) (xy 101.015069 -365.903051) (xy 100.967463 -365.932105) (xy 100.916134 -365.953917)
			(xy 100.906858 -365.956342) (xy 101.533958 -365.956342) (xy 101.538029 -365.90072) (xy 101.550155 -365.846283)
			(xy 101.570078 -365.794192) (xy 101.597374 -365.745557) (xy 101.63146 -365.701414) (xy 101.671609 -365.662705)
			(xy 101.716967 -365.630254) (xy 101.766567 -365.604753) (xy 101.819351 -365.586746) (xy 101.874194 -365.576616)
			(xy 101.929928 -365.574579) (xy 101.985365 -365.580679) (xy 102.039322 -365.594785) (xy 102.090651 -365.616597)
			(xy 102.138257 -365.645651) (xy 102.181125 -365.681326) (xy 102.218342 -365.722863) (xy 102.249115 -365.769376)
			(xy 102.272787 -365.819873) (xy 102.288855 -365.87328) (xy 102.296975 -365.928456) (xy 102.297484 -365.956342)
			(xy 102.296975 -365.984228) (xy 102.288855 -366.039404) (xy 102.272787 -366.092811) (xy 102.249115 -366.143308)
			(xy 102.218342 -366.189821) (xy 102.181125 -366.231358) (xy 102.138257 -366.267033) (xy 102.130359 -366.271853)
			(xy 104.673087 -366.271853) (xy 104.673087 -366.217347) (xy 104.680845 -366.163397) (xy 104.696202 -366.1111)
			(xy 104.718846 -366.061521) (xy 104.748316 -366.015669) (xy 104.784011 -365.974479) (xy 104.825206 -365.938788)
			(xy 104.871061 -365.909324) (xy 104.920643 -365.886686) (xy 104.972942 -365.871335) (xy 105.026893 -365.863584)
			(xy 105.054146 -365.863124) (xy 105.080526 -365.863544) (xy 105.132786 -365.870804) (xy 105.183547 -365.885191)
			(xy 105.231843 -365.906433) (xy 105.276753 -365.934124) (xy 105.317421 -365.967737) (xy 105.353072 -366.006631)
			(xy 105.383026 -366.050064) (xy 105.395268 -366.073436) (xy 105.40197 -366.085795) (xy 105.420945 -366.106523)
			(xy 105.444859 -366.121285) (xy 105.471895 -366.128957) (xy 105.499997 -366.128957) (xy 105.527033 -366.121285)
			(xy 105.550947 -366.106523) (xy 105.569922 -366.085795) (xy 105.576624 -366.073436) (xy 105.588879 -366.050073)
			(xy 105.618842 -366.006652) (xy 105.654497 -365.967769) (xy 105.695164 -365.934164) (xy 105.740071 -365.906477)
			(xy 105.788361 -365.885234) (xy 105.839116 -365.870842) (xy 105.891368 -365.863572) (xy 105.917746 -365.863124)
			(xy 105.944997 -365.863549) (xy 105.998945 -365.871311) (xy 106.051238 -365.886672) (xy 106.100814 -365.909318)
			(xy 106.146662 -365.938788) (xy 106.187851 -365.974482) (xy 106.22354 -366.015675) (xy 106.253005 -366.061527)
			(xy 106.275644 -366.111105) (xy 106.290998 -366.1634) (xy 106.298754 -366.217349) (xy 106.298754 -366.271851)
			(xy 106.290998 -366.3258) (xy 106.275644 -366.378095) (xy 106.253005 -366.427673) (xy 106.22354 -366.473525)
			(xy 106.187851 -366.514718) (xy 106.146662 -366.550412) (xy 106.100814 -366.579882) (xy 106.051238 -366.602528)
			(xy 105.998945 -366.617889) (xy 105.944997 -366.625651) (xy 105.917746 -366.62614) (xy 105.891367 -366.625691)
			(xy 105.839111 -366.618432) (xy 105.788352 -366.604046) (xy 105.740058 -366.582807) (xy 105.695148 -366.55512)
			(xy 105.65448 -366.521513) (xy 105.618826 -366.482625) (xy 105.588868 -366.439197) (xy 105.576624 -366.415828)
			(xy 105.569922 -366.403469) (xy 105.550947 -366.382741) (xy 105.527033 -366.367979) (xy 105.499997 -366.360307)
			(xy 105.471895 -366.360307) (xy 105.444859 -366.367979) (xy 105.420945 -366.382741) (xy 105.40197 -366.403469)
			(xy 105.395268 -366.415828) (xy 105.383003 -366.439186) (xy 105.353043 -366.482608) (xy 105.317391 -366.521493)
			(xy 105.276725 -366.555099) (xy 105.231819 -366.582787) (xy 105.18353 -366.60403) (xy 105.132776 -366.618423)
			(xy 105.080524 -366.625692) (xy 105.054146 -366.62614) (xy 105.026893 -366.625616) (xy 104.972942 -366.617865)
			(xy 104.920643 -366.602514) (xy 104.871061 -366.579876) (xy 104.825206 -366.550412) (xy 104.784011 -366.514721)
			(xy 104.748316 -366.473531) (xy 104.718846 -366.427679) (xy 104.696202 -366.3781) (xy 104.680845 -366.325803)
			(xy 104.673087 -366.271853) (xy 102.130359 -366.271853) (xy 102.090651 -366.296087) (xy 102.039322 -366.317899)
			(xy 101.985365 -366.332005) (xy 101.929928 -366.338105) (xy 101.874194 -366.336068) (xy 101.819351 -366.325938)
			(xy 101.766567 -366.307931) (xy 101.716967 -366.28243) (xy 101.671609 -366.249979) (xy 101.63146 -366.21127)
			(xy 101.597374 -366.167127) (xy 101.570078 -366.118492) (xy 101.550155 -366.066401) (xy 101.538029 -366.011964)
			(xy 101.533958 -365.956342) (xy 100.906858 -365.956342) (xy 100.862177 -365.968023) (xy 100.80674 -365.974123)
			(xy 100.751006 -365.972086) (xy 100.696163 -365.961956) (xy 100.643379 -365.943949) (xy 100.593779 -365.918448)
			(xy 100.548421 -365.885997) (xy 100.508272 -365.847288) (xy 100.474186 -365.803145) (xy 100.44689 -365.75451)
			(xy 100.426967 -365.702419) (xy 100.414841 -365.647982) (xy 100.41077 -365.59236) (xy 92.446512 -365.59236)
			(xy 97.920324 -367.832132) (xy 121.144028 -367.832132) (xy 121.148099 -367.77651) (xy 121.160225 -367.722073)
			(xy 121.180148 -367.669982) (xy 121.207444 -367.621347) (xy 121.24153 -367.577204) (xy 121.281679 -367.538495)
			(xy 121.327037 -367.506044) (xy 121.376637 -367.480543) (xy 121.429421 -367.462536) (xy 121.484264 -367.452406)
			(xy 121.539998 -367.450369) (xy 121.595435 -367.456469) (xy 121.649392 -367.470575) (xy 121.700721 -367.492387)
			(xy 121.748327 -367.521441) (xy 121.791195 -367.557116) (xy 121.828412 -367.598653) (xy 121.859185 -367.645166)
			(xy 121.882857 -367.695663) (xy 121.898925 -367.74907) (xy 121.907045 -367.804246) (xy 121.907554 -367.832132)
			(xy 121.907045 -367.860018) (xy 121.898925 -367.915194) (xy 121.882857 -367.968601) (xy 121.859185 -368.019098)
			(xy 121.828412 -368.065611) (xy 121.825273 -368.069114) (xy 122.207274 -368.069114) (xy 122.207774 -368.040196)
			(xy 122.216503 -367.983023) (xy 122.233763 -367.927822) (xy 122.259158 -367.87586) (xy 122.292106 -367.828327)
			(xy 122.331852 -367.786312) (xy 122.35434 -367.768124) (xy 122.366136 -367.758214) (xy 122.383662 -367.732896)
			(xy 122.392843 -367.703505) (xy 122.392846 -367.672712) (xy 122.383669 -367.64332) (xy 122.366148 -367.617999)
			(xy 122.35434 -367.608104) (xy 122.331867 -367.589901) (xy 122.292129 -367.547885) (xy 122.259188 -367.500353)
			(xy 122.233797 -367.448394) (xy 122.216539 -367.393198) (xy 122.207809 -367.336029) (xy 122.207274 -367.307114)
			(xy 122.20776 -367.279863) (xy 122.215516 -367.225915) (xy 122.230871 -367.17362) (xy 122.253513 -367.124043)
			(xy 122.282979 -367.078193) (xy 122.31867 -367.037002) (xy 122.359861 -367.001311) (xy 122.405711 -366.971845)
			(xy 122.455288 -366.949203) (xy 122.507583 -366.933848) (xy 122.561531 -366.926092) (xy 122.616033 -366.926092)
			(xy 122.669981 -366.933848) (xy 122.722276 -366.949203) (xy 122.771853 -366.971845) (xy 122.817703 -367.001311)
			(xy 122.858894 -367.037002) (xy 122.894585 -367.078193) (xy 122.924051 -367.124043) (xy 122.946693 -367.17362)
			(xy 122.962048 -367.225915) (xy 122.969804 -367.279863) (xy 122.97029 -367.307114) (xy 122.969714 -367.336029)
			(xy 122.960997 -367.393198) (xy 122.943751 -367.448395) (xy 122.91837 -367.500357) (xy 122.885437 -367.547893)
			(xy 122.845705 -367.589912) (xy 122.823224 -367.608104) (xy 122.811404 -367.617986) (xy 122.793885 -367.643313)
			(xy 122.784709 -367.672711) (xy 122.784712 -367.703507) (xy 122.793892 -367.732903) (xy 122.811416 -367.758227)
			(xy 122.823224 -367.768124) (xy 122.845724 -367.786295) (xy 122.885457 -367.82832) (xy 122.918393 -367.875859)
			(xy 122.943779 -367.927824) (xy 122.961032 -367.983025) (xy 122.969757 -368.040197) (xy 122.97029 -368.069114)
			(xy 124.355098 -368.069114) (xy 124.355627 -368.040198) (xy 124.364354 -367.983027) (xy 124.38161 -367.927828)
			(xy 124.407 -367.875867) (xy 124.439941 -367.828332) (xy 124.47968 -367.786315) (xy 124.502164 -367.768124)
			(xy 124.513957 -367.758212) (xy 124.531479 -367.732894) (xy 124.540659 -367.703504) (xy 124.540661 -367.672713)
			(xy 124.531487 -367.643322) (xy 124.513969 -367.618) (xy 124.502164 -367.608104) (xy 124.479675 -367.58992)
			(xy 124.439942 -367.547898) (xy 124.407004 -367.500361) (xy 124.381617 -367.448398) (xy 124.364362 -367.3932)
			(xy 124.355633 -367.33603) (xy 124.355098 -367.307114) (xy 124.355584 -367.279863) (xy 124.36334 -367.225915)
			(xy 124.378695 -367.17362) (xy 124.401337 -367.124043) (xy 124.430803 -367.078193) (xy 124.466494 -367.037002)
			(xy 124.507685 -367.001311) (xy 124.553535 -366.971845) (xy 124.603112 -366.949203) (xy 124.655407 -366.933848)
			(xy 124.709355 -366.926092) (xy 124.763857 -366.926092) (xy 124.817805 -366.933848) (xy 124.8701 -366.949203)
			(xy 124.919677 -366.971845) (xy 124.965527 -367.001311) (xy 125.006718 -367.037002) (xy 125.042409 -367.078193)
			(xy 125.071875 -367.124043) (xy 125.094517 -367.17362) (xy 125.109872 -367.225915) (xy 125.117628 -367.279863)
			(xy 125.118114 -367.307114) (xy 125.117566 -367.33603) (xy 125.108848 -367.393202) (xy 125.091598 -367.448401)
			(xy 125.066212 -367.500364) (xy 125.033272 -367.547898) (xy 124.993533 -367.589914) (xy 124.971048 -367.608104)
			(xy 124.959226 -367.617984) (xy 124.941702 -367.643311) (xy 124.932525 -367.67271) (xy 124.932527 -367.703508)
			(xy 124.94171 -367.732905) (xy 124.959237 -367.758228) (xy 124.971048 -367.768124) (xy 124.993553 -367.786289)
			(xy 125.033285 -367.828316) (xy 125.06622 -367.875857) (xy 125.091604 -367.927823) (xy 125.108856 -367.983024)
			(xy 125.117581 -368.040197) (xy 125.118114 -368.069114) (xy 126.488698 -368.069114) (xy 126.489227 -368.040198)
			(xy 126.497954 -367.983027) (xy 126.51521 -367.927828) (xy 126.5406 -367.875867) (xy 126.573541 -367.828332)
			(xy 126.61328 -367.786315) (xy 126.635764 -367.768124) (xy 126.647557 -367.758212) (xy 126.665079 -367.732894)
			(xy 126.674259 -367.703504) (xy 126.674261 -367.672713) (xy 126.665087 -367.643322) (xy 126.647569 -367.618)
			(xy 126.635764 -367.608104) (xy 126.613275 -367.58992) (xy 126.573542 -367.547898) (xy 126.540604 -367.500361)
			(xy 126.515217 -367.448398) (xy 126.497962 -367.3932) (xy 126.489233 -367.33603) (xy 126.488698 -367.307114)
			(xy 126.489184 -367.279863) (xy 126.49694 -367.225915) (xy 126.512295 -367.17362) (xy 126.534937 -367.124043)
			(xy 126.564403 -367.078193) (xy 126.600094 -367.037002) (xy 126.641285 -367.001311) (xy 126.687135 -366.971845)
			(xy 126.736712 -366.949203) (xy 126.789007 -366.933848) (xy 126.842955 -366.926092) (xy 126.897457 -366.926092)
			(xy 126.951405 -366.933848) (xy 127.0037 -366.949203) (xy 127.053277 -366.971845) (xy 127.099127 -367.001311)
			(xy 127.140318 -367.037002) (xy 127.176009 -367.078193) (xy 127.205475 -367.124043) (xy 127.228117 -367.17362)
			(xy 127.243472 -367.225915) (xy 127.251228 -367.279863) (xy 127.251714 -367.307114) (xy 127.251166 -367.33603)
			(xy 127.242448 -367.393202) (xy 127.225198 -367.448401) (xy 127.199812 -367.500364) (xy 127.166872 -367.547898)
			(xy 127.127133 -367.589914) (xy 127.104648 -367.608104) (xy 127.092826 -367.617984) (xy 127.075302 -367.643311)
			(xy 127.066125 -367.67271) (xy 127.066127 -367.703508) (xy 127.07531 -367.732905) (xy 127.092837 -367.758228)
			(xy 127.104648 -367.768124) (xy 127.127153 -367.786289) (xy 127.166885 -367.828316) (xy 127.19982 -367.875857)
			(xy 127.225204 -367.927823) (xy 127.242456 -367.983024) (xy 127.251181 -368.040197) (xy 127.25119 -368.040666)
			(xy 128.641348 -368.040666) (xy 128.641896 -368.01175) (xy 128.650616 -367.954579) (xy 128.667867 -367.89938)
			(xy 128.693253 -367.847418) (xy 128.726193 -367.799884) (xy 128.76593 -367.757867) (xy 128.788414 -367.739676)
			(xy 128.800251 -367.729814) (xy 128.817763 -367.70448) (xy 128.826932 -367.675078) (xy 128.826926 -367.64428)
			(xy 128.817744 -367.614882) (xy 128.800222 -367.589555) (xy 128.788414 -367.579656) (xy 128.765912 -367.561486)
			(xy 128.726178 -367.519463) (xy 128.69324 -367.471923) (xy 128.667855 -367.419958) (xy 128.650603 -367.364756)
			(xy 128.64188 -367.307583) (xy 128.641348 -367.278666) (xy 128.641834 -367.251415) (xy 128.64959 -367.197467)
			(xy 128.664945 -367.145172) (xy 128.687587 -367.095595) (xy 128.717053 -367.049745) (xy 128.752744 -367.008554)
			(xy 128.793935 -366.972863) (xy 128.839785 -366.943397) (xy 128.889362 -366.920755) (xy 128.941657 -366.9054)
			(xy 128.995605 -366.897644) (xy 129.050107 -366.897644) (xy 129.104055 -366.9054) (xy 129.15635 -366.920755)
			(xy 129.205927 -366.943397) (xy 129.251777 -366.972863) (xy 129.292968 -367.008554) (xy 129.328659 -367.049745)
			(xy 129.358125 -367.095595) (xy 129.380767 -367.145172) (xy 129.396122 -367.197467) (xy 129.403878 -367.251415)
			(xy 129.404364 -367.278666) (xy 129.403835 -367.307583) (xy 129.39511 -367.364754) (xy 129.377855 -367.419953)
			(xy 129.352466 -367.471915) (xy 129.319523 -367.519449) (xy 129.279783 -367.561466) (xy 129.257298 -367.579656)
			(xy 129.245528 -367.589592) (xy 129.228013 -367.614905) (xy 129.218835 -367.644288) (xy 129.218829 -367.675071)
			(xy 129.227994 -367.704457) (xy 129.2455 -367.729778) (xy 129.257298 -367.739676) (xy 129.27977 -367.757881)
			(xy 129.319506 -367.799898) (xy 129.352446 -367.84743) (xy 129.377836 -367.899388) (xy 129.395095 -367.954583)
			(xy 129.403827 -368.011751) (xy 129.404364 -368.040666) (xy 129.403878 -368.067917) (xy 129.396122 -368.121865)
			(xy 129.380767 -368.17416) (xy 129.358125 -368.223737) (xy 129.328659 -368.269587) (xy 129.310731 -368.290278)
			(xy 132.836408 -368.290278) (xy 132.836408 -368.205582) (xy 132.844459 -368.121268) (xy 132.860488 -368.038102)
			(xy 132.884349 -367.956835) (xy 132.915828 -367.878205) (xy 132.954639 -367.802924) (xy 133.000429 -367.731672)
			(xy 133.052785 -367.665096) (xy 133.111233 -367.603798) (xy 133.175243 -367.548333) (xy 133.244235 -367.499204)
			(xy 133.317585 -367.456855) (xy 133.394628 -367.421671) (xy 133.474667 -367.393969) (xy 133.556976 -367.374001)
			(xy 133.640811 -367.361948) (xy 133.725412 -367.357918) (xy 133.810013 -367.361948) (xy 133.893848 -367.374001)
			(xy 133.976157 -367.393969) (xy 134.056196 -367.421671) (xy 134.133239 -367.456855) (xy 134.206589 -367.499204)
			(xy 134.275581 -367.548333) (xy 134.339591 -367.603798) (xy 134.398039 -367.665096) (xy 134.450395 -367.731672)
			(xy 134.496185 -367.802924) (xy 134.534996 -367.878205) (xy 134.566475 -367.956835) (xy 134.590336 -368.038102)
			(xy 134.606365 -368.121268) (xy 134.608758 -368.14633) (xy 140.60246 -368.14633) (xy 140.606531 -368.090708)
			(xy 140.618657 -368.036271) (xy 140.63858 -367.98418) (xy 140.665876 -367.935545) (xy 140.699962 -367.891402)
			(xy 140.740111 -367.852693) (xy 140.785469 -367.820242) (xy 140.835069 -367.794741) (xy 140.887853 -367.776734)
			(xy 140.942696 -367.766604) (xy 140.99843 -367.764567) (xy 141.053867 -367.770667) (xy 141.107824 -367.784773)
			(xy 141.159153 -367.806585) (xy 141.206759 -367.835639) (xy 141.249627 -367.871314) (xy 141.286844 -367.912851)
			(xy 141.317617 -367.959364) (xy 141.341289 -368.009861) (xy 141.357357 -368.063268) (xy 141.365477 -368.118444)
			(xy 141.365986 -368.14633) (xy 141.365477 -368.174216) (xy 141.357357 -368.229392) (xy 141.341289 -368.282799)
			(xy 141.317617 -368.333296) (xy 141.286844 -368.379809) (xy 141.249627 -368.421346) (xy 141.206759 -368.457021)
			(xy 141.159153 -368.486075) (xy 141.107824 -368.507887) (xy 141.053867 -368.521993) (xy 140.99843 -368.528093)
			(xy 140.942696 -368.526056) (xy 140.887853 -368.515926) (xy 140.835069 -368.497919) (xy 140.785469 -368.472418)
			(xy 140.740111 -368.439967) (xy 140.699962 -368.401258) (xy 140.665876 -368.357115) (xy 140.63858 -368.30848)
			(xy 140.618657 -368.256389) (xy 140.606531 -368.201952) (xy 140.60246 -368.14633) (xy 134.608758 -368.14633)
			(xy 134.614416 -368.205582) (xy 134.61492 -368.24793) (xy 134.614416 -368.290278) (xy 134.606365 -368.374592)
			(xy 134.590336 -368.457758) (xy 134.566475 -368.539025) (xy 134.534996 -368.617655) (xy 134.496185 -368.692936)
			(xy 134.450395 -368.764188) (xy 134.398039 -368.830764) (xy 134.339591 -368.892062) (xy 134.275581 -368.947527)
			(xy 134.206589 -368.996656) (xy 134.133239 -369.039005) (xy 134.056196 -369.074189) (xy 133.976157 -369.101891)
			(xy 133.893848 -369.121859) (xy 133.810013 -369.133912) (xy 133.725412 -369.137943) (xy 133.640811 -369.133912)
			(xy 133.556976 -369.121859) (xy 133.474667 -369.101891) (xy 133.394628 -369.074189) (xy 133.317585 -369.039005)
			(xy 133.244235 -368.996656) (xy 133.175243 -368.947527) (xy 133.111233 -368.892062) (xy 133.052785 -368.830764)
			(xy 133.000429 -368.764188) (xy 132.954639 -368.692936) (xy 132.915828 -368.617655) (xy 132.884349 -368.539025)
			(xy 132.860488 -368.457758) (xy 132.844459 -368.374592) (xy 132.836408 -368.290278) (xy 129.310731 -368.290278)
			(xy 129.292968 -368.310778) (xy 129.251777 -368.346469) (xy 129.205927 -368.375935) (xy 129.15635 -368.398577)
			(xy 129.104055 -368.413932) (xy 129.050107 -368.421688) (xy 128.995605 -368.421688) (xy 128.941657 -368.413932)
			(xy 128.889362 -368.398577) (xy 128.839785 -368.375935) (xy 128.793935 -368.346469) (xy 128.752744 -368.310778)
			(xy 128.717053 -368.269587) (xy 128.687587 -368.223737) (xy 128.664945 -368.17416) (xy 128.64959 -368.121865)
			(xy 128.641834 -368.067917) (xy 128.641348 -368.040666) (xy 127.25119 -368.040666) (xy 127.251714 -368.069114)
			(xy 127.251228 -368.096365) (xy 127.243472 -368.150313) (xy 127.228117 -368.202608) (xy 127.205475 -368.252185)
			(xy 127.176009 -368.298035) (xy 127.140318 -368.339226) (xy 127.099127 -368.374917) (xy 127.053277 -368.404383)
			(xy 127.0037 -368.427025) (xy 126.951405 -368.44238) (xy 126.897457 -368.450136) (xy 126.842955 -368.450136)
			(xy 126.789007 -368.44238) (xy 126.736712 -368.427025) (xy 126.687135 -368.404383) (xy 126.641285 -368.374917)
			(xy 126.600094 -368.339226) (xy 126.564403 -368.298035) (xy 126.534937 -368.252185) (xy 126.512295 -368.202608)
			(xy 126.49694 -368.150313) (xy 126.489184 -368.096365) (xy 126.488698 -368.069114) (xy 125.118114 -368.069114)
			(xy 125.117628 -368.096365) (xy 125.109872 -368.150313) (xy 125.094517 -368.202608) (xy 125.071875 -368.252185)
			(xy 125.042409 -368.298035) (xy 125.006718 -368.339226) (xy 124.965527 -368.374917) (xy 124.919677 -368.404383)
			(xy 124.8701 -368.427025) (xy 124.817805 -368.44238) (xy 124.763857 -368.450136) (xy 124.709355 -368.450136)
			(xy 124.655407 -368.44238) (xy 124.603112 -368.427025) (xy 124.553535 -368.404383) (xy 124.507685 -368.374917)
			(xy 124.466494 -368.339226) (xy 124.430803 -368.298035) (xy 124.401337 -368.252185) (xy 124.378695 -368.202608)
			(xy 124.36334 -368.150313) (xy 124.355584 -368.096365) (xy 124.355098 -368.069114) (xy 122.97029 -368.069114)
			(xy 122.969804 -368.096365) (xy 122.962048 -368.150313) (xy 122.946693 -368.202608) (xy 122.924051 -368.252185)
			(xy 122.894585 -368.298035) (xy 122.858894 -368.339226) (xy 122.817703 -368.374917) (xy 122.771853 -368.404383)
			(xy 122.722276 -368.427025) (xy 122.669981 -368.44238) (xy 122.616033 -368.450136) (xy 122.561531 -368.450136)
			(xy 122.507583 -368.44238) (xy 122.455288 -368.427025) (xy 122.405711 -368.404383) (xy 122.359861 -368.374917)
			(xy 122.31867 -368.339226) (xy 122.282979 -368.298035) (xy 122.253513 -368.252185) (xy 122.230871 -368.202608)
			(xy 122.215516 -368.150313) (xy 122.20776 -368.096365) (xy 122.207274 -368.069114) (xy 121.825273 -368.069114)
			(xy 121.791195 -368.107148) (xy 121.748327 -368.142823) (xy 121.700721 -368.171877) (xy 121.649392 -368.193689)
			(xy 121.595435 -368.207795) (xy 121.539998 -368.213895) (xy 121.484264 -368.211858) (xy 121.429421 -368.201728)
			(xy 121.376637 -368.183721) (xy 121.327037 -368.15822) (xy 121.281679 -368.125769) (xy 121.24153 -368.08706)
			(xy 121.207444 -368.042917) (xy 121.180148 -367.994282) (xy 121.160225 -367.942191) (xy 121.148099 -367.887754)
			(xy 121.144028 -367.832132) (xy 97.920324 -367.832132) (xy 98.67392 -368.140488) (xy 101.960954 -368.696748)
			(xy 117.255542 -368.696748) (xy 117.259613 -368.641126) (xy 117.271739 -368.586689) (xy 117.291662 -368.534598)
			(xy 117.318958 -368.485963) (xy 117.353044 -368.44182) (xy 117.393193 -368.403111) (xy 117.438551 -368.37066)
			(xy 117.488151 -368.345159) (xy 117.540935 -368.327152) (xy 117.595778 -368.317022) (xy 117.651512 -368.314985)
			(xy 117.706949 -368.321085) (xy 117.760906 -368.335191) (xy 117.812235 -368.357003) (xy 117.859841 -368.386057)
			(xy 117.902709 -368.421732) (xy 117.939926 -368.463269) (xy 117.970699 -368.509782) (xy 117.994371 -368.560279)
			(xy 118.010439 -368.613686) (xy 118.018559 -368.668862) (xy 118.019068 -368.696748) (xy 118.018559 -368.724634)
			(xy 118.010439 -368.77981) (xy 117.994371 -368.833217) (xy 117.970699 -368.883714) (xy 117.939926 -368.930227)
			(xy 117.902709 -368.971764) (xy 117.859841 -369.007439) (xy 117.812235 -369.036493) (xy 117.760906 -369.058305)
			(xy 117.706949 -369.072411) (xy 117.651512 -369.078511) (xy 117.595778 -369.076474) (xy 117.540935 -369.066344)
			(xy 117.488151 -369.048337) (xy 117.438551 -369.022836) (xy 117.393193 -368.990385) (xy 117.353044 -368.951676)
			(xy 117.318958 -368.907533) (xy 117.291662 -368.858898) (xy 117.271739 -368.806807) (xy 117.259613 -368.75237)
			(xy 117.255542 -368.696748) (xy 101.960954 -368.696748) (xy 116.18976 -371.104668) (xy 121.8946 -372.003828)
			(xy 155.7655 -372.003828)
		)
		(stroke
			(width 0)
			(type solid)
		)
		(fill yes)
		(layer "In11.Cu")
		(net "GND")
	)
	(gr_poly
		(pts
			(xy 419.884606 -378.903484) (xy 421.684704 -378.903484) (xy 422.54043 -378.047758) (xy 422.558421 -378.030414)
			(xy 422.598841 -378.00103) (xy 422.643359 -377.978332) (xy 422.690881 -377.962877) (xy 422.740235 -377.955047)
			(xy 422.76522 -377.95454) (xy 423.561002 -377.95454) (xy 425.773596 -375.741946) (xy 425.791603 -375.72462)
			(xy 425.832019 -375.695235) (xy 425.876534 -375.672535) (xy 425.924051 -375.657077) (xy 425.973402 -375.649243)
			(xy 425.998386 -375.648728) (xy 427.276006 -375.648728) (xy 432.689 -370.235988) (xy 432.689 -346.720668)
			(xy 428.388018 -342.419686) (xy 411.417262 -342.419686) (xy 402.649944 -333.652368) (xy 395.61389 -333.652368)
			(xy 395.18082 -334.085438) (xy 395.18082 -346.010992) (xy 414.186375 -346.010992) (xy 414.190397 -345.925272)
			(xy 414.202428 -345.840304) (xy 414.222364 -345.756837) (xy 414.250027 -345.675603) (xy 414.285176 -345.597317)
			(xy 414.327502 -345.522666) (xy 414.376631 -345.452307) (xy 414.432134 -345.386857) (xy 414.493521 -345.326893)
			(xy 414.560254 -345.27294) (xy 414.631746 -345.225473) (xy 414.707368 -345.184909) (xy 414.786457 -345.151605)
			(xy 414.868317 -345.125853) (xy 414.952228 -345.10788) (xy 415.037454 -345.097844) (xy 415.123246 -345.095832)
			(xy 415.208848 -345.101863) (xy 415.29351 -345.115883) (xy 415.376487 -345.137769) (xy 415.45705 -345.16733)
			(xy 415.53449 -345.204304) (xy 415.608129 -345.248368) (xy 415.677317 -345.299134) (xy 415.741448 -345.356155)
			(xy 415.799957 -345.418931) (xy 415.85233 -345.486911) (xy 415.898108 -345.559496) (xy 415.936888 -345.636048)
			(xy 415.968329 -345.715896) (xy 415.992155 -345.798337) (xy 416.008156 -345.882647) (xy 416.016191 -345.968085)
			(xy 416.016694 -346.010992) (xy 416.01662 -346.017342) (xy 420.377117 -346.017342) (xy 420.381139 -345.931622)
			(xy 420.39317 -345.846654) (xy 420.413106 -345.763187) (xy 420.440769 -345.681953) (xy 420.475918 -345.603667)
			(xy 420.518244 -345.529016) (xy 420.567373 -345.458657) (xy 420.622876 -345.393207) (xy 420.684263 -345.333243)
			(xy 420.750996 -345.27929) (xy 420.822488 -345.231823) (xy 420.89811 -345.191259) (xy 420.977199 -345.157955)
			(xy 421.059059 -345.132203) (xy 421.14297 -345.11423) (xy 421.228196 -345.104194) (xy 421.313988 -345.102182)
			(xy 421.39959 -345.108213) (xy 421.484252 -345.122233) (xy 421.567229 -345.144119) (xy 421.647792 -345.17368)
			(xy 421.725232 -345.210654) (xy 421.798871 -345.254718) (xy 421.868059 -345.305484) (xy 421.93219 -345.362505)
			(xy 421.990699 -345.425281) (xy 422.043072 -345.493261) (xy 422.08885 -345.565846) (xy 422.12763 -345.642398)
			(xy 422.159071 -345.722246) (xy 422.182897 -345.804687) (xy 422.198898 -345.888997) (xy 422.206933 -345.974435)
			(xy 422.207436 -346.017342) (xy 426.574717 -346.017342) (xy 426.578739 -345.931622) (xy 426.59077 -345.846654)
			(xy 426.610706 -345.763187) (xy 426.638369 -345.681953) (xy 426.673518 -345.603667) (xy 426.715844 -345.529016)
			(xy 426.764973 -345.458657) (xy 426.820476 -345.393207) (xy 426.881863 -345.333243) (xy 426.948596 -345.27929)
			(xy 427.020088 -345.231823) (xy 427.09571 -345.191259) (xy 427.174799 -345.157955) (xy 427.256659 -345.132203)
			(xy 427.34057 -345.11423) (xy 427.425796 -345.104194) (xy 427.511588 -345.102182) (xy 427.59719 -345.108213)
			(xy 427.681852 -345.122233) (xy 427.764829 -345.144119) (xy 427.845392 -345.17368) (xy 427.922832 -345.210654)
			(xy 427.996471 -345.254718) (xy 428.065659 -345.305484) (xy 428.12979 -345.362505) (xy 428.188299 -345.425281)
			(xy 428.240672 -345.493261) (xy 428.28645 -345.565846) (xy 428.32523 -345.642398) (xy 428.356671 -345.722246)
			(xy 428.380497 -345.804687) (xy 428.396498 -345.888997) (xy 428.404533 -345.974435) (xy 428.405036 -346.017342)
			(xy 428.404533 -346.060249) (xy 428.396498 -346.145687) (xy 428.380497 -346.229997) (xy 428.356671 -346.312438)
			(xy 428.32523 -346.392286) (xy 428.28645 -346.468838) (xy 428.240672 -346.541423) (xy 428.188299 -346.609403)
			(xy 428.12979 -346.672179) (xy 428.065659 -346.7292) (xy 427.996471 -346.779966) (xy 427.922832 -346.82403)
			(xy 427.845392 -346.861004) (xy 427.764829 -346.890565) (xy 427.681852 -346.912451) (xy 427.59719 -346.926471)
			(xy 427.511588 -346.932502) (xy 427.425796 -346.93049) (xy 427.34057 -346.920454) (xy 427.256659 -346.902481)
			(xy 427.174799 -346.876729) (xy 427.09571 -346.843425) (xy 427.020088 -346.802861) (xy 426.948596 -346.755394)
			(xy 426.881863 -346.701441) (xy 426.820476 -346.641477) (xy 426.764973 -346.576027) (xy 426.715844 -346.505668)
			(xy 426.673518 -346.431017) (xy 426.638369 -346.352731) (xy 426.610706 -346.271497) (xy 426.59077 -346.18803)
			(xy 426.578739 -346.103062) (xy 426.574717 -346.017342) (xy 422.207436 -346.017342) (xy 422.206933 -346.060249)
			(xy 422.198898 -346.145687) (xy 422.182897 -346.229997) (xy 422.159071 -346.312438) (xy 422.12763 -346.392286)
			(xy 422.08885 -346.468838) (xy 422.043072 -346.541423) (xy 421.990699 -346.609403) (xy 421.93219 -346.672179)
			(xy 421.868059 -346.7292) (xy 421.798871 -346.779966) (xy 421.725232 -346.82403) (xy 421.647792 -346.861004)
			(xy 421.567229 -346.890565) (xy 421.484252 -346.912451) (xy 421.39959 -346.926471) (xy 421.313988 -346.932502)
			(xy 421.228196 -346.93049) (xy 421.14297 -346.920454) (xy 421.059059 -346.902481) (xy 420.977199 -346.876729)
			(xy 420.89811 -346.843425) (xy 420.822488 -346.802861) (xy 420.750996 -346.755394) (xy 420.684263 -346.701441)
			(xy 420.622876 -346.641477) (xy 420.567373 -346.576027) (xy 420.518244 -346.505668) (xy 420.475918 -346.431017)
			(xy 420.440769 -346.352731) (xy 420.413106 -346.271497) (xy 420.39317 -346.18803) (xy 420.381139 -346.103062)
			(xy 420.377117 -346.017342) (xy 416.01662 -346.017342) (xy 416.016191 -346.053899) (xy 416.008156 -346.139337)
			(xy 415.992155 -346.223647) (xy 415.968329 -346.306088) (xy 415.936888 -346.385936) (xy 415.898108 -346.462488)
			(xy 415.85233 -346.535073) (xy 415.799957 -346.603053) (xy 415.741448 -346.665829) (xy 415.677317 -346.72285)
			(xy 415.608129 -346.773616) (xy 415.53449 -346.81768) (xy 415.45705 -346.854654) (xy 415.376487 -346.884215)
			(xy 415.29351 -346.906101) (xy 415.208848 -346.920121) (xy 415.123246 -346.926152) (xy 415.037454 -346.92414)
			(xy 414.952228 -346.914104) (xy 414.868317 -346.896131) (xy 414.786457 -346.870379) (xy 414.707368 -346.837075)
			(xy 414.631746 -346.796511) (xy 414.560254 -346.749044) (xy 414.493521 -346.695091) (xy 414.432134 -346.635127)
			(xy 414.376631 -346.569677) (xy 414.327502 -346.499318) (xy 414.285176 -346.424667) (xy 414.250027 -346.346381)
			(xy 414.222364 -346.265147) (xy 414.202428 -346.18168) (xy 414.190397 -346.096712) (xy 414.186375 -346.010992)
			(xy 395.18082 -346.010992) (xy 395.18082 -351.152968) (xy 412.661354 -351.152968) (xy 412.661788 -351.125596)
			(xy 412.669612 -351.071415) (xy 412.685107 -351.018912) (xy 412.707957 -350.969165) (xy 412.737689 -350.9232)
			(xy 412.755334 -350.90227) (xy 412.764599 -350.890965) (xy 412.776768 -350.864398) (xy 412.780933 -350.835476)
			(xy 412.776755 -350.806555) (xy 412.764573 -350.779995) (xy 412.755334 -350.768666) (xy 412.737662 -350.747759)
			(xy 412.707938 -350.701787) (xy 412.685094 -350.652036) (xy 412.6696 -350.59953) (xy 412.661774 -350.545348)
			(xy 412.661777 -350.490604) (xy 412.66961 -350.436423) (xy 412.685111 -350.383918) (xy 412.707961 -350.334171)
			(xy 412.737691 -350.288203) (xy 412.755334 -350.26727) (xy 412.764599 -350.255965) (xy 412.776768 -350.229398)
			(xy 412.780933 -350.200476) (xy 412.776755 -350.171555) (xy 412.764573 -350.144995) (xy 412.755334 -350.133666)
			(xy 412.737662 -350.112759) (xy 412.707938 -350.066787) (xy 412.685094 -350.017036) (xy 412.6696 -349.96453)
			(xy 412.661774 -349.910348) (xy 412.661777 -349.855604) (xy 412.66961 -349.801423) (xy 412.685111 -349.748918)
			(xy 412.707961 -349.699171) (xy 412.737691 -349.653203) (xy 412.755334 -349.63227) (xy 412.764599 -349.620965)
			(xy 412.776768 -349.594398) (xy 412.780933 -349.565476) (xy 412.776755 -349.536555) (xy 412.764573 -349.509995)
			(xy 412.755334 -349.498666) (xy 412.737662 -349.477759) (xy 412.707938 -349.431787) (xy 412.685094 -349.382036)
			(xy 412.6696 -349.32953) (xy 412.661774 -349.275348) (xy 412.661777 -349.220604) (xy 412.66961 -349.166423)
			(xy 412.685111 -349.113918) (xy 412.707961 -349.064171) (xy 412.737691 -349.018203) (xy 412.755334 -348.99727)
			(xy 412.764599 -348.985965) (xy 412.776768 -348.959398) (xy 412.780933 -348.930476) (xy 412.776755 -348.901555)
			(xy 412.764573 -348.874995) (xy 412.755334 -348.863666) (xy 412.737662 -348.842759) (xy 412.707938 -348.796787)
			(xy 412.685094 -348.747036) (xy 412.6696 -348.69453) (xy 412.661774 -348.640348) (xy 412.661777 -348.585604)
			(xy 412.66961 -348.531423) (xy 412.685111 -348.478918) (xy 412.707961 -348.429171) (xy 412.737691 -348.383203)
			(xy 412.755334 -348.36227) (xy 412.764599 -348.350965) (xy 412.776768 -348.324398) (xy 412.780933 -348.295476)
			(xy 412.776755 -348.266555) (xy 412.764573 -348.239995) (xy 412.755334 -348.228666) (xy 412.737662 -348.207759)
			(xy 412.707938 -348.161787) (xy 412.685094 -348.112036) (xy 412.6696 -348.05953) (xy 412.661774 -348.005348)
			(xy 412.661777 -347.950604) (xy 412.66961 -347.896423) (xy 412.685111 -347.843918) (xy 412.707961 -347.794171)
			(xy 412.737691 -347.748203) (xy 412.755334 -347.72727) (xy 412.764599 -347.715965) (xy 412.776768 -347.689398)
			(xy 412.780933 -347.660476) (xy 412.776755 -347.631555) (xy 412.764573 -347.604995) (xy 412.755334 -347.593666)
			(xy 412.737718 -347.572715) (xy 412.708001 -347.526748) (xy 412.68516 -347.477006) (xy 412.669664 -347.424509)
			(xy 412.661831 -347.370336) (xy 412.661354 -347.342968) (xy 412.661848 -347.315718) (xy 412.669608 -347.261772)
			(xy 412.684965 -347.20948) (xy 412.707607 -347.159905) (xy 412.737073 -347.114057) (xy 412.772764 -347.072868)
			(xy 412.813952 -347.037177) (xy 412.8598 -347.00771) (xy 412.909374 -346.985067) (xy 412.961666 -346.969709)
			(xy 413.015612 -346.961948) (xy 413.042862 -346.96146) (xy 413.070232 -346.961934) (xy 413.124411 -346.969747)
			(xy 413.176915 -346.985234) (xy 413.226662 -347.008074) (xy 413.272629 -347.037799) (xy 413.29356 -347.05544)
			(xy 413.304888 -347.064676) (xy 413.331445 -347.076852) (xy 413.360362 -347.081025) (xy 413.389279 -347.076852)
			(xy 413.415836 -347.064676) (xy 413.427164 -347.05544) (xy 413.448104 -347.037811) (xy 413.494074 -347.008096)
			(xy 413.543819 -346.985257) (xy 413.596319 -346.969764) (xy 413.650493 -346.961935) (xy 413.677862 -346.96146)
			(xy 413.705901 -346.96198) (xy 413.761378 -346.970176) (xy 413.815059 -346.986395) (xy 413.865792 -347.010291)
			(xy 413.912485 -347.041349) (xy 413.93364 -347.059758) (xy 413.945082 -347.069403) (xy 413.972125 -347.082183)
			(xy 414.001712 -347.086569) (xy 414.031299 -347.082183) (xy 414.058342 -347.069403) (xy 414.069784 -347.059758)
			(xy 414.090918 -347.041318) (xy 414.1376 -347.010227) (xy 414.188336 -346.986316) (xy 414.242028 -346.970101)
			(xy 414.297518 -346.961931) (xy 414.325562 -346.96146) (xy 414.352812 -346.961991) (xy 414.406759 -346.969742)
			(xy 414.459054 -346.985091) (xy 414.508632 -347.007727) (xy 414.554484 -347.037188) (xy 414.595676 -347.072875)
			(xy 414.63137 -347.11406) (xy 414.66084 -347.159907) (xy 414.683484 -347.20948) (xy 414.698844 -347.261772)
			(xy 414.706604 -347.315718) (xy 414.70707 -347.342968) (xy 414.706592 -347.370338) (xy 414.698779 -347.424517)
			(xy 414.683293 -347.47702) (xy 414.660453 -347.526767) (xy 414.63073 -347.572734) (xy 414.61309 -347.593666)
			(xy 414.603885 -347.605017) (xy 414.591705 -347.631566) (xy 414.587527 -347.660476) (xy 414.591691 -347.689387)
			(xy 414.603858 -347.715943) (xy 414.61309 -347.72727) (xy 414.630699 -347.748228) (xy 414.660423 -347.794192)
			(xy 414.68327 -347.843934) (xy 414.698768 -347.896432) (xy 414.706599 -347.950607) (xy 414.706602 -348.005345)
			(xy 414.698778 -348.059521) (xy 414.683287 -348.11202) (xy 414.660447 -348.161765) (xy 414.630728 -348.207733)
			(xy 414.61309 -348.228666) (xy 414.603885 -348.240017) (xy 414.591705 -348.266566) (xy 414.587527 -348.295476)
			(xy 414.591691 -348.324387) (xy 414.603858 -348.350943) (xy 414.61309 -348.36227) (xy 414.630699 -348.383228)
			(xy 414.660423 -348.429192) (xy 414.68327 -348.478934) (xy 414.698768 -348.531432) (xy 414.706599 -348.585607)
			(xy 414.706602 -348.640345) (xy 414.698778 -348.694521) (xy 414.683287 -348.74702) (xy 414.660447 -348.796765)
			(xy 414.630728 -348.842733) (xy 414.61309 -348.863666) (xy 414.603885 -348.875017) (xy 414.591705 -348.901566)
			(xy 414.587527 -348.930476) (xy 414.591691 -348.959387) (xy 414.603858 -348.985943) (xy 414.61309 -348.99727)
			(xy 414.630699 -349.018228) (xy 414.660423 -349.064192) (xy 414.68327 -349.113934) (xy 414.698768 -349.166432)
			(xy 414.706599 -349.220607) (xy 414.706602 -349.275345) (xy 414.698778 -349.329521) (xy 414.683287 -349.38202)
			(xy 414.660447 -349.431765) (xy 414.630728 -349.477733) (xy 414.61309 -349.498666) (xy 414.603885 -349.510017)
			(xy 414.591705 -349.536566) (xy 414.587527 -349.565476) (xy 414.591691 -349.594387) (xy 414.603858 -349.620943)
			(xy 414.61309 -349.63227) (xy 414.630699 -349.653228) (xy 414.660423 -349.699192) (xy 414.68327 -349.748934)
			(xy 414.698768 -349.801432) (xy 414.706599 -349.855607) (xy 414.706602 -349.910345) (xy 414.698778 -349.964521)
			(xy 414.683287 -350.01702) (xy 414.660447 -350.066765) (xy 414.630728 -350.112733) (xy 414.61309 -350.133666)
			(xy 414.603885 -350.145017) (xy 414.591705 -350.171566) (xy 414.587527 -350.200476) (xy 414.591691 -350.229387)
			(xy 414.603858 -350.255943) (xy 414.61309 -350.26727) (xy 414.630699 -350.288228) (xy 414.660423 -350.334192)
			(xy 414.68327 -350.383934) (xy 414.698768 -350.436432) (xy 414.706599 -350.490607) (xy 414.706602 -350.545345)
			(xy 414.698778 -350.599521) (xy 414.683287 -350.65202) (xy 414.660447 -350.701765) (xy 414.630728 -350.747733)
			(xy 414.61309 -350.768666) (xy 414.603885 -350.780017) (xy 414.591705 -350.806566) (xy 414.587527 -350.835476)
			(xy 414.591691 -350.864387) (xy 414.603858 -350.890943) (xy 414.61309 -350.90227) (xy 414.630727 -350.923204)
			(xy 414.660439 -350.969176) (xy 414.683276 -351.018923) (xy 414.698767 -351.071423) (xy 414.706596 -351.125599)
			(xy 414.70707 -351.152968) (xy 417.631626 -351.152968) (xy 417.632067 -351.125597) (xy 417.63989 -351.071416)
			(xy 417.655384 -351.018913) (xy 417.678232 -350.969166) (xy 417.707962 -350.923201) (xy 417.725606 -350.90227)
			(xy 417.734873 -350.890966) (xy 417.747046 -350.864399) (xy 417.751212 -350.835476) (xy 417.747032 -350.806554)
			(xy 417.734847 -350.779994) (xy 417.725606 -350.768666) (xy 417.707935 -350.747758) (xy 417.678213 -350.701786)
			(xy 417.655371 -350.652035) (xy 417.639878 -350.599529) (xy 417.632053 -350.545348) (xy 417.632056 -350.490604)
			(xy 417.639888 -350.436423) (xy 417.655388 -350.38392) (xy 417.678236 -350.334172) (xy 417.707964 -350.288203)
			(xy 417.725606 -350.26727) (xy 417.734873 -350.255966) (xy 417.747046 -350.229399) (xy 417.751212 -350.200476)
			(xy 417.747032 -350.171554) (xy 417.734847 -350.144994) (xy 417.725606 -350.133666) (xy 417.707935 -350.112758)
			(xy 417.678213 -350.066786) (xy 417.655371 -350.017035) (xy 417.639878 -349.964529) (xy 417.632053 -349.910348)
			(xy 417.632056 -349.855604) (xy 417.639888 -349.801423) (xy 417.655388 -349.74892) (xy 417.678236 -349.699172)
			(xy 417.707964 -349.653203) (xy 417.725606 -349.63227) (xy 417.734873 -349.620966) (xy 417.747046 -349.594399)
			(xy 417.751212 -349.565476) (xy 417.747032 -349.536554) (xy 417.734847 -349.509994) (xy 417.725606 -349.498666)
			(xy 417.707935 -349.477758) (xy 417.678213 -349.431786) (xy 417.655371 -349.382035) (xy 417.639878 -349.329529)
			(xy 417.632053 -349.275348) (xy 417.632056 -349.220604) (xy 417.639888 -349.166423) (xy 417.655388 -349.11392)
			(xy 417.678236 -349.064172) (xy 417.707964 -349.018203) (xy 417.725606 -348.99727) (xy 417.734873 -348.985966)
			(xy 417.747046 -348.959399) (xy 417.751212 -348.930476) (xy 417.747032 -348.901554) (xy 417.734847 -348.874994)
			(xy 417.725606 -348.863666) (xy 417.707935 -348.842758) (xy 417.678213 -348.796786) (xy 417.655371 -348.747035)
			(xy 417.639878 -348.694529) (xy 417.632053 -348.640348) (xy 417.632056 -348.585604) (xy 417.639888 -348.531423)
			(xy 417.655388 -348.47892) (xy 417.678236 -348.429172) (xy 417.707964 -348.383203) (xy 417.725606 -348.36227)
			(xy 417.734873 -348.350966) (xy 417.747046 -348.324399) (xy 417.751212 -348.295476) (xy 417.747032 -348.266554)
			(xy 417.734847 -348.239994) (xy 417.725606 -348.228666) (xy 417.707935 -348.207758) (xy 417.678213 -348.161786)
			(xy 417.655371 -348.112035) (xy 417.639878 -348.059529) (xy 417.632053 -348.005348) (xy 417.632056 -347.950604)
			(xy 417.639888 -347.896423) (xy 417.655388 -347.84392) (xy 417.678236 -347.794172) (xy 417.707964 -347.748203)
			(xy 417.725606 -347.72727) (xy 417.734873 -347.715966) (xy 417.747046 -347.689399) (xy 417.751212 -347.660476)
			(xy 417.747032 -347.631554) (xy 417.734847 -347.604994) (xy 417.725606 -347.593666) (xy 417.707985 -347.572719)
			(xy 417.678271 -347.52675) (xy 417.655431 -347.477007) (xy 417.639936 -347.424509) (xy 417.632103 -347.370336)
			(xy 417.631626 -347.342968) (xy 417.632025 -347.315713) (xy 417.639787 -347.261758) (xy 417.655149 -347.209457)
			(xy 417.677798 -347.159874) (xy 417.707273 -347.114019) (xy 417.742973 -347.072826) (xy 417.784172 -347.037133)
			(xy 417.830032 -347.007666) (xy 417.879619 -346.985026) (xy 417.931922 -346.969673) (xy 417.985879 -346.96192)
			(xy 418.013134 -346.96146) (xy 418.041175 -346.961937) (xy 418.096653 -346.970143) (xy 418.150335 -346.986373)
			(xy 418.201067 -347.010278) (xy 418.247758 -347.041345) (xy 418.268912 -347.059758) (xy 418.280354 -347.069403)
			(xy 418.307397 -347.082183) (xy 418.336984 -347.086569) (xy 418.366571 -347.082183) (xy 418.393614 -347.069403)
			(xy 418.405056 -347.059758) (xy 418.426201 -347.041331) (xy 418.47288 -347.010239) (xy 418.523613 -346.986325)
			(xy 418.577303 -346.970106) (xy 418.63279 -346.961933) (xy 418.660834 -346.96146) (xy 418.688206 -346.961892)
			(xy 418.742387 -346.969715) (xy 418.794891 -346.985212) (xy 418.844637 -347.008062) (xy 418.890602 -347.037795)
			(xy 418.911532 -347.05544) (xy 418.92286 -347.064676) (xy 418.949417 -347.076852) (xy 418.978334 -347.081025)
			(xy 419.007251 -347.076852) (xy 419.033808 -347.064676) (xy 419.045136 -347.05544) (xy 419.066087 -347.037824)
			(xy 419.112054 -347.008107) (xy 419.161796 -346.985266) (xy 419.214293 -346.96977) (xy 419.268466 -346.961937)
			(xy 419.295834 -346.96146) (xy 419.323085 -346.961946) (xy 419.377031 -346.969706) (xy 419.429323 -346.985064)
			(xy 419.478899 -347.007707) (xy 419.524747 -347.037174) (xy 419.565936 -347.072865) (xy 419.601627 -347.114054)
			(xy 419.631094 -347.159903) (xy 419.653736 -347.209478) (xy 419.669094 -347.261771) (xy 419.676854 -347.315717)
			(xy 419.677342 -347.342968) (xy 419.676871 -347.370338) (xy 419.669057 -347.424518) (xy 419.65357 -347.477021)
			(xy 419.630728 -347.526768) (xy 419.601004 -347.572735) (xy 419.583362 -347.593666) (xy 419.574159 -347.605018)
			(xy 419.561982 -347.631567) (xy 419.557806 -347.660476) (xy 419.561969 -347.689386) (xy 419.574133 -347.715942)
			(xy 419.583362 -347.72727) (xy 419.600972 -347.748228) (xy 419.630699 -347.794191) (xy 419.653547 -347.843933)
			(xy 419.669046 -347.896431) (xy 419.676878 -347.950607) (xy 419.676881 -348.005345) (xy 419.669056 -348.059521)
			(xy 419.653564 -348.112022) (xy 419.630722 -348.161767) (xy 419.601001 -348.207734) (xy 419.583362 -348.228666)
			(xy 419.574159 -348.240018) (xy 419.561982 -348.266567) (xy 419.557806 -348.295476) (xy 419.561969 -348.324386)
			(xy 419.574133 -348.350942) (xy 419.583362 -348.36227) (xy 419.600972 -348.383228) (xy 419.630699 -348.429191)
			(xy 419.653547 -348.478933) (xy 419.669046 -348.531431) (xy 419.676878 -348.585607) (xy 419.676881 -348.640345)
			(xy 419.669056 -348.694521) (xy 419.653564 -348.747022) (xy 419.630722 -348.796767) (xy 419.601001 -348.842734)
			(xy 419.583362 -348.863666) (xy 419.574159 -348.875018) (xy 419.561982 -348.901567) (xy 419.557806 -348.930476)
			(xy 419.561969 -348.959386) (xy 419.574133 -348.985942) (xy 419.583362 -348.99727) (xy 419.600972 -349.018228)
			(xy 419.630699 -349.064191) (xy 419.653547 -349.113933) (xy 419.669046 -349.166431) (xy 419.676878 -349.220607)
			(xy 419.676881 -349.275345) (xy 419.669056 -349.329521) (xy 419.653564 -349.382022) (xy 419.630722 -349.431767)
			(xy 419.601001 -349.477734) (xy 419.583362 -349.498666) (xy 419.574159 -349.510018) (xy 419.561982 -349.536567)
			(xy 419.557806 -349.565476) (xy 419.561969 -349.594386) (xy 419.574133 -349.620942) (xy 419.583362 -349.63227)
			(xy 419.600972 -349.653228) (xy 419.630699 -349.699191) (xy 419.653547 -349.748933) (xy 419.669046 -349.801431)
			(xy 419.676878 -349.855607) (xy 419.676881 -349.910345) (xy 419.669056 -349.964521) (xy 419.653564 -350.017022)
			(xy 419.630722 -350.066767) (xy 419.601001 -350.112734) (xy 419.583362 -350.133666) (xy 419.574159 -350.145018)
			(xy 419.561982 -350.171567) (xy 419.557806 -350.200476) (xy 419.561969 -350.229386) (xy 419.574133 -350.255942)
			(xy 419.583362 -350.26727) (xy 419.600972 -350.288228) (xy 419.630699 -350.334191) (xy 419.653547 -350.383933)
			(xy 419.669046 -350.436431) (xy 419.676878 -350.490607) (xy 419.676881 -350.545345) (xy 419.669056 -350.599521)
			(xy 419.653564 -350.652022) (xy 419.630722 -350.701767) (xy 419.601001 -350.747734) (xy 419.583362 -350.768666)
			(xy 419.574159 -350.780018) (xy 419.561982 -350.806567) (xy 419.557806 -350.835476) (xy 419.561969 -350.864386)
			(xy 419.574133 -350.890942) (xy 419.583362 -350.90227) (xy 419.600995 -350.923207) (xy 419.630709 -350.969178)
			(xy 419.653547 -351.018924) (xy 419.669039 -351.071424) (xy 419.676868 -351.125599) (xy 419.677342 -351.152968)
			(xy 422.338754 -351.152968) (xy 422.339188 -351.125596) (xy 422.347012 -351.071415) (xy 422.362507 -351.018912)
			(xy 422.385357 -350.969165) (xy 422.415089 -350.9232) (xy 422.432734 -350.90227) (xy 422.441999 -350.890965)
			(xy 422.454168 -350.864398) (xy 422.458333 -350.835476) (xy 422.454155 -350.806555) (xy 422.441973 -350.779995)
			(xy 422.432734 -350.768666) (xy 422.415062 -350.747759) (xy 422.385338 -350.701787) (xy 422.362494 -350.652036)
			(xy 422.347 -350.59953) (xy 422.339174 -350.545348) (xy 422.339177 -350.490604) (xy 422.34701 -350.436423)
			(xy 422.362511 -350.383918) (xy 422.385361 -350.334171) (xy 422.415091 -350.288203) (xy 422.432734 -350.26727)
			(xy 422.441999 -350.255965) (xy 422.454168 -350.229398) (xy 422.458333 -350.200476) (xy 422.454155 -350.171555)
			(xy 422.441973 -350.144995) (xy 422.432734 -350.133666) (xy 422.415062 -350.112759) (xy 422.385338 -350.066787)
			(xy 422.362494 -350.017036) (xy 422.347 -349.96453) (xy 422.339174 -349.910348) (xy 422.339177 -349.855604)
			(xy 422.34701 -349.801423) (xy 422.362511 -349.748918) (xy 422.385361 -349.699171) (xy 422.415091 -349.653203)
			(xy 422.432734 -349.63227) (xy 422.441999 -349.620965) (xy 422.454168 -349.594398) (xy 422.458333 -349.565476)
			(xy 422.454155 -349.536555) (xy 422.441973 -349.509995) (xy 422.432734 -349.498666) (xy 422.415062 -349.477759)
			(xy 422.385338 -349.431787) (xy 422.362494 -349.382036) (xy 422.347 -349.32953) (xy 422.339174 -349.275348)
			(xy 422.339177 -349.220604) (xy 422.34701 -349.166423) (xy 422.362511 -349.113918) (xy 422.385361 -349.064171)
			(xy 422.415091 -349.018203) (xy 422.432734 -348.99727) (xy 422.441999 -348.985965) (xy 422.454168 -348.959398)
			(xy 422.458333 -348.930476) (xy 422.454155 -348.901555) (xy 422.441973 -348.874995) (xy 422.432734 -348.863666)
			(xy 422.415062 -348.842759) (xy 422.385338 -348.796787) (xy 422.362494 -348.747036) (xy 422.347 -348.69453)
			(xy 422.339174 -348.640348) (xy 422.339177 -348.585604) (xy 422.34701 -348.531423) (xy 422.362511 -348.478918)
			(xy 422.385361 -348.429171) (xy 422.415091 -348.383203) (xy 422.432734 -348.36227) (xy 422.441999 -348.350965)
			(xy 422.454168 -348.324398) (xy 422.458333 -348.295476) (xy 422.454155 -348.266555) (xy 422.441973 -348.239995)
			(xy 422.432734 -348.228666) (xy 422.415062 -348.207759) (xy 422.385338 -348.161787) (xy 422.362494 -348.112036)
			(xy 422.347 -348.05953) (xy 422.339174 -348.005348) (xy 422.339177 -347.950604) (xy 422.34701 -347.896423)
			(xy 422.362511 -347.843918) (xy 422.385361 -347.794171) (xy 422.415091 -347.748203) (xy 422.432734 -347.72727)
			(xy 422.441999 -347.715965) (xy 422.454168 -347.689398) (xy 422.458333 -347.660476) (xy 422.454155 -347.631555)
			(xy 422.441973 -347.604995) (xy 422.432734 -347.593666) (xy 422.415118 -347.572715) (xy 422.385401 -347.526748)
			(xy 422.36256 -347.477006) (xy 422.347064 -347.424509) (xy 422.339231 -347.370336) (xy 422.338754 -347.342968)
			(xy 422.339248 -347.315718) (xy 422.347008 -347.261772) (xy 422.362365 -347.20948) (xy 422.385007 -347.159905)
			(xy 422.414473 -347.114057) (xy 422.450164 -347.072868) (xy 422.491352 -347.037177) (xy 422.5372 -347.00771)
			(xy 422.586774 -346.985067) (xy 422.639066 -346.969709) (xy 422.693012 -346.961948) (xy 422.720262 -346.96146)
			(xy 422.747632 -346.961934) (xy 422.801811 -346.969747) (xy 422.854315 -346.985234) (xy 422.904062 -347.008074)
			(xy 422.950029 -347.037799) (xy 422.97096 -347.05544) (xy 422.982288 -347.064676) (xy 423.008845 -347.076852)
			(xy 423.037762 -347.081025) (xy 423.066679 -347.076852) (xy 423.093236 -347.064676) (xy 423.104564 -347.05544)
			(xy 423.125504 -347.037811) (xy 423.171474 -347.008096) (xy 423.221219 -346.985257) (xy 423.273719 -346.969764)
			(xy 423.327893 -346.961935) (xy 423.355262 -346.96146) (xy 423.383301 -346.96198) (xy 423.438778 -346.970176)
			(xy 423.492459 -346.986395) (xy 423.543192 -347.010291) (xy 423.589885 -347.041349) (xy 423.61104 -347.059758)
			(xy 423.622482 -347.069403) (xy 423.649525 -347.082183) (xy 423.679112 -347.086569) (xy 423.708699 -347.082183)
			(xy 423.735742 -347.069403) (xy 423.747184 -347.059758) (xy 423.768318 -347.041318) (xy 423.815 -347.010227)
			(xy 423.865736 -346.986316) (xy 423.919428 -346.970101) (xy 423.974918 -346.961931) (xy 424.002962 -346.96146)
			(xy 424.030212 -346.961991) (xy 424.084159 -346.969742) (xy 424.136454 -346.985091) (xy 424.186032 -347.007727)
			(xy 424.231884 -347.037188) (xy 424.273076 -347.072875) (xy 424.30877 -347.11406) (xy 424.33824 -347.159907)
			(xy 424.360884 -347.20948) (xy 424.376244 -347.261772) (xy 424.384004 -347.315718) (xy 424.38447 -347.342968)
			(xy 424.383992 -347.370338) (xy 424.376179 -347.424517) (xy 424.360693 -347.47702) (xy 424.337853 -347.526767)
			(xy 424.30813 -347.572734) (xy 424.29049 -347.593666) (xy 424.281285 -347.605017) (xy 424.269105 -347.631566)
			(xy 424.264927 -347.660476) (xy 424.269091 -347.689387) (xy 424.281258 -347.715943) (xy 424.29049 -347.72727)
			(xy 424.308099 -347.748228) (xy 424.337823 -347.794192) (xy 424.36067 -347.843934) (xy 424.376168 -347.896432)
			(xy 424.383999 -347.950607) (xy 424.384002 -348.005345) (xy 424.376178 -348.059521) (xy 424.360687 -348.11202)
			(xy 424.337847 -348.161765) (xy 424.308128 -348.207733) (xy 424.29049 -348.228666) (xy 424.281285 -348.240017)
			(xy 424.269105 -348.266566) (xy 424.264927 -348.295476) (xy 424.269091 -348.324387) (xy 424.281258 -348.350943)
			(xy 424.29049 -348.36227) (xy 424.308099 -348.383228) (xy 424.337823 -348.429192) (xy 424.36067 -348.478934)
			(xy 424.376168 -348.531432) (xy 424.383999 -348.585607) (xy 424.384002 -348.640345) (xy 424.376178 -348.694521)
			(xy 424.360687 -348.74702) (xy 424.337847 -348.796765) (xy 424.308128 -348.842733) (xy 424.29049 -348.863666)
			(xy 424.281285 -348.875017) (xy 424.269105 -348.901566) (xy 424.264927 -348.930476) (xy 424.269091 -348.959387)
			(xy 424.281258 -348.985943) (xy 424.29049 -348.99727) (xy 424.308099 -349.018228) (xy 424.337823 -349.064192)
			(xy 424.36067 -349.113934) (xy 424.376168 -349.166432) (xy 424.383999 -349.220607) (xy 424.384002 -349.275345)
			(xy 424.376178 -349.329521) (xy 424.360687 -349.38202) (xy 424.337847 -349.431765) (xy 424.308128 -349.477733)
			(xy 424.29049 -349.498666) (xy 424.281285 -349.510017) (xy 424.269105 -349.536566) (xy 424.264927 -349.565476)
			(xy 424.269091 -349.594387) (xy 424.281258 -349.620943) (xy 424.29049 -349.63227) (xy 424.308099 -349.653228)
			(xy 424.337823 -349.699192) (xy 424.36067 -349.748934) (xy 424.376168 -349.801432) (xy 424.383999 -349.855607)
			(xy 424.384002 -349.910345) (xy 424.376178 -349.964521) (xy 424.360687 -350.01702) (xy 424.337847 -350.066765)
			(xy 424.308128 -350.112733) (xy 424.29049 -350.133666) (xy 424.281285 -350.145017) (xy 424.269105 -350.171566)
			(xy 424.264927 -350.200476) (xy 424.269091 -350.229387) (xy 424.281258 -350.255943) (xy 424.29049 -350.26727)
			(xy 424.308099 -350.288228) (xy 424.337823 -350.334192) (xy 424.36067 -350.383934) (xy 424.376168 -350.436432)
			(xy 424.383999 -350.490607) (xy 424.384002 -350.545345) (xy 424.376178 -350.599521) (xy 424.360687 -350.65202)
			(xy 424.337847 -350.701765) (xy 424.308128 -350.747733) (xy 424.29049 -350.768666) (xy 424.281285 -350.780017)
			(xy 424.269105 -350.806566) (xy 424.264927 -350.835476) (xy 424.269091 -350.864387) (xy 424.281258 -350.890943)
			(xy 424.29049 -350.90227) (xy 424.308127 -350.923204) (xy 424.337839 -350.969176) (xy 424.360676 -351.018923)
			(xy 424.376167 -351.071423) (xy 424.383996 -351.125599) (xy 424.38447 -351.152968) (xy 427.95444 -351.152968)
			(xy 427.954878 -351.125597) (xy 427.962701 -351.071416) (xy 427.978196 -351.018912) (xy 428.001044 -350.969166)
			(xy 428.030775 -350.9232) (xy 428.04842 -350.90227) (xy 428.057686 -350.890965) (xy 428.069857 -350.864399)
			(xy 428.074023 -350.835476) (xy 428.069843 -350.806555) (xy 428.05766 -350.779994) (xy 428.04842 -350.768666)
			(xy 428.030748 -350.747758) (xy 428.001025 -350.701786) (xy 427.978182 -350.652036) (xy 427.962689 -350.59953)
			(xy 427.954863 -350.545348) (xy 427.954867 -350.490604) (xy 427.962699 -350.436423) (xy 427.978199 -350.383919)
			(xy 428.001049 -350.334172) (xy 428.030777 -350.288203) (xy 428.04842 -350.26727) (xy 428.057686 -350.255965)
			(xy 428.069857 -350.229399) (xy 428.074023 -350.200476) (xy 428.069843 -350.171555) (xy 428.05766 -350.144994)
			(xy 428.04842 -350.133666) (xy 428.030748 -350.112758) (xy 428.001025 -350.066786) (xy 427.978182 -350.017036)
			(xy 427.962689 -349.96453) (xy 427.954863 -349.910348) (xy 427.954867 -349.855604) (xy 427.962699 -349.801423)
			(xy 427.978199 -349.748919) (xy 428.001049 -349.699172) (xy 428.030777 -349.653203) (xy 428.04842 -349.63227)
			(xy 428.057686 -349.620965) (xy 428.069857 -349.594399) (xy 428.074023 -349.565476) (xy 428.069843 -349.536555)
			(xy 428.05766 -349.509994) (xy 428.04842 -349.498666) (xy 428.030748 -349.477758) (xy 428.001025 -349.431786)
			(xy 427.978182 -349.382036) (xy 427.962689 -349.32953) (xy 427.954863 -349.275348) (xy 427.954867 -349.220604)
			(xy 427.962699 -349.166423) (xy 427.978199 -349.113919) (xy 428.001049 -349.064172) (xy 428.030777 -349.018203)
			(xy 428.04842 -348.99727) (xy 428.057686 -348.985965) (xy 428.069857 -348.959399) (xy 428.074023 -348.930476)
			(xy 428.069843 -348.901555) (xy 428.05766 -348.874994) (xy 428.04842 -348.863666) (xy 428.030748 -348.842758)
			(xy 428.001025 -348.796786) (xy 427.978182 -348.747036) (xy 427.962689 -348.69453) (xy 427.954863 -348.640348)
			(xy 427.954867 -348.585604) (xy 427.962699 -348.531423) (xy 427.978199 -348.478919) (xy 428.001049 -348.429172)
			(xy 428.030777 -348.383203) (xy 428.04842 -348.36227) (xy 428.057686 -348.350965) (xy 428.069857 -348.324399)
			(xy 428.074023 -348.295476) (xy 428.069843 -348.266555) (xy 428.05766 -348.239994) (xy 428.04842 -348.228666)
			(xy 428.030748 -348.207758) (xy 428.001025 -348.161786) (xy 427.978182 -348.112036) (xy 427.962689 -348.05953)
			(xy 427.954863 -348.005348) (xy 427.954867 -347.950604) (xy 427.962699 -347.896423) (xy 427.978199 -347.843919)
			(xy 428.001049 -347.794172) (xy 428.030777 -347.748203) (xy 428.04842 -347.72727) (xy 428.057686 -347.715965)
			(xy 428.069857 -347.689399) (xy 428.074023 -347.660476) (xy 428.069843 -347.631555) (xy 428.05766 -347.604994)
			(xy 428.04842 -347.593666) (xy 428.030801 -347.572717) (xy 428.001086 -347.526749) (xy 427.978246 -347.477006)
			(xy 427.96275 -347.424509) (xy 427.954917 -347.370336) (xy 427.95444 -347.342968) (xy 427.954825 -347.315712)
			(xy 427.962588 -347.261756) (xy 427.97795 -347.209454) (xy 428.0006 -347.15987) (xy 428.030076 -347.114015)
			(xy 428.065778 -347.072821) (xy 428.106979 -347.037128) (xy 428.15284 -347.007662) (xy 428.202429 -346.985022)
			(xy 428.254734 -346.969671) (xy 428.308692 -346.96192) (xy 428.335948 -346.96146) (xy 428.363987 -346.961989)
			(xy 428.419463 -346.970182) (xy 428.473145 -346.9864) (xy 428.523877 -347.010293) (xy 428.570571 -347.041349)
			(xy 428.591726 -347.059758) (xy 428.603168 -347.069403) (xy 428.630211 -347.082183) (xy 428.659798 -347.086569)
			(xy 428.689385 -347.082183) (xy 428.716428 -347.069403) (xy 428.72787 -347.059758) (xy 428.74901 -347.041324)
			(xy 428.79569 -347.010233) (xy 428.846424 -346.98632) (xy 428.900115 -346.970103) (xy 428.955604 -346.961932)
			(xy 428.983648 -346.96146) (xy 429.011018 -346.961942) (xy 429.065197 -346.969754) (xy 429.1177 -346.985238)
			(xy 429.167448 -347.008077) (xy 429.213414 -347.037799) (xy 429.234346 -347.05544) (xy 429.245674 -347.064676)
			(xy 429.272231 -347.076852) (xy 429.301148 -347.081025) (xy 429.330065 -347.076852) (xy 429.356622 -347.064676)
			(xy 429.36795 -347.05544) (xy 429.388895 -347.037817) (xy 429.434864 -347.008101) (xy 429.484608 -346.985262)
			(xy 429.537106 -346.969767) (xy 429.59128 -346.961936) (xy 429.618648 -346.96146) (xy 429.645899 -346.961933)
			(xy 429.699845 -346.969695) (xy 429.752138 -346.985055) (xy 429.801714 -347.007699) (xy 429.847562 -347.037168)
			(xy 429.888751 -347.07286) (xy 429.924442 -347.11405) (xy 429.953908 -347.1599) (xy 429.976551 -347.209477)
			(xy 429.991908 -347.26177) (xy 429.999668 -347.315717) (xy 430.000156 -347.342968) (xy 429.999682 -347.370338)
			(xy 429.991868 -347.424517) (xy 429.976381 -347.477021) (xy 429.953541 -347.526768) (xy 429.923817 -347.572734)
			(xy 429.906176 -347.593666) (xy 429.896972 -347.605017) (xy 429.884794 -347.631567) (xy 429.880616 -347.660476)
			(xy 429.88478 -347.689387) (xy 429.896946 -347.715942) (xy 429.906176 -347.72727) (xy 429.923785 -347.748228)
			(xy 429.953511 -347.794192) (xy 429.976358 -347.843934) (xy 429.991857 -347.896432) (xy 429.999688 -347.950607)
			(xy 429.999692 -348.005345) (xy 429.991867 -348.059521) (xy 429.976375 -348.112021) (xy 429.953534 -348.161766)
			(xy 429.923814 -348.207733) (xy 429.906176 -348.228666) (xy 429.896972 -348.240017) (xy 429.884794 -348.266567)
			(xy 429.880616 -348.295476) (xy 429.88478 -348.324387) (xy 429.896946 -348.350942) (xy 429.906176 -348.36227)
			(xy 429.923785 -348.383228) (xy 429.953511 -348.429192) (xy 429.976358 -348.478934) (xy 429.991857 -348.531432)
			(xy 429.999688 -348.585607) (xy 429.999692 -348.640345) (xy 429.991867 -348.694521) (xy 429.976375 -348.747021)
			(xy 429.953534 -348.796766) (xy 429.923814 -348.842733) (xy 429.906176 -348.863666) (xy 429.896972 -348.875017)
			(xy 429.884794 -348.901567) (xy 429.880616 -348.930476) (xy 429.88478 -348.959387) (xy 429.896946 -348.985942)
			(xy 429.906176 -348.99727) (xy 429.923785 -349.018228) (xy 429.953511 -349.064192) (xy 429.976358 -349.113934)
			(xy 429.991857 -349.166432) (xy 429.999688 -349.220607) (xy 429.999692 -349.275345) (xy 429.991867 -349.329521)
			(xy 429.976375 -349.382021) (xy 429.953534 -349.431766) (xy 429.923814 -349.477733) (xy 429.906176 -349.498666)
			(xy 429.896972 -349.510017) (xy 429.884794 -349.536567) (xy 429.880616 -349.565476) (xy 429.88478 -349.594387)
			(xy 429.896946 -349.620942) (xy 429.906176 -349.63227) (xy 429.923785 -349.653228) (xy 429.953511 -349.699192)
			(xy 429.976358 -349.748934) (xy 429.991857 -349.801432) (xy 429.999688 -349.855607) (xy 429.999692 -349.910345)
			(xy 429.991867 -349.964521) (xy 429.976375 -350.017021) (xy 429.953534 -350.066766) (xy 429.923814 -350.112733)
			(xy 429.906176 -350.133666) (xy 429.896972 -350.145017) (xy 429.884794 -350.171567) (xy 429.880616 -350.200476)
			(xy 429.88478 -350.229387) (xy 429.896946 -350.255942) (xy 429.906176 -350.26727) (xy 429.923785 -350.288228)
			(xy 429.953511 -350.334192) (xy 429.976358 -350.383934) (xy 429.991857 -350.436432) (xy 429.999688 -350.490607)
			(xy 429.999692 -350.545345) (xy 429.991867 -350.599521) (xy 429.976375 -350.652021) (xy 429.953534 -350.701766)
			(xy 429.923814 -350.747733) (xy 429.906176 -350.768666) (xy 429.896972 -350.780017) (xy 429.884794 -350.806567)
			(xy 429.880616 -350.835476) (xy 429.88478 -350.864387) (xy 429.896946 -350.890942) (xy 429.906176 -350.90227)
			(xy 429.923811 -350.923206) (xy 429.953524 -350.969177) (xy 429.976361 -351.018924) (xy 429.991853 -351.071424)
			(xy 429.999682 -351.125599) (xy 430.000156 -351.152968) (xy 429.999592 -351.180216) (xy 429.991841 -351.234159)
			(xy 429.976493 -351.286449) (xy 429.953859 -351.336023) (xy 429.9244 -351.381871) (xy 429.888717 -351.42306)
			(xy 429.847535 -351.458752) (xy 429.801693 -351.48822) (xy 429.752124 -351.510865) (xy 429.699837 -351.526224)
			(xy 429.645896 -351.533986) (xy 429.618648 -351.534476) (xy 429.591279 -351.533988) (xy 429.5371 -351.526176)
			(xy 429.484597 -351.510693) (xy 429.43485 -351.487856) (xy 429.388882 -351.458135) (xy 429.36795 -351.440496)
			(xy 429.356622 -351.43126) (xy 429.330065 -351.419084) (xy 429.301148 -351.414911) (xy 429.272231 -351.419084)
			(xy 429.245674 -351.43126) (xy 429.234346 -351.440496) (xy 429.213407 -351.458126) (xy 429.167436 -351.48784)
			(xy 429.11769 -351.510677) (xy 429.065191 -351.52617) (xy 429.011017 -351.534001) (xy 428.983648 -351.534476)
			(xy 428.955608 -351.533966) (xy 428.900131 -351.525771) (xy 428.846448 -351.509549) (xy 428.795716 -351.485651)
			(xy 428.749024 -351.45459) (xy 428.72787 -351.436178) (xy 428.716428 -351.426533) (xy 428.689385 -351.413753)
			(xy 428.659798 -351.409367) (xy 428.630211 -351.413753) (xy 428.603168 -351.426533) (xy 428.591726 -351.436178)
			(xy 428.570593 -351.45462) (xy 428.52391 -351.485709) (xy 428.473174 -351.509619) (xy 428.419482 -351.525835)
			(xy 428.363992 -351.534005) (xy 428.335948 -351.534476) (xy 428.308695 -351.534) (xy 428.254743 -351.526249)
			(xy 428.202443 -351.510897) (xy 428.152861 -351.488258) (xy 428.107006 -351.458792) (xy 428.065812 -351.423099)
			(xy 428.030118 -351.381907) (xy 428.00065 -351.336053) (xy 427.978008 -351.286472) (xy 427.962655 -351.234173)
			(xy 427.954901 -351.180221) (xy 427.95444 -351.152968) (xy 424.38447 -351.152968) (xy 424.384015 -351.180222)
			(xy 424.376261 -351.234175) (xy 424.360907 -351.286475) (xy 424.338266 -351.336058) (xy 424.308798 -351.381913)
			(xy 424.273103 -351.423107) (xy 424.231908 -351.458801) (xy 424.186053 -351.488269) (xy 424.13647 -351.510909)
			(xy 424.084169 -351.526262) (xy 424.030216 -351.534015) (xy 424.002962 -351.534476) (xy 423.97492 -351.534017)
			(xy 423.91944 -351.52581) (xy 423.865757 -351.509576) (xy 423.815026 -351.485667) (xy 423.768336 -351.454594)
			(xy 423.747184 -351.436178) (xy 423.735742 -351.426533) (xy 423.708699 -351.413753) (xy 423.679112 -351.409367)
			(xy 423.649525 -351.413753) (xy 423.622482 -351.426533) (xy 423.61104 -351.436178) (xy 423.589902 -351.454613)
			(xy 423.54322 -351.485703) (xy 423.492486 -351.509615) (xy 423.438794 -351.525832) (xy 423.383306 -351.534004)
			(xy 423.355262 -351.534476) (xy 423.327893 -351.533979) (xy 423.273715 -351.52617) (xy 423.221212 -351.510688)
			(xy 423.171464 -351.487853) (xy 423.125496 -351.458135) (xy 423.104564 -351.440496) (xy 423.093236 -351.43126)
			(xy 423.066679 -351.419084) (xy 423.037762 -351.414911) (xy 423.008845 -351.419084) (xy 422.982288 -351.43126)
			(xy 422.97096 -351.440496) (xy 422.950016 -351.45812) (xy 422.904046 -351.487834) (xy 422.854302 -351.510673)
			(xy 422.801804 -351.526168) (xy 422.74763 -351.534) (xy 422.720262 -351.534476) (xy 422.693008 -351.534057)
			(xy 422.639057 -351.526295) (xy 422.586759 -351.510933) (xy 422.537179 -351.488285) (xy 422.491327 -351.458812)
			(xy 422.450137 -351.423114) (xy 422.414446 -351.381917) (xy 422.384981 -351.336059) (xy 422.362342 -351.286476)
			(xy 422.34699 -351.234175) (xy 422.339238 -351.180222) (xy 422.338754 -351.152968) (xy 419.677342 -351.152968)
			(xy 419.676792 -351.180217) (xy 419.669041 -351.234161) (xy 419.653691 -351.286452) (xy 419.631057 -351.336027)
			(xy 419.601597 -351.381876) (xy 419.565912 -351.423065) (xy 419.524728 -351.458757) (xy 419.478885 -351.488225)
			(xy 419.429314 -351.510868) (xy 419.377025 -351.526227) (xy 419.323083 -351.533987) (xy 419.295834 -351.534476)
			(xy 419.268464 -351.533996) (xy 419.214285 -351.526182) (xy 419.161782 -351.510697) (xy 419.112035 -351.487858)
			(xy 419.066068 -351.458136) (xy 419.045136 -351.440496) (xy 419.033808 -351.43126) (xy 419.007251 -351.419084)
			(xy 418.978334 -351.414911) (xy 418.949417 -351.419084) (xy 418.92286 -351.43126) (xy 418.911532 -351.440496)
			(xy 418.890598 -351.458133) (xy 418.844626 -351.487845) (xy 418.794879 -351.510682) (xy 418.742379 -351.526173)
			(xy 418.688203 -351.534002) (xy 418.660834 -351.534476) (xy 418.632794 -351.533974) (xy 418.577316 -351.525777)
			(xy 418.523633 -351.509554) (xy 418.472901 -351.485654) (xy 418.42621 -351.45459) (xy 418.405056 -351.436178)
			(xy 418.393614 -351.426533) (xy 418.366571 -351.413753) (xy 418.336984 -351.409367) (xy 418.307397 -351.413753)
			(xy 418.280354 -351.426533) (xy 418.268912 -351.436178) (xy 418.247785 -351.454626) (xy 418.2011 -351.485714)
			(xy 418.150363 -351.509624) (xy 418.096669 -351.525837) (xy 418.041179 -351.534006) (xy 418.013134 -351.534476)
			(xy 417.985881 -351.534013) (xy 417.931928 -351.52626) (xy 417.879628 -351.510906) (xy 417.830046 -351.488266)
			(xy 417.784191 -351.458798) (xy 417.742997 -351.423104) (xy 417.707303 -351.38191) (xy 417.677835 -351.336056)
			(xy 417.655194 -351.286474) (xy 417.639841 -351.234174) (xy 417.632087 -351.180221) (xy 417.631626 -351.152968)
			(xy 414.70707 -351.152968) (xy 414.706615 -351.180222) (xy 414.698861 -351.234175) (xy 414.683507 -351.286475)
			(xy 414.660866 -351.336058) (xy 414.631398 -351.381913) (xy 414.595703 -351.423107) (xy 414.554508 -351.458801)
			(xy 414.508653 -351.488269) (xy 414.45907 -351.510909) (xy 414.406769 -351.526262) (xy 414.352816 -351.534015)
			(xy 414.325562 -351.534476) (xy 414.29752 -351.534017) (xy 414.24204 -351.52581) (xy 414.188357 -351.509576)
			(xy 414.137626 -351.485667) (xy 414.090936 -351.454594) (xy 414.069784 -351.436178) (xy 414.058342 -351.426533)
			(xy 414.031299 -351.413753) (xy 414.001712 -351.409367) (xy 413.972125 -351.413753) (xy 413.945082 -351.426533)
			(xy 413.93364 -351.436178) (xy 413.912502 -351.454613) (xy 413.86582 -351.485703) (xy 413.815086 -351.509615)
			(xy 413.761394 -351.525832) (xy 413.705906 -351.534004) (xy 413.677862 -351.534476) (xy 413.650493 -351.533979)
			(xy 413.596315 -351.52617) (xy 413.543812 -351.510688) (xy 413.494064 -351.487853) (xy 413.448096 -351.458135)
			(xy 413.427164 -351.440496) (xy 413.415836 -351.43126) (xy 413.389279 -351.419084) (xy 413.360362 -351.414911)
			(xy 413.331445 -351.419084) (xy 413.304888 -351.43126) (xy 413.29356 -351.440496) (xy 413.272616 -351.45812)
			(xy 413.226646 -351.487834) (xy 413.176902 -351.510673) (xy 413.124404 -351.526168) (xy 413.07023 -351.534)
			(xy 413.042862 -351.534476) (xy 413.015608 -351.534057) (xy 412.961657 -351.526295) (xy 412.909359 -351.510933)
			(xy 412.859779 -351.488285) (xy 412.813927 -351.458812) (xy 412.772737 -351.423114) (xy 412.737046 -351.381917)
			(xy 412.707581 -351.336059) (xy 412.684942 -351.286476) (xy 412.66959 -351.234175) (xy 412.661838 -351.180222)
			(xy 412.661354 -351.152968) (xy 395.18082 -351.152968) (xy 395.18082 -353.289616) (xy 395.180363 -353.31457)
			(xy 395.172568 -353.363865) (xy 395.157158 -353.411334) (xy 395.134511 -353.455808) (xy 395.105185 -353.496191)
			(xy 395.087856 -353.514152) (xy 385.416552 -363.185202) (xy 385.416552 -363.551216) (xy 385.431633 -363.574784)
			(xy 385.45547 -363.625404) (xy 385.471652 -363.678964) (xy 385.479832 -363.734314) (xy 385.480306 -363.76229)
			(xy 385.47982 -363.789541) (xy 385.472064 -363.843489) (xy 385.456709 -363.895784) (xy 385.434067 -363.945361)
			(xy 385.404601 -363.991211) (xy 385.36891 -364.032402) (xy 385.327719 -364.068093) (xy 385.281869 -364.097559)
			(xy 385.232292 -364.120201) (xy 385.179997 -364.135556) (xy 385.126049 -364.143312) (xy 385.071547 -364.143312)
			(xy 385.017599 -364.135556) (xy 384.965304 -364.120201) (xy 384.915727 -364.097559) (xy 384.869877 -364.068093)
			(xy 384.828686 -364.032402) (xy 384.792995 -363.991211) (xy 384.763529 -363.945361) (xy 384.740887 -363.895784)
			(xy 384.725532 -363.843489) (xy 384.717776 -363.789541) (xy 384.71729 -363.76229) (xy 384.717467 -363.744727)
			(xy 384.720646 -363.709746) (xy 384.72364 -363.69244) (xy 384.725857 -363.677471) (xy 384.72243 -363.64742)
			(xy 384.710359 -363.619688) (xy 384.690702 -363.596702) (xy 384.665179 -363.580475) (xy 384.636025 -363.572427)
			(xy 384.605791 -363.573262) (xy 384.591306 -363.577632) (xy 384.561761 -363.586979) (xy 384.500622 -363.597056)
			(xy 384.46964 -363.597698) (xy 384.468878 -363.597698) (xy 384.441628 -363.59721) (xy 384.387683 -363.589451)
			(xy 384.335392 -363.574094) (xy 384.285818 -363.551451) (xy 384.239971 -363.521984) (xy 384.198784 -363.486293)
			(xy 384.163096 -363.445103) (xy 384.133633 -363.399254) (xy 384.110995 -363.349678) (xy 384.095642 -363.297385)
			(xy 384.087888 -363.24344) (xy 384.08737 -363.21619) (xy 384.08737 -363.215682) (xy 384.087582 -363.198311)
			(xy 384.090766 -363.163714) (xy 384.09372 -363.146594) (xy 384.095315 -363.131381) (xy 384.090373 -363.101209)
			(xy 384.076713 -363.073856) (xy 384.055562 -363.051779) (xy 384.028819 -363.03696) (xy 384.013964 -363.03331)
			(xy 383.985815 -363.026788) (xy 383.93175 -363.006405) (xy 383.881373 -362.978109) (xy 383.835834 -362.942545)
			(xy 383.796174 -362.900527) (xy 383.763297 -362.853013) (xy 383.737953 -362.801088) (xy 383.720723 -362.745937)
			(xy 383.711998 -362.68882) (xy 383.71145 -362.65993) (xy 383.711704 -362.642912) (xy 383.711878 -362.628167)
			(xy 383.704749 -362.599567) (xy 383.689745 -362.574196) (xy 383.668117 -362.554169) (xy 383.641669 -362.541157)
			(xy 383.612606 -362.536244) (xy 383.597912 -362.537502) (xy 383.585212 -362.539148) (xy 383.559663 -362.540929)
			(xy 383.546858 -362.541058) (xy 383.519896 -362.54059) (xy 383.466509 -362.532992) (xy 383.414724 -362.517953)
			(xy 383.365572 -362.495772) (xy 383.320033 -362.466892) (xy 383.279013 -362.431888) (xy 383.24333 -362.391458)
			(xy 383.213696 -362.346406) (xy 383.190699 -362.29763) (xy 383.1748 -362.246103) (xy 383.166313 -362.19285)
			(xy 383.16535 -362.1659) (xy 383.163806 -362.151181) (xy 383.153364 -362.123502) (xy 383.135444 -362.099964)
			(xy 383.111541 -362.082533) (xy 383.083653 -362.072663) (xy 383.054107 -362.07118) (xy 383.03962 -362.074206)
			(xy 383.013939 -362.081073) (xy 382.961297 -362.088472) (xy 382.934718 -362.088938) (xy 382.907465 -362.088453)
			(xy 382.853514 -362.080699) (xy 382.801215 -362.065346) (xy 382.751634 -362.042706) (xy 382.705779 -362.013241)
			(xy 382.664584 -361.97755) (xy 382.628888 -361.936359) (xy 382.599417 -361.890508) (xy 382.576771 -361.84093)
			(xy 382.561411 -361.788633) (xy 382.55365 -361.734683) (xy 382.55321 -361.70743) (xy 382.55373 -361.679127)
			(xy 382.562105 -361.623145) (xy 382.578659 -361.569015) (xy 382.603031 -361.517925) (xy 382.634684 -361.470997)
			(xy 382.672925 -361.429261) (xy 382.716912 -361.393635) (xy 382.765681 -361.364899) (xy 382.818161 -361.343685)
			(xy 382.845564 -361.33659) (xy 382.859534 -361.333034) (xy 382.920748 -361.27182) (xy 382.938747 -361.254536)
			(xy 382.97913 -361.225228) (xy 383.023596 -361.202587) (xy 383.071053 -361.187172) (xy 383.120335 -361.179359)
			(xy 383.145284 -361.178856) (xy 384.65506 -361.178856) (xy 393.157964 -352.675952) (xy 393.157964 -335.687416)
			(xy 391.308844 -335.687416) (xy 389.414512 -332.781148) (xy 382.54178 -332.781148) (xy 379.67158 -329.910948)
			(xy 374.5484 -329.910948) (xy 371.3734 -326.735948) (xy 342.5698 -326.735948) (xy 335.84642 -333.459328)
			(xy 327.358248 -333.459328) (xy 325.641208 -335.176368) (xy 340.981284 -335.176368) (xy 340.981711 -335.148996)
			(xy 340.989535 -335.094815) (xy 341.005032 -335.04231) (xy 341.027883 -334.992564) (xy 341.057618 -334.9466)
			(xy 341.075264 -334.92567) (xy 341.084535 -334.914367) (xy 341.096713 -334.887801) (xy 341.100881 -334.858876)
			(xy 341.096699 -334.829952) (xy 341.084508 -334.803392) (xy 341.075264 -334.792066) (xy 341.057637 -334.771124)
			(xy 341.027924 -334.725154) (xy 341.005087 -334.675409) (xy 340.989593 -334.62291) (xy 340.98176 -334.568736)
			(xy 340.981284 -334.541368) (xy 340.98177 -334.514117) (xy 340.989526 -334.460169) (xy 341.004881 -334.407874)
			(xy 341.027523 -334.358297) (xy 341.056989 -334.312447) (xy 341.09268 -334.271256) (xy 341.133871 -334.235565)
			(xy 341.179721 -334.206099) (xy 341.229298 -334.183457) (xy 341.281593 -334.168102) (xy 341.335541 -334.160346)
			(xy 341.390043 -334.160346) (xy 341.443991 -334.168102) (xy 341.496286 -334.183457) (xy 341.545863 -334.206099)
			(xy 341.591713 -334.235565) (xy 341.632904 -334.271256) (xy 341.668595 -334.312447) (xy 341.698061 -334.358297)
			(xy 341.720703 -334.407874) (xy 341.736058 -334.460169) (xy 341.743814 -334.514117) (xy 341.7443 -334.541368)
			(xy 341.743815 -334.568738) (xy 341.736002 -334.622916) (xy 341.720517 -334.675419) (xy 341.69768 -334.725166)
			(xy 341.667959 -334.771134) (xy 341.65032 -334.792066) (xy 341.641113 -334.803416) (xy 341.628929 -334.829965)
			(xy 341.62475 -334.858876) (xy 341.628916 -334.887788) (xy 341.641086 -334.914343) (xy 341.65032 -334.92567)
			(xy 341.667962 -334.9466) (xy 341.697672 -334.992574) (xy 341.720508 -335.042322) (xy 341.735998 -335.094823)
			(xy 341.743826 -335.148999) (xy 341.7443 -335.176368) (xy 341.743814 -335.203619) (xy 341.736058 -335.257567)
			(xy 341.720703 -335.309862) (xy 341.698061 -335.359439) (xy 341.668595 -335.405289) (xy 341.632904 -335.44648)
			(xy 341.591713 -335.482171) (xy 341.545863 -335.511637) (xy 341.496286 -335.534279) (xy 341.443991 -335.549634)
			(xy 341.390043 -335.55739) (xy 341.335541 -335.55739) (xy 341.281593 -335.549634) (xy 341.229298 -335.534279)
			(xy 341.179721 -335.511637) (xy 341.133871 -335.482171) (xy 341.09268 -335.44648) (xy 341.056989 -335.405289)
			(xy 341.027523 -335.359439) (xy 341.004881 -335.309862) (xy 340.989526 -335.257567) (xy 340.98177 -335.203619)
			(xy 340.981284 -335.176368) (xy 325.641208 -335.176368) (xy 325.062076 -335.7555) (xy 345.217421 -335.7555)
			(xy 345.22159 -335.699879) (xy 345.234002 -335.6455) (xy 345.254381 -335.593578) (xy 345.28227 -335.545274)
			(xy 345.317048 -335.501666) (xy 345.357937 -335.463729) (xy 345.404023 -335.432311) (xy 345.454278 -335.408112)
			(xy 345.507578 -335.391674) (xy 345.562733 -335.383363) (xy 345.590622 -335.38287) (xy 345.618201 -335.383365)
			(xy 345.672759 -335.391471) (xy 345.725522 -335.407545) (xy 345.750642 -335.418938) (xy 345.763019 -335.424383)
			(xy 345.789613 -335.429217) (xy 345.816543 -335.426897) (xy 345.841919 -335.417588) (xy 345.86396 -335.401941)
			(xy 345.881119 -335.381056) (xy 345.88704 -335.3689) (xy 345.898378 -335.344653) (xy 345.927062 -335.299459)
			(xy 345.96192 -335.258838) (xy 346.002233 -335.223624) (xy 346.047173 -335.194544) (xy 346.095812 -335.172197)
			(xy 346.14715 -335.157042) (xy 346.200128 -335.149393) (xy 346.226892 -335.148936) (xy 346.253364 -335.149401)
			(xy 346.305773 -335.156901) (xy 346.356596 -335.171737) (xy 346.404809 -335.193611) (xy 346.449445 -335.222083)
			(xy 346.489606 -335.256582) (xy 346.524485 -335.296413) (xy 346.55338 -335.340776) (xy 346.564966 -335.364582)
			(xy 346.571667 -335.377804) (xy 346.5913 -335.399992) (xy 346.616473 -335.415614) (xy 346.64507 -335.423359)
			(xy 346.674687 -335.422574) (xy 346.688918 -335.41843) (xy 346.717263 -335.409661) (xy 346.775839 -335.400225)
			(xy 346.805504 -335.399634) (xy 346.833361 -335.40015) (xy 346.888456 -335.40844) (xy 346.915232 -335.416144)
			(xy 346.929563 -335.419986) (xy 346.959217 -335.420195) (xy 346.987682 -335.411879) (xy 347.01256 -335.395739)
			(xy 347.031755 -335.373135) (xy 347.038168 -335.359756) (xy 347.049483 -335.335288) (xy 347.078037 -335.289568)
			(xy 347.112884 -335.248442) (xy 347.153294 -335.212767) (xy 347.198425 -335.18329) (xy 347.247333 -335.160625)
			(xy 347.298997 -335.145247) (xy 347.352338 -335.137476) (xy 347.37929 -335.136998) (xy 347.407178 -335.13746)
			(xy 347.462333 -335.145772) (xy 347.515632 -335.162211) (xy 347.54503 -335.176368) (xy 349.141796 -335.176368)
			(xy 349.142244 -335.148997) (xy 349.150067 -335.094817) (xy 349.16556 -335.042314) (xy 349.188405 -334.992568)
			(xy 349.218133 -334.946601) (xy 349.235776 -334.92567) (xy 349.245046 -334.914367) (xy 349.257222 -334.887801)
			(xy 349.26139 -334.858876) (xy 349.257208 -334.829953) (xy 349.245019 -334.803393) (xy 349.235776 -334.792066)
			(xy 349.218151 -334.771123) (xy 349.188438 -334.725153) (xy 349.165599 -334.675408) (xy 349.150105 -334.62291)
			(xy 349.142273 -334.568736) (xy 349.141796 -334.541368) (xy 349.142282 -334.514117) (xy 349.150038 -334.460169)
			(xy 349.165393 -334.407874) (xy 349.188035 -334.358297) (xy 349.217501 -334.312447) (xy 349.253192 -334.271256)
			(xy 349.294383 -334.235565) (xy 349.340233 -334.206099) (xy 349.38981 -334.183457) (xy 349.442105 -334.168102)
			(xy 349.496053 -334.160346) (xy 349.550555 -334.160346) (xy 349.604503 -334.168102) (xy 349.656798 -334.183457)
			(xy 349.706375 -334.206099) (xy 349.752225 -334.235565) (xy 349.793416 -334.271256) (xy 349.829107 -334.312447)
			(xy 349.858573 -334.358297) (xy 349.881215 -334.407874) (xy 349.89657 -334.460169) (xy 349.904326 -334.514117)
			(xy 349.904812 -334.541368) (xy 349.904324 -334.568737) (xy 349.896511 -334.622915) (xy 349.881027 -334.675418)
			(xy 349.85819 -334.725165) (xy 349.828471 -334.771133) (xy 349.810832 -334.792066) (xy 349.801624 -334.803415)
			(xy 349.789439 -334.829965) (xy 349.785259 -334.858876) (xy 349.789425 -334.887789) (xy 349.801598 -334.914344)
			(xy 349.810832 -334.92567) (xy 349.828475 -334.946598) (xy 349.858186 -334.992573) (xy 349.88102 -335.042321)
			(xy 349.89651 -335.094823) (xy 349.904338 -335.148999) (xy 349.904812 -335.176368) (xy 357.302308 -335.176368)
			(xy 357.302753 -335.148997) (xy 357.310576 -335.094817) (xy 357.32607 -335.042314) (xy 357.348916 -334.992567)
			(xy 357.378645 -334.946601) (xy 357.396288 -334.92567) (xy 357.405557 -334.914366) (xy 357.417732 -334.8878)
			(xy 357.421899 -334.858876) (xy 357.417718 -334.829953) (xy 357.40553 -334.803393) (xy 357.396288 -334.792066)
			(xy 357.378665 -334.771121) (xy 357.348951 -334.725152) (xy 357.326112 -334.675408) (xy 357.310617 -334.62291)
			(xy 357.302785 -334.568736) (xy 357.302308 -334.541368) (xy 357.302794 -334.514117) (xy 357.31055 -334.460169)
			(xy 357.325905 -334.407874) (xy 357.348547 -334.358297) (xy 357.378013 -334.312447) (xy 357.413704 -334.271256)
			(xy 357.454895 -334.235565) (xy 357.500745 -334.206099) (xy 357.550322 -334.183457) (xy 357.602617 -334.168102)
			(xy 357.656565 -334.160346) (xy 357.711067 -334.160346) (xy 357.765015 -334.168102) (xy 357.81731 -334.183457)
			(xy 357.866887 -334.206099) (xy 357.912737 -334.235565) (xy 357.953928 -334.271256) (xy 357.989619 -334.312447)
			(xy 358.019085 -334.358297) (xy 358.041727 -334.407874) (xy 358.057082 -334.460169) (xy 358.064838 -334.514117)
			(xy 358.065324 -334.541368) (xy 358.064858 -334.568738) (xy 358.057043 -334.622918) (xy 358.041555 -334.675422)
			(xy 358.018713 -334.725169) (xy 357.988986 -334.771135) (xy 357.971344 -334.792066) (xy 357.962142 -334.803418)
			(xy 357.949968 -334.829968) (xy 357.945792 -334.858876) (xy 357.949954 -334.887786) (xy 357.962116 -334.914341)
			(xy 357.971344 -334.92567) (xy 357.98899 -334.946597) (xy 358.018699 -334.992572) (xy 358.041533 -335.042321)
			(xy 358.057023 -335.094822) (xy 358.064851 -335.148999) (xy 358.065324 -335.176368) (xy 365.46282 -335.176368)
			(xy 365.463262 -335.148997) (xy 365.471085 -335.094817) (xy 365.48658 -335.042313) (xy 365.509427 -334.992567)
			(xy 365.539156 -334.946601) (xy 365.5568 -334.92567) (xy 365.566068 -334.914366) (xy 365.578241 -334.8878)
			(xy 365.582408 -334.858876) (xy 365.578228 -334.829954) (xy 365.566041 -334.803393) (xy 365.5568 -334.792066)
			(xy 365.539178 -334.77112) (xy 365.509464 -334.725151) (xy 365.486625 -334.675407) (xy 365.471129 -334.622909)
			(xy 365.463297 -334.568736) (xy 365.46282 -334.541368) (xy 365.463306 -334.514117) (xy 365.471062 -334.460169)
			(xy 365.486417 -334.407874) (xy 365.509059 -334.358297) (xy 365.538525 -334.312447) (xy 365.574216 -334.271256)
			(xy 365.615407 -334.235565) (xy 365.661257 -334.206099) (xy 365.710834 -334.183457) (xy 365.763129 -334.168102)
			(xy 365.817077 -334.160346) (xy 365.871579 -334.160346) (xy 365.925527 -334.168102) (xy 365.977822 -334.183457)
			(xy 366.027399 -334.206099) (xy 366.073249 -334.235565) (xy 366.11444 -334.271256) (xy 366.150131 -334.312447)
			(xy 366.179597 -334.358297) (xy 366.202239 -334.407874) (xy 366.217594 -334.460169) (xy 366.22535 -334.514117)
			(xy 366.225836 -334.541368) (xy 366.225367 -334.568738) (xy 366.217552 -334.622918) (xy 366.202065 -334.675422)
			(xy 366.179223 -334.725169) (xy 366.149498 -334.771135) (xy 366.131856 -334.792066) (xy 366.122653 -334.803418)
			(xy 366.110478 -334.829967) (xy 366.106301 -334.858876) (xy 366.110464 -334.887786) (xy 366.122627 -334.914341)
			(xy 366.131856 -334.92567) (xy 366.149488 -334.946608) (xy 366.179202 -334.992579) (xy 366.20204 -335.042324)
			(xy 366.217533 -335.094824) (xy 366.225362 -335.148999) (xy 366.225836 -335.176368) (xy 366.22535 -335.203619)
			(xy 366.217594 -335.257567) (xy 366.202239 -335.309862) (xy 366.179597 -335.359439) (xy 366.150131 -335.405289)
			(xy 366.11444 -335.44648) (xy 366.073249 -335.482171) (xy 366.027399 -335.511637) (xy 365.977822 -335.534279)
			(xy 365.925527 -335.549634) (xy 365.871579 -335.55739) (xy 365.817077 -335.55739) (xy 365.763129 -335.549634)
			(xy 365.710834 -335.534279) (xy 365.661257 -335.511637) (xy 365.615407 -335.482171) (xy 365.574216 -335.44648)
			(xy 365.538525 -335.405289) (xy 365.509059 -335.359439) (xy 365.486417 -335.309862) (xy 365.471062 -335.257567)
			(xy 365.463306 -335.203619) (xy 365.46282 -335.176368) (xy 358.065324 -335.176368) (xy 358.064838 -335.203619)
			(xy 358.057082 -335.257567) (xy 358.041727 -335.309862) (xy 358.019085 -335.359439) (xy 357.989619 -335.405289)
			(xy 357.953928 -335.44648) (xy 357.912737 -335.482171) (xy 357.866887 -335.511637) (xy 357.81731 -335.534279)
			(xy 357.765015 -335.549634) (xy 357.711067 -335.55739) (xy 357.656565 -335.55739) (xy 357.602617 -335.549634)
			(xy 357.550322 -335.534279) (xy 357.500745 -335.511637) (xy 357.454895 -335.482171) (xy 357.413704 -335.44648)
			(xy 357.378013 -335.405289) (xy 357.348547 -335.359439) (xy 357.325905 -335.309862) (xy 357.31055 -335.257567)
			(xy 357.302794 -335.203619) (xy 357.302308 -335.176368) (xy 349.904812 -335.176368) (xy 349.904326 -335.203619)
			(xy 349.89657 -335.257567) (xy 349.881215 -335.309862) (xy 349.858573 -335.359439) (xy 349.829107 -335.405289)
			(xy 349.793416 -335.44648) (xy 349.752225 -335.482171) (xy 349.706375 -335.511637) (xy 349.656798 -335.534279)
			(xy 349.604503 -335.549634) (xy 349.550555 -335.55739) (xy 349.496053 -335.55739) (xy 349.442105 -335.549634)
			(xy 349.38981 -335.534279) (xy 349.340233 -335.511637) (xy 349.294383 -335.482171) (xy 349.253192 -335.44648)
			(xy 349.217501 -335.405289) (xy 349.188035 -335.359439) (xy 349.165393 -335.309862) (xy 349.150038 -335.257567)
			(xy 349.142282 -335.203619) (xy 349.141796 -335.176368) (xy 347.54503 -335.176368) (xy 347.565885 -335.186411)
			(xy 347.611971 -335.217831) (xy 347.652859 -335.255768) (xy 347.687636 -335.299376) (xy 347.715525 -335.34768)
			(xy 347.735902 -335.399601) (xy 347.748314 -335.453979) (xy 347.752483 -335.5096) (xy 347.748314 -335.565221)
			(xy 347.735902 -335.619599) (xy 347.715525 -335.67152) (xy 347.687636 -335.719824) (xy 347.652859 -335.763432)
			(xy 347.611971 -335.801369) (xy 347.565885 -335.832789) (xy 347.515632 -335.856989) (xy 347.462333 -335.873428)
			(xy 347.407178 -335.88174) (xy 347.37929 -335.882234) (xy 347.351433 -335.88172) (xy 347.296338 -335.873428)
			(xy 347.269562 -335.865724) (xy 347.255229 -335.861894) (xy 347.225578 -335.861687) (xy 347.197116 -335.870002)
			(xy 347.172239 -335.886138) (xy 347.153041 -335.908736) (xy 347.146626 -335.922112) (xy 347.135349 -335.946598)
			(xy 347.106786 -335.992315) (xy 347.071933 -336.033439) (xy 347.031516 -336.069111) (xy 346.986381 -336.098585)
			(xy 346.937469 -336.121247) (xy 346.885801 -336.136624) (xy 346.832457 -336.144393) (xy 346.805504 -336.14487)
			(xy 346.779032 -336.144405) (xy 346.726623 -336.136904) (xy 346.675801 -336.122068) (xy 346.627587 -336.100194)
			(xy 346.582951 -336.071722) (xy 346.54279 -336.037224) (xy 346.507912 -335.997393) (xy 346.479016 -335.95303)
			(xy 346.46743 -335.929224) (xy 346.46073 -335.916001) (xy 346.441097 -335.893812) (xy 346.415924 -335.878189)
			(xy 346.387326 -335.870445) (xy 346.357709 -335.871231) (xy 346.343478 -335.875376) (xy 346.315133 -335.884146)
			(xy 346.256557 -335.893581) (xy 346.226892 -335.894172) (xy 346.199313 -335.893677) (xy 346.144755 -335.885572)
			(xy 346.091992 -335.869498) (xy 346.066872 -335.858104) (xy 346.054496 -335.852654) (xy 346.027901 -335.847814)
			(xy 346.000968 -335.850131) (xy 345.97559 -335.859442) (xy 345.953548 -335.875092) (xy 345.936392 -335.895983)
			(xy 345.930474 -335.908142) (xy 345.919098 -335.93237) (xy 345.890422 -335.977566) (xy 345.855571 -336.01819)
			(xy 345.815263 -336.053406) (xy 345.770329 -336.082489) (xy 345.721693 -336.104839) (xy 345.67036 -336.119996)
			(xy 345.617385 -336.127648) (xy 345.590622 -336.128106) (xy 345.562733 -336.127637) (xy 345.507578 -336.119326)
			(xy 345.454278 -336.102888) (xy 345.404023 -336.078689) (xy 345.357937 -336.047271) (xy 345.317048 -336.009334)
			(xy 345.28227 -335.965726) (xy 345.254381 -335.917422) (xy 345.234002 -335.8655) (xy 345.22159 -335.811121)
			(xy 345.217421 -335.7555) (xy 325.062076 -335.7555) (xy 324.186296 -336.63128) (xy 341.85682 -336.63128)
			(xy 341.860891 -336.575658) (xy 341.873017 -336.521221) (xy 341.89294 -336.46913) (xy 341.920236 -336.420495)
			(xy 341.954322 -336.376352) (xy 341.994471 -336.337643) (xy 342.039829 -336.305192) (xy 342.089429 -336.279691)
			(xy 342.142213 -336.261684) (xy 342.197056 -336.251554) (xy 342.25279 -336.249517) (xy 342.308227 -336.255617)
			(xy 342.362184 -336.269723) (xy 342.413513 -336.291535) (xy 342.461119 -336.320589) (xy 342.503987 -336.356264)
			(xy 342.541204 -336.397801) (xy 342.571977 -336.444314) (xy 342.595649 -336.494811) (xy 342.611717 -336.548218)
			(xy 342.619837 -336.603394) (xy 342.620346 -336.63128) (xy 342.619837 -336.659166) (xy 342.611717 -336.714342)
			(xy 342.595649 -336.767749) (xy 342.571977 -336.818246) (xy 342.541204 -336.864759) (xy 342.503987 -336.906296)
			(xy 342.461119 -336.941971) (xy 342.413513 -336.971025) (xy 342.362184 -336.992837) (xy 342.308227 -337.006943)
			(xy 342.25279 -337.013043) (xy 342.197056 -337.011006) (xy 342.142213 -337.000876) (xy 342.089429 -336.982869)
			(xy 342.039829 -336.957368) (xy 341.994471 -336.924917) (xy 341.954322 -336.886208) (xy 341.920236 -336.842065)
			(xy 341.89294 -336.79343) (xy 341.873017 -336.741339) (xy 341.860891 -336.686902) (xy 341.85682 -336.63128)
			(xy 324.186296 -336.63128) (xy 323.464682 -337.352894) (xy 341.12911 -337.352894) (xy 341.133181 -337.297272)
			(xy 341.145307 -337.242835) (xy 341.16523 -337.190744) (xy 341.192526 -337.142109) (xy 341.226612 -337.097966)
			(xy 341.266761 -337.059257) (xy 341.312119 -337.026806) (xy 341.361719 -337.001305) (xy 341.414503 -336.983298)
			(xy 341.469346 -336.973168) (xy 341.52508 -336.971131) (xy 341.580517 -336.977231) (xy 341.634474 -336.991337)
			(xy 341.685803 -337.013149) (xy 341.733409 -337.042203) (xy 341.776277 -337.077878) (xy 341.813494 -337.119415)
			(xy 341.844267 -337.165928) (xy 341.867939 -337.216425) (xy 341.884007 -337.269832) (xy 341.892127 -337.325008)
			(xy 341.892636 -337.352894) (xy 341.892127 -337.38078) (xy 341.884007 -337.435956) (xy 341.867939 -337.489363)
			(xy 341.844267 -337.53986) (xy 341.813494 -337.586373) (xy 341.776277 -337.62791) (xy 341.733409 -337.663585)
			(xy 341.685803 -337.692639) (xy 341.634474 -337.714451) (xy 341.580517 -337.728557) (xy 341.52508 -337.734657)
			(xy 341.469346 -337.73262) (xy 341.414503 -337.72249) (xy 341.361719 -337.704483) (xy 341.312119 -337.678982)
			(xy 341.266761 -337.646531) (xy 341.226612 -337.607822) (xy 341.192526 -337.563679) (xy 341.16523 -337.515044)
			(xy 341.145307 -337.462953) (xy 341.133181 -337.408516) (xy 341.12911 -337.352894) (xy 323.464682 -337.352894)
			(xy 322.649088 -338.168488) (xy 322.649088 -338.586572) (xy 332.820772 -338.586572) (xy 332.821204 -338.5592)
			(xy 332.829027 -338.505019) (xy 332.844523 -338.452515) (xy 332.867373 -338.402769) (xy 332.897106 -338.356804)
			(xy 332.914752 -338.335874) (xy 332.924012 -338.324565) (xy 332.93618 -338.298) (xy 332.940345 -338.269079)
			(xy 332.936168 -338.240159) (xy 332.923989 -338.213599) (xy 332.914752 -338.20227) (xy 332.89714 -338.181316)
			(xy 332.867423 -338.13535) (xy 332.844581 -338.085608) (xy 332.829083 -338.033112) (xy 332.821249 -337.97894)
			(xy 332.820772 -337.951572) (xy 332.821258 -337.924321) (xy 332.829014 -337.870373) (xy 332.844369 -337.818078)
			(xy 332.867011 -337.768501) (xy 332.896477 -337.722651) (xy 332.932168 -337.68146) (xy 332.973359 -337.645769)
			(xy 333.019209 -337.616303) (xy 333.068786 -337.593661) (xy 333.121081 -337.578306) (xy 333.175029 -337.57055)
			(xy 333.229531 -337.57055) (xy 333.283479 -337.578306) (xy 333.335774 -337.593661) (xy 333.385351 -337.616303)
			(xy 333.431201 -337.645769) (xy 333.472392 -337.68146) (xy 333.508083 -337.722651) (xy 333.537549 -337.768501)
			(xy 333.560191 -337.818078) (xy 333.575546 -337.870373) (xy 333.583302 -337.924321) (xy 333.583788 -337.951572)
			(xy 333.583308 -337.978942) (xy 333.575494 -338.03312) (xy 333.560009 -338.085623) (xy 333.53717 -338.135371)
			(xy 333.507448 -338.181338) (xy 333.489808 -338.20227) (xy 333.480597 -338.213617) (xy 333.468416 -338.240168)
			(xy 333.464238 -338.269079) (xy 333.468404 -338.297992) (xy 333.480574 -338.324547) (xy 333.489808 -338.335874)
			(xy 333.50745 -338.356804) (xy 333.537161 -338.402778) (xy 333.559996 -338.452526) (xy 333.575487 -338.505027)
			(xy 333.583314 -338.559203) (xy 333.583788 -338.586572) (xy 333.583302 -338.613823) (xy 333.575546 -338.667771)
			(xy 333.560191 -338.720066) (xy 333.537549 -338.769643) (xy 333.508083 -338.815493) (xy 333.472392 -338.856684)
			(xy 333.431201 -338.892375) (xy 333.385351 -338.921841) (xy 333.335774 -338.944483) (xy 333.283479 -338.959838)
			(xy 333.229531 -338.967594) (xy 333.175029 -338.967594) (xy 333.121081 -338.959838) (xy 333.068786 -338.944483)
			(xy 333.019209 -338.921841) (xy 332.973359 -338.892375) (xy 332.932168 -338.856684) (xy 332.896477 -338.815493)
			(xy 332.867011 -338.769643) (xy 332.844369 -338.720066) (xy 332.829014 -338.667771) (xy 332.821258 -338.613823)
			(xy 332.820772 -338.586572) (xy 322.649088 -338.586572) (xy 322.649088 -338.9892) (xy 337.069421 -338.9892)
			(xy 337.073589 -338.933585) (xy 337.085998 -338.879212) (xy 337.106372 -338.827295) (xy 337.134256 -338.778995)
			(xy 337.169027 -338.73539) (xy 337.209907 -338.697453) (xy 337.255985 -338.666033) (xy 337.306231 -338.64183)
			(xy 337.359523 -338.625386) (xy 337.41467 -338.617068) (xy 337.442556 -338.616544) (xy 337.469888 -338.617013)
			(xy 337.523968 -338.624982) (xy 337.576303 -338.64077) (xy 337.625767 -338.664039) (xy 337.6713 -338.694287)
			(xy 337.711922 -338.730866) (xy 337.746761 -338.772989) (xy 337.761326 -338.796122) (xy 337.769241 -338.808351)
			(xy 337.790716 -338.82802) (xy 337.816871 -338.840823) (xy 337.845578 -338.845717) (xy 337.874498 -338.842304)
			(xy 337.888072 -338.837016) (xy 337.911288 -338.827544) (xy 337.959618 -338.814186) (xy 338.009305 -338.807451)
			(xy 338.034376 -338.807044) (xy 338.059446 -338.807454) (xy 338.109129 -338.814209) (xy 338.157463 -338.827547)
			(xy 338.18068 -338.837016) (xy 338.194253 -338.842275) (xy 338.223156 -338.845636) (xy 338.251835 -338.840723)
			(xy 338.27797 -338.827931) (xy 338.299445 -338.808297) (xy 338.307426 -338.796122) (xy 338.321995 -338.772991)
			(xy 338.356838 -338.73087) (xy 338.397461 -338.694291) (xy 338.442992 -338.66404) (xy 338.492454 -338.640764)
			(xy 338.544785 -338.624964) (xy 338.598864 -338.616978) (xy 338.653528 -338.616978) (xy 338.707607 -338.624964)
			(xy 338.759938 -338.640764) (xy 338.8094 -338.66404) (xy 338.854931 -338.694291) (xy 338.895554 -338.73087)
			(xy 338.930397 -338.772991) (xy 338.944966 -338.796122) (xy 338.952843 -338.808379) (xy 338.974328 -338.828047)
			(xy 339.000494 -338.840846) (xy 339.029209 -338.845733) (xy 339.058136 -338.84231) (xy 339.071712 -338.837016)
			(xy 339.094924 -338.827531) (xy 339.143256 -338.814178) (xy 339.192945 -338.807448) (xy 339.218016 -338.807044)
			(xy 339.245655 -338.807541) (xy 339.300322 -338.815736) (xy 339.35318 -338.831914) (xy 339.40307 -338.85572)
			(xy 339.448896 -338.886633) (xy 339.489656 -338.923974) (xy 339.524454 -338.966925) (xy 339.552528 -339.014544)
			(xy 339.573262 -339.065786) (xy 339.58022 -339.09254) (xy 339.583825 -339.105648) (xy 339.596965 -339.129436)
			(xy 339.615914 -339.148918) (xy 339.639329 -339.162712) (xy 339.665554 -339.169842) (xy 339.69273 -339.169804)
			(xy 339.718934 -339.1626) (xy 339.730842 -339.15604) (xy 339.752985 -339.143402) (xy 339.799938 -339.123527)
			(xy 339.849122 -339.110092) (xy 339.899659 -339.103338) (xy 339.925152 -339.102954) (xy 339.93201 -339.102954)
			(xy 339.947094 -339.102679) (xy 339.976082 -339.094373) (xy 340.001392 -339.07798) (xy 340.020827 -339.054924)
			(xy 340.032701 -339.027205) (xy 340.03488 -339.012276) (xy 340.038284 -338.984522) (xy 340.052283 -338.930385)
			(xy 340.07403 -338.878869) (xy 340.103059 -338.831077) (xy 340.13875 -338.788031) (xy 340.180338 -338.750652)
			(xy 340.226935 -338.71974) (xy 340.277543 -338.695956) (xy 340.331079 -338.67981) (xy 340.386397 -338.671646)
			(xy 340.414356 -338.671154) (xy 340.441606 -338.671696) (xy 340.495552 -338.679446) (xy 340.547846 -338.694795)
			(xy 340.597424 -338.717429) (xy 340.643275 -338.746889) (xy 340.684467 -338.782575) (xy 340.720162 -338.823759)
			(xy 340.749631 -338.869604) (xy 340.772277 -338.919177) (xy 340.787636 -338.971468) (xy 340.795398 -339.025412)
			(xy 340.795864 -339.052662) (xy 340.795316 -339.082032) (xy 340.786317 -339.14008) (xy 340.768526 -339.196061)
			(xy 340.742363 -339.248654) (xy 340.708447 -339.296614) (xy 340.66758 -339.338808) (xy 340.64448 -339.356954)
			(xy 340.633399 -339.366027) (xy 340.616251 -339.388944) (xy 340.606145 -339.415722) (xy 340.603874 -339.444253)
			(xy 340.609619 -339.472293) (xy 340.622926 -339.497633) (xy 340.642749 -339.518279) (xy 340.654894 -339.525864)
			(xy 340.679326 -339.540649) (xy 340.723967 -339.576255) (xy 340.762805 -339.618116) (xy 340.794972 -339.665295)
			(xy 340.819752 -339.716741) (xy 340.836589 -339.771304) (xy 340.845109 -339.827767) (xy 340.845648 -339.856318)
			(xy 340.845255 -339.882212) (xy 340.838252 -339.933526) (xy 340.824365 -339.983418) (xy 340.803849 -340.03097)
			(xy 340.777082 -340.075305) (xy 340.744557 -340.115607) (xy 340.726014 -340.133686) (xy 340.715911 -340.143825)
			(xy 340.701296 -340.168419) (xy 340.694088 -340.196105) (xy 340.694855 -340.224704) (xy 340.703535 -340.251965)
			(xy 340.719447 -340.275741) (xy 340.730078 -340.285324) (xy 340.750901 -340.30352) (xy 340.787573 -340.344907)
			(xy 340.817878 -340.39116) (xy 340.841179 -340.441307) (xy 340.856987 -340.494296) (xy 340.864971 -340.549014)
			(xy 340.86546 -340.576662) (xy 340.865009 -340.603916) (xy 340.857256 -340.65787) (xy 340.841903 -340.710171)
			(xy 340.819261 -340.759754) (xy 340.789792 -340.80561) (xy 340.754097 -340.846804) (xy 340.712902 -340.882498)
			(xy 340.667045 -340.911966) (xy 340.617462 -340.934606) (xy 340.56516 -340.949958) (xy 340.511206 -340.95771)
			(xy 340.483952 -340.95817) (xy 340.454875 -340.957639) (xy 340.397395 -340.948821) (xy 340.341918 -340.93138)
			(xy 340.289732 -340.905722) (xy 340.242044 -340.872441) (xy 340.19996 -340.832307) (xy 340.164454 -340.786251)
			(xy 340.136351 -340.735339) (xy 340.125812 -340.708234) (xy 340.120356 -340.694656) (xy 340.102875 -340.671198)
			(xy 340.07946 -340.653661) (xy 340.052032 -340.643485) (xy 340.022844 -340.641505) (xy 340.008464 -340.644226)
			(xy 339.987905 -340.648519) (xy 339.946153 -340.653097) (xy 339.925152 -340.65337) (xy 339.910936 -340.653208)
			(xy 339.882586 -340.65105) (xy 339.86851 -340.649052) (xy 339.853186 -340.647282) (xy 339.822729 -340.652112)
			(xy 339.795094 -340.665797) (xy 339.772792 -340.687094) (xy 339.757848 -340.714069) (xy 339.75421 -340.729062)
			(xy 339.747713 -340.757293) (xy 339.727473 -340.811567) (xy 339.699262 -340.862158) (xy 339.663727 -340.907903)
			(xy 339.621687 -340.947751) (xy 339.574106 -340.980787) (xy 339.522078 -341.006251) (xy 339.466799 -341.023558)
			(xy 339.409539 -341.03231) (xy 339.380576 -341.032846) (xy 339.353326 -341.032345) (xy 339.299381 -341.024586)
			(xy 339.247089 -341.00923) (xy 339.197514 -340.986588) (xy 339.151665 -340.957123) (xy 339.110476 -340.921434)
			(xy 339.074785 -340.880246) (xy 339.045318 -340.834399) (xy 339.022675 -340.784825) (xy 339.007317 -340.732533)
			(xy 338.999556 -340.678588) (xy 338.999068 -340.651338) (xy 338.999571 -340.623765) (xy 339.007517 -340.569194)
			(xy 339.023236 -340.516336) (xy 339.046399 -340.46629) (xy 339.076524 -340.420099) (xy 339.112984 -340.378726)
			(xy 339.133688 -340.360508) (xy 339.144548 -340.350571) (xy 339.160623 -340.325932) (xy 339.169012 -340.297734)
			(xy 339.169019 -340.268315) (xy 339.160644 -340.240113) (xy 339.14458 -340.215466) (xy 339.133688 -340.205568)
			(xy 339.112956 -340.18738) (xy 339.076488 -340.146006) (xy 339.046358 -340.099811) (xy 339.023196 -340.049759)
			(xy 339.007484 -339.996892) (xy 338.99955 -339.942314) (xy 338.999068 -339.914738) (xy 338.999512 -339.888237)
			(xy 339.006861 -339.835745) (xy 339.021408 -339.784778) (xy 339.042873 -339.736316) (xy 339.070842 -339.691293)
			(xy 339.08746 -339.670644) (xy 339.096904 -339.6585) (xy 339.10869 -339.630099) (xy 339.111512 -339.599479)
			(xy 339.105115 -339.569402) (xy 339.090076 -339.542581) (xy 339.067752 -339.521435) (xy 339.054186 -339.51418)
			(xy 339.0305 -339.502071) (xy 338.986517 -339.472151) (xy 338.947235 -339.436283) (xy 338.91345 -339.395194)
			(xy 338.899246 -339.372702) (xy 338.891351 -339.360457) (xy 338.869873 -339.340786) (xy 338.843711 -339.327983)
			(xy 338.814999 -339.323094) (xy 338.786075 -339.326515) (xy 338.7725 -339.331808) (xy 338.749287 -339.34129)
			(xy 338.700956 -339.354644) (xy 338.651267 -339.361375) (xy 338.626196 -339.36178) (xy 338.601127 -339.361345)
			(xy 338.551444 -339.3546) (xy 338.50311 -339.341272) (xy 338.479892 -339.331808) (xy 338.466296 -339.326615)
			(xy 338.437405 -339.323236) (xy 338.408732 -339.328134) (xy 338.3826 -339.340911) (xy 338.361126 -339.360532)
			(xy 338.353146 -339.372702) (xy 338.338577 -339.395833) (xy 338.303734 -339.437954) (xy 338.263111 -339.474533)
			(xy 338.21758 -339.504784) (xy 338.168118 -339.52806) (xy 338.115787 -339.54386) (xy 338.061708 -339.551846)
			(xy 338.007044 -339.551846) (xy 337.952965 -339.54386) (xy 337.900634 -339.52806) (xy 337.851172 -339.504784)
			(xy 337.805641 -339.474533) (xy 337.765018 -339.437954) (xy 337.730175 -339.395833) (xy 337.715606 -339.372702)
			(xy 337.707654 -339.360498) (xy 337.686191 -339.340827) (xy 337.660045 -339.328019) (xy 337.631347 -339.323119)
			(xy 337.602432 -339.326524) (xy 337.58886 -339.331808) (xy 337.565652 -339.341303) (xy 337.517318 -339.354652)
			(xy 337.467628 -339.361378) (xy 337.442556 -339.36178) (xy 337.41467 -339.361332) (xy 337.359523 -339.353014)
			(xy 337.306231 -339.33657) (xy 337.255985 -339.312367) (xy 337.209907 -339.280947) (xy 337.169027 -339.24301)
			(xy 337.134256 -339.199405) (xy 337.106372 -339.151105) (xy 337.085998 -339.099188) (xy 337.073589 -339.044815)
			(xy 337.069421 -338.9892) (xy 322.649088 -338.9892) (xy 322.649088 -340.054946) (xy 333.611726 -340.054946)
			(xy 333.615797 -339.999324) (xy 333.627923 -339.944887) (xy 333.647846 -339.892796) (xy 333.675142 -339.844161)
			(xy 333.709228 -339.800018) (xy 333.749377 -339.761309) (xy 333.794735 -339.728858) (xy 333.844335 -339.703357)
			(xy 333.897119 -339.68535) (xy 333.951962 -339.67522) (xy 334.007696 -339.673183) (xy 334.063133 -339.679283)
			(xy 334.11709 -339.693389) (xy 334.168419 -339.715201) (xy 334.216025 -339.744255) (xy 334.258893 -339.77993)
			(xy 334.29611 -339.821467) (xy 334.326883 -339.86798) (xy 334.350555 -339.918477) (xy 334.366623 -339.971884)
			(xy 334.374743 -340.02706) (xy 334.375252 -340.054946) (xy 334.374743 -340.082832) (xy 334.366623 -340.138008)
			(xy 334.350555 -340.191415) (xy 334.326883 -340.241912) (xy 334.29611 -340.288425) (xy 334.258893 -340.329962)
			(xy 334.216025 -340.365637) (xy 334.168419 -340.394691) (xy 334.11709 -340.416503) (xy 334.063133 -340.430609)
			(xy 334.007696 -340.436709) (xy 333.951962 -340.434672) (xy 333.897119 -340.424542) (xy 333.844335 -340.406535)
			(xy 333.794735 -340.381034) (xy 333.749377 -340.348583) (xy 333.709228 -340.309874) (xy 333.675142 -340.265731)
			(xy 333.647846 -340.217096) (xy 333.627923 -340.165005) (xy 333.615797 -340.110568) (xy 333.611726 -340.054946)
			(xy 322.649088 -340.054946) (xy 322.649088 -341.013288) (xy 333.031082 -341.013288) (xy 333.035153 -340.957666)
			(xy 333.047279 -340.903229) (xy 333.067202 -340.851138) (xy 333.094498 -340.802503) (xy 333.128584 -340.75836)
			(xy 333.168733 -340.719651) (xy 333.214091 -340.6872) (xy 333.263691 -340.661699) (xy 333.316475 -340.643692)
			(xy 333.371318 -340.633562) (xy 333.427052 -340.631525) (xy 333.482489 -340.637625) (xy 333.536446 -340.651731)
			(xy 333.587775 -340.673543) (xy 333.635381 -340.702597) (xy 333.678249 -340.738272) (xy 333.715466 -340.779809)
			(xy 333.746239 -340.826322) (xy 333.769911 -340.876819) (xy 333.785979 -340.930226) (xy 333.794099 -340.985402)
			(xy 333.794608 -341.013288) (xy 333.794099 -341.041174) (xy 333.785979 -341.09635) (xy 333.769911 -341.149757)
			(xy 333.746239 -341.200254) (xy 333.715466 -341.246767) (xy 333.678249 -341.288304) (xy 333.635381 -341.323979)
			(xy 333.587775 -341.353033) (xy 333.536446 -341.374845) (xy 333.482489 -341.388951) (xy 333.427052 -341.395051)
			(xy 333.371318 -341.393014) (xy 333.316475 -341.382884) (xy 333.263691 -341.364877) (xy 333.214091 -341.339376)
			(xy 333.168733 -341.306925) (xy 333.128584 -341.268216) (xy 333.094498 -341.224073) (xy 333.067202 -341.175438)
			(xy 333.047279 -341.123347) (xy 333.035153 -341.06891) (xy 333.031082 -341.013288) (xy 322.649088 -341.013288)
			(xy 322.649088 -344.446606) (xy 324.569328 -344.446606) (xy 324.569934 -344.416953) (xy 324.579123 -344.358362)
			(xy 324.597265 -344.301898) (xy 324.623923 -344.24892) (xy 324.658456 -344.200704) (xy 324.700032 -344.15841)
			(xy 324.723506 -344.140282) (xy 324.735339 -344.13073) (xy 324.753323 -344.106233) (xy 324.763305 -344.077529)
			(xy 324.764401 -344.047159) (xy 324.756515 -344.017811) (xy 324.748906 -344.004646) (xy 324.735111 -343.981796)
			(xy 324.713366 -343.933051) (xy 324.698629 -343.88175) (xy 324.691187 -343.828896) (xy 324.69074 -343.802208)
			(xy 324.691226 -343.774957) (xy 324.698982 -343.721009) (xy 324.714337 -343.668714) (xy 324.736979 -343.619137)
			(xy 324.766445 -343.573287) (xy 324.802136 -343.532096) (xy 324.843327 -343.496405) (xy 324.889177 -343.466939)
			(xy 324.938754 -343.444297) (xy 324.991049 -343.428942) (xy 325.044997 -343.421186) (xy 325.099499 -343.421186)
			(xy 325.153447 -343.428942) (xy 325.205742 -343.444297) (xy 325.255319 -343.466939) (xy 325.301169 -343.496405)
			(xy 325.34236 -343.532096) (xy 325.378051 -343.573287) (xy 325.407517 -343.619137) (xy 325.430159 -343.668714)
			(xy 325.445514 -343.721009) (xy 325.45327 -343.774957) (xy 325.453756 -343.802208) (xy 325.453167 -343.831862)
			(xy 325.443975 -343.890454) (xy 325.42583 -343.946919) (xy 325.399169 -343.999897) (xy 325.364633 -344.048112)
			(xy 325.323054 -344.090405) (xy 325.299578 -344.108532) (xy 325.287732 -344.118069) (xy 325.26975 -344.142571)
			(xy 325.259772 -344.171279) (xy 325.258678 -344.201652) (xy 325.266567 -344.231003) (xy 325.274178 -344.244168)
			(xy 325.287977 -344.267016) (xy 325.309721 -344.315762) (xy 325.324457 -344.367063) (xy 325.331898 -344.419918)
			(xy 325.332344 -344.446606) (xy 325.331858 -344.473857) (xy 325.324102 -344.527805) (xy 325.308747 -344.5801)
			(xy 325.286105 -344.629677) (xy 325.256639 -344.675527) (xy 325.220948 -344.716718) (xy 325.179757 -344.752409)
			(xy 325.133907 -344.781875) (xy 325.08433 -344.804517) (xy 325.032035 -344.819872) (xy 324.978087 -344.827628)
			(xy 324.923585 -344.827628) (xy 324.869637 -344.819872) (xy 324.817342 -344.804517) (xy 324.767765 -344.781875)
			(xy 324.721915 -344.752409) (xy 324.680724 -344.716718) (xy 324.645033 -344.675527) (xy 324.615567 -344.629677)
			(xy 324.592925 -344.5801) (xy 324.57757 -344.527805) (xy 324.569814 -344.473857) (xy 324.569328 -344.446606)
			(xy 322.649088 -344.446606) (xy 322.649088 -344.604086) (xy 322.649559 -344.618668) (xy 322.657802 -344.646644)
			(xy 322.673618 -344.671147) (xy 322.695718 -344.690178) (xy 322.722296 -344.702183) (xy 322.751185 -344.706184)
			(xy 322.780026 -344.701853) (xy 322.806465 -344.689543) (xy 322.817744 -344.680286) (xy 322.839295 -344.659857)
			(xy 322.887548 -344.62525) (xy 322.940579 -344.598535) (xy 322.997108 -344.580356) (xy 323.05577 -344.571152)
			(xy 323.08546 -344.570558) (xy 323.112717 -344.571018) (xy 323.166677 -344.578771) (xy 323.218985 -344.594125)
			(xy 323.268574 -344.616767) (xy 323.314437 -344.646237) (xy 323.355638 -344.681934) (xy 323.391339 -344.723131)
			(xy 323.420813 -344.768991) (xy 323.443461 -344.818578) (xy 323.45882 -344.870884) (xy 323.466579 -344.924843)
			(xy 323.466579 -344.956892) (xy 323.685406 -344.956892) (xy 323.689477 -344.90127) (xy 323.701603 -344.846833)
			(xy 323.721526 -344.794742) (xy 323.748822 -344.746107) (xy 323.782908 -344.701964) (xy 323.823057 -344.663255)
			(xy 323.868415 -344.630804) (xy 323.918015 -344.605303) (xy 323.970799 -344.587296) (xy 324.025642 -344.577166)
			(xy 324.081376 -344.575129) (xy 324.136813 -344.581229) (xy 324.19077 -344.595335) (xy 324.242099 -344.617147)
			(xy 324.289705 -344.646201) (xy 324.332573 -344.681876) (xy 324.36979 -344.723413) (xy 324.400563 -344.769926)
			(xy 324.424235 -344.820423) (xy 324.430065 -344.8398) (xy 328.939331 -344.8398) (xy 328.9435 -344.78418)
			(xy 328.955912 -344.729802) (xy 328.97629 -344.677882) (xy 329.004179 -344.629579) (xy 329.038956 -344.585973)
			(xy 329.079844 -344.548037) (xy 329.12593 -344.516619) (xy 329.176183 -344.492421) (xy 329.229482 -344.475983)
			(xy 329.284636 -344.467673) (xy 329.312524 -344.46718) (xy 329.339854 -344.467705) (xy 329.39393 -344.475668)
			(xy 329.446262 -344.491448) (xy 329.495725 -344.514708) (xy 329.541258 -344.544947) (xy 329.581882 -344.581516)
			(xy 329.616726 -344.62363) (xy 329.631294 -344.646758) (xy 329.639256 -344.658956) (xy 329.660714 -344.678632)
			(xy 329.686857 -344.691442) (xy 329.715555 -344.696344) (xy 329.744468 -344.692937) (xy 329.75804 -344.687652)
			(xy 329.781247 -344.678155) (xy 329.829581 -344.664808) (xy 329.879272 -344.658082) (xy 329.904344 -344.65768)
			(xy 329.929413 -344.658105) (xy 329.979096 -344.664855) (xy 330.02743 -344.678187) (xy 330.050648 -344.687652)
			(xy 330.064237 -344.692861) (xy 330.09313 -344.696228) (xy 330.121802 -344.691324) (xy 330.147934 -344.678545)
			(xy 330.16941 -344.658926) (xy 330.177394 -344.646758) (xy 330.191963 -344.623627) (xy 330.226806 -344.581506)
			(xy 330.267429 -344.544927) (xy 330.31296 -344.514676) (xy 330.362422 -344.4914) (xy 330.414753 -344.4756)
			(xy 330.468832 -344.467614) (xy 330.523496 -344.467614) (xy 330.577575 -344.4756) (xy 330.629906 -344.4914)
			(xy 330.679368 -344.514676) (xy 330.724899 -344.544927) (xy 330.765522 -344.581506) (xy 330.800365 -344.623627)
			(xy 330.814934 -344.646758) (xy 330.822858 -344.658983) (xy 330.844326 -344.678659) (xy 330.87048 -344.691467)
			(xy 330.899187 -344.696361) (xy 330.928107 -344.692944) (xy 330.94168 -344.687652) (xy 330.964894 -344.678174)
			(xy 331.013225 -344.664819) (xy 331.062913 -344.658086) (xy 331.087984 -344.65768) (xy 331.114841 -344.658135)
			(xy 331.167998 -344.665853) (xy 331.219498 -344.681117) (xy 331.268276 -344.703613) (xy 331.313321 -344.732873)
			(xy 331.353703 -344.768293) (xy 331.388585 -344.80914) (xy 331.417247 -344.854569) (xy 331.428598 -344.878914)
			(xy 331.434622 -344.891386) (xy 331.452244 -344.912739) (xy 331.474963 -344.92856) (xy 331.501102 -344.937683)
			(xy 331.528733 -344.939433) (xy 331.555814 -344.933682) (xy 331.568298 -344.927682) (xy 331.595706 -344.914059)
			(xy 331.653801 -344.894808) (xy 331.714226 -344.885084) (xy 331.744828 -344.884502) (xy 331.767947 -344.884832)
			(xy 331.813848 -344.890401) (xy 331.858736 -344.90149) (xy 331.880464 -344.909394) (xy 331.894243 -344.914198)
			(xy 331.923328 -344.916452) (xy 331.951865 -344.910395) (xy 331.977527 -344.896521) (xy 331.998222 -344.87596)
			(xy 332.012263 -344.850389) (xy 332.015846 -344.836242) (xy 332.022456 -344.808278) (xy 332.043051 -344.754635)
			(xy 332.071459 -344.704687) (xy 332.107036 -344.659565) (xy 332.148979 -344.620289) (xy 332.196338 -344.587748)
			(xy 332.248042 -344.562678) (xy 332.302921 -344.545646) (xy 332.359733 -344.537038) (xy 332.388464 -344.536522)
			(xy 332.415717 -344.536989) (xy 332.46967 -344.544742) (xy 332.521969 -344.560095) (xy 332.571551 -344.582735)
			(xy 332.617406 -344.612202) (xy 332.6586 -344.647896) (xy 332.694294 -344.689089) (xy 332.723762 -344.734943)
			(xy 332.746403 -344.784525) (xy 332.761757 -344.836824) (xy 332.769511 -344.890777) (xy 332.769972 -344.91803)
			(xy 332.76953 -344.945401) (xy 332.761708 -344.999582) (xy 332.746213 -345.052085) (xy 332.723366 -345.101832)
			(xy 332.693636 -345.147797) (xy 332.675992 -345.168728) (xy 332.666727 -345.180034) (xy 332.654554 -345.2066)
			(xy 332.650387 -345.235523) (xy 332.654567 -345.264444) (xy 332.666752 -345.291004) (xy 332.675992 -345.302332)
			(xy 332.693611 -345.32328) (xy 332.723326 -345.369248) (xy 332.746166 -345.418992) (xy 332.761662 -345.471489)
			(xy 332.769495 -345.525662) (xy 332.769972 -345.55303) (xy 332.769468 -345.580603) (xy 332.761525 -345.635175)
			(xy 332.745808 -345.688034) (xy 332.722645 -345.738081) (xy 332.692519 -345.784271) (xy 332.656057 -345.825644)
			(xy 332.635352 -345.84386) (xy 332.62442 -345.853726) (xy 332.608341 -345.878383) (xy 332.599957 -345.906601)
			(xy 332.599962 -345.936038) (xy 332.608358 -345.964252) (xy 332.624446 -345.988904) (xy 332.635352 -345.9988)
			(xy 332.656057 -346.017018) (xy 332.69253 -346.058384) (xy 332.722664 -346.104572) (xy 332.745831 -346.154619)
			(xy 332.761548 -346.207481) (xy 332.769487 -346.262055) (xy 332.769972 -346.28963) (xy 332.769573 -346.316885)
			(xy 332.761811 -346.37084) (xy 332.746449 -346.423142) (xy 332.723801 -346.472724) (xy 332.694326 -346.518579)
			(xy 332.658626 -346.559772) (xy 332.617426 -346.595466) (xy 332.571566 -346.624932) (xy 332.52198 -346.647572)
			(xy 332.469676 -346.662925) (xy 332.415719 -346.670678) (xy 332.388464 -346.671138) (xy 332.360591 -346.670614)
			(xy 332.305439 -346.662496) (xy 332.252055 -346.646438) (xy 332.201576 -346.622782) (xy 332.155078 -346.592032)
			(xy 332.11355 -346.554842) (xy 332.077876 -346.512004) (xy 332.048817 -346.464431) (xy 332.037436 -346.438982)
			(xy 332.030807 -346.424806) (xy 332.01038 -346.401115) (xy 331.983751 -346.384701) (xy 331.953407 -346.377099)
			(xy 331.922185 -346.379018) (xy 331.907388 -346.384118) (xy 331.885434 -346.392189) (xy 331.840046 -346.4035)
			(xy 331.793616 -346.409181) (xy 331.770228 -346.409518) (xy 331.756079 -346.409421) (xy 331.727856 -346.407389)
			(xy 331.71384 -346.405454) (xy 331.700495 -346.403821) (xy 331.673795 -346.406923) (xy 331.648836 -346.416899)
			(xy 331.627353 -346.433054) (xy 331.610843 -346.454264) (xy 331.600453 -346.479054) (xy 331.59827 -346.492322)
			(xy 331.594113 -346.519464) (xy 331.579146 -346.57229) (xy 331.556761 -346.622425) (xy 331.527421 -346.668834)
			(xy 331.491731 -346.710557) (xy 331.45043 -346.746735) (xy 331.404369 -346.776618) (xy 331.3545 -346.79959)
			(xy 331.301854 -346.815177) (xy 331.247517 -346.823056) (xy 331.220064 -346.823538) (xy 331.192813 -346.823056)
			(xy 331.138867 -346.815295) (xy 331.086574 -346.799937) (xy 331.036999 -346.777294) (xy 330.99115 -346.747827)
			(xy 330.949961 -346.712135) (xy 330.91427 -346.670945) (xy 330.884803 -346.625096) (xy 330.862161 -346.57552)
			(xy 330.846804 -346.523227) (xy 330.839044 -346.469281) (xy 330.838556 -346.44203) (xy 330.839023 -346.414455)
			(xy 330.846972 -346.359882) (xy 330.862696 -346.307021) (xy 330.885866 -346.256974) (xy 330.915999 -346.210785)
			(xy 330.952468 -346.169415) (xy 330.973176 -346.1512) (xy 330.984045 -346.141272) (xy 331.000122 -346.116631)
			(xy 331.008511 -346.08843) (xy 331.008517 -346.059008) (xy 331.000138 -346.030805) (xy 330.984071 -346.006157)
			(xy 330.973176 -345.99626) (xy 330.952486 -345.978026) (xy 330.916015 -345.936662) (xy 330.885881 -345.890476)
			(xy 330.862712 -345.840433) (xy 330.84699 -345.787575) (xy 330.839045 -345.733003) (xy 330.838556 -345.70543)
			(xy 330.839066 -345.675958) (xy 330.848108 -345.617712) (xy 330.865997 -345.561549) (xy 330.892307 -345.508804)
			(xy 330.908914 -345.48445) (xy 330.91637 -345.473083) (xy 330.925686 -345.44756) (xy 330.927945 -345.420484)
			(xy 330.922989 -345.39377) (xy 330.911167 -345.369307) (xy 330.893316 -345.348824) (xy 330.882244 -345.34094)
			(xy 330.859621 -345.325432) (xy 330.818807 -345.288794) (xy 330.783827 -345.246549) (xy 330.769214 -345.223338)
			(xy 330.761245 -345.211145) (xy 330.739789 -345.19147) (xy 330.713648 -345.178659) (xy 330.684951 -345.173756)
			(xy 330.656039 -345.17716) (xy 330.642468 -345.182444) (xy 330.61926 -345.191938) (xy 330.570926 -345.205287)
			(xy 330.521236 -345.212013) (xy 330.496164 -345.212416) (xy 330.471095 -345.211988) (xy 330.421412 -345.20524)
			(xy 330.373078 -345.191909) (xy 330.34986 -345.182444) (xy 330.336267 -345.177245) (xy 330.307376 -345.173876)
			(xy 330.278705 -345.178779) (xy 330.252575 -345.191555) (xy 330.231098 -345.211171) (xy 330.223114 -345.223338)
			(xy 330.208545 -345.246469) (xy 330.173702 -345.28859) (xy 330.133079 -345.325169) (xy 330.087548 -345.35542)
			(xy 330.038086 -345.378696) (xy 329.985755 -345.394496) (xy 329.931676 -345.402482) (xy 329.877012 -345.402482)
			(xy 329.822933 -345.394496) (xy 329.770602 -345.378696) (xy 329.72114 -345.35542) (xy 329.675609 -345.325169)
			(xy 329.634986 -345.28859) (xy 329.600143 -345.246469) (xy 329.585574 -345.223338) (xy 329.577644 -345.211118)
			(xy 329.556177 -345.191442) (xy 329.530025 -345.178634) (xy 329.50132 -345.173738) (xy 329.472401 -345.177154)
			(xy 329.458828 -345.182444) (xy 329.435613 -345.191919) (xy 329.387282 -345.205275) (xy 329.337595 -345.212009)
			(xy 329.312524 -345.212416) (xy 329.284636 -345.211927) (xy 329.229482 -345.203617) (xy 329.176183 -345.187179)
			(xy 329.12593 -345.162981) (xy 329.079844 -345.131563) (xy 329.038956 -345.093627) (xy 329.004179 -345.050021)
			(xy 328.97629 -345.001718) (xy 328.955912 -344.949798) (xy 328.9435 -344.89542) (xy 328.939331 -344.8398)
			(xy 324.430065 -344.8398) (xy 324.440303 -344.87383) (xy 324.448423 -344.929006) (xy 324.448932 -344.956892)
			(xy 324.448423 -344.984778) (xy 324.440303 -345.039954) (xy 324.424235 -345.093361) (xy 324.400563 -345.143858)
			(xy 324.36979 -345.190371) (xy 324.332573 -345.231908) (xy 324.289705 -345.267583) (xy 324.242099 -345.296637)
			(xy 324.19077 -345.318449) (xy 324.136813 -345.332555) (xy 324.081376 -345.338655) (xy 324.025642 -345.336618)
			(xy 323.970799 -345.326488) (xy 323.918015 -345.308481) (xy 323.868415 -345.28298) (xy 323.823057 -345.250529)
			(xy 323.782908 -345.21182) (xy 323.748822 -345.167677) (xy 323.721526 -345.119042) (xy 323.701603 -345.066951)
			(xy 323.689477 -345.012514) (xy 323.685406 -344.956892) (xy 323.466579 -344.956892) (xy 323.466579 -344.979357)
			(xy 323.45882 -345.033316) (xy 323.443461 -345.085622) (xy 323.420813 -345.135209) (xy 323.391339 -345.181069)
			(xy 323.355638 -345.222266) (xy 323.314437 -345.257963) (xy 323.268574 -345.287433) (xy 323.218985 -345.310075)
			(xy 323.166677 -345.325429) (xy 323.112717 -345.333182) (xy 323.08546 -345.333574) (xy 323.073552 -345.333471)
			(xy 323.049785 -345.331948) (xy 323.037962 -345.330526) (xy 323.024068 -345.329494) (xy 322.99661 -345.334162)
			(xy 322.971434 -345.346072) (xy 322.95041 -345.364339) (xy 322.935101 -345.387607) (xy 322.926645 -345.414144)
			(xy 322.925671 -345.441978) (xy 322.932251 -345.469041) (xy 322.945896 -345.493322) (xy 322.955412 -345.5035)
			(xy 322.994782 -345.54287) (xy 323.308218 -345.85656) (xy 324.11924 -345.85656) (xy 324.142808 -345.841481)
			(xy 324.193428 -345.817646) (xy 324.246989 -345.801466) (xy 324.302339 -345.79329) (xy 324.330314 -345.792806)
			(xy 324.357564 -345.793293) (xy 324.411508 -345.801051) (xy 324.463799 -345.816407) (xy 324.513372 -345.839048)
			(xy 324.559219 -345.868513) (xy 324.600406 -345.904204) (xy 324.6016 -345.905582) (xy 325.481694 -345.905582)
			(xy 325.485765 -345.84996) (xy 325.497891 -345.795523) (xy 325.517814 -345.743432) (xy 325.54511 -345.694797)
			(xy 325.579196 -345.650654) (xy 325.619345 -345.611945) (xy 325.664703 -345.579494) (xy 325.714303 -345.553993)
			(xy 325.767087 -345.535986) (xy 325.82193 -345.525856) (xy 325.877664 -345.523819) (xy 325.933101 -345.529919)
			(xy 325.987058 -345.544025) (xy 326.038387 -345.565837) (xy 326.085993 -345.594891) (xy 326.128861 -345.630566)
			(xy 326.166078 -345.672103) (xy 326.196851 -345.718616) (xy 326.220523 -345.769113) (xy 326.236591 -345.82252)
			(xy 326.244711 -345.877696) (xy 326.24522 -345.905582) (xy 326.244711 -345.933468) (xy 326.236591 -345.988644)
			(xy 326.220523 -346.042051) (xy 326.196851 -346.092548) (xy 326.166078 -346.139061) (xy 326.128861 -346.180598)
			(xy 326.085993 -346.216273) (xy 326.038387 -346.245327) (xy 325.987058 -346.267139) (xy 325.933101 -346.281245)
			(xy 325.877664 -346.287345) (xy 325.82193 -346.285308) (xy 325.767087 -346.275178) (xy 325.714303 -346.257171)
			(xy 325.664703 -346.23167) (xy 325.619345 -346.199219) (xy 325.579196 -346.16051) (xy 325.54511 -346.116367)
			(xy 325.517814 -346.067732) (xy 325.497891 -346.015641) (xy 325.485765 -345.961204) (xy 325.481694 -345.905582)
			(xy 324.6016 -345.905582) (xy 324.636095 -345.945392) (xy 324.665559 -345.99124) (xy 324.688198 -346.040814)
			(xy 324.703552 -346.093106) (xy 324.711308 -346.14705) (xy 324.711308 -346.20155) (xy 324.703552 -346.255494)
			(xy 324.688198 -346.307786) (xy 324.665559 -346.35736) (xy 324.636095 -346.403208) (xy 324.600406 -346.444396)
			(xy 324.559219 -346.480087) (xy 324.513372 -346.509552) (xy 324.463799 -346.532193) (xy 324.411508 -346.547549)
			(xy 324.357564 -346.555307) (xy 324.330314 -346.555822) (xy 324.302339 -346.555331) (xy 324.246988 -346.547157)
			(xy 324.193427 -346.530983) (xy 324.142803 -346.507155) (xy 324.11924 -346.492068) (xy 323.176392 -346.492068)
			(xy 323.151439 -346.491586) (xy 323.102146 -346.483794) (xy 323.054679 -346.468388) (xy 323.010206 -346.445746)
			(xy 322.969822 -346.416426) (xy 322.951856 -346.399104) (xy 322.10629 -345.553538) (xy 322.08894 -345.535549)
			(xy 322.059545 -345.495132) (xy 322.036835 -345.450615) (xy 322.021369 -345.403092) (xy 322.013527 -345.353736)
			(xy 322.013072 -345.328748) (xy 322.013072 -338.036916) (xy 322.013537 -338.011928) (xy 322.021364 -337.962569)
			(xy 322.036825 -337.915045) (xy 322.05954 -337.87053) (xy 322.088948 -337.830123) (xy 322.10629 -337.812126)
			(xy 326.285606 -333.63281) (xy 326.295837 -333.621843) (xy 326.309991 -333.595417) (xy 326.315868 -333.566021)
			(xy 326.312963 -333.536185) (xy 326.301525 -333.508475) (xy 326.282539 -333.485276) (xy 326.257639 -333.468584)
			(xy 326.228966 -333.459835) (xy 326.213978 -333.459328) (xy 322.917566 -333.459328) (xy 322.838572 -333.647288)
			(xy 312.987436 -343.498424) (xy 301.91964 -343.498424) (xy 301.880524 -343.53754) (xy 318.94018 -343.53754)
			(xy 318.94018 -343.156032) (xy 318.940682 -343.124071) (xy 318.948693 -343.060653) (xy 318.96459 -342.998739)
			(xy 318.988122 -342.939306) (xy 319.018916 -342.883291) (xy 319.056489 -342.831576) (xy 319.100246 -342.784979)
			(xy 319.149499 -342.744234) (xy 319.20347 -342.709983) (xy 319.261309 -342.682766) (xy 319.322102 -342.663013)
			(xy 319.384892 -342.651035) (xy 319.448688 -342.647022) (xy 319.512484 -342.651035) (xy 319.575274 -342.663013)
			(xy 319.636067 -342.682766) (xy 319.693906 -342.709983) (xy 319.747877 -342.744234) (xy 319.79713 -342.784979)
			(xy 319.840887 -342.831576) (xy 319.87846 -342.883291) (xy 319.909254 -342.939306) (xy 319.932786 -342.998739)
			(xy 319.948683 -343.060653) (xy 319.956694 -343.124071) (xy 319.957196 -343.156032) (xy 319.957196 -343.326974)
			(xy 320.832988 -344.20302) (xy 320.856112 -344.226956) (xy 320.896621 -344.27976) (xy 320.929895 -344.337399)
			(xy 320.955363 -344.398886) (xy 320.972591 -344.463171) (xy 320.981284 -344.529154) (xy 320.981832 -344.56243)
			(xy 320.981832 -347.2307) (xy 320.981345 -347.262827) (xy 320.973282 -347.326571) (xy 320.957234 -347.388788)
			(xy 320.93346 -347.44848) (xy 320.918332 -347.476826) (xy 320.918332 -348.410022) (xy 321.94754 -348.410022)
			(xy 321.947925 -348.38364) (xy 321.955189 -348.331379) (xy 321.969582 -348.280617) (xy 321.990828 -348.23232)
			(xy 322.018525 -348.18741) (xy 322.052142 -348.146743) (xy 322.09104 -348.111093) (xy 322.134478 -348.081141)
			(xy 322.157852 -348.0689) (xy 322.170193 -348.062167) (xy 322.190922 -348.043198) (xy 322.205685 -348.01929)
			(xy 322.213359 -347.992259) (xy 322.213362 -347.96416) (xy 322.205693 -347.937128) (xy 322.190935 -347.913217)
			(xy 322.170209 -347.894244) (xy 322.157852 -347.887544) (xy 322.13448 -347.875306) (xy 322.091058 -347.845342)
			(xy 322.052174 -347.809685) (xy 322.018569 -347.769015) (xy 321.990883 -347.724105) (xy 321.969642 -347.675813)
			(xy 321.955252 -347.625056) (xy 321.947987 -347.572801) (xy 321.94754 -347.546422) (xy 321.948026 -347.519171)
			(xy 321.955782 -347.465223) (xy 321.971137 -347.412928) (xy 321.993779 -347.363351) (xy 322.023245 -347.317501)
			(xy 322.058936 -347.27631) (xy 322.100127 -347.240619) (xy 322.145977 -347.211153) (xy 322.195554 -347.188511)
			(xy 322.247849 -347.173156) (xy 322.301797 -347.1654) (xy 322.356299 -347.1654) (xy 322.410247 -347.173156)
			(xy 322.462542 -347.188511) (xy 322.512119 -347.211153) (xy 322.557969 -347.240619) (xy 322.59916 -347.27631)
			(xy 322.634851 -347.317501) (xy 322.664317 -347.363351) (xy 322.686959 -347.412928) (xy 322.702314 -347.465223)
			(xy 322.707196 -347.499178) (xy 326.2884 -347.499178) (xy 326.288939 -347.469489) (xy 326.298141 -347.410829)
			(xy 326.31632 -347.354303) (xy 326.343036 -347.301276) (xy 326.377645 -347.253028) (xy 326.41931 -347.210723)
			(xy 326.442832 -347.1926) (xy 326.453471 -347.184212) (xy 326.470174 -347.162889) (xy 326.480687 -347.137927)
			(xy 326.484272 -347.11108) (xy 326.480677 -347.084233) (xy 326.470153 -347.059275) (xy 326.453442 -347.03796)
			(xy 326.442832 -347.029532) (xy 326.419344 -347.011369) (xy 326.37768 -346.969072) (xy 326.343072 -346.920831)
			(xy 326.316356 -346.867811) (xy 326.298175 -346.811292) (xy 326.288969 -346.752639) (xy 326.2884 -346.722954)
			(xy 326.288851 -346.695691) (xy 326.29662 -346.641722) (xy 326.311993 -346.589408) (xy 326.334657 -346.539816)
			(xy 326.364151 -346.493955) (xy 326.399873 -346.45276) (xy 326.441096 -346.417071) (xy 326.486979 -346.387613)
			(xy 326.536589 -346.364988) (xy 326.588915 -346.349656) (xy 326.642891 -346.34193) (xy 326.697417 -346.341966)
			(xy 326.751382 -346.349764) (xy 326.803687 -346.365166) (xy 326.853267 -346.387857) (xy 326.899112 -346.417376)
			(xy 326.940287 -346.45312) (xy 326.975954 -346.494362) (xy 327.005386 -346.540262) (xy 327.027984 -346.589885)
			(xy 327.043288 -346.642219) (xy 327.050985 -346.696199) (xy 327.051416 -346.723462) (xy 327.051416 -346.744798)
			(xy 327.153524 -346.846652) (xy 327.164612 -346.856435) (xy 327.191088 -346.869584) (xy 327.220221 -346.8746)
			(xy 327.24957 -346.871061) (xy 327.276676 -346.859266) (xy 327.299269 -346.840201) (xy 327.315455 -346.815465)
			(xy 327.320148 -346.80144) (xy 327.328432 -346.775558) (xy 327.35119 -346.726214) (xy 327.380717 -346.680597)
			(xy 327.416416 -346.639629) (xy 327.457566 -346.604141) (xy 327.503335 -346.574848) (xy 327.552795 -346.552344)
			(xy 327.604948 -346.537084) (xy 327.658738 -346.529377) (xy 327.685908 -346.528898) (xy 327.686162 -346.528898)
			(xy 327.711365 -346.529306) (xy 327.761333 -346.535942) (xy 327.809988 -346.549116) (xy 327.856478 -346.568597)
			(xy 327.87844 -346.580968) (xy 327.891398 -346.58802) (xy 327.920037 -346.595048) (xy 327.94949 -346.593599)
			(xy 327.977302 -346.583795) (xy 328.001152 -346.566452) (xy 328.019051 -346.543016) (xy 328.024744 -346.529406)
			(xy 328.035473 -346.502644) (xy 328.063756 -346.452403) (xy 328.099281 -346.406993) (xy 328.141238 -346.367449)
			(xy 328.188671 -346.334674) (xy 328.240497 -346.309414) (xy 328.295536 -346.292244) (xy 328.352533 -346.283558)
			(xy 328.38136 -346.283026) (xy 328.408613 -346.283493) (xy 328.462566 -346.291245) (xy 328.514866 -346.306598)
			(xy 328.564448 -346.329238) (xy 328.610303 -346.358705) (xy 328.651497 -346.394399) (xy 328.687191 -346.435592)
			(xy 328.716659 -346.481447) (xy 328.7393 -346.531028) (xy 328.754654 -346.583328) (xy 328.762407 -346.637281)
			(xy 328.762868 -346.664534) (xy 328.762868 -346.664788) (xy 328.762281 -346.694626) (xy 328.752973 -346.753572)
			(xy 328.744326 -346.782136) (xy 328.740293 -346.796046) (xy 328.739378 -346.824979) (xy 328.74664 -346.853002)
			(xy 328.761492 -346.877849) (xy 328.782735 -346.897514) (xy 328.808653 -346.910408) (xy 328.822812 -346.913454)
			(xy 328.84889 -346.918601) (xy 328.899396 -346.935172) (xy 328.947111 -346.958596) (xy 328.991111 -346.98842)
			(xy 329.030542 -347.024066) (xy 329.064641 -347.064842) (xy 329.092747 -347.109958) (xy 329.114315 -347.158541)
			(xy 329.128927 -347.209648) (xy 329.1363 -347.262289) (xy 329.136756 -347.288866) (xy 329.13627 -347.316117)
			(xy 329.128514 -347.370065) (xy 329.113159 -347.42236) (xy 329.090517 -347.471937) (xy 329.061051 -347.517787)
			(xy 329.02536 -347.558978) (xy 328.984169 -347.594669) (xy 328.938319 -347.624135) (xy 328.888742 -347.646777)
			(xy 328.836447 -347.662132) (xy 328.782499 -347.669888) (xy 328.727997 -347.669888) (xy 328.674049 -347.662132)
			(xy 328.621754 -347.646777) (xy 328.572177 -347.624135) (xy 328.526327 -347.594669) (xy 328.485136 -347.558978)
			(xy 328.449445 -347.517787) (xy 328.419979 -347.471937) (xy 328.397337 -347.42236) (xy 328.381982 -347.370065)
			(xy 328.374226 -347.316117) (xy 328.37374 -347.288866) (xy 328.37374 -347.288612) (xy 328.374328 -347.258774)
			(xy 328.383635 -347.199828) (xy 328.392282 -347.171264) (xy 328.396308 -347.157353) (xy 328.397223 -347.128421)
			(xy 328.389962 -347.1004) (xy 328.375111 -347.075553) (xy 328.35387 -347.055888) (xy 328.327954 -347.042993)
			(xy 328.313796 -347.039946) (xy 328.280955 -347.033371) (xy 328.218103 -347.010243) (xy 328.188828 -346.993972)
			(xy 328.175839 -346.98698) (xy 328.147211 -346.979935) (xy 328.117765 -346.98137) (xy 328.089957 -346.991163)
			(xy 328.06611 -347.008498) (xy 328.048214 -347.031927) (xy 328.042524 -347.045534) (xy 328.031687 -347.072689)
			(xy 328.0029 -347.123578) (xy 327.966688 -347.16948) (xy 327.923899 -347.209323) (xy 327.875533 -347.242172)
			(xy 327.822724 -347.267261) (xy 327.794874 -347.276166) (xy 327.780876 -347.280916) (xy 327.756156 -347.297091)
			(xy 327.737103 -347.319668) (xy 327.725317 -347.346757) (xy 327.721783 -347.376086) (xy 327.726798 -347.405199)
			(xy 327.739943 -347.431656) (xy 327.749662 -347.44279) (xy 328.246232 -347.939614) (xy 328.257542 -347.951294)
			(xy 328.277417 -347.977025) (xy 328.285856 -347.990922) (xy 328.296841 -348.010544) (xy 328.312462 -348.052708)
			(xy 328.320411 -348.096964) (xy 328.320908 -348.119446) (xy 328.320908 -348.963234) (xy 328.41311 -349.055436)
			(xy 332.126844 -349.055436) (xy 333.788766 -347.393768) (xy 334.625442 -346.557092) (xy 334.637113 -346.545772)
			(xy 334.66285 -346.525904) (xy 334.67675 -346.517468) (xy 334.696368 -346.506475) (xy 334.738533 -346.490856)
			(xy 334.782791 -346.482911) (xy 334.805274 -346.482416) (xy 343.055956 -346.482416) (xy 343.078434 -346.482951)
			(xy 343.12268 -346.490919) (xy 343.164847 -346.50651) (xy 343.18448 -346.517468) (xy 343.198384 -346.525897)
			(xy 343.224113 -346.545776) (xy 343.235788 -346.557092) (xy 343.932764 -347.254068) (xy 344.646504 -347.254068)
			(xy 344.671487 -347.25469) (xy 344.720495 -347.264429) (xy 344.766665 -347.283533) (xy 344.808226 -347.31127)
			(xy 344.826336 -347.32849) (xy 351.942654 -354.444808) (xy 352.808284 -354.444808) (xy 352.812355 -354.389186)
			(xy 352.824481 -354.334749) (xy 352.844404 -354.282658) (xy 352.8717 -354.234023) (xy 352.905786 -354.18988)
			(xy 352.945935 -354.151171) (xy 352.991293 -354.11872) (xy 353.040893 -354.093219) (xy 353.093677 -354.075212)
			(xy 353.14852 -354.065082) (xy 353.204254 -354.063045) (xy 353.259691 -354.069145) (xy 353.313648 -354.083251)
			(xy 353.364977 -354.105063) (xy 353.412583 -354.134117) (xy 353.455451 -354.169792) (xy 353.492668 -354.211329)
			(xy 353.523441 -354.257842) (xy 353.547113 -354.308339) (xy 353.563181 -354.361746) (xy 353.571301 -354.416922)
			(xy 353.57181 -354.444808) (xy 353.571301 -354.472694) (xy 353.563181 -354.52787) (xy 353.547113 -354.581277)
			(xy 353.523441 -354.631774) (xy 353.492668 -354.678287) (xy 353.455451 -354.719824) (xy 353.412583 -354.755499)
			(xy 353.364977 -354.784553) (xy 353.313648 -354.806365) (xy 353.259691 -354.820471) (xy 353.204254 -354.826571)
			(xy 353.14852 -354.824534) (xy 353.093677 -354.814404) (xy 353.040893 -354.796397) (xy 352.991293 -354.770896)
			(xy 352.945935 -354.738445) (xy 352.905786 -354.699736) (xy 352.8717 -354.655593) (xy 352.844404 -354.606958)
			(xy 352.824481 -354.554867) (xy 352.812355 -354.50043) (xy 352.808284 -354.444808) (xy 351.942654 -354.444808)
			(xy 352.262948 -354.765102) (xy 352.679 -354.937314) (xy 353.702874 -355.36124) (xy 356.569772 -355.36124)
			(xy 357.170736 -354.760276) (xy 357.473504 -354.457762) (xy 357.369872 -354.354384) (xy 357.369872 -353.700334)
			(xy 357.331772 -353.662488) (xy 357.331772 -353.548188) (xy 351.919032 -353.548188) (xy 351.896554 -353.547657)
			(xy 351.852308 -353.539688) (xy 351.810141 -353.524095) (xy 351.790508 -353.513136) (xy 351.776604 -353.504708)
			(xy 351.750875 -353.484828) (xy 351.7392 -353.473512) (xy 344.761058 -346.495624) (xy 344.318844 -346.495624)
			(xy 344.296367 -346.495083) (xy 344.252121 -346.487117) (xy 344.209953 -346.471528) (xy 344.19032 -346.460572)
			(xy 344.176419 -346.452139) (xy 344.150688 -346.432263) (xy 344.139012 -346.420948) (xy 343.450672 -345.732862)
			(xy 342.083898 -344.366088) (xy 335.815178 -344.366088) (xy 335.792699 -344.36558) (xy 335.748452 -344.357601)
			(xy 335.706286 -344.341999) (xy 335.686654 -344.331036) (xy 335.672753 -344.322603) (xy 335.647022 -344.302727)
			(xy 335.635346 -344.291412) (xy 334.81772 -343.473786) (xy 334.806406 -343.46211) (xy 334.786534 -343.436376)
			(xy 334.778096 -343.422478) (xy 334.767116 -343.402854) (xy 334.751492 -343.360691) (xy 334.743541 -343.316436)
			(xy 334.743044 -343.293954) (xy 334.743044 -342.028018) (xy 334.704944 -342.018112) (xy 334.677973 -342.010666)
			(xy 334.626406 -341.988955) (xy 334.57856 -341.959947) (xy 334.535463 -341.924265) (xy 334.498037 -341.882674)
			(xy 334.467085 -341.836063) (xy 334.443269 -341.785433) (xy 334.4271 -341.731869) (xy 334.418925 -341.676518)
			(xy 334.418432 -341.648542) (xy 334.419005 -341.618854) (xy 334.428198 -341.560196) (xy 334.446369 -341.50367)
			(xy 334.473079 -341.450642) (xy 334.507682 -341.402392) (xy 334.549344 -341.360088) (xy 334.572864 -341.341964)
			(xy 334.583445 -341.333505) (xy 334.600159 -341.312203) (xy 334.610684 -341.287255) (xy 334.61428 -341.260418)
			(xy 334.610693 -341.23358) (xy 334.600177 -341.208628) (xy 334.583471 -341.18732) (xy 334.572864 -341.178896)
			(xy 334.549344 -341.160772) (xy 334.507686 -341.118465) (xy 334.473083 -341.070215) (xy 334.446373 -341.017188)
			(xy 334.428198 -340.960663) (xy 334.418998 -340.902005) (xy 334.418432 -340.872318) (xy 334.418814 -340.84505)
			(xy 334.426576 -340.791069) (xy 334.441945 -340.738743) (xy 334.464608 -340.689138) (xy 334.494102 -340.643266)
			(xy 334.529827 -340.60206) (xy 334.571055 -340.56636) (xy 334.616946 -340.536895) (xy 334.666564 -340.514263)
			(xy 334.7189 -340.498926) (xy 334.772886 -340.491197) (xy 334.827422 -340.491234) (xy 334.881397 -340.499034)
			(xy 334.933712 -340.514441) (xy 334.983301 -340.537139) (xy 335.029152 -340.566665) (xy 335.070332 -340.60242)
			(xy 335.106003 -340.643673) (xy 335.135436 -340.689585) (xy 335.158032 -340.73922) (xy 335.173331 -340.791566)
			(xy 335.181022 -340.845557) (xy 335.181448 -340.872826) (xy 335.181448 -340.894162) (xy 335.281016 -340.99373)
			(xy 335.292068 -341.00391) (xy 335.31858 -341.018012) (xy 335.348047 -341.0238) (xy 335.377923 -341.020774)
			(xy 335.405631 -341.009197) (xy 335.428779 -340.990068) (xy 335.445368 -340.965037) (xy 335.45018 -340.950804)
			(xy 335.458414 -340.924905) (xy 335.481178 -340.87556) (xy 335.510712 -340.829943) (xy 335.546419 -340.788976)
			(xy 335.587575 -340.753489) (xy 335.63335 -340.724199) (xy 335.682816 -340.701698) (xy 335.734974 -340.686442)
			(xy 335.788768 -340.678739) (xy 335.81594 -340.678262) (xy 335.816194 -340.678262) (xy 335.841398 -340.678661)
			(xy 335.891366 -340.6853) (xy 335.94002 -340.698477) (xy 335.98651 -340.71796) (xy 336.008472 -340.730332)
			(xy 336.021462 -340.737322) (xy 336.050089 -340.744366) (xy 336.079535 -340.742932) (xy 336.107342 -340.733139)
			(xy 336.131189 -340.715805) (xy 336.149085 -340.692377) (xy 336.154776 -340.67877) (xy 336.16546 -340.651988)
			(xy 336.19375 -340.601747) (xy 336.229282 -340.556338) (xy 336.271246 -340.516797) (xy 336.318685 -340.484024)
			(xy 336.370517 -340.458767) (xy 336.425562 -340.441602) (xy 336.482563 -340.432919) (xy 336.511392 -340.43239)
			(xy 336.538645 -340.432863) (xy 336.592595 -340.440619) (xy 336.644893 -340.455974) (xy 336.694473 -340.478615)
			(xy 336.740326 -340.508082) (xy 336.781518 -340.543775) (xy 336.817212 -340.584966) (xy 336.84668 -340.630819)
			(xy 336.869323 -340.680398) (xy 336.884679 -340.732695) (xy 336.892437 -340.786645) (xy 336.8929 -340.813898)
			(xy 336.8929 -340.814152) (xy 336.89233 -340.843991) (xy 336.883011 -340.902937) (xy 336.874358 -340.9315)
			(xy 336.870419 -340.945432) (xy 336.869498 -340.974349) (xy 336.876747 -341.002357) (xy 336.89158 -341.027197)
			(xy 336.9128 -341.046861) (xy 336.938695 -341.059765) (xy 336.952844 -341.062818) (xy 336.978919 -341.067975)
			(xy 337.029423 -341.084548) (xy 337.077136 -341.107974) (xy 337.121134 -341.137797) (xy 337.160564 -341.173442)
			(xy 337.194662 -341.214216) (xy 337.222769 -341.25933) (xy 337.244338 -341.30791) (xy 337.258953 -341.359015)
			(xy 337.26633 -341.411653) (xy 337.266788 -341.43823) (xy 337.266302 -341.465481) (xy 337.258546 -341.519429)
			(xy 337.243191 -341.571724) (xy 337.220549 -341.621301) (xy 337.191083 -341.667151) (xy 337.155392 -341.708342)
			(xy 337.114201 -341.744033) (xy 337.068351 -341.773499) (xy 337.018774 -341.796141) (xy 336.966479 -341.811496)
			(xy 336.912531 -341.819252) (xy 336.858029 -341.819252) (xy 336.804081 -341.811496) (xy 336.751786 -341.796141)
			(xy 336.702209 -341.773499) (xy 336.656359 -341.744033) (xy 336.615168 -341.708342) (xy 336.579477 -341.667151)
			(xy 336.550011 -341.621301) (xy 336.527369 -341.571724) (xy 336.512014 -341.519429) (xy 336.504258 -341.465481)
			(xy 336.503772 -341.43823) (xy 336.503772 -341.437976) (xy 336.50435 -341.408137) (xy 336.513664 -341.349191)
			(xy 336.522314 -341.320628) (xy 336.526356 -341.306722) (xy 336.527261 -341.277789) (xy 336.519994 -341.24977)
			(xy 336.505141 -341.224924) (xy 336.4839 -341.205258) (xy 336.457986 -341.19236) (xy 336.443828 -341.18931)
			(xy 336.41099 -341.182721) (xy 336.348137 -341.159602) (xy 336.31886 -341.143336) (xy 336.305903 -341.136282)
			(xy 336.277264 -341.129254) (xy 336.24781 -341.130702) (xy 336.219998 -341.140507) (xy 336.196148 -341.157851)
			(xy 336.178248 -341.181287) (xy 336.172556 -341.194898) (xy 336.161829 -341.221661) (xy 336.133545 -341.271902)
			(xy 336.09802 -341.317312) (xy 336.056063 -341.356855) (xy 336.00863 -341.38963) (xy 335.956803 -341.414891)
			(xy 335.901764 -341.43206) (xy 335.844767 -341.440746) (xy 335.81594 -341.441278) (xy 335.799797 -341.441135)
			(xy 335.767623 -341.438464) (xy 335.751678 -341.435944) (xy 335.737044 -341.434019) (xy 335.707759 -341.437554)
			(xy 335.68071 -341.449321) (xy 335.658159 -341.468334) (xy 335.64199 -341.493005) (xy 335.633556 -341.521271)
			(xy 335.63306 -341.53602) (xy 335.63306 -343.030556) (xy 336.078576 -343.476072) (xy 342.347296 -343.476072)
			(xy 342.372293 -343.476696) (xy 342.421317 -343.486502) (xy 342.467488 -343.505679) (xy 342.509033 -343.533491)
			(xy 342.527128 -343.550748) (xy 342.921061 -343.944632) (xy 344.389706 -343.944632) (xy 344.389706 -343.859936)
			(xy 344.397757 -343.775622) (xy 344.413786 -343.692456) (xy 344.437647 -343.611189) (xy 344.469126 -343.532559)
			(xy 344.507937 -343.457278) (xy 344.553727 -343.386026) (xy 344.606083 -343.31945) (xy 344.664531 -343.258152)
			(xy 344.728541 -343.202687) (xy 344.797533 -343.153558) (xy 344.870883 -343.111209) (xy 344.947926 -343.076025)
			(xy 345.027965 -343.048323) (xy 345.110274 -343.028355) (xy 345.194109 -343.016302) (xy 345.27871 -343.012272)
			(xy 345.363311 -343.016302) (xy 345.447146 -343.028355) (xy 345.529455 -343.048323) (xy 345.609494 -343.076025)
			(xy 345.686537 -343.111209) (xy 345.759887 -343.153558) (xy 345.828879 -343.202687) (xy 345.892889 -343.258152)
			(xy 345.951337 -343.31945) (xy 346.003693 -343.386026) (xy 346.049483 -343.457278) (xy 346.088294 -343.532559)
			(xy 346.119773 -343.611189) (xy 346.143634 -343.692456) (xy 346.159663 -343.775622) (xy 346.167714 -343.859936)
			(xy 346.168218 -343.902284) (xy 346.167714 -343.944632) (xy 346.159663 -344.028946) (xy 346.143634 -344.112112)
			(xy 346.119773 -344.193379) (xy 346.088294 -344.272009) (xy 346.049483 -344.34729) (xy 346.003693 -344.418542)
			(xy 345.951337 -344.485118) (xy 345.892889 -344.546416) (xy 345.828879 -344.601881) (xy 345.759887 -344.65101)
			(xy 345.686537 -344.693359) (xy 345.609494 -344.728543) (xy 345.529455 -344.756245) (xy 345.447146 -344.776213)
			(xy 345.363311 -344.788266) (xy 345.27871 -344.792297) (xy 345.194109 -344.788266) (xy 345.110274 -344.776213)
			(xy 345.027965 -344.756245) (xy 344.947926 -344.728543) (xy 344.870883 -344.693359) (xy 344.797533 -344.65101)
			(xy 344.728541 -344.601881) (xy 344.664531 -344.546416) (xy 344.606083 -344.485118) (xy 344.553727 -344.418542)
			(xy 344.507937 -344.34729) (xy 344.469126 -344.272009) (xy 344.437647 -344.193379) (xy 344.413786 -344.112112)
			(xy 344.397757 -344.028946) (xy 344.389706 -343.944632) (xy 342.921061 -343.944632) (xy 344.582242 -345.605608)
			(xy 345.024456 -345.605608) (xy 345.04945 -345.606275) (xy 345.098471 -345.61607) (xy 345.144642 -345.635235)
			(xy 345.18619 -345.663033) (xy 345.204288 -345.680284) (xy 352.181668 -352.657664) (xy 352.289618 -352.657664)
			(xy 352.304607 -352.657193) (xy 352.333279 -352.648435) (xy 352.358177 -352.631736) (xy 352.377161 -352.608532)
			(xy 352.388597 -352.580819) (xy 352.391502 -352.55098) (xy 352.385627 -352.521582) (xy 352.371476 -352.495152)
			(xy 352.361246 -352.484182) (xy 351.65792 -351.780856) (xy 351.65792 -349.885508) (xy 351.77984 -349.763588)
			(xy 353.420172 -349.763588) (xy 353.420172 -348.939104) (xy 353.041712 -348.560644) (xy 350.492822 -348.560644)
			(xy 350.467826 -348.560004) (xy 350.418803 -348.550203) (xy 350.372632 -348.53103) (xy 350.331086 -348.503223)
			(xy 350.31299 -348.485968) (xy 348.78264 -346.955618) (xy 348.765406 -346.937502) (xy 348.73759 -346.895965)
			(xy 348.718411 -346.8498) (xy 348.708604 -346.800781) (xy 348.707964 -346.775786) (xy 348.707964 -344.39987)
			(xy 348.707401 -344.385192) (xy 348.69901 -344.35706) (xy 348.68296 -344.332479) (xy 348.660578 -344.313483)
			(xy 348.633715 -344.301642) (xy 348.604593 -344.297935) (xy 348.575621 -344.30267) (xy 348.549194 -344.315454)
			(xy 348.527498 -344.335231) (xy 348.519496 -344.347546) (xy 348.498255 -344.381969) (xy 348.450271 -344.447095)
			(xy 348.396412 -344.507451) (xy 348.337147 -344.56251) (xy 348.272997 -344.61179) (xy 348.204522 -344.654859)
			(xy 348.132322 -344.691341) (xy 348.057028 -344.720915) (xy 347.979301 -344.743324) (xy 347.899819 -344.758371)
			(xy 347.819279 -344.765924) (xy 347.778832 -344.766392) (xy 347.73769 -344.765951) (xy 347.655779 -344.758132)
			(xy 347.574982 -344.742563) (xy 347.496031 -344.719383) (xy 347.419641 -344.688804) (xy 347.346504 -344.651101)
			(xy 347.277282 -344.606617) (xy 347.212602 -344.555754) (xy 347.153049 -344.498974) (xy 347.099164 -344.436789)
			(xy 347.051434 -344.369764) (xy 347.010292 -344.298505) (xy 346.976109 -344.223657) (xy 346.949196 -344.1459)
			(xy 346.929797 -344.065936) (xy 346.918086 -343.98449) (xy 346.914171 -343.9023) (xy 346.918086 -343.82011)
			(xy 346.929797 -343.738664) (xy 346.949196 -343.6587) (xy 346.976109 -343.580943) (xy 347.010292 -343.506095)
			(xy 347.051434 -343.434836) (xy 347.099164 -343.367811) (xy 347.153049 -343.305626) (xy 347.212602 -343.248846)
			(xy 347.277282 -343.197983) (xy 347.346504 -343.153499) (xy 347.419641 -343.115796) (xy 347.496031 -343.085217)
			(xy 347.574982 -343.062037) (xy 347.655779 -343.046468) (xy 347.73769 -343.038649) (xy 347.778832 -343.038176)
			(xy 347.819279 -343.038601) (xy 347.899817 -343.04617) (xy 347.979296 -343.061231) (xy 348.05702 -343.08365)
			(xy 348.13231 -343.113233) (xy 348.204507 -343.149719) (xy 348.27298 -343.192791) (xy 348.337129 -343.242072)
			(xy 348.396394 -343.29713) (xy 348.450257 -343.357483) (xy 348.498245 -343.422605) (xy 348.519496 -343.457022)
			(xy 348.52749 -343.469367) (xy 348.549177 -343.489214) (xy 348.575623 -343.502053) (xy 348.604631 -343.50682)
			(xy 348.633795 -343.503119) (xy 348.660693 -343.491256) (xy 348.683092 -343.472218) (xy 348.699135 -343.447583)
			(xy 348.707488 -343.419397) (xy 348.707964 -343.404698) (xy 348.707964 -342.25103) (xy 347.756988 -341.2998)
			(xy 343.989406 -341.2998) (xy 343.964425 -341.299152) (xy 343.915419 -341.289418) (xy 343.86925 -341.270321)
			(xy 343.827687 -341.242594) (xy 343.809574 -341.225378) (xy 343.049606 -340.46541) (xy 343.032384 -340.4473)
			(xy 343.00464 -340.405742) (xy 342.985532 -340.359572) (xy 342.975793 -340.310562) (xy 342.975184 -340.285578)
			(xy 342.975184 -338.669122) (xy 342.974802 -338.659661) (xy 342.967894 -338.642044) (xy 342.95508 -338.628118)
			(xy 342.938096 -338.619772) (xy 342.928702 -338.618576) (xy 342.900451 -338.615728) (xy 342.845198 -338.602652)
			(xy 342.792491 -338.581534) (xy 342.743495 -338.55284) (xy 342.699291 -338.517204) (xy 342.660854 -338.475412)
			(xy 342.629032 -338.428387) (xy 342.60453 -338.377166) (xy 342.587885 -338.32288) (xy 342.579468 -338.266728)
			(xy 342.578944 -338.238338) (xy 342.579509 -338.20865) (xy 342.588703 -338.149991) (xy 342.606875 -338.093464)
			(xy 342.633587 -338.040436) (xy 342.668192 -337.992187) (xy 342.709855 -337.949883) (xy 342.733376 -337.93176)
			(xy 342.74396 -337.923305) (xy 342.760672 -337.902001) (xy 342.771195 -337.877053) (xy 342.77479 -337.850216)
			(xy 342.771204 -337.823377) (xy 342.760688 -337.798426) (xy 342.743982 -337.777116) (xy 342.733376 -337.768692)
			(xy 342.709857 -337.750567) (xy 342.668198 -337.70826) (xy 342.633595 -337.660011) (xy 342.606884 -337.606984)
			(xy 342.588709 -337.550459) (xy 342.57951 -337.491801) (xy 342.578944 -337.462114) (xy 342.579503 -337.434852)
			(xy 342.587264 -337.380884) (xy 342.602629 -337.328571) (xy 342.625287 -337.278978) (xy 342.654774 -337.233117)
			(xy 342.690491 -337.191921) (xy 342.731709 -337.15623) (xy 342.777589 -337.126772) (xy 342.827196 -337.104145)
			(xy 342.879519 -337.088813) (xy 342.933492 -337.081086) (xy 342.988015 -337.081122) (xy 343.041978 -337.088921)
			(xy 343.09428 -337.104323) (xy 343.143857 -337.127016) (xy 343.189698 -337.156535) (xy 343.230868 -337.192281)
			(xy 343.26653 -337.233524) (xy 343.295957 -337.279425) (xy 343.318548 -337.329048) (xy 343.333844 -337.381381)
			(xy 343.341533 -337.43536) (xy 343.34196 -337.462622) (xy 343.34196 -337.483958) (xy 343.441528 -337.583526)
			(xy 343.452567 -337.593722) (xy 343.479083 -337.607823) (xy 343.508552 -337.61361) (xy 343.538432 -337.610583)
			(xy 343.566142 -337.599003) (xy 343.589291 -337.579869) (xy 343.60588 -337.554835) (xy 343.610692 -337.5406)
			(xy 343.618913 -337.514697) (xy 343.641679 -337.465351) (xy 343.671214 -337.419733) (xy 343.706922 -337.378767)
			(xy 343.748081 -337.34328) (xy 343.793857 -337.313991) (xy 343.843324 -337.291491) (xy 343.895484 -337.276236)
			(xy 343.94928 -337.268534) (xy 343.976452 -337.268058) (xy 343.976706 -337.268058) (xy 344.00191 -337.268452)
			(xy 344.051878 -337.275093) (xy 344.100533 -337.288271) (xy 344.147022 -337.307756) (xy 344.168984 -337.320128)
			(xy 344.181966 -337.327134) (xy 344.210596 -337.334177) (xy 344.240045 -337.33274) (xy 344.267854 -337.322944)
			(xy 344.291702 -337.305606) (xy 344.309598 -337.282175) (xy 344.315288 -337.268566) (xy 344.325959 -337.241779)
			(xy 344.354252 -337.191538) (xy 344.389785 -337.146129) (xy 344.431751 -337.106587) (xy 344.479192 -337.073815)
			(xy 344.531026 -337.048559) (xy 344.586072 -337.031395) (xy 344.643074 -337.022715) (xy 344.671904 -337.022186)
			(xy 344.699155 -337.022674) (xy 344.753102 -337.030431) (xy 344.805397 -337.045786) (xy 344.854974 -337.068427)
			(xy 344.900824 -337.097894) (xy 344.942014 -337.133585) (xy 344.977705 -337.174775) (xy 345.007172 -337.220625)
			(xy 345.016538 -337.241134) (xy 347.15958 -337.241134) (xy 347.160076 -337.213561) (xy 347.168023 -337.158989)
			(xy 347.183743 -337.10613) (xy 347.206907 -337.056085) (xy 347.237034 -337.009894) (xy 347.273496 -336.968521)
			(xy 347.2942 -336.950304) (xy 347.305063 -336.940371) (xy 347.321136 -336.91573) (xy 347.329523 -336.887532)
			(xy 347.32953 -336.858112) (xy 347.321155 -336.82991) (xy 347.305092 -336.805263) (xy 347.2942 -336.795364)
			(xy 347.273468 -336.777175) (xy 347.237 -336.735802) (xy 347.20687 -336.689607) (xy 347.183708 -336.639555)
			(xy 347.167996 -336.586688) (xy 347.160062 -336.53211) (xy 347.15958 -336.504534) (xy 347.160087 -336.477283)
			(xy 347.167839 -336.423334) (xy 347.18319 -336.371037) (xy 347.205828 -336.321458) (xy 347.235291 -336.275606)
			(xy 347.27098 -336.234413) (xy 347.312169 -336.198719) (xy 347.358018 -336.16925) (xy 347.407594 -336.146606)
			(xy 347.459889 -336.131249) (xy 347.513837 -336.12349) (xy 347.541088 -336.123026) (xy 347.575378 -336.12455)
			(xy 347.588737 -336.125329) (xy 347.615099 -336.120819) (xy 347.639377 -336.109598) (xy 347.659895 -336.092442)
			(xy 347.675237 -336.070533) (xy 347.684343 -336.045386) (xy 347.685868 -336.032094) (xy 347.688871 -336.003927)
			(xy 347.702039 -335.948837) (xy 347.723211 -335.896301) (xy 347.751922 -335.847475) (xy 347.78754 -335.803434)
			(xy 347.829282 -335.765146) (xy 347.876228 -335.733455) (xy 347.927346 -335.709058) (xy 347.981511 -335.692491)
			(xy 348.037531 -335.684119) (xy 348.065852 -335.683606) (xy 348.083871 -335.683823) (xy 348.119746 -335.68726)
			(xy 348.13748 -335.690464) (xy 348.152691 -335.692778) (xy 348.183241 -335.689255) (xy 348.211358 -335.6768)
			(xy 348.234494 -335.65654) (xy 348.250551 -335.630313) (xy 348.254828 -335.615534) (xy 348.262201 -335.588483)
			(xy 348.283834 -335.536756) (xy 348.312802 -335.48875) (xy 348.348481 -335.445499) (xy 348.390103 -335.407933)
			(xy 348.436774 -335.37686) (xy 348.487488 -335.352948) (xy 348.541154 -335.336713) (xy 348.596618 -335.328504)
			(xy 348.624652 -335.328006) (xy 348.651904 -335.3285) (xy 348.705855 -335.336251) (xy 348.758153 -335.351601)
			(xy 348.807734 -335.374239) (xy 348.853588 -335.403704) (xy 348.894782 -335.439394) (xy 348.930476 -335.480585)
			(xy 348.959944 -335.526436) (xy 348.982587 -335.576015) (xy 348.983463 -335.579) (xy 353.390417 -335.579)
			(xy 353.394585 -335.523382) (xy 353.406996 -335.469006) (xy 353.427372 -335.417087) (xy 353.455258 -335.368785)
			(xy 353.490031 -335.325178) (xy 353.530916 -335.287241) (xy 353.576997 -335.255821) (xy 353.627247 -335.23162)
			(xy 353.680542 -335.215178) (xy 353.735693 -335.206862) (xy 353.76358 -335.20634) (xy 353.790913 -335.206792)
			(xy 353.844993 -335.214765) (xy 353.897328 -335.230556) (xy 353.946793 -335.253827) (xy 353.992325 -335.284078)
			(xy 354.032946 -335.320659) (xy 354.067785 -335.362784) (xy 354.08235 -335.385918) (xy 354.090244 -335.398163)
			(xy 354.111724 -335.417832) (xy 354.137885 -335.430633) (xy 354.166597 -335.435523) (xy 354.195521 -335.432104)
			(xy 354.209096 -335.426812) (xy 354.23231 -335.417332) (xy 354.280641 -335.403977) (xy 354.330329 -335.397245)
			(xy 354.3554 -335.39684) (xy 354.380469 -335.397275) (xy 354.430152 -335.40402) (xy 354.478486 -335.417348)
			(xy 354.501704 -335.426812) (xy 354.515304 -335.431992) (xy 354.544193 -335.435371) (xy 354.572863 -335.430475)
			(xy 354.598994 -335.417702) (xy 354.620468 -335.398086) (xy 354.62845 -335.385918) (xy 354.643019 -335.362787)
			(xy 354.677862 -335.320666) (xy 354.718485 -335.284087) (xy 354.764016 -335.253836) (xy 354.813478 -335.23056)
			(xy 354.865809 -335.21476) (xy 354.919888 -335.206774) (xy 354.974552 -335.206774) (xy 355.028631 -335.21476)
			(xy 355.080962 -335.23056) (xy 355.130424 -335.253836) (xy 355.175955 -335.284087) (xy 355.216578 -335.320666)
			(xy 355.251421 -335.362787) (xy 355.26599 -335.385918) (xy 355.273941 -335.398122) (xy 355.295405 -335.417791)
			(xy 355.321551 -335.430597) (xy 355.350249 -335.435498) (xy 355.379163 -335.432094) (xy 355.392736 -335.426812)
			(xy 355.415945 -335.41732) (xy 355.464278 -335.403969) (xy 355.513968 -335.397243) (xy 355.53904 -335.39684)
			(xy 355.56588 -335.397387) (xy 355.619004 -335.405082) (xy 355.670475 -335.420321) (xy 355.719225 -335.442789)
			(xy 355.764247 -335.472021) (xy 355.804608 -335.507411) (xy 355.839472 -335.548227) (xy 355.868118 -335.593623)
			(xy 355.889952 -335.642661) (xy 355.897688 -335.668366) (xy 355.902375 -335.682854) (xy 355.91889 -335.708414)
			(xy 355.9422 -335.727978) (xy 355.970239 -335.739808) (xy 356.000517 -335.742857) (xy 356.030351 -335.736853)
			(xy 356.043992 -335.730088) (xy 356.072132 -335.715442) (xy 356.132086 -335.694719) (xy 356.194647 -335.684226)
			(xy 356.226364 -335.683606) (xy 356.244384 -335.683822) (xy 356.280258 -335.687259) (xy 356.297992 -335.690464)
			(xy 356.313202 -335.69279) (xy 356.343753 -335.689265) (xy 356.371871 -335.676806) (xy 356.395007 -335.656544)
			(xy 356.411064 -335.630314) (xy 356.41534 -335.615534) (xy 356.422702 -335.588479) (xy 356.444336 -335.536752)
			(xy 356.473305 -335.488746) (xy 356.508985 -335.445495) (xy 356.550609 -335.407928) (xy 356.597281 -335.376856)
			(xy 356.647996 -335.352945) (xy 356.701664 -335.336711) (xy 356.757129 -335.328503) (xy 356.785164 -335.328006)
			(xy 356.812417 -335.328489) (xy 356.866368 -335.336241) (xy 356.918666 -335.351593) (xy 356.968247 -335.374233)
			(xy 357.014101 -335.403698) (xy 357.055294 -335.43939) (xy 357.090988 -335.480582) (xy 357.120457 -335.526434)
			(xy 357.143099 -335.576013) (xy 357.143976 -335.579) (xy 361.550917 -335.579) (xy 361.555086 -335.523381)
			(xy 361.567497 -335.469004) (xy 361.587873 -335.417084) (xy 361.61576 -335.368781) (xy 361.650535 -335.325174)
			(xy 361.691421 -335.287237) (xy 361.737504 -335.255817) (xy 361.787755 -335.231616) (xy 361.841052 -335.215175)
			(xy 361.896204 -335.206862) (xy 361.924092 -335.20634) (xy 361.951425 -335.206783) (xy 362.005506 -335.214757)
			(xy 362.057841 -335.23055) (xy 362.107306 -335.253822) (xy 362.152838 -335.284075) (xy 362.193459 -335.320657)
			(xy 362.228297 -335.362784) (xy 362.242862 -335.385918) (xy 362.250744 -335.398171) (xy 362.272228 -335.417841)
			(xy 362.298392 -335.43064) (xy 362.327106 -335.435528) (xy 362.356032 -335.432105) (xy 362.369608 -335.426812)
			(xy 362.39282 -335.417328) (xy 362.441152 -335.403975) (xy 362.490841 -335.397244) (xy 362.515912 -335.39684)
			(xy 362.540981 -335.397271) (xy 362.590664 -335.404017) (xy 362.638998 -335.417347) (xy 362.662216 -335.426812)
			(xy 362.675812 -335.432005) (xy 362.704703 -335.435381) (xy 362.733375 -335.430482) (xy 362.759506 -335.417706)
			(xy 362.78098 -335.398087) (xy 362.788962 -335.385918) (xy 362.803531 -335.362787) (xy 362.838374 -335.320666)
			(xy 362.878997 -335.284087) (xy 362.924528 -335.253836) (xy 362.97399 -335.23056) (xy 363.026321 -335.21476)
			(xy 363.0804 -335.206774) (xy 363.135064 -335.206774) (xy 363.189143 -335.21476) (xy 363.241474 -335.23056)
			(xy 363.290936 -335.253836) (xy 363.336467 -335.284087) (xy 363.37709 -335.320666) (xy 363.411933 -335.362787)
			(xy 363.426502 -335.385918) (xy 363.434441 -335.39813) (xy 363.455909 -335.417799) (xy 363.482058 -335.430604)
			(xy 363.510759 -335.435503) (xy 363.539675 -335.432096) (xy 363.553248 -335.426812) (xy 363.576455 -335.417316)
			(xy 363.624789 -335.403967) (xy 363.67448 -335.397242) (xy 363.699552 -335.39684) (xy 363.726392 -335.397376)
			(xy 363.779517 -335.405073) (xy 363.830988 -335.420314) (xy 363.879739 -335.442783) (xy 363.92476 -335.472016)
			(xy 363.965121 -335.507407) (xy 363.999985 -335.548224) (xy 364.02863 -335.593622) (xy 364.050464 -335.642661)
			(xy 364.0582 -335.668366) (xy 364.062871 -335.68286) (xy 364.079389 -335.708422) (xy 364.102703 -335.727986)
			(xy 364.130744 -335.739816) (xy 364.161026 -335.742862) (xy 364.190862 -335.736855) (xy 364.204504 -335.730088)
			(xy 364.232659 -335.715474) (xy 364.292606 -335.69474) (xy 364.35516 -335.684233) (xy 364.386876 -335.683606)
			(xy 364.404896 -335.68382) (xy 364.44077 -335.687259) (xy 364.458504 -335.690464) (xy 364.473713 -335.692802)
			(xy 364.504265 -335.689273) (xy 364.532384 -335.676812) (xy 364.555519 -335.656547) (xy 364.571576 -335.630315)
			(xy 364.575852 -335.615534) (xy 364.583203 -335.588476) (xy 364.604838 -335.536748) (xy 364.633808 -335.488742)
			(xy 364.66949 -335.44549) (xy 364.711115 -335.407924) (xy 364.757788 -335.376851) (xy 364.808505 -335.352942)
			(xy 364.862174 -335.336709) (xy 364.917641 -335.328502) (xy 364.945676 -335.328006) (xy 364.972929 -335.328478)
			(xy 365.02688 -335.336232) (xy 365.079179 -335.351585) (xy 365.12876 -335.374226) (xy 365.174614 -335.403693)
			(xy 365.215807 -335.439386) (xy 365.251501 -335.480578) (xy 365.280969 -335.526431) (xy 365.303611 -335.576012)
			(xy 365.304488 -335.579) (xy 369.711391 -335.579) (xy 369.71556 -335.523376) (xy 369.727972 -335.468994)
			(xy 369.748351 -335.41707) (xy 369.776242 -335.368763) (xy 369.81102 -335.325152) (xy 369.85191 -335.287212)
			(xy 369.897998 -335.255791) (xy 369.948254 -335.231589) (xy 370.001557 -335.215148) (xy 370.056714 -335.206835)
			(xy 370.084604 -335.20634) (xy 370.111937 -335.206773) (xy 370.166019 -335.214749) (xy 370.218354 -335.230543)
			(xy 370.267819 -335.253818) (xy 370.313351 -335.284071) (xy 370.353972 -335.320655) (xy 370.38881 -335.362783)
			(xy 370.403374 -335.385918) (xy 370.41134 -335.398111) (xy 370.4328 -335.41778) (xy 370.458942 -335.430588)
			(xy 370.487637 -335.435491) (xy 370.516548 -335.432092) (xy 370.53012 -335.426812) (xy 370.553331 -335.417325)
			(xy 370.601663 -335.403973) (xy 370.651352 -335.397244) (xy 370.676424 -335.39684) (xy 370.701493 -335.397267)
			(xy 370.751176 -335.404015) (xy 370.799511 -335.417346) (xy 370.822728 -335.426812) (xy 370.836319 -335.432017)
			(xy 370.865212 -335.435391) (xy 370.893886 -335.430489) (xy 370.920018 -335.41771) (xy 370.941493 -335.398088)
			(xy 370.949474 -335.385918) (xy 370.964043 -335.362787) (xy 370.998886 -335.320666) (xy 371.039509 -335.284087)
			(xy 371.08504 -335.253836) (xy 371.134502 -335.23056) (xy 371.186833 -335.21476) (xy 371.240912 -335.206774)
			(xy 371.295576 -335.206774) (xy 371.349655 -335.21476) (xy 371.401986 -335.23056) (xy 371.451448 -335.253836)
			(xy 371.496979 -335.284087) (xy 371.537602 -335.320666) (xy 371.572445 -335.362787) (xy 371.587014 -335.385918)
			(xy 371.594942 -335.398139) (xy 371.616413 -335.417808) (xy 371.642565 -335.430612) (xy 371.671268 -335.435508)
			(xy 371.700186 -335.432098) (xy 371.71376 -335.426812) (xy 371.736966 -335.417312) (xy 371.785301 -335.403965)
			(xy 371.834992 -335.397241) (xy 371.860064 -335.39684) (xy 371.887949 -335.397417) (xy 371.943098 -335.405724)
			(xy 371.996392 -335.422159) (xy 372.046641 -335.446353) (xy 372.092723 -335.477767) (xy 372.133608 -335.515699)
			(xy 372.168382 -335.5593) (xy 372.196269 -335.607598) (xy 372.216645 -335.659513) (xy 372.229056 -335.713885)
			(xy 372.233224 -335.7695) (xy 372.229056 -335.825115) (xy 372.216645 -335.879487) (xy 372.196269 -335.931402)
			(xy 372.168382 -335.9797) (xy 372.133608 -336.023301) (xy 372.092723 -336.061233) (xy 372.046641 -336.092647)
			(xy 371.996392 -336.116841) (xy 371.943098 -336.133276) (xy 371.887949 -336.141583) (xy 371.860064 -336.142076)
			(xy 371.832733 -336.141582) (xy 371.778654 -336.133616) (xy 371.726321 -336.117831) (xy 371.676857 -336.094567)
			(xy 371.631324 -336.064323) (xy 371.590701 -336.027748) (xy 371.55586 -335.985629) (xy 371.541294 -335.962498)
			(xy 371.533355 -335.950285) (xy 371.511888 -335.930614) (xy 371.485739 -335.917808) (xy 371.457037 -335.91291)
			(xy 371.428121 -335.916318) (xy 371.414548 -335.921604) (xy 371.391341 -335.931102) (xy 371.343007 -335.94445)
			(xy 371.293316 -335.951174) (xy 371.268244 -335.951576) (xy 371.243174 -335.951158) (xy 371.193491 -335.944406)
			(xy 371.145157 -335.931071) (xy 371.12194 -335.921604) (xy 371.108362 -335.916358) (xy 371.079462 -335.912991)
			(xy 371.050783 -335.917901) (xy 371.024648 -335.93069) (xy 371.003174 -335.950323) (xy 370.995194 -335.962498)
			(xy 370.980625 -335.985629) (xy 370.945782 -336.02775) (xy 370.905159 -336.064329) (xy 370.859628 -336.09458)
			(xy 370.810166 -336.117856) (xy 370.757835 -336.133656) (xy 370.703756 -336.141642) (xy 370.649092 -336.141642)
			(xy 370.595013 -336.133656) (xy 370.542682 -336.117856) (xy 370.49322 -336.09458) (xy 370.447689 -336.064329)
			(xy 370.407066 -336.02775) (xy 370.372223 -335.985629) (xy 370.357654 -335.962498) (xy 370.349753 -335.950258)
			(xy 370.328276 -335.930587) (xy 370.302116 -335.917784) (xy 370.273406 -335.912893) (xy 370.244483 -335.916312)
			(xy 370.230908 -335.921604) (xy 370.207694 -335.931084) (xy 370.159363 -335.944438) (xy 370.109675 -335.95117)
			(xy 370.084604 -335.951576) (xy 370.056714 -335.951165) (xy 370.001557 -335.942852) (xy 369.948254 -335.926411)
			(xy 369.897998 -335.902209) (xy 369.85191 -335.870788) (xy 369.81102 -335.832848) (xy 369.776242 -335.789237)
			(xy 369.748351 -335.74093) (xy 369.727972 -335.689006) (xy 369.71556 -335.634624) (xy 369.711391 -335.579)
			(xy 365.304488 -335.579) (xy 365.318966 -335.62831) (xy 365.326722 -335.682261) (xy 365.327184 -335.709514)
			(xy 365.326665 -335.737087) (xy 365.318724 -335.791657) (xy 365.30301 -335.844517) (xy 365.27985 -335.894563)
			(xy 365.249727 -335.940754) (xy 365.213267 -335.982127) (xy 365.192564 -336.000344) (xy 365.181647 -336.010225)
			(xy 365.165566 -336.034878) (xy 365.157178 -336.063092) (xy 365.157181 -336.092526) (xy 365.165573 -336.120739)
			(xy 365.181659 -336.145388) (xy 365.192564 -336.155284) (xy 365.213285 -336.173484) (xy 365.249752 -336.214856)
			(xy 365.279881 -336.261047) (xy 365.303045 -336.311096) (xy 365.318761 -336.363959) (xy 365.326701 -336.418534)
			(xy 365.326699 -336.473684) (xy 365.318757 -336.528258) (xy 365.303039 -336.581121) (xy 365.279872 -336.631168)
			(xy 365.249741 -336.677359) (xy 365.213272 -336.718729) (xy 365.192564 -336.736944) (xy 365.181647 -336.746825)
			(xy 365.165566 -336.771478) (xy 365.157178 -336.799692) (xy 365.157181 -336.829126) (xy 365.165573 -336.857339)
			(xy 365.181659 -336.881988) (xy 365.192564 -336.891884) (xy 365.213263 -336.910108) (xy 365.249736 -336.951473)
			(xy 365.279871 -336.99766) (xy 365.303039 -337.047706) (xy 365.318757 -337.100566) (xy 365.326698 -337.15514)
			(xy 365.327184 -337.182714) (xy 365.326758 -337.209968) (xy 365.318999 -337.263922) (xy 365.312332 -337.286625)
			(xy 365.717275 -337.286625) (xy 365.717279 -337.232123) (xy 365.725039 -337.178175) (xy 365.740398 -337.125881)
			(xy 365.763043 -337.076305) (xy 365.792513 -337.030457) (xy 365.828207 -336.989269) (xy 365.8694 -336.95358)
			(xy 365.915253 -336.924117) (xy 365.964832 -336.901479) (xy 366.017128 -336.886128) (xy 366.071077 -336.878375)
			(xy 366.098328 -336.877914) (xy 366.113057 -336.878063) (xy 366.142427 -336.880351) (xy 366.157002 -336.882486)
			(xy 366.171557 -336.88423) (xy 366.200601 -336.880377) (xy 366.227353 -336.86843) (xy 366.249607 -336.849374)
			(xy 366.265529 -336.82478) (xy 366.273806 -336.796675) (xy 366.273755 -336.767376) (xy 366.270032 -336.7532)
			(xy 366.262676 -336.726691) (xy 366.254769 -336.672249) (xy 366.254284 -336.644742) (xy 366.25471 -336.617485)
			(xy 366.262462 -336.563526) (xy 366.277815 -336.511219) (xy 366.300456 -336.46163) (xy 366.329924 -336.415768)
			(xy 366.365619 -336.374566) (xy 366.406814 -336.338864) (xy 366.452671 -336.309388) (xy 366.502256 -336.286739)
			(xy 366.55456 -336.271377) (xy 366.608518 -336.263615) (xy 366.663031 -336.263611) (xy 366.71699 -336.271366)
			(xy 366.769296 -336.286721) (xy 366.818885 -336.309364) (xy 366.864745 -336.338834) (xy 366.905946 -336.37453)
			(xy 366.941646 -336.415727) (xy 366.97112 -336.461586) (xy 366.993767 -336.511172) (xy 367.009127 -336.563476)
			(xy 367.016886 -336.617435) (xy 367.016888 -336.671948) (xy 367.009131 -336.725907) (xy 366.993773 -336.778212)
			(xy 366.971128 -336.827799) (xy 366.941656 -336.873659) (xy 366.905958 -336.914857) (xy 366.864759 -336.950556)
			(xy 366.8189 -336.980028) (xy 366.769313 -337.002673) (xy 366.717007 -337.01803) (xy 366.663049 -337.025788)
			(xy 366.635792 -337.02625) (xy 366.621063 -337.026099) (xy 366.591693 -337.023813) (xy 366.577118 -337.021678)
			(xy 366.562577 -337.019774) (xy 366.533512 -337.023648) (xy 366.506747 -337.03562) (xy 366.484486 -337.054704)
			(xy 366.468564 -337.079326) (xy 366.460293 -337.107457) (xy 366.460356 -337.136778) (xy 366.464088 -337.150964)
			(xy 366.471458 -337.17747) (xy 366.479357 -337.231915) (xy 366.479836 -337.259422) (xy 366.479321 -337.286673)
			(xy 366.471561 -337.340621) (xy 366.456203 -337.392915) (xy 366.433559 -337.442491) (xy 366.40409 -337.48834)
			(xy 366.368396 -337.529528) (xy 366.327203 -337.565217) (xy 366.281351 -337.594681) (xy 366.231772 -337.617319)
			(xy 366.179476 -337.632671) (xy 366.125527 -337.640424) (xy 366.071025 -337.640421) (xy 366.017077 -337.632661)
			(xy 365.964783 -337.617302) (xy 365.915207 -337.594658) (xy 365.869358 -337.565189) (xy 365.82817 -337.529494)
			(xy 365.792481 -337.488301) (xy 365.763018 -337.442449) (xy 365.74038 -337.39287) (xy 365.725028 -337.340574)
			(xy 365.717275 -337.286625) (xy 365.312332 -337.286625) (xy 365.30364 -337.316222) (xy 365.280994 -337.365804)
			(xy 365.251522 -337.411658) (xy 365.215824 -337.452851) (xy 365.174628 -337.488545) (xy 365.12877 -337.518012)
			(xy 365.079186 -337.540653) (xy 365.026885 -337.556007) (xy 364.97293 -337.563761) (xy 364.945676 -337.564222)
			(xy 364.917821 -337.563704) (xy 364.862706 -337.555578) (xy 364.809356 -337.53953) (xy 364.758904 -337.515902)
			(xy 364.71242 -337.485194) (xy 364.670891 -337.448059) (xy 364.635198 -337.405284) (xy 364.606098 -337.357777)
			(xy 364.584209 -337.306547) (xy 364.576614 -337.279742) (xy 364.572272 -337.26565) (xy 364.556899 -337.240508)
			(xy 364.534998 -337.22079) (xy 364.508385 -337.208132) (xy 364.479268 -337.203584) (xy 364.4646 -337.205066)
			(xy 364.451583 -337.206734) (xy 364.425399 -337.208514) (xy 364.412276 -337.208622) (xy 364.398127 -337.208531)
			(xy 364.369904 -337.206495) (xy 364.355888 -337.204558) (xy 364.342533 -337.203057) (xy 364.315853 -337.206144)
			(xy 364.290907 -337.216099) (xy 364.26943 -337.232227) (xy 364.252916 -337.253409) (xy 364.242512 -337.278171)
			(xy 364.240318 -337.291426) (xy 364.236214 -337.318577) (xy 364.221244 -337.371407) (xy 364.198855 -337.421545)
			(xy 364.169509 -337.467956) (xy 364.133814 -337.509681) (xy 364.092506 -337.545858) (xy 364.046438 -337.57574)
			(xy 363.996563 -337.598709) (xy 363.94391 -337.614291) (xy 363.889567 -337.622164) (xy 363.862112 -337.622642)
			(xy 363.834863 -337.622111) (xy 363.780918 -337.614357) (xy 363.728627 -337.599005) (xy 363.679052 -337.576368)
			(xy 363.633203 -337.546906) (xy 363.592014 -337.511219) (xy 363.556322 -337.470034) (xy 363.526855 -337.424189)
			(xy 363.504211 -337.374617) (xy 363.488853 -337.322327) (xy 363.481093 -337.268383) (xy 363.480604 -337.241134)
			(xy 363.481092 -337.21356) (xy 363.48904 -337.158988) (xy 363.50476 -337.106129) (xy 363.527926 -337.056083)
			(xy 363.558055 -337.009893) (xy 363.594519 -336.96852) (xy 363.615224 -336.950304) (xy 363.626084 -336.940369)
			(xy 363.642154 -336.915728) (xy 363.650539 -336.887531) (xy 363.650546 -336.858113) (xy 363.642173 -336.829912)
			(xy 363.626114 -336.805264) (xy 363.615224 -336.795364) (xy 363.594497 -336.77717) (xy 363.558027 -336.735798)
			(xy 363.527896 -336.689605) (xy 363.504733 -336.639553) (xy 363.48902 -336.586688) (xy 363.481086 -336.53211)
			(xy 363.480604 -336.504534) (xy 363.481038 -336.478032) (xy 363.488387 -336.42554) (xy 363.502936 -336.374572)
			(xy 363.524404 -336.32611) (xy 363.552377 -336.281088) (xy 363.568996 -336.26044) (xy 363.578467 -336.248313)
			(xy 363.590263 -336.219907) (xy 363.593087 -336.189278) (xy 363.586685 -336.159193) (xy 363.571635 -336.132369)
			(xy 363.549295 -336.111226) (xy 363.535722 -336.103976) (xy 363.512025 -336.091888) (xy 363.468045 -336.061961)
			(xy 363.428765 -336.026086) (xy 363.394984 -335.984992) (xy 363.380782 -335.962498) (xy 363.372854 -335.950277)
			(xy 363.351384 -335.930606) (xy 363.325232 -335.917801) (xy 363.296528 -335.912905) (xy 363.26761 -335.916317)
			(xy 363.254036 -335.921604) (xy 363.230819 -335.931075) (xy 363.18249 -335.944433) (xy 363.132803 -335.951169)
			(xy 363.107732 -335.951576) (xy 363.082662 -335.951162) (xy 363.032979 -335.944408) (xy 362.984645 -335.931072)
			(xy 362.961428 -335.921604) (xy 362.947855 -335.916345) (xy 362.918952 -335.912981) (xy 362.890271 -335.917894)
			(xy 362.864136 -335.930686) (xy 362.842662 -335.950321) (xy 362.834682 -335.962498) (xy 362.820113 -335.985629)
			(xy 362.78527 -336.02775) (xy 362.744647 -336.064329) (xy 362.699116 -336.09458) (xy 362.649654 -336.117856)
			(xy 362.597323 -336.133656) (xy 362.543244 -336.141642) (xy 362.48858 -336.141642) (xy 362.434501 -336.133656)
			(xy 362.38217 -336.117856) (xy 362.332708 -336.09458) (xy 362.287177 -336.064329) (xy 362.246554 -336.02775)
			(xy 362.211711 -335.985629) (xy 362.197142 -335.962498) (xy 362.189252 -335.95025) (xy 362.167772 -335.930579)
			(xy 362.141609 -335.917777) (xy 362.112896 -335.912888) (xy 362.083971 -335.916311) (xy 362.070396 -335.921604)
			(xy 362.047184 -335.931087) (xy 361.998852 -335.944441) (xy 361.949163 -335.951171) (xy 361.924092 -335.951576)
			(xy 361.896204 -335.951138) (xy 361.841052 -335.942825) (xy 361.787755 -335.926384) (xy 361.737504 -335.902183)
			(xy 361.691421 -335.870763) (xy 361.650535 -335.832826) (xy 361.61576 -335.789219) (xy 361.587873 -335.740916)
			(xy 361.567497 -335.688996) (xy 361.555086 -335.634619) (xy 361.550917 -335.579) (xy 357.143976 -335.579)
			(xy 357.158454 -335.628311) (xy 357.16621 -335.682261) (xy 357.166672 -335.709514) (xy 357.166157 -335.737087)
			(xy 357.158216 -335.791658) (xy 357.142501 -335.844517) (xy 357.119341 -335.894564) (xy 357.089216 -335.940755)
			(xy 357.052756 -335.982127) (xy 357.032052 -336.000344) (xy 357.021136 -336.010226) (xy 357.005057 -336.034879)
			(xy 356.99667 -336.063092) (xy 356.996673 -336.092526) (xy 357.005064 -336.120738) (xy 357.021148 -336.145388)
			(xy 357.032052 -336.155284) (xy 357.052774 -336.173483) (xy 357.089241 -336.214855) (xy 357.119372 -336.261047)
			(xy 357.142536 -336.311096) (xy 357.158253 -336.363959) (xy 357.166193 -336.418534) (xy 357.166192 -336.473684)
			(xy 357.158249 -336.528259) (xy 357.14253 -336.581121) (xy 357.119363 -336.631169) (xy 357.08923 -336.67736)
			(xy 357.052761 -336.718729) (xy 357.032052 -336.736944) (xy 357.021136 -336.746826) (xy 357.005057 -336.771479)
			(xy 356.99667 -336.799692) (xy 356.996673 -336.829126) (xy 357.005064 -336.857338) (xy 357.021148 -336.881988)
			(xy 357.032052 -336.891884) (xy 357.052749 -336.910111) (xy 357.089222 -336.951475) (xy 357.119358 -336.997661)
			(xy 357.142526 -337.047706) (xy 357.158245 -337.100567) (xy 357.166186 -337.15514) (xy 357.166672 -337.182714)
			(xy 357.166258 -337.209969) (xy 357.160641 -337.249022) (xy 357.497106 -337.249022) (xy 357.49711 -337.194524)
			(xy 357.50487 -337.140581) (xy 357.520227 -337.088292) (xy 357.54287 -337.03872) (xy 357.572337 -336.992875)
			(xy 357.608029 -336.951691) (xy 357.649218 -336.916005) (xy 357.695067 -336.886545) (xy 357.744642 -336.863909)
			(xy 357.796933 -336.848559) (xy 357.850877 -336.840806) (xy 357.878126 -336.840322) (xy 357.903517 -336.840764)
			(xy 357.953848 -336.847513) (xy 357.978456 -336.853784) (xy 357.993101 -336.857224) (xy 358.023156 -336.856294)
			(xy 358.051639 -336.846659) (xy 358.076088 -336.829153) (xy 358.094384 -336.805291) (xy 358.104946 -336.777137)
			(xy 358.106859 -336.747129) (xy 358.103932 -336.732372) (xy 358.099164 -336.71078) (xy 358.094072 -336.666853)
			(xy 358.093772 -336.644742) (xy 358.09421 -336.617485) (xy 358.101962 -336.563526) (xy 358.117315 -336.511219)
			(xy 358.139957 -336.461629) (xy 358.169425 -336.415767) (xy 358.20512 -336.374565) (xy 358.246316 -336.338863)
			(xy 358.292173 -336.309387) (xy 358.341759 -336.286738) (xy 358.394064 -336.271376) (xy 358.448022 -336.263615)
			(xy 358.502536 -336.263611) (xy 358.556495 -336.271367) (xy 358.608801 -336.286723) (xy 358.658389 -336.309366)
			(xy 358.70425 -336.338837) (xy 358.74545 -336.374535) (xy 358.78115 -336.415732) (xy 358.810623 -336.461592)
			(xy 358.83327 -336.511179) (xy 358.848628 -336.563484) (xy 358.856387 -336.617443) (xy 358.856387 -336.671956)
			(xy 358.848629 -336.725915) (xy 358.83327 -336.77822) (xy 358.810624 -336.827807) (xy 358.781151 -336.873667)
			(xy 358.745451 -336.914864) (xy 358.704251 -336.950562) (xy 358.65839 -336.980033) (xy 358.608802 -337.002677)
			(xy 358.556496 -337.018033) (xy 358.502537 -337.025788) (xy 358.47528 -337.02625) (xy 358.449889 -337.025807)
			(xy 358.399558 -337.019059) (xy 358.37495 -337.012788) (xy 358.360298 -337.009388) (xy 358.330251 -337.010317)
			(xy 358.301774 -337.019948) (xy 358.27733 -337.037447) (xy 358.259034 -337.061301) (xy 358.24847 -337.089446)
			(xy 358.246551 -337.119446) (xy 358.249474 -337.1342) (xy 358.254238 -337.155793) (xy 358.259332 -337.199719)
			(xy 358.259634 -337.22183) (xy 358.25909 -337.249079) (xy 358.25133 -337.303022) (xy 358.235972 -337.355311)
			(xy 358.213328 -337.404882) (xy 358.183861 -337.450727) (xy 358.148169 -337.491911) (xy 358.10698 -337.527596)
			(xy 358.061131 -337.557057) (xy 358.011556 -337.579692) (xy 357.959264 -337.595042) (xy 357.90532 -337.602794)
			(xy 357.850822 -337.60279) (xy 357.79688 -337.59503) (xy 357.74459 -337.579672) (xy 357.695019 -337.557029)
			(xy 357.649174 -337.527562) (xy 357.60799 -337.49187) (xy 357.572305 -337.450681) (xy 357.542844 -337.404832)
			(xy 357.520208 -337.355257) (xy 357.504858 -337.302966) (xy 357.497106 -337.249022) (xy 357.160641 -337.249022)
			(xy 357.158498 -337.263923) (xy 357.143139 -337.316225) (xy 357.120492 -337.365807) (xy 357.091019 -337.411662)
			(xy 357.05532 -337.452855) (xy 357.014122 -337.488549) (xy 356.968263 -337.518016) (xy 356.918678 -337.540656)
			(xy 356.866375 -337.556009) (xy 356.812419 -337.563762) (xy 356.785164 -337.564222) (xy 356.757309 -337.563715)
			(xy 356.702193 -337.555587) (xy 356.648843 -337.539538) (xy 356.598391 -337.515908) (xy 356.551907 -337.485199)
			(xy 356.510378 -337.448062) (xy 356.474685 -337.405286) (xy 356.445586 -337.357779) (xy 356.423697 -337.306547)
			(xy 356.416102 -337.279742) (xy 356.411772 -337.265645) (xy 356.396397 -337.240502) (xy 356.374492 -337.220784)
			(xy 356.347876 -337.208128) (xy 356.318757 -337.203582) (xy 356.304088 -337.205066) (xy 356.291071 -337.206735)
			(xy 356.264887 -337.208515) (xy 356.251764 -337.208622) (xy 356.237615 -337.208532) (xy 356.209392 -337.206495)
			(xy 356.195376 -337.204558) (xy 356.182023 -337.203045) (xy 356.155341 -337.206135) (xy 356.130394 -337.216092)
			(xy 356.108917 -337.232223) (xy 356.092403 -337.253406) (xy 356.082 -337.27817) (xy 356.079806 -337.291426)
			(xy 356.075714 -337.318579) (xy 356.060743 -337.37141) (xy 356.038353 -337.421549) (xy 356.009006 -337.46796)
			(xy 355.973309 -337.509686) (xy 355.932 -337.545862) (xy 355.885931 -337.575744) (xy 355.836054 -337.598712)
			(xy 355.7834 -337.614293) (xy 355.729056 -337.622165) (xy 355.7016 -337.622642) (xy 355.67435 -337.622122)
			(xy 355.620406 -337.614367) (xy 355.568114 -337.599013) (xy 355.518539 -337.576375) (xy 355.47269 -337.546911)
			(xy 355.4315 -337.511224) (xy 355.395809 -337.470037) (xy 355.366342 -337.424191) (xy 355.343699 -337.374618)
			(xy 355.328341 -337.322328) (xy 355.32058 -337.268384) (xy 355.320092 -337.241134) (xy 355.320584 -337.21356)
			(xy 355.328531 -337.158989) (xy 355.344252 -337.10613) (xy 355.367417 -337.056084) (xy 355.397544 -337.009893)
			(xy 355.434007 -336.968521) (xy 355.454712 -336.950304) (xy 355.465574 -336.94037) (xy 355.481645 -336.915729)
			(xy 355.490031 -336.887531) (xy 355.490038 -336.858113) (xy 355.481664 -336.829911) (xy 355.465603 -336.805263)
			(xy 355.454712 -336.795364) (xy 355.433983 -336.777173) (xy 355.397513 -336.7358) (xy 355.367383 -336.689606)
			(xy 355.34422 -336.639554) (xy 355.328508 -336.586688) (xy 355.320574 -336.53211) (xy 355.320092 -336.504534)
			(xy 355.320528 -336.478032) (xy 355.327878 -336.425541) (xy 355.342426 -336.374573) (xy 355.363893 -336.326111)
			(xy 355.391865 -336.281089) (xy 355.408484 -336.26044) (xy 355.417925 -336.248295) (xy 355.429707 -336.219894)
			(xy 355.432526 -336.189276) (xy 355.42613 -336.159201) (xy 355.411094 -336.13238) (xy 355.388774 -336.111232)
			(xy 355.37521 -336.103976) (xy 355.351511 -336.091892) (xy 355.307531 -336.061963) (xy 355.268253 -336.026087)
			(xy 355.234472 -335.984992) (xy 355.22027 -335.962498) (xy 355.212354 -335.950269) (xy 355.19088 -335.930598)
			(xy 355.164725 -335.917794) (xy 355.136018 -335.9129) (xy 355.107098 -335.916315) (xy 355.093524 -335.921604)
			(xy 355.070308 -335.931079) (xy 355.021978 -335.944435) (xy 354.972291 -335.951169) (xy 354.94722 -335.951576)
			(xy 354.922151 -335.951133) (xy 354.872469 -335.944392) (xy 354.824134 -335.931066) (xy 354.800916 -335.921604)
			(xy 354.787324 -335.916389) (xy 354.758423 -335.913003) (xy 354.729739 -335.917897) (xy 354.703596 -335.930674)
			(xy 354.682112 -335.950299) (xy 354.67417 -335.962498) (xy 354.659601 -335.985629) (xy 354.624758 -336.02775)
			(xy 354.584135 -336.064329) (xy 354.538604 -336.09458) (xy 354.489142 -336.117856) (xy 354.436811 -336.133656)
			(xy 354.382732 -336.141642) (xy 354.328068 -336.141642) (xy 354.273989 -336.133656) (xy 354.221658 -336.117856)
			(xy 354.172196 -336.09458) (xy 354.126665 -336.064329) (xy 354.086042 -336.02775) (xy 354.051199 -335.985629)
			(xy 354.03663 -335.962498) (xy 354.028751 -335.950242) (xy 354.007268 -335.93057) (xy 353.981103 -335.91777)
			(xy 353.952387 -335.912884) (xy 353.92346 -335.916309) (xy 353.909884 -335.921604) (xy 353.886673 -335.931091)
			(xy 353.838341 -335.944443) (xy 353.788652 -335.951172) (xy 353.76358 -335.951576) (xy 353.735693 -335.951138)
			(xy 353.680542 -335.942822) (xy 353.627247 -335.92638) (xy 353.576997 -335.902179) (xy 353.530916 -335.870759)
			(xy 353.490031 -335.832822) (xy 353.455258 -335.789215) (xy 353.427372 -335.740913) (xy 353.406996 -335.688994)
			(xy 353.394585 -335.634618) (xy 353.390417 -335.579) (xy 348.983463 -335.579) (xy 348.997942 -335.628312)
			(xy 349.005698 -335.682262) (xy 349.00616 -335.709514) (xy 349.005649 -335.737087) (xy 348.997708 -335.791659)
			(xy 348.981993 -335.844518) (xy 348.958831 -335.894565) (xy 348.928706 -335.940755) (xy 348.892245 -335.982128)
			(xy 348.87154 -336.000344) (xy 348.860626 -336.010227) (xy 348.844548 -336.03488) (xy 348.836162 -336.063093)
			(xy 348.836165 -336.092525) (xy 348.844555 -336.120737) (xy 348.860638 -336.145387) (xy 348.87154 -336.155284)
			(xy 348.892262 -336.173483) (xy 348.928731 -336.214854) (xy 348.958862 -336.261046) (xy 348.982028 -336.311095)
			(xy 348.997745 -336.363958) (xy 349.005685 -336.418534) (xy 349.005684 -336.473684) (xy 348.997741 -336.52826)
			(xy 348.982021 -336.581122) (xy 348.958854 -336.63117) (xy 348.92872 -336.67736) (xy 348.892249 -336.71873)
			(xy 348.87154 -336.736944) (xy 348.860626 -336.746827) (xy 348.844548 -336.77148) (xy 348.836162 -336.799693)
			(xy 348.836165 -336.829125) (xy 348.844555 -336.857337) (xy 348.860638 -336.881987) (xy 348.87154 -336.891884)
			(xy 348.892255 -336.910091) (xy 348.928723 -336.951462) (xy 348.958854 -336.997653) (xy 348.982018 -337.047701)
			(xy 348.997735 -337.100564) (xy 349.005674 -337.155139) (xy 349.00616 -337.182714) (xy 349.005954 -337.196688)
			(xy 349.431337 -337.196688) (xy 349.439088 -337.142734) (xy 349.454439 -337.090433) (xy 349.477077 -337.040848)
			(xy 349.506541 -336.99499) (xy 349.542231 -336.953792) (xy 349.583421 -336.918092) (xy 349.629273 -336.888618)
			(xy 349.678852 -336.865969) (xy 349.73115 -336.850606) (xy 349.785102 -336.842843) (xy 349.812356 -336.842354)
			(xy 349.83547 -336.843116) (xy 349.848795 -336.843542) (xy 349.874897 -336.838144) (xy 349.898719 -336.826187)
			(xy 349.918644 -336.808483) (xy 349.933321 -336.786233) (xy 349.941752 -336.760947) (xy 349.943367 -336.734342)
			(xy 349.941134 -336.721196) (xy 349.937481 -336.702293) (xy 349.933539 -336.663993) (xy 349.93326 -336.644742)
			(xy 349.93371 -336.617485) (xy 349.941463 -336.563525) (xy 349.956816 -336.511218) (xy 349.979457 -336.461628)
			(xy 350.008926 -336.415765) (xy 350.044621 -336.374563) (xy 350.085818 -336.338861) (xy 350.131676 -336.309386)
			(xy 350.181262 -336.286737) (xy 350.233567 -336.271375) (xy 350.287526 -336.263614) (xy 350.34204 -336.263612)
			(xy 350.395999 -336.271368) (xy 350.448305 -336.286724) (xy 350.497894 -336.309369) (xy 350.543755 -336.33884)
			(xy 350.584954 -336.374539) (xy 350.620654 -336.415737) (xy 350.650126 -336.461597) (xy 350.672772 -336.511185)
			(xy 350.68813 -336.563491) (xy 350.695887 -336.61745) (xy 350.695886 -336.671964) (xy 350.688127 -336.725923)
			(xy 350.672767 -336.778229) (xy 350.650119 -336.827815) (xy 350.620645 -336.873674) (xy 350.584944 -336.914871)
			(xy 350.543743 -336.950568) (xy 350.497881 -336.980038) (xy 350.448292 -337.002681) (xy 350.395985 -337.018035)
			(xy 350.342025 -337.025789) (xy 350.314768 -337.02625) (xy 350.291654 -337.025488) (xy 350.278329 -337.025079)
			(xy 350.252227 -337.030472) (xy 350.228404 -337.042425) (xy 350.208478 -337.060126) (xy 350.193801 -337.082374)
			(xy 350.18537 -337.107659) (xy 350.183757 -337.134263) (xy 350.18599 -337.147408) (xy 350.189644 -337.166311)
			(xy 350.193585 -337.204611) (xy 350.193864 -337.223862) (xy 350.193463 -337.251116) (xy 350.185711 -337.30507)
			(xy 350.17036 -337.357371) (xy 350.147721 -337.406955) (xy 350.118257 -337.452813) (xy 350.082566 -337.494011)
			(xy 350.041376 -337.52971) (xy 349.995524 -337.559184) (xy 349.945944 -337.581832) (xy 349.893646 -337.597194)
			(xy 349.839694 -337.604957) (xy 349.785186 -337.604963) (xy 349.731232 -337.597211) (xy 349.678931 -337.58186)
			(xy 349.629347 -337.559222) (xy 349.583489 -337.529758) (xy 349.542291 -337.494068) (xy 349.506591 -337.452877)
			(xy 349.477117 -337.407026) (xy 349.454468 -337.357446) (xy 349.439106 -337.305148) (xy 349.431343 -337.251196)
			(xy 349.431337 -337.196688) (xy 349.005954 -337.196688) (xy 349.005758 -337.209969) (xy 348.997998 -337.263925)
			(xy 348.982638 -337.316227) (xy 348.95999 -337.365811) (xy 348.930516 -337.411666) (xy 348.894816 -337.45286)
			(xy 348.853616 -337.488553) (xy 348.807756 -337.51802) (xy 348.758169 -337.540659) (xy 348.705864 -337.556011)
			(xy 348.651907 -337.563762) (xy 348.624652 -337.564222) (xy 348.596796 -337.563726) (xy 348.54168 -337.555596)
			(xy 348.48833 -337.539545) (xy 348.437878 -337.515914) (xy 348.391394 -337.485204) (xy 348.349865 -337.448066)
			(xy 348.314173 -337.405289) (xy 348.285073 -337.35778) (xy 348.263185 -337.306548) (xy 348.25559 -337.279742)
			(xy 348.251272 -337.265641) (xy 348.235894 -337.240497) (xy 348.213987 -337.220779) (xy 348.187368 -337.208124)
			(xy 348.158246 -337.203581) (xy 348.143576 -337.205066) (xy 348.13056 -337.206736) (xy 348.104375 -337.208515)
			(xy 348.091252 -337.208622) (xy 348.077103 -337.208522) (xy 348.04888 -337.206492) (xy 348.034864 -337.204558)
			(xy 348.021512 -337.203033) (xy 347.994829 -337.206126) (xy 347.969882 -337.216085) (xy 347.948405 -337.232218)
			(xy 347.931891 -337.253404) (xy 347.921488 -337.278169) (xy 347.919294 -337.291426) (xy 347.915213 -337.318581)
			(xy 347.900242 -337.371413) (xy 347.877851 -337.421553) (xy 347.848503 -337.467965) (xy 347.812805 -337.50969)
			(xy 347.771494 -337.545867) (xy 347.725423 -337.575748) (xy 347.675545 -337.598715) (xy 347.622889 -337.614295)
			(xy 347.568544 -337.622166) (xy 347.541088 -337.622642) (xy 347.513838 -337.622133) (xy 347.459893 -337.614376)
			(xy 347.407601 -337.599021) (xy 347.358026 -337.576381) (xy 347.312177 -337.546917) (xy 347.270988 -337.511228)
			(xy 347.235296 -337.470041) (xy 347.205829 -337.424194) (xy 347.183186 -337.37462) (xy 347.167828 -337.322329)
			(xy 347.160068 -337.268384) (xy 347.15958 -337.241134) (xy 345.016538 -337.241134) (xy 345.029813 -337.270201)
			(xy 345.045169 -337.322496) (xy 345.052926 -337.376443) (xy 345.053412 -337.403694) (xy 345.053412 -337.403948)
			(xy 345.05284 -337.433787) (xy 345.043522 -337.492733) (xy 345.03487 -337.521296) (xy 345.030926 -337.535227)
			(xy 345.030004 -337.564145) (xy 345.037252 -337.592155) (xy 345.052087 -337.616995) (xy 345.073309 -337.63666)
			(xy 345.099206 -337.649562) (xy 345.113356 -337.652614) (xy 345.139432 -337.657766) (xy 345.189936 -337.674341)
			(xy 345.237648 -337.697767) (xy 345.281646 -337.727591) (xy 345.321075 -337.763236) (xy 345.355174 -337.804011)
			(xy 345.38328 -337.849126) (xy 345.404849 -337.897706) (xy 345.419464 -337.94881) (xy 345.426841 -338.001449)
			(xy 345.4273 -338.028026) (xy 345.426814 -338.055277) (xy 345.419058 -338.109225) (xy 345.403703 -338.16152)
			(xy 345.381061 -338.211097) (xy 345.351595 -338.256947) (xy 345.315904 -338.298138) (xy 345.274713 -338.333829)
			(xy 345.228863 -338.363295) (xy 345.179286 -338.385937) (xy 345.126991 -338.401292) (xy 345.073043 -338.409048)
			(xy 345.018541 -338.409048) (xy 344.964593 -338.401292) (xy 344.912298 -338.385937) (xy 344.862721 -338.363295)
			(xy 344.816871 -338.333829) (xy 344.77568 -338.298138) (xy 344.739989 -338.256947) (xy 344.710523 -338.211097)
			(xy 344.687881 -338.16152) (xy 344.672526 -338.109225) (xy 344.66477 -338.055277) (xy 344.664284 -338.028026)
			(xy 344.664284 -338.027772) (xy 344.66486 -337.997933) (xy 344.674175 -337.938987) (xy 344.682826 -337.910424)
			(xy 344.686863 -337.896517) (xy 344.687767 -337.867586) (xy 344.6805 -337.839567) (xy 344.665647 -337.814723)
			(xy 344.644409 -337.795057) (xy 344.618497 -337.782157) (xy 344.60434 -337.779106) (xy 344.571503 -337.772515)
			(xy 344.508649 -337.749398) (xy 344.479372 -337.733132) (xy 344.466407 -337.726095) (xy 344.437771 -337.719064)
			(xy 344.40832 -337.72051) (xy 344.38051 -337.730312) (xy 344.35666 -337.747652) (xy 344.338761 -337.771085)
			(xy 344.333068 -337.784694) (xy 344.322329 -337.811452) (xy 344.294047 -337.861692) (xy 344.258523 -337.907102)
			(xy 344.216568 -337.946646) (xy 344.169137 -337.979422) (xy 344.117312 -338.004683) (xy 344.062274 -338.021853)
			(xy 344.005279 -338.030541) (xy 343.976452 -338.031074) (xy 343.962558 -338.030944) (xy 343.934844 -338.028913)
			(xy 343.92108 -338.02701) (xy 343.911805 -338.026054) (xy 343.893622 -338.030113) (xy 343.878089 -338.040401)
			(xy 343.867256 -338.055558) (xy 343.862554 -338.073586) (xy 343.863168 -338.08289) (xy 343.864692 -338.1121)
			(xy 343.864692 -340.02218) (xy 344.252804 -340.410292) (xy 348.020386 -340.410292) (xy 348.045369 -340.410919)
			(xy 348.094377 -340.420655) (xy 348.140547 -340.439758) (xy 348.182108 -340.467494) (xy 348.200218 -340.484714)
			(xy 349.523304 -341.8078) (xy 349.540554 -341.825901) (xy 349.568365 -341.867444) (xy 349.58754 -341.913614)
			(xy 349.597342 -341.962636) (xy 349.59798 -341.987632) (xy 349.59798 -346.512388) (xy 350.75622 -347.670628)
			(xy 353.305364 -347.670628) (xy 353.330359 -347.671284) (xy 353.379381 -347.681082) (xy 353.425551 -347.70025)
			(xy 353.467099 -347.728052) (xy 353.485196 -347.745304) (xy 354.339144 -348.598998) (xy 354.350126 -348.609174)
			(xy 354.376515 -348.623277) (xy 354.40586 -348.629121) (xy 354.435639 -348.626201) (xy 354.46329 -348.61477)
			(xy 354.486438 -348.595809) (xy 354.503091 -348.57095) (xy 354.511817 -348.54233) (xy 354.512372 -348.52737)
			(xy 354.512372 -346.830396) (xy 354.38969 -346.70746) (xy 351.500948 -346.70746) (xy 351.475964 -346.706859)
			(xy 351.426956 -346.697112) (xy 351.380786 -346.678001) (xy 351.339226 -346.65026) (xy 351.321116 -346.633038)
			(xy 350.299274 -345.611196) (xy 350.28204 -345.593097) (xy 350.2543 -345.551534) (xy 350.235195 -345.505361)
			(xy 350.22546 -345.456349) (xy 350.224852 -345.431364) (xy 350.224852 -341.079074) (xy 350.225465 -341.054091)
			(xy 350.235208 -341.005083) (xy 350.254315 -340.958913) (xy 350.282053 -340.917352) (xy 350.299274 -340.899242)
			(xy 351.120456 -340.077806) (xy 351.120456 -338.622386) (xy 351.075752 -338.617052) (xy 351.048293 -338.613307)
			(xy 350.994791 -338.598864) (xy 350.943943 -338.576829) (xy 350.89682 -338.547666) (xy 350.854414 -338.511989)
			(xy 350.817619 -338.47055) (xy 350.787209 -338.424222) (xy 350.763826 -338.37398) (xy 350.747961 -338.320882)
			(xy 350.739948 -338.266047) (xy 350.739456 -338.238338) (xy 350.740016 -338.20865) (xy 350.749211 -338.14999)
			(xy 350.767383 -338.093463) (xy 350.794096 -338.040435) (xy 350.828702 -337.992186) (xy 350.870366 -337.949883)
			(xy 350.893888 -337.93176) (xy 350.904471 -337.923305) (xy 350.921181 -337.902) (xy 350.931703 -337.877052)
			(xy 350.935297 -337.850216) (xy 350.931711 -337.823378) (xy 350.921197 -337.798427) (xy 350.904493 -337.777117)
			(xy 350.893888 -337.768692) (xy 350.870371 -337.750564) (xy 350.828712 -337.708258) (xy 350.794108 -337.66001)
			(xy 350.767397 -337.606983) (xy 350.749222 -337.550459) (xy 350.740022 -337.491801) (xy 350.739456 -337.462114)
			(xy 350.739991 -337.434852) (xy 350.747752 -337.380882) (xy 350.763118 -337.328567) (xy 350.785776 -337.278973)
			(xy 350.815265 -337.23311) (xy 350.850983 -337.191913) (xy 350.892202 -337.156221) (xy 350.938084 -337.126761)
			(xy 350.987692 -337.104134) (xy 351.040017 -337.088801) (xy 351.093991 -337.081074) (xy 351.148516 -337.08111)
			(xy 351.20248 -337.088909) (xy 351.254785 -337.104312) (xy 351.304363 -337.127005) (xy 351.350205 -337.156526)
			(xy 351.391377 -337.192273) (xy 351.42704 -337.233517) (xy 351.456467 -337.279419) (xy 351.479059 -337.329044)
			(xy 351.494356 -337.381379) (xy 351.502045 -337.435359) (xy 351.502472 -337.462622) (xy 351.502472 -337.483958)
			(xy 351.60204 -337.583526) (xy 351.613066 -337.593736) (xy 351.639586 -337.607837) (xy 351.669059 -337.613622)
			(xy 351.698941 -337.610593) (xy 351.726653 -337.59901) (xy 351.749803 -337.579874) (xy 351.766393 -337.554836)
			(xy 351.771204 -337.5406) (xy 351.779414 -337.514693) (xy 351.802181 -337.465347) (xy 351.831718 -337.419729)
			(xy 351.867427 -337.378762) (xy 351.908587 -337.343275) (xy 351.954364 -337.313986) (xy 352.003833 -337.291487)
			(xy 352.055994 -337.276234) (xy 352.109791 -337.268533) (xy 352.136964 -337.268058) (xy 352.137218 -337.268058)
			(xy 352.162422 -337.268447) (xy 352.21239 -337.27509) (xy 352.261045 -337.288269) (xy 352.307534 -337.307755)
			(xy 352.329496 -337.320128) (xy 352.342471 -337.327148) (xy 352.371104 -337.334189) (xy 352.400555 -337.332749)
			(xy 352.428366 -337.322951) (xy 352.452214 -337.30561) (xy 352.47011 -337.282176) (xy 352.4758 -337.268566)
			(xy 352.486461 -337.241775) (xy 352.514755 -337.191533) (xy 352.55029 -337.146124) (xy 352.592257 -337.106583)
			(xy 352.639699 -337.073811) (xy 352.691535 -337.048556) (xy 352.746582 -337.031393) (xy 352.803586 -337.022714)
			(xy 352.832416 -337.022186) (xy 352.859667 -337.022663) (xy 352.913615 -337.030421) (xy 352.96591 -337.045778)
			(xy 353.015487 -337.068421) (xy 353.061337 -337.097888) (xy 353.102526 -337.133581) (xy 353.138218 -337.174771)
			(xy 353.167684 -337.220622) (xy 353.190325 -337.2702) (xy 353.205681 -337.322495) (xy 353.213438 -337.376443)
			(xy 353.213924 -337.403694) (xy 353.213924 -337.403948) (xy 353.213352 -337.433787) (xy 353.204034 -337.492733)
			(xy 353.195382 -337.521296) (xy 353.191429 -337.535225) (xy 353.190506 -337.564145) (xy 353.197755 -337.592157)
			(xy 353.212592 -337.616998) (xy 353.233817 -337.636663) (xy 353.259717 -337.649563) (xy 353.273868 -337.652614)
			(xy 353.299946 -337.657757) (xy 353.350449 -337.674333) (xy 353.398162 -337.697761) (xy 353.442159 -337.727587)
			(xy 353.481589 -337.763233) (xy 353.515687 -337.804008) (xy 353.543792 -337.849124) (xy 353.565362 -337.897704)
			(xy 353.579976 -337.94881) (xy 353.587353 -338.001449) (xy 353.587812 -338.028026) (xy 353.587326 -338.055277)
			(xy 353.57957 -338.109225) (xy 353.564215 -338.16152) (xy 353.541573 -338.211097) (xy 353.512107 -338.256947)
			(xy 353.476416 -338.298138) (xy 353.435225 -338.333829) (xy 353.389375 -338.363295) (xy 353.339798 -338.385937)
			(xy 353.287503 -338.401292) (xy 353.233555 -338.409048) (xy 353.179053 -338.409048) (xy 353.125105 -338.401292)
			(xy 353.07281 -338.385937) (xy 353.023233 -338.363295) (xy 352.977383 -338.333829) (xy 352.936192 -338.298138)
			(xy 352.900501 -338.256947) (xy 352.871035 -338.211097) (xy 352.848393 -338.16152) (xy 352.833038 -338.109225)
			(xy 352.825282 -338.055277) (xy 352.824796 -338.028026) (xy 352.824796 -338.027772) (xy 352.825372 -337.997933)
			(xy 352.834687 -337.938987) (xy 352.843338 -337.910424) (xy 352.847365 -337.896515) (xy 352.848269 -337.867586)
			(xy 352.841003 -337.839569) (xy 352.826153 -337.814726) (xy 352.804916 -337.79506) (xy 352.779007 -337.782158)
			(xy 352.764852 -337.779106) (xy 352.732015 -337.772512) (xy 352.669162 -337.749397) (xy 352.639884 -337.733132)
			(xy 352.626912 -337.726109) (xy 352.598279 -337.719076) (xy 352.568829 -337.72052) (xy 352.541021 -337.730319)
			(xy 352.517172 -337.747656) (xy 352.499273 -337.771086) (xy 352.49358 -337.784694) (xy 352.482914 -337.811483)
			(xy 352.454624 -337.861727) (xy 352.41909 -337.907138) (xy 352.377124 -337.946681) (xy 352.329682 -337.979454)
			(xy 352.277846 -338.004709) (xy 352.222799 -338.021871) (xy 352.165794 -338.030548) (xy 352.136964 -338.031074)
			(xy 352.11998 -338.030867) (xy 352.086148 -338.02781) (xy 352.0694 -338.024978) (xy 352.060179 -338.023734)
			(xy 352.041915 -338.027212) (xy 352.026086 -338.036965) (xy 352.014765 -338.051713) (xy 352.009436 -338.069525)
			(xy 352.00971 -338.078826) (xy 352.010472 -338.097114) (xy 352.010472 -340.341204) (xy 352.00984 -340.3662)
			(xy 352.000034 -340.415223) (xy 351.98086 -340.461394) (xy 351.953051 -340.50294) (xy 351.935796 -340.521036)
			(xy 351.11436 -341.342472) (xy 351.11436 -343.944632) (xy 351.95027 -343.944632) (xy 351.95027 -343.859936)
			(xy 351.958321 -343.775622) (xy 351.97435 -343.692456) (xy 351.998211 -343.611189) (xy 352.02969 -343.532559)
			(xy 352.068501 -343.457278) (xy 352.114291 -343.386026) (xy 352.166647 -343.31945) (xy 352.225095 -343.258152)
			(xy 352.289105 -343.202687) (xy 352.358097 -343.153558) (xy 352.431447 -343.111209) (xy 352.50849 -343.076025)
			(xy 352.588529 -343.048323) (xy 352.670838 -343.028355) (xy 352.754673 -343.016302) (xy 352.839274 -343.012272)
			(xy 352.923875 -343.016302) (xy 353.00771 -343.028355) (xy 353.090019 -343.048323) (xy 353.170058 -343.076025)
			(xy 353.247101 -343.111209) (xy 353.320451 -343.153558) (xy 353.389443 -343.202687) (xy 353.453453 -343.258152)
			(xy 353.511901 -343.31945) (xy 353.564257 -343.386026) (xy 353.610047 -343.457278) (xy 353.648858 -343.532559)
			(xy 353.680337 -343.611189) (xy 353.704198 -343.692456) (xy 353.720227 -343.775622) (xy 353.728278 -343.859936)
			(xy 353.728782 -343.902284) (xy 354.474783 -343.902284) (xy 354.478819 -343.818837) (xy 354.490891 -343.736169)
			(xy 354.510884 -343.655052) (xy 354.538613 -343.576243) (xy 354.573819 -343.500478) (xy 354.616173 -343.428465)
			(xy 354.665279 -343.360876) (xy 354.72068 -343.298342) (xy 354.781857 -343.241447) (xy 354.84824 -343.190721)
			(xy 354.919208 -343.14664) (xy 354.9941 -343.109614) (xy 355.072216 -343.079988) (xy 355.152826 -343.05804)
			(xy 355.235178 -343.043975) (xy 355.318504 -343.037923) (xy 355.402024 -343.039942) (xy 355.48496 -343.050012)
			(xy 355.566536 -343.06804) (xy 355.645992 -343.093857) (xy 355.722585 -343.127222) (xy 355.795601 -343.167823)
			(xy 355.864357 -343.215282) (xy 355.928211 -343.269155) (xy 355.986568 -343.32894) (xy 356.038883 -343.394077)
			(xy 356.084666 -343.46396) (xy 356.123491 -343.537935) (xy 356.154996 -343.615312) (xy 356.178885 -343.695369)
			(xy 356.194936 -343.777357) (xy 356.202999 -343.860512) (xy 356.203504 -343.902284) (xy 356.202999 -343.944056)
			(xy 356.194936 -344.027211) (xy 356.178885 -344.109199) (xy 356.154996 -344.189256) (xy 356.123491 -344.266633)
			(xy 356.084666 -344.340608) (xy 356.038883 -344.410491) (xy 355.986568 -344.475628) (xy 355.928211 -344.535413)
			(xy 355.864357 -344.589286) (xy 355.795601 -344.636745) (xy 355.722585 -344.677346) (xy 355.645992 -344.710711)
			(xy 355.566536 -344.736528) (xy 355.48496 -344.754556) (xy 355.402024 -344.764626) (xy 355.318504 -344.766645)
			(xy 355.235178 -344.760593) (xy 355.152826 -344.746528) (xy 355.072216 -344.72458) (xy 354.9941 -344.694954)
			(xy 354.919208 -344.657928) (xy 354.84824 -344.613847) (xy 354.781857 -344.563121) (xy 354.72068 -344.506226)
			(xy 354.665279 -344.443692) (xy 354.616173 -344.376103) (xy 354.573819 -344.30409) (xy 354.538613 -344.228325)
			(xy 354.510884 -344.149516) (xy 354.490891 -344.068399) (xy 354.478819 -343.985731) (xy 354.474783 -343.902284)
			(xy 353.728782 -343.902284) (xy 353.728278 -343.944632) (xy 353.720227 -344.028946) (xy 353.704198 -344.112112)
			(xy 353.680337 -344.193379) (xy 353.648858 -344.272009) (xy 353.610047 -344.34729) (xy 353.564257 -344.418542)
			(xy 353.511901 -344.485118) (xy 353.453453 -344.546416) (xy 353.389443 -344.601881) (xy 353.320451 -344.65101)
			(xy 353.247101 -344.693359) (xy 353.170058 -344.728543) (xy 353.090019 -344.756245) (xy 353.00771 -344.776213)
			(xy 352.923875 -344.788266) (xy 352.839274 -344.792297) (xy 352.754673 -344.788266) (xy 352.670838 -344.776213)
			(xy 352.588529 -344.756245) (xy 352.50849 -344.728543) (xy 352.431447 -344.693359) (xy 352.358097 -344.65101)
			(xy 352.289105 -344.601881) (xy 352.225095 -344.546416) (xy 352.166647 -344.485118) (xy 352.114291 -344.418542)
			(xy 352.068501 -344.34729) (xy 352.02969 -344.272009) (xy 351.998211 -344.193379) (xy 351.97435 -344.112112)
			(xy 351.958321 -344.028946) (xy 351.95027 -343.944632) (xy 351.11436 -343.944632) (xy 351.11436 -345.167712)
			(xy 351.7646 -345.817952) (xy 354.653342 -345.817952) (xy 354.678326 -345.818556) (xy 354.727334 -345.828301)
			(xy 354.773504 -345.847411) (xy 354.815064 -345.875152) (xy 354.833174 -345.892374) (xy 355.444552 -346.503752)
			(xy 355.461818 -346.521839) (xy 355.489628 -346.563386) (xy 355.508799 -346.60956) (xy 355.518594 -346.658587)
			(xy 355.519228 -346.683584) (xy 355.519228 -349.197422) (xy 355.601524 -349.197422) (xy 355.615494 -349.168974)
			(xy 355.625165 -349.150339) (xy 355.649679 -349.11626) (xy 355.664262 -349.101156) (xy 357.619808 -347.145356)
			(xy 357.619808 -341.868252) (xy 357.62048 -341.843258) (xy 357.630274 -341.794237) (xy 357.649437 -341.748067)
			(xy 357.677234 -341.706518) (xy 357.694484 -341.68842) (xy 359.153968 -340.228682) (xy 359.153968 -338.599526)
			(xy 359.12425 -338.58581) (xy 359.099544 -338.57411) (xy 359.053456 -338.544716) (xy 359.012038 -338.509042)
			(xy 358.976138 -338.46782) (xy 358.946492 -338.421894) (xy 358.923707 -338.372205) (xy 358.908251 -338.319772)
			(xy 358.90044 -338.26567) (xy 358.899968 -338.238338) (xy 358.900524 -338.20865) (xy 358.909719 -338.149989)
			(xy 358.927892 -338.093462) (xy 358.954605 -338.040434) (xy 358.989212 -337.992186) (xy 359.030878 -337.949883)
			(xy 359.0544 -337.93176) (xy 359.064982 -337.923304) (xy 359.08169 -337.901999) (xy 359.092211 -337.877051)
			(xy 359.095804 -337.850216) (xy 359.092219 -337.823379) (xy 359.081706 -337.798428) (xy 359.065004 -337.777118)
			(xy 359.0544 -337.768692) (xy 359.030886 -337.750561) (xy 358.989225 -337.708256) (xy 358.954621 -337.660008)
			(xy 358.927909 -337.606982) (xy 358.909734 -337.550458) (xy 358.900534 -337.491801) (xy 358.899968 -337.462114)
			(xy 358.900479 -337.434851) (xy 358.90824 -337.380879) (xy 358.923607 -337.328563) (xy 358.946266 -337.278967)
			(xy 358.975755 -337.233103) (xy 359.011474 -337.191904) (xy 359.052695 -337.156211) (xy 359.098578 -337.126751)
			(xy 359.148188 -337.104123) (xy 359.200514 -337.088789) (xy 359.25449 -337.081062) (xy 359.309017 -337.081098)
			(xy 359.362983 -337.088897) (xy 359.415289 -337.104301) (xy 359.464869 -337.126995) (xy 359.510712 -337.156516)
			(xy 359.551885 -337.192264) (xy 359.58755 -337.23351) (xy 359.616978 -337.279414) (xy 359.639571 -337.329039)
			(xy 359.654868 -337.381376) (xy 359.662557 -337.435358) (xy 359.662984 -337.462622) (xy 359.662984 -337.483958)
			(xy 359.762552 -337.583526) (xy 359.773566 -337.59375) (xy 359.800089 -337.60785) (xy 359.829565 -337.613634)
			(xy 359.859449 -337.610602) (xy 359.887163 -337.599017) (xy 359.910314 -337.579878) (xy 359.926905 -337.554837)
			(xy 359.931716 -337.5406) (xy 359.939916 -337.51469) (xy 359.962683 -337.465342) (xy 359.992221 -337.419724)
			(xy 360.027932 -337.378757) (xy 360.069093 -337.343271) (xy 360.114872 -337.313982) (xy 360.164343 -337.291484)
			(xy 360.216505 -337.276231) (xy 360.270303 -337.268532) (xy 360.297476 -337.268058) (xy 360.29773 -337.268058)
			(xy 360.322934 -337.268442) (xy 360.372903 -337.275086) (xy 360.421557 -337.288267) (xy 360.468047 -337.307754)
			(xy 360.490008 -337.320128) (xy 360.502976 -337.327162) (xy 360.531612 -337.334201) (xy 360.561065 -337.332759)
			(xy 360.588877 -337.322957) (xy 360.612726 -337.305614) (xy 360.630622 -337.282177) (xy 360.636312 -337.268566)
			(xy 360.646963 -337.241771) (xy 360.675258 -337.191528) (xy 360.710794 -337.146119) (xy 360.752763 -337.106578)
			(xy 360.800207 -337.073806) (xy 360.852044 -337.048552) (xy 360.907092 -337.03139) (xy 360.964097 -337.022713)
			(xy 360.992928 -337.022186) (xy 361.02018 -337.022652) (xy 361.074128 -337.030412) (xy 361.126423 -337.04577)
			(xy 361.175999 -337.068414) (xy 361.221849 -337.097883) (xy 361.263039 -337.133576) (xy 361.29873 -337.174768)
			(xy 361.328196 -337.22062) (xy 361.350837 -337.270198) (xy 361.366193 -337.322494) (xy 361.37395 -337.376442)
			(xy 361.374436 -337.403694) (xy 361.374436 -337.403948) (xy 361.373863 -337.433787) (xy 361.364546 -337.492733)
			(xy 361.355894 -337.521296) (xy 361.351931 -337.535223) (xy 361.351008 -337.564145) (xy 361.358258 -337.592159)
			(xy 361.373097 -337.617001) (xy 361.394325 -337.636666) (xy 361.420227 -337.649564) (xy 361.43438 -337.652614)
			(xy 361.460445 -337.657823) (xy 361.510948 -337.674387) (xy 361.558661 -337.697804) (xy 361.60266 -337.727621)
			(xy 361.642092 -337.763259) (xy 361.676192 -337.804028) (xy 361.704301 -337.849138) (xy 361.725872 -337.897714)
			(xy 361.740488 -337.948815) (xy 361.747865 -338.001451) (xy 361.748324 -338.028026) (xy 361.747838 -338.055277)
			(xy 361.740082 -338.109225) (xy 361.724727 -338.16152) (xy 361.702085 -338.211097) (xy 361.672619 -338.256947)
			(xy 361.636928 -338.298138) (xy 361.595737 -338.333829) (xy 361.549887 -338.363295) (xy 361.50031 -338.385937)
			(xy 361.448015 -338.401292) (xy 361.394067 -338.409048) (xy 361.339565 -338.409048) (xy 361.285617 -338.401292)
			(xy 361.233322 -338.385937) (xy 361.183745 -338.363295) (xy 361.137895 -338.333829) (xy 361.096704 -338.298138)
			(xy 361.061013 -338.256947) (xy 361.031547 -338.211097) (xy 361.008905 -338.16152) (xy 360.99355 -338.109225)
			(xy 360.985794 -338.055277) (xy 360.985308 -338.028026) (xy 360.985308 -338.027772) (xy 360.985883 -337.997933)
			(xy 360.995199 -337.938987) (xy 361.00385 -337.910424) (xy 361.007868 -337.896513) (xy 361.008772 -337.867586)
			(xy 361.001506 -337.839571) (xy 360.986658 -337.814728) (xy 360.965424 -337.795062) (xy 360.939518 -337.782159)
			(xy 360.925364 -337.779106) (xy 360.892528 -337.772509) (xy 360.829674 -337.749396) (xy 360.800396 -337.733132)
			(xy 360.787417 -337.726123) (xy 360.758786 -337.719088) (xy 360.729339 -337.720529) (xy 360.701532 -337.730326)
			(xy 360.677684 -337.74766) (xy 360.659785 -337.771087) (xy 360.654092 -337.784694) (xy 360.643416 -337.811479)
			(xy 360.615127 -337.861723) (xy 360.579595 -337.907133) (xy 360.53763 -337.946676) (xy 360.49019 -337.979449)
			(xy 360.438355 -338.004705) (xy 360.383309 -338.021868) (xy 360.326306 -338.030547) (xy 360.297476 -338.031074)
			(xy 360.296968 -338.031074) (xy 360.266526 -338.030467) (xy 360.20642 -338.020772) (xy 360.177334 -338.01177)
			(xy 360.164171 -338.007909) (xy 360.136781 -338.006588) (xy 360.110028 -338.012604) (xy 360.085841 -338.025523)
			(xy 360.065965 -338.044414) (xy 360.051834 -338.067914) (xy 360.044467 -338.094327) (xy 360.043984 -338.108036)
			(xy 360.043984 -340.49208) (xy 360.043334 -340.517075) (xy 360.033534 -340.566097) (xy 360.014364 -340.612268)
			(xy 359.986561 -340.653815) (xy 359.969308 -340.671912) (xy 358.509824 -342.13165) (xy 358.509824 -343.944632)
			(xy 359.655614 -343.944632) (xy 359.655614 -343.859936) (xy 359.663665 -343.775622) (xy 359.679694 -343.692456)
			(xy 359.703555 -343.611189) (xy 359.735034 -343.532559) (xy 359.773845 -343.457278) (xy 359.819635 -343.386026)
			(xy 359.871991 -343.31945) (xy 359.930439 -343.258152) (xy 359.994449 -343.202687) (xy 360.063441 -343.153558)
			(xy 360.136791 -343.111209) (xy 360.213834 -343.076025) (xy 360.293873 -343.048323) (xy 360.376182 -343.028355)
			(xy 360.460017 -343.016302) (xy 360.544618 -343.012272) (xy 360.629219 -343.016302) (xy 360.713054 -343.028355)
			(xy 360.795363 -343.048323) (xy 360.875402 -343.076025) (xy 360.952445 -343.111209) (xy 361.025795 -343.153558)
			(xy 361.094787 -343.202687) (xy 361.158797 -343.258152) (xy 361.217245 -343.31945) (xy 361.269601 -343.386026)
			(xy 361.315391 -343.457278) (xy 361.354202 -343.532559) (xy 361.385681 -343.611189) (xy 361.409542 -343.692456)
			(xy 361.425571 -343.775622) (xy 361.433622 -343.859936) (xy 361.434126 -343.902284) (xy 362.180127 -343.902284)
			(xy 362.184163 -343.818837) (xy 362.196235 -343.736169) (xy 362.216228 -343.655052) (xy 362.243957 -343.576243)
			(xy 362.279163 -343.500478) (xy 362.321517 -343.428465) (xy 362.370623 -343.360876) (xy 362.426024 -343.298342)
			(xy 362.487201 -343.241447) (xy 362.553584 -343.190721) (xy 362.624552 -343.14664) (xy 362.699444 -343.109614)
			(xy 362.77756 -343.079988) (xy 362.85817 -343.05804) (xy 362.940522 -343.043975) (xy 363.023848 -343.037923)
			(xy 363.107368 -343.039942) (xy 363.190304 -343.050012) (xy 363.27188 -343.06804) (xy 363.351336 -343.093857)
			(xy 363.427929 -343.127222) (xy 363.500945 -343.167823) (xy 363.569701 -343.215282) (xy 363.633555 -343.269155)
			(xy 363.691912 -343.32894) (xy 363.744227 -343.394077) (xy 363.79001 -343.46396) (xy 363.828835 -343.537935)
			(xy 363.86034 -343.615312) (xy 363.884229 -343.695369) (xy 363.90028 -343.777357) (xy 363.908343 -343.860512)
			(xy 363.908848 -343.902284) (xy 363.908343 -343.944056) (xy 363.90028 -344.027211) (xy 363.884229 -344.109199)
			(xy 363.86034 -344.189256) (xy 363.828835 -344.266633) (xy 363.79001 -344.340608) (xy 363.744227 -344.410491)
			(xy 363.691912 -344.475628) (xy 363.633555 -344.535413) (xy 363.569701 -344.589286) (xy 363.500945 -344.636745)
			(xy 363.427929 -344.677346) (xy 363.351336 -344.710711) (xy 363.27188 -344.736528) (xy 363.190304 -344.754556)
			(xy 363.107368 -344.764626) (xy 363.023848 -344.766645) (xy 362.940522 -344.760593) (xy 362.85817 -344.746528)
			(xy 362.77756 -344.72458) (xy 362.699444 -344.694954) (xy 362.624552 -344.657928) (xy 362.553584 -344.613847)
			(xy 362.487201 -344.563121) (xy 362.426024 -344.506226) (xy 362.370623 -344.443692) (xy 362.321517 -344.376103)
			(xy 362.279163 -344.30409) (xy 362.243957 -344.228325) (xy 362.216228 -344.149516) (xy 362.196235 -344.068399)
			(xy 362.184163 -343.985731) (xy 362.180127 -343.902284) (xy 361.434126 -343.902284) (xy 361.433622 -343.944632)
			(xy 361.425571 -344.028946) (xy 361.409542 -344.112112) (xy 361.385681 -344.193379) (xy 361.354202 -344.272009)
			(xy 361.315391 -344.34729) (xy 361.269601 -344.418542) (xy 361.217245 -344.485118) (xy 361.158797 -344.546416)
			(xy 361.094787 -344.601881) (xy 361.025795 -344.65101) (xy 360.952445 -344.693359) (xy 360.875402 -344.728543)
			(xy 360.795363 -344.756245) (xy 360.713054 -344.776213) (xy 360.629219 -344.788266) (xy 360.544618 -344.792297)
			(xy 360.460017 -344.788266) (xy 360.376182 -344.776213) (xy 360.293873 -344.756245) (xy 360.213834 -344.728543)
			(xy 360.136791 -344.693359) (xy 360.063441 -344.65101) (xy 359.994449 -344.601881) (xy 359.930439 -344.546416)
			(xy 359.871991 -344.485118) (xy 359.819635 -344.418542) (xy 359.773845 -344.34729) (xy 359.735034 -344.272009)
			(xy 359.703555 -344.193379) (xy 359.679694 -344.112112) (xy 359.663665 -344.028946) (xy 359.655614 -343.944632)
			(xy 358.509824 -343.944632) (xy 358.509824 -347.408754) (xy 358.509175 -347.43375) (xy 358.499377 -347.482772)
			(xy 358.480207 -347.528943) (xy 358.452402 -347.57049) (xy 358.435148 -347.588586) (xy 356.479348 -349.544386)
			(xy 356.479348 -349.765112) (xy 357.183944 -349.765112) (xy 358.137968 -348.811088) (xy 358.156039 -348.793805)
			(xy 358.197593 -348.766) (xy 358.243771 -348.746835) (xy 358.292802 -348.737044) (xy 358.3178 -348.736412)
			(xy 360.716068 -348.736412) (xy 365.162084 -344.290396) (xy 365.162084 -341.926672) (xy 365.162685 -341.901674)
			(xy 365.172498 -341.852649) (xy 365.191681 -341.806478) (xy 365.219499 -341.764934) (xy 365.23676 -341.74684)
			(xy 367.463832 -339.519768) (xy 367.463832 -338.669884) (xy 367.46344 -338.660269) (xy 367.456415 -338.642371)
			(xy 367.443286 -338.628325) (xy 367.425902 -338.62011) (xy 367.416334 -338.619084) (xy 367.387732 -338.616681)
			(xy 367.331694 -338.604261) (xy 367.278147 -338.583591) (xy 367.228299 -338.555136) (xy 367.183272 -338.519539)
			(xy 367.144083 -338.477602) (xy 367.111615 -338.43027) (xy 367.086599 -338.37861) (xy 367.0696 -338.323787)
			(xy 367.061 -338.267037) (xy 367.06048 -338.238338) (xy 367.061071 -338.208651) (xy 367.070263 -338.149994)
			(xy 367.088432 -338.09347) (xy 367.115138 -338.040442) (xy 367.149738 -337.992192) (xy 367.191394 -337.949885)
			(xy 367.214912 -337.93176) (xy 367.225493 -337.923304) (xy 367.242199 -337.901998) (xy 367.252719 -337.877051)
			(xy 367.256312 -337.850216) (xy 367.252727 -337.82338) (xy 367.242215 -337.798429) (xy 367.225516 -337.777118)
			(xy 367.214912 -337.768692) (xy 367.1914 -337.750558) (xy 367.149739 -337.708254) (xy 367.115135 -337.660007)
			(xy 367.088422 -337.606981) (xy 367.070246 -337.550458) (xy 367.061046 -337.491801) (xy 367.06048 -337.462114)
			(xy 367.060967 -337.43485) (xy 367.068728 -337.380877) (xy 367.084096 -337.328558) (xy 367.106755 -337.278961)
			(xy 367.136246 -337.233095) (xy 367.171966 -337.191896) (xy 367.213188 -337.156202) (xy 367.259072 -337.12674)
			(xy 367.308684 -337.104112) (xy 367.361011 -337.088777) (xy 367.41499 -337.08105) (xy 367.469518 -337.081086)
			(xy 367.523486 -337.088886) (xy 367.575793 -337.10429) (xy 367.625374 -337.126984) (xy 367.671219 -337.156507)
			(xy 367.712394 -337.192256) (xy 367.748059 -337.233503) (xy 367.777488 -337.279408) (xy 367.800082 -337.329035)
			(xy 367.815379 -337.381374) (xy 367.823069 -337.435357) (xy 367.823496 -337.462622) (xy 367.823496 -337.483958)
			(xy 367.923064 -337.583526) (xy 367.934066 -337.593765) (xy 367.960592 -337.607864) (xy 367.990071 -337.613646)
			(xy 368.019958 -337.610612) (xy 368.047674 -337.599025) (xy 368.070826 -337.579883) (xy 368.087417 -337.554839)
			(xy 368.092228 -337.5406) (xy 368.100505 -337.514716) (xy 368.123266 -337.465374) (xy 368.152796 -337.419758)
			(xy 368.188497 -337.378792) (xy 368.229648 -337.343305) (xy 368.275416 -337.314013) (xy 368.324876 -337.291509)
			(xy 368.377029 -337.276248) (xy 368.430818 -337.268538) (xy 368.457988 -337.268058) (xy 368.458242 -337.268058)
			(xy 368.483446 -337.268437) (xy 368.533415 -337.275082) (xy 368.58207 -337.288265) (xy 368.628559 -337.307753)
			(xy 368.65052 -337.320128) (xy 368.66348 -337.327177) (xy 368.692119 -337.334213) (xy 368.721575 -337.332769)
			(xy 368.749388 -337.322964) (xy 368.773238 -337.305619) (xy 368.791135 -337.282179) (xy 368.796824 -337.268566)
			(xy 368.807549 -337.241802) (xy 368.835835 -337.191563) (xy 368.871361 -337.146155) (xy 368.913319 -337.106613)
			(xy 368.960752 -337.073838) (xy 369.012578 -337.048578) (xy 369.067617 -337.031408) (xy 369.124613 -337.022719)
			(xy 369.15344 -337.022186) (xy 369.180692 -337.022641) (xy 369.23464 -337.030402) (xy 369.286935 -337.045762)
			(xy 369.336512 -337.068408) (xy 369.382362 -337.097878) (xy 369.423552 -337.133572) (xy 369.459243 -337.174765)
			(xy 369.488709 -337.220617) (xy 369.51135 -337.270196) (xy 369.526705 -337.322493) (xy 369.534462 -337.376442)
			(xy 369.534948 -337.403694) (xy 369.534948 -337.403948) (xy 369.534375 -337.433787) (xy 369.526646 -337.482688)
			(xy 371.647212 -337.482688) (xy 371.647734 -337.455115) (xy 371.655675 -337.400545) (xy 371.671388 -337.347686)
			(xy 371.694547 -337.29764) (xy 371.72467 -337.251449) (xy 371.761129 -337.210075) (xy 371.781832 -337.191858)
			(xy 371.792738 -337.18197) (xy 371.808804 -337.157315) (xy 371.817183 -337.129106) (xy 371.817181 -337.099679)
			(xy 371.808798 -337.071471) (xy 371.792728 -337.046819) (xy 371.781832 -337.036918) (xy 371.761133 -337.018694)
			(xy 371.72466 -336.977329) (xy 371.694526 -336.931142) (xy 371.671358 -336.881096) (xy 371.655639 -336.828235)
			(xy 371.647698 -336.773662) (xy 371.647212 -336.746088) (xy 371.647644 -336.718834) (xy 371.655403 -336.664881)
			(xy 371.670761 -336.612581) (xy 371.693407 -336.562999) (xy 371.722878 -336.517145) (xy 371.758575 -336.475952)
			(xy 371.799771 -336.440259) (xy 371.845628 -336.410791) (xy 371.895211 -336.38815) (xy 371.947512 -336.372796)
			(xy 372.001466 -336.365041) (xy 372.02872 -336.36458) (xy 372.040882 -336.364673) (xy 372.065157 -336.366196)
			(xy 372.077234 -336.367628) (xy 372.090996 -336.368863) (xy 372.118323 -336.364892) (xy 372.143589 -336.353747)
			(xy 372.164947 -336.336242) (xy 372.180837 -336.313657) (xy 372.190098 -336.287642) (xy 372.191534 -336.273902)
			(xy 372.194089 -336.24537) (xy 372.206571 -336.189465) (xy 372.227274 -336.136055) (xy 372.255732 -336.086344)
			(xy 372.291306 -336.041447) (xy 372.333195 -336.002377) (xy 372.380457 -335.970012) (xy 372.432028 -335.945079)
			(xy 372.486747 -335.92814) (xy 372.543385 -335.919577) (xy 372.572026 -335.919064) (xy 372.590045 -335.919286)
			(xy 372.62592 -335.922719) (xy 372.643654 -335.925922) (xy 372.658866 -335.928241) (xy 372.689419 -335.924725)
			(xy 372.71754 -335.91227) (xy 372.740676 -335.892007) (xy 372.756729 -335.865774) (xy 372.761002 -335.850992)
			(xy 372.768437 -335.823959) (xy 372.790061 -335.772233) (xy 372.819019 -335.724227) (xy 372.854689 -335.680974)
			(xy 372.896304 -335.643406) (xy 372.942967 -335.61233) (xy 372.993675 -335.588415) (xy 373.047335 -335.572177)
			(xy 373.102794 -335.563964) (xy 373.130826 -335.563464) (xy 373.158077 -335.563954) (xy 373.212023 -335.571713)
			(xy 373.264316 -335.58707) (xy 373.313891 -335.609712) (xy 373.35974 -335.639178) (xy 373.400929 -335.674869)
			(xy 373.43662 -335.716058) (xy 373.466087 -335.761907) (xy 373.488729 -335.811482) (xy 373.504087 -335.863775)
			(xy 373.511846 -335.917721) (xy 373.512334 -335.944972) (xy 373.511872 -335.972547) (xy 373.503922 -336.027121)
			(xy 373.488198 -336.079982) (xy 373.465027 -336.130028) (xy 373.434893 -336.176218) (xy 373.398423 -336.217587)
			(xy 373.377714 -336.235802) (xy 373.366844 -336.245729) (xy 373.350769 -336.27037) (xy 373.342381 -336.298571)
			(xy 373.342376 -336.327993) (xy 373.350753 -336.356197) (xy 373.36682 -336.380844) (xy 373.377714 -336.390742)
			(xy 373.398391 -336.408989) (xy 373.434853 -336.450357) (xy 373.464979 -336.496543) (xy 373.488141 -336.546586)
			(xy 373.503857 -336.599442) (xy 373.511799 -336.65401) (xy 373.511802 -336.709154) (xy 373.503865 -336.763723)
			(xy 373.488154 -336.81658) (xy 373.464997 -336.866625) (xy 373.434875 -336.912815) (xy 373.398417 -336.954186)
			(xy 373.377714 -336.972402) (xy 373.366844 -336.982329) (xy 373.350769 -337.00697) (xy 373.342381 -337.035171)
			(xy 373.342376 -337.064593) (xy 373.350753 -337.092797) (xy 373.36682 -337.117444) (xy 373.377714 -337.127342)
			(xy 373.398403 -337.145577) (xy 373.434875 -337.186941) (xy 373.465009 -337.233126) (xy 373.488179 -337.283169)
			(xy 373.5039 -337.336028) (xy 373.511845 -337.390599) (xy 373.512334 -337.418172) (xy 373.511819 -337.445423)
			(xy 373.504066 -337.499371) (xy 373.488715 -337.551666) (xy 373.466078 -337.601244) (xy 373.436615 -337.647096)
			(xy 373.400927 -337.688289) (xy 373.35974 -337.723983) (xy 373.313892 -337.753452) (xy 373.264317 -337.776096)
			(xy 373.212024 -337.791455) (xy 373.158077 -337.799215) (xy 373.130826 -337.79968) (xy 373.102971 -337.799148)
			(xy 373.047855 -337.791028) (xy 372.994504 -337.774985) (xy 372.944051 -337.75136) (xy 372.897566 -337.720654)
			(xy 372.856036 -337.683519) (xy 372.820343 -337.640744) (xy 372.791244 -337.593237) (xy 372.769358 -337.542005)
			(xy 372.761764 -337.5152) (xy 372.757496 -337.501082) (xy 372.742104 -337.475937) (xy 372.720184 -337.456222)
			(xy 372.693554 -337.443572) (xy 372.664424 -337.439035) (xy 372.64975 -337.440524) (xy 372.636734 -337.442196)
			(xy 372.610549 -337.443974) (xy 372.597426 -337.44408) (xy 372.579795 -337.443842) (xy 372.544687 -337.440537)
			(xy 372.527322 -337.437476) (xy 372.513546 -337.435268) (xy 372.485761 -337.437711) (xy 372.459678 -337.447592)
			(xy 372.437249 -337.464172) (xy 372.420152 -337.48621) (xy 372.409666 -337.512056) (xy 372.407688 -337.525868)
			(xy 372.404033 -337.553442) (xy 372.389802 -337.607212) (xy 372.36791 -337.658344) (xy 372.338821 -337.705752)
			(xy 372.303152 -337.748431) (xy 372.261661 -337.785475) (xy 372.215229 -337.816097) (xy 372.16484 -337.839648)
			(xy 372.111563 -337.855628) (xy 372.056531 -337.863698) (xy 372.02872 -337.864196) (xy 372.001467 -337.863726)
			(xy 371.947516 -337.855971) (xy 371.895217 -337.840617) (xy 371.845636 -337.817976) (xy 371.799783 -337.788509)
			(xy 371.758589 -337.752816) (xy 371.722896 -337.711624) (xy 371.693428 -337.665771) (xy 371.670785 -337.61619)
			(xy 371.65543 -337.563892) (xy 371.647675 -337.509941) (xy 371.647212 -337.482688) (xy 369.526646 -337.482688)
			(xy 369.525058 -337.492733) (xy 369.516406 -337.521296) (xy 369.512434 -337.535221) (xy 369.51151 -337.564145)
			(xy 369.518761 -337.59216) (xy 369.533602 -337.617004) (xy 369.554832 -337.636669) (xy 369.580738 -337.649566)
			(xy 369.594892 -337.652614) (xy 369.620959 -337.657814) (xy 369.671462 -337.67438) (xy 369.719175 -337.697798)
			(xy 369.763174 -337.727617) (xy 369.802605 -337.763256) (xy 369.836705 -337.804026) (xy 369.864813 -337.849136)
			(xy 369.886384 -337.897713) (xy 369.901 -337.948814) (xy 369.908377 -338.001451) (xy 369.908836 -338.028026)
			(xy 369.90835 -338.055277) (xy 369.900594 -338.109225) (xy 369.885239 -338.16152) (xy 369.862597 -338.211097)
			(xy 369.833131 -338.256947) (xy 369.79744 -338.298138) (xy 369.756249 -338.333829) (xy 369.710399 -338.363295)
			(xy 369.660822 -338.385937) (xy 369.608527 -338.401292) (xy 369.554579 -338.409048) (xy 369.500077 -338.409048)
			(xy 369.446129 -338.401292) (xy 369.393834 -338.385937) (xy 369.344257 -338.363295) (xy 369.298407 -338.333829)
			(xy 369.257216 -338.298138) (xy 369.221525 -338.256947) (xy 369.192059 -338.211097) (xy 369.169417 -338.16152)
			(xy 369.154062 -338.109225) (xy 369.146306 -338.055277) (xy 369.14582 -338.028026) (xy 369.14582 -338.027772)
			(xy 369.146395 -337.997933) (xy 369.15571 -337.938987) (xy 369.164362 -337.910424) (xy 369.168449 -337.896528)
			(xy 369.169356 -337.867586) (xy 369.162084 -337.839558) (xy 369.147221 -337.814708) (xy 369.125967 -337.795042)
			(xy 369.10004 -337.78215) (xy 369.085876 -337.779106) (xy 369.053035 -337.77253) (xy 368.990184 -337.749402)
			(xy 368.960908 -337.733132) (xy 368.947922 -337.726137) (xy 368.919294 -337.719101) (xy 368.889849 -337.720539)
			(xy 368.862044 -337.730333) (xy 368.838197 -337.747665) (xy 368.820298 -337.771089) (xy 368.814604 -337.784694)
			(xy 368.803918 -337.811475) (xy 368.77563 -337.861718) (xy 368.740099 -337.907128) (xy 368.698136 -337.946671)
			(xy 368.650697 -337.979445) (xy 368.598864 -338.004702) (xy 368.543819 -338.021866) (xy 368.486817 -338.030546)
			(xy 368.457988 -338.031074) (xy 368.439645 -338.030847) (xy 368.403132 -338.02728) (xy 368.38509 -338.023962)
			(xy 368.347498 -338.05876) (xy 368.351054 -338.084922) (xy 368.352115 -338.093327) (xy 368.35326 -338.110232)
			(xy 368.35334 -338.118704) (xy 368.35334 -338.592922) (xy 373.623332 -338.592922) (xy 373.623824 -338.564881)
			(xy 373.632024 -338.509403) (xy 373.648249 -338.45572) (xy 373.672151 -338.404988) (xy 373.703217 -338.358297)
			(xy 373.72163 -338.337144) (xy 373.731299 -338.325722) (xy 373.74407 -338.298671) (xy 373.748448 -338.269079)
			(xy 373.744057 -338.239489) (xy 373.731275 -338.212444) (xy 373.72163 -338.201) (xy 373.703177 -338.179876)
			(xy 373.67209 -338.133191) (xy 373.648181 -338.082453) (xy 373.631968 -338.028758) (xy 373.623802 -337.973267)
			(xy 373.623332 -337.945222) (xy 373.623818 -337.917971) (xy 373.631574 -337.864023) (xy 373.646929 -337.811728)
			(xy 373.669571 -337.762151) (xy 373.699037 -337.716301) (xy 373.734728 -337.67511) (xy 373.775919 -337.639419)
			(xy 373.821769 -337.609953) (xy 373.871346 -337.587311) (xy 373.923641 -337.571956) (xy 373.977589 -337.5642)
			(xy 374.032091 -337.5642) (xy 374.086039 -337.571956) (xy 374.138334 -337.587311) (xy 374.187911 -337.609953)
			(xy 374.233761 -337.639419) (xy 374.274952 -337.67511) (xy 374.310643 -337.716301) (xy 374.340109 -337.762151)
			(xy 374.362751 -337.811728) (xy 374.378106 -337.864023) (xy 374.385862 -337.917971) (xy 374.386348 -337.945222)
			(xy 374.385861 -337.973263) (xy 374.377658 -338.02874) (xy 374.36143 -338.082422) (xy 374.337527 -338.133154)
			(xy 374.306462 -338.179846) (xy 374.28805 -338.201) (xy 374.27843 -338.212462) (xy 374.265642 -338.239497)
			(xy 374.261249 -338.269079) (xy 374.26563 -338.298663) (xy 374.278406 -338.325704) (xy 374.28805 -338.337144)
			(xy 374.306473 -338.358293) (xy 374.337565 -338.404971) (xy 374.36148 -338.455703) (xy 374.377699 -338.509392)
			(xy 374.385874 -338.564879) (xy 374.386348 -338.592922) (xy 374.385862 -338.620173) (xy 374.378106 -338.674121)
			(xy 374.362751 -338.726416) (xy 374.340109 -338.775993) (xy 374.310643 -338.821843) (xy 374.274952 -338.863034)
			(xy 374.233761 -338.898725) (xy 374.187911 -338.928191) (xy 374.138334 -338.950833) (xy 374.086039 -338.966188)
			(xy 374.032091 -338.973944) (xy 373.977589 -338.973944) (xy 373.923641 -338.966188) (xy 373.871346 -338.950833)
			(xy 373.821769 -338.928191) (xy 373.775919 -338.898725) (xy 373.734728 -338.863034) (xy 373.699037 -338.821843)
			(xy 373.669571 -338.775993) (xy 373.646929 -338.726416) (xy 373.631574 -338.674121) (xy 373.623818 -338.620173)
			(xy 373.623332 -338.592922) (xy 368.35334 -338.592922) (xy 368.35334 -338.9892) (xy 377.871895 -338.9892)
			(xy 377.876064 -338.933575) (xy 377.888477 -338.879193) (xy 377.908856 -338.827269) (xy 377.936747 -338.778961)
			(xy 377.971527 -338.735351) (xy 378.012418 -338.697411) (xy 378.058507 -338.66599) (xy 378.108764 -338.641789)
			(xy 378.162068 -338.625349) (xy 378.217226 -338.617038) (xy 378.245116 -338.616544) (xy 378.27245 -338.616965)
			(xy 378.326532 -338.624943) (xy 378.378868 -338.64074) (xy 378.428332 -338.664016) (xy 378.473864 -338.694271)
			(xy 378.514485 -338.730857) (xy 378.549322 -338.772986) (xy 378.563886 -338.796122) (xy 378.571839 -338.808324)
			(xy 378.593304 -338.827993) (xy 378.619449 -338.840799) (xy 378.648146 -338.8457) (xy 378.677059 -338.842298)
			(xy 378.690632 -338.837016) (xy 378.713841 -338.827525) (xy 378.762174 -338.814174) (xy 378.811864 -338.807447)
			(xy 378.836936 -338.807044) (xy 378.862005 -338.807467) (xy 378.911688 -338.814217) (xy 378.960023 -338.82755)
			(xy 378.98324 -338.837016) (xy 378.996827 -338.842232) (xy 379.025723 -338.845603) (xy 379.054397 -338.840699)
			(xy 379.08053 -338.827917) (xy 379.102005 -338.808293) (xy 379.109986 -338.796122) (xy 379.124555 -338.772991)
			(xy 379.159398 -338.73087) (xy 379.200021 -338.694291) (xy 379.245552 -338.66404) (xy 379.295014 -338.640764)
			(xy 379.347345 -338.624964) (xy 379.401424 -338.616978) (xy 379.456088 -338.616978) (xy 379.510167 -338.624964)
			(xy 379.562498 -338.640764) (xy 379.61196 -338.66404) (xy 379.657491 -338.694291) (xy 379.698114 -338.73087)
			(xy 379.732957 -338.772991) (xy 379.747526 -338.796122) (xy 379.755441 -338.808351) (xy 379.776916 -338.82802)
			(xy 379.803071 -338.840823) (xy 379.831778 -338.845717) (xy 379.860698 -338.842304) (xy 379.874272 -338.837016)
			(xy 379.897488 -338.827544) (xy 379.945818 -338.814186) (xy 379.995505 -338.807451) (xy 380.020576 -338.807044)
			(xy 380.045517 -338.807416) (xy 380.094955 -338.814065) (xy 380.143064 -338.827247) (xy 380.188986 -338.846727)
			(xy 380.231899 -338.872158) (xy 380.251716 -338.887308) (xy 380.26328 -338.895793) (xy 380.289788 -338.906699)
			(xy 380.318285 -338.909788) (xy 380.346513 -338.904813) (xy 380.372238 -338.89217) (xy 380.393421 -338.872859)
			(xy 380.401322 -338.860892) (xy 380.416313 -338.837415) (xy 380.451977 -338.794632) (xy 380.493486 -338.757491)
			(xy 380.539956 -338.726784) (xy 380.590398 -338.703162) (xy 380.64374 -338.68713) (xy 380.698846 -338.679027)
			(xy 380.726696 -338.67852) (xy 380.754851 -338.678952) (xy 380.810552 -338.687216) (xy 380.864433 -338.703578)
			(xy 380.915323 -338.727684) (xy 380.962116 -338.75901) (xy 381.003795 -338.796875) (xy 381.039454 -338.840456)
			(xy 381.068319 -338.888806) (xy 381.089761 -338.940874) (xy 381.097028 -338.96808) (xy 381.101361 -338.983027)
			(xy 381.117615 -339.009543) (xy 381.141093 -339.029942) (xy 381.169619 -339.042335) (xy 381.200552 -339.045572)
			(xy 381.2159 -339.04301) (xy 381.234683 -339.039438) (xy 381.272728 -339.035624) (xy 381.291846 -339.03539)
			(xy 381.319095 -339.035883) (xy 381.373037 -339.043645) (xy 381.425326 -339.059004) (xy 381.474898 -339.081647)
			(xy 381.520742 -339.111115) (xy 381.561926 -339.146806) (xy 381.597613 -339.187995) (xy 381.627075 -339.233843)
			(xy 381.649712 -339.283417) (xy 381.665065 -339.335708) (xy 381.67282 -339.389651) (xy 381.67282 -339.444149)
			(xy 381.665065 -339.498092) (xy 381.649712 -339.550383) (xy 381.627075 -339.599957) (xy 381.597613 -339.645805)
			(xy 381.561926 -339.686994) (xy 381.520742 -339.722685) (xy 381.474898 -339.752153) (xy 381.425326 -339.774796)
			(xy 381.373037 -339.790155) (xy 381.319095 -339.797917) (xy 381.291846 -339.798406) (xy 381.263693 -339.797916)
			(xy 381.207995 -339.789659) (xy 381.154117 -339.773304) (xy 381.103229 -339.749205) (xy 381.056436 -339.717886)
			(xy 381.014757 -339.680028) (xy 380.979096 -339.636454) (xy 380.950229 -339.588111) (xy 380.928783 -339.536049)
			(xy 380.921514 -339.508846) (xy 380.917228 -339.493882) (xy 380.900967 -339.467358) (xy 380.877478 -339.446956)
			(xy 380.848939 -339.434569) (xy 380.817994 -339.431344) (xy 380.802642 -339.433916) (xy 380.783858 -339.437482)
			(xy 380.745814 -339.4413) (xy 380.726696 -339.441536) (xy 380.700531 -339.44109) (xy 380.648686 -339.43398)
			(xy 380.598303 -339.419839) (xy 380.550329 -339.398935) (xy 380.505669 -339.37166) (xy 380.485142 -339.35543)
			(xy 380.473724 -339.346722) (xy 380.44736 -339.335384) (xy 380.41888 -339.33185) (xy 380.390544 -339.3364)
			(xy 380.364601 -339.348673) (xy 380.343112 -339.367694) (xy 380.335028 -339.37956) (xy 380.3293 -339.388435)
			(xy 380.316971 -339.405588) (xy 380.31039 -339.41385) (xy 380.301159 -339.426158) (xy 380.289769 -339.454718)
			(xy 380.287381 -339.485373) (xy 380.29421 -339.515353) (xy 380.30964 -339.541948) (xy 380.332277 -339.562757)
			(xy 380.34595 -339.569806) (xy 380.369084 -339.581162) (xy 380.412323 -339.609201) (xy 380.451386 -339.642814)
			(xy 380.485561 -339.681387) (xy 380.514222 -339.724216) (xy 380.536847 -339.770519) (xy 380.54534 -339.79485)
			(xy 380.550438 -339.808602) (xy 380.567205 -339.832649) (xy 380.590102 -339.850956) (xy 380.61725 -339.862021)
			(xy 380.64642 -339.864934) (xy 380.66091 -339.862668) (xy 380.678835 -339.859457) (xy 380.715091 -339.856019)
			(xy 380.7333 -339.85581) (xy 380.760554 -339.856255) (xy 380.814506 -339.864013) (xy 380.866805 -339.87937)
			(xy 380.916387 -339.902014) (xy 380.962241 -339.931483) (xy 381.003434 -339.967179) (xy 381.039128 -340.008374)
			(xy 381.068595 -340.054229) (xy 381.091237 -340.103811) (xy 381.106591 -340.156111) (xy 381.114346 -340.210064)
			(xy 381.114808 -340.237318) (xy 381.114554 -340.247732) (xy 381.114676 -340.262099) (xy 381.12194 -340.289884)
			(xy 381.136646 -340.31455) (xy 381.157635 -340.334151) (xy 381.183249 -340.347138) (xy 381.211465 -340.352486)
			(xy 381.225806 -340.351618) (xy 381.262382 -340.34984) (xy 381.289639 -340.350206) (xy 381.343599 -340.357962)
			(xy 381.395906 -340.373318) (xy 381.445494 -340.395962) (xy 381.491355 -340.425434) (xy 381.532555 -340.461132)
			(xy 381.568256 -340.50233) (xy 381.597729 -340.54819) (xy 381.620376 -340.597778) (xy 381.635735 -340.650084)
			(xy 381.643493 -340.704043) (xy 381.643493 -340.758557) (xy 381.635735 -340.812516) (xy 381.620376 -340.864822)
			(xy 381.597729 -340.91441) (xy 381.568256 -340.96027) (xy 381.532555 -341.001468) (xy 381.491355 -341.037166)
			(xy 381.445494 -341.066638) (xy 381.395906 -341.089282) (xy 381.343599 -341.104638) (xy 381.289639 -341.112394)
			(xy 381.262382 -341.112856) (xy 381.251371 -341.112781) (xy 381.229386 -341.111508) (xy 381.21844 -341.110316)
			(xy 381.203582 -341.109091) (xy 381.174247 -341.11434) (xy 381.14768 -341.12784) (xy 381.126144 -341.148439)
			(xy 381.111478 -341.17438) (xy 381.107696 -341.188802) (xy 381.100847 -341.216546) (xy 381.07999 -341.269747)
			(xy 381.051435 -341.319245) (xy 381.015821 -341.363933) (xy 380.973944 -341.402814) (xy 380.926739 -341.435018)
			(xy 380.875262 -341.459826) (xy 380.820661 -341.476683) (xy 380.764158 -341.485214) (xy 380.735586 -341.485728)
			(xy 380.706599 -341.485189) (xy 380.649292 -341.476416) (xy 380.593972 -341.459074) (xy 380.541912 -341.433561)
			(xy 380.494312 -341.400467) (xy 380.452267 -341.360551) (xy 380.416744 -341.314734) (xy 380.388562 -341.26407)
			(xy 380.36837 -341.209726) (xy 380.356632 -341.152952) (xy 380.354586 -341.124032) (xy 380.353411 -341.109958)
			(xy 380.34432 -341.083231) (xy 380.328247 -341.060024) (xy 380.306424 -341.042115) (xy 380.280526 -341.030879)
			(xy 380.252539 -341.027179) (xy 380.238508 -341.028782) (xy 380.224743 -341.030678) (xy 380.19703 -341.032711)
			(xy 380.183136 -341.032846) (xy 380.155887 -341.032288) (xy 380.101944 -341.024538) (xy 380.049653 -341.009189)
			(xy 380.000079 -340.986555) (xy 379.95423 -340.957096) (xy 379.91304 -340.921412) (xy 379.877348 -340.880229)
			(xy 379.847881 -340.834386) (xy 379.825237 -340.784816) (xy 379.809878 -340.732528) (xy 379.802117 -340.678587)
			(xy 379.801628 -340.651338) (xy 379.80211 -340.623764) (xy 379.810058 -340.569191) (xy 379.825779 -340.516331)
			(xy 379.848946 -340.466285) (xy 379.879076 -340.420095) (xy 379.915542 -340.378724) (xy 379.936248 -340.360508)
			(xy 379.947111 -340.350573) (xy 379.963193 -340.325935) (xy 379.971585 -340.297735) (xy 379.971592 -340.268314)
			(xy 379.963214 -340.24011) (xy 379.947144 -340.215464) (xy 379.936248 -340.205568) (xy 379.915528 -340.187366)
			(xy 379.879056 -340.145997) (xy 379.848924 -340.099805) (xy 379.825759 -340.049755) (xy 379.810046 -339.99689)
			(xy 379.80211 -339.942313) (xy 379.801628 -339.914738) (xy 379.802058 -339.888236) (xy 379.809408 -339.835744)
			(xy 379.823958 -339.784775) (xy 379.845426 -339.736313) (xy 379.8734 -339.691292) (xy 379.89002 -339.670644)
			(xy 379.899478 -339.658509) (xy 379.911271 -339.630105) (xy 379.914094 -339.59948) (xy 379.907695 -339.569399)
			(xy 379.892649 -339.542576) (xy 379.870316 -339.521432) (xy 379.856746 -339.51418) (xy 379.833054 -339.502083)
			(xy 379.789072 -339.472159) (xy 379.749792 -339.436287) (xy 379.716009 -339.395195) (xy 379.701806 -339.372702)
			(xy 379.693854 -339.360498) (xy 379.672391 -339.340827) (xy 379.646245 -339.328019) (xy 379.617547 -339.323119)
			(xy 379.588632 -339.326524) (xy 379.57506 -339.331808) (xy 379.551852 -339.341303) (xy 379.503518 -339.354652)
			(xy 379.453828 -339.361378) (xy 379.428756 -339.36178) (xy 379.403687 -339.361358) (xy 379.354004 -339.354608)
			(xy 379.305669 -339.341274) (xy 379.282452 -339.331808) (xy 379.26887 -339.326573) (xy 379.239972 -339.323203)
			(xy 379.211294 -339.32811) (xy 379.18516 -339.340897) (xy 379.163686 -339.360528) (xy 379.155706 -339.372702)
			(xy 379.141137 -339.395833) (xy 379.106294 -339.437954) (xy 379.065671 -339.474533) (xy 379.02014 -339.504784)
			(xy 378.970678 -339.52806) (xy 378.918347 -339.54386) (xy 378.864268 -339.551846) (xy 378.809604 -339.551846)
			(xy 378.755525 -339.54386) (xy 378.703194 -339.52806) (xy 378.653732 -339.504784) (xy 378.608201 -339.474533)
			(xy 378.567578 -339.437954) (xy 378.532735 -339.395833) (xy 378.518166 -339.372702) (xy 378.510252 -339.360471)
			(xy 378.488779 -339.340799) (xy 378.462623 -339.327995) (xy 378.433915 -339.323102) (xy 378.404994 -339.326518)
			(xy 378.39142 -339.331808) (xy 378.368205 -339.341284) (xy 378.319875 -339.35464) (xy 378.270187 -339.361374)
			(xy 378.245116 -339.36178) (xy 378.217226 -339.361362) (xy 378.162068 -339.353051) (xy 378.108764 -339.336611)
			(xy 378.058507 -339.31241) (xy 378.012418 -339.280989) (xy 377.971527 -339.243049) (xy 377.936747 -339.199439)
			(xy 377.908856 -339.151131) (xy 377.888477 -339.099207) (xy 377.876064 -339.044825) (xy 377.871895 -338.9892)
			(xy 368.35334 -338.9892) (xy 368.35334 -339.783166) (xy 368.352753 -339.808151) (xy 368.343003 -339.85716)
			(xy 368.323888 -339.90333) (xy 368.296143 -339.944889) (xy 368.278918 -339.962998) (xy 367.61072 -340.631272)
			(xy 374.003316 -340.631272) (xy 374.003769 -340.603734) (xy 374.011666 -340.549227) (xy 374.027321 -340.496423)
			(xy 374.050409 -340.44642) (xy 374.080448 -340.400257) (xy 374.116816 -340.358896) (xy 374.158754 -340.323195)
			(xy 374.205391 -340.293897) (xy 374.255757 -340.271613) (xy 374.308805 -340.256804) (xy 374.336056 -340.252812)
			(xy 374.349853 -340.250659) (xy 374.375538 -340.239719) (xy 374.397306 -340.222238) (xy 374.413534 -340.199522)
			(xy 374.423013 -340.173262) (xy 374.425036 -340.145418) (xy 374.42267 -340.131654) (xy 374.419017 -340.112687)
			(xy 374.415068 -340.07426) (xy 374.414796 -340.054946) (xy 374.415282 -340.027695) (xy 374.423038 -339.973747)
			(xy 374.438393 -339.921452) (xy 374.461035 -339.871875) (xy 374.490501 -339.826025) (xy 374.526192 -339.784834)
			(xy 374.567383 -339.749143) (xy 374.613233 -339.719677) (xy 374.66281 -339.697035) (xy 374.715105 -339.68168)
			(xy 374.769053 -339.673924) (xy 374.823555 -339.673924) (xy 374.877503 -339.68168) (xy 374.929798 -339.697035)
			(xy 374.979375 -339.719677) (xy 375.025225 -339.749143) (xy 375.066416 -339.784834) (xy 375.102107 -339.826025)
			(xy 375.131573 -339.871875) (xy 375.154215 -339.921452) (xy 375.16957 -339.973747) (xy 375.177326 -340.027695)
			(xy 375.177812 -340.054946) (xy 375.177351 -340.082484) (xy 375.169452 -340.136989) (xy 375.153796 -340.189791)
			(xy 375.130709 -340.239793) (xy 375.10067 -340.285954) (xy 375.064304 -340.327316) (xy 375.022367 -340.363016)
			(xy 374.975732 -340.392315) (xy 374.925368 -340.414601) (xy 374.872322 -340.429412) (xy 374.845072 -340.433406)
			(xy 374.831299 -340.435672) (xy 374.805626 -340.446595) (xy 374.783863 -340.464053) (xy 374.767632 -340.486746)
			(xy 374.758143 -340.512982) (xy 374.756103 -340.540807) (xy 374.758458 -340.554564) (xy 374.762114 -340.573531)
			(xy 374.766061 -340.611958) (xy 374.766332 -340.631272) (xy 374.765846 -340.658523) (xy 374.75809 -340.712471)
			(xy 374.742735 -340.764766) (xy 374.720093 -340.814343) (xy 374.690627 -340.860193) (xy 374.654936 -340.901384)
			(xy 374.613745 -340.937075) (xy 374.567895 -340.966541) (xy 374.518318 -340.989183) (xy 374.466023 -341.004538)
			(xy 374.412075 -341.012294) (xy 374.357573 -341.012294) (xy 374.303625 -341.004538) (xy 374.25133 -340.989183)
			(xy 374.201753 -340.966541) (xy 374.155903 -340.937075) (xy 374.114712 -340.901384) (xy 374.079021 -340.860193)
			(xy 374.049555 -340.814343) (xy 374.026913 -340.764766) (xy 374.011558 -340.712471) (xy 374.003802 -340.658523)
			(xy 374.003316 -340.631272) (xy 367.61072 -340.631272) (xy 366.0521 -342.19007) (xy 366.0521 -343.944632)
			(xy 367.216178 -343.944632) (xy 367.216178 -343.859936) (xy 367.224229 -343.775622) (xy 367.240258 -343.692456)
			(xy 367.264119 -343.611189) (xy 367.295598 -343.532559) (xy 367.334409 -343.457278) (xy 367.380199 -343.386026)
			(xy 367.432555 -343.31945) (xy 367.491003 -343.258152) (xy 367.555013 -343.202687) (xy 367.624005 -343.153558)
			(xy 367.697355 -343.111209) (xy 367.774398 -343.076025) (xy 367.854437 -343.048323) (xy 367.936746 -343.028355)
			(xy 368.020581 -343.016302) (xy 368.105182 -343.012272) (xy 368.189783 -343.016302) (xy 368.273618 -343.028355)
			(xy 368.355927 -343.048323) (xy 368.435966 -343.076025) (xy 368.513009 -343.111209) (xy 368.586359 -343.153558)
			(xy 368.655351 -343.202687) (xy 368.719361 -343.258152) (xy 368.777809 -343.31945) (xy 368.830165 -343.386026)
			(xy 368.875955 -343.457278) (xy 368.914766 -343.532559) (xy 368.946245 -343.611189) (xy 368.970106 -343.692456)
			(xy 368.986135 -343.775622) (xy 368.994186 -343.859936) (xy 368.99469 -343.902284) (xy 369.740691 -343.902284)
			(xy 369.744727 -343.818837) (xy 369.756799 -343.736169) (xy 369.776792 -343.655052) (xy 369.804521 -343.576243)
			(xy 369.839727 -343.500478) (xy 369.882081 -343.428465) (xy 369.931187 -343.360876) (xy 369.986588 -343.298342)
			(xy 370.047765 -343.241447) (xy 370.114148 -343.190721) (xy 370.185116 -343.14664) (xy 370.260008 -343.109614)
			(xy 370.338124 -343.079988) (xy 370.418734 -343.05804) (xy 370.501086 -343.043975) (xy 370.584412 -343.037923)
			(xy 370.667932 -343.039942) (xy 370.750868 -343.050012) (xy 370.832444 -343.06804) (xy 370.9119 -343.093857)
			(xy 370.988493 -343.127222) (xy 371.061509 -343.167823) (xy 371.130265 -343.215282) (xy 371.194119 -343.269155)
			(xy 371.252476 -343.32894) (xy 371.304791 -343.394077) (xy 371.350574 -343.46396) (xy 371.389399 -343.537935)
			(xy 371.420904 -343.615312) (xy 371.444793 -343.695369) (xy 371.460844 -343.777357) (xy 371.468907 -343.860512)
			(xy 371.469412 -343.902284) (xy 371.468907 -343.944056) (xy 371.460844 -344.027211) (xy 371.444793 -344.109199)
			(xy 371.420904 -344.189256) (xy 371.389399 -344.266633) (xy 371.350574 -344.340608) (xy 371.304791 -344.410491)
			(xy 371.252476 -344.475628) (xy 371.194119 -344.535413) (xy 371.130265 -344.589286) (xy 371.061509 -344.636745)
			(xy 370.988493 -344.677346) (xy 370.9119 -344.710711) (xy 370.832444 -344.736528) (xy 370.750868 -344.754556)
			(xy 370.667932 -344.764626) (xy 370.584412 -344.766645) (xy 370.501086 -344.760593) (xy 370.418734 -344.746528)
			(xy 370.338124 -344.72458) (xy 370.260008 -344.694954) (xy 370.185116 -344.657928) (xy 370.114148 -344.613847)
			(xy 370.047765 -344.563121) (xy 369.986588 -344.506226) (xy 369.931187 -344.443692) (xy 369.882081 -344.376103)
			(xy 369.839727 -344.30409) (xy 369.804521 -344.228325) (xy 369.776792 -344.149516) (xy 369.756799 -344.068399)
			(xy 369.744727 -343.985731) (xy 369.740691 -343.902284) (xy 368.99469 -343.902284) (xy 368.994186 -343.944632)
			(xy 368.986135 -344.028946) (xy 368.970106 -344.112112) (xy 368.946245 -344.193379) (xy 368.914766 -344.272009)
			(xy 368.875955 -344.34729) (xy 368.830165 -344.418542) (xy 368.777809 -344.485118) (xy 368.719361 -344.546416)
			(xy 368.655351 -344.601881) (xy 368.586359 -344.65101) (xy 368.513009 -344.693359) (xy 368.435966 -344.728543)
			(xy 368.355927 -344.756245) (xy 368.273618 -344.776213) (xy 368.189783 -344.788266) (xy 368.105182 -344.792297)
			(xy 368.020581 -344.788266) (xy 367.936746 -344.776213) (xy 367.854437 -344.756245) (xy 367.774398 -344.728543)
			(xy 367.697355 -344.693359) (xy 367.624005 -344.65101) (xy 367.555013 -344.601881) (xy 367.491003 -344.546416)
			(xy 367.432555 -344.485118) (xy 367.380199 -344.418542) (xy 367.334409 -344.34729) (xy 367.295598 -344.272009)
			(xy 367.264119 -344.193379) (xy 367.240258 -344.112112) (xy 367.224229 -344.028946) (xy 367.216178 -343.944632)
			(xy 366.0521 -343.944632) (xy 366.0521 -344.554048) (xy 366.051454 -344.579044) (xy 366.041656 -344.628067)
			(xy 366.022486 -344.674238) (xy 365.994679 -344.715784) (xy 365.977424 -344.73388) (xy 361.159552 -349.551752)
			(xy 361.141463 -349.569016) (xy 361.099917 -349.596827) (xy 361.053743 -349.615998) (xy 361.004717 -349.625794)
			(xy 360.97972 -349.626428) (xy 358.593644 -349.626428) (xy 358.518206 -349.701612) (xy 358.54259 -349.765112)
			(xy 359.44683 -349.765112) (xy 359.5116 -349.829628) (xy 361.573318 -349.829628) (xy 365.329724 -346.073476)
			(xy 365.347812 -346.056212) (xy 365.38936 -346.028404) (xy 365.435533 -346.009233) (xy 365.484559 -345.999436)
			(xy 365.509556 -345.9988) (xy 374.448324 -345.9988) (xy 375.551192 -344.895932) (xy 375.551192 -342.02878)
			(xy 375.51233 -342.019382) (xy 375.484998 -342.012197) (xy 375.432662 -341.990878) (xy 375.384043 -341.962074)
			(xy 375.340203 -341.926415) (xy 375.302101 -341.88468) (xy 375.270571 -341.837783) (xy 375.246302 -341.786748)
			(xy 375.229824 -341.732692) (xy 375.221499 -341.676798) (xy 375.220992 -341.648542) (xy 375.221581 -341.618855)
			(xy 375.230773 -341.560198) (xy 375.248942 -341.503673) (xy 375.275649 -341.450645) (xy 375.310249 -341.402396)
			(xy 375.351906 -341.360089) (xy 375.375424 -341.341964) (xy 375.386 -341.333502) (xy 375.402704 -341.312197)
			(xy 375.413223 -341.287251) (xy 375.416816 -341.260418) (xy 375.413232 -341.233583) (xy 375.402723 -341.208634)
			(xy 375.386026 -341.187323) (xy 375.375424 -341.178896) (xy 375.351917 -341.160756) (xy 375.310255 -341.118454)
			(xy 375.275649 -341.070208) (xy 375.248936 -341.017184) (xy 375.230759 -340.960661) (xy 375.221558 -340.902005)
			(xy 375.220992 -340.872318) (xy 375.221455 -340.845053) (xy 375.229216 -340.791077) (xy 375.244583 -340.738757)
			(xy 375.267243 -340.689158) (xy 375.296735 -340.64329) (xy 375.332456 -340.602089) (xy 375.373679 -340.566393)
			(xy 375.419565 -340.53693) (xy 375.469179 -340.514301) (xy 375.521508 -340.498966) (xy 375.575488 -340.491238)
			(xy 375.630019 -340.491274) (xy 375.683989 -340.499074) (xy 375.736298 -340.514479) (xy 375.785881 -340.537174)
			(xy 375.831728 -340.566698) (xy 375.872904 -340.602449) (xy 375.90857 -340.643698) (xy 375.938 -340.689604)
			(xy 375.960594 -340.739234) (xy 375.975892 -340.791575) (xy 375.983581 -340.84556) (xy 375.984008 -340.872826)
			(xy 375.984008 -340.894162) (xy 376.083576 -340.99373) (xy 376.094567 -341.003981) (xy 376.121096 -341.018079)
			(xy 376.150578 -341.023859) (xy 376.180467 -341.020823) (xy 376.208184 -341.009233) (xy 376.231337 -340.99009)
			(xy 376.247929 -340.965044) (xy 376.25274 -340.950804) (xy 376.261009 -340.924918) (xy 376.28377 -340.875574)
			(xy 376.313301 -340.829958) (xy 376.349003 -340.788992) (xy 376.390155 -340.753504) (xy 376.435924 -340.724213)
			(xy 376.485386 -340.701709) (xy 376.537539 -340.68645) (xy 376.59133 -340.678742) (xy 376.6185 -340.678262)
			(xy 376.618754 -340.678262) (xy 376.643957 -340.678679) (xy 376.693925 -340.685313) (xy 376.742579 -340.698484)
			(xy 376.78907 -340.717962) (xy 376.811032 -340.730332) (xy 376.823986 -340.737393) (xy 376.852628 -340.744427)
			(xy 376.882085 -340.74298) (xy 376.909899 -340.733173) (xy 376.93375 -340.715825) (xy 376.951646 -340.692384)
			(xy 376.957336 -340.67877) (xy 376.968053 -340.652003) (xy 376.996339 -340.601763) (xy 377.031867 -340.556355)
			(xy 377.073826 -340.516813) (xy 377.12126 -340.484038) (xy 377.173088 -340.458779) (xy 377.228127 -340.44161)
			(xy 377.285124 -340.432922) (xy 377.313952 -340.43239) (xy 377.341204 -340.4329) (xy 377.395153 -340.44065)
			(xy 377.44745 -340.456) (xy 377.497029 -340.478637) (xy 377.542883 -340.5081) (xy 377.584076 -340.543789)
			(xy 377.61977 -340.584977) (xy 377.649239 -340.630827) (xy 377.671882 -340.680403) (xy 377.687239 -340.732698)
			(xy 377.694996 -340.786646) (xy 377.69546 -340.813898) (xy 377.69546 -340.814152) (xy 377.694888 -340.843991)
			(xy 377.68557 -340.902937) (xy 377.676918 -340.9315) (xy 377.672932 -340.945422) (xy 377.672009 -340.974348)
			(xy 377.679262 -341.002366) (xy 377.694105 -341.027211) (xy 377.715339 -341.046875) (xy 377.741249 -341.059771)
			(xy 377.755404 -341.062818) (xy 377.781473 -341.068005) (xy 377.831977 -341.084573) (xy 377.87969 -341.107993)
			(xy 377.923689 -341.137813) (xy 377.96312 -341.173454) (xy 377.99722 -341.214225) (xy 378.025327 -341.259337)
			(xy 378.046897 -341.307914) (xy 378.061513 -341.359017) (xy 378.06889 -341.411654) (xy 378.069348 -341.43823)
			(xy 378.068862 -341.465481) (xy 378.061106 -341.519429) (xy 378.045751 -341.571724) (xy 378.023109 -341.621301)
			(xy 377.993643 -341.667151) (xy 377.957952 -341.708342) (xy 377.916761 -341.744033) (xy 377.870911 -341.773499)
			(xy 377.821334 -341.796141) (xy 377.769039 -341.811496) (xy 377.715091 -341.819252) (xy 377.660589 -341.819252)
			(xy 377.606641 -341.811496) (xy 377.554346 -341.796141) (xy 377.504769 -341.773499) (xy 377.458919 -341.744033)
			(xy 377.417728 -341.708342) (xy 377.382037 -341.667151) (xy 377.352571 -341.621301) (xy 377.329929 -341.571724)
			(xy 377.314574 -341.519429) (xy 377.306818 -341.465481) (xy 377.306332 -341.43823) (xy 377.306332 -341.437976)
			(xy 377.306911 -341.408137) (xy 377.316224 -341.349191) (xy 377.324874 -341.320628) (xy 377.328947 -341.306729)
			(xy 377.329854 -341.27779) (xy 377.322584 -341.249764) (xy 377.307724 -341.224915) (xy 377.286474 -341.205249)
			(xy 377.26055 -341.192355) (xy 377.246388 -341.18931) (xy 377.213548 -341.182731) (xy 377.150696 -341.159605)
			(xy 377.12142 -341.143336) (xy 377.108428 -341.136353) (xy 377.079802 -341.129314) (xy 377.050359 -341.13075)
			(xy 377.022554 -341.140542) (xy 376.998708 -341.157871) (xy 376.980809 -341.181294) (xy 376.975116 -341.194898)
			(xy 376.964422 -341.221675) (xy 376.936135 -341.271918) (xy 376.900605 -341.317328) (xy 376.858643 -341.356871)
			(xy 376.811205 -341.389645) (xy 376.759374 -341.414902) (xy 376.70433 -341.432068) (xy 376.647329 -341.440749)
			(xy 376.6185 -341.441278) (xy 376.603448 -341.441106) (xy 376.573441 -341.438692) (xy 376.558556 -341.436452)
			(xy 376.544003 -341.434743) (xy 376.514973 -341.438573) (xy 376.488225 -341.450488) (xy 376.46596 -341.469508)
			(xy 376.450012 -341.494066) (xy 376.441693 -341.522141) (xy 376.441208 -341.536782) (xy 376.441208 -344.377264)
			(xy 381.783844 -344.377264) (xy 381.784278 -344.349892) (xy 381.792102 -344.295712) (xy 381.807598 -344.243208)
			(xy 381.830447 -344.193461) (xy 381.860179 -344.147496) (xy 381.877824 -344.126566) (xy 381.887094 -344.115264)
			(xy 381.899264 -344.088697) (xy 381.903429 -344.059773) (xy 381.899248 -344.030851) (xy 381.887064 -344.00429)
			(xy 381.877824 -343.992962) (xy 381.860204 -343.972014) (xy 381.830489 -343.926046) (xy 381.807649 -343.876303)
			(xy 381.792153 -343.823805) (xy 381.78432 -343.769632) (xy 381.783844 -343.742264) (xy 381.78433 -343.715013)
			(xy 381.792086 -343.661065) (xy 381.807441 -343.60877) (xy 381.830083 -343.559193) (xy 381.859549 -343.513343)
			(xy 381.89524 -343.472152) (xy 381.936431 -343.436461) (xy 381.982281 -343.406995) (xy 382.031858 -343.384353)
			(xy 382.084153 -343.368998) (xy 382.138101 -343.361242) (xy 382.192603 -343.361242) (xy 382.246551 -343.368998)
			(xy 382.298846 -343.384353) (xy 382.348423 -343.406995) (xy 382.394273 -343.436461) (xy 382.435464 -343.472152)
			(xy 382.471155 -343.513343) (xy 382.500621 -343.559193) (xy 382.523263 -343.60877) (xy 382.538618 -343.661065)
			(xy 382.546374 -343.715013) (xy 382.54686 -343.742264) (xy 382.546383 -343.769634) (xy 382.538569 -343.823813)
			(xy 382.523083 -343.876316) (xy 382.500244 -343.926063) (xy 382.470521 -343.97203) (xy 382.45288 -343.992962)
			(xy 382.443679 -344.004316) (xy 382.4315 -344.030864) (xy 382.427322 -344.059773) (xy 382.431485 -344.088683)
			(xy 382.44365 -344.115238) (xy 382.45288 -344.126566) (xy 382.470514 -344.147503) (xy 382.500227 -344.193474)
			(xy 382.523064 -344.24322) (xy 382.538557 -344.29572) (xy 382.546386 -344.349895) (xy 382.54686 -344.377264)
			(xy 382.546374 -344.404515) (xy 382.538618 -344.458463) (xy 382.523263 -344.510758) (xy 382.500621 -344.560335)
			(xy 382.471155 -344.606185) (xy 382.435464 -344.647376) (xy 382.394273 -344.683067) (xy 382.348423 -344.712533)
			(xy 382.298846 -344.735175) (xy 382.246551 -344.75053) (xy 382.192603 -344.758286) (xy 382.138101 -344.758286)
			(xy 382.084153 -344.75053) (xy 382.031858 -344.735175) (xy 381.982281 -344.712533) (xy 381.936431 -344.683067)
			(xy 381.89524 -344.647376) (xy 381.859549 -344.606185) (xy 381.830083 -344.560335) (xy 381.807441 -344.510758)
			(xy 381.792086 -344.458463) (xy 381.78433 -344.404515) (xy 381.783844 -344.377264) (xy 376.441208 -344.377264)
			(xy 376.441208 -344.7799) (xy 386.032387 -344.7799) (xy 386.036556 -344.724273) (xy 386.04897 -344.669889)
			(xy 386.069351 -344.617962) (xy 386.097243 -344.569653) (xy 386.132025 -344.526041) (xy 386.172918 -344.488101)
			(xy 386.21901 -344.456679) (xy 386.26927 -344.432478) (xy 386.322576 -344.416039) (xy 386.377736 -344.407729)
			(xy 386.405628 -344.407236) (xy 386.432959 -344.407731) (xy 386.487038 -344.415696) (xy 386.539372 -344.43148)
			(xy 386.588836 -344.454744) (xy 386.634369 -344.484988) (xy 386.674992 -344.521563) (xy 386.709832 -344.563683)
			(xy 386.724398 -344.586814) (xy 386.732342 -344.599023) (xy 386.753808 -344.618693) (xy 386.779956 -344.631498)
			(xy 386.808656 -344.636398) (xy 386.837571 -344.632992) (xy 386.851144 -344.627708) (xy 386.874352 -344.618213)
			(xy 386.922686 -344.604864) (xy 386.972376 -344.598138) (xy 386.997448 -344.597736) (xy 387.022517 -344.598156)
			(xy 387.072201 -344.604907) (xy 387.120535 -344.618241) (xy 387.143752 -344.627708) (xy 387.157334 -344.63294)
			(xy 387.186232 -344.636309) (xy 387.214909 -344.631401) (xy 387.241043 -344.618616) (xy 387.262517 -344.598987)
			(xy 387.270498 -344.586814) (xy 387.285067 -344.563683) (xy 387.31991 -344.521562) (xy 387.360533 -344.484983)
			(xy 387.406064 -344.454732) (xy 387.455526 -344.431456) (xy 387.507857 -344.415656) (xy 387.561936 -344.40767)
			(xy 387.6166 -344.40767) (xy 387.670679 -344.415656) (xy 387.72301 -344.431456) (xy 387.772472 -344.454732)
			(xy 387.818003 -344.484983) (xy 387.858626 -344.521562) (xy 387.893469 -344.563683) (xy 387.908038 -344.586814)
			(xy 387.915944 -344.59905) (xy 387.937421 -344.61872) (xy 387.963579 -344.631522) (xy 387.992288 -344.636414)
			(xy 388.021209 -344.632998) (xy 388.034784 -344.627708) (xy 388.057999 -344.618232) (xy 388.106329 -344.604875)
			(xy 388.156017 -344.598142) (xy 388.181088 -344.597736) (xy 388.207932 -344.598171) (xy 388.261065 -344.605875)
			(xy 388.312542 -344.621125) (xy 388.361297 -344.643606) (xy 388.406321 -344.672851) (xy 388.446681 -344.708256)
			(xy 388.481541 -344.749087) (xy 388.510181 -344.794499) (xy 388.532006 -344.843551) (xy 388.539736 -344.869262)
			(xy 388.544362 -344.883773) (xy 388.560887 -344.909341) (xy 388.584211 -344.928907) (xy 388.612263 -344.940734)
			(xy 388.642554 -344.943775) (xy 388.672397 -344.937757) (xy 388.68604 -344.930984) (xy 388.714189 -344.916356)
			(xy 388.774138 -344.895627) (xy 388.836696 -344.885126) (xy 388.868412 -344.884502) (xy 388.886431 -344.884725)
			(xy 388.922306 -344.888158) (xy 388.94004 -344.89136) (xy 388.955244 -344.893737) (xy 388.985802 -344.890199)
			(xy 389.013922 -344.877728) (xy 389.037058 -344.857454) (xy 389.053113 -344.831214) (xy 389.057388 -344.81643)
			(xy 389.064795 -344.789389) (xy 389.086426 -344.737665) (xy 389.11539 -344.689661) (xy 389.151065 -344.64641)
			(xy 389.192683 -344.608844) (xy 389.239348 -344.577769) (xy 389.290058 -344.553856) (xy 389.343719 -344.537617)
			(xy 389.39918 -344.529403) (xy 389.427212 -344.528902) (xy 389.454464 -344.529367) (xy 389.508413 -344.537125)
			(xy 389.560709 -344.552482) (xy 389.610287 -344.575125) (xy 389.656138 -344.604594) (xy 389.697328 -344.640288)
			(xy 389.733019 -344.68148) (xy 389.762485 -344.727333) (xy 389.785125 -344.776912) (xy 389.80048 -344.829209)
			(xy 389.808235 -344.883158) (xy 389.80872 -344.91041) (xy 389.808185 -344.937982) (xy 389.800246 -344.992551)
			(xy 389.784534 -345.04541) (xy 389.761377 -345.095456) (xy 389.731257 -345.141647) (xy 389.694801 -345.183022)
			(xy 389.6741 -345.20124) (xy 389.663193 -345.211129) (xy 389.647122 -345.235782) (xy 389.638739 -345.263992)
			(xy 389.638741 -345.293421) (xy 389.647127 -345.32163) (xy 389.663202 -345.346281) (xy 389.6741 -345.35618)
			(xy 389.694815 -345.374385) (xy 389.731279 -345.415758) (xy 389.761405 -345.461949) (xy 389.784567 -345.511998)
			(xy 389.800281 -345.564859) (xy 389.808221 -345.619433) (xy 389.80822 -345.67458) (xy 389.800279 -345.729153)
			(xy 389.784563 -345.782015) (xy 389.761399 -345.832062) (xy 389.731271 -345.878253) (xy 389.694806 -345.919624)
			(xy 389.6741 -345.93784) (xy 389.663193 -345.947729) (xy 389.647122 -345.972382) (xy 389.638739 -346.000592)
			(xy 389.638741 -346.030021) (xy 389.647127 -346.05823) (xy 389.663202 -346.082881) (xy 389.6741 -346.09278)
			(xy 389.694805 -346.110998) (xy 389.731275 -346.152365) (xy 389.761408 -346.198554) (xy 389.784575 -346.2486)
			(xy 389.800293 -346.301462) (xy 389.808234 -346.356036) (xy 389.80872 -346.38361) (xy 389.808232 -346.410861)
			(xy 389.800474 -346.464808) (xy 389.785118 -346.517102) (xy 389.762477 -346.566678) (xy 389.733011 -346.612528)
			(xy 389.697319 -346.653718) (xy 389.65613 -346.689409) (xy 389.61028 -346.718876) (xy 389.560704 -346.741517)
			(xy 389.50841 -346.756874) (xy 389.454463 -346.764631) (xy 389.427212 -346.765118) (xy 389.399358 -346.764571)
			(xy 389.344244 -346.756449) (xy 389.290895 -346.740406) (xy 389.240443 -346.716782) (xy 389.193959 -346.686078)
			(xy 389.152429 -346.648946) (xy 389.116736 -346.606174) (xy 389.087635 -346.55867) (xy 389.065746 -346.507442)
			(xy 389.05815 -346.480638) (xy 389.053874 -346.466522) (xy 389.038487 -346.441374) (xy 389.01657 -346.421656)
			(xy 388.98994 -346.409005) (xy 388.96081 -346.404471) (xy 388.946136 -346.405962) (xy 388.93312 -346.407636)
			(xy 388.906935 -346.409413) (xy 388.893812 -346.409518) (xy 388.879663 -346.409423) (xy 388.85144 -346.40739)
			(xy 388.837424 -346.405454) (xy 388.82408 -346.403805) (xy 388.797379 -346.40691) (xy 388.772419 -346.416889)
			(xy 388.750936 -346.433048) (xy 388.734426 -346.454261) (xy 388.724036 -346.479053) (xy 388.721854 -346.492322)
			(xy 388.717712 -346.519466) (xy 388.702744 -346.572294) (xy 388.680358 -346.62243) (xy 388.651017 -346.668839)
			(xy 388.615326 -346.710563) (xy 388.574022 -346.74674) (xy 388.527959 -346.776623) (xy 388.478089 -346.799595)
			(xy 388.42544 -346.81518) (xy 388.371101 -346.823057) (xy 388.343648 -346.823538) (xy 388.316398 -346.823)
			(xy 388.262451 -346.81525) (xy 388.210156 -346.799902) (xy 388.160578 -346.777267) (xy 388.114726 -346.747807)
			(xy 388.073534 -346.712121) (xy 388.03784 -346.670936) (xy 388.00837 -346.62509) (xy 387.985725 -346.575517)
			(xy 387.970366 -346.523225) (xy 387.962605 -346.46928) (xy 387.96214 -346.44203) (xy 387.962612 -346.414456)
			(xy 387.970562 -346.359882) (xy 387.986284 -346.307022) (xy 388.009453 -346.256976) (xy 388.039585 -346.210786)
			(xy 388.076053 -346.169415) (xy 388.09676 -346.1512) (xy 388.10763 -346.141273) (xy 388.12371 -346.116632)
			(xy 388.1321 -346.088431) (xy 388.132106 -346.059008) (xy 388.123726 -346.030803) (xy 388.107656 -346.006157)
			(xy 388.09676 -345.99626) (xy 388.076067 -345.97803) (xy 388.039597 -345.936664) (xy 388.009463 -345.890478)
			(xy 387.986295 -345.840434) (xy 387.970574 -345.787575) (xy 387.962629 -345.733003) (xy 387.96214 -345.70543)
			(xy 387.962563 -345.678928) (xy 387.969914 -345.626435) (xy 387.984465 -345.575466) (xy 388.005935 -345.527005)
			(xy 388.033911 -345.481984) (xy 388.050532 -345.461336) (xy 388.059995 -345.449205) (xy 388.071785 -345.4208)
			(xy 388.074606 -345.390175) (xy 388.068206 -345.360093) (xy 388.05316 -345.33327) (xy 388.030828 -345.312125)
			(xy 388.017258 -345.304872) (xy 387.993566 -345.292774) (xy 387.949585 -345.262851) (xy 387.910304 -345.226979)
			(xy 387.876521 -345.185887) (xy 387.862318 -345.163394) (xy 387.854357 -345.151197) (xy 387.832896 -345.131527)
			(xy 387.806753 -345.118719) (xy 387.778056 -345.113816) (xy 387.749144 -345.117218) (xy 387.735572 -345.1225)
			(xy 387.712363 -345.13199) (xy 387.664029 -345.145341) (xy 387.61434 -345.152069) (xy 387.589268 -345.152472)
			(xy 387.564199 -345.152047) (xy 387.514516 -345.145298) (xy 387.466181 -345.131966) (xy 387.442964 -345.1225)
			(xy 387.429377 -345.117281) (xy 387.400481 -345.113909) (xy 387.371806 -345.118813) (xy 387.345673 -345.131595)
			(xy 387.324198 -345.151222) (xy 387.316218 -345.163394) (xy 387.301649 -345.186525) (xy 387.266806 -345.228646)
			(xy 387.226183 -345.265225) (xy 387.180652 -345.295476) (xy 387.13119 -345.318752) (xy 387.078859 -345.334552)
			(xy 387.02478 -345.342538) (xy 386.970116 -345.342538) (xy 386.916037 -345.334552) (xy 386.863706 -345.318752)
			(xy 386.814244 -345.295476) (xy 386.768713 -345.265225) (xy 386.72809 -345.228646) (xy 386.693247 -345.186525)
			(xy 386.678678 -345.163394) (xy 386.670755 -345.15117) (xy 386.649283 -345.131499) (xy 386.62313 -345.118695)
			(xy 386.594425 -345.1138) (xy 386.565506 -345.117212) (xy 386.551932 -345.1225) (xy 386.528715 -345.131972)
			(xy 386.480386 -345.14533) (xy 386.430699 -345.152065) (xy 386.405628 -345.152472) (xy 386.377736 -345.152071)
			(xy 386.322576 -345.143761) (xy 386.26927 -345.127322) (xy 386.21901 -345.103121) (xy 386.172918 -345.071699)
			(xy 386.132025 -345.033759) (xy 386.097243 -344.990147) (xy 386.069351 -344.941838) (xy 386.04897 -344.889911)
			(xy 386.036556 -344.835527) (xy 386.032387 -344.7799) (xy 376.441208 -344.7799) (xy 376.441208 -345.15933)
			(xy 376.44061 -345.184328) (xy 376.430797 -345.233354) (xy 376.411613 -345.279525) (xy 376.383793 -345.321068)
			(xy 376.366532 -345.339162) (xy 375.16865 -346.537044) (xy 382.033826 -346.537044) (xy 382.033826 -346.482551)
			(xy 382.041582 -346.428612) (xy 382.056934 -346.376326) (xy 382.079571 -346.326756) (xy 382.109032 -346.280913)
			(xy 382.144717 -346.239729) (xy 382.185899 -346.204042) (xy 382.231741 -346.174579) (xy 382.281309 -346.15194)
			(xy 382.333595 -346.136585) (xy 382.387533 -346.128828) (xy 382.41478 -346.12834) (xy 382.43435 -346.128544)
			(xy 382.473291 -346.132488) (xy 382.492504 -346.136214) (xy 382.506172 -346.138647) (xy 382.533865 -346.136801)
			(xy 382.560034 -346.127559) (xy 382.582744 -346.111605) (xy 382.600312 -346.090118) (xy 382.611437 -346.064692)
			(xy 382.615296 -346.037208) (xy 382.611603 -346.009701) (xy 382.60655 -345.996768) (xy 382.596661 -345.972815)
			(xy 382.582754 -345.922894) (xy 382.57574 -345.871549) (xy 382.575308 -345.845638) (xy 382.575714 -345.818382)
			(xy 382.583467 -345.764424) (xy 382.59882 -345.712119) (xy 382.62146 -345.662531) (xy 382.650927 -345.61667)
			(xy 382.686621 -345.57547) (xy 382.727815 -345.539768) (xy 382.773671 -345.510293) (xy 382.823255 -345.487644)
			(xy 382.875557 -345.472281) (xy 382.929513 -345.464519) (xy 382.984025 -345.464515) (xy 383.037983 -345.472268)
			(xy 383.090288 -345.487622) (xy 383.139875 -345.510263) (xy 383.185736 -345.539731) (xy 383.226936 -345.575426)
			(xy 383.262636 -345.616621) (xy 383.292111 -345.662477) (xy 383.314759 -345.712061) (xy 383.33012 -345.764364)
			(xy 383.337881 -345.818321) (xy 383.337885 -345.872833) (xy 383.33013 -345.92679) (xy 383.314775 -345.979095)
			(xy 383.292133 -346.028682) (xy 383.262664 -346.074542) (xy 383.226969 -346.115741) (xy 383.185773 -346.151441)
			(xy 383.139916 -346.180914) (xy 383.090332 -346.203562) (xy 383.038029 -346.218922) (xy 382.984072 -346.226682)
			(xy 382.956816 -346.227146) (xy 382.937246 -346.226943) (xy 382.898305 -346.222999) (xy 382.879092 -346.219272)
			(xy 382.865405 -346.216953) (xy 382.837722 -346.218776) (xy 382.811557 -346.227999) (xy 382.78885 -346.243937)
			(xy 382.771282 -346.265408) (xy 382.760157 -346.290823) (xy 382.756298 -346.318296) (xy 382.759992 -346.345791)
			(xy 382.765046 -346.358718) (xy 382.774931 -346.382673) (xy 382.78884 -346.432593) (xy 382.795855 -346.483937)
			(xy 382.796288 -346.509848) (xy 382.79577 -346.537095) (xy 382.788009 -346.591033) (xy 382.77265 -346.643317)
			(xy 382.750007 -346.692884) (xy 382.720541 -346.738723) (xy 382.684851 -346.779903) (xy 382.643665 -346.815585)
			(xy 382.597819 -346.845042) (xy 382.548248 -346.867676) (xy 382.495961 -346.883024) (xy 382.442021 -346.890776)
			(xy 382.387528 -346.890772) (xy 382.33359 -346.883014) (xy 382.281304 -346.867658) (xy 382.231736 -346.845018)
			(xy 382.185895 -346.815555) (xy 382.144713 -346.779867) (xy 382.109029 -346.738683) (xy 382.079568 -346.692839)
			(xy 382.056932 -346.643269) (xy 382.04158 -346.590983) (xy 382.033826 -346.537044) (xy 375.16865 -346.537044)
			(xy 374.891554 -346.81414) (xy 374.873488 -346.831432) (xy 374.831936 -346.859248) (xy 374.785756 -346.878424)
			(xy 374.736723 -346.888222) (xy 374.711722 -346.888816) (xy 365.773208 -346.888816) (xy 362.261491 -350.400296)
			(xy 363.397796 -350.400296) (xy 363.397796 -350.3156) (xy 363.405847 -350.231286) (xy 363.421876 -350.14812)
			(xy 363.445737 -350.066853) (xy 363.477216 -349.988223) (xy 363.516027 -349.912942) (xy 363.561817 -349.84169)
			(xy 363.614173 -349.775114) (xy 363.672621 -349.713816) (xy 363.736631 -349.658351) (xy 363.805623 -349.609222)
			(xy 363.878973 -349.566873) (xy 363.956016 -349.531689) (xy 364.036055 -349.503987) (xy 364.118364 -349.484019)
			(xy 364.202199 -349.471966) (xy 364.2868 -349.467936) (xy 364.371401 -349.471966) (xy 364.455236 -349.484019)
			(xy 364.537545 -349.503987) (xy 364.617584 -349.531689) (xy 364.694627 -349.566873) (xy 364.767977 -349.609222)
			(xy 364.836969 -349.658351) (xy 364.900979 -349.713816) (xy 364.959427 -349.775114) (xy 365.011783 -349.84169)
			(xy 365.057573 -349.912942) (xy 365.096384 -349.988223) (xy 365.127863 -350.066853) (xy 365.151724 -350.14812)
			(xy 365.167753 -350.231286) (xy 365.175804 -350.3156) (xy 365.176308 -350.357948) (xy 365.922309 -350.357948)
			(xy 365.926345 -350.274501) (xy 365.938417 -350.191833) (xy 365.95841 -350.110716) (xy 365.986139 -350.031907)
			(xy 366.021345 -349.956142) (xy 366.063699 -349.884129) (xy 366.112805 -349.81654) (xy 366.168206 -349.754006)
			(xy 366.229383 -349.697111) (xy 366.295766 -349.646385) (xy 366.366734 -349.602304) (xy 366.441626 -349.565278)
			(xy 366.519742 -349.535652) (xy 366.600352 -349.513704) (xy 366.682704 -349.499639) (xy 366.76603 -349.493587)
			(xy 366.84955 -349.495606) (xy 366.932486 -349.505676) (xy 367.014062 -349.523704) (xy 367.093518 -349.549521)
			(xy 367.170111 -349.582886) (xy 367.243127 -349.623487) (xy 367.311883 -349.670946) (xy 367.375737 -349.724819)
			(xy 367.434094 -349.784604) (xy 367.486409 -349.849741) (xy 367.532192 -349.919624) (xy 367.571017 -349.993599)
			(xy 367.602522 -350.070976) (xy 367.626411 -350.151033) (xy 367.642462 -350.233021) (xy 367.650525 -350.316176)
			(xy 367.65103 -350.357948) (xy 367.650525 -350.39972) (xy 367.642462 -350.482875) (xy 367.626411 -350.564863)
			(xy 367.602522 -350.64492) (xy 367.571017 -350.722297) (xy 367.532192 -350.796272) (xy 367.486409 -350.866155)
			(xy 367.434094 -350.931292) (xy 367.375737 -350.991077) (xy 367.311883 -351.04495) (xy 367.243127 -351.092409)
			(xy 367.170111 -351.13301) (xy 367.093518 -351.166375) (xy 367.014062 -351.192192) (xy 366.932486 -351.21022)
			(xy 366.84955 -351.22029) (xy 366.76603 -351.222309) (xy 366.682704 -351.216257) (xy 366.600352 -351.202192)
			(xy 366.519742 -351.180244) (xy 366.441626 -351.150618) (xy 366.366734 -351.113592) (xy 366.295766 -351.069511)
			(xy 366.229383 -351.018785) (xy 366.168206 -350.96189) (xy 366.112805 -350.899356) (xy 366.063699 -350.831767)
			(xy 366.021345 -350.759754) (xy 365.986139 -350.683989) (xy 365.95841 -350.60518) (xy 365.938417 -350.524063)
			(xy 365.926345 -350.441395) (xy 365.922309 -350.357948) (xy 365.176308 -350.357948) (xy 365.175804 -350.400296)
			(xy 365.167753 -350.48461) (xy 365.151724 -350.567776) (xy 365.127863 -350.649043) (xy 365.096384 -350.727673)
			(xy 365.057573 -350.802954) (xy 365.011783 -350.874206) (xy 364.959427 -350.940782) (xy 364.900979 -351.00208)
			(xy 364.836969 -351.057545) (xy 364.767977 -351.106674) (xy 364.694627 -351.149023) (xy 364.617584 -351.184207)
			(xy 364.537545 -351.211909) (xy 364.455236 -351.231877) (xy 364.371401 -351.24393) (xy 364.2868 -351.247961)
			(xy 364.202199 -351.24393) (xy 364.118364 -351.231877) (xy 364.036055 -351.211909) (xy 363.956016 -351.184207)
			(xy 363.878973 -351.149023) (xy 363.805623 -351.106674) (xy 363.736631 -351.057545) (xy 363.672621 -351.00208)
			(xy 363.614173 -350.940782) (xy 363.561817 -350.874206) (xy 363.516027 -350.802954) (xy 363.477216 -350.727673)
			(xy 363.445737 -350.649043) (xy 363.421876 -350.567776) (xy 363.405847 -350.48461) (xy 363.397796 -350.400296)
			(xy 362.261491 -350.400296) (xy 362.012484 -350.649286) (xy 361.994399 -350.666536) (xy 361.95283 -350.69427)
			(xy 361.906653 -350.71337) (xy 361.857638 -350.723102) (xy 361.832652 -350.723708) (xy 360.494326 -350.723708)
			(xy 360.468164 -350.7867) (xy 360.577892 -350.89592) (xy 360.856784 -351.175066) (xy 360.868003 -351.185466)
			(xy 360.895043 -351.199735) (xy 360.925092 -351.20537) (xy 360.955465 -351.201868) (xy 360.983443 -351.189542)
			(xy 361.006526 -351.169494) (xy 361.015026 -351.156778) (xy 361.030058 -351.133578) (xy 361.065748 -351.091364)
			(xy 361.107157 -351.054743) (xy 361.153417 -351.02448) (xy 361.20356 -351.00121) (xy 361.256536 -350.985419)
			(xy 361.311236 -350.977438) (xy 361.338876 -350.976946) (xy 361.366125 -350.9775) (xy 361.420067 -350.985252)
			(xy 361.472358 -351.000602) (xy 361.521932 -351.023237) (xy 361.56778 -351.052697) (xy 361.60897 -351.088381)
			(xy 361.644661 -351.129564) (xy 361.674129 -351.175407) (xy 361.696773 -351.224976) (xy 361.712133 -351.277264)
			(xy 361.719895 -351.331206) (xy 361.720384 -351.358454) (xy 361.719873 -351.386094) (xy 361.711901 -351.440795)
			(xy 361.696116 -351.493772) (xy 361.67285 -351.543917) (xy 361.642589 -351.590178) (xy 361.605969 -351.631587)
			(xy 361.563754 -351.667276) (xy 361.540552 -351.682304) (xy 361.52791 -351.69086) (xy 361.507943 -351.713929)
			(xy 361.495679 -351.741865) (xy 361.492212 -351.772178) (xy 361.497851 -351.802162) (xy 361.512093 -351.829143)
			(xy 361.522518 -351.840292) (xy 361.690666 -352.00844) (xy 367.68532 -352.00844) (xy 372.276116 -347.417898)
			(xy 372.294214 -347.400662) (xy 372.335776 -347.372921) (xy 372.38195 -347.353817) (xy 372.430963 -347.344083)
			(xy 372.455948 -347.343476) (xy 379.482858 -347.343476) (xy 379.507843 -347.344063) (xy 379.556852 -347.353813)
			(xy 379.603022 -347.372927) (xy 379.644581 -347.400673) (xy 379.66269 -347.417898) (xy 380.558294 -348.313248)
			(xy 383.072894 -348.313248) (xy 383.508504 -347.877638) (xy 383.508504 -347.72346) (xy 383.488896 -347.705283)
			(xy 383.454437 -347.6644) (xy 383.426023 -347.619108) (xy 383.404209 -347.570293) (xy 383.389424 -347.518911)
			(xy 383.381955 -347.465968) (xy 383.381504 -347.439234) (xy 383.382082 -347.409547) (xy 383.391276 -347.350889)
			(xy 383.409446 -347.294363) (xy 383.436155 -347.241336) (xy 383.470757 -347.193086) (xy 383.512417 -347.15078)
			(xy 383.535936 -347.132656) (xy 383.546519 -347.124203) (xy 383.563221 -347.102895) (xy 383.573738 -347.077948)
			(xy 383.57733 -347.051113) (xy 383.573745 -347.024278) (xy 383.563235 -346.999328) (xy 383.546538 -346.978015)
			(xy 383.535936 -346.969588) (xy 383.512428 -346.95145) (xy 383.470765 -346.909147) (xy 383.436159 -346.860901)
			(xy 383.409446 -346.807877) (xy 383.39127 -346.751353) (xy 383.38207 -346.692697) (xy 383.381504 -346.66301)
			(xy 383.381943 -346.635744) (xy 383.389705 -346.581768) (xy 383.405074 -346.529447) (xy 383.427735 -346.479847)
			(xy 383.457227 -346.433979) (xy 383.49295 -346.392777) (xy 383.534174 -346.357081) (xy 383.580062 -346.327618)
			(xy 383.629676 -346.304988) (xy 383.682007 -346.289653) (xy 383.735988 -346.281925) (xy 383.790519 -346.281962)
			(xy 383.84449 -346.289762) (xy 383.896801 -346.305166) (xy 383.946385 -346.327862) (xy 383.992233 -346.357386)
			(xy 384.03341 -346.393137) (xy 384.069077 -346.434386) (xy 384.098509 -346.480294) (xy 384.121104 -346.529924)
			(xy 384.136403 -346.582265) (xy 384.144093 -346.636252) (xy 384.14452 -346.663518) (xy 384.14452 -346.684854)
			(xy 384.244088 -346.784422) (xy 384.255064 -346.794691) (xy 384.281598 -346.808789) (xy 384.311083 -346.814569)
			(xy 384.340976 -346.81153) (xy 384.368695 -346.799937) (xy 384.39185 -346.780789) (xy 384.408441 -346.755738)
			(xy 384.413252 -346.741496) (xy 384.421506 -346.715604) (xy 384.444269 -346.66626) (xy 384.473801 -346.620644)
			(xy 384.509505 -346.579678) (xy 384.550659 -346.544191) (xy 384.596431 -346.5149) (xy 384.645894 -346.492398)
			(xy 384.698049 -346.477139) (xy 384.751841 -346.469433) (xy 384.779012 -346.468954) (xy 384.779266 -346.468954)
			(xy 384.804469 -346.469366) (xy 384.854437 -346.476002) (xy 384.903091 -346.489175) (xy 384.949582 -346.508654)
			(xy 384.971544 -346.521024) (xy 384.984489 -346.528103) (xy 385.013135 -346.535136) (xy 385.042595 -346.533686)
			(xy 385.070411 -346.523876) (xy 385.094263 -346.506524) (xy 385.112159 -346.483078) (xy 385.117848 -346.469462)
			(xy 385.128551 -346.442689) (xy 385.156839 -346.392449) (xy 385.192369 -346.347041) (xy 385.23433 -346.307499)
			(xy 385.281766 -346.274725) (xy 385.333596 -346.249467) (xy 385.388637 -346.232299) (xy 385.445636 -346.223613)
			(xy 385.474464 -346.223082) (xy 385.501716 -346.223589) (xy 385.555664 -346.231341) (xy 385.607961 -346.246692)
			(xy 385.65754 -346.269329) (xy 385.703393 -346.298792) (xy 385.744586 -346.334482) (xy 385.78028 -346.37567)
			(xy 385.809749 -346.421519) (xy 385.832392 -346.471096) (xy 385.84775 -346.523391) (xy 385.855508 -346.577339)
			(xy 385.855972 -346.60459) (xy 385.855972 -346.604844) (xy 385.855401 -346.634683) (xy 385.846083 -346.693629)
			(xy 385.83743 -346.722192) (xy 385.833331 -346.736085) (xy 385.832428 -346.765028) (xy 385.839703 -346.793056)
			(xy 385.854568 -346.817907) (xy 385.875823 -346.837573) (xy 385.901752 -346.850466) (xy 385.915916 -346.85351)
			(xy 385.941986 -346.858696) (xy 385.992488 -346.875265) (xy 386.040201 -346.898686) (xy 386.084199 -346.928506)
			(xy 386.12363 -346.964147) (xy 386.157729 -347.004918) (xy 386.185837 -347.05003) (xy 386.207407 -347.098607)
			(xy 386.222023 -347.149709) (xy 386.229401 -347.202346) (xy 386.22986 -347.228922) (xy 386.229374 -347.256173)
			(xy 386.221618 -347.310121) (xy 386.206263 -347.362416) (xy 386.183621 -347.411993) (xy 386.154155 -347.457843)
			(xy 386.118464 -347.499034) (xy 386.077273 -347.534725) (xy 386.031423 -347.564191) (xy 385.981846 -347.586833)
			(xy 385.929551 -347.602188) (xy 385.875603 -347.609944) (xy 385.821101 -347.609944) (xy 385.767153 -347.602188)
			(xy 385.714858 -347.586833) (xy 385.665281 -347.564191) (xy 385.619431 -347.534725) (xy 385.57824 -347.499034)
			(xy 385.542549 -347.457843) (xy 385.513083 -347.411993) (xy 385.490441 -347.362416) (xy 385.475086 -347.310121)
			(xy 385.46733 -347.256173) (xy 385.466844 -347.228922) (xy 385.466844 -347.228668) (xy 385.467421 -347.198829)
			(xy 385.476735 -347.139883) (xy 385.485386 -347.11132) (xy 385.489459 -347.097421) (xy 385.490364 -347.068483)
			(xy 385.483092 -347.040458) (xy 385.468233 -347.015609) (xy 385.446984 -346.995944) (xy 385.421061 -346.983049)
			(xy 385.4069 -346.980002) (xy 385.37406 -346.973421) (xy 385.311208 -346.950297) (xy 385.281932 -346.934028)
			(xy 385.26899 -346.926946) (xy 385.240345 -346.919923) (xy 385.210887 -346.921377) (xy 385.183072 -346.931188)
			(xy 385.159221 -346.948537) (xy 385.141321 -346.971977) (xy 385.135628 -346.98559) (xy 385.12492 -347.012361)
			(xy 385.096635 -347.062604) (xy 385.061107 -347.108014) (xy 385.019147 -347.147557) (xy 384.971711 -347.180332)
			(xy 384.919882 -347.20559) (xy 384.86484 -347.222757) (xy 384.80784 -347.23144) (xy 384.779012 -347.23197)
			(xy 384.756116 -347.231642) (xy 384.710654 -347.226163) (xy 384.688334 -347.221048) (xy 384.673285 -347.217895)
			(xy 384.64261 -347.219739) (xy 384.613875 -347.230634) (xy 384.589688 -347.24959) (xy 384.572242 -347.274888)
			(xy 384.56312 -347.304234) (xy 384.562604 -347.3196) (xy 384.562604 -347.977206) (xy 384.561993 -348.002204)
			(xy 384.552184 -348.051229) (xy 384.533004 -348.0974) (xy 384.505188 -348.138944) (xy 384.487928 -348.157038)
			(xy 383.516378 -349.128588) (xy 383.498284 -349.145845) (xy 383.456739 -349.173656) (xy 383.410567 -349.192829)
			(xy 383.361542 -349.202628) (xy 383.336546 -349.203264) (xy 380.294896 -349.203264) (xy 380.2699 -349.202634)
			(xy 380.220877 -349.192828) (xy 380.174706 -349.173653) (xy 380.13316 -349.145844) (xy 380.115064 -349.128588)
			(xy 379.21946 -348.232984) (xy 372.719346 -348.232984) (xy 368.07775 -352.87458) (xy 368.059666 -352.891849)
			(xy 368.018118 -352.919658) (xy 367.971943 -352.938828) (xy 367.922915 -352.948622) (xy 367.897918 -352.949256)
			(xy 361.700572 -352.949256) (xy 361.700572 -353.09683) (xy 363.038644 -354.434902) (xy 363.038644 -354.687886)
			(xy 364.22584 -354.687886) (xy 364.226278 -354.661506) (xy 364.233533 -354.609247) (xy 364.247918 -354.558486)
			(xy 364.269157 -354.51019) (xy 364.296845 -354.46528) (xy 364.330456 -354.424611) (xy 364.369348 -354.38896)
			(xy 364.41278 -354.359006) (xy 364.436152 -354.346764) (xy 364.448524 -354.340084) (xy 364.469257 -354.321106)
			(xy 364.484021 -354.297188) (xy 364.491693 -354.270148) (xy 364.491692 -354.24204) (xy 364.484016 -354.215001)
			(xy 364.469249 -354.191084) (xy 364.448514 -354.172109) (xy 364.436152 -354.165408) (xy 364.412765 -354.153197)
			(xy 364.369342 -354.123229) (xy 364.330458 -354.087569) (xy 364.296855 -354.046894) (xy 364.26917 -354.001981)
			(xy 364.247932 -353.953685) (xy 364.233546 -353.902924) (xy 364.226284 -353.850666) (xy 364.22584 -353.824286)
			(xy 364.226326 -353.797035) (xy 364.234082 -353.743087) (xy 364.249437 -353.690792) (xy 364.272079 -353.641215)
			(xy 364.301545 -353.595365) (xy 364.337236 -353.554174) (xy 364.378427 -353.518483) (xy 364.424277 -353.489017)
			(xy 364.473854 -353.466375) (xy 364.526149 -353.45102) (xy 364.580097 -353.443264) (xy 364.634599 -353.443264)
			(xy 364.688547 -353.45102) (xy 364.740842 -353.466375) (xy 364.790419 -353.489017) (xy 364.836269 -353.518483)
			(xy 364.87746 -353.554174) (xy 364.913151 -353.595365) (xy 364.942617 -353.641215) (xy 364.965259 -353.690792)
			(xy 364.980614 -353.743087) (xy 364.98776 -353.79279) (xy 366.64722 -353.79279) (xy 366.651291 -353.737168)
			(xy 366.663417 -353.682731) (xy 366.68334 -353.63064) (xy 366.710636 -353.582005) (xy 366.744722 -353.537862)
			(xy 366.784871 -353.499153) (xy 366.830229 -353.466702) (xy 366.879829 -353.441201) (xy 366.932613 -353.423194)
			(xy 366.987456 -353.413064) (xy 367.04319 -353.411027) (xy 367.098627 -353.417127) (xy 367.152584 -353.431233)
			(xy 367.203913 -353.453045) (xy 367.251519 -353.482099) (xy 367.294387 -353.517774) (xy 367.331604 -353.559311)
			(xy 367.362377 -353.605824) (xy 367.386049 -353.656321) (xy 367.402117 -353.709728) (xy 367.410237 -353.764904)
			(xy 367.410746 -353.79279) (xy 367.410237 -353.820676) (xy 367.402117 -353.875852) (xy 367.386049 -353.929259)
			(xy 367.362377 -353.979756) (xy 367.331604 -354.026269) (xy 367.294387 -354.067806) (xy 367.251519 -354.103481)
			(xy 367.203913 -354.132535) (xy 367.152584 -354.154347) (xy 367.098627 -354.168453) (xy 367.04319 -354.174553)
			(xy 366.987456 -354.172516) (xy 366.932613 -354.162386) (xy 366.879829 -354.144379) (xy 366.830229 -354.118878)
			(xy 366.784871 -354.086427) (xy 366.744722 -354.047718) (xy 366.710636 -354.003575) (xy 366.68334 -353.95494)
			(xy 366.663417 -353.902849) (xy 366.651291 -353.848412) (xy 366.64722 -353.79279) (xy 364.98776 -353.79279)
			(xy 364.98837 -353.797035) (xy 364.988856 -353.824286) (xy 364.988425 -353.850666) (xy 364.981162 -353.902922)
			(xy 364.966772 -353.953681) (xy 364.945531 -354.001975) (xy 364.917841 -354.046884) (xy 364.884232 -354.087552)
			(xy 364.845342 -354.123205) (xy 364.801914 -354.153164) (xy 364.778544 -354.165408) (xy 364.766197 -354.17213)
			(xy 364.745467 -354.191101) (xy 364.730705 -354.215011) (xy 364.723031 -354.242044) (xy 364.72303 -354.270144)
			(xy 364.7307 -354.297177) (xy 364.745459 -354.321089) (xy 364.766186 -354.340063) (xy 364.778544 -354.346764)
			(xy 364.801919 -354.358998) (xy 364.845341 -354.388962) (xy 364.884225 -354.42462) (xy 364.91783 -354.465291)
			(xy 364.945516 -354.5102) (xy 364.966756 -354.558494) (xy 364.981145 -354.609252) (xy 364.98841 -354.661507)
			(xy 364.988856 -354.687886) (xy 364.98837 -354.715137) (xy 364.980614 -354.769085) (xy 364.965259 -354.82138)
			(xy 364.942617 -354.870957) (xy 364.913151 -354.916807) (xy 364.87746 -354.957998) (xy 364.836269 -354.993689)
			(xy 364.790419 -355.023155) (xy 364.740842 -355.045797) (xy 364.688547 -355.061152) (xy 364.634599 -355.068908)
			(xy 364.580097 -355.068908) (xy 364.526149 -355.061152) (xy 364.473854 -355.045797) (xy 364.424277 -355.023155)
			(xy 364.378427 -354.993689) (xy 364.337236 -354.957998) (xy 364.301545 -354.916807) (xy 364.272079 -354.870957)
			(xy 364.249437 -354.82138) (xy 364.234082 -354.769085) (xy 364.226326 -354.715137) (xy 364.22584 -354.687886)
			(xy 363.038644 -354.687886) (xy 363.038644 -355.352604) (xy 368.216686 -355.352604) (xy 368.220757 -355.296982)
			(xy 368.232883 -355.242545) (xy 368.252806 -355.190454) (xy 368.280102 -355.141819) (xy 368.314188 -355.097676)
			(xy 368.354337 -355.058967) (xy 368.399695 -355.026516) (xy 368.449295 -355.001015) (xy 368.502079 -354.983008)
			(xy 368.556922 -354.972878) (xy 368.612656 -354.970841) (xy 368.668093 -354.976941) (xy 368.72205 -354.991047)
			(xy 368.773379 -355.012859) (xy 368.820985 -355.041913) (xy 368.863853 -355.077588) (xy 368.90107 -355.119125)
			(xy 368.931843 -355.165638) (xy 368.955515 -355.216135) (xy 368.971583 -355.269542) (xy 368.979703 -355.324718)
			(xy 368.980212 -355.352604) (xy 368.979703 -355.38049) (xy 368.971583 -355.435666) (xy 368.955515 -355.489073)
			(xy 368.931843 -355.53957) (xy 368.90107 -355.586083) (xy 368.863853 -355.62762) (xy 368.820985 -355.663295)
			(xy 368.773379 -355.692349) (xy 368.72205 -355.714161) (xy 368.668093 -355.728267) (xy 368.612656 -355.734367)
			(xy 368.556922 -355.73233) (xy 368.502079 -355.7222) (xy 368.449295 -355.704193) (xy 368.399695 -355.678692)
			(xy 368.354337 -355.646241) (xy 368.314188 -355.607532) (xy 368.280102 -355.563389) (xy 368.252806 -355.514754)
			(xy 368.232883 -355.462663) (xy 368.220757 -355.408226) (xy 368.216686 -355.352604) (xy 363.038644 -355.352604)
			(xy 363.038644 -356.373938) (xy 368.222274 -356.373938) (xy 368.226345 -356.318316) (xy 368.238471 -356.263879)
			(xy 368.258394 -356.211788) (xy 368.28569 -356.163153) (xy 368.319776 -356.11901) (xy 368.359925 -356.080301)
			(xy 368.405283 -356.04785) (xy 368.454883 -356.022349) (xy 368.507667 -356.004342) (xy 368.56251 -355.994212)
			(xy 368.618244 -355.992175) (xy 368.673681 -355.998275) (xy 368.727638 -356.012381) (xy 368.778967 -356.034193)
			(xy 368.826573 -356.063247) (xy 368.869441 -356.098922) (xy 368.906658 -356.140459) (xy 368.937431 -356.186972)
			(xy 368.961103 -356.237469) (xy 368.977171 -356.290876) (xy 368.978854 -356.30231) (xy 370.449854 -356.30231)
			(xy 370.453925 -356.246688) (xy 370.466051 -356.192251) (xy 370.485974 -356.14016) (xy 370.51327 -356.091525)
			(xy 370.547356 -356.047382) (xy 370.587505 -356.008673) (xy 370.632863 -355.976222) (xy 370.682463 -355.950721)
			(xy 370.735247 -355.932714) (xy 370.79009 -355.922584) (xy 370.845824 -355.920547) (xy 370.901261 -355.926647)
			(xy 370.955218 -355.940753) (xy 371.006547 -355.962565) (xy 371.054153 -355.991619) (xy 371.097021 -356.027294)
			(xy 371.134238 -356.068831) (xy 371.165011 -356.115344) (xy 371.188683 -356.165841) (xy 371.204751 -356.219248)
			(xy 371.212871 -356.274424) (xy 371.21338 -356.30231) (xy 371.212871 -356.330196) (xy 371.204751 -356.385372)
			(xy 371.188683 -356.438779) (xy 371.165011 -356.489276) (xy 371.134238 -356.535789) (xy 371.097021 -356.577326)
			(xy 371.054153 -356.613001) (xy 371.006547 -356.642055) (xy 370.955218 -356.663867) (xy 370.901261 -356.677973)
			(xy 370.845824 -356.684073) (xy 370.79009 -356.682036) (xy 370.735247 -356.671906) (xy 370.682463 -356.653899)
			(xy 370.632863 -356.628398) (xy 370.587505 -356.595947) (xy 370.547356 -356.557238) (xy 370.51327 -356.513095)
			(xy 370.485974 -356.46446) (xy 370.466051 -356.412369) (xy 370.453925 -356.357932) (xy 370.449854 -356.30231)
			(xy 368.978854 -356.30231) (xy 368.985291 -356.346052) (xy 368.9858 -356.373938) (xy 368.985291 -356.401824)
			(xy 368.977171 -356.457) (xy 368.961103 -356.510407) (xy 368.937431 -356.560904) (xy 368.906658 -356.607417)
			(xy 368.869441 -356.648954) (xy 368.826573 -356.684629) (xy 368.778967 -356.713683) (xy 368.727638 -356.735495)
			(xy 368.673681 -356.749601) (xy 368.618244 -356.755701) (xy 368.56251 -356.753664) (xy 368.507667 -356.743534)
			(xy 368.454883 -356.725527) (xy 368.405283 -356.700026) (xy 368.359925 -356.667575) (xy 368.319776 -356.628866)
			(xy 368.28569 -356.584723) (xy 368.258394 -356.536088) (xy 368.238471 -356.483997) (xy 368.226345 -356.42956)
			(xy 368.222274 -356.373938) (xy 363.038644 -356.373938) (xy 363.038644 -357.197406) (xy 364.728504 -357.197406)
			(xy 364.732575 -357.141784) (xy 364.744701 -357.087347) (xy 364.764624 -357.035256) (xy 364.79192 -356.986621)
			(xy 364.826006 -356.942478) (xy 364.866155 -356.903769) (xy 364.911513 -356.871318) (xy 364.961113 -356.845817)
			(xy 365.013897 -356.82781) (xy 365.06874 -356.81768) (xy 365.124474 -356.815643) (xy 365.179911 -356.821743)
			(xy 365.233868 -356.835849) (xy 365.285197 -356.857661) (xy 365.332803 -356.886715) (xy 365.375671 -356.92239)
			(xy 365.412888 -356.963927) (xy 365.443661 -357.01044) (xy 365.467333 -357.060937) (xy 365.483401 -357.114344)
			(xy 365.491521 -357.16952) (xy 365.49203 -357.197406) (xy 365.491521 -357.225292) (xy 365.483401 -357.280468)
			(xy 365.467333 -357.333875) (xy 365.443661 -357.384372) (xy 365.412888 -357.430885) (xy 365.375671 -357.472422)
			(xy 365.332803 -357.508097) (xy 365.285197 -357.537151) (xy 365.233868 -357.558963) (xy 365.179911 -357.573069)
			(xy 365.124474 -357.579169) (xy 365.06874 -357.577132) (xy 365.013897 -357.567002) (xy 364.961113 -357.548995)
			(xy 364.911513 -357.523494) (xy 364.866155 -357.491043) (xy 364.826006 -357.452334) (xy 364.79192 -357.408191)
			(xy 364.764624 -357.359556) (xy 364.744701 -357.307465) (xy 364.732575 -357.253028) (xy 364.728504 -357.197406)
			(xy 363.038644 -357.197406) (xy 363.038644 -357.865934) (xy 362.803189 -358.101389) (xy 369.986045 -358.101389)
			(xy 369.993796 -358.047437) (xy 370.009146 -357.995136) (xy 370.031783 -357.945553) (xy 370.061246 -357.899696)
			(xy 370.096935 -357.858499) (xy 370.138124 -357.8228) (xy 370.183974 -357.793326) (xy 370.233552 -357.770678)
			(xy 370.285848 -357.755315) (xy 370.339799 -357.747551) (xy 370.367052 -357.747062) (xy 370.380048 -357.747169)
			(xy 370.405979 -357.748949) (xy 370.418868 -357.750618) (xy 370.433246 -357.752024) (xy 370.461801 -357.747758)
			(xy 370.488017 -357.735664) (xy 370.509796 -357.71671) (xy 370.525393 -357.692414) (xy 370.533559 -357.664721)
			(xy 370.53364 -357.635849) (xy 370.53012 -357.62184) (xy 370.523198 -357.59604) (xy 370.5158 -357.543139)
			(xy 370.515388 -357.51643) (xy 370.515823 -357.489174) (xy 370.523576 -357.435218) (xy 370.53893 -357.382913)
			(xy 370.561571 -357.333327) (xy 370.591039 -357.287467) (xy 370.626734 -357.246268) (xy 370.667928 -357.210568)
			(xy 370.713784 -357.181095) (xy 370.763368 -357.158447) (xy 370.81567 -357.143087) (xy 370.869626 -357.135326)
			(xy 370.924137 -357.135324) (xy 370.978093 -357.143079) (xy 371.030397 -357.158434) (xy 371.079983 -357.181077)
			(xy 371.125842 -357.210546) (xy 371.16704 -357.246242) (xy 371.202738 -357.287437) (xy 371.232211 -357.333294)
			(xy 371.254857 -357.382878) (xy 371.270216 -357.435181) (xy 371.277975 -357.489137) (xy 371.277976 -357.543648)
			(xy 371.270219 -357.597605) (xy 371.254862 -357.649908) (xy 371.232218 -357.699493) (xy 371.202747 -357.745351)
			(xy 371.16705 -357.786548) (xy 371.125854 -357.822245) (xy 371.079996 -357.851716) (xy 371.030411 -357.874361)
			(xy 370.978108 -357.889718) (xy 370.924152 -357.897475) (xy 370.896896 -357.897938) (xy 370.8839 -357.897826)
			(xy 370.857969 -357.896049) (xy 370.84508 -357.894382) (xy 370.830698 -357.893022) (xy 370.802146 -357.897276)
			(xy 370.77593 -357.909361) (xy 370.754151 -357.928308) (xy 370.738553 -357.952598) (xy 370.730387 -357.980286)
			(xy 370.730307 -358.009153) (xy 370.733828 -358.02316) (xy 370.740749 -358.04896) (xy 370.748147 -358.101861)
			(xy 370.74856 -358.12857) (xy 370.748154 -358.155823) (xy 370.740402 -358.209775) (xy 370.72505 -358.262075)
			(xy 370.702411 -358.311657) (xy 370.672947 -358.357513) (xy 370.637256 -358.398709) (xy 370.596066 -358.434407)
			(xy 370.550215 -358.463879) (xy 370.500637 -358.486527) (xy 370.44834 -358.501888) (xy 370.394389 -358.50965)
			(xy 370.339883 -358.509655) (xy 370.285931 -358.501903) (xy 370.233631 -358.486552) (xy 370.184048 -358.463914)
			(xy 370.138191 -358.43445) (xy 370.096995 -358.39876) (xy 370.061297 -358.357571) (xy 370.031823 -358.311721)
			(xy 370.009176 -358.262142) (xy 369.993814 -358.209846) (xy 369.986051 -358.155895) (xy 369.986045 -358.101389)
			(xy 362.803189 -358.101389) (xy 362.08589 -358.818688) (xy 366.653062 -358.818688) (xy 366.657133 -358.763066)
			(xy 366.669259 -358.708629) (xy 366.689182 -358.656538) (xy 366.716478 -358.607903) (xy 366.750564 -358.56376)
			(xy 366.790713 -358.525051) (xy 366.836071 -358.4926) (xy 366.885671 -358.467099) (xy 366.938455 -358.449092)
			(xy 366.993298 -358.438962) (xy 367.049032 -358.436925) (xy 367.104469 -358.443025) (xy 367.158426 -358.457131)
			(xy 367.209755 -358.478943) (xy 367.257361 -358.507997) (xy 367.300229 -358.543672) (xy 367.337446 -358.585209)
			(xy 367.368219 -358.631722) (xy 367.391891 -358.682219) (xy 367.407959 -358.735626) (xy 367.416079 -358.790802)
			(xy 367.416588 -358.818688) (xy 367.416079 -358.846574) (xy 367.407959 -358.90175) (xy 367.391891 -358.955157)
			(xy 367.387519 -358.964484) (xy 370.72773 -358.964484) (xy 370.731801 -358.908862) (xy 370.743927 -358.854425)
			(xy 370.76385 -358.802334) (xy 370.791146 -358.753699) (xy 370.825232 -358.709556) (xy 370.865381 -358.670847)
			(xy 370.910739 -358.638396) (xy 370.960339 -358.612895) (xy 371.013123 -358.594888) (xy 371.067966 -358.584758)
			(xy 371.1237 -358.582721) (xy 371.179137 -358.588821) (xy 371.233094 -358.602927) (xy 371.284423 -358.624739)
			(xy 371.332029 -358.653793) (xy 371.374897 -358.689468) (xy 371.412114 -358.731005) (xy 371.442887 -358.777518)
			(xy 371.466559 -358.828015) (xy 371.482627 -358.881422) (xy 371.490747 -358.936598) (xy 371.491256 -358.964484)
			(xy 371.490747 -358.99237) (xy 371.482627 -359.047546) (xy 371.466559 -359.100953) (xy 371.442887 -359.15145)
			(xy 371.412114 -359.197963) (xy 371.374897 -359.2395) (xy 371.332029 -359.275175) (xy 371.284423 -359.304229)
			(xy 371.233094 -359.326041) (xy 371.179137 -359.340147) (xy 371.1237 -359.346247) (xy 371.067966 -359.34421)
			(xy 371.013123 -359.33408) (xy 370.960339 -359.316073) (xy 370.910739 -359.290572) (xy 370.865381 -359.258121)
			(xy 370.825232 -359.219412) (xy 370.791146 -359.175269) (xy 370.76385 -359.126634) (xy 370.743927 -359.074543)
			(xy 370.731801 -359.020106) (xy 370.72773 -358.964484) (xy 367.387519 -358.964484) (xy 367.368219 -359.005654)
			(xy 367.337446 -359.052167) (xy 367.300229 -359.093704) (xy 367.257361 -359.129379) (xy 367.209755 -359.158433)
			(xy 367.158426 -359.180245) (xy 367.104469 -359.194351) (xy 367.049032 -359.200451) (xy 366.993298 -359.198414)
			(xy 366.938455 -359.188284) (xy 366.885671 -359.170277) (xy 366.836071 -359.144776) (xy 366.790713 -359.112325)
			(xy 366.750564 -359.073616) (xy 366.716478 -359.029473) (xy 366.689182 -358.980838) (xy 366.669259 -358.928747)
			(xy 366.657133 -358.87431) (xy 366.653062 -358.818688) (xy 362.08589 -358.818688) (xy 361.44454 -359.460038)
			(xy 363.93323 -359.460038) (xy 363.937301 -359.404416) (xy 363.949427 -359.349979) (xy 363.96935 -359.297888)
			(xy 363.996646 -359.249253) (xy 364.030732 -359.20511) (xy 364.070881 -359.166401) (xy 364.116239 -359.13395)
			(xy 364.165839 -359.108449) (xy 364.218623 -359.090442) (xy 364.273466 -359.080312) (xy 364.3292 -359.078275)
			(xy 364.384637 -359.084375) (xy 364.438594 -359.098481) (xy 364.489923 -359.120293) (xy 364.537529 -359.149347)
			(xy 364.580397 -359.185022) (xy 364.617614 -359.226559) (xy 364.648387 -359.273072) (xy 364.672059 -359.323569)
			(xy 364.688127 -359.376976) (xy 364.696247 -359.432152) (xy 364.696756 -359.460038) (xy 364.696247 -359.487924)
			(xy 364.688127 -359.5431) (xy 364.672059 -359.596507) (xy 364.648387 -359.647004) (xy 364.617614 -359.693517)
			(xy 364.580397 -359.735054) (xy 364.537529 -359.770729) (xy 364.489923 -359.799783) (xy 364.438594 -359.821595)
			(xy 364.384637 -359.835701) (xy 364.3292 -359.841801) (xy 364.273466 -359.839764) (xy 364.218623 -359.829634)
			(xy 364.165839 -359.811627) (xy 364.116239 -359.786126) (xy 364.070881 -359.753675) (xy 364.030732 -359.714966)
			(xy 363.996646 -359.670823) (xy 363.96935 -359.622188) (xy 363.949427 -359.570097) (xy 363.937301 -359.51566)
			(xy 363.93323 -359.460038) (xy 361.44454 -359.460038) (xy 361.420664 -359.483914) (xy 361.428489 -359.511189)
			(xy 361.436908 -359.567303) (xy 361.437428 -359.595674) (xy 361.436921 -359.622925) (xy 361.429168 -359.676874)
			(xy 361.413816 -359.729169) (xy 361.391178 -359.778748) (xy 361.361714 -359.8246) (xy 361.326025 -359.865793)
			(xy 361.284837 -359.901487) (xy 361.238989 -359.930956) (xy 361.189413 -359.9536) (xy 361.137119 -359.968958)
			(xy 361.083171 -359.976717) (xy 361.05592 -359.977182) (xy 361.030012 -359.97642) (xy 361.016138 -359.975983)
			(xy 360.988984 -359.981679) (xy 360.964371 -359.994483) (xy 360.94412 -360.013449) (xy 360.929732 -360.037171)
			(xy 360.92227 -360.063893) (xy 360.921808 -360.077766) (xy 360.921808 -360.146346) (xy 360.922183 -360.159729)
			(xy 360.929176 -360.185566) (xy 360.942642 -360.208699) (xy 360.961657 -360.227538) (xy 360.984915 -360.240788)
			(xy 361.010816 -360.247539) (xy 361.037582 -360.247328) (xy 361.050586 -360.244136) (xy 361.075781 -360.237483)
			(xy 361.127401 -360.23035) (xy 361.153456 -360.229912) (xy 361.180712 -360.230332) (xy 361.234671 -360.238084)
			(xy 361.286977 -360.253437) (xy 361.336565 -360.276078) (xy 361.382426 -360.305547) (xy 361.423626 -360.341242)
			(xy 361.459327 -360.382438) (xy 361.4888 -360.428296) (xy 361.511447 -360.477882) (xy 361.526806 -360.530186)
			(xy 361.534565 -360.584144) (xy 361.534565 -360.638656) (xy 361.526806 -360.692614) (xy 361.511447 -360.744918)
			(xy 361.4888 -360.794504) (xy 361.459327 -360.840362) (xy 361.423626 -360.881558) (xy 361.382426 -360.917253)
			(xy 361.336565 -360.946722) (xy 361.286977 -360.969363) (xy 361.234671 -360.984716) (xy 361.180712 -360.992468)
			(xy 361.153456 -360.992928) (xy 361.125957 -360.99248) (xy 361.071528 -360.984581) (xy 361.018796 -360.968954)
			(xy 360.968852 -360.945921) (xy 360.922731 -360.91596) (xy 360.901742 -360.898186) (xy 360.865928 -360.866944)
			(xy 360.727752 -361.005374) (xy 360.717314 -361.01653) (xy 360.703076 -361.043548) (xy 360.697467 -361.073568)
			(xy 360.700987 -361.103903) (xy 360.713322 -361.131841) (xy 360.727046 -361.147614) (xy 366.10544 -361.147614)
			(xy 366.10544 -360.153966) (xy 366.105959 -360.123562) (xy 366.114239 -360.063321) (xy 366.130644 -360.004768)
			(xy 366.15487 -359.948994) (xy 366.186465 -359.897039) (xy 366.22484 -359.849869) (xy 366.269281 -359.808365)
			(xy 366.318959 -359.773298) (xy 366.372949 -359.745323) (xy 366.430246 -359.724959) (xy 366.489782 -359.712588)
			(xy 366.550448 -359.708438) (xy 366.611114 -359.712588) (xy 366.67065 -359.724959) (xy 366.727947 -359.745323)
			(xy 366.781937 -359.773298) (xy 366.831615 -359.808365) (xy 366.876056 -359.849869) (xy 366.914431 -359.897039)
			(xy 366.946026 -359.948994) (xy 366.970252 -360.004768) (xy 366.986657 -360.063321) (xy 366.994937 -360.123562)
			(xy 366.995456 -360.153966) (xy 366.995456 -360.680508) (xy 376.90679 -360.680508) (xy 376.907263 -360.653255)
			(xy 376.915019 -360.599305) (xy 376.930374 -360.547007) (xy 376.953015 -360.497427) (xy 376.982482 -360.451574)
			(xy 377.018175 -360.410382) (xy 377.059366 -360.374688) (xy 377.105219 -360.34522) (xy 377.154798 -360.322577)
			(xy 377.207095 -360.307221) (xy 377.261045 -360.299463) (xy 377.288298 -360.299) (xy 377.315273 -360.29945)
			(xy 377.368686 -360.307038) (xy 377.420497 -360.322077) (xy 377.469672 -360.344266) (xy 377.515229 -360.373164)
			(xy 377.55626 -360.408193) (xy 377.591945 -360.448655) (xy 377.621572 -360.493741) (xy 377.633484 -360.517948)
			(xy 377.637294 -360.526076) (xy 379.238002 -362.126784) (xy 382.338326 -362.126784) (xy 382.366292 -362.12736)
			(xy 382.421537 -362.136091) (xy 382.474738 -362.15335) (xy 382.524588 -362.178712) (xy 382.569862 -362.211554)
			(xy 382.59004 -362.230924) (xy 385.147312 -364.788196) (xy 392.263884 -364.788196) (xy 397.961358 -359.090722)
			(xy 397.981524 -359.071324) (xy 398.026787 -359.03843) (xy 398.076633 -359.013012) (xy 398.129838 -358.995693)
			(xy 398.185096 -358.986901) (xy 398.213072 -358.986328) (xy 407.10866 -358.986328) (xy 408.634946 -357.460296)
			(xy 408.655085 -357.440876) (xy 408.70035 -357.407998) (xy 408.750206 -357.382616) (xy 408.803423 -357.365358)
			(xy 408.858687 -357.35665) (xy 408.88666 -357.356156) (xy 410.183584 -357.356156) (xy 410.211552 -357.356675)
			(xy 410.266801 -357.365417) (xy 410.320004 -357.382688) (xy 410.369853 -357.408063) (xy 410.415123 -357.440919)
			(xy 410.435298 -357.460296) (xy 410.989272 -358.01427) (xy 411.008668 -358.034431) (xy 411.041547 -358.079691)
			(xy 411.066931 -358.129542) (xy 411.084195 -358.182754) (xy 411.092913 -358.238013) (xy 411.093412 -358.265984)
			(xy 411.093412 -360.315256) (xy 411.092856 -360.343222) (xy 411.08412 -360.398469) (xy 411.066857 -360.45167)
			(xy 411.04149 -360.50152) (xy 411.008644 -360.546792) (xy 410.989272 -360.56697) (xy 410.605478 -360.951018)
			(xy 410.606748 -360.973624) (xy 410.607256 -360.995214) (xy 410.60677 -361.022465) (xy 410.599014 -361.076413)
			(xy 410.583659 -361.128708) (xy 410.561017 -361.178285) (xy 410.531551 -361.224135) (xy 410.49586 -361.265326)
			(xy 410.454669 -361.301017) (xy 410.408819 -361.330483) (xy 410.359242 -361.353125) (xy 410.306947 -361.36848)
			(xy 410.252999 -361.376236) (xy 410.198497 -361.376236) (xy 410.144549 -361.36848) (xy 410.092254 -361.353125)
			(xy 410.042677 -361.330483) (xy 409.996827 -361.301017) (xy 409.955636 -361.265326) (xy 409.919945 -361.224135)
			(xy 409.890479 -361.178285) (xy 409.867837 -361.128708) (xy 409.852482 -361.076413) (xy 409.844726 -361.022465)
			(xy 409.84424 -360.995214) (xy 409.844977 -360.962282) (xy 409.85634 -360.897402) (xy 409.866846 -360.866182)
			(xy 409.86964 -360.8578) (xy 409.86964 -360.827066) (xy 409.870198 -360.799086) (xy 409.878962 -360.743817)
			(xy 409.896269 -360.690602) (xy 409.921693 -360.640751) (xy 409.954606 -360.595494) (xy 409.974034 -360.575352)
			(xy 410.381704 -360.167682) (xy 410.381704 -358.413558) (xy 410.03601 -358.067864) (xy 409.034234 -358.067864)
			(xy 407.507948 -359.59415) (xy 407.487774 -359.61354) (xy 407.442514 -359.646436) (xy 407.39267 -359.671857)
			(xy 407.339466 -359.689177) (xy 407.28421 -359.697971) (xy 407.256234 -359.698544) (xy 398.360646 -359.698544)
			(xy 392.663172 -365.395764) (xy 392.643035 -365.415186) (xy 392.597768 -365.448062) (xy 392.547911 -365.473442)
			(xy 392.494694 -365.4907) (xy 392.439431 -365.499409) (xy 392.411458 -365.499904) (xy 384.999738 -365.499904)
			(xy 384.971771 -365.499354) (xy 384.916525 -365.490617) (xy 384.863323 -365.473353) (xy 384.813473 -365.447985)
			(xy 384.768201 -365.415137) (xy 384.748024 -365.395764) (xy 382.190752 -362.838492) (xy 379.090428 -362.838492)
			(xy 379.062461 -362.837951) (xy 379.007214 -362.829213) (xy 378.954011 -362.811946) (xy 378.904162 -362.786576)
			(xy 378.858891 -362.753726) (xy 378.838714 -362.734352) (xy 377.133866 -361.029504) (xy 377.125738 -361.025694)
			(xy 377.101532 -361.013785) (xy 377.056457 -360.984146) (xy 377.016006 -360.948455) (xy 376.980984 -360.907422)
			(xy 376.95209 -360.861867) (xy 376.929899 -360.812696) (xy 376.914855 -360.76089) (xy 376.907256 -360.707481)
			(xy 376.90679 -360.680508) (xy 366.995456 -360.680508) (xy 366.995456 -360.963464) (xy 367.16511 -361.133136)
			(xy 369.3861 -361.133136) (xy 369.390189 -361.077254) (xy 369.402372 -361.022564) (xy 369.422388 -360.97023)
			(xy 369.449811 -360.921368) (xy 369.484056 -360.87702) (xy 369.524392 -360.83813) (xy 369.569962 -360.805528)
			(xy 369.619793 -360.779909) (xy 369.672823 -360.761817) (xy 369.727921 -360.75164) (xy 369.783915 -360.749594)
			(xy 369.83961 -360.755722) (xy 369.893819 -360.769894) (xy 369.945387 -360.791808) (xy 369.993215 -360.820997)
			(xy 370.036283 -360.856838) (xy 370.073673 -360.898568) (xy 370.104589 -360.945298) (xy 370.128372 -360.996031)
			(xy 370.144514 -361.049687) (xy 370.152673 -361.105121) (xy 370.153184 -361.133136) (xy 370.152673 -361.161151)
			(xy 370.144514 -361.216585) (xy 370.128372 -361.270241) (xy 370.104589 -361.320974) (xy 370.073673 -361.367704)
			(xy 370.036283 -361.409434) (xy 369.993215 -361.445275) (xy 369.945387 -361.474464) (xy 369.893819 -361.496378)
			(xy 369.83961 -361.51055) (xy 369.783915 -361.516678) (xy 369.727921 -361.514632) (xy 369.672823 -361.504455)
			(xy 369.619793 -361.486363) (xy 369.569962 -361.460744) (xy 369.524392 -361.428142) (xy 369.484056 -361.389252)
			(xy 369.449811 -361.344904) (xy 369.422388 -361.296042) (xy 369.402372 -361.243708) (xy 369.390189 -361.189018)
			(xy 369.3861 -361.133136) (xy 367.16511 -361.133136) (xy 368.128939 -362.097066) (xy 376.025154 -362.097066)
			(xy 376.029225 -362.041444) (xy 376.041351 -361.987007) (xy 376.061274 -361.934916) (xy 376.08857 -361.886281)
			(xy 376.122656 -361.842138) (xy 376.162805 -361.803429) (xy 376.208163 -361.770978) (xy 376.257763 -361.745477)
			(xy 376.310547 -361.72747) (xy 376.36539 -361.71734) (xy 376.421124 -361.715303) (xy 376.476561 -361.721403)
			(xy 376.530518 -361.735509) (xy 376.581847 -361.757321) (xy 376.629453 -361.786375) (xy 376.672321 -361.82205)
			(xy 376.709538 -361.863587) (xy 376.740311 -361.9101) (xy 376.763983 -361.960597) (xy 376.780051 -362.014004)
			(xy 376.788171 -362.06918) (xy 376.78868 -362.097066) (xy 376.788171 -362.124952) (xy 376.780051 -362.180128)
			(xy 376.763983 -362.233535) (xy 376.740311 -362.284032) (xy 376.709538 -362.330545) (xy 376.672321 -362.372082)
			(xy 376.629453 -362.407757) (xy 376.581847 -362.436811) (xy 376.530518 -362.458623) (xy 376.476561 -362.472729)
			(xy 376.421124 -362.478829) (xy 376.36539 -362.476792) (xy 376.310547 -362.466662) (xy 376.257763 -362.448655)
			(xy 376.208163 -362.423154) (xy 376.162805 -362.390703) (xy 376.122656 -362.351994) (xy 376.08857 -362.307851)
			(xy 376.061274 -362.259216) (xy 376.041351 -362.207125) (xy 376.029225 -362.152688) (xy 376.025154 -362.097066)
			(xy 368.128939 -362.097066) (xy 369.42395 -363.392212) (xy 382.216914 -363.392212) (xy 382.246034 -363.392668)
			(xy 382.303777 -363.400265) (xy 382.360033 -363.41534) (xy 382.413837 -363.437634) (xy 382.464268 -363.466766)
			(xy 382.510461 -363.502236) (xy 382.531366 -363.522514) (xy 385.084828 -366.075976) (xy 392.92276 -366.075976)
			(xy 398.732756 -360.26598) (xy 398.753661 -360.24569) (xy 398.799838 -360.210171) (xy 398.850261 -360.180991)
			(xy 398.904064 -360.15865) (xy 398.960325 -360.143531) (xy 399.01808 -360.135894) (xy 399.047208 -360.135424)
			(xy 407.601166 -360.135424) (xy 408.47137 -359.265474) (xy 408.492304 -359.245229) (xy 408.538495 -359.209763)
			(xy 408.588921 -359.180631) (xy 408.642719 -359.158331) (xy 408.698967 -359.143246) (xy 408.756704 -359.135633)
			(xy 408.785822 -359.135172) (xy 409.713938 -359.135172) (xy 409.744325 -359.135641) (xy 409.804531 -359.143921)
			(xy 409.86305 -359.160322) (xy 409.91879 -359.184537) (xy 409.970714 -359.216117) (xy 410.017855 -359.254473)
			(xy 410.059334 -359.29889) (xy 410.094379 -359.348541) (xy 410.122338 -359.402501) (xy 410.142688 -359.459766)
			(xy 410.155052 -359.519268) (xy 410.1592 -359.5799) (xy 410.155052 -359.640532) (xy 410.142688 -359.700034)
			(xy 410.122338 -359.757299) (xy 410.094379 -359.811259) (xy 410.059334 -359.86091) (xy 410.017855 -359.905327)
			(xy 409.970714 -359.943683) (xy 409.91879 -359.975263) (xy 409.86305 -359.999478) (xy 409.804531 -360.015879)
			(xy 409.744325 -360.024159) (xy 409.713938 -360.02468) (xy 408.969972 -360.02468) (xy 408.099768 -360.894884)
			(xy 408.078864 -360.915174) (xy 408.032685 -360.950691) (xy 407.982262 -360.979869) (xy 407.928459 -361.00221)
			(xy 407.872198 -361.017329) (xy 407.814444 -361.024969) (xy 407.785316 -361.02544) (xy 399.231358 -361.02544)
			(xy 398.033442 -362.223304) (xy 409.80944 -362.223304) (xy 409.813511 -362.167682) (xy 409.825637 -362.113245)
			(xy 409.84556 -362.061154) (xy 409.872856 -362.012519) (xy 409.906942 -361.968376) (xy 409.947091 -361.929667)
			(xy 409.992449 -361.897216) (xy 410.042049 -361.871715) (xy 410.094833 -361.853708) (xy 410.149676 -361.843578)
			(xy 410.20541 -361.841541) (xy 410.260847 -361.847641) (xy 410.314804 -361.861747) (xy 410.366133 -361.883559)
			(xy 410.413739 -361.912613) (xy 410.456607 -361.948288) (xy 410.493824 -361.989825) (xy 410.524597 -362.036338)
			(xy 410.548269 -362.086835) (xy 410.564337 -362.140242) (xy 410.572457 -362.195418) (xy 410.572966 -362.223304)
			(xy 410.572457 -362.25119) (xy 410.564337 -362.306366) (xy 410.548269 -362.359773) (xy 410.524597 -362.41027)
			(xy 410.493824 -362.456783) (xy 410.456607 -362.49832) (xy 410.413739 -362.533995) (xy 410.366133 -362.563049)
			(xy 410.314804 -362.584861) (xy 410.260847 -362.598967) (xy 410.20541 -362.605067) (xy 410.149676 -362.60303)
			(xy 410.094833 -362.5929) (xy 410.042049 -362.574893) (xy 409.992449 -362.549392) (xy 409.947091 -362.516941)
			(xy 409.906942 -362.478232) (xy 409.872856 -362.434089) (xy 409.84556 -362.385454) (xy 409.825637 -362.333363)
			(xy 409.813511 -362.278926) (xy 409.80944 -362.223304) (xy 398.033442 -362.223304) (xy 397.063119 -363.193584)
			(xy 409.80944 -363.193584) (xy 409.813511 -363.137962) (xy 409.825637 -363.083525) (xy 409.84556 -363.031434)
			(xy 409.872856 -362.982799) (xy 409.906942 -362.938656) (xy 409.947091 -362.899947) (xy 409.992449 -362.867496)
			(xy 410.042049 -362.841995) (xy 410.094833 -362.823988) (xy 410.149676 -362.813858) (xy 410.20541 -362.811821)
			(xy 410.260847 -362.817921) (xy 410.314804 -362.832027) (xy 410.366133 -362.853839) (xy 410.413739 -362.882893)
			(xy 410.456607 -362.918568) (xy 410.493824 -362.960105) (xy 410.524597 -363.006618) (xy 410.548269 -363.057115)
			(xy 410.564337 -363.110522) (xy 410.572457 -363.165698) (xy 410.572966 -363.193584) (xy 410.572457 -363.22147)
			(xy 410.564337 -363.276646) (xy 410.548269 -363.330053) (xy 410.524597 -363.38055) (xy 410.493824 -363.427063)
			(xy 410.456607 -363.4686) (xy 410.413739 -363.504275) (xy 410.366133 -363.533329) (xy 410.316868 -363.554264)
			(xy 412.204154 -363.554264) (xy 412.204632 -363.526223) (xy 412.212837 -363.470745) (xy 412.229067 -363.417063)
			(xy 412.252972 -363.366331) (xy 412.284039 -363.31964) (xy 412.302452 -363.298486) (xy 412.312086 -363.287035)
			(xy 412.324872 -363.259996) (xy 412.329261 -363.23041) (xy 412.324878 -363.200824) (xy 412.312097 -363.173783)
			(xy 412.302452 -363.162342) (xy 412.284023 -363.141199) (xy 412.252931 -363.094519) (xy 412.229018 -363.043786)
			(xy 412.2128 -362.990095) (xy 412.204627 -362.934608) (xy 412.204154 -362.906564) (xy 412.20464 -362.879313)
			(xy 412.212396 -362.825365) (xy 412.227751 -362.77307) (xy 412.250393 -362.723493) (xy 412.279859 -362.677643)
			(xy 412.31555 -362.636452) (xy 412.356741 -362.600761) (xy 412.402591 -362.571295) (xy 412.452168 -362.548653)
			(xy 412.504463 -362.533298) (xy 412.558411 -362.525542) (xy 412.612913 -362.525542) (xy 412.666861 -362.533298)
			(xy 412.719156 -362.548653) (xy 412.768733 -362.571295) (xy 412.814583 -362.600761) (xy 412.855774 -362.636452)
			(xy 412.891465 -362.677643) (xy 412.920931 -362.723493) (xy 412.943573 -362.77307) (xy 412.958928 -362.825365)
			(xy 412.966684 -362.879313) (xy 412.96717 -362.906564) (xy 412.966669 -362.934604) (xy 412.958472 -362.990082)
			(xy 412.942248 -363.043765) (xy 412.918348 -363.094497) (xy 412.887284 -363.141188) (xy 412.868872 -363.162342)
			(xy 412.864368 -363.167676) (xy 420.18153 -363.167676) (xy 420.185601 -363.112054) (xy 420.197727 -363.057617)
			(xy 420.21765 -363.005526) (xy 420.244946 -362.956891) (xy 420.279032 -362.912748) (xy 420.319181 -362.874039)
			(xy 420.364539 -362.841588) (xy 420.414139 -362.816087) (xy 420.466923 -362.79808) (xy 420.521766 -362.78795)
			(xy 420.5775 -362.785913) (xy 420.632937 -362.792013) (xy 420.686894 -362.806119) (xy 420.738223 -362.827931)
			(xy 420.785829 -362.856985) (xy 420.828697 -362.89266) (xy 420.865914 -362.934197) (xy 420.896687 -362.98071)
			(xy 420.920359 -363.031207) (xy 420.936427 -363.084614) (xy 420.944547 -363.13979) (xy 420.945056 -363.167676)
			(xy 420.944547 -363.195562) (xy 420.936427 -363.250738) (xy 420.920359 -363.304145) (xy 420.896687 -363.354642)
			(xy 420.865914 -363.401155) (xy 420.828697 -363.442692) (xy 420.785829 -363.478367) (xy 420.738223 -363.507421)
			(xy 420.686894 -363.529233) (xy 420.632937 -363.543339) (xy 420.591359 -363.547914) (xy 421.892476 -363.547914)
			(xy 421.892932 -363.520543) (xy 421.900749 -363.466363) (xy 421.91624 -363.413859) (xy 421.939084 -363.364112)
			(xy 421.968813 -363.318147) (xy 421.986456 -363.297216) (xy 421.995675 -363.285877) (xy 422.007847 -363.259322)
			(xy 422.01202 -363.230411) (xy 422.007853 -363.201498) (xy 421.995686 -363.174941) (xy 421.986456 -363.163612)
			(xy 421.968802 -363.142692) (xy 421.939094 -363.096715) (xy 421.916261 -363.046965) (xy 421.900773 -362.994462)
			(xy 421.892948 -362.940284) (xy 421.892476 -362.912914) (xy 421.892962 -362.885663) (xy 421.900718 -362.831715)
			(xy 421.916073 -362.77942) (xy 421.938715 -362.729843) (xy 421.968181 -362.683993) (xy 422.003872 -362.642802)
			(xy 422.045063 -362.607111) (xy 422.090913 -362.577645) (xy 422.14049 -362.555003) (xy 422.192785 -362.539648)
			(xy 422.246733 -362.531892) (xy 422.301235 -362.531892) (xy 422.355183 -362.539648) (xy 422.407478 -362.555003)
			(xy 422.457055 -362.577645) (xy 422.502905 -362.607111) (xy 422.544096 -362.642802) (xy 422.579787 -362.683993)
			(xy 422.609253 -362.729843) (xy 422.631895 -362.77942) (xy 422.64725 -362.831715) (xy 422.655006 -362.885663)
			(xy 422.655492 -362.912914) (xy 422.655036 -362.940285) (xy 422.647216 -362.994464) (xy 422.631725 -363.046968)
			(xy 422.608881 -363.096714) (xy 422.579154 -363.142681) (xy 422.561512 -363.163612) (xy 422.555283 -363.171232)
			(xy 429.73955 -363.171232) (xy 429.743621 -363.11561) (xy 429.755747 -363.061173) (xy 429.77567 -363.009082)
			(xy 429.802966 -362.960447) (xy 429.837052 -362.916304) (xy 429.877201 -362.877595) (xy 429.922559 -362.845144)
			(xy 429.972159 -362.819643) (xy 430.024943 -362.801636) (xy 430.079786 -362.791506) (xy 430.13552 -362.789469)
			(xy 430.190957 -362.795569) (xy 430.244914 -362.809675) (xy 430.296243 -362.831487) (xy 430.343849 -362.860541)
			(xy 430.386717 -362.896216) (xy 430.423934 -362.937753) (xy 430.454707 -362.984266) (xy 430.478379 -363.034763)
			(xy 430.494447 -363.08817) (xy 430.502567 -363.143346) (xy 430.503076 -363.171232) (xy 430.502567 -363.199118)
			(xy 430.494447 -363.254294) (xy 430.478379 -363.307701) (xy 430.454707 -363.358198) (xy 430.423934 -363.404711)
			(xy 430.386717 -363.446248) (xy 430.343849 -363.481923) (xy 430.296243 -363.510977) (xy 430.244914 -363.532789)
			(xy 430.190957 -363.546895) (xy 430.13552 -363.552995) (xy 430.079786 -363.550958) (xy 430.024943 -363.540828)
			(xy 429.972159 -363.522821) (xy 429.922559 -363.49732) (xy 429.877201 -363.464869) (xy 429.837052 -363.42616)
			(xy 429.802966 -363.382017) (xy 429.77567 -363.333382) (xy 429.755747 -363.281291) (xy 429.743621 -363.226854)
			(xy 429.73955 -363.171232) (xy 422.555283 -363.171232) (xy 422.552261 -363.174929) (xy 422.540084 -363.20149)
			(xy 422.535913 -363.230411) (xy 422.54009 -363.25933) (xy 422.552272 -363.285889) (xy 422.561512 -363.297216)
			(xy 422.579127 -363.318167) (xy 422.608842 -363.364135) (xy 422.631682 -363.413878) (xy 422.647179 -363.466374)
			(xy 422.655014 -363.520546) (xy 422.655492 -363.547914) (xy 422.655006 -363.575165) (xy 422.64725 -363.629113)
			(xy 422.631895 -363.681408) (xy 422.609253 -363.730985) (xy 422.579787 -363.776835) (xy 422.544096 -363.818026)
			(xy 422.502905 -363.853717) (xy 422.457055 -363.883183) (xy 422.407478 -363.905825) (xy 422.355183 -363.92118)
			(xy 422.301235 -363.928936) (xy 422.246733 -363.928936) (xy 422.192785 -363.92118) (xy 422.14049 -363.905825)
			(xy 422.090913 -363.883183) (xy 422.045063 -363.853717) (xy 422.003872 -363.818026) (xy 421.968181 -363.776835)
			(xy 421.938715 -363.730985) (xy 421.916073 -363.681408) (xy 421.900718 -363.629113) (xy 421.892962 -363.575165)
			(xy 421.892476 -363.547914) (xy 420.591359 -363.547914) (xy 420.5775 -363.549439) (xy 420.521766 -363.547402)
			(xy 420.466923 -363.537272) (xy 420.414139 -363.519265) (xy 420.364539 -363.493764) (xy 420.319181 -363.461313)
			(xy 420.279032 -363.422604) (xy 420.244946 -363.378461) (xy 420.21765 -363.329826) (xy 420.197727 -363.277735)
			(xy 420.185601 -363.223298) (xy 420.18153 -363.167676) (xy 412.864368 -363.167676) (xy 412.859217 -363.173775)
			(xy 412.846444 -363.200822) (xy 412.842063 -363.23041) (xy 412.84645 -363.259998) (xy 412.859228 -363.287043)
			(xy 412.868872 -363.298486) (xy 412.887318 -363.319615) (xy 412.918407 -363.366299) (xy 412.942317 -363.417036)
			(xy 412.958531 -363.470729) (xy 412.966699 -363.526219) (xy 412.96717 -363.554264) (xy 412.966684 -363.581515)
			(xy 412.958928 -363.635463) (xy 412.943573 -363.687758) (xy 412.920931 -363.737335) (xy 412.891465 -363.783185)
			(xy 412.855774 -363.824376) (xy 412.814583 -363.860067) (xy 412.768733 -363.889533) (xy 412.719156 -363.912175)
			(xy 412.666861 -363.92753) (xy 412.612913 -363.935286) (xy 412.558411 -363.935286) (xy 412.504463 -363.92753)
			(xy 412.452168 -363.912175) (xy 412.402591 -363.889533) (xy 412.356741 -363.860067) (xy 412.31555 -363.824376)
			(xy 412.279859 -363.783185) (xy 412.250393 -363.737335) (xy 412.227751 -363.687758) (xy 412.212396 -363.635463)
			(xy 412.20464 -363.581515) (xy 412.204154 -363.554264) (xy 410.316868 -363.554264) (xy 410.314804 -363.555141)
			(xy 410.260847 -363.569247) (xy 410.20541 -363.575347) (xy 410.149676 -363.57331) (xy 410.094833 -363.56318)
			(xy 410.042049 -363.545173) (xy 409.992449 -363.519672) (xy 409.947091 -363.487221) (xy 409.906942 -363.448512)
			(xy 409.872856 -363.404369) (xy 409.84556 -363.355734) (xy 409.825637 -363.303643) (xy 409.813511 -363.249206)
			(xy 409.80944 -363.193584) (xy 397.063119 -363.193584) (xy 396.30617 -363.9505) (xy 416.452737 -363.9505)
			(xy 416.456906 -363.894879) (xy 416.469318 -363.840501) (xy 416.489697 -363.788581) (xy 416.517587 -363.740278)
			(xy 416.552365 -363.696672) (xy 416.593254 -363.658736) (xy 416.639341 -363.627319) (xy 416.689595 -363.603122)
			(xy 416.742895 -363.586686) (xy 416.79805 -363.578378) (xy 416.825938 -363.577886) (xy 416.853268 -363.578397)
			(xy 416.907345 -363.586362) (xy 416.959677 -363.602145) (xy 417.009141 -363.625407) (xy 417.054673 -363.655648)
			(xy 417.095297 -363.692219) (xy 417.13014 -363.734335) (xy 417.144708 -363.757464) (xy 417.152655 -363.769672)
			(xy 417.174117 -363.789348) (xy 417.200265 -363.802157) (xy 417.228966 -363.807056) (xy 417.257882 -363.803645)
			(xy 417.271454 -363.798358) (xy 417.29466 -363.788857) (xy 417.342995 -363.775511) (xy 417.392686 -363.768787)
			(xy 417.417758 -363.768386) (xy 417.442827 -363.768806) (xy 417.49251 -363.775558) (xy 417.540845 -363.788892)
			(xy 417.564062 -363.798358) (xy 417.577647 -363.803579) (xy 417.606542 -363.806943) (xy 417.635215 -363.802036)
			(xy 417.661347 -363.789254) (xy 417.682824 -363.769633) (xy 417.690808 -363.757464) (xy 417.705377 -363.734333)
			(xy 417.74022 -363.692212) (xy 417.780843 -363.655633) (xy 417.826374 -363.625382) (xy 417.875836 -363.602106)
			(xy 417.928167 -363.586306) (xy 417.982246 -363.57832) (xy 418.03691 -363.57832) (xy 418.090989 -363.586306)
			(xy 418.14332 -363.602106) (xy 418.192782 -363.625382) (xy 418.238313 -363.655633) (xy 418.278936 -363.692212)
			(xy 418.313779 -363.734333) (xy 418.328348 -363.757464) (xy 418.336257 -363.7697) (xy 418.35773 -363.789375)
			(xy 418.383887 -363.802181) (xy 418.412598 -363.807072) (xy 418.44152 -363.803652) (xy 418.455094 -363.798358)
			(xy 418.478307 -363.788876) (xy 418.526638 -363.775523) (xy 418.576327 -363.768791) (xy 418.601398 -363.768386)
			(xy 418.627622 -363.768832) (xy 418.679552 -363.776174) (xy 418.72994 -363.790728) (xy 418.777787 -363.812206)
			(xy 418.822149 -363.840183) (xy 418.862149 -363.874105) (xy 418.896994 -363.913303) (xy 418.925997 -363.957001)
			(xy 418.937694 -363.980476) (xy 418.9441 -363.992667) (xy 418.962164 -364.013433) (xy 418.985123 -364.028613)
			(xy 419.011303 -364.037104) (xy 419.038801 -364.038288) (xy 419.065615 -364.032078) (xy 419.089792 -364.018927)
			(xy 419.1 -364.009686) (xy 419.121475 -363.98975) (xy 419.169373 -363.956) (xy 419.221866 -363.929965)
			(xy 419.277721 -363.912257) (xy 419.335625 -363.903292) (xy 419.364922 -363.902752) (xy 419.382941 -363.902975)
			(xy 419.418816 -363.906408) (xy 419.43655 -363.90961) (xy 419.451762 -363.911934) (xy 419.482317 -363.908418)
			(xy 419.510438 -363.895963) (xy 419.533574 -363.875698) (xy 419.549626 -363.849463) (xy 419.553898 -363.83468)
			(xy 419.561329 -363.807646) (xy 419.582954 -363.75592) (xy 419.611913 -363.707915) (xy 419.647584 -363.664662)
			(xy 419.689199 -363.627094) (xy 419.735863 -363.596019) (xy 419.78657 -363.572104) (xy 419.840231 -363.555866)
			(xy 419.89569 -363.547652) (xy 419.923722 -363.547152) (xy 419.950972 -363.547657) (xy 420.004917 -363.555416)
			(xy 420.057209 -363.570772) (xy 420.106783 -363.593412) (xy 420.152632 -363.622877) (xy 420.193821 -363.658566)
			(xy 420.229512 -363.699754) (xy 420.258979 -363.745601) (xy 420.281622 -363.795174) (xy 420.29698 -363.847465)
			(xy 420.304742 -363.90141) (xy 420.30523 -363.92866) (xy 420.304831 -363.9505) (xy 426.141163 -363.9505)
			(xy 426.145331 -363.894891) (xy 426.157739 -363.840523) (xy 426.178111 -363.788612) (xy 426.205992 -363.740317)
			(xy 426.240759 -363.696717) (xy 426.281635 -363.658784) (xy 426.327709 -363.627368) (xy 426.37795 -363.603168)
			(xy 426.431236 -363.586726) (xy 426.486377 -363.57841) (xy 426.51426 -363.577886) (xy 426.541591 -363.57838)
			(xy 426.595669 -363.586348) (xy 426.648001 -363.602134) (xy 426.697465 -363.625399) (xy 426.742997 -363.655643)
			(xy 426.78362 -363.692216) (xy 426.818463 -363.734334) (xy 426.83303 -363.757464) (xy 426.840956 -363.769687)
			(xy 426.862424 -363.789363) (xy 426.888577 -363.80217) (xy 426.917283 -363.807065) (xy 426.946203 -363.803649)
			(xy 426.959776 -363.798358) (xy 426.982991 -363.788881) (xy 427.031321 -363.775526) (xy 427.081009 -363.768793)
			(xy 427.10608 -363.768386) (xy 427.131148 -363.768832) (xy 427.180831 -363.775573) (xy 427.229166 -363.788896)
			(xy 427.252384 -363.798358) (xy 427.265997 -363.803497) (xy 427.294878 -363.806878) (xy 427.323541 -363.801989)
			(xy 427.349668 -363.789227) (xy 427.371145 -363.769625) (xy 427.37913 -363.757464) (xy 427.393699 -363.734333)
			(xy 427.428542 -363.692212) (xy 427.469165 -363.655633) (xy 427.514696 -363.625382) (xy 427.564158 -363.602106)
			(xy 427.616489 -363.586306) (xy 427.670568 -363.57832) (xy 427.725232 -363.57832) (xy 427.779311 -363.586306)
			(xy 427.831642 -363.602106) (xy 427.881104 -363.625382) (xy 427.926635 -363.655633) (xy 427.967258 -363.692212)
			(xy 428.002101 -363.734333) (xy 428.01667 -363.757464) (xy 428.024558 -363.769715) (xy 428.046036 -363.78939)
			(xy 428.0722 -363.802194) (xy 428.100915 -363.807082) (xy 428.129841 -363.803655) (xy 428.143416 -363.798358)
			(xy 428.166626 -363.788869) (xy 428.214959 -363.775518) (xy 428.264648 -363.76879) (xy 428.28972 -363.768386)
			(xy 428.316563 -363.768828) (xy 428.369694 -363.776536) (xy 428.421169 -363.791788) (xy 428.469922 -363.814269)
			(xy 428.514944 -363.843513) (xy 428.555304 -363.878916) (xy 428.590165 -363.919745) (xy 428.618807 -363.965153)
			(xy 428.640635 -364.014202) (xy 428.648368 -364.039912) (xy 428.653106 -364.054383) (xy 428.669606 -364.079945)
			(xy 428.692905 -364.099513) (xy 428.720934 -364.111348) (xy 428.751206 -364.1144) (xy 428.781034 -364.108398)
			(xy 428.794672 -364.101634) (xy 428.822813 -364.086991) (xy 428.882767 -364.066268) (xy 428.945327 -364.055774)
			(xy 428.977044 -364.055152) (xy 428.995063 -364.055372) (xy 429.030938 -364.058807) (xy 429.048672 -364.06201)
			(xy 429.063881 -364.064356) (xy 429.094438 -364.060834) (xy 429.122561 -364.048373) (xy 429.145697 -364.028104)
			(xy 429.161749 -364.001864) (xy 429.16602 -363.98708) (xy 429.173431 -363.960039) (xy 429.195057 -363.908313)
			(xy 429.224019 -363.860306) (xy 429.259692 -363.817054) (xy 429.30131 -363.779486) (xy 429.347976 -363.748411)
			(xy 429.398687 -363.724498) (xy 429.45235 -363.708261) (xy 429.507811 -363.700051) (xy 429.535844 -363.699552)
			(xy 429.563095 -363.700037) (xy 429.61704 -363.707798) (xy 429.669332 -363.723157) (xy 429.718907 -363.7458)
			(xy 429.764755 -363.775267) (xy 429.805944 -363.810959) (xy 429.841635 -363.852148) (xy 429.871102 -363.897996)
			(xy 429.893744 -363.947571) (xy 429.909103 -363.999864) (xy 429.916864 -364.053809) (xy 429.917352 -364.08106)
			(xy 429.916876 -364.108634) (xy 429.908928 -364.163207) (xy 429.893206 -364.216068) (xy 429.870038 -364.266114)
			(xy 429.839906 -364.312304) (xy 429.803439 -364.353675) (xy 429.782732 -364.37189) (xy 429.771872 -364.381828)
			(xy 429.755794 -364.406466) (xy 429.747403 -364.434664) (xy 429.747395 -364.464084) (xy 429.755772 -364.492287)
			(xy 429.771838 -364.516933) (xy 429.782732 -364.52683) (xy 429.803396 -364.54509) (xy 429.839856 -364.586457)
			(xy 429.869981 -364.632642) (xy 429.893143 -364.682683) (xy 429.908859 -364.735537) (xy 429.916801 -364.790103)
			(xy 429.916805 -364.845245) (xy 429.90887 -364.899812) (xy 429.893161 -364.952669) (xy 429.870006 -365.002713)
			(xy 429.839888 -365.048902) (xy 429.803433 -365.090273) (xy 429.782732 -365.10849) (xy 429.771872 -365.118428)
			(xy 429.755794 -365.143066) (xy 429.747403 -365.171264) (xy 429.747395 -365.200684) (xy 429.755772 -365.228887)
			(xy 429.771838 -365.253533) (xy 429.782732 -365.26343) (xy 429.803467 -365.281615) (xy 429.839934 -365.32299)
			(xy 429.870063 -365.369186) (xy 429.893224 -365.419239) (xy 429.908935 -365.472105) (xy 429.91687 -365.526684)
			(xy 429.917352 -365.55426) (xy 429.916785 -365.581508) (xy 429.909035 -365.635451) (xy 429.893687 -365.687741)
			(xy 429.871054 -365.737315) (xy 429.841596 -365.783164) (xy 429.805913 -365.824353) (xy 429.764731 -365.860045)
			(xy 429.718889 -365.889513) (xy 429.66932 -365.912158) (xy 429.617033 -365.927517) (xy 429.563092 -365.935279)
			(xy 429.535844 -365.935768) (xy 429.507989 -365.935229) (xy 429.452873 -365.927111) (xy 429.399522 -365.91107)
			(xy 429.349068 -365.887446) (xy 429.302582 -365.856741) (xy 429.261052 -365.819607) (xy 429.225359 -365.776832)
			(xy 429.196261 -365.729325) (xy 429.174375 -365.678093) (xy 429.166782 -365.651288) (xy 429.162503 -365.637174)
			(xy 429.147112 -365.612032) (xy 429.125194 -365.592318) (xy 429.098568 -365.579666) (xy 429.069441 -365.575125)
			(xy 429.054768 -365.576612) (xy 429.041752 -365.578282) (xy 429.015567 -365.580061) (xy 429.002444 -365.580168)
			(xy 428.988295 -365.58007) (xy 428.960072 -365.578039) (xy 428.946056 -365.576104) (xy 428.932707 -365.574531)
			(xy 428.906016 -365.577627) (xy 428.881063 -365.587594) (xy 428.859584 -365.603737) (xy 428.843071 -365.624934)
			(xy 428.832675 -365.64971) (xy 428.830486 -365.662972) (xy 428.826449 -365.690134) (xy 428.811471 -365.742967)
			(xy 428.789074 -365.793107) (xy 428.75972 -365.839519) (xy 428.724017 -365.881243) (xy 428.682701 -365.917419)
			(xy 428.636627 -365.947298) (xy 428.586745 -365.970264) (xy 428.534086 -365.985843) (xy 428.479738 -365.993712)
			(xy 428.45228 -365.994188) (xy 428.425027 -365.993741) (xy 428.371077 -365.985981) (xy 428.318781 -365.970622)
			(xy 428.269202 -365.947977) (xy 428.223351 -365.918507) (xy 428.18216 -365.882812) (xy 428.146469 -365.841617)
			(xy 428.117003 -365.795763) (xy 428.094364 -365.746182) (xy 428.07901 -365.693884) (xy 428.071256 -365.639933)
			(xy 428.070772 -365.61268) (xy 428.071303 -365.585108) (xy 428.079243 -365.530538) (xy 428.094956 -365.47768)
			(xy 428.118114 -365.427634) (xy 428.148235 -365.381443) (xy 428.18469 -365.340068) (xy 428.205392 -365.32185)
			(xy 428.21631 -365.311972) (xy 428.232382 -365.287316) (xy 428.240764 -365.259103) (xy 428.24076 -365.229671)
			(xy 428.232371 -365.20146) (xy 428.216292 -365.176809) (xy 428.205392 -365.16691) (xy 428.184681 -365.148699)
			(xy 428.148211 -365.10733) (xy 428.118079 -365.06114) (xy 428.094913 -365.011092) (xy 428.079197 -364.95823)
			(xy 428.071257 -364.903655) (xy 428.070772 -364.87608) (xy 428.071239 -364.849579) (xy 428.078582 -364.797089)
			(xy 428.093124 -364.746122) (xy 428.114584 -364.697659) (xy 428.142548 -364.652636) (xy 428.159164 -364.631986)
			(xy 428.168558 -364.619807) (xy 428.180349 -364.591418) (xy 428.183178 -364.560808) (xy 428.17679 -364.530739)
			(xy 428.161762 -364.503922) (xy 428.13945 -364.482778) (xy 428.12589 -364.475522) (xy 428.102212 -364.463399)
			(xy 428.058228 -364.433483) (xy 428.018943 -364.397619) (xy 427.985156 -364.356534) (xy 427.97095 -364.334044)
			(xy 427.963041 -364.321808) (xy 427.941569 -364.302132) (xy 427.915411 -364.289326) (xy 427.8867 -364.284434)
			(xy 427.857778 -364.287856) (xy 427.844204 -364.29315) (xy 427.820992 -364.302633) (xy 427.77266 -364.315986)
			(xy 427.722971 -364.322717) (xy 427.6979 -364.323122) (xy 427.672831 -364.32269) (xy 427.623148 -364.315945)
			(xy 427.574814 -364.302615) (xy 427.551596 -364.29315) (xy 427.537991 -364.287986) (xy 427.509106 -364.28461)
			(xy 427.480439 -364.289503) (xy 427.45431 -364.302271) (xy 427.432834 -364.32188) (xy 427.42485 -364.334044)
			(xy 427.410281 -364.357175) (xy 427.375438 -364.399296) (xy 427.334815 -364.435875) (xy 427.289284 -364.466126)
			(xy 427.239822 -364.489402) (xy 427.187491 -364.505202) (xy 427.133412 -364.513188) (xy 427.078748 -364.513188)
			(xy 427.024669 -364.505202) (xy 426.972338 -364.489402) (xy 426.922876 -364.466126) (xy 426.877345 -364.435875)
			(xy 426.836722 -364.399296) (xy 426.801879 -364.357175) (xy 426.78731 -364.334044) (xy 426.779344 -364.321849)
			(xy 426.757887 -364.302173) (xy 426.731745 -364.289362) (xy 426.703048 -364.284459) (xy 426.674135 -364.287865)
			(xy 426.660564 -364.29315) (xy 426.637357 -364.302646) (xy 426.589022 -364.315994) (xy 426.539332 -364.32272)
			(xy 426.51426 -364.323122) (xy 426.486377 -364.32259) (xy 426.431236 -364.314274) (xy 426.37795 -364.297832)
			(xy 426.327709 -364.273632) (xy 426.281635 -364.242216) (xy 426.240759 -364.204283) (xy 426.205992 -364.160683)
			(xy 426.178111 -364.112388) (xy 426.157739 -364.060477) (xy 426.145331 -364.006109) (xy 426.141163 -363.9505)
			(xy 420.304831 -363.9505) (xy 420.304726 -363.956233) (xy 420.29678 -364.010804) (xy 420.281062 -364.063662)
			(xy 420.257899 -364.113708) (xy 420.227774 -364.159899) (xy 420.191314 -364.201273) (xy 420.17061 -364.21949)
			(xy 420.159752 -364.229429) (xy 420.143677 -364.254067) (xy 420.135288 -364.282265) (xy 420.135281 -364.311684)
			(xy 420.143655 -364.339885) (xy 420.159718 -364.364532) (xy 420.17061 -364.37443) (xy 420.191275 -364.39269)
			(xy 420.227737 -364.434056) (xy 420.257864 -364.48024) (xy 420.281027 -364.530281) (xy 420.296744 -364.583136)
			(xy 420.304687 -364.637703) (xy 420.304691 -364.692845) (xy 420.296755 -364.747413) (xy 420.281046 -364.80027)
			(xy 420.257889 -364.850314) (xy 420.227769 -364.896503) (xy 420.191312 -364.937874) (xy 420.17061 -364.95609)
			(xy 420.159752 -364.966029) (xy 420.143677 -364.990667) (xy 420.136055 -365.016288) (xy 422.68343 -365.016288)
			(xy 422.687501 -364.960666) (xy 422.699627 -364.906229) (xy 422.71955 -364.854138) (xy 422.746846 -364.805503)
			(xy 422.780932 -364.76136) (xy 422.821081 -364.722651) (xy 422.866439 -364.6902) (xy 422.916039 -364.664699)
			(xy 422.968823 -364.646692) (xy 423.023666 -364.636562) (xy 423.0794 -364.634525) (xy 423.134837 -364.640625)
			(xy 423.188794 -364.654731) (xy 423.240123 -364.676543) (xy 423.287729 -364.705597) (xy 423.330597 -364.741272)
			(xy 423.367814 -364.782809) (xy 423.398587 -364.829322) (xy 423.422259 -364.879819) (xy 423.438327 -364.933226)
			(xy 423.446447 -364.988402) (xy 423.446956 -365.016288) (xy 423.446447 -365.044174) (xy 423.438327 -365.09935)
			(xy 423.422259 -365.152757) (xy 423.398587 -365.203254) (xy 423.367814 -365.249767) (xy 423.330597 -365.291304)
			(xy 423.287729 -365.326979) (xy 423.240123 -365.356033) (xy 423.188794 -365.377845) (xy 423.134837 -365.391951)
			(xy 423.0794 -365.398051) (xy 423.023666 -365.396014) (xy 422.968823 -365.385884) (xy 422.916039 -365.367877)
			(xy 422.866439 -365.342376) (xy 422.821081 -365.309925) (xy 422.780932 -365.271216) (xy 422.746846 -365.227073)
			(xy 422.71955 -365.178438) (xy 422.699627 -365.126347) (xy 422.687501 -365.07191) (xy 422.68343 -365.016288)
			(xy 420.136055 -365.016288) (xy 420.135288 -365.018865) (xy 420.135281 -365.048284) (xy 420.143655 -365.076485)
			(xy 420.159718 -365.101132) (xy 420.17061 -365.11103) (xy 420.191341 -365.12922) (xy 420.227809 -365.170593)
			(xy 420.257939 -365.216788) (xy 420.281101 -365.26684) (xy 420.296813 -365.319706) (xy 420.304748 -365.374284)
			(xy 420.30523 -365.40186) (xy 420.304708 -365.429111) (xy 420.296957 -365.483059) (xy 420.281607 -365.535354)
			(xy 420.258971 -365.584932) (xy 420.229509 -365.630785) (xy 420.193821 -365.671977) (xy 420.152634 -365.707672)
			(xy 420.106787 -365.737141) (xy 420.057212 -365.759785) (xy 420.004919 -365.775143) (xy 419.950973 -365.782903)
			(xy 419.923722 -365.783368) (xy 419.895866 -365.782849) (xy 419.840749 -365.774727) (xy 419.787398 -365.758683)
			(xy 419.736944 -365.735057) (xy 419.690459 -365.704349) (xy 419.648929 -365.667213) (xy 419.613236 -365.624437)
			(xy 419.584138 -365.576927) (xy 419.562253 -365.525694) (xy 419.55466 -365.498888) (xy 419.550403 -365.484766)
			(xy 419.535007 -365.459622) (xy 419.513085 -365.439908) (xy 419.486453 -365.427258) (xy 419.45732 -365.422722)
			(xy 419.442646 -365.424212) (xy 419.42963 -365.425885) (xy 419.403445 -365.427662) (xy 419.390322 -365.427768)
			(xy 419.361422 -365.427257) (xy 419.304278 -365.418587) (xy 419.27653 -365.410496) (xy 419.262999 -365.40669)
			(xy 419.234907 -365.405954) (xy 419.207676 -365.412891) (xy 419.183359 -365.426976) (xy 419.163794 -365.447148)
			(xy 419.150457 -365.471882) (xy 419.144354 -365.499313) (xy 419.144704 -365.513366) (xy 419.145466 -365.53648)
			(xy 419.14498 -365.563731) (xy 419.137224 -365.617679) (xy 419.121869 -365.669974) (xy 419.099227 -365.719551)
			(xy 419.069761 -365.765401) (xy 419.03407 -365.806592) (xy 418.992879 -365.842283) (xy 418.947029 -365.871749)
			(xy 418.897452 -365.894391) (xy 418.845157 -365.909746) (xy 418.791209 -365.917502) (xy 418.736707 -365.917502)
			(xy 418.682759 -365.909746) (xy 418.630464 -365.894391) (xy 418.580887 -365.871749) (xy 418.535037 -365.842283)
			(xy 418.493846 -365.806592) (xy 418.458155 -365.765401) (xy 418.428689 -365.719551) (xy 418.406047 -365.669974)
			(xy 418.390692 -365.617679) (xy 418.382936 -365.563731) (xy 418.38245 -365.53648) (xy 418.382953 -365.508907)
			(xy 418.390896 -365.454335) (xy 418.406612 -365.401475) (xy 418.429775 -365.351428) (xy 418.459902 -365.305238)
			(xy 418.496365 -365.263866) (xy 418.51707 -365.24565) (xy 418.52799 -365.235773) (xy 418.544066 -365.211118)
			(xy 418.552449 -365.182904) (xy 418.552446 -365.15347) (xy 418.544055 -365.125259) (xy 418.527972 -365.100607)
			(xy 418.51707 -365.09071) (xy 418.496354 -365.072504) (xy 418.459886 -365.031133) (xy 418.429755 -364.984942)
			(xy 418.40659 -364.934893) (xy 418.390874 -364.88203) (xy 418.382935 -364.827455) (xy 418.38245 -364.79988)
			(xy 418.38292 -364.77338) (xy 418.390262 -364.720892) (xy 418.404802 -364.669925) (xy 418.42626 -364.621464)
			(xy 418.439854 -364.598712) (xy 418.446578 -364.587148) (xy 418.454271 -364.561535) (xy 418.455055 -364.534802)
			(xy 418.448875 -364.508782) (xy 418.436156 -364.485257) (xy 418.417769 -364.465837) (xy 418.40658 -364.458504)
			(xy 418.381664 -364.442569) (xy 418.336742 -364.404103) (xy 418.298456 -364.359028) (xy 418.282628 -364.334044)
			(xy 418.27474 -364.321793) (xy 418.253262 -364.302117) (xy 418.227099 -364.289313) (xy 418.198383 -364.284425)
			(xy 418.169457 -364.287852) (xy 418.155882 -364.29315) (xy 418.132672 -364.30264) (xy 418.084339 -364.31599)
			(xy 418.03465 -364.322718) (xy 418.009578 -364.323122) (xy 417.984509 -364.322697) (xy 417.934826 -364.315949)
			(xy 417.886491 -364.302616) (xy 417.863274 -364.29315) (xy 417.849677 -364.287963) (xy 417.820788 -364.284591)
			(xy 417.792118 -364.28949) (xy 417.765988 -364.302264) (xy 417.744512 -364.321878) (xy 417.736528 -364.334044)
			(xy 417.721959 -364.357175) (xy 417.687116 -364.399296) (xy 417.646493 -364.435875) (xy 417.600962 -364.466126)
			(xy 417.5515 -364.489402) (xy 417.499169 -364.505202) (xy 417.44509 -364.513188) (xy 417.390426 -364.513188)
			(xy 417.336347 -364.505202) (xy 417.284016 -364.489402) (xy 417.234554 -364.466126) (xy 417.189023 -364.435875)
			(xy 417.1484 -364.399296) (xy 417.113557 -364.357175) (xy 417.098988 -364.334044) (xy 417.091043 -364.321834)
			(xy 417.06958 -364.302158) (xy 417.043432 -364.289349) (xy 417.014731 -364.28445) (xy 416.985814 -364.287862)
			(xy 416.972242 -364.29315) (xy 416.949037 -364.302652) (xy 416.900702 -364.315998) (xy 416.85101 -364.322721)
			(xy 416.825938 -364.323122) (xy 416.79805 -364.322622) (xy 416.742895 -364.314314) (xy 416.689595 -364.297878)
			(xy 416.639341 -364.273681) (xy 416.593254 -364.242264) (xy 416.552365 -364.204328) (xy 416.517587 -364.160722)
			(xy 416.489697 -364.112419) (xy 416.469318 -364.060499) (xy 416.456906 -364.006121) (xy 416.452737 -363.9505)
			(xy 396.30617 -363.9505) (xy 395.240336 -365.016288) (xy 412.995108 -365.016288) (xy 412.999179 -364.960666)
			(xy 413.011305 -364.906229) (xy 413.031228 -364.854138) (xy 413.058524 -364.805503) (xy 413.09261 -364.76136)
			(xy 413.132759 -364.722651) (xy 413.178117 -364.6902) (xy 413.227717 -364.664699) (xy 413.280501 -364.646692)
			(xy 413.335344 -364.636562) (xy 413.391078 -364.634525) (xy 413.446515 -364.640625) (xy 413.500472 -364.654731)
			(xy 413.551801 -364.676543) (xy 413.599407 -364.705597) (xy 413.642275 -364.741272) (xy 413.679492 -364.782809)
			(xy 413.710265 -364.829322) (xy 413.733937 -364.879819) (xy 413.750005 -364.933226) (xy 413.758125 -364.988402)
			(xy 413.758634 -365.016288) (xy 413.758125 -365.044174) (xy 413.750005 -365.09935) (xy 413.733937 -365.152757)
			(xy 413.710265 -365.203254) (xy 413.679492 -365.249767) (xy 413.642275 -365.291304) (xy 413.599407 -365.326979)
			(xy 413.551801 -365.356033) (xy 413.500472 -365.377845) (xy 413.446515 -365.391951) (xy 413.391078 -365.398051)
			(xy 413.335344 -365.396014) (xy 413.280501 -365.385884) (xy 413.227717 -365.367877) (xy 413.178117 -365.342376)
			(xy 413.132759 -365.309925) (xy 413.09261 -365.271216) (xy 413.058524 -365.227073) (xy 413.031228 -365.178438)
			(xy 413.011305 -365.126347) (xy 412.999179 -365.07191) (xy 412.995108 -365.016288) (xy 395.240336 -365.016288)
			(xy 394.287794 -365.968788) (xy 410.390592 -365.968788) (xy 410.394663 -365.913166) (xy 410.406789 -365.858729)
			(xy 410.426712 -365.806638) (xy 410.454008 -365.758003) (xy 410.488094 -365.71386) (xy 410.528243 -365.675151)
			(xy 410.573601 -365.6427) (xy 410.623201 -365.617199) (xy 410.675985 -365.599192) (xy 410.730828 -365.589062)
			(xy 410.786562 -365.587025) (xy 410.841999 -365.593125) (xy 410.895956 -365.607231) (xy 410.947285 -365.629043)
			(xy 410.994891 -365.658097) (xy 411.037759 -365.693772) (xy 411.074976 -365.735309) (xy 411.105749 -365.781822)
			(xy 411.129421 -365.832319) (xy 411.145489 -365.885726) (xy 411.153609 -365.940902) (xy 411.154118 -365.968788)
			(xy 411.153872 -365.98225) (xy 412.330644 -365.98225) (xy 412.334715 -365.926628) (xy 412.346841 -365.872191)
			(xy 412.366764 -365.8201) (xy 412.39406 -365.771465) (xy 412.428146 -365.727322) (xy 412.468295 -365.688613)
			(xy 412.513653 -365.656162) (xy 412.563253 -365.630661) (xy 412.616037 -365.612654) (xy 412.67088 -365.602524)
			(xy 412.726614 -365.600487) (xy 412.782051 -365.606587) (xy 412.836008 -365.620693) (xy 412.887337 -365.642505)
			(xy 412.934943 -365.671559) (xy 412.977811 -365.707234) (xy 413.015028 -365.748771) (xy 413.045801 -365.795284)
			(xy 413.069473 -365.845781) (xy 413.085541 -365.899188) (xy 413.093661 -365.954364) (xy 413.09417 -365.98225)
			(xy 413.093661 -366.010136) (xy 413.085541 -366.065312) (xy 413.069473 -366.118719) (xy 413.045801 -366.169216)
			(xy 413.015028 -366.215729) (xy 412.977811 -366.257266) (xy 412.934943 -366.292941) (xy 412.887337 -366.321995)
			(xy 412.836008 -366.343807) (xy 412.782051 -366.357913) (xy 412.726614 -366.364013) (xy 412.67088 -366.361976)
			(xy 412.616037 -366.351846) (xy 412.563253 -366.333839) (xy 412.513653 -366.308338) (xy 412.468295 -366.275887)
			(xy 412.428146 -366.237178) (xy 412.39406 -366.193035) (xy 412.366764 -366.1444) (xy 412.346841 -366.092309)
			(xy 412.334715 -366.037872) (xy 412.330644 -365.98225) (xy 411.153872 -365.98225) (xy 411.153609 -365.996674)
			(xy 411.145489 -366.05185) (xy 411.129421 -366.105257) (xy 411.105749 -366.155754) (xy 411.074976 -366.202267)
			(xy 411.037759 -366.243804) (xy 410.994891 -366.279479) (xy 410.947285 -366.308533) (xy 410.895956 -366.330345)
			(xy 410.841999 -366.344451) (xy 410.786562 -366.350551) (xy 410.730828 -366.348514) (xy 410.675985 -366.338384)
			(xy 410.623201 -366.320377) (xy 410.573601 -366.294876) (xy 410.528243 -366.262425) (xy 410.488094 -366.223716)
			(xy 410.454008 -366.179573) (xy 410.426712 -366.130938) (xy 410.406789 -366.078847) (xy 410.394663 -366.02441)
			(xy 410.390592 -365.968788) (xy 394.287794 -365.968788) (xy 393.711697 -366.54486) (xy 413.801814 -366.54486)
			(xy 413.802256 -366.518544) (xy 413.809478 -366.466409) (xy 413.823793 -366.41576) (xy 413.844929 -366.367558)
			(xy 413.872487 -366.322717) (xy 413.905943 -366.282086) (xy 413.925004 -366.263936) (xy 413.935064 -366.254162)
			(xy 413.949759 -366.230278) (xy 413.957391 -366.203294) (xy 413.957384 -366.175252) (xy 413.949737 -366.148272)
			(xy 413.935029 -366.124396) (xy 413.925004 -366.114584) (xy 413.905918 -366.096456) (xy 413.87244 -366.055834)
			(xy 413.84487 -366.010993) (xy 413.823733 -365.962784) (xy 413.80943 -365.912125) (xy 413.802234 -365.85998)
			(xy 413.801814 -365.83366) (xy 413.8023 -365.806409) (xy 413.810056 -365.752461) (xy 413.825411 -365.700166)
			(xy 413.848053 -365.650589) (xy 413.877519 -365.604739) (xy 413.91321 -365.563548) (xy 413.954401 -365.527857)
			(xy 414.000251 -365.498391) (xy 414.049828 -365.475749) (xy 414.102123 -365.460394) (xy 414.156071 -365.452638)
			(xy 414.210573 -365.452638) (xy 414.264521 -365.460394) (xy 414.316816 -365.475749) (xy 414.366393 -365.498391)
			(xy 414.412243 -365.527857) (xy 414.453434 -365.563548) (xy 414.489125 -365.604739) (xy 414.518591 -365.650589)
			(xy 414.541233 -365.700166) (xy 414.556588 -365.752461) (xy 414.564344 -365.806409) (xy 414.56483 -365.83366)
			(xy 414.564387 -365.859976) (xy 414.557164 -365.91211) (xy 414.542848 -365.962758) (xy 414.521711 -366.01096)
			(xy 414.494155 -366.055802) (xy 414.4607 -366.096434) (xy 414.44164 -366.114584) (xy 414.431657 -366.124432)
			(xy 414.416951 -366.148293) (xy 414.409305 -366.175259) (xy 414.409298 -366.203287) (xy 414.416929 -366.230257)
			(xy 414.431622 -366.254126) (xy 414.44164 -366.263936) (xy 414.460725 -366.282065) (xy 414.494205 -366.322685)
			(xy 414.521776 -366.367527) (xy 414.542914 -366.415735) (xy 414.557217 -366.466394) (xy 414.564259 -366.517428)
			(xy 414.817304 -366.517428) (xy 414.821375 -366.461806) (xy 414.833501 -366.407369) (xy 414.853424 -366.355278)
			(xy 414.88072 -366.306643) (xy 414.914806 -366.2625) (xy 414.954955 -366.223791) (xy 415.000313 -366.19134)
			(xy 415.049913 -366.165839) (xy 415.102697 -366.147832) (xy 415.15754 -366.137702) (xy 415.213274 -366.135665)
			(xy 415.268711 -366.141765) (xy 415.322668 -366.155871) (xy 415.373997 -366.177683) (xy 415.421603 -366.206737)
			(xy 415.464471 -366.242412) (xy 415.501688 -366.283949) (xy 415.532461 -366.330462) (xy 415.556133 -366.380959)
			(xy 415.572201 -366.434366) (xy 415.580321 -366.489542) (xy 415.58083 -366.517428) (xy 415.580321 -366.545314)
			(xy 415.572201 -366.60049) (xy 415.556133 -366.653897) (xy 415.532461 -366.704394) (xy 415.501688 -366.750907)
			(xy 415.464471 -366.792444) (xy 415.421603 -366.828119) (xy 415.373997 -366.857173) (xy 415.322668 -366.878985)
			(xy 415.268711 -366.893091) (xy 415.213274 -366.899191) (xy 415.15754 -366.897154) (xy 415.102697 -366.887024)
			(xy 415.049913 -366.869017) (xy 415.000313 -366.843516) (xy 414.954955 -366.811065) (xy 414.914806 -366.772356)
			(xy 414.88072 -366.728213) (xy 414.853424 -366.679578) (xy 414.833501 -366.627487) (xy 414.821375 -366.57305)
			(xy 414.817304 -366.517428) (xy 414.564259 -366.517428) (xy 414.564412 -366.51854) (xy 414.56483 -366.54486)
			(xy 414.564344 -366.572111) (xy 414.556588 -366.626059) (xy 414.541233 -366.678354) (xy 414.518591 -366.727931)
			(xy 414.489125 -366.773781) (xy 414.453434 -366.814972) (xy 414.412243 -366.850663) (xy 414.366393 -366.880129)
			(xy 414.316816 -366.902771) (xy 414.264521 -366.918126) (xy 414.210573 -366.925882) (xy 414.156071 -366.925882)
			(xy 414.102123 -366.918126) (xy 414.049828 -366.902771) (xy 414.000251 -366.880129) (xy 413.954401 -366.850663)
			(xy 413.91321 -366.814972) (xy 413.877519 -366.773781) (xy 413.848053 -366.727931) (xy 413.825411 -366.678354)
			(xy 413.810056 -366.626059) (xy 413.8023 -366.572111) (xy 413.801814 -366.54486) (xy 393.711697 -366.54486)
			(xy 393.421362 -366.835182) (xy 393.400468 -366.85547) (xy 393.354267 -366.89093) (xy 393.303832 -366.920055)
			(xy 393.250027 -366.942346) (xy 393.193772 -366.957423) (xy 393.13603 -366.965027) (xy 393.10691 -366.965484)
			(xy 384.900678 -366.965484) (xy 384.871557 -366.965034) (xy 384.813814 -366.957436) (xy 384.757559 -366.94236)
			(xy 384.703754 -366.920065) (xy 384.653324 -366.890931) (xy 384.607131 -366.85546) (xy 384.586226 -366.835182)
			(xy 382.032764 -364.28172) (xy 369.2398 -364.28172) (xy 369.21068 -364.281245) (xy 369.152939 -364.273651)
			(xy 369.096684 -364.258579) (xy 369.04288 -364.236288) (xy 368.992448 -364.20716) (xy 368.946254 -364.171694)
			(xy 368.925348 -364.151418) (xy 366.235996 -361.462066) (xy 366.215701 -361.441166) (xy 366.180186 -361.394986)
			(xy 366.151009 -361.344562) (xy 366.128669 -361.290758) (xy 366.11355 -361.234497) (xy 366.105911 -361.176742)
			(xy 366.10544 -361.147614) (xy 360.727046 -361.147614) (xy 360.733368 -361.15488) (xy 360.759331 -361.17096)
			(xy 360.77398 -361.1753) (xy 360.800847 -361.182862) (xy 360.85222 -361.204671) (xy 360.89987 -361.23373)
			(xy 360.942778 -361.269419) (xy 360.980031 -361.310978) (xy 361.010834 -361.357519) (xy 361.034529 -361.40805)
			(xy 361.050611 -361.461494) (xy 361.058738 -361.51671) (xy 361.059222 -361.544616) (xy 361.058737 -361.571867)
			(xy 361.050979 -361.625814) (xy 361.035622 -361.678108) (xy 361.01298 -361.727684) (xy 360.983514 -361.773534)
			(xy 360.947822 -361.814724) (xy 360.906632 -361.850415) (xy 360.860783 -361.879881) (xy 360.811206 -361.902523)
			(xy 360.758912 -361.917879) (xy 360.704965 -361.925637) (xy 360.677714 -361.926124) (xy 360.649811 -361.925604)
			(xy 360.594601 -361.917467) (xy 360.541164 -361.901381) (xy 360.490638 -361.877686) (xy 360.444099 -361.846889)
			(xy 360.402539 -361.809644) (xy 360.366844 -361.766747) (xy 360.337774 -361.71911) (xy 360.315949 -361.667749)
			(xy 360.308398 -361.640882) (xy 360.303992 -361.626271) (xy 360.287885 -361.600369) (xy 360.264853 -361.580373)
			(xy 360.236946 -361.568062) (xy 360.206649 -361.564532) (xy 360.17666 -361.570098) (xy 360.149648 -361.584264)
			(xy 360.138472 -361.594654) (xy 359.727246 -362.00588) (xy 359.717062 -362.01685) (xy 359.702974 -362.043242)
			(xy 359.697141 -362.072586) (xy 359.700066 -362.102359) (xy 359.711497 -362.130007) (xy 359.730452 -362.153153)
			(xy 359.755304 -362.169809) (xy 359.783917 -362.178546) (xy 359.798874 -362.179108) (xy 361.542076 -362.179108)
			(xy 361.64901 -362.072428) (xy 361.667112 -362.055179) (xy 361.708654 -362.027366) (xy 361.754823 -362.008191)
			(xy 361.803846 -361.99839) (xy 361.828842 -361.997752) (xy 362.44149 -361.997752) (xy 362.466486 -361.998386)
			(xy 362.515509 -362.008189) (xy 362.56168 -362.027364) (xy 362.603226 -362.055172) (xy 362.621322 -362.072428)
			(xy 363.043216 -362.494322) (xy 363.051973 -362.503271) (xy 363.067877 -362.52261) (xy 363.074966 -362.53293)
			(xy 363.399663 -363.018832) (xy 363.790482 -363.018832) (xy 363.794553 -362.96321) (xy 363.806679 -362.908773)
			(xy 363.826602 -362.856682) (xy 363.853898 -362.808047) (xy 363.887984 -362.763904) (xy 363.928133 -362.725195)
			(xy 363.973491 -362.692744) (xy 364.023091 -362.667243) (xy 364.075875 -362.649236) (xy 364.130718 -362.639106)
			(xy 364.186452 -362.637069) (xy 364.241889 -362.643169) (xy 364.295846 -362.657275) (xy 364.347175 -362.679087)
			(xy 364.394781 -362.708141) (xy 364.437649 -362.743816) (xy 364.474866 -362.785353) (xy 364.505639 -362.831866)
			(xy 364.529311 -362.882363) (xy 364.545379 -362.93577) (xy 364.553499 -362.990946) (xy 364.554008 -363.018832)
			(xy 364.553499 -363.046718) (xy 364.545379 -363.101894) (xy 364.529311 -363.155301) (xy 364.505639 -363.205798)
			(xy 364.474866 -363.252311) (xy 364.437649 -363.293848) (xy 364.394781 -363.329523) (xy 364.347175 -363.358577)
			(xy 364.295846 -363.380389) (xy 364.241889 -363.394495) (xy 364.186452 -363.400595) (xy 364.130718 -363.398558)
			(xy 364.075875 -363.388428) (xy 364.023091 -363.370421) (xy 363.973491 -363.34492) (xy 363.928133 -363.312469)
			(xy 363.887984 -363.27376) (xy 363.853898 -363.229617) (xy 363.826602 -363.180982) (xy 363.806679 -363.128891)
			(xy 363.794553 -363.074454) (xy 363.790482 -363.018832) (xy 363.399663 -363.018832) (xy 363.868462 -363.72038)
			(xy 363.881827 -363.741491) (xy 363.900965 -363.787637) (xy 363.91075 -363.836626) (xy 363.911388 -363.861604)
			(xy 363.911388 -363.886496) (xy 366.311686 -363.886496) (xy 366.315757 -363.830874) (xy 366.327883 -363.776437)
			(xy 366.347806 -363.724346) (xy 366.375102 -363.675711) (xy 366.409188 -363.631568) (xy 366.449337 -363.592859)
			(xy 366.494695 -363.560408) (xy 366.544295 -363.534907) (xy 366.597079 -363.5169) (xy 366.651922 -363.50677)
			(xy 366.707656 -363.504733) (xy 366.763093 -363.510833) (xy 366.81705 -363.524939) (xy 366.868379 -363.546751)
			(xy 366.915985 -363.575805) (xy 366.958853 -363.61148) (xy 366.99607 -363.653017) (xy 367.026843 -363.69953)
			(xy 367.050515 -363.750027) (xy 367.066583 -363.803434) (xy 367.074703 -363.85861) (xy 367.075212 -363.886496)
			(xy 367.074703 -363.914382) (xy 367.066583 -363.969558) (xy 367.050515 -364.022965) (xy 367.026843 -364.073462)
			(xy 366.99607 -364.119975) (xy 366.958853 -364.161512) (xy 366.915985 -364.197187) (xy 366.868379 -364.226241)
			(xy 366.81705 -364.248053) (xy 366.763093 -364.262159) (xy 366.707656 -364.268259) (xy 366.651922 -364.266222)
			(xy 366.597079 -364.256092) (xy 366.544295 -364.238085) (xy 366.494695 -364.212584) (xy 366.449337 -364.180133)
			(xy 366.409188 -364.141424) (xy 366.375102 -364.097281) (xy 366.347806 -364.048646) (xy 366.327883 -363.996555)
			(xy 366.315757 -363.942118) (xy 366.311686 -363.886496) (xy 363.911388 -363.886496) (xy 363.911388 -364.678722)
			(xy 364.211196 -364.978696) (xy 365.31245 -364.978696) (xy 365.316521 -364.923074) (xy 365.328647 -364.868637)
			(xy 365.34857 -364.816546) (xy 365.375866 -364.767911) (xy 365.409952 -364.723768) (xy 365.450101 -364.685059)
			(xy 365.495459 -364.652608) (xy 365.545059 -364.627107) (xy 365.597843 -364.6091) (xy 365.652686 -364.59897)
			(xy 365.70842 -364.596933) (xy 365.763857 -364.603033) (xy 365.817814 -364.617139) (xy 365.869143 -364.638951)
			(xy 365.916749 -364.668005) (xy 365.959617 -364.70368) (xy 365.996834 -364.745217) (xy 366.027607 -364.79173)
			(xy 366.051279 -364.842227) (xy 366.067347 -364.895634) (xy 366.075467 -364.95081) (xy 366.075976 -364.978696)
			(xy 366.075467 -365.006582) (xy 366.067347 -365.061758) (xy 366.051279 -365.115165) (xy 366.027607 -365.165662)
			(xy 365.996834 -365.212175) (xy 365.959617 -365.253712) (xy 365.916749 -365.289387) (xy 365.869143 -365.318441)
			(xy 365.817814 -365.340253) (xy 365.763857 -365.354359) (xy 365.70842 -365.360459) (xy 365.652686 -365.358422)
			(xy 365.597843 -365.348292) (xy 365.545059 -365.330285) (xy 365.495459 -365.304784) (xy 365.450101 -365.272333)
			(xy 365.409952 -365.233624) (xy 365.375866 -365.189481) (xy 365.34857 -365.140846) (xy 365.328647 -365.088755)
			(xy 365.316521 -365.034318) (xy 365.31245 -364.978696) (xy 364.211196 -364.978696) (xy 364.370112 -365.1377)
			(xy 364.387363 -365.1558) (xy 364.415174 -365.197344) (xy 364.434348 -365.243513) (xy 364.44415 -365.292536)
			(xy 364.444788 -365.317532) (xy 364.444788 -365.64062) (xy 380.886211 -365.64062) (xy 380.890247 -365.557173)
			(xy 380.902319 -365.474505) (xy 380.922312 -365.393388) (xy 380.950041 -365.314579) (xy 380.985247 -365.238814)
			(xy 381.027601 -365.166801) (xy 381.076707 -365.099212) (xy 381.132108 -365.036678) (xy 381.193285 -364.979783)
			(xy 381.259668 -364.929057) (xy 381.330636 -364.884976) (xy 381.405528 -364.84795) (xy 381.483644 -364.818324)
			(xy 381.564254 -364.796376) (xy 381.646606 -364.782311) (xy 381.729932 -364.776259) (xy 381.813452 -364.778278)
			(xy 381.896388 -364.788348) (xy 381.977964 -364.806376) (xy 382.05742 -364.832193) (xy 382.134013 -364.865558)
			(xy 382.207029 -364.906159) (xy 382.275785 -364.953618) (xy 382.339639 -365.007491) (xy 382.397996 -365.067276)
			(xy 382.450311 -365.132413) (xy 382.496094 -365.202296) (xy 382.534919 -365.276271) (xy 382.566424 -365.353648)
			(xy 382.590313 -365.433705) (xy 382.606364 -365.515693) (xy 382.614427 -365.598848) (xy 382.614932 -365.64062)
			(xy 382.614427 -365.682392) (xy 382.606364 -365.765547) (xy 382.590313 -365.847535) (xy 382.566424 -365.927592)
			(xy 382.534919 -366.004969) (xy 382.496094 -366.078944) (xy 382.450311 -366.148827) (xy 382.397996 -366.213964)
			(xy 382.339639 -366.273749) (xy 382.275785 -366.327622) (xy 382.207029 -366.375081) (xy 382.134013 -366.415682)
			(xy 382.05742 -366.449047) (xy 381.977964 -366.474864) (xy 381.896388 -366.492892) (xy 381.813452 -366.502962)
			(xy 381.729932 -366.504981) (xy 381.646606 -366.498929) (xy 381.564254 -366.484864) (xy 381.483644 -366.462916)
			(xy 381.405528 -366.43329) (xy 381.330636 -366.396264) (xy 381.259668 -366.352183) (xy 381.193285 -366.301457)
			(xy 381.132108 -366.244562) (xy 381.076707 -366.182028) (xy 381.027601 -366.114439) (xy 380.985247 -366.042426)
			(xy 380.950041 -365.966661) (xy 380.922312 -365.887852) (xy 380.902319 -365.806735) (xy 380.890247 -365.724067)
			(xy 380.886211 -365.64062) (xy 364.444788 -365.64062) (xy 364.444788 -366.337342) (xy 365.883659 -367.776252)
			(xy 369.189506 -367.776252) (xy 369.193577 -367.72063) (xy 369.205703 -367.666193) (xy 369.225626 -367.614102)
			(xy 369.252922 -367.565467) (xy 369.287008 -367.521324) (xy 369.327157 -367.482615) (xy 369.372515 -367.450164)
			(xy 369.422115 -367.424663) (xy 369.474899 -367.406656) (xy 369.529742 -367.396526) (xy 369.585476 -367.394489)
			(xy 369.640913 -367.400589) (xy 369.69487 -367.414695) (xy 369.746199 -367.436507) (xy 369.793805 -367.465561)
			(xy 369.836673 -367.501236) (xy 369.87389 -367.542773) (xy 369.904663 -367.589286) (xy 369.928335 -367.639783)
			(xy 369.944403 -367.69319) (xy 369.952523 -367.748366) (xy 369.953032 -367.776252) (xy 369.952523 -367.804138)
			(xy 369.944403 -367.859314) (xy 369.928335 -367.912721) (xy 369.905269 -367.961926) (xy 370.232686 -367.961926)
			(xy 370.23319 -367.933008) (xy 370.241918 -367.875835) (xy 370.259176 -367.820634) (xy 370.28457 -367.768672)
			(xy 370.317518 -367.721139) (xy 370.357264 -367.679124) (xy 370.379752 -367.660936) (xy 370.391535 -367.651012)
			(xy 370.409059 -367.625697) (xy 370.418241 -367.59631) (xy 370.418245 -367.565522) (xy 370.409073 -367.536131)
			(xy 370.391557 -367.510811) (xy 370.379752 -367.500916) (xy 370.357266 -367.482728) (xy 370.317533 -367.440706)
			(xy 370.284596 -367.39317) (xy 370.259208 -367.341209) (xy 370.241952 -367.286011) (xy 370.233222 -367.228842)
			(xy 370.232686 -367.199926) (xy 370.233172 -367.172675) (xy 370.240928 -367.118727) (xy 370.256283 -367.066432)
			(xy 370.278925 -367.016855) (xy 370.308391 -366.971005) (xy 370.344082 -366.929814) (xy 370.385273 -366.894123)
			(xy 370.431123 -366.864657) (xy 370.4807 -366.842015) (xy 370.532995 -366.82666) (xy 370.586943 -366.818904)
			(xy 370.641445 -366.818904) (xy 370.695393 -366.82666) (xy 370.747688 -366.842015) (xy 370.797265 -366.864657)
			(xy 370.843115 -366.894123) (xy 370.884306 -366.929814) (xy 370.919997 -366.971005) (xy 370.949463 -367.016855)
			(xy 370.972105 -367.066432) (xy 370.98746 -367.118727) (xy 370.995216 -367.172675) (xy 370.995702 -367.199926)
			(xy 370.99513 -367.228841) (xy 370.986412 -367.28601) (xy 370.969165 -367.341207) (xy 370.943783 -367.393169)
			(xy 370.910849 -367.440705) (xy 370.871117 -367.482724) (xy 370.848636 -367.500916) (xy 370.836802 -367.510784)
			(xy 370.819281 -367.536114) (xy 370.810106 -367.565516) (xy 370.810111 -367.596316) (xy 370.819295 -367.625715)
			(xy 370.836825 -367.65104) (xy 370.848636 -367.660936) (xy 370.871144 -367.679098) (xy 370.910876 -367.721125)
			(xy 370.943811 -367.768666) (xy 370.969195 -367.820633) (xy 370.986446 -367.875835) (xy 370.99517 -367.933008)
			(xy 370.995702 -367.961926) (xy 372.38051 -367.961926) (xy 372.381043 -367.93301) (xy 372.389769 -367.875839)
			(xy 372.407023 -367.82064) (xy 372.432412 -367.768678) (xy 372.465353 -367.721144) (xy 372.505092 -367.679127)
			(xy 372.527576 -367.660936) (xy 372.539356 -367.651011) (xy 372.556876 -367.625695) (xy 372.566056 -367.596309)
			(xy 372.56606 -367.565523) (xy 372.55689 -367.536134) (xy 372.539378 -367.510813) (xy 372.527576 -367.500916)
			(xy 372.505095 -367.482722) (xy 372.465361 -367.440702) (xy 372.432422 -367.393168) (xy 372.407034 -367.341207)
			(xy 372.389777 -367.28601) (xy 372.381046 -367.228842) (xy 372.38051 -367.199926) (xy 372.380996 -367.172675)
			(xy 372.388752 -367.118727) (xy 372.404107 -367.066432) (xy 372.426749 -367.016855) (xy 372.456215 -366.971005)
			(xy 372.491906 -366.929814) (xy 372.533097 -366.894123) (xy 372.578947 -366.864657) (xy 372.628524 -366.842015)
			(xy 372.680819 -366.82666) (xy 372.734767 -366.818904) (xy 372.789269 -366.818904) (xy 372.843217 -366.82666)
			(xy 372.895512 -366.842015) (xy 372.945089 -366.864657) (xy 372.990939 -366.894123) (xy 373.03213 -366.929814)
			(xy 373.067821 -366.971005) (xy 373.097287 -367.016855) (xy 373.119929 -367.066432) (xy 373.135284 -367.118727)
			(xy 373.14304 -367.172675) (xy 373.143526 -367.199926) (xy 373.142982 -367.228842) (xy 373.134263 -367.286014)
			(xy 373.117011 -367.341213) (xy 373.091625 -367.393176) (xy 373.058684 -367.44071) (xy 373.018945 -367.482726)
			(xy 372.99646 -367.500916) (xy 372.984624 -367.510783) (xy 372.967099 -367.536112) (xy 372.957922 -367.565515)
			(xy 372.957926 -367.596317) (xy 372.967113 -367.625716) (xy 372.984647 -367.651041) (xy 372.99646 -367.660936)
			(xy 373.018952 -367.679117) (xy 373.058689 -367.721137) (xy 373.091628 -367.768674) (xy 373.117015 -367.820638)
			(xy 373.134269 -367.875838) (xy 373.142994 -367.933009) (xy 373.143526 -367.961926) (xy 374.51411 -367.961926)
			(xy 374.514643 -367.93301) (xy 374.523369 -367.875839) (xy 374.540623 -367.82064) (xy 374.566012 -367.768678)
			(xy 374.598953 -367.721144) (xy 374.638692 -367.679127) (xy 374.661176 -367.660936) (xy 374.672956 -367.651011)
			(xy 374.690476 -367.625695) (xy 374.699656 -367.596309) (xy 374.69966 -367.565523) (xy 374.69049 -367.536134)
			(xy 374.672978 -367.510813) (xy 374.661176 -367.500916) (xy 374.638695 -367.482722) (xy 374.598961 -367.440702)
			(xy 374.566022 -367.393168) (xy 374.540634 -367.341207) (xy 374.523377 -367.28601) (xy 374.514646 -367.228842)
			(xy 374.51411 -367.199926) (xy 374.514596 -367.172675) (xy 374.522352 -367.118727) (xy 374.537707 -367.066432)
			(xy 374.560349 -367.016855) (xy 374.589815 -366.971005) (xy 374.625506 -366.929814) (xy 374.666697 -366.894123)
			(xy 374.712547 -366.864657) (xy 374.762124 -366.842015) (xy 374.814419 -366.82666) (xy 374.868367 -366.818904)
			(xy 374.922869 -366.818904) (xy 374.976817 -366.82666) (xy 375.029112 -366.842015) (xy 375.078689 -366.864657)
			(xy 375.124539 -366.894123) (xy 375.16573 -366.929814) (xy 375.201421 -366.971005) (xy 375.230887 -367.016855)
			(xy 375.253529 -367.066432) (xy 375.268884 -367.118727) (xy 375.27664 -367.172675) (xy 375.277126 -367.199926)
			(xy 375.276582 -367.228842) (xy 375.267863 -367.286014) (xy 375.250611 -367.341213) (xy 375.225225 -367.393176)
			(xy 375.192284 -367.44071) (xy 375.152545 -367.482726) (xy 375.13006 -367.500916) (xy 375.118224 -367.510783)
			(xy 375.100699 -367.536112) (xy 375.091522 -367.565515) (xy 375.091526 -367.596317) (xy 375.100713 -367.625716)
			(xy 375.118247 -367.651041) (xy 375.13006 -367.660936) (xy 375.152552 -367.679117) (xy 375.192289 -367.721137)
			(xy 375.225228 -367.768674) (xy 375.250615 -367.820638) (xy 375.267869 -367.875838) (xy 375.276594 -367.933009)
			(xy 375.276603 -367.933478) (xy 376.66676 -367.933478) (xy 376.667312 -367.904562) (xy 376.676031 -367.847391)
			(xy 376.693281 -367.792192) (xy 376.718666 -367.74023) (xy 376.751605 -367.692695) (xy 376.791342 -367.650678)
			(xy 376.813826 -367.632488) (xy 376.825649 -367.622612) (xy 376.84316 -367.597281) (xy 376.852329 -367.567884)
			(xy 376.852325 -367.537089) (xy 376.843148 -367.507694) (xy 376.825631 -367.482368) (xy 376.813826 -367.472468)
			(xy 376.791333 -367.454288) (xy 376.751597 -367.412267) (xy 376.718658 -367.36473) (xy 376.693271 -367.312766)
			(xy 376.676018 -367.257566) (xy 376.667293 -367.200395) (xy 376.66676 -367.171478) (xy 376.667246 -367.144227)
			(xy 376.675002 -367.090279) (xy 376.690357 -367.037984) (xy 376.712999 -366.988407) (xy 376.742465 -366.942557)
			(xy 376.778156 -366.901366) (xy 376.819347 -366.865675) (xy 376.865197 -366.836209) (xy 376.914774 -366.813567)
			(xy 376.967069 -366.798212) (xy 377.021017 -366.790456) (xy 377.075519 -366.790456) (xy 377.129467 -366.798212)
			(xy 377.181762 -366.813567) (xy 377.231339 -366.836209) (xy 377.277189 -366.865675) (xy 377.31838 -366.901366)
			(xy 377.354071 -366.942557) (xy 377.383537 -366.988407) (xy 377.406179 -367.037984) (xy 377.421534 -367.090279)
			(xy 377.42929 -367.144227) (xy 377.429776 -367.171478) (xy 377.429251 -367.200395) (xy 377.420525 -367.257566)
			(xy 377.403269 -367.312765) (xy 377.377878 -367.364727) (xy 377.344935 -367.412261) (xy 377.305195 -367.454278)
			(xy 377.28271 -367.472468) (xy 377.270927 -367.48239) (xy 377.25341 -367.507707) (xy 377.244232 -367.537093)
			(xy 377.244228 -367.56788) (xy 377.253398 -367.597269) (xy 377.270909 -367.62259) (xy 377.28271 -367.632488)
			(xy 377.30519 -367.650683) (xy 377.344925 -367.692702) (xy 377.377864 -367.740237) (xy 377.403253 -367.792197)
			(xy 377.42051 -367.847394) (xy 377.42924 -367.904562) (xy 377.429776 -367.933478) (xy 377.42929 -367.960729)
			(xy 377.421534 -368.014677) (xy 377.406179 -368.066972) (xy 377.383537 -368.116549) (xy 377.354071 -368.162399)
			(xy 377.336143 -368.18309) (xy 380.86182 -368.18309) (xy 380.86182 -368.098394) (xy 380.869871 -368.01408)
			(xy 380.8859 -367.930914) (xy 380.909761 -367.849647) (xy 380.94124 -367.771017) (xy 380.980051 -367.695736)
			(xy 381.025841 -367.624484) (xy 381.078197 -367.557908) (xy 381.136645 -367.49661) (xy 381.200655 -367.441145)
			(xy 381.269647 -367.392016) (xy 381.342997 -367.349667) (xy 381.42004 -367.314483) (xy 381.500079 -367.286781)
			(xy 381.582388 -367.266813) (xy 381.666223 -367.25476) (xy 381.750824 -367.25073) (xy 381.835425 -367.25476)
			(xy 381.91926 -367.266813) (xy 382.001569 -367.286781) (xy 382.081608 -367.314483) (xy 382.158651 -367.349667)
			(xy 382.232001 -367.392016) (xy 382.300993 -367.441145) (xy 382.365003 -367.49661) (xy 382.423451 -367.557908)
			(xy 382.475807 -367.624484) (xy 382.521597 -367.695736) (xy 382.560408 -367.771017) (xy 382.591887 -367.849647)
			(xy 382.615748 -367.930914) (xy 382.631777 -368.01408) (xy 382.639828 -368.098394) (xy 382.640332 -368.140742)
			(xy 382.639828 -368.18309) (xy 382.631777 -368.267404) (xy 382.615748 -368.35057) (xy 382.591887 -368.431837)
			(xy 382.560408 -368.510467) (xy 382.521597 -368.585748) (xy 382.475807 -368.657) (xy 382.423451 -368.723576)
			(xy 382.365003 -368.784874) (xy 382.300993 -368.840339) (xy 382.232001 -368.889468) (xy 382.158651 -368.931817)
			(xy 382.081608 -368.967001) (xy 382.001569 -368.994703) (xy 381.91926 -369.014671) (xy 381.835425 -369.026724)
			(xy 381.750824 -369.030755) (xy 381.666223 -369.026724) (xy 381.582388 -369.014671) (xy 381.500079 -368.994703)
			(xy 381.42004 -368.967001) (xy 381.342997 -368.931817) (xy 381.269647 -368.889468) (xy 381.200655 -368.840339)
			(xy 381.136645 -368.784874) (xy 381.078197 -368.723576) (xy 381.025841 -368.657) (xy 380.980051 -368.585748)
			(xy 380.94124 -368.510467) (xy 380.909761 -368.431837) (xy 380.8859 -368.35057) (xy 380.869871 -368.267404)
			(xy 380.86182 -368.18309) (xy 377.336143 -368.18309) (xy 377.31838 -368.20359) (xy 377.277189 -368.239281)
			(xy 377.231339 -368.268747) (xy 377.181762 -368.291389) (xy 377.129467 -368.306744) (xy 377.075519 -368.3145)
			(xy 377.021017 -368.3145) (xy 376.967069 -368.306744) (xy 376.914774 -368.291389) (xy 376.865197 -368.268747)
			(xy 376.819347 -368.239281) (xy 376.778156 -368.20359) (xy 376.742465 -368.162399) (xy 376.712999 -368.116549)
			(xy 376.690357 -368.066972) (xy 376.675002 -368.014677) (xy 376.667246 -367.960729) (xy 376.66676 -367.933478)
			(xy 375.276603 -367.933478) (xy 375.277126 -367.961926) (xy 375.27664 -367.989177) (xy 375.268884 -368.043125)
			(xy 375.253529 -368.09542) (xy 375.230887 -368.144997) (xy 375.201421 -368.190847) (xy 375.16573 -368.232038)
			(xy 375.124539 -368.267729) (xy 375.078689 -368.297195) (xy 375.029112 -368.319837) (xy 374.976817 -368.335192)
			(xy 374.922869 -368.342948) (xy 374.868367 -368.342948) (xy 374.814419 -368.335192) (xy 374.762124 -368.319837)
			(xy 374.712547 -368.297195) (xy 374.666697 -368.267729) (xy 374.625506 -368.232038) (xy 374.589815 -368.190847)
			(xy 374.560349 -368.144997) (xy 374.537707 -368.09542) (xy 374.522352 -368.043125) (xy 374.514596 -367.989177)
			(xy 374.51411 -367.961926) (xy 373.143526 -367.961926) (xy 373.14304 -367.989177) (xy 373.135284 -368.043125)
			(xy 373.119929 -368.09542) (xy 373.097287 -368.144997) (xy 373.067821 -368.190847) (xy 373.03213 -368.232038)
			(xy 372.990939 -368.267729) (xy 372.945089 -368.297195) (xy 372.895512 -368.319837) (xy 372.843217 -368.335192)
			(xy 372.789269 -368.342948) (xy 372.734767 -368.342948) (xy 372.680819 -368.335192) (xy 372.628524 -368.319837)
			(xy 372.578947 -368.297195) (xy 372.533097 -368.267729) (xy 372.491906 -368.232038) (xy 372.456215 -368.190847)
			(xy 372.426749 -368.144997) (xy 372.404107 -368.09542) (xy 372.388752 -368.043125) (xy 372.380996 -367.989177)
			(xy 372.38051 -367.961926) (xy 370.995702 -367.961926) (xy 370.995216 -367.989177) (xy 370.98746 -368.043125)
			(xy 370.972105 -368.09542) (xy 370.949463 -368.144997) (xy 370.919997 -368.190847) (xy 370.884306 -368.232038)
			(xy 370.843115 -368.267729) (xy 370.797265 -368.297195) (xy 370.747688 -368.319837) (xy 370.695393 -368.335192)
			(xy 370.641445 -368.342948) (xy 370.586943 -368.342948) (xy 370.532995 -368.335192) (xy 370.4807 -368.319837)
			(xy 370.431123 -368.297195) (xy 370.385273 -368.267729) (xy 370.344082 -368.232038) (xy 370.308391 -368.190847)
			(xy 370.278925 -368.144997) (xy 370.256283 -368.09542) (xy 370.240928 -368.043125) (xy 370.233172 -367.989177)
			(xy 370.232686 -367.961926) (xy 369.905269 -367.961926) (xy 369.904663 -367.963218) (xy 369.87389 -368.009731)
			(xy 369.836673 -368.051268) (xy 369.793805 -368.086943) (xy 369.746199 -368.115997) (xy 369.69487 -368.137809)
			(xy 369.640913 -368.151915) (xy 369.585476 -368.158015) (xy 369.529742 -368.155978) (xy 369.474899 -368.145848)
			(xy 369.422115 -368.127841) (xy 369.372515 -368.10234) (xy 369.327157 -368.069889) (xy 369.287008 -368.03118)
			(xy 369.252922 -367.987037) (xy 369.225626 -367.938402) (xy 369.205703 -367.886311) (xy 369.193577 -367.831874)
			(xy 369.189506 -367.776252) (xy 365.883659 -367.776252) (xy 373.79148 -375.684288) (xy 409.587954 -375.684288)
			(xy 410.515816 -374.756172) (xy 410.515816 -369.578128) (xy 410.516471 -369.553133) (xy 410.52627 -369.504111)
			(xy 410.545438 -369.457941) (xy 410.57324 -369.416393) (xy 410.590492 -369.398296) (xy 411.739588 -368.2492)
			(xy 411.757695 -368.231957) (xy 411.799236 -368.204144) (xy 411.845404 -368.184968) (xy 411.894425 -368.175164)
			(xy 411.91942 -368.174524) (xy 416.135566 -368.174524) (xy 416.500564 -367.80978) (xy 416.500564 -366.99952)
			(xy 416.273234 -366.77219) (xy 416.251898 -366.77219) (xy 416.22462 -366.771789) (xy 416.170613 -366.764089)
			(xy 416.118252 -366.748775) (xy 416.068607 -366.726158) (xy 416.022689 -366.696702) (xy 415.981435 -366.661005)
			(xy 415.945686 -366.619796) (xy 415.916172 -366.573915) (xy 415.893493 -366.524298) (xy 415.878113 -366.471957)
			(xy 415.870345 -366.417959) (xy 415.869882 -366.390682) (xy 415.870116 -366.372015) (xy 415.873808 -366.334863)
			(xy 415.877248 -366.316514) (xy 415.879613 -366.302249) (xy 415.877082 -366.273457) (xy 415.86658 -366.246528)
			(xy 415.848951 -366.223623) (xy 415.825608 -366.206579) (xy 415.798422 -366.196762) (xy 415.78403 -366.195356)
			(xy 415.755378 -366.192963) (xy 415.699213 -366.180679) (xy 415.645527 -366.160108) (xy 415.595534 -366.131715)
			(xy 415.550368 -366.096142) (xy 415.51105 -366.054196) (xy 415.478471 -366.006825) (xy 415.453368 -365.955102)
			(xy 415.43631 -365.900198) (xy 415.427682 -365.843356) (xy 415.42716 -365.81461) (xy 415.427646 -365.787359)
			(xy 415.435402 -365.733411) (xy 415.450757 -365.681116) (xy 415.473399 -365.631539) (xy 415.502865 -365.585689)
			(xy 415.538556 -365.544498) (xy 415.579747 -365.508807) (xy 415.625597 -365.479341) (xy 415.675174 -365.456699)
			(xy 415.727469 -365.441344) (xy 415.781417 -365.433588) (xy 415.835919 -365.433588) (xy 415.889867 -365.441344)
			(xy 415.942162 -365.456699) (xy 415.991739 -365.479341) (xy 416.037589 -365.508807) (xy 416.07878 -365.544498)
			(xy 416.114471 -365.585689) (xy 416.143937 -365.631539) (xy 416.166579 -365.681116) (xy 416.181934 -365.733411)
			(xy 416.18969 -365.787359) (xy 416.190176 -365.81461) (xy 416.189939 -365.833277) (xy 416.18625 -365.870429)
			(xy 416.18281 -365.888778) (xy 416.180493 -365.903048) (xy 416.183021 -365.931832) (xy 416.193516 -365.958754)
			(xy 416.211135 -365.981656) (xy 416.228289 -365.994188) (xy 422.018966 -365.994188) (xy 422.023037 -365.938566)
			(xy 422.035163 -365.884129) (xy 422.055086 -365.832038) (xy 422.082382 -365.783403) (xy 422.116468 -365.73926)
			(xy 422.156617 -365.700551) (xy 422.201975 -365.6681) (xy 422.251575 -365.642599) (xy 422.304359 -365.624592)
			(xy 422.359202 -365.614462) (xy 422.414936 -365.612425) (xy 422.470373 -365.618525) (xy 422.52433 -365.632631)
			(xy 422.575659 -365.654443) (xy 422.623265 -365.683497) (xy 422.666133 -365.719172) (xy 422.70335 -365.760709)
			(xy 422.734123 -365.807222) (xy 422.757795 -365.857719) (xy 422.773863 -365.911126) (xy 422.781983 -365.966302)
			(xy 422.782492 -365.994188) (xy 422.781983 -366.022074) (xy 422.773863 -366.07725) (xy 422.757795 -366.130657)
			(xy 422.734123 -366.181154) (xy 422.70335 -366.227667) (xy 422.666133 -366.269204) (xy 422.623265 -366.304879)
			(xy 422.575659 -366.333933) (xy 422.52433 -366.355745) (xy 422.470373 -366.369851) (xy 422.414936 -366.375951)
			(xy 422.359202 -366.373914) (xy 422.304359 -366.363784) (xy 422.251575 -366.345777) (xy 422.201975 -366.320276)
			(xy 422.156617 -366.287825) (xy 422.116468 -366.249116) (xy 422.082382 -366.204973) (xy 422.055086 -366.156338)
			(xy 422.035163 -366.104247) (xy 422.023037 -366.04981) (xy 422.018966 -365.994188) (xy 416.228289 -365.994188)
			(xy 416.234467 -365.998701) (xy 416.261641 -366.008525) (xy 416.276028 -366.009936) (xy 416.304709 -366.012291)
			(xy 416.360922 -366.0246) (xy 416.41465 -366.045211) (xy 416.464675 -366.073655) (xy 416.509861 -366.109288)
			(xy 416.549184 -366.151302) (xy 416.581753 -366.198745) (xy 416.606829 -366.250539) (xy 416.623844 -366.305512)
			(xy 416.632412 -366.362416) (xy 416.632898 -366.39119) (xy 416.632898 -366.412526) (xy 416.807396 -366.587024)
			(xy 423.490136 -366.587024) (xy 423.490687 -366.558579) (xy 423.499137 -366.502321) (xy 423.515853 -366.447943)
			(xy 423.540465 -366.396652) (xy 423.572425 -366.349589) (xy 423.611023 -366.307797) (xy 423.632884 -366.28959)
			(xy 423.644312 -366.279599) (xy 423.66133 -366.25449) (xy 423.670235 -366.225493) (xy 423.670243 -366.19516)
			(xy 423.661353 -366.166158) (xy 423.644348 -366.14104) (xy 423.632884 -366.131094) (xy 423.610998 -366.112915)
			(xy 423.572397 -366.071118) (xy 423.540436 -366.02405) (xy 423.515824 -365.972754) (xy 423.499109 -365.918371)
			(xy 423.49066 -365.862107) (xy 423.490136 -365.83366) (xy 423.490622 -365.806409) (xy 423.498378 -365.752461)
			(xy 423.513733 -365.700166) (xy 423.536375 -365.650589) (xy 423.565841 -365.604739) (xy 423.601532 -365.563548)
			(xy 423.642723 -365.527857) (xy 423.688573 -365.498391) (xy 423.73815 -365.475749) (xy 423.790445 -365.460394)
			(xy 423.844393 -365.452638) (xy 423.898895 -365.452638) (xy 423.952843 -365.460394) (xy 424.005138 -365.475749)
			(xy 424.054715 -365.498391) (xy 424.100565 -365.527857) (xy 424.141756 -365.563548) (xy 424.177447 -365.604739)
			(xy 424.206913 -365.650589) (xy 424.229555 -365.700166) (xy 424.24491 -365.752461) (xy 424.252666 -365.806409)
			(xy 424.253152 -365.83366) (xy 424.252665 -365.862107) (xy 424.244202 -365.918369) (xy 424.227473 -365.972748)
			(xy 424.20285 -366.024038) (xy 424.170879 -366.0711) (xy 424.13227 -366.112889) (xy 424.110404 -366.131094)
			(xy 424.098893 -366.140996) (xy 424.081878 -366.166131) (xy 424.072984 -366.19515) (xy 424.072992 -366.225502)
			(xy 424.081901 -366.254517) (xy 424.098929 -366.279643) (xy 424.110404 -366.28959) (xy 424.13228 -366.307781)
			(xy 424.170882 -366.349575) (xy 424.202845 -366.396641) (xy 424.227458 -366.447934) (xy 424.244176 -366.502315)
			(xy 424.246446 -366.517428) (xy 424.505626 -366.517428) (xy 424.509697 -366.461806) (xy 424.521823 -366.407369)
			(xy 424.541746 -366.355278) (xy 424.569042 -366.306643) (xy 424.603128 -366.2625) (xy 424.643277 -366.223791)
			(xy 424.688635 -366.19134) (xy 424.738235 -366.165839) (xy 424.791019 -366.147832) (xy 424.845862 -366.137702)
			(xy 424.901596 -366.135665) (xy 424.957033 -366.141765) (xy 425.01099 -366.155871) (xy 425.062319 -366.177683)
			(xy 425.109925 -366.206737) (xy 425.152793 -366.242412) (xy 425.19001 -366.283949) (xy 425.220783 -366.330462)
			(xy 425.244455 -366.380959) (xy 425.260523 -366.434366) (xy 425.268643 -366.489542) (xy 425.269152 -366.517428)
			(xy 425.268643 -366.545314) (xy 425.260523 -366.60049) (xy 425.244455 -366.653897) (xy 425.220783 -366.704394)
			(xy 425.19001 -366.750907) (xy 425.152793 -366.792444) (xy 425.109925 -366.828119) (xy 425.062319 -366.857173)
			(xy 425.01099 -366.878985) (xy 424.957033 -366.893091) (xy 424.901596 -366.899191) (xy 424.845862 -366.897154)
			(xy 424.791019 -366.887024) (xy 424.738235 -366.869017) (xy 424.688635 -366.843516) (xy 424.643277 -366.811065)
			(xy 424.603128 -366.772356) (xy 424.569042 -366.728213) (xy 424.541746 -366.679578) (xy 424.521823 -366.627487)
			(xy 424.509697 -366.57305) (xy 424.505626 -366.517428) (xy 424.246446 -366.517428) (xy 424.252627 -366.558577)
			(xy 424.253152 -366.587024) (xy 424.252666 -366.614275) (xy 424.24491 -366.668223) (xy 424.229555 -366.720518)
			(xy 424.206913 -366.770095) (xy 424.177447 -366.815945) (xy 424.141756 -366.857136) (xy 424.100565 -366.892827)
			(xy 424.054715 -366.922293) (xy 424.005138 -366.944935) (xy 423.952843 -366.96029) (xy 423.898895 -366.968046)
			(xy 423.844393 -366.968046) (xy 423.790445 -366.96029) (xy 423.73815 -366.944935) (xy 423.688573 -366.922293)
			(xy 423.642723 -366.892827) (xy 423.601532 -366.857136) (xy 423.565841 -366.815945) (xy 423.536375 -366.770095)
			(xy 423.513733 -366.720518) (xy 423.498378 -366.668223) (xy 423.490622 -366.614275) (xy 423.490136 -366.587024)
			(xy 416.807396 -366.587024) (xy 416.93465 -366.714278) (xy 416.951876 -366.732385) (xy 416.979616 -366.773945)
			(xy 416.998723 -366.820116) (xy 417.008462 -366.869126) (xy 417.009072 -366.89411) (xy 417.009072 -367.91519)
			(xy 417.00843 -367.940172) (xy 416.998695 -367.989178) (xy 416.979597 -368.035348) (xy 416.951867 -368.07691)
			(xy 416.93465 -368.095022) (xy 416.420808 -368.608864) (xy 416.402697 -368.626103) (xy 416.361158 -368.653918)
			(xy 416.314992 -368.673096) (xy 416.265971 -368.682901) (xy 416.240976 -368.68354) (xy 412.02483 -368.68354)
			(xy 411.024832 -369.683538) (xy 411.024832 -372.299218) (xy 413.591022 -372.299218) (xy 413.594749 -372.24597)
			(xy 413.605863 -372.193761) (xy 413.624146 -372.143611) (xy 413.649242 -372.096499) (xy 413.68066 -372.053346)
			(xy 413.717787 -372.014993) (xy 413.738568 -371.99824) (xy 413.750345 -371.988311) (xy 413.767866 -371.962997)
			(xy 413.777047 -371.933611) (xy 413.777053 -371.902825) (xy 413.767883 -371.873436) (xy 413.75037 -371.848116)
			(xy 413.738568 -371.83822) (xy 413.716087 -371.820026) (xy 413.676354 -371.778006) (xy 413.643415 -371.730471)
			(xy 413.618027 -371.678511) (xy 413.600769 -371.623314) (xy 413.592038 -371.566146) (xy 413.591502 -371.53723)
			(xy 413.591985 -371.50986) (xy 413.599799 -371.455682) (xy 413.615284 -371.403179) (xy 413.638122 -371.353432)
			(xy 413.667843 -371.307464) (xy 413.685482 -371.286532) (xy 413.694691 -371.275184) (xy 413.706874 -371.248634)
			(xy 413.711053 -371.219723) (xy 413.706887 -371.19081) (xy 413.694716 -371.164255) (xy 413.685482 -371.152928)
			(xy 413.667873 -371.131971) (xy 413.63815 -371.086006) (xy 413.615306 -371.036264) (xy 413.599809 -370.983766)
			(xy 413.591979 -370.929591) (xy 413.591975 -370.874854) (xy 413.599799 -370.820679) (xy 413.61529 -370.768179)
			(xy 413.638128 -370.718434) (xy 413.667845 -370.672466) (xy 413.685482 -370.651532) (xy 413.694691 -370.640184)
			(xy 413.706874 -370.613634) (xy 413.711053 -370.584723) (xy 413.706887 -370.55581) (xy 413.694716 -370.529255)
			(xy 413.685482 -370.517928) (xy 413.66784 -370.496999) (xy 413.638129 -370.451025) (xy 413.615294 -370.401277)
			(xy 413.599804 -370.348775) (xy 413.591976 -370.294599) (xy 413.591502 -370.26723) (xy 413.591983 -370.239977)
			(xy 413.599736 -370.186027) (xy 413.615089 -370.133728) (xy 413.637729 -370.084148) (xy 413.667195 -370.038294)
			(xy 413.702887 -369.997101) (xy 413.744078 -369.961407) (xy 413.78993 -369.931938) (xy 413.83951 -369.909296)
			(xy 413.891807 -369.893941) (xy 413.945757 -369.886185) (xy 413.97301 -369.885722) (xy 414.000381 -369.886177)
			(xy 414.05456 -369.893997) (xy 414.107064 -369.909488) (xy 414.156811 -369.932332) (xy 414.202777 -369.962059)
			(xy 414.223708 -369.979702) (xy 414.235036 -369.988938) (xy 414.261593 -370.001114) (xy 414.29051 -370.005287)
			(xy 414.319427 -370.001114) (xy 414.345984 -369.988938) (xy 414.357312 -369.979702) (xy 414.378267 -369.962091)
			(xy 414.424233 -369.932375) (xy 414.473975 -369.909533) (xy 414.526471 -369.894036) (xy 414.580642 -369.8862)
			(xy 414.60801 -369.885722) (xy 414.636925 -369.886297) (xy 414.694094 -369.895013) (xy 414.749292 -369.912259)
			(xy 414.801254 -369.93764) (xy 414.848789 -369.970574) (xy 414.890808 -370.010307) (xy 414.909 -370.032788)
			(xy 414.918897 -370.044593) (xy 414.944221 -370.062112) (xy 414.973614 -370.071288) (xy 415.004406 -370.071288)
			(xy 415.033799 -370.062112) (xy 415.059123 -370.044593) (xy 415.06902 -370.032788) (xy 415.087197 -370.010292)
			(xy 415.12922 -369.970559) (xy 415.176758 -369.937621) (xy 415.228722 -369.912235) (xy 415.283922 -369.894981)
			(xy 415.341093 -369.886255) (xy 415.37001 -369.885722) (xy 415.397264 -369.886146) (xy 415.451218 -369.893905)
			(xy 415.503519 -369.909264) (xy 415.553101 -369.931909) (xy 415.598956 -369.961381) (xy 415.640149 -369.997079)
			(xy 415.675843 -370.038276) (xy 415.70531 -370.084134) (xy 415.72795 -370.133719) (xy 415.743304 -370.186021)
			(xy 415.751057 -370.239975) (xy 415.751518 -370.26723) (xy 415.75109 -370.294602) (xy 415.743266 -370.348783)
			(xy 415.727769 -370.401288) (xy 415.704918 -370.451034) (xy 415.675184 -370.496998) (xy 415.657538 -370.517928)
			(xy 415.648269 -370.529232) (xy 415.636091 -370.555798) (xy 415.631922 -370.584723) (xy 415.636104 -370.613646)
			(xy 415.648294 -370.640206) (xy 415.657538 -370.651532) (xy 415.67521 -370.67244) (xy 415.704936 -370.718411)
			(xy 415.727782 -370.768162) (xy 415.743277 -370.820668) (xy 415.751104 -370.87485) (xy 415.7511 -370.929595)
			(xy 415.743267 -370.983777) (xy 415.727766 -371.036281) (xy 415.704914 -371.086028) (xy 415.675182 -371.131996)
			(xy 415.657538 -371.152928) (xy 415.648269 -371.164232) (xy 415.636091 -371.190798) (xy 415.631922 -371.219723)
			(xy 415.636104 -371.248646) (xy 415.648294 -371.275206) (xy 415.657538 -371.286532) (xy 415.675165 -371.307474)
			(xy 415.704877 -371.353444) (xy 415.727715 -371.40319) (xy 415.743209 -371.455688) (xy 415.751042 -371.509862)
			(xy 415.751518 -371.53723) (xy 415.75098 -371.566147) (xy 415.74226 -371.623318) (xy 415.725008 -371.678518)
			(xy 415.69962 -371.730481) (xy 415.666678 -371.778015) (xy 415.626937 -371.820031) (xy 415.604452 -371.83822)
			(xy 415.592613 -371.848083) (xy 415.575089 -371.873414) (xy 415.565913 -371.902817) (xy 415.565919 -371.933619)
			(xy 415.575106 -371.963019) (xy 415.592639 -371.988344) (xy 415.604452 -371.99824) (xy 415.625264 -372.014958)
			(xy 415.662394 -372.053316) (xy 415.693814 -372.096475) (xy 415.718912 -372.143593) (xy 415.737196 -372.193749)
			(xy 415.748311 -372.245964) (xy 415.75026 -372.273818) (xy 416.956522 -372.273818) (xy 416.960249 -372.22057)
			(xy 416.971363 -372.168361) (xy 416.989646 -372.118211) (xy 417.014742 -372.071099) (xy 417.04616 -372.027946)
			(xy 417.083287 -371.989593) (xy 417.104068 -371.97284) (xy 417.115845 -371.962911) (xy 417.133366 -371.937597)
			(xy 417.142547 -371.908211) (xy 417.142553 -371.877425) (xy 417.133383 -371.848036) (xy 417.11587 -371.822716)
			(xy 417.104068 -371.81282) (xy 417.081587 -371.794626) (xy 417.041854 -371.752606) (xy 417.008915 -371.705071)
			(xy 416.983527 -371.653111) (xy 416.966269 -371.597914) (xy 416.957538 -371.540746) (xy 416.957002 -371.51183)
			(xy 416.957485 -371.48446) (xy 416.965299 -371.430282) (xy 416.980784 -371.377779) (xy 417.003622 -371.328032)
			(xy 417.033343 -371.282064) (xy 417.050982 -371.261132) (xy 417.060191 -371.249784) (xy 417.072374 -371.223234)
			(xy 417.076553 -371.194323) (xy 417.072387 -371.16541) (xy 417.060216 -371.138855) (xy 417.050982 -371.127528)
			(xy 417.033373 -371.106571) (xy 417.00365 -371.060606) (xy 416.980806 -371.010864) (xy 416.965309 -370.958366)
			(xy 416.957479 -370.904191) (xy 416.957475 -370.849454) (xy 416.965299 -370.795279) (xy 416.98079 -370.742779)
			(xy 417.003628 -370.693034) (xy 417.033345 -370.647066) (xy 417.050982 -370.626132) (xy 417.060191 -370.614784)
			(xy 417.072374 -370.588234) (xy 417.076553 -370.559323) (xy 417.072387 -370.53041) (xy 417.060216 -370.503855)
			(xy 417.050982 -370.492528) (xy 417.03334 -370.471599) (xy 417.003629 -370.425625) (xy 416.980794 -370.375877)
			(xy 416.965304 -370.323375) (xy 416.957476 -370.269199) (xy 416.957002 -370.24183) (xy 416.957488 -370.214579)
			(xy 416.965244 -370.160631) (xy 416.980599 -370.108336) (xy 417.003241 -370.058759) (xy 417.032707 -370.012909)
			(xy 417.068398 -369.971718) (xy 417.109589 -369.936027) (xy 417.155439 -369.906561) (xy 417.205016 -369.883919)
			(xy 417.257311 -369.868564) (xy 417.311259 -369.860808) (xy 417.365761 -369.860808) (xy 417.419709 -369.868564)
			(xy 417.472004 -369.883919) (xy 417.521581 -369.906561) (xy 417.567431 -369.936027) (xy 417.608622 -369.971718)
			(xy 417.644313 -370.012909) (xy 417.669658 -370.052346) (xy 419.301422 -370.052346) (xy 419.301948 -370.023176)
			(xy 419.310856 -369.96552) (xy 419.32844 -369.909892) (xy 419.35429 -369.857592) (xy 419.387803 -369.809837)
			(xy 419.428198 -369.767744) (xy 419.451028 -369.749578) (xy 419.461394 -369.741142) (xy 419.47769 -369.719968)
			(xy 419.487936 -369.695292) (xy 419.491432 -369.668804) (xy 419.487938 -369.642315) (xy 419.477693 -369.617638)
			(xy 419.4614 -369.596464) (xy 419.451028 -369.588034) (xy 419.428198 -369.569867) (xy 419.387796 -369.527782)
			(xy 419.35428 -369.480029) (xy 419.328434 -369.427727) (xy 419.310862 -369.372096) (xy 419.301975 -369.314436)
			(xy 419.301422 -369.285266) (xy 419.301846 -369.258013) (xy 419.309608 -369.204061) (xy 419.324969 -369.151763)
			(xy 419.347616 -369.102184) (xy 419.377089 -369.056332) (xy 419.412787 -369.015142) (xy 419.453984 -368.979451)
			(xy 419.49984 -368.949986) (xy 419.549423 -368.927347) (xy 419.601724 -368.911995) (xy 419.655676 -368.904242)
			(xy 419.68293 -368.903758) (xy 419.711846 -368.904305) (xy 419.769017 -368.913025) (xy 419.824216 -368.930276)
			(xy 419.876178 -368.955662) (xy 419.923713 -368.988602) (xy 419.96573 -369.02834) (xy 419.98392 -369.050824)
			(xy 419.993817 -369.062629) (xy 420.019141 -369.080148) (xy 420.048534 -369.089324) (xy 420.079326 -369.089324)
			(xy 420.108719 -369.080148) (xy 420.134043 -369.062629) (xy 420.14394 -369.050824) (xy 420.162115 -369.028326)
			(xy 420.204137 -368.988591) (xy 420.251675 -368.955653) (xy 420.30364 -368.930267) (xy 420.358841 -368.913014)
			(xy 420.416013 -368.90429) (xy 420.44493 -368.903758) (xy 420.473478 -368.904268) (xy 420.529933 -368.912792)
			(xy 420.584489 -368.929632) (xy 420.635927 -368.95441) (xy 420.659814 -368.970052) (xy 420.670957 -368.977114)
			(xy 420.69581 -368.985923) (xy 420.722092 -368.988052) (xy 420.748038 -368.983358) (xy 420.771908 -368.972156)
			(xy 420.792099 -368.955198) (xy 420.800022 -368.944652) (xy 420.815446 -368.923649) (xy 420.851043 -368.885595)
			(xy 420.891486 -368.852737) (xy 420.936022 -368.825686) (xy 420.983824 -368.804944) (xy 421.034003 -368.790897)
			(xy 421.085626 -368.783806) (xy 421.11168 -368.783362) (xy 421.140598 -368.783871) (xy 421.19777 -368.792599)
			(xy 421.25297 -368.809857) (xy 421.304932 -368.83525) (xy 421.352466 -368.868197) (xy 421.394481 -368.907941)
			(xy 421.41267 -368.930428) (xy 421.422567 -368.942233) (xy 421.447891 -368.959752) (xy 421.477284 -368.968928)
			(xy 421.508076 -368.968928) (xy 421.537469 -368.959752) (xy 421.562793 -368.942233) (xy 421.57269 -368.930428)
			(xy 421.590894 -368.907955) (xy 421.63291 -368.868218) (xy 421.680442 -368.835277) (xy 421.732401 -368.809886)
			(xy 421.787597 -368.792628) (xy 421.844765 -368.783898) (xy 421.87368 -368.783362) (xy 421.900929 -368.783897)
			(xy 421.954874 -368.79165) (xy 422.007166 -368.807001) (xy 422.056741 -368.829637) (xy 422.10259 -368.859099)
			(xy 422.143779 -368.894785) (xy 422.179471 -368.93597) (xy 422.208939 -368.981815) (xy 422.231582 -369.031387)
			(xy 422.24694 -369.083677) (xy 422.2547 -369.137621) (xy 422.255188 -369.16487) (xy 422.254738 -369.190913)
			(xy 422.247655 -369.242514) (xy 422.233618 -369.292672) (xy 422.212886 -369.340454) (xy 422.185846 -369.384971)
			(xy 422.153001 -369.425395) (xy 422.134284 -369.443508) (xy 422.124324 -369.453453) (xy 422.109861 -369.477587)
			(xy 422.102521 -369.504749) (xy 422.102859 -369.532884) (xy 422.110849 -369.559862) (xy 422.125888 -369.583642)
			(xy 422.136062 -369.593368) (xy 422.155664 -369.611509) (xy 422.190054 -369.652374) (xy 422.218408 -369.697637)
			(xy 422.240172 -369.746412) (xy 422.25492 -369.797746) (xy 422.262364 -369.850635) (xy 422.262808 -369.87734)
			(xy 422.262337 -369.905111) (xy 422.254279 -369.960065) (xy 422.238337 -370.01327) (xy 422.214849 -370.063601)
			(xy 422.184312 -370.109994) (xy 422.147371 -370.15147) (xy 422.12641 -370.169694) (xy 422.115726 -370.179181)
			(xy 422.099744 -370.202854) (xy 422.090956 -370.230032) (xy 422.090053 -370.258581) (xy 422.097104 -370.28626)
			(xy 422.111557 -370.310897) (xy 422.121584 -370.321078) (xy 422.139964 -370.339133) (xy 422.172132 -370.37938)
			(xy 422.198597 -370.423587) (xy 422.218876 -370.470952) (xy 422.232603 -370.520613) (xy 422.239527 -370.571668)
			(xy 422.239948 -370.59743) (xy 422.239512 -370.624801) (xy 422.231689 -370.678982) (xy 422.216194 -370.731486)
			(xy 422.193345 -370.781233) (xy 422.163613 -370.827198) (xy 422.145968 -370.848128) (xy 422.136705 -370.859435)
			(xy 422.124535 -370.886001) (xy 422.120369 -370.914923) (xy 422.124548 -370.943843) (xy 422.136729 -370.970403)
			(xy 422.145968 -370.981732) (xy 422.163638 -371.002641) (xy 422.193362 -371.048613) (xy 422.216206 -371.098363)
			(xy 422.2317 -371.150869) (xy 422.239526 -371.20505) (xy 422.239523 -371.259795) (xy 422.231691 -371.313976)
			(xy 422.21619 -371.36648) (xy 422.19334 -371.416227) (xy 422.163611 -371.462195) (xy 422.145968 -371.483128)
			(xy 422.136705 -371.494435) (xy 422.124535 -371.521001) (xy 422.120369 -371.549923) (xy 422.124548 -371.578843)
			(xy 422.136729 -371.605403) (xy 422.145968 -371.616732) (xy 422.163638 -371.637641) (xy 422.193362 -371.683613)
			(xy 422.216206 -371.733363) (xy 422.2317 -371.785869) (xy 422.235289 -371.810718) (xy 423.31665 -371.810718)
			(xy 423.31665 -371.726022) (xy 423.324701 -371.641708) (xy 423.34073 -371.558542) (xy 423.364591 -371.477275)
			(xy 423.39607 -371.398645) (xy 423.434881 -371.323364) (xy 423.480671 -371.252112) (xy 423.533027 -371.185536)
			(xy 423.591475 -371.124238) (xy 423.655485 -371.068773) (xy 423.724477 -371.019644) (xy 423.797827 -370.977295)
			(xy 423.87487 -370.942111) (xy 423.954909 -370.914409) (xy 424.037218 -370.894441) (xy 424.121053 -370.882388)
			(xy 424.205654 -370.878358) (xy 424.290255 -370.882388) (xy 424.37409 -370.894441) (xy 424.456399 -370.914409)
			(xy 424.536438 -370.942111) (xy 424.613481 -370.977295) (xy 424.686831 -371.019644) (xy 424.755823 -371.068773)
			(xy 424.819833 -371.124238) (xy 424.878281 -371.185536) (xy 424.930637 -371.252112) (xy 424.976427 -371.323364)
			(xy 425.015238 -371.398645) (xy 425.046717 -371.477275) (xy 425.070578 -371.558542) (xy 425.086607 -371.641708)
			(xy 425.094658 -371.726022) (xy 425.095162 -371.76837) (xy 425.841163 -371.76837) (xy 425.845199 -371.684923)
			(xy 425.857271 -371.602255) (xy 425.877264 -371.521138) (xy 425.904993 -371.442329) (xy 425.940199 -371.366564)
			(xy 425.982553 -371.294551) (xy 426.031659 -371.226962) (xy 426.08706 -371.164428) (xy 426.148237 -371.107533)
			(xy 426.21462 -371.056807) (xy 426.285588 -371.012726) (xy 426.36048 -370.9757) (xy 426.438596 -370.946074)
			(xy 426.519206 -370.924126) (xy 426.601558 -370.910061) (xy 426.684884 -370.904009) (xy 426.768404 -370.906028)
			(xy 426.85134 -370.916098) (xy 426.932916 -370.934126) (xy 427.012372 -370.959943) (xy 427.088965 -370.993308)
			(xy 427.161981 -371.033909) (xy 427.230737 -371.081368) (xy 427.294591 -371.135241) (xy 427.352948 -371.195026)
			(xy 427.405263 -371.260163) (xy 427.451046 -371.330046) (xy 427.489871 -371.404021) (xy 427.521376 -371.481398)
			(xy 427.545265 -371.561455) (xy 427.561316 -371.643443) (xy 427.569379 -371.726598) (xy 427.569884 -371.76837)
			(xy 427.569379 -371.810142) (xy 427.561316 -371.893297) (xy 427.545265 -371.975285) (xy 427.521376 -372.055342)
			(xy 427.489871 -372.132719) (xy 427.451046 -372.206694) (xy 427.405263 -372.276577) (xy 427.352948 -372.341714)
			(xy 427.294591 -372.401499) (xy 427.230737 -372.455372) (xy 427.161981 -372.502831) (xy 427.088965 -372.543432)
			(xy 427.012372 -372.576797) (xy 426.932916 -372.602614) (xy 426.85134 -372.620642) (xy 426.768404 -372.630712)
			(xy 426.684884 -372.632731) (xy 426.601558 -372.626679) (xy 426.519206 -372.612614) (xy 426.438596 -372.590666)
			(xy 426.36048 -372.56104) (xy 426.285588 -372.524014) (xy 426.21462 -372.479933) (xy 426.148237 -372.429207)
			(xy 426.08706 -372.372312) (xy 426.031659 -372.309778) (xy 425.982553 -372.242189) (xy 425.940199 -372.170176)
			(xy 425.904993 -372.094411) (xy 425.877264 -372.015602) (xy 425.857271 -371.934485) (xy 425.845199 -371.851817)
			(xy 425.841163 -371.76837) (xy 425.095162 -371.76837) (xy 425.094658 -371.810718) (xy 425.086607 -371.895032)
			(xy 425.070578 -371.978198) (xy 425.046717 -372.059465) (xy 425.015238 -372.138095) (xy 424.976427 -372.213376)
			(xy 424.930637 -372.284628) (xy 424.878281 -372.351204) (xy 424.819833 -372.412502) (xy 424.755823 -372.467967)
			(xy 424.686831 -372.517096) (xy 424.613481 -372.559445) (xy 424.536438 -372.594629) (xy 424.456399 -372.622331)
			(xy 424.37409 -372.642299) (xy 424.290255 -372.654352) (xy 424.205654 -372.658383) (xy 424.121053 -372.654352)
			(xy 424.037218 -372.642299) (xy 423.954909 -372.622331) (xy 423.87487 -372.594629) (xy 423.797827 -372.559445)
			(xy 423.724477 -372.517096) (xy 423.655485 -372.467967) (xy 423.591475 -372.412502) (xy 423.533027 -372.351204)
			(xy 423.480671 -372.284628) (xy 423.434881 -372.213376) (xy 423.39607 -372.138095) (xy 423.364591 -372.059465)
			(xy 423.34073 -371.978198) (xy 423.324701 -371.895032) (xy 423.31665 -371.810718) (xy 422.235289 -371.810718)
			(xy 422.239526 -371.84005) (xy 422.239523 -371.894795) (xy 422.231691 -371.948976) (xy 422.21619 -372.00148)
			(xy 422.19334 -372.051227) (xy 422.163611 -372.097195) (xy 422.145968 -372.118128) (xy 422.136705 -372.129435)
			(xy 422.124535 -372.156001) (xy 422.120369 -372.184923) (xy 422.124548 -372.213843) (xy 422.136729 -372.240403)
			(xy 422.145968 -372.251732) (xy 422.163584 -372.272683) (xy 422.1933 -372.31865) (xy 422.216141 -372.368393)
			(xy 422.231638 -372.420889) (xy 422.239471 -372.475062) (xy 422.239948 -372.50243) (xy 422.23945 -372.52968)
			(xy 422.231691 -372.583625) (xy 422.216334 -372.635917) (xy 422.193692 -372.685492) (xy 422.164226 -372.73134)
			(xy 422.128536 -372.772529) (xy 422.087348 -372.80822) (xy 422.041501 -372.837687) (xy 421.991927 -372.86033)
			(xy 421.939635 -372.875689) (xy 421.88569 -372.88345) (xy 421.85844 -372.883938) (xy 421.829523 -372.883415)
			(xy 421.772351 -372.87469) (xy 421.717151 -372.857435) (xy 421.665189 -372.832044) (xy 421.617655 -372.7991)
			(xy 421.575639 -372.759358) (xy 421.55745 -372.736872) (xy 421.547553 -372.725067) (xy 421.522229 -372.707548)
			(xy 421.492836 -372.698372) (xy 421.462044 -372.698372) (xy 421.432651 -372.707548) (xy 421.407327 -372.725067)
			(xy 421.39743 -372.736872) (xy 421.379215 -372.759335) (xy 421.337201 -372.799073) (xy 421.289671 -372.832015)
			(xy 421.237715 -372.857407) (xy 421.182521 -372.874668) (xy 421.125355 -372.883401) (xy 421.09644 -372.883938)
			(xy 421.069189 -372.883408) (xy 421.015243 -372.875657) (xy 420.962948 -372.860307) (xy 420.91337 -372.837672)
			(xy 420.867518 -372.808211) (xy 420.826326 -372.772524) (xy 420.790631 -372.731338) (xy 420.761162 -372.685492)
			(xy 420.738517 -372.635918) (xy 420.723158 -372.583626) (xy 420.715397 -372.52968) (xy 420.714932 -372.50243)
			(xy 420.715408 -372.47506) (xy 420.723222 -372.420881) (xy 420.738708 -372.368378) (xy 420.761548 -372.318631)
			(xy 420.791271 -372.272664) (xy 420.808912 -372.251732) (xy 420.818119 -372.240383) (xy 420.830298 -372.213833)
			(xy 420.834476 -372.184923) (xy 420.830311 -372.156011) (xy 420.818144 -372.129455) (xy 420.808912 -372.118128)
			(xy 420.791301 -372.097171) (xy 420.761576 -372.051207) (xy 420.73873 -372.001465) (xy 420.723232 -371.948967)
			(xy 420.715401 -371.894792) (xy 420.715398 -371.840054) (xy 420.723223 -371.785878) (xy 420.738714 -371.733378)
			(xy 420.761555 -371.683632) (xy 420.791274 -371.637665) (xy 420.808912 -371.616732) (xy 420.818119 -371.605383)
			(xy 420.830298 -371.578833) (xy 420.834476 -371.549923) (xy 420.830311 -371.521011) (xy 420.818144 -371.494455)
			(xy 420.808912 -371.483128) (xy 420.791301 -371.462171) (xy 420.761576 -371.416207) (xy 420.73873 -371.366465)
			(xy 420.723232 -371.313967) (xy 420.715401 -371.259792) (xy 420.715398 -371.205054) (xy 420.723223 -371.150878)
			(xy 420.738714 -371.098378) (xy 420.761555 -371.048632) (xy 420.791274 -371.002665) (xy 420.808912 -370.981732)
			(xy 420.818119 -370.970383) (xy 420.830298 -370.943833) (xy 420.834476 -370.914923) (xy 420.830311 -370.886011)
			(xy 420.818144 -370.859455) (xy 420.808912 -370.848128) (xy 420.791274 -370.827195) (xy 420.761562 -370.781222)
			(xy 420.738726 -370.731475) (xy 420.723234 -370.678975) (xy 420.715406 -370.624799) (xy 420.714932 -370.59743)
			(xy 420.71516 -370.578375) (xy 420.718982 -370.540457) (xy 420.722552 -370.521738) (xy 420.724834 -370.508255)
			(xy 420.723002 -370.480984) (xy 420.713998 -370.455177) (xy 420.698467 -370.432685) (xy 420.677525 -370.41512)
			(xy 420.652672 -370.403744) (xy 420.625691 -370.399371) (xy 420.598517 -370.402315) (xy 420.585646 -370.40693)
			(xy 420.563174 -370.415447) (xy 420.516636 -370.42744) (xy 420.468959 -370.433487) (xy 420.44493 -370.433854)
			(xy 420.416013 -370.433332) (xy 420.358841 -370.424606) (xy 420.303642 -370.40735) (xy 420.25168 -370.381959)
			(xy 420.204146 -370.349015) (xy 420.16213 -370.309274) (xy 420.14394 -370.286788) (xy 420.134043 -370.274983)
			(xy 420.108719 -370.257464) (xy 420.079326 -370.248288) (xy 420.048534 -370.248288) (xy 420.019141 -370.257464)
			(xy 419.993817 -370.274983) (xy 419.98392 -370.286788) (xy 419.965715 -370.309259) (xy 419.923698 -370.348996)
			(xy 419.876166 -370.381937) (xy 419.824208 -370.407327) (xy 419.769013 -370.424586) (xy 419.711845 -370.433318)
			(xy 419.68293 -370.433854) (xy 419.655682 -370.433294) (xy 419.601739 -370.425543) (xy 419.549448 -370.410194)
			(xy 419.499874 -370.387559) (xy 419.454026 -370.358101) (xy 419.412837 -370.322417) (xy 419.377145 -370.281235)
			(xy 419.347677 -370.235392) (xy 419.325033 -370.185823) (xy 419.309673 -370.133535) (xy 419.301911 -370.079594)
			(xy 419.301422 -370.052346) (xy 417.669658 -370.052346) (xy 417.673779 -370.058759) (xy 417.696421 -370.108336)
			(xy 417.711776 -370.160631) (xy 417.719532 -370.214579) (xy 417.720018 -370.24183) (xy 417.71959 -370.269202)
			(xy 417.711766 -370.323383) (xy 417.696269 -370.375888) (xy 417.673418 -370.425634) (xy 417.643684 -370.471598)
			(xy 417.626038 -370.492528) (xy 417.616769 -370.503832) (xy 417.604591 -370.530398) (xy 417.600422 -370.559323)
			(xy 417.604604 -370.588246) (xy 417.616794 -370.614806) (xy 417.626038 -370.626132) (xy 417.64371 -370.64704)
			(xy 417.673436 -370.693011) (xy 417.696282 -370.742762) (xy 417.711777 -370.795268) (xy 417.719604 -370.84945)
			(xy 417.7196 -370.904195) (xy 417.711767 -370.958377) (xy 417.696266 -371.010881) (xy 417.673414 -371.060628)
			(xy 417.643682 -371.106596) (xy 417.626038 -371.127528) (xy 417.616769 -371.138832) (xy 417.604591 -371.165398)
			(xy 417.600422 -371.194323) (xy 417.604604 -371.223246) (xy 417.616794 -371.249806) (xy 417.626038 -371.261132)
			(xy 417.643665 -371.282074) (xy 417.673377 -371.328044) (xy 417.696215 -371.37779) (xy 417.711709 -371.430288)
			(xy 417.719542 -371.484462) (xy 417.720018 -371.51183) (xy 417.71948 -371.540747) (xy 417.71076 -371.597918)
			(xy 417.693508 -371.653118) (xy 417.66812 -371.705081) (xy 417.635178 -371.752615) (xy 417.595437 -371.794631)
			(xy 417.572952 -371.81282) (xy 417.561113 -371.822683) (xy 417.543589 -371.848014) (xy 417.534413 -371.877417)
			(xy 417.534419 -371.908219) (xy 417.543606 -371.937619) (xy 417.561139 -371.962944) (xy 417.572952 -371.97284)
			(xy 417.593764 -371.989558) (xy 417.630894 -372.027916) (xy 417.662314 -372.071075) (xy 417.687412 -372.118193)
			(xy 417.705696 -372.168349) (xy 417.716811 -372.220564) (xy 417.720538 -372.273818) (xy 417.716805 -372.327073)
			(xy 417.705686 -372.379287) (xy 417.687397 -372.429441) (xy 417.662295 -372.476556) (xy 417.63087 -372.519712)
			(xy 417.593737 -372.558066) (xy 417.572952 -372.57482) (xy 417.561113 -372.584683) (xy 417.543589 -372.610014)
			(xy 417.534413 -372.639417) (xy 417.534419 -372.670219) (xy 417.543606 -372.699619) (xy 417.561139 -372.724944)
			(xy 417.572952 -372.73484) (xy 417.595465 -372.752995) (xy 417.635196 -372.795024) (xy 417.66813 -372.842567)
			(xy 417.693513 -372.894535) (xy 417.710763 -372.949738) (xy 417.719486 -373.006912) (xy 417.720018 -373.03583)
			(xy 417.719532 -373.063081) (xy 417.711776 -373.117029) (xy 417.696421 -373.169324) (xy 417.673779 -373.218901)
			(xy 417.644313 -373.264751) (xy 417.608622 -373.305942) (xy 417.567431 -373.341633) (xy 417.521581 -373.371099)
			(xy 417.472004 -373.393741) (xy 417.419709 -373.409096) (xy 417.365761 -373.416852) (xy 417.311259 -373.416852)
			(xy 417.257311 -373.409096) (xy 417.205016 -373.393741) (xy 417.155439 -373.371099) (xy 417.109589 -373.341633)
			(xy 417.068398 -373.305942) (xy 417.032707 -373.264751) (xy 417.003241 -373.218901) (xy 416.980599 -373.169324)
			(xy 416.965244 -373.117029) (xy 416.957488 -373.063081) (xy 416.957002 -373.03583) (xy 416.957541 -373.006914)
			(xy 416.966266 -372.949744) (xy 416.98352 -372.894545) (xy 417.008907 -372.842583) (xy 417.041847 -372.795049)
			(xy 417.081584 -372.753031) (xy 417.104068 -372.73484) (xy 417.115845 -372.724911) (xy 417.133366 -372.699597)
			(xy 417.142547 -372.670211) (xy 417.142553 -372.639425) (xy 417.133383 -372.610036) (xy 417.11587 -372.584716)
			(xy 417.104068 -372.57482) (xy 417.083314 -372.558031) (xy 417.046184 -372.519683) (xy 417.014761 -372.476532)
			(xy 416.989661 -372.429423) (xy 416.971373 -372.379275) (xy 416.960254 -372.327067) (xy 416.956522 -372.273818)
			(xy 415.75026 -372.273818) (xy 415.752038 -372.299218) (xy 415.748305 -372.352473) (xy 415.737186 -372.404687)
			(xy 415.718897 -372.454841) (xy 415.693795 -372.501956) (xy 415.66237 -372.545112) (xy 415.625237 -372.583466)
			(xy 415.604452 -372.60022) (xy 415.592613 -372.610083) (xy 415.575089 -372.635414) (xy 415.565913 -372.664817)
			(xy 415.565919 -372.695619) (xy 415.575106 -372.725019) (xy 415.592639 -372.750344) (xy 415.604452 -372.76024)
			(xy 415.626965 -372.778395) (xy 415.666696 -372.820424) (xy 415.69963 -372.867967) (xy 415.725013 -372.919935)
			(xy 415.742263 -372.975138) (xy 415.750986 -373.032312) (xy 415.751518 -373.06123) (xy 415.75105 -373.088482)
			(xy 415.74329 -373.142429) (xy 415.727931 -373.194724) (xy 415.705287 -373.244301) (xy 415.675819 -373.29015)
			(xy 415.640126 -373.33134) (xy 415.598934 -373.367031) (xy 415.553083 -373.396497) (xy 415.503505 -373.419138)
			(xy 415.45121 -373.434494) (xy 415.397262 -373.442252) (xy 415.37001 -373.442738) (xy 415.341092 -373.442236)
			(xy 415.283919 -373.433507) (xy 415.228719 -373.416247) (xy 415.176757 -373.390853) (xy 415.129224 -373.357905)
			(xy 415.087209 -373.31816) (xy 415.06902 -373.295672) (xy 415.059123 -373.283867) (xy 415.033799 -373.266348)
			(xy 415.004406 -373.257172) (xy 414.973614 -373.257172) (xy 414.944221 -373.266348) (xy 414.918897 -373.283867)
			(xy 414.909 -373.295672) (xy 414.890802 -373.31815) (xy 414.848784 -373.357886) (xy 414.801251 -373.390827)
			(xy 414.749291 -373.416217) (xy 414.694095 -373.433474) (xy 414.636926 -373.442203) (xy 414.60801 -373.442738)
			(xy 414.580639 -373.442281) (xy 414.526459 -373.434463) (xy 414.473955 -373.418973) (xy 414.424209 -373.396129)
			(xy 414.378243 -373.366401) (xy 414.357312 -373.348758) (xy 414.345984 -373.339522) (xy 414.319427 -373.327346)
			(xy 414.29051 -373.323173) (xy 414.261593 -373.327346) (xy 414.235036 -373.339522) (xy 414.223708 -373.348758)
			(xy 414.202778 -373.3664) (xy 414.156806 -373.396113) (xy 414.107058 -373.418949) (xy 414.054556 -373.434439)
			(xy 414.000379 -373.442265) (xy 413.97301 -373.442738) (xy 413.94576 -373.442213) (xy 413.891816 -373.434458)
			(xy 413.839524 -373.419106) (xy 413.789948 -373.396468) (xy 413.744099 -373.367006) (xy 413.70291 -373.331318)
			(xy 413.667218 -373.290133) (xy 413.637751 -373.244287) (xy 413.615108 -373.194714) (xy 413.59975 -373.142423)
			(xy 413.59199 -373.08848) (xy 413.591502 -373.06123) (xy 413.592041 -373.032314) (xy 413.600766 -372.975144)
			(xy 413.61802 -372.919945) (xy 413.643407 -372.867983) (xy 413.676347 -372.820449) (xy 413.716084 -372.778431)
			(xy 413.738568 -372.76024) (xy 413.750345 -372.750311) (xy 413.767866 -372.724997) (xy 413.777047 -372.695611)
			(xy 413.777053 -372.664825) (xy 413.767883 -372.635436) (xy 413.75037 -372.610116) (xy 413.738568 -372.60022)
			(xy 413.717814 -372.583431) (xy 413.680684 -372.545083) (xy 413.649261 -372.501932) (xy 413.624161 -372.454823)
			(xy 413.605873 -372.404675) (xy 413.594754 -372.352467) (xy 413.591022 -372.299218) (xy 411.024832 -372.299218)
			(xy 411.024832 -374.333052) (xy 416.088785 -374.333052) (xy 416.088785 -374.278548) (xy 416.096542 -374.224599)
			(xy 416.111899 -374.172302) (xy 416.134542 -374.122724) (xy 416.16401 -374.076873) (xy 416.199704 -374.035683)
			(xy 416.240897 -373.999992) (xy 416.286751 -373.970527) (xy 416.336331 -373.947888) (xy 416.388628 -373.932536)
			(xy 416.442578 -373.924783) (xy 416.46983 -373.924322) (xy 416.498745 -373.924882) (xy 416.555915 -373.933601)
			(xy 416.611113 -373.95085) (xy 416.663076 -373.976234) (xy 416.710611 -374.009171) (xy 416.752629 -374.048905)
			(xy 416.77082 -374.071388) (xy 416.780717 -374.083193) (xy 416.806041 -374.100712) (xy 416.835434 -374.109888)
			(xy 416.866226 -374.109888) (xy 416.895619 -374.100712) (xy 416.920943 -374.083193) (xy 416.93084 -374.071388)
			(xy 416.949005 -374.048883) (xy 416.991031 -374.00915) (xy 417.038571 -373.976213) (xy 417.090537 -373.950829)
			(xy 417.145739 -373.933577) (xy 417.202913 -373.924854) (xy 417.23183 -373.924322) (xy 417.259082 -373.92475)
			(xy 417.313031 -373.93251) (xy 417.365326 -373.947869) (xy 417.414903 -373.970514) (xy 417.460754 -373.999983)
			(xy 417.501943 -374.035678) (xy 417.537635 -374.07687) (xy 417.5671 -374.122723) (xy 417.589741 -374.172302)
			(xy 417.605096 -374.224599) (xy 417.612852 -374.278548) (xy 417.612852 -374.333052) (xy 417.605096 -374.387001)
			(xy 417.589741 -374.439298) (xy 417.5671 -374.488877) (xy 417.537635 -374.53473) (xy 417.501943 -374.575922)
			(xy 417.460754 -374.611617) (xy 417.414903 -374.641086) (xy 417.365326 -374.663731) (xy 417.313031 -374.67909)
			(xy 417.259082 -374.68685) (xy 417.23183 -374.687338) (xy 417.202913 -374.686822) (xy 417.14574 -374.678096)
			(xy 417.09054 -374.660839) (xy 417.038578 -374.635447) (xy 416.991045 -374.602502) (xy 416.949029 -374.562759)
			(xy 416.93084 -374.540272) (xy 416.920943 -374.528467) (xy 416.895619 -374.510948) (xy 416.866226 -374.501772)
			(xy 416.835434 -374.501772) (xy 416.806041 -374.510948) (xy 416.780717 -374.528467) (xy 416.77082 -374.540272)
			(xy 416.752611 -374.56274) (xy 416.710596 -374.602478) (xy 416.663065 -374.635419) (xy 416.611107 -374.66081)
			(xy 416.555912 -374.67807) (xy 416.498745 -374.686802) (xy 416.46983 -374.687338) (xy 416.442578 -374.686817)
			(xy 416.388628 -374.679064) (xy 416.336331 -374.663712) (xy 416.286751 -374.641073) (xy 416.240897 -374.611608)
			(xy 416.199704 -374.575917) (xy 416.16401 -374.534727) (xy 416.134542 -374.488876) (xy 416.111899 -374.439298)
			(xy 416.096542 -374.387001) (xy 416.088785 -374.333052) (xy 411.024832 -374.333052) (xy 411.024832 -374.861582)
			(xy 411.024198 -374.886578) (xy 411.014395 -374.935602) (xy 410.995221 -374.981773) (xy 410.967412 -375.023318)
			(xy 410.950156 -375.041414) (xy 409.873196 -376.118374) (xy 409.855104 -376.135616) (xy 409.813538 -376.163353)
			(xy 409.767363 -376.182454) (xy 409.718349 -376.192189) (xy 409.693364 -376.192796) (xy 373.68607 -376.192796)
			(xy 373.661087 -376.192171) (xy 373.612081 -376.18243) (xy 373.565912 -376.163326) (xy 373.52435 -376.135593)
			(xy 373.506238 -376.118374) (xy 364.010448 -366.622584) (xy 363.993199 -366.604481) (xy 363.965386 -366.56294)
			(xy 363.94621 -366.516771) (xy 363.936409 -366.467748) (xy 363.935772 -366.442752) (xy 363.935772 -365.422942)
			(xy 363.477048 -364.963964) (xy 363.45979 -364.94587) (xy 363.431978 -364.904325) (xy 363.412805 -364.858154)
			(xy 363.403007 -364.809129) (xy 363.402372 -364.784132) (xy 363.402372 -363.93882) (xy 362.665772 -362.836206)
			(xy 362.33608 -362.506768) (xy 361.934252 -362.506768) (xy 361.827318 -362.613448) (xy 361.8092 -362.63068)
			(xy 361.767664 -362.658497) (xy 361.7215 -362.677677) (xy 361.672481 -362.687484) (xy 361.647486 -362.688124)
			(xy 359.636822 -362.688124) (xy 359.618676 -362.70723) (xy 359.578019 -362.740752) (xy 359.53314 -362.768366)
			(xy 359.48489 -362.789546) (xy 359.434186 -362.803891) (xy 359.381991 -362.811129) (xy 359.355644 -362.811568)
			(xy 359.32687 -362.811046) (xy 359.269975 -362.802396) (xy 359.215024 -362.785299) (xy 359.163264 -362.760145)
			(xy 359.115868 -362.727503) (xy 359.094532 -362.70819) (xy 359.058464 -362.674408) (xy 358.885744 -362.847382)
			(xy 358.885744 -363.32541) (xy 360.662472 -363.32541) (xy 360.666543 -363.269788) (xy 360.678669 -363.215351)
			(xy 360.698592 -363.16326) (xy 360.725888 -363.114625) (xy 360.759974 -363.070482) (xy 360.800123 -363.031773)
			(xy 360.845481 -362.999322) (xy 360.895081 -362.973821) (xy 360.947865 -362.955814) (xy 361.002708 -362.945684)
			(xy 361.058442 -362.943647) (xy 361.113879 -362.949747) (xy 361.167836 -362.963853) (xy 361.219165 -362.985665)
			(xy 361.266771 -363.014719) (xy 361.309639 -363.050394) (xy 361.346856 -363.091931) (xy 361.377629 -363.138444)
			(xy 361.401301 -363.188941) (xy 361.417369 -363.242348) (xy 361.425489 -363.297524) (xy 361.425998 -363.32541)
			(xy 361.425489 -363.353296) (xy 361.417369 -363.408472) (xy 361.401301 -363.461879) (xy 361.377629 -363.512376)
			(xy 361.346856 -363.558889) (xy 361.309639 -363.600426) (xy 361.266771 -363.636101) (xy 361.219165 -363.665155)
			(xy 361.167836 -363.686967) (xy 361.113879 -363.701073) (xy 361.058442 -363.707173) (xy 361.002708 -363.705136)
			(xy 360.947865 -363.695006) (xy 360.895081 -363.676999) (xy 360.845481 -363.651498) (xy 360.800123 -363.619047)
			(xy 360.759974 -363.580338) (xy 360.725888 -363.536195) (xy 360.698592 -363.48756) (xy 360.678669 -363.435469)
			(xy 360.666543 -363.381032) (xy 360.662472 -363.32541) (xy 358.885744 -363.32541) (xy 358.885744 -363.901482)
			(xy 358.972866 -363.988604) (xy 359.432098 -363.988604) (xy 359.448851 -363.967821) (xy 359.487205 -363.930691)
			(xy 359.530359 -363.899269) (xy 359.577473 -363.87417) (xy 359.627625 -363.855884) (xy 359.679836 -363.844767)
			(xy 359.733088 -363.841037) (xy 359.78634 -363.844767) (xy 359.838551 -363.855884) (xy 359.888703 -363.87417)
			(xy 359.935817 -363.899269) (xy 359.978971 -363.930691) (xy 360.017325 -363.967821) (xy 360.034078 -363.988604)
			(xy 360.751882 -363.988604) (xy 360.961178 -364.1979) (xy 361.550202 -364.1979) (xy 361.554273 -364.142278)
			(xy 361.566399 -364.087841) (xy 361.586322 -364.03575) (xy 361.613618 -363.987115) (xy 361.647704 -363.942972)
			(xy 361.687853 -363.904263) (xy 361.733211 -363.871812) (xy 361.782811 -363.846311) (xy 361.835595 -363.828304)
			(xy 361.890438 -363.818174) (xy 361.946172 -363.816137) (xy 362.001609 -363.822237) (xy 362.055566 -363.836343)
			(xy 362.106895 -363.858155) (xy 362.154501 -363.887209) (xy 362.197369 -363.922884) (xy 362.234586 -363.964421)
			(xy 362.265359 -364.010934) (xy 362.289031 -364.061431) (xy 362.305099 -364.114838) (xy 362.313219 -364.170014)
			(xy 362.313728 -364.1979) (xy 362.313219 -364.225786) (xy 362.305099 -364.280962) (xy 362.289031 -364.334369)
			(xy 362.265359 -364.384866) (xy 362.234586 -364.431379) (xy 362.197369 -364.472916) (xy 362.154501 -364.508591)
			(xy 362.106895 -364.537645) (xy 362.055566 -364.559457) (xy 362.001609 -364.573563) (xy 361.946172 -364.579663)
			(xy 361.890438 -364.577626) (xy 361.835595 -364.567496) (xy 361.782811 -364.549489) (xy 361.733211 -364.523988)
			(xy 361.687853 -364.491537) (xy 361.647704 -364.452828) (xy 361.613618 -364.408685) (xy 361.586322 -364.36005)
			(xy 361.566399 -364.307959) (xy 361.554273 -364.253522) (xy 361.550202 -364.1979) (xy 360.961178 -364.1979)
			(xy 361.345988 -364.58271) (xy 361.345988 -366.13338) (xy 360.582464 -366.89665) (xy 363.220762 -369.534948)
			(xy 364.036862 -369.534948) (xy 364.040933 -369.479326) (xy 364.053059 -369.424889) (xy 364.072982 -369.372798)
			(xy 364.100278 -369.324163) (xy 364.134364 -369.28002) (xy 364.174513 -369.241311) (xy 364.219871 -369.20886)
			(xy 364.269471 -369.183359) (xy 364.322255 -369.165352) (xy 364.377098 -369.155222) (xy 364.432832 -369.153185)
			(xy 364.488269 -369.159285) (xy 364.542226 -369.173391) (xy 364.593555 -369.195203) (xy 364.641161 -369.224257)
			(xy 364.684029 -369.259932) (xy 364.721246 -369.301469) (xy 364.752019 -369.347982) (xy 364.775691 -369.398479)
			(xy 364.791759 -369.451886) (xy 364.799879 -369.507062) (xy 364.800388 -369.534948) (xy 364.800249 -369.542568)
			(xy 365.489742 -369.542568) (xy 365.493813 -369.486946) (xy 365.505939 -369.432509) (xy 365.525862 -369.380418)
			(xy 365.553158 -369.331783) (xy 365.587244 -369.28764) (xy 365.627393 -369.248931) (xy 365.672751 -369.21648)
			(xy 365.722351 -369.190979) (xy 365.775135 -369.172972) (xy 365.829978 -369.162842) (xy 365.885712 -369.160805)
			(xy 365.941149 -369.166905) (xy 365.995106 -369.181011) (xy 366.046435 -369.202823) (xy 366.094041 -369.231877)
			(xy 366.136909 -369.267552) (xy 366.174126 -369.309089) (xy 366.204899 -369.355602) (xy 366.228571 -369.406099)
			(xy 366.244639 -369.459506) (xy 366.252759 -369.514682) (xy 366.253268 -369.542568) (xy 366.252759 -369.570454)
			(xy 366.244639 -369.62563) (xy 366.228571 -369.679037) (xy 366.204899 -369.729534) (xy 366.174126 -369.776047)
			(xy 366.136909 -369.817584) (xy 366.094041 -369.853259) (xy 366.046435 -369.882313) (xy 365.995106 -369.904125)
			(xy 365.941149 -369.918231) (xy 365.885712 -369.924331) (xy 365.829978 -369.922294) (xy 365.775135 -369.912164)
			(xy 365.722351 -369.894157) (xy 365.672751 -369.868656) (xy 365.627393 -369.836205) (xy 365.587244 -369.797496)
			(xy 365.553158 -369.753353) (xy 365.525862 -369.704718) (xy 365.505939 -369.652627) (xy 365.493813 -369.59819)
			(xy 365.489742 -369.542568) (xy 364.800249 -369.542568) (xy 364.799879 -369.562834) (xy 364.791759 -369.61801)
			(xy 364.775691 -369.671417) (xy 364.752019 -369.721914) (xy 364.721246 -369.768427) (xy 364.684029 -369.809964)
			(xy 364.641161 -369.845639) (xy 364.593555 -369.874693) (xy 364.542226 -369.896505) (xy 364.488269 -369.910611)
			(xy 364.432832 -369.916711) (xy 364.377098 -369.914674) (xy 364.322255 -369.904544) (xy 364.269471 -369.886537)
			(xy 364.219871 -369.861036) (xy 364.174513 -369.828585) (xy 364.134364 -369.789876) (xy 364.100278 -369.745733)
			(xy 364.072982 -369.697098) (xy 364.053059 -369.645007) (xy 364.040933 -369.59057) (xy 364.036862 -369.534948)
			(xy 363.220762 -369.534948) (xy 370.453666 -376.767852) (xy 423.349928 -376.767852) (xy 428.463964 -371.653816)
			(xy 428.463964 -369.274852) (xy 425.961556 -366.77219) (xy 425.94022 -366.77219) (xy 425.912943 -366.771768)
			(xy 425.858936 -366.764071) (xy 425.806576 -366.748759) (xy 425.756931 -366.726146) (xy 425.711013 -366.696691)
			(xy 425.669759 -366.660997) (xy 425.63401 -366.61979) (xy 425.604495 -366.573911) (xy 425.581816 -366.524295)
			(xy 425.566436 -366.471955) (xy 425.558668 -366.417958) (xy 425.558204 -366.390682) (xy 425.55844 -366.372015)
			(xy 425.56213 -366.334863) (xy 425.56557 -366.316514) (xy 425.567914 -366.302247) (xy 425.565383 -366.273459)
			(xy 425.554885 -366.246533) (xy 425.53726 -366.22363) (xy 425.513922 -366.206585) (xy 425.486742 -366.196765)
			(xy 425.472352 -366.195356) (xy 425.443694 -366.19303) (xy 425.387527 -366.180735) (xy 425.33384 -366.160154)
			(xy 425.283849 -366.131752) (xy 425.238684 -366.096171) (xy 425.199367 -366.054217) (xy 425.16679 -366.00684)
			(xy 425.141688 -365.955112) (xy 425.124631 -365.900204) (xy 425.116004 -365.843358) (xy 425.115482 -365.81461)
			(xy 425.115968 -365.787359) (xy 425.123724 -365.733411) (xy 425.139079 -365.681116) (xy 425.161721 -365.631539)
			(xy 425.191187 -365.585689) (xy 425.226878 -365.544498) (xy 425.268069 -365.508807) (xy 425.313919 -365.479341)
			(xy 425.363496 -365.456699) (xy 425.415791 -365.441344) (xy 425.469739 -365.433588) (xy 425.524241 -365.433588)
			(xy 425.578189 -365.441344) (xy 425.630484 -365.456699) (xy 425.680061 -365.479341) (xy 425.725911 -365.508807)
			(xy 425.767102 -365.544498) (xy 425.802793 -365.585689) (xy 425.832259 -365.631539) (xy 425.854901 -365.681116)
			(xy 425.870256 -365.733411) (xy 425.878012 -365.787359) (xy 425.878498 -365.81461) (xy 425.878261 -365.833277)
			(xy 425.874571 -365.870429) (xy 425.871132 -365.888778) (xy 425.868794 -365.903046) (xy 425.871323 -365.931834)
			(xy 425.88182 -365.958759) (xy 425.899444 -365.981662) (xy 425.922781 -365.998707) (xy 425.94996 -366.008527)
			(xy 425.96435 -366.009936) (xy 425.993032 -366.012272) (xy 426.049246 -366.024584) (xy 426.102975 -366.045198)
			(xy 426.152999 -366.073645) (xy 426.198184 -366.10928) (xy 426.237507 -366.151296) (xy 426.270076 -366.19874)
			(xy 426.295152 -366.250536) (xy 426.312166 -366.30551) (xy 426.320734 -366.362416) (xy 426.32122 -366.39119)
			(xy 426.32122 -366.412526) (xy 428.898304 -368.98961) (xy 428.915558 -369.007707) (xy 428.943369 -369.049252)
			(xy 428.962542 -369.095422) (xy 428.972342 -369.144446) (xy 428.97298 -369.169442) (xy 428.97298 -371.759226)
			(xy 428.972359 -371.784223) (xy 428.96255 -371.833246) (xy 428.943372 -371.879416) (xy 428.915561 -371.920962)
			(xy 428.898304 -371.939058) (xy 423.63517 -377.202192) (xy 423.61708 -377.219454) (xy 423.575533 -377.247263)
			(xy 423.52936 -377.266435) (xy 423.480335 -377.276232) (xy 423.455338 -377.276868) (xy 370.348256 -377.276868)
			(xy 370.323262 -377.276201) (xy 370.27424 -377.266406) (xy 370.22807 -377.247242) (xy 370.186522 -377.219443)
			(xy 370.168424 -377.202192) (xy 359.936034 -366.970056) (xy 357.589074 -366.970056) (xy 356.159816 -365.540544)
			(xy 356.159816 -364.856776) (xy 356.159342 -364.841505) (xy 356.150263 -364.812343) (xy 356.13298 -364.787159)
			(xy 356.109034 -364.768198) (xy 356.080559 -364.757151) (xy 356.050091 -364.755) (xy 356.035102 -364.75797)
			(xy 356.013691 -364.762642) (xy 355.970147 -364.767602) (xy 355.948234 -364.767876) (xy 355.920977 -364.767479)
			(xy 355.867018 -364.759726) (xy 355.814712 -364.744371) (xy 355.765123 -364.721729) (xy 355.719262 -364.692259)
			(xy 355.678062 -364.656563) (xy 355.642361 -364.615365) (xy 355.612887 -364.569507) (xy 355.590241 -364.51992)
			(xy 355.574882 -364.467615) (xy 355.567123 -364.413657) (xy 355.567123 -364.359143) (xy 355.574882 -364.305185)
			(xy 355.590241 -364.25288) (xy 355.612887 -364.203293) (xy 355.642361 -364.157435) (xy 355.678062 -364.116237)
			(xy 355.719262 -364.080541) (xy 355.765123 -364.051071) (xy 355.814712 -364.028429) (xy 355.867018 -364.013074)
			(xy 355.920977 -364.005321) (xy 355.948234 -364.00486) (xy 355.970147 -364.005138) (xy 356.013689 -364.010104)
			(xy 356.035102 -364.014766) (xy 356.050101 -364.01771) (xy 356.080576 -364.015609) (xy 356.109064 -364.004583)
			(xy 356.133012 -363.985619) (xy 356.150275 -363.960417) (xy 356.159305 -363.931234) (xy 356.159816 -363.91596)
			(xy 356.159816 -361.218734) (xy 356.160403 -361.196419) (xy 356.169039 -361.152632) (xy 356.18599 -361.111347)
			(xy 356.210616 -361.074126) (xy 356.241982 -361.042377) (xy 356.278903 -361.017304) (xy 356.319981 -360.999854)
			(xy 356.363659 -360.990689) (xy 356.408286 -360.990156) (xy 356.430326 -360.99369) (xy 356.434898 -360.994452)
			(xy 356.436168 -360.994452) (xy 356.452424 -360.99877) (xy 356.46857 -361.002805) (xy 356.501569 -361.007133)
			(xy 356.51821 -361.007406) (xy 356.518464 -361.007406) (xy 356.540645 -361.006912) (xy 356.584334 -360.999214)
			(xy 356.626022 -360.984047) (xy 356.664442 -360.96187) (xy 356.698428 -360.933358) (xy 356.726946 -360.899377)
			(xy 356.749129 -360.86096) (xy 356.764304 -360.819274) (xy 356.772008 -360.775587) (xy 356.772464 -360.753406)
			(xy 356.77199 -360.731344) (xy 356.764377 -360.687883) (xy 356.749379 -360.646387) (xy 356.727446 -360.608102)
			(xy 356.699236 -360.574175) (xy 356.665595 -360.545625) (xy 356.627531 -360.523308) (xy 356.586188 -360.507894)
			(xy 356.542806 -360.499845) (xy 356.52075 -360.499152) (xy 356.517956 -360.499152) (xy 356.50562 -360.499313)
			(xy 356.481065 -360.501731) (xy 356.468934 -360.503978) (xy 356.46868 -360.503978) (xy 356.375462 -360.521758)
			(xy 356.159816 -360.306112) (xy 356.159816 -358.271572) (xy 358.117648 -356.31374) (xy 358.117648 -355.040184)
			(xy 357.969566 -355.040184) (xy 357.789988 -354.860606) (xy 356.855014 -355.79558) (xy 356.843335 -355.806891)
			(xy 356.817603 -355.826765) (xy 356.803706 -355.835204) (xy 356.784076 -355.846174) (xy 356.741917 -355.861802)
			(xy 356.697663 -355.869756) (xy 356.675182 -355.870256) (xy 353.652328 -355.870256) (xy 353.637522 -355.870048)
			(xy 353.60811 -355.866605) (xy 353.593654 -355.863398) (xy 353.583791 -355.860904) (xy 353.564463 -355.854548)
			(xy 353.555046 -355.850698) (xy 352.021648 -355.215698) (xy 351.99876 -355.205623) (xy 351.957179 -355.177855)
			(xy 351.939098 -355.16058) (xy 344.541094 -347.762576) (xy 343.827354 -347.762576) (xy 343.80237 -347.761967)
			(xy 343.753363 -347.752221) (xy 343.707193 -347.733113) (xy 343.665633 -347.705375) (xy 343.647522 -347.688154)
			(xy 343.414096 -347.454728) (xy 342.950546 -346.991432) (xy 334.910684 -346.991432) (xy 333.248762 -348.6531)
			(xy 332.412086 -349.489776) (xy 332.400409 -349.50109) (xy 332.374676 -349.520962) (xy 332.360778 -349.5294)
			(xy 332.341153 -349.54038) (xy 332.298991 -349.556004) (xy 332.254736 -349.563955) (xy 332.232254 -349.564452)
			(xy 328.3077 -349.564452) (xy 328.285221 -349.563939) (xy 328.240974 -349.555963) (xy 328.198808 -349.540363)
			(xy 328.179176 -349.5294) (xy 328.165281 -349.520957) (xy 328.139546 -349.501088) (xy 328.127868 -349.489776)
			(xy 327.886568 -349.248476) (xy 327.875257 -349.236797) (xy 327.855382 -349.211065) (xy 327.846944 -349.197168)
			(xy 327.835955 -349.177548) (xy 327.820335 -349.135383) (xy 327.812388 -349.091126) (xy 327.811892 -349.068644)
			(xy 327.811892 -348.224856) (xy 327.399142 -347.811852) (xy 327.18883 -347.601794) (xy 327.178155 -347.592488)
			(xy 327.152958 -347.579589) (xy 327.125187 -347.574107) (xy 327.096978 -347.576464) (xy 327.070502 -347.58648)
			(xy 327.047796 -347.603384) (xy 327.030607 -347.625874) (xy 327.025 -347.638878) (xy 327.013993 -347.665205)
			(xy 326.985416 -347.714591) (xy 326.949805 -347.759173) (xy 326.907954 -347.797957) (xy 326.860796 -347.830079)
			(xy 326.809382 -347.854823) (xy 326.754857 -347.871637) (xy 326.698437 -347.880147) (xy 326.669908 -347.880686)
			(xy 326.642654 -347.880237) (xy 326.588702 -347.872481) (xy 326.536402 -347.857125) (xy 326.486821 -347.834481)
			(xy 326.440967 -347.805012) (xy 326.399773 -347.769317) (xy 326.364079 -347.728122) (xy 326.334612 -347.682267)
			(xy 326.311971 -347.632685) (xy 326.296616 -347.580385) (xy 326.288862 -347.526432) (xy 326.2884 -347.499178)
			(xy 322.707196 -347.499178) (xy 322.71007 -347.519171) (xy 322.710556 -347.546422) (xy 322.710072 -347.5728)
			(xy 322.702818 -347.625054) (xy 322.688437 -347.675812) (xy 322.667203 -347.724105) (xy 322.63952 -347.769015)
			(xy 322.605918 -347.809684) (xy 322.567034 -347.845339) (xy 322.523611 -347.875299) (xy 322.500244 -347.887544)
			(xy 322.487865 -347.894212) (xy 322.467132 -347.913193) (xy 322.452369 -347.937113) (xy 322.444697 -347.964155)
			(xy 322.4447 -347.992264) (xy 322.452377 -348.019305) (xy 322.467145 -348.043222) (xy 322.487881 -348.062199)
			(xy 322.500244 -348.0689) (xy 322.523634 -348.081106) (xy 322.567057 -348.111075) (xy 322.60594 -348.146736)
			(xy 322.639544 -348.187411) (xy 322.667229 -348.232325) (xy 322.688466 -348.280622) (xy 322.702852 -348.331383)
			(xy 322.710112 -348.383642) (xy 322.710556 -348.410022) (xy 322.71007 -348.437273) (xy 322.702314 -348.491221)
			(xy 322.686959 -348.543516) (xy 322.664317 -348.593093) (xy 322.634851 -348.638943) (xy 322.59916 -348.680134)
			(xy 322.557969 -348.715825) (xy 322.512119 -348.745291) (xy 322.462542 -348.767933) (xy 322.410247 -348.783288)
			(xy 322.356299 -348.791044) (xy 322.301797 -348.791044) (xy 322.247849 -348.783288) (xy 322.195554 -348.767933)
			(xy 322.145977 -348.745291) (xy 322.100127 -348.715825) (xy 322.058936 -348.680134) (xy 322.023245 -348.638943)
			(xy 321.993779 -348.593093) (xy 321.971137 -348.543516) (xy 321.955782 -348.491221) (xy 321.948026 -348.437273)
			(xy 321.94754 -348.410022) (xy 320.918332 -348.410022) (xy 320.918332 -350.895412) (xy 336.039206 -350.895412)
			(xy 336.039731 -350.866495) (xy 336.048458 -350.809324) (xy 336.065715 -350.754126) (xy 336.091105 -350.702164)
			(xy 336.124048 -350.65463) (xy 336.163787 -350.612612) (xy 336.186272 -350.594422) (xy 336.198067 -350.584512)
			(xy 336.215587 -350.559193) (xy 336.224765 -350.529802) (xy 336.224768 -350.499012) (xy 336.215593 -350.469621)
			(xy 336.198077 -350.444299) (xy 336.186272 -350.434402) (xy 336.163784 -350.416217) (xy 336.12405 -350.374195)
			(xy 336.091112 -350.326659) (xy 336.065725 -350.274696) (xy 336.04847 -350.219498) (xy 336.039741 -350.162328)
			(xy 336.039206 -350.133412) (xy 336.039743 -350.1044) (xy 336.048511 -350.047042) (xy 336.065861 -349.991673)
			(xy 336.091395 -349.939569) (xy 336.124522 -349.891931) (xy 336.144108 -349.870522) (xy 336.154365 -349.858964)
			(xy 336.167938 -349.831216) (xy 336.1726 -349.80068) (xy 336.167925 -349.770145) (xy 336.154342 -349.742403)
			(xy 336.144108 -349.730822) (xy 336.124536 -349.709401) (xy 336.091417 -349.661761) (xy 336.065886 -349.609659)
			(xy 336.04853 -349.554295) (xy 336.039748 -349.496942) (xy 336.039206 -349.467932) (xy 336.039729 -349.440676)
			(xy 336.04749 -349.386719) (xy 336.062846 -349.334415) (xy 336.085484 -349.284826) (xy 336.114944 -349.23896)
			(xy 336.150627 -349.19775) (xy 336.191808 -349.162033) (xy 336.214466 -349.146876) (xy 336.226362 -349.138554)
			(xy 336.245364 -349.116627) (xy 336.25742 -349.090236) (xy 336.261553 -349.061517) (xy 336.25743 -349.032797)
			(xy 336.245383 -349.006402) (xy 336.226389 -348.984469) (xy 336.214466 -348.976188) (xy 336.19178 -348.961065)
			(xy 336.150579 -348.925356) (xy 336.11488 -348.884147) (xy 336.085409 -348.838276) (xy 336.062767 -348.788677)
			(xy 336.047415 -348.736361) (xy 336.039664 -348.682393) (xy 336.039206 -348.655132) (xy 336.039685 -348.627879)
			(xy 336.047438 -348.573928) (xy 336.062791 -348.52163) (xy 336.085431 -348.472049) (xy 336.114897 -348.426195)
			(xy 336.150589 -348.385001) (xy 336.19178 -348.349307) (xy 336.237633 -348.319839) (xy 336.287213 -348.297197)
			(xy 336.339511 -348.281842) (xy 336.393461 -348.274086) (xy 336.420714 -348.273624) (xy 336.446635 -348.274074)
			(xy 336.497997 -348.281107) (xy 336.547935 -348.295027) (xy 336.595529 -348.315578) (xy 336.639903 -348.342383)
			(xy 336.680241 -348.374947) (xy 336.698336 -348.393512) (xy 336.707692 -348.402998) (xy 336.730329 -348.417038)
			(xy 336.755831 -348.424737) (xy 336.782456 -348.425569) (xy 336.808389 -348.419477) (xy 336.831858 -348.406876)
			(xy 336.851264 -348.388627) (xy 336.85861 -348.37751) (xy 336.873637 -348.354274) (xy 336.909342 -348.312)
			(xy 336.950778 -348.275326) (xy 336.997075 -348.245019) (xy 337.047264 -348.221716) (xy 337.100292 -348.205904)
			(xy 337.155047 -348.197915) (xy 337.182714 -348.197424) (xy 337.209967 -348.197847) (xy 337.263918 -348.205606)
			(xy 337.316215 -348.220963) (xy 337.365795 -348.243607) (xy 337.411647 -348.273076) (xy 337.452839 -348.308771)
			(xy 337.488532 -348.349964) (xy 337.518 -348.395818) (xy 337.540642 -348.445398) (xy 337.555997 -348.497696)
			(xy 337.563754 -348.551647) (xy 337.563754 -348.606153) (xy 337.560749 -348.627052) (xy 337.766138 -348.627052)
			(xy 337.766138 -348.572548) (xy 337.773894 -348.518599) (xy 337.789248 -348.466303) (xy 337.811888 -348.416723)
			(xy 337.841353 -348.37087) (xy 337.877043 -348.329677) (xy 337.918232 -348.293982) (xy 337.964081 -348.264511)
			(xy 338.013657 -348.241865) (xy 338.065952 -348.226504) (xy 338.1199 -348.218741) (xy 338.147152 -348.218252)
			(xy 338.176069 -348.218785) (xy 338.23324 -348.227508) (xy 338.288439 -348.244762) (xy 338.340402 -348.270151)
			(xy 338.387936 -348.303093) (xy 338.429952 -348.342833) (xy 338.448142 -348.365318) (xy 338.458039 -348.377123)
			(xy 338.483363 -348.394642) (xy 338.512756 -348.403818) (xy 338.543548 -348.403818) (xy 338.572941 -348.394642)
			(xy 338.598265 -348.377123) (xy 338.608162 -348.365318) (xy 338.624915 -348.344535) (xy 338.663269 -348.307405)
			(xy 338.706423 -348.275983) (xy 338.753537 -348.250884) (xy 338.803689 -348.232598) (xy 338.8559 -348.221481)
			(xy 338.909152 -348.217751) (xy 338.962404 -348.221481) (xy 339.014615 -348.232598) (xy 339.064767 -348.250884)
			(xy 339.111881 -348.275983) (xy 339.155035 -348.307405) (xy 339.193389 -348.344535) (xy 339.210142 -348.365318)
			(xy 339.220039 -348.377123) (xy 339.245363 -348.394642) (xy 339.274756 -348.403818) (xy 339.305548 -348.403818)
			(xy 339.334941 -348.394642) (xy 339.360265 -348.377123) (xy 339.370162 -348.365318) (xy 339.386915 -348.344535)
			(xy 339.425269 -348.307405) (xy 339.468423 -348.275983) (xy 339.515537 -348.250884) (xy 339.565689 -348.232598)
			(xy 339.6179 -348.221481) (xy 339.671152 -348.217751) (xy 339.724404 -348.221481) (xy 339.776615 -348.232598)
			(xy 339.826767 -348.250884) (xy 339.873881 -348.275983) (xy 339.917035 -348.307405) (xy 339.955389 -348.344535)
			(xy 339.972142 -348.365318) (xy 339.982039 -348.377123) (xy 340.007363 -348.394642) (xy 340.036756 -348.403818)
			(xy 340.067548 -348.403818) (xy 340.096941 -348.394642) (xy 340.122265 -348.377123) (xy 340.132162 -348.365318)
			(xy 340.150379 -348.342856) (xy 340.192393 -348.303119) (xy 340.239922 -348.270177) (xy 340.291878 -348.244785)
			(xy 340.347072 -348.227524) (xy 340.404237 -348.21879) (xy 340.433152 -348.218252) (xy 340.461719 -348.218782)
			(xy 340.518214 -348.227316) (xy 340.572807 -348.244169) (xy 340.624281 -348.268966) (xy 340.671487 -348.301155)
			(xy 340.713371 -348.340015) (xy 340.731602 -348.362016) (xy 340.741172 -348.373259) (xy 340.765411 -348.390096)
			(xy 340.793451 -348.399307) (xy 340.822953 -348.400124) (xy 340.851459 -348.392478) (xy 340.876593 -348.377006)
			(xy 340.886796 -348.366334) (xy 340.904952 -348.346705) (xy 340.945838 -348.312247) (xy 340.991134 -348.283834)
			(xy 341.039954 -348.262024) (xy 341.09134 -348.247243) (xy 341.144287 -348.239782) (xy 341.171022 -348.239334)
			(xy 341.199937 -348.239896) (xy 341.257107 -348.248614) (xy 341.312306 -348.265862) (xy 341.364268 -348.291246)
			(xy 341.411803 -348.324183) (xy 341.453821 -348.363917) (xy 341.472012 -348.3864) (xy 341.481909 -348.398205)
			(xy 341.507233 -348.415724) (xy 341.536626 -348.4249) (xy 341.567418 -348.4249) (xy 341.596811 -348.415724)
			(xy 341.622135 -348.398205) (xy 341.632032 -348.3864) (xy 341.650205 -348.363901) (xy 341.692228 -348.324167)
			(xy 341.739767 -348.29123) (xy 341.791732 -348.265844) (xy 341.846933 -348.248591) (xy 341.904105 -348.239867)
			(xy 341.933022 -348.239334) (xy 341.960275 -348.239737) (xy 342.014227 -348.247497) (xy 342.066524 -348.262856)
			(xy 342.116104 -348.285501) (xy 342.161957 -348.314971) (xy 342.203149 -348.350666) (xy 342.238842 -348.391861)
			(xy 342.26831 -348.437715) (xy 342.290952 -348.487296) (xy 342.306307 -348.539595) (xy 342.314064 -348.593547)
			(xy 342.314064 -348.648053) (xy 342.306307 -348.702005) (xy 342.290952 -348.754304) (xy 342.26831 -348.803885)
			(xy 342.238842 -348.849739) (xy 342.203149 -348.890934) (xy 342.161957 -348.926629) (xy 342.116104 -348.956099)
			(xy 342.066524 -348.978744) (xy 342.014227 -348.994103) (xy 341.960275 -349.001863) (xy 341.933022 -349.00235)
			(xy 341.904105 -349.001835) (xy 341.846933 -348.993108) (xy 341.791733 -348.975851) (xy 341.739771 -348.950458)
			(xy 341.692237 -348.917513) (xy 341.650221 -348.877771) (xy 341.632032 -348.855284) (xy 341.622135 -348.843479)
			(xy 341.596811 -348.82596) (xy 341.567418 -348.816784) (xy 341.536626 -348.816784) (xy 341.507233 -348.82596)
			(xy 341.481909 -348.843479) (xy 341.472012 -348.855284) (xy 341.45381 -348.877758) (xy 341.411793 -348.917495)
			(xy 341.364261 -348.950435) (xy 341.312301 -348.975826) (xy 341.257106 -348.993084) (xy 341.199937 -349.001814)
			(xy 341.171022 -349.00235) (xy 341.142456 -349.001766) (xy 341.085964 -348.993244) (xy 341.031372 -348.976401)
			(xy 340.979898 -348.951614) (xy 340.932691 -348.919435) (xy 340.890804 -348.880583) (xy 340.872572 -348.858586)
			(xy 340.86303 -348.847318) (xy 340.838783 -348.83048) (xy 340.810736 -348.821272) (xy 340.781228 -348.82046)
			(xy 340.752717 -348.828113) (xy 340.727582 -348.843592) (xy 340.717378 -348.854268) (xy 340.699186 -348.873862)
			(xy 340.658307 -348.908323) (xy 340.613018 -348.93674) (xy 340.564206 -348.958556) (xy 340.512826 -348.973344)
			(xy 340.459885 -348.980815) (xy 340.433152 -348.981268) (xy 340.404236 -348.980725) (xy 340.347065 -348.972002)
			(xy 340.291866 -348.95475) (xy 340.239904 -348.929363) (xy 340.19237 -348.896424) (xy 340.150352 -348.856686)
			(xy 340.132162 -348.834202) (xy 340.122265 -348.822397) (xy 340.096941 -348.804878) (xy 340.067548 -348.795702)
			(xy 340.036756 -348.795702) (xy 340.007363 -348.804878) (xy 339.982039 -348.822397) (xy 339.972142 -348.834202)
			(xy 339.955389 -348.854985) (xy 339.917035 -348.892115) (xy 339.873881 -348.923537) (xy 339.826767 -348.948636)
			(xy 339.776615 -348.966922) (xy 339.724404 -348.978039) (xy 339.671152 -348.981769) (xy 339.6179 -348.978039)
			(xy 339.565689 -348.966922) (xy 339.515537 -348.948636) (xy 339.468423 -348.923537) (xy 339.425269 -348.892115)
			(xy 339.386915 -348.854985) (xy 339.370162 -348.834202) (xy 339.360265 -348.822397) (xy 339.334941 -348.804878)
			(xy 339.305548 -348.795702) (xy 339.274756 -348.795702) (xy 339.245363 -348.804878) (xy 339.220039 -348.822397)
			(xy 339.210142 -348.834202) (xy 339.193389 -348.854985) (xy 339.155035 -348.892115) (xy 339.111881 -348.923537)
			(xy 339.064767 -348.948636) (xy 339.014615 -348.966922) (xy 338.962404 -348.978039) (xy 338.909152 -348.981769)
			(xy 338.8559 -348.978039) (xy 338.803689 -348.966922) (xy 338.753537 -348.948636) (xy 338.706423 -348.923537)
			(xy 338.663269 -348.892115) (xy 338.624915 -348.854985) (xy 338.608162 -348.834202) (xy 338.598265 -348.822397)
			(xy 338.572941 -348.804878) (xy 338.543548 -348.795702) (xy 338.512756 -348.795702) (xy 338.483363 -348.804878)
			(xy 338.458039 -348.822397) (xy 338.448142 -348.834202) (xy 338.429928 -348.856666) (xy 338.387913 -348.896402)
			(xy 338.340383 -348.929343) (xy 338.288426 -348.954735) (xy 338.233233 -348.971996) (xy 338.176067 -348.98073)
			(xy 338.147152 -348.981268) (xy 338.1199 -348.980859) (xy 338.065952 -348.973096) (xy 338.013657 -348.957735)
			(xy 337.964081 -348.935089) (xy 337.918232 -348.905618) (xy 337.877043 -348.869923) (xy 337.841353 -348.82873)
			(xy 337.811888 -348.782877) (xy 337.789248 -348.733297) (xy 337.773894 -348.681001) (xy 337.766138 -348.627052)
			(xy 337.560749 -348.627052) (xy 337.555997 -348.660104) (xy 337.540642 -348.712402) (xy 337.518 -348.761982)
			(xy 337.488532 -348.807836) (xy 337.452839 -348.849029) (xy 337.411647 -348.884724) (xy 337.365795 -348.914193)
			(xy 337.316215 -348.936837) (xy 337.263918 -348.952194) (xy 337.209967 -348.959953) (xy 337.182714 -348.96044)
			(xy 337.156793 -348.960017) (xy 337.10543 -348.952976) (xy 337.055492 -348.939049) (xy 337.007899 -348.918493)
			(xy 336.963525 -348.891684) (xy 336.923187 -348.859117) (xy 336.905092 -348.840552) (xy 336.895703 -348.831104)
			(xy 336.873072 -348.817068) (xy 336.84758 -348.809369) (xy 336.820963 -348.808534) (xy 336.795038 -348.814618)
			(xy 336.771572 -348.827208) (xy 336.752166 -348.845443) (xy 336.744818 -348.856554) (xy 336.729487 -348.880269)
			(xy 336.692936 -348.923312) (xy 336.650442 -348.960499) (xy 336.626962 -348.976188) (xy 336.614968 -348.984388)
			(xy 336.595949 -349.006342) (xy 336.583886 -349.032766) (xy 336.579756 -349.061517) (xy 336.583895 -349.090268)
			(xy 336.595967 -349.116687) (xy 336.614994 -349.138635) (xy 336.626962 -349.146876) (xy 336.653745 -349.164882)
			(xy 336.701371 -349.208427) (xy 336.721704 -349.23349) (xy 336.731601 -349.245295) (xy 336.756925 -349.262814)
			(xy 336.786318 -349.27199) (xy 336.81711 -349.27199) (xy 336.846503 -349.262814) (xy 336.871827 -349.245295)
			(xy 336.881724 -349.23349) (xy 336.899899 -349.210993) (xy 336.941922 -349.171259) (xy 336.989461 -349.138322)
			(xy 337.041425 -349.112936) (xy 337.096625 -349.095683) (xy 337.153797 -349.086957) (xy 337.182714 -349.086424)
			(xy 337.209969 -349.086842) (xy 337.263923 -349.094602) (xy 337.316224 -349.109961) (xy 337.365806 -349.132608)
			(xy 337.411661 -349.16208) (xy 337.452854 -349.197779) (xy 337.488548 -349.238976) (xy 337.518015 -349.284834)
			(xy 337.540655 -349.33442) (xy 337.556008 -349.386722) (xy 337.563761 -349.440677) (xy 337.564222 -349.467932)
			(xy 337.563704 -349.496945) (xy 337.554931 -349.554303) (xy 337.537575 -349.609672) (xy 337.512038 -349.661775)
			(xy 337.478908 -349.709413) (xy 337.45932 -349.730822) (xy 337.449116 -349.742424) (xy 337.435534 -349.770156)
			(xy 337.43086 -349.80068) (xy 337.435521 -349.831205) (xy 337.449093 -349.858943) (xy 337.45932 -349.870522)
			(xy 337.478917 -349.891921) (xy 337.512032 -349.939567) (xy 337.537558 -349.991675) (xy 337.554908 -350.047044)
			(xy 337.563683 -350.1044) (xy 337.564222 -350.133412) (xy 337.563824 -350.15424) (xy 337.765644 -350.15424)
			(xy 337.766188 -350.125228) (xy 337.774952 -350.06787) (xy 337.792301 -350.012501) (xy 337.817833 -349.960397)
			(xy 337.85096 -349.912759) (xy 337.870546 -349.89135) (xy 337.880781 -349.879772) (xy 337.894365 -349.852032)
			(xy 337.899035 -349.8215) (xy 337.894365 -349.790968) (xy 337.880781 -349.763228) (xy 337.870546 -349.75165)
			(xy 337.850977 -349.730227) (xy 337.81786 -349.682586) (xy 337.79233 -349.630485) (xy 337.774972 -349.575122)
			(xy 337.766188 -349.51777) (xy 337.765644 -349.48876) (xy 337.76614 -349.46151) (xy 337.773901 -349.407565)
			(xy 337.789259 -349.355274) (xy 337.811901 -349.305699) (xy 337.841367 -349.259851) (xy 337.877057 -349.218663)
			(xy 337.918245 -349.182972) (xy 337.964092 -349.153505) (xy 338.013666 -349.130862) (xy 338.065957 -349.115503)
			(xy 338.119902 -349.107741) (xy 338.147152 -349.107252) (xy 338.176069 -349.107785) (xy 338.23324 -349.116508)
			(xy 338.288439 -349.133762) (xy 338.340402 -349.159151) (xy 338.387936 -349.192093) (xy 338.429952 -349.231833)
			(xy 338.448142 -349.254318) (xy 338.458039 -349.266123) (xy 338.483363 -349.283642) (xy 338.512756 -349.292818)
			(xy 338.543548 -349.292818) (xy 338.572941 -349.283642) (xy 338.598265 -349.266123) (xy 338.608162 -349.254318)
			(xy 338.624915 -349.233535) (xy 338.663269 -349.196405) (xy 338.706423 -349.164983) (xy 338.753537 -349.139884)
			(xy 338.803689 -349.121598) (xy 338.8559 -349.110481) (xy 338.909152 -349.106751) (xy 338.962404 -349.110481)
			(xy 339.014615 -349.121598) (xy 339.064767 -349.139884) (xy 339.111881 -349.164983) (xy 339.155035 -349.196405)
			(xy 339.193389 -349.233535) (xy 339.210142 -349.254318) (xy 339.220039 -349.266123) (xy 339.245363 -349.283642)
			(xy 339.274756 -349.292818) (xy 339.305548 -349.292818) (xy 339.334941 -349.283642) (xy 339.360265 -349.266123)
			(xy 339.370162 -349.254318) (xy 339.386915 -349.233535) (xy 339.425269 -349.196405) (xy 339.468423 -349.164983)
			(xy 339.515537 -349.139884) (xy 339.565689 -349.121598) (xy 339.6179 -349.110481) (xy 339.671152 -349.106751)
			(xy 339.724404 -349.110481) (xy 339.776615 -349.121598) (xy 339.826767 -349.139884) (xy 339.873881 -349.164983)
			(xy 339.917035 -349.196405) (xy 339.955389 -349.233535) (xy 339.972142 -349.254318) (xy 339.982039 -349.266123)
			(xy 340.007363 -349.283642) (xy 340.036756 -349.292818) (xy 340.067548 -349.292818) (xy 340.096941 -349.283642)
			(xy 340.122265 -349.266123) (xy 340.132162 -349.254318) (xy 340.150379 -349.231856) (xy 340.192393 -349.192119)
			(xy 340.239922 -349.159177) (xy 340.291878 -349.133785) (xy 340.347072 -349.116524) (xy 340.404237 -349.10779)
			(xy 340.433152 -349.107252) (xy 340.461719 -349.107782) (xy 340.518214 -349.116316) (xy 340.572807 -349.133169)
			(xy 340.624281 -349.157966) (xy 340.671487 -349.190155) (xy 340.713371 -349.229015) (xy 340.731602 -349.251016)
			(xy 340.741172 -349.262259) (xy 340.765411 -349.279096) (xy 340.793451 -349.288307) (xy 340.822953 -349.289124)
			(xy 340.851459 -349.281478) (xy 340.876593 -349.266006) (xy 340.886796 -349.255334) (xy 340.904952 -349.235705)
			(xy 340.945838 -349.201247) (xy 340.991134 -349.172834) (xy 341.039954 -349.151024) (xy 341.09134 -349.136243)
			(xy 341.144287 -349.128782) (xy 341.171022 -349.128334) (xy 341.199937 -349.128896) (xy 341.257107 -349.137614)
			(xy 341.312306 -349.154862) (xy 341.364268 -349.180246) (xy 341.411803 -349.213183) (xy 341.453821 -349.252917)
			(xy 341.472012 -349.2754) (xy 341.481909 -349.287205) (xy 341.507233 -349.304724) (xy 341.536626 -349.3139)
			(xy 341.567418 -349.3139) (xy 341.596811 -349.304724) (xy 341.622135 -349.287205) (xy 341.632032 -349.2754)
			(xy 341.650205 -349.252901) (xy 341.692228 -349.213167) (xy 341.739767 -349.18023) (xy 341.791732 -349.154844)
			(xy 341.846933 -349.137591) (xy 341.904105 -349.128867) (xy 341.933022 -349.128334) (xy 341.960275 -349.128737)
			(xy 342.014227 -349.136497) (xy 342.066524 -349.151856) (xy 342.116104 -349.174501) (xy 342.161957 -349.203971)
			(xy 342.203149 -349.239666) (xy 342.238842 -349.280861) (xy 342.26831 -349.326715) (xy 342.290952 -349.376296)
			(xy 342.306307 -349.428595) (xy 342.314064 -349.482547) (xy 342.314064 -349.537053) (xy 342.306307 -349.591005)
			(xy 342.290952 -349.643304) (xy 342.26831 -349.692885) (xy 342.238842 -349.738739) (xy 342.203149 -349.779934)
			(xy 342.161957 -349.815629) (xy 342.116104 -349.845099) (xy 342.066524 -349.867744) (xy 342.014227 -349.883103)
			(xy 341.960275 -349.890863) (xy 341.933022 -349.89135) (xy 341.904105 -349.890835) (xy 341.846933 -349.882108)
			(xy 341.791733 -349.864851) (xy 341.739771 -349.839458) (xy 341.692237 -349.806513) (xy 341.650221 -349.766771)
			(xy 341.632032 -349.744284) (xy 341.622135 -349.732479) (xy 341.596811 -349.71496) (xy 341.567418 -349.705784)
			(xy 341.536626 -349.705784) (xy 341.507233 -349.71496) (xy 341.481909 -349.732479) (xy 341.472012 -349.744284)
			(xy 341.45381 -349.766758) (xy 341.411793 -349.806495) (xy 341.364261 -349.839435) (xy 341.312301 -349.864826)
			(xy 341.257106 -349.882084) (xy 341.199937 -349.890814) (xy 341.171022 -349.89135) (xy 341.142456 -349.890766)
			(xy 341.085964 -349.882244) (xy 341.031372 -349.865401) (xy 340.979898 -349.840614) (xy 340.932691 -349.808435)
			(xy 340.890804 -349.769583) (xy 340.872572 -349.747586) (xy 340.86303 -349.736318) (xy 340.838783 -349.71948)
			(xy 340.810736 -349.710272) (xy 340.781228 -349.70946) (xy 340.752717 -349.717113) (xy 340.727582 -349.732592)
			(xy 340.717378 -349.743268) (xy 340.699186 -349.762862) (xy 340.658307 -349.797323) (xy 340.613018 -349.82574)
			(xy 340.564206 -349.847556) (xy 340.512826 -349.862344) (xy 340.459885 -349.869815) (xy 340.433152 -349.870268)
			(xy 340.404236 -349.869725) (xy 340.347065 -349.861002) (xy 340.291866 -349.84375) (xy 340.239904 -349.818363)
			(xy 340.19237 -349.785424) (xy 340.150352 -349.745686) (xy 340.132162 -349.723202) (xy 340.122265 -349.711397)
			(xy 340.096941 -349.693878) (xy 340.067548 -349.684702) (xy 340.036756 -349.684702) (xy 340.007363 -349.693878)
			(xy 339.982039 -349.711397) (xy 339.972142 -349.723202) (xy 339.955389 -349.743985) (xy 339.917035 -349.781115)
			(xy 339.873881 -349.812537) (xy 339.826767 -349.837636) (xy 339.776615 -349.855922) (xy 339.724404 -349.867039)
			(xy 339.671152 -349.870769) (xy 339.6179 -349.867039) (xy 339.565689 -349.855922) (xy 339.515537 -349.837636)
			(xy 339.468423 -349.812537) (xy 339.425269 -349.781115) (xy 339.386915 -349.743985) (xy 339.370162 -349.723202)
			(xy 339.360265 -349.711397) (xy 339.334941 -349.693878) (xy 339.305548 -349.684702) (xy 339.274756 -349.684702)
			(xy 339.245363 -349.693878) (xy 339.220039 -349.711397) (xy 339.210142 -349.723202) (xy 339.193389 -349.743985)
			(xy 339.155035 -349.781115) (xy 339.111881 -349.812537) (xy 339.064767 -349.837636) (xy 339.014615 -349.855922)
			(xy 338.962404 -349.867039) (xy 338.909152 -349.870769) (xy 338.8559 -349.867039) (xy 338.803689 -349.855922)
			(xy 338.753537 -349.837636) (xy 338.706423 -349.812537) (xy 338.663269 -349.781115) (xy 338.624915 -349.743985)
			(xy 338.608162 -349.723202) (xy 338.598265 -349.711397) (xy 338.572941 -349.693878) (xy 338.543548 -349.684702)
			(xy 338.512756 -349.684702) (xy 338.483363 -349.693878) (xy 338.458039 -349.711397) (xy 338.448142 -349.723202)
			(xy 338.423758 -349.75165) (xy 338.413523 -349.763228) (xy 338.399939 -349.790968) (xy 338.395268 -349.8215)
			(xy 338.399939 -349.852032) (xy 338.413523 -349.879772) (xy 338.423758 -349.89135) (xy 338.443327 -349.912773)
			(xy 338.476444 -349.960414) (xy 338.501975 -350.012515) (xy 338.519332 -350.067878) (xy 338.528116 -350.12523)
			(xy 338.52866 -350.15424) (xy 338.528174 -350.181491) (xy 338.520418 -350.235439) (xy 338.505063 -350.287734)
			(xy 338.482421 -350.337311) (xy 338.452955 -350.383161) (xy 338.417264 -350.424352) (xy 338.376073 -350.460043)
			(xy 338.330223 -350.489509) (xy 338.280646 -350.512151) (xy 338.228351 -350.527506) (xy 338.174403 -350.535262)
			(xy 338.119901 -350.535262) (xy 338.065953 -350.527506) (xy 338.013658 -350.512151) (xy 337.964081 -350.489509)
			(xy 337.918231 -350.460043) (xy 337.87704 -350.424352) (xy 337.841349 -350.383161) (xy 337.811883 -350.337311)
			(xy 337.789241 -350.287734) (xy 337.773886 -350.235439) (xy 337.76613 -350.181491) (xy 337.765644 -350.15424)
			(xy 337.563824 -350.15424) (xy 337.56367 -350.162328) (xy 337.554952 -350.219499) (xy 337.537703 -350.274698)
			(xy 337.512318 -350.326661) (xy 337.479378 -350.374195) (xy 337.43964 -350.416212) (xy 337.417156 -350.434402)
			(xy 337.405335 -350.444284) (xy 337.38781 -350.46961) (xy 337.378631 -350.499008) (xy 337.378634 -350.529806)
			(xy 337.387816 -350.559204) (xy 337.405345 -350.584527) (xy 337.417156 -350.594422) (xy 337.439641 -350.612612)
			(xy 337.479378 -350.65463) (xy 337.512318 -350.702165) (xy 337.537707 -350.754127) (xy 337.554962 -350.809325)
			(xy 337.563689 -350.866496) (xy 337.564222 -350.895412) (xy 337.563848 -350.91624) (xy 342.433656 -350.91624)
			(xy 342.434182 -350.887323) (xy 342.442906 -350.830151) (xy 342.460161 -350.774952) (xy 342.485551 -350.722989)
			(xy 342.518495 -350.675455) (xy 342.558236 -350.633439) (xy 342.580722 -350.61525) (xy 342.592484 -350.605307)
			(xy 342.609996 -350.579994) (xy 342.619172 -350.550614) (xy 342.61918 -350.519835) (xy 342.610018 -350.49045)
			(xy 342.592518 -350.465129) (xy 342.580722 -350.45523) (xy 342.558257 -350.437016) (xy 342.51852 -350.395002)
			(xy 342.485578 -350.347472) (xy 342.460186 -350.295515) (xy 342.442926 -350.240321) (xy 342.434193 -350.183155)
			(xy 342.433656 -350.15424) (xy 342.434224 -350.125229) (xy 342.442986 -350.067874) (xy 342.46033 -350.012505)
			(xy 342.485856 -349.960401) (xy 342.518976 -349.912761) (xy 342.538558 -349.89135) (xy 342.548791 -349.879771)
			(xy 342.562374 -349.852032) (xy 342.567044 -349.8215) (xy 342.562374 -349.790968) (xy 342.548791 -349.763229)
			(xy 342.538558 -349.75165) (xy 342.518991 -349.730225) (xy 342.485874 -349.682585) (xy 342.460342 -349.630484)
			(xy 342.442985 -349.575121) (xy 342.4342 -349.51777) (xy 342.433656 -349.48876) (xy 342.43414 -349.461509)
			(xy 342.441902 -349.407564) (xy 342.45726 -349.355271) (xy 342.479903 -349.305696) (xy 342.50937 -349.259848)
			(xy 342.545062 -349.218659) (xy 342.586251 -349.182968) (xy 342.632099 -349.153501) (xy 342.681675 -349.130858)
			(xy 342.733967 -349.115501) (xy 342.787913 -349.10774) (xy 342.815164 -349.107252) (xy 342.844081 -349.107776)
			(xy 342.901253 -349.116501) (xy 342.956452 -349.133757) (xy 343.008415 -349.159147) (xy 343.055948 -349.192091)
			(xy 343.097965 -349.231832) (xy 343.116154 -349.254318) (xy 343.126051 -349.266123) (xy 343.151375 -349.283642)
			(xy 343.180768 -349.292818) (xy 343.21156 -349.292818) (xy 343.240953 -349.283642) (xy 343.266277 -349.266123)
			(xy 343.276174 -349.254318) (xy 343.294384 -349.231851) (xy 343.336399 -349.192114) (xy 343.38393 -349.159172)
			(xy 343.435888 -349.133781) (xy 343.491082 -349.116521) (xy 343.548249 -349.107789) (xy 343.577164 -349.107252)
			(xy 343.604413 -349.107812) (xy 343.658355 -349.115562) (xy 343.710646 -349.130911) (xy 343.760221 -349.153545)
			(xy 343.806069 -349.183003) (xy 343.847259 -349.218687) (xy 343.882951 -349.25987) (xy 343.912419 -349.305713)
			(xy 343.935063 -349.355282) (xy 343.950422 -349.40757) (xy 343.958183 -349.461512) (xy 343.958672 -349.48876)
			(xy 343.958124 -349.517772) (xy 343.94936 -349.575129) (xy 343.932012 -349.630498) (xy 343.906481 -349.682603)
			(xy 343.873356 -349.730241) (xy 343.85377 -349.75165) (xy 343.843534 -349.763227) (xy 343.829948 -349.790967)
			(xy 343.825277 -349.8215) (xy 343.829948 -349.852033) (xy 343.843534 -349.879773) (xy 343.85377 -349.89135)
			(xy 343.873341 -349.912771) (xy 343.906457 -349.960413) (xy 343.931987 -350.012514) (xy 343.949344 -350.067878)
			(xy 343.958128 -350.12523) (xy 343.958672 -350.15424) (xy 343.958121 -350.183156) (xy 343.949401 -350.240326)
			(xy 343.93215 -350.295525) (xy 343.906764 -350.347487) (xy 343.873826 -350.395021) (xy 343.834089 -350.437039)
			(xy 343.811606 -350.45523) (xy 343.799761 -350.465084) (xy 343.782246 -350.49042) (xy 343.773075 -350.519824)
			(xy 343.773082 -350.550625) (xy 343.782267 -350.580025) (xy 343.799795 -350.605352) (xy 343.811606 -350.61525)
			(xy 343.834067 -350.633468) (xy 343.873803 -350.675482) (xy 343.906745 -350.723012) (xy 343.932137 -350.774968)
			(xy 343.949398 -350.83016) (xy 343.958133 -350.887326) (xy 343.958672 -350.91624) (xy 343.958259 -350.943494)
			(xy 343.950496 -350.997446) (xy 343.935134 -351.049744) (xy 343.912486 -351.099324) (xy 343.883012 -351.145176)
			(xy 343.847313 -351.186367) (xy 343.806115 -351.222058) (xy 343.760257 -351.251522) (xy 343.710673 -351.274161)
			(xy 343.658372 -351.289513) (xy 343.604418 -351.297265) (xy 343.577164 -351.297748) (xy 343.548248 -351.297203)
			(xy 343.491077 -351.288482) (xy 343.435878 -351.271231) (xy 343.383916 -351.245844) (xy 343.336381 -351.212904)
			(xy 343.294364 -351.173166) (xy 343.276174 -351.150682) (xy 343.266277 -351.138877) (xy 343.240953 -351.121358)
			(xy 343.21156 -351.112182) (xy 343.180768 -351.112182) (xy 343.151375 -351.121358) (xy 343.126051 -351.138877)
			(xy 343.116154 -351.150682) (xy 343.097928 -351.173136) (xy 343.055916 -351.212874) (xy 343.008389 -351.245817)
			(xy 342.956434 -351.27121) (xy 342.901243 -351.288473) (xy 342.844078 -351.297209) (xy 342.815164 -351.297748)
			(xy 342.787914 -351.297256) (xy 342.733968 -351.289495) (xy 342.681676 -351.274138) (xy 342.632101 -351.251495)
			(xy 342.586253 -351.222029) (xy 342.545064 -351.186338) (xy 342.509373 -351.14515) (xy 342.479907 -351.099302)
			(xy 342.457264 -351.049728) (xy 342.441905 -350.997436) (xy 342.434144 -350.94349) (xy 342.433656 -350.91624)
			(xy 337.563848 -350.91624) (xy 337.563733 -350.922663) (xy 337.555976 -350.97661) (xy 337.54062 -351.028904)
			(xy 337.517978 -351.07848) (xy 337.488512 -351.12433) (xy 337.452821 -351.165519) (xy 337.411631 -351.201211)
			(xy 337.365782 -351.230677) (xy 337.316206 -351.253319) (xy 337.263912 -351.268675) (xy 337.209965 -351.276433)
			(xy 337.182714 -351.27692) (xy 337.153796 -351.276422) (xy 337.096622 -351.267693) (xy 337.041422 -351.250433)
			(xy 336.98946 -351.225038) (xy 336.941926 -351.192089) (xy 336.899912 -351.152342) (xy 336.881724 -351.129854)
			(xy 336.871827 -351.118049) (xy 336.846503 -351.10053) (xy 336.81711 -351.091354) (xy 336.786318 -351.091354)
			(xy 336.756925 -351.10053) (xy 336.731601 -351.118049) (xy 336.721704 -351.129854) (xy 336.703524 -351.152347)
			(xy 336.661501 -351.192079) (xy 336.613963 -351.225015) (xy 336.562 -351.250402) (xy 336.506801 -351.267656)
			(xy 336.44963 -351.276385) (xy 336.420714 -351.27692) (xy 336.393462 -351.276432) (xy 336.339513 -351.268677)
			(xy 336.287216 -351.253323) (xy 336.237637 -351.230683) (xy 336.191784 -351.201218) (xy 336.150592 -351.165527)
			(xy 336.114898 -351.124337) (xy 336.085429 -351.078486) (xy 336.062786 -351.028908) (xy 336.047429 -350.976613)
			(xy 336.03967 -350.922664) (xy 336.039206 -350.895412) (xy 320.918332 -350.895412) (xy 320.918332 -354.083112)
			(xy 349.389698 -354.083112) (xy 349.393769 -354.02749) (xy 349.405895 -353.973053) (xy 349.425818 -353.920962)
			(xy 349.453114 -353.872327) (xy 349.4872 -353.828184) (xy 349.527349 -353.789475) (xy 349.572707 -353.757024)
			(xy 349.622307 -353.731523) (xy 349.675091 -353.713516) (xy 349.729934 -353.703386) (xy 349.785668 -353.701349)
			(xy 349.841105 -353.707449) (xy 349.895062 -353.721555) (xy 349.946391 -353.743367) (xy 349.993997 -353.772421)
			(xy 350.036865 -353.808096) (xy 350.074082 -353.849633) (xy 350.104855 -353.896146) (xy 350.128527 -353.946643)
			(xy 350.144595 -354.00005) (xy 350.152715 -354.055226) (xy 350.153224 -354.083112) (xy 350.152715 -354.110998)
			(xy 350.144595 -354.166174) (xy 350.128527 -354.219581) (xy 350.104855 -354.270078) (xy 350.074082 -354.316591)
			(xy 350.036865 -354.358128) (xy 349.993997 -354.393803) (xy 349.946391 -354.422857) (xy 349.895062 -354.444669)
			(xy 349.841105 -354.458775) (xy 349.785668 -354.464875) (xy 349.729934 -354.462838) (xy 349.675091 -354.452708)
			(xy 349.622307 -354.434701) (xy 349.572707 -354.4092) (xy 349.527349 -354.376749) (xy 349.4872 -354.33804)
			(xy 349.453114 -354.293897) (xy 349.425818 -354.245262) (xy 349.405895 -354.193171) (xy 349.393769 -354.138734)
			(xy 349.389698 -354.083112) (xy 320.918332 -354.083112) (xy 320.918332 -356.89365) (xy 336.912199 -356.89365)
			(xy 336.912199 -356.83915) (xy 336.919955 -356.785205) (xy 336.93531 -356.732913) (xy 336.95795 -356.683338)
			(xy 336.987415 -356.63749) (xy 337.023105 -356.596302) (xy 337.064293 -356.560613) (xy 337.110142 -356.531148)
			(xy 337.159717 -356.508508) (xy 337.212009 -356.493155) (xy 337.265954 -356.485399) (xy 337.293204 -356.484936)
			(xy 337.319273 -356.485399) (xy 337.370924 -356.492507) (xy 337.421127 -356.506577) (xy 337.468949 -356.527347)
			(xy 337.5135 -356.55443) (xy 337.553953 -356.587323) (xy 337.589553 -356.625414) (xy 337.619639 -356.667995)
			(xy 337.63204 -356.69093) (xy 337.638853 -356.703047) (xy 337.65782 -356.723352) (xy 337.681561 -356.737788)
			(xy 337.708317 -356.745284) (xy 337.736103 -356.745284) (xy 337.762859 -356.737788) (xy 337.7866 -356.723352)
			(xy 337.805567 -356.703047) (xy 337.81238 -356.69093) (xy 337.825437 -356.666805) (xy 337.857419 -356.622237)
			(xy 337.895431 -356.582687) (xy 337.916774 -356.565454) (xy 337.928536 -356.555509) (xy 337.946057 -356.530199)
			(xy 337.955239 -356.500818) (xy 337.955247 -356.470036) (xy 337.946081 -356.44065) (xy 337.928574 -356.41533)
			(xy 337.916774 -356.405434) (xy 337.894301 -356.38723) (xy 337.854567 -356.345212) (xy 337.821627 -356.29768)
			(xy 337.796237 -356.245721) (xy 337.778978 -356.190526) (xy 337.770245 -356.133359) (xy 337.769708 -356.104444)
			(xy 337.770196 -356.077192) (xy 337.777948 -356.023241) (xy 337.793299 -355.970942) (xy 337.815937 -355.921361)
			(xy 337.845402 -355.875507) (xy 337.881094 -355.834314) (xy 337.922285 -355.798619) (xy 337.968137 -355.769151)
			(xy 338.017716 -355.746509) (xy 338.070013 -355.731154) (xy 338.123964 -355.723398) (xy 338.151216 -355.722936)
			(xy 338.180131 -355.723501) (xy 338.237301 -355.732219) (xy 338.292499 -355.749466) (xy 338.344462 -355.774849)
			(xy 338.391997 -355.807785) (xy 338.434015 -355.84752) (xy 338.452206 -355.870002) (xy 338.462103 -355.881807)
			(xy 338.487427 -355.899326) (xy 338.51682 -355.908502) (xy 338.547612 -355.908502) (xy 338.577005 -355.899326)
			(xy 338.602329 -355.881807) (xy 338.612226 -355.870002) (xy 338.628979 -355.849219) (xy 338.667333 -355.812089)
			(xy 338.710487 -355.780667) (xy 338.757601 -355.755568) (xy 338.807753 -355.737282) (xy 338.859964 -355.726165)
			(xy 338.913216 -355.722435) (xy 338.966468 -355.726165) (xy 339.018679 -355.737282) (xy 339.068831 -355.755568)
			(xy 339.115945 -355.780667) (xy 339.159099 -355.812089) (xy 339.197453 -355.849219) (xy 339.214206 -355.870002)
			(xy 339.224103 -355.881807) (xy 339.249427 -355.899326) (xy 339.27882 -355.908502) (xy 339.309612 -355.908502)
			(xy 339.339005 -355.899326) (xy 339.364329 -355.881807) (xy 339.374226 -355.870002) (xy 339.390979 -355.849219)
			(xy 339.429333 -355.812089) (xy 339.472487 -355.780667) (xy 339.519601 -355.755568) (xy 339.569753 -355.737282)
			(xy 339.621964 -355.726165) (xy 339.675216 -355.722435) (xy 339.728468 -355.726165) (xy 339.780679 -355.737282)
			(xy 339.830831 -355.755568) (xy 339.877945 -355.780667) (xy 339.921099 -355.812089) (xy 339.959453 -355.849219)
			(xy 339.976206 -355.870002) (xy 339.986103 -355.881807) (xy 340.011427 -355.899326) (xy 340.04082 -355.908502)
			(xy 340.071612 -355.908502) (xy 340.101005 -355.899326) (xy 340.126329 -355.881807) (xy 340.136226 -355.870002)
			(xy 340.152979 -355.849219) (xy 340.191333 -355.812089) (xy 340.234487 -355.780667) (xy 340.281601 -355.755568)
			(xy 340.331753 -355.737282) (xy 340.383964 -355.726165) (xy 340.437216 -355.722435) (xy 340.490468 -355.726165)
			(xy 340.542679 -355.737282) (xy 340.592831 -355.755568) (xy 340.639945 -355.780667) (xy 340.683099 -355.812089)
			(xy 340.721453 -355.849219) (xy 340.738206 -355.870002) (xy 340.748103 -355.881807) (xy 340.773427 -355.899326)
			(xy 340.80282 -355.908502) (xy 340.833612 -355.908502) (xy 340.863005 -355.899326) (xy 340.888329 -355.881807)
			(xy 340.898226 -355.870002) (xy 340.914979 -355.849219) (xy 340.953333 -355.812089) (xy 340.996487 -355.780667)
			(xy 341.043601 -355.755568) (xy 341.093753 -355.737282) (xy 341.145964 -355.726165) (xy 341.199216 -355.722435)
			(xy 341.252468 -355.726165) (xy 341.304679 -355.737282) (xy 341.354831 -355.755568) (xy 341.401945 -355.780667)
			(xy 341.445099 -355.812089) (xy 341.483453 -355.849219) (xy 341.500206 -355.870002) (xy 341.510103 -355.881807)
			(xy 341.535427 -355.899326) (xy 341.56482 -355.908502) (xy 341.595612 -355.908502) (xy 341.625005 -355.899326)
			(xy 341.650329 -355.881807) (xy 341.660226 -355.870002) (xy 341.678403 -355.847506) (xy 341.720425 -355.807772)
			(xy 341.767963 -355.774834) (xy 341.819927 -355.749448) (xy 341.875127 -355.732194) (xy 341.932299 -355.723469)
			(xy 341.961216 -355.722936) (xy 341.987469 -355.723337) (xy 342.03948 -355.730528) (xy 342.090012 -355.744786)
			(xy 342.138112 -355.76584) (xy 342.182868 -355.793294) (xy 342.223436 -355.826627) (xy 342.259047 -355.86521)
			(xy 342.274398 -355.886512) (xy 342.282762 -355.897725) (xy 342.304387 -355.915451) (xy 342.330011 -355.926648)
			(xy 342.35771 -355.930476) (xy 342.385409 -355.926648) (xy 342.411033 -355.915451) (xy 342.432658 -355.897725)
			(xy 342.441022 -355.886512) (xy 342.456356 -355.865201) (xy 342.491981 -355.826635) (xy 342.532557 -355.793316)
			(xy 342.577317 -355.765873) (xy 342.625416 -355.744825) (xy 342.675946 -355.730568) (xy 342.727953 -355.723372)
			(xy 342.754204 -355.722936) (xy 342.784327 -355.723508) (xy 342.843823 -355.73299) (xy 342.901091 -355.7517)
			(xy 342.954708 -355.779176) (xy 343.003343 -355.814733) (xy 343.024968 -355.835712) (xy 343.03469 -355.84493)
			(xy 343.057852 -355.858375) (xy 343.083713 -355.865337) (xy 343.110495 -355.865337) (xy 343.136356 -355.858375)
			(xy 343.159518 -355.84493) (xy 343.16924 -355.835712) (xy 343.19087 -355.814737) (xy 343.239497 -355.779168)
			(xy 343.293112 -355.751687) (xy 343.350382 -355.732977) (xy 343.40988 -355.723505) (xy 343.440004 -355.722936)
			(xy 343.467259 -355.723352) (xy 343.521214 -355.73111) (xy 343.573515 -355.746469) (xy 343.623098 -355.769115)
			(xy 343.668954 -355.798588) (xy 343.710147 -355.834287) (xy 343.745841 -355.875485) (xy 343.775308 -355.921344)
			(xy 343.797948 -355.97093) (xy 343.8133 -356.023233) (xy 343.821052 -356.077189) (xy 343.821512 -356.104444)
			(xy 343.820987 -356.133361) (xy 343.812264 -356.190533) (xy 343.795009 -356.245734) (xy 343.769619 -356.297696)
			(xy 343.736675 -356.34523) (xy 343.696932 -356.387245) (xy 343.674446 -356.405434) (xy 343.662593 -356.415281)
			(xy 343.645071 -356.440617) (xy 343.635897 -356.470024) (xy 343.635905 -356.500829) (xy 343.645095 -356.530232)
			(xy 343.662631 -356.555558) (xy 343.674446 -356.565454) (xy 343.696917 -356.583659) (xy 343.736651 -356.625678)
			(xy 343.76959 -356.67321) (xy 343.79498 -356.725168) (xy 343.81224 -356.780362) (xy 343.820974 -356.837529)
			(xy 343.821512 -356.866444) (xy 343.821063 -356.893696) (xy 343.813301 -356.947645) (xy 343.79794 -356.99994)
			(xy 343.775294 -357.049517) (xy 343.745824 -357.095367) (xy 343.710129 -357.136557) (xy 343.668935 -357.172248)
			(xy 343.623082 -357.201713) (xy 343.573503 -357.224354) (xy 343.521206 -357.239709) (xy 343.467256 -357.247466)
			(xy 343.440004 -357.247952) (xy 343.409881 -357.247378) (xy 343.350384 -357.237898) (xy 343.293117 -357.219188)
			(xy 343.2395 -357.191712) (xy 343.190865 -357.156155) (xy 343.16924 -357.135176) (xy 343.159518 -357.125958)
			(xy 343.136356 -357.112513) (xy 343.110495 -357.105551) (xy 343.083713 -357.105551) (xy 343.057852 -357.112513)
			(xy 343.03469 -357.125958) (xy 343.024968 -357.135176) (xy 343.003332 -357.156145) (xy 342.954707 -357.191715)
			(xy 342.901093 -357.219198) (xy 342.843825 -357.237909) (xy 342.784328 -357.247383) (xy 342.754204 -357.247952)
			(xy 342.727951 -357.247541) (xy 342.675941 -357.240352) (xy 342.625408 -357.226097) (xy 342.577309 -357.205044)
			(xy 342.532552 -357.177592) (xy 342.491984 -357.14426) (xy 342.456373 -357.105677) (xy 342.441022 -357.084376)
			(xy 342.432658 -357.073163) (xy 342.411033 -357.055437) (xy 342.385409 -357.04424) (xy 342.35771 -357.040412)
			(xy 342.330011 -357.04424) (xy 342.304387 -357.055437) (xy 342.282762 -357.073163) (xy 342.274398 -357.084376)
			(xy 342.259048 -357.105675) (xy 342.223426 -357.144242) (xy 342.182853 -357.177562) (xy 342.138096 -357.205006)
			(xy 342.09 -357.226057) (xy 342.039472 -357.240316) (xy 341.987467 -357.247514) (xy 341.961216 -357.247952)
			(xy 341.932299 -357.24744) (xy 341.875126 -357.238713) (xy 341.819927 -357.221454) (xy 341.767964 -357.196062)
			(xy 341.720431 -357.163116) (xy 341.678415 -357.123373) (xy 341.660226 -357.100886) (xy 341.650329 -357.089081)
			(xy 341.625005 -357.071562) (xy 341.595612 -357.062386) (xy 341.56482 -357.062386) (xy 341.535427 -357.071562)
			(xy 341.510103 -357.089081) (xy 341.500206 -357.100886) (xy 341.483453 -357.121669) (xy 341.445099 -357.158799)
			(xy 341.401945 -357.190221) (xy 341.354831 -357.21532) (xy 341.304679 -357.233606) (xy 341.252468 -357.244723)
			(xy 341.199216 -357.248453) (xy 341.145964 -357.244723) (xy 341.093753 -357.233606) (xy 341.043601 -357.21532)
			(xy 340.996487 -357.190221) (xy 340.953333 -357.158799) (xy 340.914979 -357.121669) (xy 340.898226 -357.100886)
			(xy 340.888329 -357.089081) (xy 340.863005 -357.071562) (xy 340.833612 -357.062386) (xy 340.80282 -357.062386)
			(xy 340.773427 -357.071562) (xy 340.748103 -357.089081) (xy 340.738206 -357.100886) (xy 340.721453 -357.121669)
			(xy 340.683099 -357.158799) (xy 340.639945 -357.190221) (xy 340.592831 -357.21532) (xy 340.542679 -357.233606)
			(xy 340.490468 -357.244723) (xy 340.437216 -357.248453) (xy 340.383964 -357.244723) (xy 340.331753 -357.233606)
			(xy 340.281601 -357.21532) (xy 340.234487 -357.190221) (xy 340.191333 -357.158799) (xy 340.152979 -357.121669)
			(xy 340.136226 -357.100886) (xy 340.126329 -357.089081) (xy 340.101005 -357.071562) (xy 340.071612 -357.062386)
			(xy 340.04082 -357.062386) (xy 340.011427 -357.071562) (xy 339.986103 -357.089081) (xy 339.976206 -357.100886)
			(xy 339.959453 -357.121669) (xy 339.921099 -357.158799) (xy 339.877945 -357.190221) (xy 339.830831 -357.21532)
			(xy 339.780679 -357.233606) (xy 339.728468 -357.244723) (xy 339.675216 -357.248453) (xy 339.621964 -357.244723)
			(xy 339.569753 -357.233606) (xy 339.519601 -357.21532) (xy 339.472487 -357.190221) (xy 339.429333 -357.158799)
			(xy 339.390979 -357.121669) (xy 339.374226 -357.100886) (xy 339.364329 -357.089081) (xy 339.339005 -357.071562)
			(xy 339.309612 -357.062386) (xy 339.27882 -357.062386) (xy 339.249427 -357.071562) (xy 339.224103 -357.089081)
			(xy 339.214206 -357.100886) (xy 339.197453 -357.121669) (xy 339.159099 -357.158799) (xy 339.115945 -357.190221)
			(xy 339.068831 -357.21532) (xy 339.018679 -357.233606) (xy 338.966468 -357.244723) (xy 338.913216 -357.248453)
			(xy 338.859964 -357.244723) (xy 338.807753 -357.233606) (xy 338.757601 -357.21532) (xy 338.710487 -357.190221)
			(xy 338.667333 -357.158799) (xy 338.628979 -357.121669) (xy 338.612226 -357.100886) (xy 338.602329 -357.089081)
			(xy 338.577005 -357.071562) (xy 338.547612 -357.062386) (xy 338.51682 -357.062386) (xy 338.487427 -357.071562)
			(xy 338.462103 -357.089081) (xy 338.452206 -357.100886) (xy 338.434008 -357.123364) (xy 338.39199 -357.1631)
			(xy 338.344457 -357.19604) (xy 338.292497 -357.221429) (xy 338.2373 -357.238687) (xy 338.180132 -357.247417)
			(xy 338.151216 -357.247952) (xy 338.125148 -357.247479) (xy 338.073497 -357.240373) (xy 338.023293 -357.226305)
			(xy 337.975471 -357.205538) (xy 337.93092 -357.178456) (xy 337.890467 -357.145564) (xy 337.854867 -357.107473)
			(xy 337.82478 -357.064893) (xy 337.81238 -357.041958) (xy 337.805567 -357.029841) (xy 337.7866 -357.009536)
			(xy 337.762859 -356.9951) (xy 337.736103 -356.987604) (xy 337.708317 -356.987604) (xy 337.681561 -356.9951)
			(xy 337.65782 -357.009536) (xy 337.638853 -357.029841) (xy 337.63204 -357.041958) (xy 337.619684 -357.064922)
			(xy 337.589607 -357.107522) (xy 337.554009 -357.145628) (xy 337.513553 -357.178532) (xy 337.468992 -357.20562)
			(xy 337.421158 -357.226386) (xy 337.370941 -357.240445) (xy 337.319278 -357.247534) (xy 337.293204 -357.247952)
			(xy 337.265954 -357.247401) (xy 337.212009 -357.239645) (xy 337.159717 -357.224292) (xy 337.110142 -357.201652)
			(xy 337.064293 -357.172187) (xy 337.023105 -357.136498) (xy 336.987415 -357.09531) (xy 336.95795 -357.049462)
			(xy 336.93531 -356.999887) (xy 336.919955 -356.947595) (xy 336.912199 -356.89365) (xy 320.918332 -356.89365)
			(xy 320.918332 -358.14762) (xy 322.009514 -359.238802) (xy 335.453223 -359.238802) (xy 335.456952 -359.18555)
			(xy 335.46807 -359.133337) (xy 335.486358 -359.083185) (xy 335.511459 -359.036072) (xy 335.542884 -358.992918)
			(xy 335.580018 -358.954566) (xy 335.600802 -358.937814) (xy 335.612602 -358.927911) (xy 335.630117 -358.902589)
			(xy 335.639292 -358.873197) (xy 335.639292 -358.842407) (xy 335.630119 -358.813016) (xy 335.612605 -358.787692)
			(xy 335.600802 -358.777794) (xy 335.578316 -358.759606) (xy 335.538581 -358.717586) (xy 335.505642 -358.67005)
			(xy 335.480254 -358.618088) (xy 335.462999 -358.56289) (xy 335.45427 -358.50572) (xy 335.453736 -358.476804)
			(xy 335.454159 -358.449549) (xy 335.461917 -358.395595) (xy 335.477275 -358.343293) (xy 335.49992 -358.29371)
			(xy 335.529391 -358.247855) (xy 335.565089 -358.206661) (xy 335.606287 -358.170967) (xy 335.652145 -358.141501)
			(xy 335.701731 -358.118861) (xy 335.754034 -358.103508) (xy 335.807989 -358.095756) (xy 335.835244 -358.095296)
			(xy 335.864296 -358.095875) (xy 335.92173 -358.104666) (xy 335.977166 -358.122067) (xy 336.029321 -358.147676)
			(xy 336.076988 -358.1809) (xy 336.119063 -358.220971) (xy 336.13725 -358.243632) (xy 336.146504 -358.254707)
			(xy 336.169828 -358.271677) (xy 336.196969 -358.281442) (xy 336.225758 -358.283222) (xy 336.253895 -358.276877)
			(xy 336.279133 -358.262911) (xy 336.28965 -358.25303) (xy 336.298332 -358.244396) (xy 336.316634 -358.228128)
			(xy 336.326226 -358.220518) (xy 336.33802 -358.21061) (xy 336.355531 -358.185287) (xy 336.364703 -358.155898)
			(xy 336.364705 -358.125111) (xy 336.355535 -358.095721) (xy 336.338026 -358.070397) (xy 336.326226 -358.060498)
			(xy 336.303747 -358.042302) (xy 336.26401 -358.000284) (xy 336.23107 -357.95275) (xy 336.205681 -357.90079)
			(xy 336.188424 -357.845593) (xy 336.179695 -357.788424) (xy 336.17916 -357.759508) (xy 336.179685 -357.732258)
			(xy 336.18744 -357.678314) (xy 336.202792 -357.626022) (xy 336.22543 -357.576447) (xy 336.254893 -357.530598)
			(xy 336.29058 -357.489408) (xy 336.331766 -357.453717) (xy 336.377611 -357.424249) (xy 336.427184 -357.401606)
			(xy 336.479475 -357.386248) (xy 336.533418 -357.378488) (xy 336.560668 -357.378) (xy 336.588047 -357.378477)
			(xy 336.64224 -357.386314) (xy 336.694757 -357.401816) (xy 336.744519 -357.424665) (xy 336.790505 -357.454393)
			(xy 336.831769 -357.490388) (xy 336.849974 -357.510842) (xy 336.860022 -357.521832) (xy 336.885087 -357.537887)
			(xy 336.913716 -357.54604) (xy 336.943479 -357.545599) (xy 336.971854 -357.536602) (xy 336.996433 -357.519812)
			(xy 337.006184 -357.508556) (xy 337.024421 -357.486776) (xy 337.066213 -357.448305) (xy 337.113247 -357.416454)
			(xy 337.164482 -357.391927) (xy 337.218787 -357.375267) (xy 337.274962 -357.366841) (xy 337.303364 -357.366316)
			(xy 337.331062 -357.366795) (xy 337.385876 -357.374797) (xy 337.438957 -357.390639) (xy 337.489191 -357.413988)
			(xy 337.535522 -357.444352) (xy 337.576978 -357.481096) (xy 337.59521 -357.501952) (xy 337.604729 -357.512643)
			(xy 337.628495 -357.528585) (xy 337.655753 -357.537301) (xy 337.684359 -357.538106) (xy 337.712064 -357.530938)
			(xy 337.736689 -357.516359) (xy 337.746848 -357.50627) (xy 337.764952 -357.487755) (xy 337.805259 -357.455249)
			(xy 337.849593 -357.428494) (xy 337.897138 -357.407982) (xy 337.947021 -357.394091) (xy 337.998325 -357.387075)
			(xy 338.024216 -357.386636) (xy 338.051471 -357.38704) (xy 338.105427 -357.3948) (xy 338.157728 -357.410161)
			(xy 338.207312 -357.432808) (xy 338.253167 -357.462282) (xy 338.29436 -357.497982) (xy 338.330054 -357.539181)
			(xy 338.35952 -357.585041) (xy 338.38216 -357.634628) (xy 338.397512 -357.686932) (xy 338.405264 -357.740889)
			(xy 338.405724 -357.768144) (xy 338.405194 -357.797061) (xy 338.396471 -357.854233) (xy 338.379218 -357.909433)
			(xy 338.353828 -357.961395) (xy 338.320885 -358.008929) (xy 338.281144 -358.050945) (xy 338.258658 -358.069134)
			(xy 338.246804 -358.078981) (xy 338.22928 -358.104316) (xy 338.220104 -358.133724) (xy 338.220112 -358.16453)
			(xy 338.229303 -358.193933) (xy 338.246842 -358.219259) (xy 338.258658 -358.229154) (xy 338.281111 -358.247382)
			(xy 338.32085 -358.289392) (xy 338.353794 -358.336919) (xy 338.379188 -358.388874) (xy 338.39645 -358.444065)
			(xy 338.405186 -358.50123) (xy 338.405724 -358.530144) (xy 338.405225 -358.557347) (xy 338.397493 -358.611202)
			(xy 338.382179 -358.663409) (xy 338.359595 -358.712906) (xy 338.330198 -358.758688) (xy 338.31276 -358.779572)
			(xy 338.303282 -358.791464) (xy 338.291054 -358.819286) (xy 338.287557 -358.849474) (xy 338.293099 -358.879354)
			(xy 338.307191 -358.906279) (xy 338.328583 -358.927865) (xy 338.341716 -358.935528) (xy 338.364879 -358.948451)
			(xy 338.407693 -358.979759) (xy 338.445736 -359.016719) (xy 338.462366 -359.037382) (xy 338.472263 -359.049187)
			(xy 338.497587 -359.066706) (xy 338.52698 -359.075882) (xy 338.557772 -359.075882) (xy 338.587165 -359.066706)
			(xy 338.612489 -359.049187) (xy 338.622386 -359.037382) (xy 338.639139 -359.016599) (xy 338.677493 -358.979469)
			(xy 338.720647 -358.948047) (xy 338.767761 -358.922948) (xy 338.817913 -358.904662) (xy 338.870124 -358.893545)
			(xy 338.923376 -358.889815) (xy 338.976628 -358.893545) (xy 339.028839 -358.904662) (xy 339.078991 -358.922948)
			(xy 339.126105 -358.948047) (xy 339.169259 -358.979469) (xy 339.207613 -359.016599) (xy 339.224366 -359.037382)
			(xy 339.234263 -359.049187) (xy 339.259587 -359.066706) (xy 339.28898 -359.075882) (xy 339.319772 -359.075882)
			(xy 339.349165 -359.066706) (xy 339.374489 -359.049187) (xy 339.384386 -359.037382) (xy 339.401139 -359.016599)
			(xy 339.439493 -358.979469) (xy 339.482647 -358.948047) (xy 339.529761 -358.922948) (xy 339.579913 -358.904662)
			(xy 339.632124 -358.893545) (xy 339.685376 -358.889815) (xy 339.738628 -358.893545) (xy 339.790839 -358.904662)
			(xy 339.840991 -358.922948) (xy 339.888105 -358.948047) (xy 339.931259 -358.979469) (xy 339.969613 -359.016599)
			(xy 339.986366 -359.037382) (xy 339.996263 -359.049187) (xy 340.021587 -359.066706) (xy 340.05098 -359.075882)
			(xy 340.081772 -359.075882) (xy 340.111165 -359.066706) (xy 340.136489 -359.049187) (xy 340.146386 -359.037382)
			(xy 340.163139 -359.016599) (xy 340.201493 -358.979469) (xy 340.244647 -358.948047) (xy 340.291761 -358.922948)
			(xy 340.341913 -358.904662) (xy 340.394124 -358.893545) (xy 340.447376 -358.889815) (xy 340.500628 -358.893545)
			(xy 340.552839 -358.904662) (xy 340.602991 -358.922948) (xy 340.650105 -358.948047) (xy 340.693259 -358.979469)
			(xy 340.731613 -359.016599) (xy 340.748366 -359.037382) (xy 340.758263 -359.049187) (xy 340.783587 -359.066706)
			(xy 340.81298 -359.075882) (xy 340.843772 -359.075882) (xy 340.873165 -359.066706) (xy 340.898489 -359.049187)
			(xy 340.908386 -359.037382) (xy 340.925139 -359.016599) (xy 340.963493 -358.979469) (xy 341.006647 -358.948047)
			(xy 341.053761 -358.922948) (xy 341.103913 -358.904662) (xy 341.156124 -358.893545) (xy 341.209376 -358.889815)
			(xy 341.262628 -358.893545) (xy 341.314839 -358.904662) (xy 341.364991 -358.922948) (xy 341.412105 -358.948047)
			(xy 341.455259 -358.979469) (xy 341.493613 -359.016599) (xy 341.510366 -359.037382) (xy 341.520263 -359.049187)
			(xy 341.545587 -359.066706) (xy 341.57498 -359.075882) (xy 341.605772 -359.075882) (xy 341.635165 -359.066706)
			(xy 341.660489 -359.049187) (xy 341.670386 -359.037382) (xy 341.688207 -359.015359) (xy 341.729273 -358.976336)
			(xy 341.752174 -358.959658) (xy 341.764272 -358.950505) (xy 341.782866 -358.926555) (xy 341.793608 -358.8982)
			(xy 341.795551 -358.867941) (xy 341.788523 -358.838446) (xy 341.773144 -358.812314) (xy 341.762334 -358.80167)
			(xy 341.743114 -358.783539) (xy 341.709397 -358.742857) (xy 341.681616 -358.697912) (xy 341.660303 -358.649563)
			(xy 341.645864 -358.598736) (xy 341.638575 -358.546403) (xy 341.638128 -358.519984) (xy 341.638696 -358.491069)
			(xy 341.647413 -358.4339) (xy 341.664661 -358.378701) (xy 341.690043 -358.326739) (xy 341.722978 -358.279204)
			(xy 341.762712 -358.237186) (xy 341.785194 -358.218994) (xy 341.797015 -358.209114) (xy 341.814531 -358.183785)
			(xy 341.823704 -358.154388) (xy 341.823701 -358.123593) (xy 341.814522 -358.094197) (xy 341.797001 -358.068872)
			(xy 341.785194 -358.058974) (xy 341.762697 -358.040799) (xy 341.722963 -357.998776) (xy 341.690026 -357.951238)
			(xy 341.66464 -357.899273) (xy 341.647386 -357.844073) (xy 341.638661 -357.786901) (xy 341.638128 -357.757984)
			(xy 341.63854 -357.730729) (xy 341.6463 -357.676774) (xy 341.66166 -357.624473) (xy 341.684307 -357.574891)
			(xy 341.71378 -357.529036) (xy 341.749479 -357.487842) (xy 341.790678 -357.452149) (xy 341.836536 -357.422682)
			(xy 341.886122 -357.400042) (xy 341.938425 -357.384689) (xy 341.992381 -357.376936) (xy 342.019636 -357.376476)
			(xy 342.0472 -357.376933) (xy 342.101756 -357.384854) (xy 342.154606 -357.400539) (xy 342.20465 -357.423664)
			(xy 342.250847 -357.453746) (xy 342.292236 -357.490161) (xy 342.310466 -357.510842) (xy 342.320577 -357.521809)
			(xy 342.345631 -357.537962) (xy 342.374281 -357.5462) (xy 342.404088 -357.545822) (xy 342.432519 -357.536859)
			(xy 342.457154 -357.520074) (xy 342.46693 -357.50881) (xy 342.485142 -357.486967) (xy 342.526959 -357.448426)
			(xy 342.574034 -357.416519) (xy 342.625322 -357.39195) (xy 342.679689 -357.375266) (xy 342.735929 -357.366836)
			(xy 342.764364 -357.366316) (xy 342.794486 -357.366919) (xy 342.85398 -357.376394) (xy 342.911248 -357.395098)
			(xy 342.964865 -357.422566) (xy 343.013502 -357.458117) (xy 343.035128 -357.479092) (xy 343.04485 -357.48831)
			(xy 343.068012 -357.501755) (xy 343.093873 -357.508717) (xy 343.120655 -357.508717) (xy 343.146516 -357.501755)
			(xy 343.169678 -357.48831) (xy 343.1794 -357.479092) (xy 343.201 -357.458085) (xy 343.249636 -357.422521)
			(xy 343.303259 -357.395046) (xy 343.360534 -357.376344) (xy 343.420038 -357.36688) (xy 343.450164 -357.366316)
			(xy 343.477417 -357.366789) (xy 343.531369 -357.374542) (xy 343.583668 -357.389894) (xy 343.63325 -357.412534)
			(xy 343.679104 -357.442001) (xy 343.720298 -357.477694) (xy 343.755992 -357.518886) (xy 343.78546 -357.56474)
			(xy 343.808102 -357.614321) (xy 343.823456 -357.666619) (xy 343.83121 -357.720571) (xy 343.831672 -357.747824)
			(xy 343.83111 -357.776739) (xy 343.822392 -357.833909) (xy 343.805143 -357.889108) (xy 343.77976 -357.94107)
			(xy 343.746823 -357.988605) (xy 343.707089 -358.030623) (xy 343.684606 -358.048814) (xy 343.672777 -358.058686)
			(xy 343.655261 -358.084017) (xy 343.646089 -358.113416) (xy 343.646093 -358.144213) (xy 343.655274 -358.17361)
			(xy 343.672798 -358.198936) (xy 343.684606 -358.208834) (xy 343.705414 -358.225558) (xy 343.742548 -358.263913)
			(xy 343.773972 -358.307071) (xy 343.799073 -358.354188) (xy 343.81736 -358.404344) (xy 343.828477 -358.456559)
			(xy 343.832205 -358.509815) (xy 343.828473 -358.56307) (xy 343.817352 -358.615285) (xy 343.799061 -358.665439)
			(xy 343.773957 -358.712554) (xy 343.742529 -358.755709) (xy 343.705392 -358.794062) (xy 343.684606 -358.810814)
			(xy 343.672777 -358.820686) (xy 343.655261 -358.846017) (xy 343.646089 -358.875416) (xy 343.646093 -358.906213)
			(xy 343.655274 -358.93561) (xy 343.672798 -358.960936) (xy 343.684606 -358.970834) (xy 343.705414 -358.987558)
			(xy 343.742548 -359.025913) (xy 343.773972 -359.069071) (xy 343.799073 -359.116188) (xy 343.81736 -359.166344)
			(xy 343.828477 -359.218559) (xy 343.832205 -359.271815) (xy 343.828473 -359.32507) (xy 343.817352 -359.377285)
			(xy 343.799061 -359.427439) (xy 343.773957 -359.474554) (xy 343.742529 -359.517709) (xy 343.705392 -359.556062)
			(xy 343.684606 -359.572814) (xy 343.672777 -359.582686) (xy 343.655261 -359.608017) (xy 343.646089 -359.637416)
			(xy 343.646093 -359.668213) (xy 343.655274 -359.69761) (xy 343.672798 -359.722936) (xy 343.684606 -359.732834)
			(xy 343.705414 -359.749558) (xy 343.742548 -359.787913) (xy 343.773972 -359.831071) (xy 343.799073 -359.878188)
			(xy 343.81736 -359.928344) (xy 343.828477 -359.980559) (xy 343.832205 -360.033815) (xy 343.828473 -360.08707)
			(xy 343.817352 -360.139285) (xy 343.799061 -360.189439) (xy 343.773957 -360.236554) (xy 343.742529 -360.279709)
			(xy 343.705392 -360.318062) (xy 343.684606 -360.334814) (xy 343.672777 -360.344686) (xy 343.655261 -360.370017)
			(xy 343.646089 -360.399416) (xy 343.646093 -360.430213) (xy 343.655274 -360.45961) (xy 343.672798 -360.484936)
			(xy 343.684606 -360.494834) (xy 343.707107 -360.513004) (xy 343.746841 -360.555029) (xy 343.779778 -360.602568)
			(xy 343.805163 -360.654533) (xy 343.822415 -360.709734) (xy 343.83114 -360.766907) (xy 343.831672 -360.795824)
			(xy 343.831267 -360.823079) (xy 343.823506 -360.877034) (xy 343.808145 -360.929335) (xy 343.785497 -360.978918)
			(xy 343.756023 -361.024773) (xy 343.720324 -361.065966) (xy 343.679125 -361.101659) (xy 343.633265 -361.131126)
			(xy 343.583679 -361.153766) (xy 343.531375 -361.169119) (xy 343.477419 -361.176872) (xy 343.450164 -361.177332)
			(xy 343.420835 -361.17678) (xy 343.362867 -361.167803) (xy 343.306955 -361.150067) (xy 343.254413 -361.123987)
			(xy 343.206477 -361.090179) (xy 343.164276 -361.049438) (xy 343.128803 -361.002721) (xy 343.114376 -360.97718)
			(xy 343.109557 -360.969235) (xy 343.095458 -360.957159) (xy 343.077983 -360.950894) (xy 343.059423 -360.951261)
			(xy 343.04221 -360.958212) (xy 343.035128 -360.964226) (xy 343.02319 -360.974894) (xy 343.013502 -360.983802)
			(xy 342.998565 -361.005455) (xy 342.98967 -361.030211) (xy 342.987408 -361.056418) (xy 342.991932 -361.082332)
			(xy 343.002939 -361.106223) (xy 343.010998 -361.116626) (xy 343.027386 -361.137204) (xy 343.054961 -361.182004)
			(xy 343.076115 -361.23017) (xy 343.090444 -361.280787) (xy 343.097678 -361.332893) (xy 343.09812 -361.359196)
			(xy 343.097619 -361.386447) (xy 343.089863 -361.440393) (xy 343.074509 -361.492687) (xy 343.051869 -361.542263)
			(xy 343.022404 -361.588113) (xy 342.986714 -361.629303) (xy 342.945526 -361.664995) (xy 342.899677 -361.694461)
			(xy 342.850102 -361.717103) (xy 342.797809 -361.732459) (xy 342.743863 -361.740217) (xy 342.716612 -361.740704)
			(xy 342.687694 -361.740214) (xy 342.630519 -361.731484) (xy 342.575318 -361.714223) (xy 342.523356 -361.688826)
			(xy 342.475823 -361.655876) (xy 342.43381 -361.616127) (xy 342.415622 -361.593638) (xy 342.405725 -361.581833)
			(xy 342.380401 -361.564314) (xy 342.351008 -361.555138) (xy 342.320216 -361.555138) (xy 342.290823 -361.564314)
			(xy 342.265499 -361.581833) (xy 342.255602 -361.593638) (xy 342.248333 -361.602813) (xy 342.232828 -361.620351)
			(xy 342.224614 -361.62869) (xy 342.214238 -361.639813) (xy 342.200039 -361.666701) (xy 342.19437 -361.696575)
			(xy 342.197731 -361.726795) (xy 342.209827 -361.754692) (xy 342.21928 -361.766612) (xy 342.236469 -361.78743)
			(xy 342.265387 -361.833019) (xy 342.287596 -361.882227) (xy 342.302652 -361.934073) (xy 342.310254 -361.987522)
			(xy 342.31072 -362.014516) (xy 342.310237 -362.041767) (xy 342.302479 -362.095714) (xy 342.287122 -362.148008)
			(xy 342.26448 -362.197585) (xy 342.235013 -362.243435) (xy 342.199322 -362.284624) (xy 342.158131 -362.320316)
			(xy 342.112281 -362.349782) (xy 342.062705 -362.372424) (xy 342.01041 -362.38778) (xy 341.956463 -362.395537)
			(xy 341.929212 -362.396024) (xy 341.901243 -362.395556) (xy 341.845902 -362.3874) (xy 341.792347 -362.371247)
			(xy 341.741726 -362.347444) (xy 341.695126 -362.3165) (xy 341.653546 -362.279081) (xy 341.635334 -362.257848)
			(xy 341.625758 -362.247132) (xy 341.601994 -362.231) (xy 341.574677 -362.222124) (xy 341.545969 -362.221208)
			(xy 341.518142 -362.228325) (xy 341.493398 -362.24291) (xy 341.483188 -362.253022) (xy 341.465075 -362.271613)
			(xy 341.424725 -362.30426) (xy 341.38032 -362.331132) (xy 341.33268 -362.351734) (xy 341.282687 -362.365685)
			(xy 341.231264 -362.372726) (xy 341.205312 -362.373164) (xy 341.176395 -362.372651) (xy 341.119223 -362.363923)
			(xy 341.064023 -362.346664) (xy 341.012061 -362.321272) (xy 340.964528 -362.288327) (xy 340.922511 -362.248584)
			(xy 340.904322 -362.226098) (xy 340.894425 -362.214293) (xy 340.869101 -362.196774) (xy 340.839708 -362.187598)
			(xy 340.808916 -362.187598) (xy 340.779523 -362.196774) (xy 340.754199 -362.214293) (xy 340.744302 -362.226098)
			(xy 340.727549 -362.246881) (xy 340.689195 -362.284011) (xy 340.646041 -362.315433) (xy 340.598927 -362.340532)
			(xy 340.548775 -362.358818) (xy 340.496564 -362.369935) (xy 340.443312 -362.373665) (xy 340.39006 -362.369935)
			(xy 340.337849 -362.358818) (xy 340.287697 -362.340532) (xy 340.240583 -362.315433) (xy 340.197429 -362.284011)
			(xy 340.159075 -362.246881) (xy 340.142322 -362.226098) (xy 340.132425 -362.214293) (xy 340.107101 -362.196774)
			(xy 340.077708 -362.187598) (xy 340.046916 -362.187598) (xy 340.017523 -362.196774) (xy 339.992199 -362.214293)
			(xy 339.982302 -362.226098) (xy 339.964109 -362.24858) (xy 339.92209 -362.288315) (xy 339.874555 -362.321255)
			(xy 339.822594 -362.346643) (xy 339.767397 -362.3639) (xy 339.710228 -362.372629) (xy 339.681312 -362.373164)
			(xy 339.654097 -362.372702) (xy 339.600221 -362.364968) (xy 339.54799 -362.349654) (xy 339.498466 -362.327072)
			(xy 339.452655 -362.297681) (xy 339.411486 -362.262076) (xy 339.393276 -362.241846) (xy 339.383459 -362.231266)
			(xy 339.359238 -362.215595) (xy 339.331598 -362.207332) (xy 339.302751 -362.207139) (xy 339.275003 -362.215032)
			(xy 339.250575 -362.230378) (xy 339.240622 -362.24083) (xy 339.222462 -362.260636) (xy 339.18151 -362.295429)
			(xy 339.13608 -362.324127) (xy 339.08707 -362.346163) (xy 339.035452 -362.3611) (xy 338.982248 -362.368642)
			(xy 338.95538 -362.3691) (xy 338.926465 -362.368524) (xy 338.869297 -362.359807) (xy 338.814099 -362.342561)
			(xy 338.762137 -362.31718) (xy 338.714602 -362.284246) (xy 338.672582 -362.244515) (xy 338.65439 -362.222034)
			(xy 338.644493 -362.210229) (xy 338.619169 -362.19271) (xy 338.589776 -362.183534) (xy 338.558984 -362.183534)
			(xy 338.529591 -362.19271) (xy 338.504267 -362.210229) (xy 338.49437 -362.222034) (xy 338.476205 -362.244539)
			(xy 338.434178 -362.284271) (xy 338.386638 -362.317207) (xy 338.334672 -362.342591) (xy 338.27947 -362.359843)
			(xy 338.222297 -362.368567) (xy 338.19338 -362.3691) (xy 338.167312 -362.36863) (xy 338.115662 -362.361521)
			(xy 338.06546 -362.347451) (xy 338.017638 -362.326681) (xy 337.973087 -362.299599) (xy 337.932635 -362.266708)
			(xy 337.897034 -362.228618) (xy 337.866946 -362.18604) (xy 337.854544 -362.163106) (xy 337.847731 -362.150989)
			(xy 337.828764 -362.130684) (xy 337.805023 -362.116248) (xy 337.778267 -362.108752) (xy 337.750481 -362.108752)
			(xy 337.723725 -362.116248) (xy 337.699984 -362.130684) (xy 337.681017 -362.150989) (xy 337.674204 -362.163106)
			(xy 337.661804 -362.186044) (xy 337.63173 -362.228638) (xy 337.596136 -362.266741) (xy 337.555686 -362.299643)
			(xy 337.511132 -362.326731) (xy 337.463305 -362.347499) (xy 337.413096 -362.361562) (xy 337.361439 -362.368658)
			(xy 337.335368 -362.3691) (xy 337.30799 -362.368598) (xy 337.253798 -362.360767) (xy 337.201281 -362.345269)
			(xy 337.151519 -362.322425) (xy 337.105533 -362.292702) (xy 337.064268 -362.256711) (xy 337.046062 -362.236258)
			(xy 337.035978 -362.225304) (xy 337.010922 -362.209248) (xy 336.982304 -362.201091) (xy 336.952548 -362.201525)
			(xy 336.924179 -362.210513) (xy 336.899603 -362.227293) (xy 336.889852 -362.238544) (xy 336.871595 -362.260307)
			(xy 336.829807 -362.298779) (xy 336.782778 -362.330632) (xy 336.731546 -362.355162) (xy 336.677245 -362.371826)
			(xy 336.621073 -362.380257) (xy 336.592672 -362.380784) (xy 336.563618 -362.380272) (xy 336.50618 -362.371469)
			(xy 336.450742 -362.354055) (xy 336.398587 -362.328433) (xy 336.350922 -362.295197) (xy 336.30885 -362.255115)
			(xy 336.290666 -362.232448) (xy 336.281394 -362.221386) (xy 336.258079 -362.204404) (xy 336.230941 -362.19463)
			(xy 336.202152 -362.192845) (xy 336.174014 -362.199193) (xy 336.14878 -362.213165) (xy 336.138266 -362.22305)
			(xy 336.116651 -362.244093) (xy 336.067986 -362.279738) (xy 336.014317 -362.307277) (xy 335.956981 -362.326024)
			(xy 335.897409 -362.335512) (xy 335.867248 -362.33608) (xy 335.839995 -362.3356) (xy 335.786043 -362.327849)
			(xy 335.733744 -362.312497) (xy 335.684162 -362.289858) (xy 335.638307 -362.260393) (xy 335.597114 -362.224701)
			(xy 335.561419 -362.183509) (xy 335.531951 -362.137655) (xy 335.50931 -362.088075) (xy 335.493955 -362.035776)
			(xy 335.486201 -361.981825) (xy 335.48574 -361.954572) (xy 335.486232 -361.926969) (xy 335.494193 -361.872338)
			(xy 335.509943 -361.819426) (xy 335.533154 -361.769336) (xy 335.563343 -361.723113) (xy 335.581244 -361.702096)
			(xy 335.590775 -361.690438) (xy 335.603212 -361.663031) (xy 335.607139 -361.633191) (xy 335.602218 -361.6035)
			(xy 335.588874 -361.576523) (xy 335.578958 -361.56519) (xy 335.559548 -361.543811) (xy 335.526716 -361.496311)
			(xy 335.501424 -361.444403) (xy 335.484248 -361.389275) (xy 335.475583 -361.332187) (xy 335.475072 -361.303316)
			(xy 335.475523 -361.275711) (xy 335.483492 -361.221079) (xy 335.499252 -361.168165) (xy 335.522473 -361.118076)
			(xy 335.55267 -361.071856) (xy 335.570576 -361.05084) (xy 335.580061 -361.039148) (xy 335.592499 -361.011753)
			(xy 335.596433 -360.981925) (xy 335.591524 -360.952241) (xy 335.578196 -360.925268) (xy 335.56829 -360.913934)
			(xy 335.548859 -360.892573) (xy 335.516029 -360.845069) (xy 335.490739 -360.793157) (xy 335.473569 -360.738024)
			(xy 335.464911 -360.680933) (xy 335.464404 -360.65206) (xy 335.464898 -360.624457) (xy 335.472859 -360.569827)
			(xy 335.48861 -360.516915) (xy 335.511821 -360.466825) (xy 335.542007 -360.420602) (xy 335.559908 -360.399584)
			(xy 335.569445 -360.387932) (xy 335.581872 -360.360522) (xy 335.585794 -360.330682) (xy 335.580873 -360.300991)
			(xy 335.567534 -360.274013) (xy 335.557622 -360.262678) (xy 335.5382 -360.241309) (xy 335.505372 -360.193806)
			(xy 335.480082 -360.141896) (xy 335.462909 -360.086765) (xy 335.454246 -360.029676) (xy 335.453736 -360.000804)
			(xy 335.454244 -359.971887) (xy 335.462973 -359.914714) (xy 335.480232 -359.859515) (xy 335.505626 -359.807553)
			(xy 335.538572 -359.760019) (xy 335.578315 -359.718003) (xy 335.600802 -359.699814) (xy 335.612602 -359.689911)
			(xy 335.630117 -359.664589) (xy 335.639292 -359.635197) (xy 335.639292 -359.604407) (xy 335.630119 -359.575016)
			(xy 335.612605 -359.549692) (xy 335.600802 -359.539794) (xy 335.580021 -359.523037) (xy 335.542887 -359.484686)
			(xy 335.511462 -359.441533) (xy 335.48636 -359.39442) (xy 335.468071 -359.344267) (xy 335.456953 -359.292055)
			(xy 335.453223 -359.238802) (xy 322.009514 -359.238802) (xy 327.048368 -364.277656) (xy 343.301828 -364.277656)
			(xy 344.974164 -362.60532) (xy 344.974164 -357.238808) (xy 344.97462 -357.209688) (xy 344.982215 -357.151944)
			(xy 344.997289 -357.095688) (xy 345.019583 -357.041883) (xy 345.048716 -356.991453) (xy 345.084188 -356.94526)
			(xy 345.104466 -356.924356) (xy 346.983812 -355.04501) (xy 347.004716 -355.024733) (xy 347.050915 -354.989272)
			(xy 347.101348 -354.960146) (xy 347.155151 -354.937853) (xy 347.211404 -354.922773) (xy 347.269144 -354.915166)
			(xy 347.298264 -354.914708) (xy 347.327389 -354.915201) (xy 347.385143 -354.922798) (xy 347.441411 -354.937865)
			(xy 347.495232 -354.960146) (xy 347.545685 -354.98926) (xy 347.591909 -355.024708) (xy 347.633111 -355.065885)
			(xy 347.668588 -355.112086) (xy 347.697732 -355.162522) (xy 347.720047 -355.216329) (xy 347.735149 -355.272588)
			(xy 347.742781 -355.330337) (xy 347.743272 -355.359462) (xy 347.742768 -355.388587) (xy 347.735109 -355.446332)
			(xy 347.719982 -355.502585) (xy 347.697645 -355.556383) (xy 347.668481 -355.606807) (xy 347.632988 -355.652996)
			(xy 347.612716 -355.673914) (xy 347.348048 -355.938836) (xy 347.337663 -355.950058) (xy 347.323421 -355.977094)
			(xy 347.317803 -356.007132) (xy 347.321312 -356.037488) (xy 347.322611 -356.040436) (xy 351.932746 -356.040436)
			(xy 351.936817 -355.984814) (xy 351.948943 -355.930377) (xy 351.968866 -355.878286) (xy 351.996162 -355.829651)
			(xy 352.030248 -355.785508) (xy 352.070397 -355.746799) (xy 352.115755 -355.714348) (xy 352.165355 -355.688847)
			(xy 352.218139 -355.67084) (xy 352.272982 -355.66071) (xy 352.328716 -355.658673) (xy 352.384153 -355.664773)
			(xy 352.43811 -355.678879) (xy 352.489439 -355.700691) (xy 352.537045 -355.729745) (xy 352.579913 -355.76542)
			(xy 352.61713 -355.806957) (xy 352.647903 -355.85347) (xy 352.671575 -355.903967) (xy 352.687643 -355.957374)
			(xy 352.695763 -356.01255) (xy 352.696272 -356.040436) (xy 352.695763 -356.068322) (xy 352.687643 -356.123498)
			(xy 352.671575 -356.176905) (xy 352.647903 -356.227402) (xy 352.61713 -356.273915) (xy 352.579913 -356.315452)
			(xy 352.537045 -356.351127) (xy 352.489439 -356.380181) (xy 352.43811 -356.401993) (xy 352.384153 -356.416099)
			(xy 352.328716 -356.422199) (xy 352.272982 -356.420162) (xy 352.218139 -356.410032) (xy 352.165355 -356.392025)
			(xy 352.115755 -356.366524) (xy 352.070397 -356.334073) (xy 352.030248 -356.295364) (xy 351.996162 -356.251221)
			(xy 351.968866 -356.202586) (xy 351.948943 -356.150495) (xy 351.936817 -356.096058) (xy 351.932746 -356.040436)
			(xy 347.322611 -356.040436) (xy 347.333633 -356.065451) (xy 347.353667 -356.088526) (xy 347.379625 -356.104651)
			(xy 347.394276 -356.109016) (xy 347.421163 -356.116547) (xy 347.472568 -356.138337) (xy 347.520251 -356.167384)
			(xy 347.563193 -356.203068) (xy 347.600478 -356.244627) (xy 347.63131 -356.291175) (xy 347.655032 -356.341719)
			(xy 347.671137 -356.395179) (xy 347.679281 -356.450415) (xy 347.679772 -356.478332) (xy 347.679375 -356.505587)
			(xy 347.671613 -356.559543) (xy 347.656251 -356.611844) (xy 347.633602 -356.661427) (xy 347.604127 -356.707281)
			(xy 347.568426 -356.748475) (xy 347.527227 -356.784168) (xy 347.481367 -356.813634) (xy 347.43178 -356.836274)
			(xy 347.379476 -356.851627) (xy 347.325519 -356.85938) (xy 347.298264 -356.85984) (xy 347.270344 -356.859342)
			(xy 347.215097 -356.851223) (xy 347.161624 -356.835137) (xy 347.111068 -356.811425) (xy 347.06451 -356.780596)
			(xy 347.022944 -356.743308) (xy 346.98726 -356.700357) (xy 346.958219 -356.652663) (xy 346.936442 -356.601244)
			(xy 346.928948 -356.574344) (xy 346.924543 -356.559694) (xy 346.908444 -356.533702) (xy 346.885376 -356.513637)
			(xy 346.857404 -356.501293) (xy 346.827033 -356.497777) (xy 346.796982 -356.503404) (xy 346.76994 -356.517668)
			(xy 346.758768 -356.528116) (xy 345.863672 -357.422958) (xy 345.863672 -357.494332) (xy 346.916246 -357.494332)
			(xy 346.920317 -357.43871) (xy 346.932443 -357.384273) (xy 346.952366 -357.332182) (xy 346.979662 -357.283547)
			(xy 347.013748 -357.239404) (xy 347.053897 -357.200695) (xy 347.099255 -357.168244) (xy 347.148855 -357.142743)
			(xy 347.201639 -357.124736) (xy 347.256482 -357.114606) (xy 347.312216 -357.112569) (xy 347.367653 -357.118669)
			(xy 347.42161 -357.132775) (xy 347.472939 -357.154587) (xy 347.520545 -357.183641) (xy 347.563413 -357.219316)
			(xy 347.60063 -357.260853) (xy 347.631403 -357.307366) (xy 347.655075 -357.357863) (xy 347.671143 -357.41127)
			(xy 347.679263 -357.466446) (xy 347.679772 -357.494332) (xy 347.679263 -357.522218) (xy 347.671143 -357.577394)
			(xy 347.655075 -357.630801) (xy 347.631403 -357.681298) (xy 347.60063 -357.727811) (xy 347.563413 -357.769348)
			(xy 347.520545 -357.805023) (xy 347.472939 -357.834077) (xy 347.42161 -357.855889) (xy 347.367653 -357.869995)
			(xy 347.312216 -357.876095) (xy 347.256482 -357.874058) (xy 347.201639 -357.863928) (xy 347.148855 -357.845921)
			(xy 347.099255 -357.82042) (xy 347.053897 -357.787969) (xy 347.013748 -357.74926) (xy 346.979662 -357.705117)
			(xy 346.952366 -357.656482) (xy 346.932443 -357.604391) (xy 346.920317 -357.549954) (xy 346.916246 -357.494332)
			(xy 345.863672 -357.494332) (xy 345.863672 -358.217724) (xy 347.824806 -358.217724) (xy 347.825278 -358.190471)
			(xy 347.833032 -358.13652) (xy 347.848385 -358.084221) (xy 347.871026 -358.03464) (xy 347.900493 -357.988786)
			(xy 347.936186 -357.947593) (xy 347.977378 -357.911899) (xy 348.023231 -357.882431) (xy 348.072812 -357.859789)
			(xy 348.12511 -357.844434) (xy 348.179061 -357.836678) (xy 348.206314 -357.836216) (xy 348.234623 -357.836677)
			(xy 348.290621 -357.845025) (xy 348.344768 -357.861565) (xy 348.395872 -357.885934) (xy 348.442809 -357.917595)
			(xy 348.484546 -357.955851) (xy 348.520164 -357.99986) (xy 348.54888 -358.048654) (xy 348.570061 -358.10116)
			(xy 348.577154 -358.12857) (xy 348.580456 -358.142286) (xy 348.659437 -358.221267) (xy 351.436611 -358.221267)
			(xy 351.444366 -358.167309) (xy 351.459721 -358.115003) (xy 351.482364 -358.065416) (xy 351.511833 -358.019555)
			(xy 351.547529 -357.978356) (xy 351.588725 -357.942656) (xy 351.634583 -357.913182) (xy 351.684168 -357.890534)
			(xy 351.736472 -357.875174) (xy 351.79043 -357.867414) (xy 351.817686 -357.86695) (xy 351.833829 -357.867091)
			(xy 351.866003 -357.869764) (xy 351.881948 -357.872284) (xy 351.89597 -357.874265) (xy 351.924113 -357.871202)
			(xy 351.950334 -357.86053) (xy 351.972617 -357.843069) (xy 351.989249 -357.82016) (xy 351.998953 -357.793566)
			(xy 352.000981 -357.765329) (xy 351.998534 -357.75138) (xy 351.994727 -357.732111) (xy 351.990659 -357.693042)
			(xy 351.990406 -357.673402) (xy 351.990876 -357.646151) (xy 351.998632 -357.592203) (xy 352.013987 -357.539908)
			(xy 352.036627 -357.490331) (xy 352.066093 -357.44448) (xy 352.101784 -357.40329) (xy 352.142974 -357.367598)
			(xy 352.188824 -357.338131) (xy 352.238401 -357.315489) (xy 352.290695 -357.300134) (xy 352.344643 -357.292376)
			(xy 352.399145 -357.292375) (xy 352.453093 -357.300131) (xy 352.505388 -357.315485) (xy 352.554966 -357.338125)
			(xy 352.600816 -357.367591) (xy 352.642007 -357.403281) (xy 352.6777 -357.444471) (xy 352.707167 -357.49032)
			(xy 352.729809 -357.539897) (xy 352.745166 -357.592191) (xy 352.752924 -357.646139) (xy 352.752925 -357.700641)
			(xy 352.74517 -357.754589) (xy 352.729816 -357.806884) (xy 352.707177 -357.856462) (xy 352.677712 -357.902313)
			(xy 352.642022 -357.943505) (xy 352.600832 -357.979197) (xy 352.554983 -358.008665) (xy 352.505407 -358.031308)
			(xy 352.453113 -358.046665) (xy 352.399165 -358.054423) (xy 352.371914 -358.05491) (xy 352.355771 -358.05477)
			(xy 352.323597 -358.052097) (xy 352.307652 -358.049576) (xy 352.293627 -358.047643) (xy 352.265492 -358.050705)
			(xy 352.239279 -358.061372) (xy 352.217001 -358.078825) (xy 352.200369 -358.101723) (xy 352.190662 -358.128307)
			(xy 352.188624 -358.156534) (xy 352.191066 -358.17048) (xy 352.194867 -358.18975) (xy 352.198939 -358.228818)
			(xy 352.199194 -358.248458) (xy 352.19879 -358.275714) (xy 352.191038 -358.329673) (xy 352.175685 -358.381979)
			(xy 352.153045 -358.431568) (xy 352.123578 -358.47743) (xy 352.087884 -358.518631) (xy 352.04669 -358.554333)
			(xy 352.000833 -358.583809) (xy 351.951249 -358.606459) (xy 351.898946 -358.621822) (xy 351.844989 -358.629585)
			(xy 351.790476 -358.629589) (xy 351.736518 -358.621836) (xy 351.684212 -358.606482) (xy 351.634624 -358.583841)
			(xy 351.588763 -358.554372) (xy 351.547562 -358.518677) (xy 351.511861 -358.477482) (xy 351.482386 -358.431625)
			(xy 351.459737 -358.38204) (xy 351.444376 -358.329737) (xy 351.436615 -358.27578) (xy 351.436611 -358.221267)
			(xy 348.659437 -358.221267) (xy 349.60433 -359.16616) (xy 349.906844 -359.16616) (xy 349.930392 -359.151128)
			(xy 349.980968 -359.1274) (xy 350.034462 -359.111292) (xy 350.089731 -359.103148) (xy 350.117664 -359.10266)
			(xy 350.118172 -359.10266) (xy 350.146259 -359.103185) (xy 350.201824 -359.111438) (xy 350.255581 -359.127742)
			(xy 350.306369 -359.151744) (xy 350.309437 -359.153714) (xy 351.933254 -359.153714) (xy 351.937325 -359.098092)
			(xy 351.949451 -359.043655) (xy 351.969374 -358.991564) (xy 351.99667 -358.942929) (xy 352.030756 -358.898786)
			(xy 352.070905 -358.860077) (xy 352.116263 -358.827626) (xy 352.165863 -358.802125) (xy 352.218647 -358.784118)
			(xy 352.27349 -358.773988) (xy 352.329224 -358.771951) (xy 352.384661 -358.778051) (xy 352.438618 -358.792157)
			(xy 352.489947 -358.813969) (xy 352.537553 -358.843023) (xy 352.580421 -358.878698) (xy 352.617638 -358.920235)
			(xy 352.648411 -358.966748) (xy 352.672083 -359.017245) (xy 352.688151 -359.070652) (xy 352.696271 -359.125828)
			(xy 352.69678 -359.153714) (xy 352.696271 -359.1816) (xy 352.688151 -359.236776) (xy 352.672083 -359.290183)
			(xy 352.648411 -359.34068) (xy 352.617638 -359.387193) (xy 352.580421 -359.42873) (xy 352.537553 -359.464405)
			(xy 352.489947 -359.493459) (xy 352.438618 -359.515271) (xy 352.384661 -359.529377) (xy 352.329224 -359.535477)
			(xy 352.27349 -359.53344) (xy 352.218647 -359.52331) (xy 352.165863 -359.505303) (xy 352.116263 -359.479802)
			(xy 352.070905 -359.447351) (xy 352.030756 -359.408642) (xy 351.99667 -359.364499) (xy 351.969374 -359.315864)
			(xy 351.949451 -359.263773) (xy 351.937325 -359.209336) (xy 351.933254 -359.153714) (xy 350.309437 -359.153714)
			(xy 350.330008 -359.166922) (xy 350.352721 -359.16889) (xy 350.397281 -359.17853) (xy 350.440012 -359.194421)
			(xy 350.480042 -359.21624) (xy 350.516554 -359.243541) (xy 350.532954 -359.259378) (xy 350.81337 -359.539794)
			(xy 350.830755 -359.557751) (xy 350.860155 -359.59817) (xy 350.882861 -359.642696) (xy 350.898312 -359.690228)
			(xy 350.906128 -359.739594) (xy 350.906588 -359.764584) (xy 350.906588 -360.248708) (xy 352.035362 -360.248708)
			(xy 352.039433 -360.193086) (xy 352.051559 -360.138649) (xy 352.071482 -360.086558) (xy 352.098778 -360.037923)
			(xy 352.132864 -359.99378) (xy 352.173013 -359.955071) (xy 352.218371 -359.92262) (xy 352.267971 -359.897119)
			(xy 352.320755 -359.879112) (xy 352.375598 -359.868982) (xy 352.431332 -359.866945) (xy 352.486769 -359.873045)
			(xy 352.540726 -359.887151) (xy 352.592055 -359.908963) (xy 352.639661 -359.938017) (xy 352.682529 -359.973692)
			(xy 352.719746 -360.015229) (xy 352.750519 -360.061742) (xy 352.774191 -360.112239) (xy 352.790259 -360.165646)
			(xy 352.798379 -360.220822) (xy 352.798888 -360.248708) (xy 352.798379 -360.276594) (xy 352.790259 -360.33177)
			(xy 352.774191 -360.385177) (xy 352.750519 -360.435674) (xy 352.719746 -360.482187) (xy 352.682529 -360.523724)
			(xy 352.639661 -360.559399) (xy 352.592055 -360.588453) (xy 352.540726 -360.610265) (xy 352.486769 -360.624371)
			(xy 352.431332 -360.630471) (xy 352.375598 -360.628434) (xy 352.320755 -360.618304) (xy 352.267971 -360.600297)
			(xy 352.218371 -360.574796) (xy 352.173013 -360.542345) (xy 352.132864 -360.503636) (xy 352.098778 -360.459493)
			(xy 352.071482 -360.410858) (xy 352.051559 -360.358767) (xy 352.039433 -360.30433) (xy 352.035362 -360.248708)
			(xy 350.906588 -360.248708) (xy 350.906588 -361.587034) (xy 350.93783 -361.599988) (xy 350.963487 -361.611292)
			(xy 351.011496 -361.640243) (xy 351.054752 -361.675908) (xy 351.059592 -361.681268) (xy 352.721162 -361.681268)
			(xy 352.725233 -361.625646) (xy 352.737359 -361.571209) (xy 352.757282 -361.519118) (xy 352.784578 -361.470483)
			(xy 352.818664 -361.42634) (xy 352.858813 -361.387631) (xy 352.904171 -361.35518) (xy 352.953771 -361.329679)
			(xy 353.006555 -361.311672) (xy 353.061398 -361.301542) (xy 353.117132 -361.299505) (xy 353.172569 -361.305605)
			(xy 353.226526 -361.319711) (xy 353.277855 -361.341523) (xy 353.325461 -361.370577) (xy 353.368329 -361.406252)
			(xy 353.405546 -361.447789) (xy 353.436319 -361.494302) (xy 353.459991 -361.544799) (xy 353.476059 -361.598206)
			(xy 353.484179 -361.653382) (xy 353.484688 -361.681268) (xy 353.484179 -361.709154) (xy 353.476059 -361.76433)
			(xy 353.459991 -361.817737) (xy 353.436319 -361.868234) (xy 353.405546 -361.914747) (xy 353.368329 -361.956284)
			(xy 353.325461 -361.991959) (xy 353.277855 -362.021013) (xy 353.226526 -362.042825) (xy 353.172569 -362.056931)
			(xy 353.117132 -362.063031) (xy 353.061398 -362.060994) (xy 353.006555 -362.050864) (xy 352.953771 -362.032857)
			(xy 352.904171 -362.007356) (xy 352.858813 -361.974905) (xy 352.818664 -361.936196) (xy 352.784578 -361.892053)
			(xy 352.757282 -361.843418) (xy 352.737359 -361.791327) (xy 352.725233 -361.73689) (xy 352.721162 -361.681268)
			(xy 351.059592 -361.681268) (xy 351.092324 -361.717518) (xy 351.123403 -361.764178) (xy 351.147319 -361.814883)
			(xy 351.163559 -361.868543) (xy 351.171772 -361.924001) (xy 351.172272 -361.952032) (xy 351.171875 -361.979287)
			(xy 351.164113 -362.033243) (xy 351.148751 -362.085544) (xy 351.126102 -362.135127) (xy 351.096627 -362.180981)
			(xy 351.060926 -362.222175) (xy 351.019727 -362.257868) (xy 350.973867 -362.287334) (xy 350.92428 -362.309974)
			(xy 350.871976 -362.325327) (xy 350.818019 -362.33308) (xy 350.790764 -362.33354) (xy 350.762457 -362.333056)
			(xy 350.706462 -362.324707) (xy 350.652318 -362.308166) (xy 350.601216 -362.283799) (xy 350.554281 -362.252141)
			(xy 350.512544 -362.213889) (xy 350.476925 -362.169884) (xy 350.448206 -362.121095) (xy 350.42702 -362.068594)
			(xy 350.419924 -362.041186) (xy 350.416622 -362.02747) (xy 350.36379 -361.974638) (xy 350.346431 -361.956657)
			(xy 350.317025 -361.916245) (xy 350.294313 -361.871726) (xy 350.278856 -361.824199) (xy 350.271035 -361.774837)
			(xy 350.270572 -361.749848) (xy 350.270572 -359.896156) (xy 350.225614 -359.851198) (xy 350.19869 -359.85704)
			(xy 350.178742 -359.861082) (xy 350.138269 -359.865405) (xy 350.117918 -359.865676) (xy 350.117664 -359.865676)
			(xy 350.08973 -359.865197) (xy 350.034457 -359.857066) (xy 349.980964 -359.840954) (xy 349.930395 -359.817206)
			(xy 349.906844 -359.802176) (xy 349.472758 -359.802176) (xy 349.447773 -359.801678) (xy 349.398422 -359.793839)
			(xy 349.350904 -359.778377) (xy 349.30639 -359.755673) (xy 349.265975 -359.726285) (xy 349.247968 -359.708958)
			(xy 348.13113 -358.59212) (xy 348.11716 -358.588564) (xy 348.08977 -358.581423) (xy 348.037294 -358.560212)
			(xy 347.988527 -358.531481) (xy 347.944541 -358.49586) (xy 347.906301 -358.45413) (xy 347.874646 -358.407209)
			(xy 347.850271 -358.356125) (xy 347.833711 -358.302001) (xy 347.82533 -358.246024) (xy 347.824806 -358.217724)
			(xy 345.863672 -358.217724) (xy 345.863672 -359.353612) (xy 346.946726 -359.353612) (xy 346.950797 -359.29799)
			(xy 346.962923 -359.243553) (xy 346.982846 -359.191462) (xy 347.010142 -359.142827) (xy 347.044228 -359.098684)
			(xy 347.084377 -359.059975) (xy 347.129735 -359.027524) (xy 347.179335 -359.002023) (xy 347.232119 -358.984016)
			(xy 347.286962 -358.973886) (xy 347.342696 -358.971849) (xy 347.398133 -358.977949) (xy 347.45209 -358.992055)
			(xy 347.503419 -359.013867) (xy 347.551025 -359.042921) (xy 347.593893 -359.078596) (xy 347.63111 -359.120133)
			(xy 347.661883 -359.166646) (xy 347.685555 -359.217143) (xy 347.701623 -359.27055) (xy 347.709743 -359.325726)
			(xy 347.710252 -359.353612) (xy 347.709743 -359.381498) (xy 347.701623 -359.436674) (xy 347.685555 -359.490081)
			(xy 347.661883 -359.540578) (xy 347.63111 -359.587091) (xy 347.593893 -359.628628) (xy 347.551025 -359.664303)
			(xy 347.503419 -359.693357) (xy 347.45209 -359.715169) (xy 347.398133 -359.729275) (xy 347.342696 -359.735375)
			(xy 347.286962 -359.733338) (xy 347.232119 -359.723208) (xy 347.179335 -359.705201) (xy 347.129735 -359.6797)
			(xy 347.084377 -359.647249) (xy 347.044228 -359.60854) (xy 347.010142 -359.564397) (xy 346.982846 -359.515762)
			(xy 346.962923 -359.463671) (xy 346.950797 -359.409234) (xy 346.946726 -359.353612) (xy 345.863672 -359.353612)
			(xy 345.863672 -360.48569) (xy 347.061788 -360.48569) (xy 347.065859 -360.430068) (xy 347.077985 -360.375631)
			(xy 347.097908 -360.32354) (xy 347.125204 -360.274905) (xy 347.15929 -360.230762) (xy 347.199439 -360.192053)
			(xy 347.244797 -360.159602) (xy 347.294397 -360.134101) (xy 347.347181 -360.116094) (xy 347.402024 -360.105964)
			(xy 347.457758 -360.103927) (xy 347.513195 -360.110027) (xy 347.567152 -360.124133) (xy 347.618481 -360.145945)
			(xy 347.666087 -360.174999) (xy 347.708955 -360.210674) (xy 347.746172 -360.252211) (xy 347.776945 -360.298724)
			(xy 347.800617 -360.349221) (xy 347.816685 -360.402628) (xy 347.824805 -360.457804) (xy 347.825314 -360.48569)
			(xy 347.824805 -360.513576) (xy 347.816685 -360.568752) (xy 347.800617 -360.622159) (xy 347.776945 -360.672656)
			(xy 347.746172 -360.719169) (xy 347.708955 -360.760706) (xy 347.666087 -360.796381) (xy 347.618481 -360.825435)
			(xy 347.567152 -360.847247) (xy 347.513195 -360.861353) (xy 347.457758 -360.867453) (xy 347.402024 -360.865416)
			(xy 347.347181 -360.855286) (xy 347.294397 -360.837279) (xy 347.244797 -360.811778) (xy 347.199439 -360.779327)
			(xy 347.15929 -360.740618) (xy 347.125204 -360.696475) (xy 347.097908 -360.64784) (xy 347.077985 -360.595749)
			(xy 347.065859 -360.541312) (xy 347.061788 -360.48569) (xy 345.863672 -360.48569) (xy 345.863672 -361.162346)
			(xy 347.74454 -361.162346) (xy 347.748611 -361.106724) (xy 347.760737 -361.052287) (xy 347.78066 -361.000196)
			(xy 347.807956 -360.951561) (xy 347.842042 -360.907418) (xy 347.882191 -360.868709) (xy 347.927549 -360.836258)
			(xy 347.977149 -360.810757) (xy 348.029933 -360.79275) (xy 348.084776 -360.78262) (xy 348.14051 -360.780583)
			(xy 348.195947 -360.786683) (xy 348.249904 -360.800789) (xy 348.301233 -360.822601) (xy 348.348839 -360.851655)
			(xy 348.391707 -360.88733) (xy 348.428924 -360.928867) (xy 348.459697 -360.97538) (xy 348.483369 -361.025877)
			(xy 348.499437 -361.079284) (xy 348.507557 -361.13446) (xy 348.508066 -361.162346) (xy 348.507557 -361.190232)
			(xy 348.499437 -361.245408) (xy 348.483369 -361.298815) (xy 348.459697 -361.349312) (xy 348.428924 -361.395825)
			(xy 348.391707 -361.437362) (xy 348.348839 -361.473037) (xy 348.301233 -361.502091) (xy 348.249904 -361.523903)
			(xy 348.195947 -361.538009) (xy 348.14051 -361.544109) (xy 348.084776 -361.542072) (xy 348.029933 -361.531942)
			(xy 347.977149 -361.513935) (xy 347.927549 -361.488434) (xy 347.882191 -361.455983) (xy 347.842042 -361.417274)
			(xy 347.807956 -361.373131) (xy 347.78066 -361.324496) (xy 347.760737 -361.272405) (xy 347.748611 -361.217968)
			(xy 347.74454 -361.162346) (xy 345.863672 -361.162346) (xy 345.863672 -361.953556) (xy 349.395032 -361.953556)
			(xy 349.399103 -361.897934) (xy 349.411229 -361.843497) (xy 349.431152 -361.791406) (xy 349.458448 -361.742771)
			(xy 349.492534 -361.698628) (xy 349.532683 -361.659919) (xy 349.578041 -361.627468) (xy 349.627641 -361.601967)
			(xy 349.680425 -361.58396) (xy 349.735268 -361.57383) (xy 349.791002 -361.571793) (xy 349.846439 -361.577893)
			(xy 349.900396 -361.591999) (xy 349.951725 -361.613811) (xy 349.999331 -361.642865) (xy 350.042199 -361.67854)
			(xy 350.079416 -361.720077) (xy 350.110189 -361.76659) (xy 350.133861 -361.817087) (xy 350.149929 -361.870494)
			(xy 350.158049 -361.92567) (xy 350.158558 -361.953556) (xy 350.158049 -361.981442) (xy 350.149929 -362.036618)
			(xy 350.133861 -362.090025) (xy 350.110189 -362.140522) (xy 350.079416 -362.187035) (xy 350.042199 -362.228572)
			(xy 349.999331 -362.264247) (xy 349.951725 -362.293301) (xy 349.900396 -362.315113) (xy 349.846439 -362.329219)
			(xy 349.791002 -362.335319) (xy 349.735268 -362.333282) (xy 349.680425 -362.323152) (xy 349.627641 -362.305145)
			(xy 349.578041 -362.279644) (xy 349.532683 -362.247193) (xy 349.492534 -362.208484) (xy 349.458448 -362.164341)
			(xy 349.431152 -362.115706) (xy 349.411229 -362.063615) (xy 349.399103 -362.009178) (xy 349.395032 -361.953556)
			(xy 345.863672 -361.953556) (xy 345.863672 -362.78947) (xy 345.863192 -362.81859) (xy 345.855933 -362.873798)
			(xy 346.387672 -362.873798) (xy 346.391743 -362.818176) (xy 346.403869 -362.763739) (xy 346.423792 -362.711648)
			(xy 346.451088 -362.663013) (xy 346.485174 -362.61887) (xy 346.525323 -362.580161) (xy 346.570681 -362.54771)
			(xy 346.620281 -362.522209) (xy 346.673065 -362.504202) (xy 346.727908 -362.494072) (xy 346.783642 -362.492035)
			(xy 346.839079 -362.498135) (xy 346.893036 -362.512241) (xy 346.944365 -362.534053) (xy 346.991971 -362.563107)
			(xy 347.034839 -362.598782) (xy 347.057083 -362.623608) (xy 351.008948 -362.623608) (xy 351.013019 -362.567986)
			(xy 351.025145 -362.513549) (xy 351.045068 -362.461458) (xy 351.072364 -362.412823) (xy 351.10645 -362.36868)
			(xy 351.146599 -362.329971) (xy 351.191957 -362.29752) (xy 351.241557 -362.272019) (xy 351.294341 -362.254012)
			(xy 351.349184 -362.243882) (xy 351.404918 -362.241845) (xy 351.460355 -362.247945) (xy 351.514312 -362.262051)
			(xy 351.565641 -362.283863) (xy 351.613247 -362.312917) (xy 351.653899 -362.346748) (xy 353.600002 -362.346748)
			(xy 353.604073 -362.291126) (xy 353.616199 -362.236689) (xy 353.636122 -362.184598) (xy 353.663418 -362.135963)
			(xy 353.697504 -362.09182) (xy 353.737653 -362.053111) (xy 353.783011 -362.02066) (xy 353.832611 -361.995159)
			(xy 353.885395 -361.977152) (xy 353.940238 -361.967022) (xy 353.995972 -361.964985) (xy 354.051409 -361.971085)
			(xy 354.105366 -361.985191) (xy 354.156695 -362.007003) (xy 354.204301 -362.036057) (xy 354.247169 -362.071732)
			(xy 354.284386 -362.113269) (xy 354.315159 -362.159782) (xy 354.338831 -362.210279) (xy 354.354899 -362.263686)
			(xy 354.363019 -362.318862) (xy 354.363528 -362.346748) (xy 354.363019 -362.374634) (xy 354.354899 -362.42981)
			(xy 354.338831 -362.483217) (xy 354.315159 -362.533714) (xy 354.284386 -362.580227) (xy 354.247169 -362.621764)
			(xy 354.204301 -362.657439) (xy 354.156695 -362.686493) (xy 354.105366 -362.708305) (xy 354.051409 -362.722411)
			(xy 353.995972 -362.728511) (xy 353.940238 -362.726474) (xy 353.885395 -362.716344) (xy 353.832611 -362.698337)
			(xy 353.783011 -362.672836) (xy 353.737653 -362.640385) (xy 353.697504 -362.601676) (xy 353.663418 -362.557533)
			(xy 353.636122 -362.508898) (xy 353.616199 -362.456807) (xy 353.604073 -362.40237) (xy 353.600002 -362.346748)
			(xy 351.653899 -362.346748) (xy 351.656115 -362.348592) (xy 351.693332 -362.390129) (xy 351.724105 -362.436642)
			(xy 351.747777 -362.487139) (xy 351.763845 -362.540546) (xy 351.771965 -362.595722) (xy 351.772474 -362.623608)
			(xy 351.771965 -362.651494) (xy 351.763845 -362.70667) (xy 351.747777 -362.760077) (xy 351.724105 -362.810574)
			(xy 351.693332 -362.857087) (xy 351.656115 -362.898624) (xy 351.613247 -362.934299) (xy 351.565641 -362.963353)
			(xy 351.514312 -362.985165) (xy 351.460355 -362.999271) (xy 351.404918 -363.005371) (xy 351.349184 -363.003334)
			(xy 351.294341 -362.993204) (xy 351.241557 -362.975197) (xy 351.191957 -362.949696) (xy 351.146599 -362.917245)
			(xy 351.10645 -362.878536) (xy 351.072364 -362.834393) (xy 351.045068 -362.785758) (xy 351.025145 -362.733667)
			(xy 351.013019 -362.67923) (xy 351.008948 -362.623608) (xy 347.057083 -362.623608) (xy 347.072056 -362.640319)
			(xy 347.102829 -362.686832) (xy 347.126501 -362.737329) (xy 347.142569 -362.790736) (xy 347.150689 -362.845912)
			(xy 347.151198 -362.873798) (xy 347.150689 -362.901684) (xy 347.142569 -362.95686) (xy 347.126501 -363.010267)
			(xy 347.102829 -363.060764) (xy 347.072056 -363.107277) (xy 347.034839 -363.148814) (xy 346.991971 -363.184489)
			(xy 346.944365 -363.213543) (xy 346.893036 -363.235355) (xy 346.839079 -363.249461) (xy 346.783642 -363.255561)
			(xy 346.727908 -363.253524) (xy 346.673065 -363.243394) (xy 346.620281 -363.225387) (xy 346.570681 -363.199886)
			(xy 346.525323 -363.167435) (xy 346.485174 -363.128726) (xy 346.451088 -363.084583) (xy 346.423792 -363.035948)
			(xy 346.403869 -362.983857) (xy 346.391743 -362.92942) (xy 346.387672 -362.873798) (xy 345.855933 -362.873798)
			(xy 345.8556 -362.876331) (xy 345.84053 -362.932587) (xy 345.81824 -362.986391) (xy 345.789112 -363.036823)
			(xy 345.753646 -363.083016) (xy 345.73337 -363.103922) (xy 345.243404 -363.593888) (xy 346.993462 -363.593888)
			(xy 346.997533 -363.538266) (xy 347.009659 -363.483829) (xy 347.029582 -363.431738) (xy 347.056878 -363.383103)
			(xy 347.090964 -363.33896) (xy 347.131113 -363.300251) (xy 347.176471 -363.2678) (xy 347.226071 -363.242299)
			(xy 347.278855 -363.224292) (xy 347.333698 -363.214162) (xy 347.389432 -363.212125) (xy 347.444869 -363.218225)
			(xy 347.498826 -363.232331) (xy 347.550155 -363.254143) (xy 347.597761 -363.283197) (xy 347.640629 -363.318872)
			(xy 347.677846 -363.360409) (xy 347.708619 -363.406922) (xy 347.732291 -363.457419) (xy 347.748359 -363.510826)
			(xy 347.756479 -363.566002) (xy 347.756988 -363.593888) (xy 347.756479 -363.621774) (xy 347.754116 -363.63783)
			(xy 352.31146 -363.63783) (xy 352.315531 -363.582208) (xy 352.327657 -363.527771) (xy 352.34758 -363.47568)
			(xy 352.374876 -363.427045) (xy 352.408962 -363.382902) (xy 352.449111 -363.344193) (xy 352.494469 -363.311742)
			(xy 352.544069 -363.286241) (xy 352.596853 -363.268234) (xy 352.651696 -363.258104) (xy 352.70743 -363.256067)
			(xy 352.762867 -363.262167) (xy 352.816824 -363.276273) (xy 352.820083 -363.277658) (xy 354.17836 -363.277658)
			(xy 354.182431 -363.222036) (xy 354.194557 -363.167599) (xy 354.21448 -363.115508) (xy 354.241776 -363.066873)
			(xy 354.275862 -363.02273) (xy 354.316011 -362.984021) (xy 354.361369 -362.95157) (xy 354.410969 -362.926069)
			(xy 354.463753 -362.908062) (xy 354.518596 -362.897932) (xy 354.57433 -362.895895) (xy 354.629767 -362.901995)
			(xy 354.683724 -362.916101) (xy 354.735053 -362.937913) (xy 354.782659 -362.966967) (xy 354.825527 -363.002642)
			(xy 354.862744 -363.044179) (xy 354.893517 -363.090692) (xy 354.917189 -363.141189) (xy 354.933257 -363.194596)
			(xy 354.941377 -363.249772) (xy 354.941886 -363.277658) (xy 354.941377 -363.305544) (xy 354.933257 -363.36072)
			(xy 354.917189 -363.414127) (xy 354.893517 -363.464624) (xy 354.862744 -363.511137) (xy 354.825527 -363.552674)
			(xy 354.782659 -363.588349) (xy 354.735053 -363.617403) (xy 354.683724 -363.639215) (xy 354.629767 -363.653321)
			(xy 354.57433 -363.659421) (xy 354.518596 -363.657384) (xy 354.463753 -363.647254) (xy 354.410969 -363.629247)
			(xy 354.361369 -363.603746) (xy 354.316011 -363.571295) (xy 354.275862 -363.532586) (xy 354.241776 -363.488443)
			(xy 354.21448 -363.439808) (xy 354.194557 -363.387717) (xy 354.182431 -363.33328) (xy 354.17836 -363.277658)
			(xy 352.820083 -363.277658) (xy 352.868153 -363.298085) (xy 352.915759 -363.327139) (xy 352.958627 -363.362814)
			(xy 352.995844 -363.404351) (xy 353.026617 -363.450864) (xy 353.050289 -363.501361) (xy 353.066357 -363.554768)
			(xy 353.074477 -363.609944) (xy 353.074986 -363.63783) (xy 353.074477 -363.665716) (xy 353.066357 -363.720892)
			(xy 353.050289 -363.774299) (xy 353.026617 -363.824796) (xy 352.995844 -363.871309) (xy 352.958627 -363.912846)
			(xy 352.915759 -363.948521) (xy 352.868153 -363.977575) (xy 352.816824 -363.999387) (xy 352.762867 -364.013493)
			(xy 352.70743 -364.019593) (xy 352.651696 -364.017556) (xy 352.596853 -364.007426) (xy 352.544069 -363.989419)
			(xy 352.494469 -363.963918) (xy 352.449111 -363.931467) (xy 352.408962 -363.892758) (xy 352.374876 -363.848615)
			(xy 352.34758 -363.79998) (xy 352.327657 -363.747889) (xy 352.315531 -363.693452) (xy 352.31146 -363.63783)
			(xy 347.754116 -363.63783) (xy 347.748359 -363.67695) (xy 347.732291 -363.730357) (xy 347.708619 -363.780854)
			(xy 347.677846 -363.827367) (xy 347.640629 -363.868904) (xy 347.597761 -363.904579) (xy 347.550155 -363.933633)
			(xy 347.498826 -363.955445) (xy 347.444869 -363.969551) (xy 347.389432 -363.975651) (xy 347.333698 -363.973614)
			(xy 347.278855 -363.963484) (xy 347.226071 -363.945477) (xy 347.176471 -363.919976) (xy 347.131113 -363.887525)
			(xy 347.090964 -363.848816) (xy 347.056878 -363.804673) (xy 347.029582 -363.756038) (xy 347.009659 -363.703947)
			(xy 346.997533 -363.64951) (xy 346.993462 -363.593888) (xy 345.243404 -363.593888) (xy 344.673682 -364.16361)
			(xy 347.661482 -364.16361) (xy 347.665553 -364.107988) (xy 347.677679 -364.053551) (xy 347.697602 -364.00146)
			(xy 347.724898 -363.952825) (xy 347.758984 -363.908682) (xy 347.799133 -363.869973) (xy 347.844491 -363.837522)
			(xy 347.894091 -363.812021) (xy 347.946875 -363.794014) (xy 348.001718 -363.783884) (xy 348.057452 -363.781847)
			(xy 348.112889 -363.787947) (xy 348.166846 -363.802053) (xy 348.218175 -363.823865) (xy 348.265781 -363.852919)
			(xy 348.308649 -363.888594) (xy 348.345866 -363.930131) (xy 348.376639 -363.976644) (xy 348.400311 -364.027141)
			(xy 348.416379 -364.080548) (xy 348.424499 -364.135724) (xy 348.425008 -364.16361) (xy 348.424499 -364.191496)
			(xy 348.416379 -364.246672) (xy 348.400311 -364.300079) (xy 348.376639 -364.350576) (xy 348.345866 -364.397089)
			(xy 348.330893 -364.4138) (xy 354.060504 -364.4138) (xy 354.064575 -364.358178) (xy 354.076701 -364.303741)
			(xy 354.096624 -364.25165) (xy 354.12392 -364.203015) (xy 354.158006 -364.158872) (xy 354.198155 -364.120163)
			(xy 354.243513 -364.087712) (xy 354.293113 -364.062211) (xy 354.345897 -364.044204) (xy 354.40074 -364.034074)
			(xy 354.456474 -364.032037) (xy 354.511911 -364.038137) (xy 354.565868 -364.052243) (xy 354.617197 -364.074055)
			(xy 354.664803 -364.103109) (xy 354.707671 -364.138784) (xy 354.744888 -364.180321) (xy 354.775661 -364.226834)
			(xy 354.799333 -364.277331) (xy 354.815401 -364.330738) (xy 354.823521 -364.385914) (xy 354.82403 -364.4138)
			(xy 354.823521 -364.441686) (xy 354.815401 -364.496862) (xy 354.799333 -364.550269) (xy 354.775661 -364.600766)
			(xy 354.744888 -364.647279) (xy 354.707671 -364.688816) (xy 354.664803 -364.724491) (xy 354.617197 -364.753545)
			(xy 354.565868 -364.775357) (xy 354.511911 -364.789463) (xy 354.456474 -364.795563) (xy 354.40074 -364.793526)
			(xy 354.345897 -364.783396) (xy 354.293113 -364.765389) (xy 354.243513 -364.739888) (xy 354.198155 -364.707437)
			(xy 354.158006 -364.668728) (xy 354.12392 -364.624585) (xy 354.096624 -364.57595) (xy 354.076701 -364.523859)
			(xy 354.064575 -364.469422) (xy 354.060504 -364.4138) (xy 348.330893 -364.4138) (xy 348.308649 -364.438626)
			(xy 348.265781 -364.474301) (xy 348.218175 -364.503355) (xy 348.166846 -364.525167) (xy 348.112889 -364.539273)
			(xy 348.057452 -364.545373) (xy 348.001718 -364.543336) (xy 347.946875 -364.533206) (xy 347.894091 -364.515199)
			(xy 347.844491 -364.489698) (xy 347.799133 -364.457247) (xy 347.758984 -364.418538) (xy 347.724898 -364.374395)
			(xy 347.697602 -364.32576) (xy 347.677679 -364.273669) (xy 347.665553 -364.219232) (xy 347.661482 -364.16361)
			(xy 344.673682 -364.16361) (xy 343.80043 -365.036862) (xy 343.779502 -365.057114) (xy 343.733309 -365.092578)
			(xy 343.682881 -365.121708) (xy 343.629083 -365.144006) (xy 343.572833 -365.159091) (xy 343.515096 -365.166703)
			(xy 343.485978 -365.167164) (xy 326.864218 -365.167164) (xy 326.835098 -365.166694) (xy 326.777356 -365.159101)
			(xy 326.7211 -365.144029) (xy 326.667296 -365.121737) (xy 326.616865 -365.092607) (xy 326.570671 -365.057139)
			(xy 326.549766 -365.036862) (xy 320.159126 -358.646222) (xy 320.138868 -358.6253) (xy 320.103405 -358.579105)
			(xy 320.074276 -358.528676) (xy 320.051979 -358.474876) (xy 320.036896 -358.418626) (xy 320.029284 -358.360889)
			(xy 320.028824 -358.33177) (xy 320.028824 -347.476826) (xy 320.013712 -347.448473) (xy 319.989964 -347.388774)
			(xy 319.973915 -347.326562) (xy 319.96582 -347.262825) (xy 319.965324 -347.2307) (xy 319.965324 -344.772996)
			(xy 319.089278 -343.89695) (xy 319.066112 -343.87304) (xy 319.025547 -343.820251) (xy 318.992222 -343.762617)
			(xy 318.966708 -343.701125) (xy 318.949441 -343.636828) (xy 318.940717 -343.570827) (xy 318.94018 -343.53754)
			(xy 301.880524 -343.53754) (xy 301.589694 -343.82837) (xy 300.317916 -343.82837) (xy 300.30417 -343.82882)
			(xy 300.277673 -343.836151) (xy 300.254092 -343.850285) (xy 300.235137 -343.870198) (xy 300.222182 -343.894446)
			(xy 300.216166 -343.921272) (xy 300.217525 -343.948731) (xy 300.226161 -343.974831) (xy 300.241447 -343.997682)
			(xy 300.251622 -344.006932) (xy 300.285742 -344.035021) (xy 300.348834 -344.096915) (xy 300.405473 -344.164763)
			(xy 300.455102 -344.237897) (xy 300.49723 -344.315593) (xy 300.531441 -344.397086) (xy 300.557397 -344.481571)
			(xy 300.574844 -344.568214) (xy 300.583608 -344.656161) (xy 300.584108 -344.700352) (xy 300.583604 -344.7427)
			(xy 300.575553 -344.827014) (xy 300.559524 -344.91018) (xy 300.535663 -344.991447) (xy 300.504184 -345.070077)
			(xy 300.465373 -345.145358) (xy 300.419583 -345.21661) (xy 300.367227 -345.283186) (xy 300.308779 -345.344484)
			(xy 300.244769 -345.399949) (xy 300.175777 -345.449078) (xy 300.102427 -345.491427) (xy 300.025384 -345.526611)
			(xy 299.945345 -345.554313) (xy 299.863036 -345.574281) (xy 299.779201 -345.586334) (xy 299.6946 -345.590365)
			(xy 299.609999 -345.586334) (xy 299.526164 -345.574281) (xy 299.443855 -345.554313) (xy 299.363816 -345.526611)
			(xy 299.286773 -345.491427) (xy 299.213423 -345.449078) (xy 299.144431 -345.399949) (xy 299.080421 -345.344484)
			(xy 299.021973 -345.283186) (xy 298.969617 -345.21661) (xy 298.923827 -345.145358) (xy 298.885016 -345.070077)
			(xy 298.853537 -344.991447) (xy 298.829676 -344.91018) (xy 298.813647 -344.827014) (xy 298.805596 -344.7427)
			(xy 298.805092 -344.700352) (xy 298.805639 -344.656163) (xy 298.814409 -344.568221) (xy 298.831858 -344.481583)
			(xy 298.857815 -344.397103) (xy 298.892022 -344.315613) (xy 298.934143 -344.237919) (xy 298.983763 -344.164785)
			(xy 299.040391 -344.096933) (xy 299.10347 -344.035032) (xy 299.137578 -344.006932) (xy 299.147689 -343.997626)
			(xy 299.162962 -343.974794) (xy 299.171591 -343.948715) (xy 299.172949 -343.921279) (xy 299.166938 -343.894476)
			(xy 299.153993 -343.870248) (xy 299.135054 -343.850351) (xy 299.111493 -343.836229) (xy 299.085019 -343.828904)
			(xy 299.071284 -343.82837) (xy 294.120316 -343.82837) (xy 294.10657 -343.82882) (xy 294.080073 -343.836151)
			(xy 294.056492 -343.850285) (xy 294.037537 -343.870198) (xy 294.024582 -343.894446) (xy 294.018566 -343.921272)
			(xy 294.019925 -343.948731) (xy 294.028561 -343.974831) (xy 294.043847 -343.997682) (xy 294.054022 -344.006932)
			(xy 294.088142 -344.035021) (xy 294.151234 -344.096915) (xy 294.207873 -344.164763) (xy 294.257502 -344.237897)
			(xy 294.29963 -344.315593) (xy 294.333841 -344.397086) (xy 294.359797 -344.481571) (xy 294.377244 -344.568214)
			(xy 294.386008 -344.656161) (xy 294.386508 -344.700352) (xy 294.386004 -344.7427) (xy 294.377953 -344.827014)
			(xy 294.361924 -344.91018) (xy 294.338063 -344.991447) (xy 294.306584 -345.070077) (xy 294.267773 -345.145358)
			(xy 294.221983 -345.21661) (xy 294.169627 -345.283186) (xy 294.111179 -345.344484) (xy 294.047169 -345.399949)
			(xy 293.978177 -345.449078) (xy 293.904827 -345.491427) (xy 293.827784 -345.526611) (xy 293.747745 -345.554313)
			(xy 293.665436 -345.574281) (xy 293.581601 -345.586334) (xy 293.497 -345.590365) (xy 293.412399 -345.586334)
			(xy 293.328564 -345.574281) (xy 293.246255 -345.554313) (xy 293.166216 -345.526611) (xy 293.089173 -345.491427)
			(xy 293.015823 -345.449078) (xy 292.946831 -345.399949) (xy 292.882821 -345.344484) (xy 292.824373 -345.283186)
			(xy 292.772017 -345.21661) (xy 292.726227 -345.145358) (xy 292.687416 -345.070077) (xy 292.655937 -344.991447)
			(xy 292.632076 -344.91018) (xy 292.616047 -344.827014) (xy 292.607996 -344.7427) (xy 292.607492 -344.700352)
			(xy 292.607996 -344.657715) (xy 292.616163 -344.572832) (xy 292.632416 -344.48912) (xy 292.656607 -344.407348)
			(xy 292.688513 -344.328267) (xy 292.727842 -344.252603) (xy 292.774232 -344.181051) (xy 292.827258 -344.114267)
			(xy 292.886432 -344.052865) (xy 292.951212 -343.997409) (xy 293.021002 -343.948407) (xy 293.057834 -343.926922)
			(xy 293.063676 -343.92362) (xy 293.072312 -343.914984) (xy 293.079011 -343.907553) (xy 293.086607 -343.889068)
			(xy 293.086557 -343.869082) (xy 293.078869 -343.850635) (xy 293.064712 -343.836528) (xy 293.046237 -343.828907)
			(xy 293.036244 -343.82837) (xy 292.945058 -343.82837) (xy 292.93693 -343.831164) (xy 292.911458 -343.839232)
			(xy 292.858742 -343.847921) (xy 292.832028 -343.848436) (xy 287.921192 -343.848436) (xy 287.770824 -343.698068)
			(xy 286.88919 -343.698068) (xy 284.90799 -345.679268) (xy 284.90418 -345.681808) (xy 283.905452 -346.680536)
			(xy 283.350462 -348.146878) (xy 281.656028 -349.841312) (xy 281.656028 -351.8408) (xy 285.286958 -351.8408)
			(xy 285.28741 -351.813429) (xy 285.295229 -351.759249) (xy 285.310721 -351.706745) (xy 285.333566 -351.656998)
			(xy 285.363295 -351.611033) (xy 285.380938 -351.590102) (xy 285.390172 -351.578773) (xy 285.402345 -351.552215)
			(xy 285.406515 -351.5233) (xy 285.402345 -351.494385) (xy 285.390172 -351.467827) (xy 285.380938 -351.456498)
			(xy 285.363297 -351.435565) (xy 285.333571 -351.389598) (xy 285.310725 -351.339852) (xy 285.295228 -351.28735)
			(xy 285.2874 -351.233171) (xy 285.2874 -351.178429) (xy 285.295228 -351.12425) (xy 285.310725 -351.071748)
			(xy 285.333571 -351.022002) (xy 285.363297 -350.976035) (xy 285.380938 -350.955102) (xy 285.390172 -350.943773)
			(xy 285.402345 -350.917215) (xy 285.406515 -350.8883) (xy 285.402345 -350.859385) (xy 285.390172 -350.832827)
			(xy 285.380938 -350.821498) (xy 285.363297 -350.800565) (xy 285.333571 -350.754598) (xy 285.310725 -350.704852)
			(xy 285.295228 -350.65235) (xy 285.2874 -350.598171) (xy 285.2874 -350.543429) (xy 285.295228 -350.48925)
			(xy 285.310725 -350.436748) (xy 285.333571 -350.387002) (xy 285.363297 -350.341035) (xy 285.380938 -350.320102)
			(xy 285.390172 -350.308773) (xy 285.402345 -350.282215) (xy 285.406515 -350.2533) (xy 285.402345 -350.224385)
			(xy 285.390172 -350.197827) (xy 285.380938 -350.186498) (xy 285.363297 -350.165565) (xy 285.333571 -350.119598)
			(xy 285.310725 -350.069852) (xy 285.295228 -350.01735) (xy 285.2874 -349.963171) (xy 285.2874 -349.908429)
			(xy 285.295228 -349.85425) (xy 285.310725 -349.801748) (xy 285.333571 -349.752002) (xy 285.363297 -349.706035)
			(xy 285.380938 -349.685102) (xy 285.390172 -349.673773) (xy 285.402345 -349.647215) (xy 285.406515 -349.6183)
			(xy 285.402345 -349.589385) (xy 285.390172 -349.562827) (xy 285.380938 -349.551498) (xy 285.363297 -349.530565)
			(xy 285.333571 -349.484598) (xy 285.310725 -349.434852) (xy 285.295228 -349.38235) (xy 285.2874 -349.328171)
			(xy 285.2874 -349.273429) (xy 285.295228 -349.21925) (xy 285.310725 -349.166748) (xy 285.333571 -349.117002)
			(xy 285.363297 -349.071035) (xy 285.380938 -349.050102) (xy 285.390172 -349.038773) (xy 285.402345 -349.012215)
			(xy 285.406515 -348.9833) (xy 285.402345 -348.954385) (xy 285.390172 -348.927827) (xy 285.380938 -348.916498)
			(xy 285.363297 -348.895565) (xy 285.333571 -348.849598) (xy 285.310725 -348.799852) (xy 285.295228 -348.74735)
			(xy 285.2874 -348.693171) (xy 285.2874 -348.638429) (xy 285.295228 -348.58425) (xy 285.310725 -348.531748)
			(xy 285.333571 -348.482002) (xy 285.363297 -348.436035) (xy 285.380938 -348.415102) (xy 285.390172 -348.403773)
			(xy 285.402345 -348.377215) (xy 285.406515 -348.3483) (xy 285.402345 -348.319385) (xy 285.390172 -348.292827)
			(xy 285.380938 -348.281498) (xy 285.36329 -348.260573) (xy 285.333579 -348.214599) (xy 285.310744 -348.164849)
			(xy 285.295255 -348.112347) (xy 285.28743 -348.05817) (xy 285.286958 -348.0308) (xy 285.287478 -348.00355)
			(xy 285.295233 -347.949606) (xy 285.310587 -347.897314) (xy 285.333225 -347.847739) (xy 285.362689 -347.80189)
			(xy 285.398376 -347.7607) (xy 285.439563 -347.725009) (xy 285.485409 -347.695542) (xy 285.534982 -347.672899)
			(xy 285.587272 -347.657541) (xy 285.641216 -347.64978) (xy 285.668466 -347.649292) (xy 285.695835 -347.64978)
			(xy 285.750013 -347.657593) (xy 285.802516 -347.673077) (xy 285.852263 -347.695914) (xy 285.898231 -347.725633)
			(xy 285.919164 -347.743272) (xy 285.930492 -347.752508) (xy 285.957049 -347.764684) (xy 285.985966 -347.768857)
			(xy 286.014883 -347.764684) (xy 286.04144 -347.752508) (xy 286.052768 -347.743272) (xy 286.073698 -347.72563)
			(xy 286.119672 -347.69592) (xy 286.16942 -347.673085) (xy 286.221921 -347.657594) (xy 286.276097 -347.649766)
			(xy 286.303466 -347.649292) (xy 286.331506 -347.649802) (xy 286.386983 -347.657998) (xy 286.440665 -347.67422)
			(xy 286.491398 -347.698118) (xy 286.53809 -347.729179) (xy 286.559244 -347.74759) (xy 286.570686 -347.757235)
			(xy 286.597729 -347.770015) (xy 286.627316 -347.774401) (xy 286.656903 -347.770015) (xy 286.683946 -347.757235)
			(xy 286.695388 -347.74759) (xy 286.71379 -347.731553) (xy 286.753943 -347.703798) (xy 286.797303 -347.68138)
			(xy 286.820102 -347.67266) (xy 286.833437 -347.667262) (xy 286.856596 -347.650215) (xy 286.874094 -347.627394)
			(xy 286.884546 -347.600604) (xy 286.887126 -347.571964) (xy 286.88163 -347.543737) (xy 286.868493 -347.518156)
			(xy 286.848753 -347.497245) (xy 286.836612 -347.489526) (xy 286.799538 -347.467197) (xy 286.729339 -347.416569)
			(xy 286.664236 -347.359536) (xy 286.604811 -347.296608) (xy 286.551597 -347.228348) (xy 286.505069 -347.155367)
			(xy 286.465642 -347.078317) (xy 286.433671 -346.997887) (xy 286.40944 -346.914797) (xy 286.393166 -346.829789)
			(xy 286.384995 -346.743624) (xy 286.384492 -346.700348) (xy 286.38498 -346.658072) (xy 286.392782 -346.57388)
			(xy 286.408318 -346.490767) (xy 286.431457 -346.409443) (xy 286.462001 -346.3306) (xy 286.499689 -346.254912)
			(xy 286.5442 -346.183024) (xy 286.595154 -346.11555) (xy 286.652117 -346.053065) (xy 286.714602 -345.996102)
			(xy 286.782076 -345.945148) (xy 286.853964 -345.900637) (xy 286.929652 -345.862949) (xy 287.008495 -345.832405)
			(xy 287.089819 -345.809266) (xy 287.172932 -345.79373) (xy 287.257124 -345.785928) (xy 287.341676 -345.785928)
			(xy 287.425868 -345.79373) (xy 287.508981 -345.809266) (xy 287.590305 -345.832405) (xy 287.669148 -345.862949)
			(xy 287.744836 -345.900637) (xy 287.816724 -345.945148) (xy 287.884198 -345.996102) (xy 287.946683 -346.053065)
			(xy 288.003646 -346.11555) (xy 288.0546 -346.183024) (xy 288.099111 -346.254912) (xy 288.136799 -346.3306)
			(xy 288.167343 -346.409443) (xy 288.190482 -346.490767) (xy 288.206018 -346.57388) (xy 288.21382 -346.658072)
			(xy 288.214308 -346.700348) (xy 292.581589 -346.700348) (xy 292.585611 -346.614628) (xy 292.597642 -346.52966)
			(xy 292.617578 -346.446193) (xy 292.645241 -346.364959) (xy 292.68039 -346.286673) (xy 292.722716 -346.212022)
			(xy 292.771845 -346.141663) (xy 292.827348 -346.076213) (xy 292.888735 -346.016249) (xy 292.955468 -345.962296)
			(xy 293.02696 -345.914829) (xy 293.102582 -345.874265) (xy 293.181671 -345.840961) (xy 293.263531 -345.815209)
			(xy 293.347442 -345.797236) (xy 293.432668 -345.7872) (xy 293.51846 -345.785188) (xy 293.604062 -345.791219)
			(xy 293.688724 -345.805239) (xy 293.771701 -345.827125) (xy 293.852264 -345.856686) (xy 293.929704 -345.89366)
			(xy 294.003343 -345.937724) (xy 294.072531 -345.98849) (xy 294.136662 -346.045511) (xy 294.195171 -346.108287)
			(xy 294.247544 -346.176267) (xy 294.293322 -346.248852) (xy 294.332102 -346.325404) (xy 294.363543 -346.405252)
			(xy 294.387369 -346.487693) (xy 294.40337 -346.572003) (xy 294.411405 -346.657441) (xy 294.411908 -346.700348)
			(xy 298.779189 -346.700348) (xy 298.783211 -346.614628) (xy 298.795242 -346.52966) (xy 298.815178 -346.446193)
			(xy 298.842841 -346.364959) (xy 298.87799 -346.286673) (xy 298.920316 -346.212022) (xy 298.969445 -346.141663)
			(xy 299.024948 -346.076213) (xy 299.086335 -346.016249) (xy 299.153068 -345.962296) (xy 299.22456 -345.914829)
			(xy 299.300182 -345.874265) (xy 299.379271 -345.840961) (xy 299.461131 -345.815209) (xy 299.545042 -345.797236)
			(xy 299.630268 -345.7872) (xy 299.71606 -345.785188) (xy 299.801662 -345.791219) (xy 299.886324 -345.805239)
			(xy 299.969301 -345.827125) (xy 300.049864 -345.856686) (xy 300.127304 -345.89366) (xy 300.200943 -345.937724)
			(xy 300.270131 -345.98849) (xy 300.334262 -346.045511) (xy 300.392771 -346.108287) (xy 300.445144 -346.176267)
			(xy 300.490922 -346.248852) (xy 300.529702 -346.325404) (xy 300.561143 -346.405252) (xy 300.584969 -346.487693)
			(xy 300.60097 -346.572003) (xy 300.609005 -346.657441) (xy 300.609508 -346.700348) (xy 300.609005 -346.743255)
			(xy 300.60097 -346.828693) (xy 300.584969 -346.913003) (xy 300.561143 -346.995444) (xy 300.529702 -347.075292)
			(xy 300.490922 -347.151844) (xy 300.445144 -347.224429) (xy 300.392771 -347.292409) (xy 300.334262 -347.355185)
			(xy 300.270131 -347.412206) (xy 300.200943 -347.462972) (xy 300.127304 -347.507036) (xy 300.049864 -347.54401)
			(xy 299.969301 -347.573571) (xy 299.886324 -347.595457) (xy 299.801662 -347.609477) (xy 299.71606 -347.615508)
			(xy 299.630268 -347.613496) (xy 299.545042 -347.60346) (xy 299.461131 -347.585487) (xy 299.379271 -347.559735)
			(xy 299.300182 -347.526431) (xy 299.22456 -347.485867) (xy 299.153068 -347.4384) (xy 299.086335 -347.384447)
			(xy 299.024948 -347.324483) (xy 298.969445 -347.259033) (xy 298.920316 -347.188674) (xy 298.87799 -347.114023)
			(xy 298.842841 -347.035737) (xy 298.815178 -346.954503) (xy 298.795242 -346.871036) (xy 298.783211 -346.786068)
			(xy 298.779189 -346.700348) (xy 294.411908 -346.700348) (xy 294.411405 -346.743255) (xy 294.40337 -346.828693)
			(xy 294.387369 -346.913003) (xy 294.363543 -346.995444) (xy 294.332102 -347.075292) (xy 294.293322 -347.151844)
			(xy 294.247544 -347.224429) (xy 294.195171 -347.292409) (xy 294.136662 -347.355185) (xy 294.072531 -347.412206)
			(xy 294.003343 -347.462972) (xy 293.929704 -347.507036) (xy 293.852264 -347.54401) (xy 293.771701 -347.573571)
			(xy 293.688724 -347.595457) (xy 293.604062 -347.609477) (xy 293.51846 -347.615508) (xy 293.432668 -347.613496)
			(xy 293.347442 -347.60346) (xy 293.263531 -347.585487) (xy 293.181671 -347.559735) (xy 293.102582 -347.526431)
			(xy 293.02696 -347.485867) (xy 292.955468 -347.4384) (xy 292.888735 -347.384447) (xy 292.827348 -347.324483)
			(xy 292.771845 -347.259033) (xy 292.722716 -347.188674) (xy 292.68039 -347.114023) (xy 292.645241 -347.035737)
			(xy 292.617578 -346.954503) (xy 292.597642 -346.871036) (xy 292.585611 -346.786068) (xy 292.581589 -346.700348)
			(xy 288.214308 -346.700348) (xy 288.21379 -346.742119) (xy 288.206161 -346.825312) (xy 288.190979 -346.907463)
			(xy 288.168372 -346.987888) (xy 288.138526 -347.065917) (xy 288.101692 -347.140901) (xy 288.058175 -347.212214)
			(xy 288.008338 -347.279263) (xy 287.952597 -347.34149) (xy 287.891415 -347.398376) (xy 287.825301 -347.449448)
			(xy 287.754807 -347.49428) (xy 287.68052 -347.532499) (xy 287.603058 -347.563786) (xy 287.523066 -347.587882)
			(xy 287.44121 -347.604585) (xy 287.358173 -347.613756) (xy 287.316418 -347.615002) (xy 287.302046 -347.615754)
			(xy 287.274565 -347.624259) (xy 287.250547 -347.640089) (xy 287.231895 -347.661989) (xy 287.22009 -347.688222)
			(xy 287.216068 -347.716706) (xy 287.220149 -347.745181) (xy 287.232008 -347.771389) (xy 287.24098 -347.782642)
			(xy 287.258186 -347.803491) (xy 287.287192 -347.849105) (xy 287.309471 -347.898356) (xy 287.324576 -347.950258)
			(xy 287.332204 -348.003772) (xy 287.332674 -348.0308) (xy 287.332214 -348.058171) (xy 287.324396 -348.11235)
			(xy 287.308906 -348.164854) (xy 287.286062 -348.2146) (xy 287.256336 -348.260567) (xy 287.238694 -348.281498)
			(xy 287.229458 -348.292825) (xy 287.217281 -348.319383) (xy 287.213109 -348.3483) (xy 287.217281 -348.377217)
			(xy 287.229458 -348.403775) (xy 287.238694 -348.415102) (xy 287.256334 -348.436035) (xy 287.286057 -348.482003)
			(xy 287.308901 -348.53175) (xy 287.324396 -348.584252) (xy 287.332225 -348.63843) (xy 287.332225 -348.69317)
			(xy 287.324396 -348.747348) (xy 287.308901 -348.79985) (xy 287.286057 -348.849597) (xy 287.256334 -348.895565)
			(xy 287.238694 -348.916498) (xy 287.229458 -348.927825) (xy 287.217281 -348.954383) (xy 287.213109 -348.9833)
			(xy 287.217281 -349.012217) (xy 287.229458 -349.038775) (xy 287.238694 -349.050102) (xy 287.256334 -349.071035)
			(xy 287.286057 -349.117003) (xy 287.308901 -349.16675) (xy 287.324396 -349.219252) (xy 287.332225 -349.27343)
			(xy 287.332225 -349.32817) (xy 287.324396 -349.382348) (xy 287.308901 -349.43485) (xy 287.286057 -349.484597)
			(xy 287.256334 -349.530565) (xy 287.238694 -349.551498) (xy 287.229458 -349.562825) (xy 287.217281 -349.589383)
			(xy 287.213109 -349.6183) (xy 287.217281 -349.647217) (xy 287.229458 -349.673775) (xy 287.238694 -349.685102)
			(xy 287.256334 -349.706035) (xy 287.286057 -349.752003) (xy 287.308901 -349.80175) (xy 287.324396 -349.854252)
			(xy 287.332225 -349.90843) (xy 287.332225 -349.96317) (xy 287.324396 -350.017348) (xy 287.308901 -350.06985)
			(xy 287.286057 -350.119597) (xy 287.256334 -350.165565) (xy 287.238694 -350.186498) (xy 287.229458 -350.197825)
			(xy 287.217281 -350.224383) (xy 287.213109 -350.2533) (xy 287.217281 -350.282217) (xy 287.229458 -350.308775)
			(xy 287.238694 -350.320102) (xy 287.256334 -350.341035) (xy 287.286057 -350.387003) (xy 287.308901 -350.43675)
			(xy 287.324396 -350.489252) (xy 287.332225 -350.54343) (xy 287.332225 -350.59817) (xy 287.324396 -350.652348)
			(xy 287.308901 -350.70485) (xy 287.286057 -350.754597) (xy 287.256334 -350.800565) (xy 287.238694 -350.821498)
			(xy 287.229458 -350.832825) (xy 287.217281 -350.859383) (xy 287.213109 -350.8883) (xy 287.217281 -350.917217)
			(xy 287.229458 -350.943775) (xy 287.238694 -350.955102) (xy 287.256334 -350.976035) (xy 287.286057 -351.022003)
			(xy 287.308901 -351.07175) (xy 287.324396 -351.124252) (xy 287.332225 -351.17843) (xy 287.332225 -351.23317)
			(xy 287.324396 -351.287348) (xy 287.308901 -351.33985) (xy 287.286057 -351.389597) (xy 287.256334 -351.435565)
			(xy 287.238694 -351.456498) (xy 287.229458 -351.467825) (xy 287.217281 -351.494383) (xy 287.213109 -351.5233)
			(xy 287.217281 -351.552217) (xy 287.229458 -351.578775) (xy 287.238694 -351.590102) (xy 287.256347 -351.611023)
			(xy 287.286057 -351.656999) (xy 287.30889 -351.706749) (xy 287.324378 -351.759252) (xy 287.332202 -351.81343)
			(xy 287.332674 -351.8408) (xy 290.25723 -351.8408) (xy 290.257689 -351.813429) (xy 290.265507 -351.75925)
			(xy 290.280998 -351.706746) (xy 290.303841 -351.656999) (xy 290.333568 -351.611033) (xy 290.35121 -351.590102)
			(xy 290.360446 -351.578774) (xy 290.372622 -351.552217) (xy 290.376794 -351.5233) (xy 290.372622 -351.494383)
			(xy 290.360446 -351.467826) (xy 290.35121 -351.456498) (xy 290.33357 -351.435565) (xy 290.303847 -351.389597)
			(xy 290.281002 -351.33985) (xy 290.265507 -351.287349) (xy 290.257678 -351.23317) (xy 290.257678 -351.17843)
			(xy 290.265507 -351.124251) (xy 290.281002 -351.07175) (xy 290.303847 -351.022003) (xy 290.33357 -350.976035)
			(xy 290.35121 -350.955102) (xy 290.360446 -350.943774) (xy 290.372622 -350.917217) (xy 290.376794 -350.8883)
			(xy 290.372622 -350.859383) (xy 290.360446 -350.832826) (xy 290.35121 -350.821498) (xy 290.33357 -350.800565)
			(xy 290.303847 -350.754597) (xy 290.281002 -350.70485) (xy 290.265507 -350.652349) (xy 290.257678 -350.59817)
			(xy 290.257678 -350.54343) (xy 290.265507 -350.489251) (xy 290.281002 -350.43675) (xy 290.303847 -350.387003)
			(xy 290.33357 -350.341035) (xy 290.35121 -350.320102) (xy 290.360446 -350.308774) (xy 290.372622 -350.282217)
			(xy 290.376794 -350.2533) (xy 290.372622 -350.224383) (xy 290.360446 -350.197826) (xy 290.35121 -350.186498)
			(xy 290.33357 -350.165565) (xy 290.303847 -350.119597) (xy 290.281002 -350.06985) (xy 290.265507 -350.017349)
			(xy 290.257678 -349.96317) (xy 290.257678 -349.90843) (xy 290.265507 -349.854251) (xy 290.281002 -349.80175)
			(xy 290.303847 -349.752003) (xy 290.33357 -349.706035) (xy 290.35121 -349.685102) (xy 290.360446 -349.673774)
			(xy 290.372622 -349.647217) (xy 290.376794 -349.6183) (xy 290.372622 -349.589383) (xy 290.360446 -349.562826)
			(xy 290.35121 -349.551498) (xy 290.33357 -349.530565) (xy 290.303847 -349.484597) (xy 290.281002 -349.43485)
			(xy 290.265507 -349.382349) (xy 290.257678 -349.32817) (xy 290.257678 -349.27343) (xy 290.265507 -349.219251)
			(xy 290.281002 -349.16675) (xy 290.303847 -349.117003) (xy 290.33357 -349.071035) (xy 290.35121 -349.050102)
			(xy 290.360446 -349.038774) (xy 290.372622 -349.012217) (xy 290.376794 -348.9833) (xy 290.372622 -348.954383)
			(xy 290.360446 -348.927826) (xy 290.35121 -348.916498) (xy 290.33357 -348.895565) (xy 290.303847 -348.849597)
			(xy 290.281002 -348.79985) (xy 290.265507 -348.747349) (xy 290.257678 -348.69317) (xy 290.257678 -348.63843)
			(xy 290.265507 -348.584251) (xy 290.281002 -348.53175) (xy 290.303847 -348.482003) (xy 290.33357 -348.436035)
			(xy 290.35121 -348.415102) (xy 290.360446 -348.403774) (xy 290.372622 -348.377217) (xy 290.376794 -348.3483)
			(xy 290.372622 -348.319383) (xy 290.360446 -348.292826) (xy 290.35121 -348.281498) (xy 290.333558 -348.260576)
			(xy 290.303848 -348.214601) (xy 290.281014 -348.164851) (xy 290.265526 -348.112348) (xy 290.257702 -348.05817)
			(xy 290.25723 -348.0308) (xy 290.257655 -348.003545) (xy 290.265413 -347.949591) (xy 290.280771 -347.89729)
			(xy 290.303417 -347.847708) (xy 290.332888 -347.801853) (xy 290.368586 -347.760659) (xy 290.409783 -347.724965)
			(xy 290.455641 -347.695498) (xy 290.505226 -347.672858) (xy 290.557528 -347.657505) (xy 290.611483 -347.649753)
			(xy 290.638738 -347.649292) (xy 290.666779 -347.649759) (xy 290.722259 -347.657966) (xy 290.775941 -347.674198)
			(xy 290.826673 -347.698105) (xy 290.873363 -347.729175) (xy 290.894516 -347.74759) (xy 290.905958 -347.757235)
			(xy 290.933001 -347.770015) (xy 290.962588 -347.774401) (xy 290.992175 -347.770015) (xy 291.019218 -347.757235)
			(xy 291.03066 -347.74759) (xy 291.051808 -347.729166) (xy 291.098486 -347.698072) (xy 291.149217 -347.674157)
			(xy 291.202907 -347.657938) (xy 291.258395 -347.649765) (xy 291.286438 -347.649292) (xy 291.313807 -347.649796)
			(xy 291.367984 -347.657605) (xy 291.420487 -347.673085) (xy 291.470234 -347.695919) (xy 291.516203 -347.725635)
			(xy 291.537136 -347.743272) (xy 291.548464 -347.752508) (xy 291.575021 -347.764684) (xy 291.603938 -347.768857)
			(xy 291.632855 -347.764684) (xy 291.659412 -347.752508) (xy 291.67074 -347.743272) (xy 291.69168 -347.725643)
			(xy 291.737651 -347.695931) (xy 291.787397 -347.673093) (xy 291.839895 -347.6576) (xy 291.894069 -347.649768)
			(xy 291.921438 -347.649292) (xy 291.94869 -347.649742) (xy 292.002639 -347.657504) (xy 292.054935 -347.672864)
			(xy 292.104512 -347.69551) (xy 292.150362 -347.72498) (xy 292.191552 -347.760675) (xy 292.227243 -347.801868)
			(xy 292.256709 -347.847721) (xy 292.279349 -347.897301) (xy 292.294704 -347.949598) (xy 292.30246 -348.003548)
			(xy 292.302946 -348.0308) (xy 292.302493 -348.058171) (xy 292.294674 -348.112351) (xy 292.279183 -348.164855)
			(xy 292.256338 -348.214602) (xy 292.226609 -348.260567) (xy 292.208966 -348.281498) (xy 292.199732 -348.292826)
			(xy 292.187559 -348.319384) (xy 292.183388 -348.3483) (xy 292.187559 -348.377216) (xy 292.199732 -348.403774)
			(xy 292.208966 -348.415102) (xy 292.226607 -348.436035) (xy 292.256332 -348.482002) (xy 292.279178 -348.531748)
			(xy 292.294675 -348.584251) (xy 292.302503 -348.638429) (xy 292.302503 -348.693171) (xy 292.294675 -348.747349)
			(xy 292.279178 -348.799852) (xy 292.256332 -348.849598) (xy 292.226607 -348.895565) (xy 292.208966 -348.916498)
			(xy 292.199732 -348.927826) (xy 292.187559 -348.954384) (xy 292.183388 -348.9833) (xy 292.187559 -349.012216)
			(xy 292.199732 -349.038774) (xy 292.208966 -349.050102) (xy 292.226607 -349.071035) (xy 292.256332 -349.117002)
			(xy 292.279178 -349.166748) (xy 292.294675 -349.219251) (xy 292.302503 -349.273429) (xy 292.302503 -349.328171)
			(xy 292.294675 -349.382349) (xy 292.279178 -349.434852) (xy 292.256332 -349.484598) (xy 292.226607 -349.530565)
			(xy 292.208966 -349.551498) (xy 292.199732 -349.562826) (xy 292.187559 -349.589384) (xy 292.183388 -349.6183)
			(xy 292.187559 -349.647216) (xy 292.199732 -349.673774) (xy 292.208966 -349.685102) (xy 292.226607 -349.706035)
			(xy 292.256332 -349.752002) (xy 292.279178 -349.801748) (xy 292.294675 -349.854251) (xy 292.302503 -349.908429)
			(xy 292.302503 -349.963171) (xy 292.294675 -350.017349) (xy 292.279178 -350.069852) (xy 292.256332 -350.119598)
			(xy 292.226607 -350.165565) (xy 292.208966 -350.186498) (xy 292.199732 -350.197826) (xy 292.187559 -350.224384)
			(xy 292.183388 -350.2533) (xy 292.187559 -350.282216) (xy 292.199732 -350.308774) (xy 292.208966 -350.320102)
			(xy 292.226607 -350.341035) (xy 292.256332 -350.387002) (xy 292.279178 -350.436748) (xy 292.294675 -350.489251)
			(xy 292.302503 -350.543429) (xy 292.302503 -350.598171) (xy 292.294675 -350.652349) (xy 292.279178 -350.704852)
			(xy 292.256332 -350.754598) (xy 292.226607 -350.800565) (xy 292.208966 -350.821498) (xy 292.199732 -350.832826)
			(xy 292.187559 -350.859384) (xy 292.183388 -350.8883) (xy 292.187559 -350.917216) (xy 292.199732 -350.943774)
			(xy 292.208966 -350.955102) (xy 292.226607 -350.976035) (xy 292.256332 -351.022002) (xy 292.279178 -351.071748)
			(xy 292.294675 -351.124251) (xy 292.302503 -351.178429) (xy 292.302503 -351.233171) (xy 292.294675 -351.287349)
			(xy 292.279178 -351.339852) (xy 292.256332 -351.389598) (xy 292.226607 -351.435565) (xy 292.208966 -351.456498)
			(xy 292.199732 -351.467826) (xy 292.187559 -351.494384) (xy 292.183388 -351.5233) (xy 292.187559 -351.552216)
			(xy 292.199732 -351.578774) (xy 292.208966 -351.590102) (xy 292.226614 -351.611027) (xy 292.256326 -351.657001)
			(xy 292.279161 -351.70675) (xy 292.294649 -351.759253) (xy 292.302474 -351.81343) (xy 292.302946 -351.8408)
			(xy 294.964358 -351.8408) (xy 294.96481 -351.813429) (xy 294.972629 -351.759249) (xy 294.988121 -351.706745)
			(xy 295.010966 -351.656998) (xy 295.040695 -351.611033) (xy 295.058338 -351.590102) (xy 295.067572 -351.578773)
			(xy 295.079745 -351.552215) (xy 295.083915 -351.5233) (xy 295.079745 -351.494385) (xy 295.067572 -351.467827)
			(xy 295.058338 -351.456498) (xy 295.040697 -351.435565) (xy 295.010971 -351.389598) (xy 294.988125 -351.339852)
			(xy 294.972628 -351.28735) (xy 294.9648 -351.233171) (xy 294.9648 -351.178429) (xy 294.972628 -351.12425)
			(xy 294.988125 -351.071748) (xy 295.010971 -351.022002) (xy 295.040697 -350.976035) (xy 295.058338 -350.955102)
			(xy 295.067572 -350.943773) (xy 295.079745 -350.917215) (xy 295.083915 -350.8883) (xy 295.079745 -350.859385)
			(xy 295.067572 -350.832827) (xy 295.058338 -350.821498) (xy 295.040697 -350.800565) (xy 295.010971 -350.754598)
			(xy 294.988125 -350.704852) (xy 294.972628 -350.65235) (xy 294.9648 -350.598171) (xy 294.9648 -350.543429)
			(xy 294.972628 -350.48925) (xy 294.988125 -350.436748) (xy 295.010971 -350.387002) (xy 295.040697 -350.341035)
			(xy 295.058338 -350.320102) (xy 295.067572 -350.308773) (xy 295.079745 -350.282215) (xy 295.083915 -350.2533)
			(xy 295.079745 -350.224385) (xy 295.067572 -350.197827) (xy 295.058338 -350.186498) (xy 295.040697 -350.165565)
			(xy 295.010971 -350.119598) (xy 294.988125 -350.069852) (xy 294.972628 -350.01735) (xy 294.9648 -349.963171)
			(xy 294.9648 -349.908429) (xy 294.972628 -349.85425) (xy 294.988125 -349.801748) (xy 295.010971 -349.752002)
			(xy 295.040697 -349.706035) (xy 295.058338 -349.685102) (xy 295.067572 -349.673773) (xy 295.079745 -349.647215)
			(xy 295.083915 -349.6183) (xy 295.079745 -349.589385) (xy 295.067572 -349.562827) (xy 295.058338 -349.551498)
			(xy 295.040697 -349.530565) (xy 295.010971 -349.484598) (xy 294.988125 -349.434852) (xy 294.972628 -349.38235)
			(xy 294.9648 -349.328171) (xy 294.9648 -349.273429) (xy 294.972628 -349.21925) (xy 294.988125 -349.166748)
			(xy 295.010971 -349.117002) (xy 295.040697 -349.071035) (xy 295.058338 -349.050102) (xy 295.067572 -349.038773)
			(xy 295.079745 -349.012215) (xy 295.083915 -348.9833) (xy 295.079745 -348.954385) (xy 295.067572 -348.927827)
			(xy 295.058338 -348.916498) (xy 295.040697 -348.895565) (xy 295.010971 -348.849598) (xy 294.988125 -348.799852)
			(xy 294.972628 -348.74735) (xy 294.9648 -348.693171) (xy 294.9648 -348.638429) (xy 294.972628 -348.58425)
			(xy 294.988125 -348.531748) (xy 295.010971 -348.482002) (xy 295.040697 -348.436035) (xy 295.058338 -348.415102)
			(xy 295.067572 -348.403773) (xy 295.079745 -348.377215) (xy 295.083915 -348.3483) (xy 295.079745 -348.319385)
			(xy 295.067572 -348.292827) (xy 295.058338 -348.281498) (xy 295.04069 -348.260573) (xy 295.010979 -348.214599)
			(xy 294.988144 -348.164849) (xy 294.972655 -348.112347) (xy 294.96483 -348.05817) (xy 294.964358 -348.0308)
			(xy 294.964878 -348.00355) (xy 294.972633 -347.949606) (xy 294.987987 -347.897314) (xy 295.010625 -347.847739)
			(xy 295.040089 -347.80189) (xy 295.075776 -347.7607) (xy 295.116963 -347.725009) (xy 295.162809 -347.695542)
			(xy 295.212382 -347.672899) (xy 295.264672 -347.657541) (xy 295.318616 -347.64978) (xy 295.345866 -347.649292)
			(xy 295.373235 -347.64978) (xy 295.427413 -347.657593) (xy 295.479916 -347.673077) (xy 295.529663 -347.695914)
			(xy 295.575631 -347.725633) (xy 295.596564 -347.743272) (xy 295.607892 -347.752508) (xy 295.634449 -347.764684)
			(xy 295.663366 -347.768857) (xy 295.692283 -347.764684) (xy 295.71884 -347.752508) (xy 295.730168 -347.743272)
			(xy 295.751098 -347.72563) (xy 295.797072 -347.69592) (xy 295.84682 -347.673085) (xy 295.899321 -347.657594)
			(xy 295.953497 -347.649766) (xy 295.980866 -347.649292) (xy 296.008906 -347.649802) (xy 296.064383 -347.657998)
			(xy 296.118065 -347.67422) (xy 296.168798 -347.698118) (xy 296.21549 -347.729179) (xy 296.236644 -347.74759)
			(xy 296.248086 -347.757235) (xy 296.275129 -347.770015) (xy 296.304716 -347.774401) (xy 296.334303 -347.770015)
			(xy 296.361346 -347.757235) (xy 296.372788 -347.74759) (xy 296.393925 -347.729153) (xy 296.440606 -347.698061)
			(xy 296.49134 -347.674149) (xy 296.545032 -347.657932) (xy 296.600522 -347.649763) (xy 296.628566 -347.649292)
			(xy 296.655818 -347.649787) (xy 296.709768 -347.657539) (xy 296.762065 -347.672891) (xy 296.811645 -347.69553)
			(xy 296.857498 -347.724994) (xy 296.898691 -347.760684) (xy 296.934386 -347.801874) (xy 296.963854 -347.847725)
			(xy 296.986497 -347.897303) (xy 297.001853 -347.949599) (xy 297.009611 -348.003548) (xy 297.010074 -348.0308)
			(xy 297.009614 -348.058171) (xy 297.001796 -348.11235) (xy 296.986306 -348.164854) (xy 296.963462 -348.2146)
			(xy 296.933736 -348.260567) (xy 296.916094 -348.281498) (xy 296.906858 -348.292825) (xy 296.894681 -348.319383)
			(xy 296.890509 -348.3483) (xy 296.894681 -348.377217) (xy 296.906858 -348.403775) (xy 296.916094 -348.415102)
			(xy 296.933734 -348.436035) (xy 296.963457 -348.482003) (xy 296.986301 -348.53175) (xy 297.001796 -348.584252)
			(xy 297.009625 -348.63843) (xy 297.009625 -348.69317) (xy 297.001796 -348.747348) (xy 296.986301 -348.79985)
			(xy 296.963457 -348.849597) (xy 296.933734 -348.895565) (xy 296.916094 -348.916498) (xy 296.906858 -348.927825)
			(xy 296.894681 -348.954383) (xy 296.890509 -348.9833) (xy 296.894681 -349.012217) (xy 296.906858 -349.038775)
			(xy 296.916094 -349.050102) (xy 296.933734 -349.071035) (xy 296.963457 -349.117003) (xy 296.986301 -349.16675)
			(xy 297.001796 -349.219252) (xy 297.009625 -349.27343) (xy 297.009625 -349.32817) (xy 297.001796 -349.382348)
			(xy 296.986301 -349.43485) (xy 296.963457 -349.484597) (xy 296.933734 -349.530565) (xy 296.916094 -349.551498)
			(xy 296.906858 -349.562825) (xy 296.894681 -349.589383) (xy 296.890509 -349.6183) (xy 296.894681 -349.647217)
			(xy 296.906858 -349.673775) (xy 296.916094 -349.685102) (xy 296.933734 -349.706035) (xy 296.963457 -349.752003)
			(xy 296.986301 -349.80175) (xy 297.001796 -349.854252) (xy 297.009625 -349.90843) (xy 297.009625 -349.96317)
			(xy 297.001796 -350.017348) (xy 296.986301 -350.06985) (xy 296.963457 -350.119597) (xy 296.933734 -350.165565)
			(xy 296.916094 -350.186498) (xy 296.906858 -350.197825) (xy 296.894681 -350.224383) (xy 296.890509 -350.2533)
			(xy 296.894681 -350.282217) (xy 296.906858 -350.308775) (xy 296.916094 -350.320102) (xy 296.933734 -350.341035)
			(xy 296.963457 -350.387003) (xy 296.986301 -350.43675) (xy 297.001796 -350.489252) (xy 297.009625 -350.54343)
			(xy 297.009625 -350.59817) (xy 297.001796 -350.652348) (xy 296.986301 -350.70485) (xy 296.963457 -350.754597)
			(xy 296.933734 -350.800565) (xy 296.916094 -350.821498) (xy 296.906858 -350.832825) (xy 296.894681 -350.859383)
			(xy 296.890509 -350.8883) (xy 296.894681 -350.917217) (xy 296.906858 -350.943775) (xy 296.916094 -350.955102)
			(xy 296.933734 -350.976035) (xy 296.963457 -351.022003) (xy 296.986301 -351.07175) (xy 297.001796 -351.124252)
			(xy 297.009625 -351.17843) (xy 297.009625 -351.23317) (xy 297.001796 -351.287348) (xy 296.986301 -351.33985)
			(xy 296.963457 -351.389597) (xy 296.933734 -351.435565) (xy 296.916094 -351.456498) (xy 296.906858 -351.467825)
			(xy 296.894681 -351.494383) (xy 296.890509 -351.5233) (xy 296.894681 -351.552217) (xy 296.906858 -351.578775)
			(xy 296.916094 -351.590102) (xy 296.933747 -351.611023) (xy 296.963457 -351.656999) (xy 296.98629 -351.706749)
			(xy 297.001778 -351.759252) (xy 297.009602 -351.81343) (xy 297.010074 -351.8408) (xy 300.03623 -351.8408)
			(xy 300.036689 -351.813429) (xy 300.044507 -351.75925) (xy 300.059998 -351.706746) (xy 300.082841 -351.656999)
			(xy 300.112568 -351.611033) (xy 300.13021 -351.590102) (xy 300.139446 -351.578774) (xy 300.151622 -351.552217)
			(xy 300.155794 -351.5233) (xy 300.151622 -351.494383) (xy 300.139446 -351.467826) (xy 300.13021 -351.456498)
			(xy 300.11257 -351.435565) (xy 300.082847 -351.389597) (xy 300.060002 -351.33985) (xy 300.044507 -351.287349)
			(xy 300.036678 -351.23317) (xy 300.036678 -351.17843) (xy 300.044507 -351.124251) (xy 300.060002 -351.07175)
			(xy 300.082847 -351.022003) (xy 300.11257 -350.976035) (xy 300.13021 -350.955102) (xy 300.139446 -350.943774)
			(xy 300.151622 -350.917217) (xy 300.155794 -350.8883) (xy 300.151622 -350.859383) (xy 300.139446 -350.832826)
			(xy 300.13021 -350.821498) (xy 300.11257 -350.800565) (xy 300.082847 -350.754597) (xy 300.060002 -350.70485)
			(xy 300.044507 -350.652349) (xy 300.036678 -350.59817) (xy 300.036678 -350.54343) (xy 300.044507 -350.489251)
			(xy 300.060002 -350.43675) (xy 300.082847 -350.387003) (xy 300.11257 -350.341035) (xy 300.13021 -350.320102)
			(xy 300.139446 -350.308774) (xy 300.151622 -350.282217) (xy 300.155794 -350.2533) (xy 300.151622 -350.224383)
			(xy 300.139446 -350.197826) (xy 300.13021 -350.186498) (xy 300.11257 -350.165565) (xy 300.082847 -350.119597)
			(xy 300.060002 -350.06985) (xy 300.044507 -350.017349) (xy 300.036678 -349.96317) (xy 300.036678 -349.90843)
			(xy 300.044507 -349.854251) (xy 300.060002 -349.80175) (xy 300.082847 -349.752003) (xy 300.11257 -349.706035)
			(xy 300.13021 -349.685102) (xy 300.139446 -349.673774) (xy 300.151622 -349.647217) (xy 300.155794 -349.6183)
			(xy 300.151622 -349.589383) (xy 300.139446 -349.562826) (xy 300.13021 -349.551498) (xy 300.11257 -349.530565)
			(xy 300.082847 -349.484597) (xy 300.060002 -349.43485) (xy 300.044507 -349.382349) (xy 300.036678 -349.32817)
			(xy 300.036678 -349.27343) (xy 300.044507 -349.219251) (xy 300.060002 -349.16675) (xy 300.082847 -349.117003)
			(xy 300.11257 -349.071035) (xy 300.13021 -349.050102) (xy 300.139446 -349.038774) (xy 300.151622 -349.012217)
			(xy 300.155794 -348.9833) (xy 300.151622 -348.954383) (xy 300.139446 -348.927826) (xy 300.13021 -348.916498)
			(xy 300.11257 -348.895565) (xy 300.082847 -348.849597) (xy 300.060002 -348.79985) (xy 300.044507 -348.747349)
			(xy 300.036678 -348.69317) (xy 300.036678 -348.63843) (xy 300.044507 -348.584251) (xy 300.060002 -348.53175)
			(xy 300.082847 -348.482003) (xy 300.11257 -348.436035) (xy 300.13021 -348.415102) (xy 300.139446 -348.403774)
			(xy 300.151622 -348.377217) (xy 300.155794 -348.3483) (xy 300.151622 -348.319383) (xy 300.139446 -348.292826)
			(xy 300.13021 -348.281498) (xy 300.112558 -348.260576) (xy 300.082848 -348.214601) (xy 300.060014 -348.164851)
			(xy 300.044526 -348.112348) (xy 300.036702 -348.05817) (xy 300.03623 -348.0308) (xy 300.036655 -348.003545)
			(xy 300.044413 -347.949591) (xy 300.059771 -347.89729) (xy 300.082417 -347.847708) (xy 300.111888 -347.801853)
			(xy 300.147586 -347.760659) (xy 300.188783 -347.724965) (xy 300.234641 -347.695498) (xy 300.284226 -347.672858)
			(xy 300.336528 -347.657505) (xy 300.390483 -347.649753) (xy 300.417738 -347.649292) (xy 300.445779 -347.649759)
			(xy 300.501259 -347.657966) (xy 300.554941 -347.674198) (xy 300.605673 -347.698105) (xy 300.652363 -347.729175)
			(xy 300.673516 -347.74759) (xy 300.684958 -347.757235) (xy 300.712001 -347.770015) (xy 300.741588 -347.774401)
			(xy 300.771175 -347.770015) (xy 300.798218 -347.757235) (xy 300.80966 -347.74759) (xy 300.830808 -347.729166)
			(xy 300.877486 -347.698072) (xy 300.928217 -347.674157) (xy 300.981907 -347.657938) (xy 301.037395 -347.649765)
			(xy 301.065438 -347.649292) (xy 301.092807 -347.649796) (xy 301.146984 -347.657605) (xy 301.199487 -347.673085)
			(xy 301.249234 -347.695919) (xy 301.295203 -347.725635) (xy 301.316136 -347.743272) (xy 301.327464 -347.752508)
			(xy 301.354021 -347.764684) (xy 301.382938 -347.768857) (xy 301.411855 -347.764684) (xy 301.438412 -347.752508)
			(xy 301.44974 -347.743272) (xy 301.47068 -347.725643) (xy 301.516651 -347.695931) (xy 301.566397 -347.673093)
			(xy 301.618895 -347.6576) (xy 301.673069 -347.649768) (xy 301.700438 -347.649292) (xy 301.72769 -347.649742)
			(xy 301.781639 -347.657504) (xy 301.833935 -347.672864) (xy 301.883512 -347.69551) (xy 301.929362 -347.72498)
			(xy 301.970552 -347.760675) (xy 302.006243 -347.801868) (xy 302.035709 -347.847721) (xy 302.058349 -347.897301)
			(xy 302.073704 -347.949598) (xy 302.08146 -348.003548) (xy 302.081946 -348.0308) (xy 302.081493 -348.058171)
			(xy 302.073674 -348.112351) (xy 302.058183 -348.164855) (xy 302.035338 -348.214602) (xy 302.005609 -348.260567)
			(xy 301.987966 -348.281498) (xy 301.978732 -348.292826) (xy 301.966559 -348.319384) (xy 301.962388 -348.3483)
			(xy 301.966559 -348.377216) (xy 301.978732 -348.403774) (xy 301.987966 -348.415102) (xy 302.005607 -348.436035)
			(xy 302.035332 -348.482002) (xy 302.058178 -348.531748) (xy 302.073675 -348.584251) (xy 302.081503 -348.638429)
			(xy 302.081503 -348.693171) (xy 302.073675 -348.747349) (xy 302.058178 -348.799852) (xy 302.035332 -348.849598)
			(xy 302.005607 -348.895565) (xy 301.987966 -348.916498) (xy 301.978732 -348.927826) (xy 301.966559 -348.954384)
			(xy 301.962388 -348.9833) (xy 301.966559 -349.012216) (xy 301.978732 -349.038774) (xy 301.987966 -349.050102)
			(xy 302.005607 -349.071035) (xy 302.035332 -349.117002) (xy 302.058178 -349.166748) (xy 302.073675 -349.219251)
			(xy 302.081503 -349.273429) (xy 302.081503 -349.328171) (xy 302.073675 -349.382349) (xy 302.058178 -349.434852)
			(xy 302.035332 -349.484598) (xy 302.005607 -349.530565) (xy 301.987966 -349.551498) (xy 301.978732 -349.562826)
			(xy 301.966559 -349.589384) (xy 301.962388 -349.6183) (xy 301.966559 -349.647216) (xy 301.978732 -349.673774)
			(xy 301.987966 -349.685102) (xy 302.005607 -349.706035) (xy 302.035332 -349.752002) (xy 302.058178 -349.801748)
			(xy 302.073675 -349.854251) (xy 302.081503 -349.908429) (xy 302.081503 -349.963171) (xy 302.073675 -350.017349)
			(xy 302.058178 -350.069852) (xy 302.035332 -350.119598) (xy 302.005607 -350.165565) (xy 301.987966 -350.186498)
			(xy 301.978732 -350.197826) (xy 301.966559 -350.224384) (xy 301.962388 -350.2533) (xy 301.966559 -350.282216)
			(xy 301.978732 -350.308774) (xy 301.987966 -350.320102) (xy 302.005607 -350.341035) (xy 302.035332 -350.387002)
			(xy 302.058178 -350.436748) (xy 302.073675 -350.489251) (xy 302.081503 -350.543429) (xy 302.081503 -350.598171)
			(xy 302.073675 -350.652349) (xy 302.058178 -350.704852) (xy 302.035332 -350.754598) (xy 302.005607 -350.800565)
			(xy 301.987966 -350.821498) (xy 301.978732 -350.832826) (xy 301.966559 -350.859384) (xy 301.962388 -350.8883)
			(xy 301.966559 -350.917216) (xy 301.978732 -350.943774) (xy 301.987966 -350.955102) (xy 302.005607 -350.976035)
			(xy 302.035332 -351.022002) (xy 302.058178 -351.071748) (xy 302.073675 -351.124251) (xy 302.081503 -351.178429)
			(xy 302.081503 -351.233171) (xy 302.073675 -351.287349) (xy 302.058178 -351.339852) (xy 302.035332 -351.389598)
			(xy 302.005607 -351.435565) (xy 301.987966 -351.456498) (xy 301.978732 -351.467826) (xy 301.966559 -351.494384)
			(xy 301.962388 -351.5233) (xy 301.966559 -351.552216) (xy 301.978732 -351.578774) (xy 301.987966 -351.590102)
			(xy 302.005614 -351.611027) (xy 302.035326 -351.657001) (xy 302.058161 -351.70675) (xy 302.073649 -351.759253)
			(xy 302.081474 -351.81343) (xy 302.081946 -351.8408) (xy 302.081422 -351.86805) (xy 302.073667 -351.921994)
			(xy 302.058314 -351.974286) (xy 302.035675 -352.02386) (xy 302.006212 -352.069709) (xy 301.970525 -352.110898)
			(xy 301.929339 -352.14659) (xy 301.883494 -352.176057) (xy 301.833921 -352.1987) (xy 301.781631 -352.214059)
			(xy 301.727687 -352.22182) (xy 301.700438 -352.222308) (xy 301.673069 -352.221818) (xy 301.618891 -352.214005)
			(xy 301.566388 -352.198522) (xy 301.516641 -352.175686) (xy 301.470673 -352.145967) (xy 301.44974 -352.128328)
			(xy 301.438412 -352.119092) (xy 301.411855 -352.106916) (xy 301.382938 -352.102743) (xy 301.354021 -352.106916)
			(xy 301.327464 -352.119092) (xy 301.316136 -352.128328) (xy 301.295205 -352.145968) (xy 301.249231 -352.175679)
			(xy 301.199484 -352.198514) (xy 301.146983 -352.214005) (xy 301.092807 -352.221834) (xy 301.065438 -352.222308)
			(xy 301.037398 -352.221796) (xy 300.981921 -352.2136) (xy 300.928239 -352.197379) (xy 300.877507 -352.173481)
			(xy 300.830814 -352.142421) (xy 300.80966 -352.12401) (xy 300.798218 -352.114365) (xy 300.771175 -352.101585)
			(xy 300.741588 -352.097199) (xy 300.712001 -352.101585) (xy 300.684958 -352.114365) (xy 300.673516 -352.12401)
			(xy 300.652378 -352.142445) (xy 300.605697 -352.173537) (xy 300.554963 -352.19745) (xy 300.501271 -352.213667)
			(xy 300.445782 -352.221837) (xy 300.417738 -352.222308) (xy 300.390486 -352.221809) (xy 300.336536 -352.214058)
			(xy 300.284239 -352.198706) (xy 300.234659 -352.176068) (xy 300.188806 -352.146604) (xy 300.147613 -352.110914)
			(xy 300.111919 -352.069725) (xy 300.08245 -352.023874) (xy 300.059807 -351.974296) (xy 300.044451 -351.922001)
			(xy 300.036693 -351.868052) (xy 300.03623 -351.8408) (xy 297.010074 -351.8408) (xy 297.009645 -351.868054)
			(xy 297.001887 -351.922008) (xy 296.986529 -351.974309) (xy 296.963884 -352.023891) (xy 296.934413 -352.069746)
			(xy 296.898715 -352.11094) (xy 296.857519 -352.146633) (xy 296.811661 -352.1761) (xy 296.762077 -352.198741)
			(xy 296.709775 -352.214094) (xy 296.65582 -352.221847) (xy 296.628566 -352.222308) (xy 296.600525 -352.221839)
			(xy 296.545046 -352.213632) (xy 296.491363 -352.197401) (xy 296.440631 -352.173494) (xy 296.393941 -352.142425)
			(xy 296.372788 -352.12401) (xy 296.361346 -352.114365) (xy 296.334303 -352.101585) (xy 296.304716 -352.097199)
			(xy 296.275129 -352.101585) (xy 296.248086 -352.114365) (xy 296.236644 -352.12401) (xy 296.215495 -352.142432)
			(xy 296.168817 -352.173526) (xy 296.118086 -352.197441) (xy 296.064396 -352.213661) (xy 296.008909 -352.221835)
			(xy 295.980866 -352.222308) (xy 295.953495 -352.22186) (xy 295.899315 -352.214037) (xy 295.846812 -352.198544)
			(xy 295.797066 -352.175698) (xy 295.751099 -352.145971) (xy 295.730168 -352.128328) (xy 295.71884 -352.119092)
			(xy 295.692283 -352.106916) (xy 295.663366 -352.102743) (xy 295.634449 -352.106916) (xy 295.607892 -352.119092)
			(xy 295.596564 -352.128328) (xy 295.575622 -352.145955) (xy 295.529652 -352.175668) (xy 295.479907 -352.198505)
			(xy 295.427408 -352.213999) (xy 295.373234 -352.221832) (xy 295.345866 -352.222308) (xy 295.318614 -352.221854)
			(xy 295.264665 -352.214093) (xy 295.21237 -352.198733) (xy 295.162792 -352.176088) (xy 295.116942 -352.146618)
			(xy 295.075752 -352.110924) (xy 295.040061 -352.069731) (xy 295.010596 -352.023878) (xy 294.987955 -351.974298)
			(xy 294.9726 -351.922002) (xy 294.964844 -351.868052) (xy 294.964358 -351.8408) (xy 292.302946 -351.8408)
			(xy 292.302422 -351.86805) (xy 292.294667 -351.921994) (xy 292.279314 -351.974286) (xy 292.256675 -352.02386)
			(xy 292.227212 -352.069709) (xy 292.191525 -352.110898) (xy 292.150339 -352.14659) (xy 292.104494 -352.176057)
			(xy 292.054921 -352.1987) (xy 292.002631 -352.214059) (xy 291.948687 -352.22182) (xy 291.921438 -352.222308)
			(xy 291.894069 -352.221818) (xy 291.839891 -352.214005) (xy 291.787388 -352.198522) (xy 291.737641 -352.175686)
			(xy 291.691673 -352.145967) (xy 291.67074 -352.128328) (xy 291.659412 -352.119092) (xy 291.632855 -352.106916)
			(xy 291.603938 -352.102743) (xy 291.575021 -352.106916) (xy 291.548464 -352.119092) (xy 291.537136 -352.128328)
			(xy 291.516205 -352.145968) (xy 291.470231 -352.175679) (xy 291.420484 -352.198514) (xy 291.367983 -352.214005)
			(xy 291.313807 -352.221834) (xy 291.286438 -352.222308) (xy 291.258398 -352.221796) (xy 291.202921 -352.2136)
			(xy 291.149239 -352.197379) (xy 291.098507 -352.173481) (xy 291.051814 -352.142421) (xy 291.03066 -352.12401)
			(xy 291.019218 -352.114365) (xy 290.992175 -352.101585) (xy 290.962588 -352.097199) (xy 290.933001 -352.101585)
			(xy 290.905958 -352.114365) (xy 290.894516 -352.12401) (xy 290.873378 -352.142445) (xy 290.826697 -352.173537)
			(xy 290.775963 -352.19745) (xy 290.722271 -352.213667) (xy 290.666782 -352.221837) (xy 290.638738 -352.222308)
			(xy 290.611486 -352.221809) (xy 290.557536 -352.214058) (xy 290.505239 -352.198706) (xy 290.455659 -352.176068)
			(xy 290.409806 -352.146604) (xy 290.368613 -352.110914) (xy 290.332919 -352.069725) (xy 290.30345 -352.023874)
			(xy 290.280807 -351.974296) (xy 290.265451 -351.922001) (xy 290.257693 -351.868052) (xy 290.25723 -351.8408)
			(xy 287.332674 -351.8408) (xy 287.332245 -351.868054) (xy 287.324487 -351.922008) (xy 287.309129 -351.974309)
			(xy 287.286484 -352.023891) (xy 287.257013 -352.069746) (xy 287.221315 -352.11094) (xy 287.180119 -352.146633)
			(xy 287.134261 -352.1761) (xy 287.084677 -352.198741) (xy 287.032375 -352.214094) (xy 286.97842 -352.221847)
			(xy 286.951166 -352.222308) (xy 286.923125 -352.221839) (xy 286.867646 -352.213632) (xy 286.813963 -352.197401)
			(xy 286.763231 -352.173494) (xy 286.716541 -352.142425) (xy 286.695388 -352.12401) (xy 286.683946 -352.114365)
			(xy 286.656903 -352.101585) (xy 286.627316 -352.097199) (xy 286.597729 -352.101585) (xy 286.570686 -352.114365)
			(xy 286.559244 -352.12401) (xy 286.538095 -352.142432) (xy 286.491417 -352.173526) (xy 286.440686 -352.197441)
			(xy 286.386996 -352.213661) (xy 286.331509 -352.221835) (xy 286.303466 -352.222308) (xy 286.276095 -352.22186)
			(xy 286.221915 -352.214037) (xy 286.169412 -352.198544) (xy 286.119666 -352.175698) (xy 286.073699 -352.145971)
			(xy 286.052768 -352.128328) (xy 286.04144 -352.119092) (xy 286.014883 -352.106916) (xy 285.985966 -352.102743)
			(xy 285.957049 -352.106916) (xy 285.930492 -352.119092) (xy 285.919164 -352.128328) (xy 285.898222 -352.145955)
			(xy 285.852252 -352.175668) (xy 285.802507 -352.198505) (xy 285.750008 -352.213999) (xy 285.695834 -352.221832)
			(xy 285.668466 -352.222308) (xy 285.641214 -352.221854) (xy 285.587265 -352.214093) (xy 285.53497 -352.198733)
			(xy 285.485392 -352.176088) (xy 285.439542 -352.146618) (xy 285.398352 -352.110924) (xy 285.362661 -352.069731)
			(xy 285.333196 -352.023878) (xy 285.310555 -351.974298) (xy 285.2952 -351.922002) (xy 285.287444 -351.868052)
			(xy 285.286958 -351.8408) (xy 281.656028 -351.8408) (xy 281.656028 -363.366812) (xy 281.656603 -363.381788)
			(xy 281.665372 -363.410431) (xy 281.682066 -363.435303) (xy 281.705252 -363.45427) (xy 281.732939 -363.465703)
			(xy 281.762751 -363.468622) (xy 281.79213 -363.462775) (xy 281.818554 -363.448665) (xy 281.82951 -363.43844)
			(xy 283.05252 -362.21543) (xy 283.055822 -362.20146) (xy 283.062953 -362.17408) (xy 283.084195 -362.12164)
			(xy 283.112948 -362.072913) (xy 283.148582 -362.028967) (xy 283.190316 -361.990765) (xy 283.237234 -361.959145)
			(xy 283.288308 -361.934802) (xy 283.342416 -361.918268) (xy 283.398373 -361.909906) (xy 283.426662 -361.90936)
			(xy 283.453917 -361.90982) (xy 283.507874 -361.917573) (xy 283.560179 -361.932925) (xy 283.609766 -361.955565)
			(xy 283.655626 -361.985031) (xy 283.696826 -362.020725) (xy 283.732527 -362.061918) (xy 283.762001 -362.107773)
			(xy 283.78465 -362.157356) (xy 283.800012 -362.209657) (xy 283.807775 -362.263613) (xy 283.80817 -362.290868)
			(xy 283.80765 -362.31917) (xy 283.799276 -362.375152) (xy 283.782721 -362.429282) (xy 283.758349 -362.480371)
			(xy 283.726695 -362.527297) (xy 283.688454 -362.569031) (xy 283.644466 -362.604656) (xy 283.595696 -362.63339)
			(xy 283.543216 -362.654602) (xy 283.515816 -362.661708) (xy 283.501846 -362.665264) (xy 281.656028 -364.511082)
			(xy 281.656028 -364.745778) (xy 281.656492 -364.759629) (xy 281.663936 -364.786311) (xy 281.678282 -364.810008)
			(xy 281.698472 -364.828975) (xy 281.723019 -364.841812) (xy 281.750115 -364.847575) (xy 281.777762 -364.845838)
			(xy 281.803923 -364.83673) (xy 281.826671 -364.820922) (xy 281.83586 -364.810548) (xy 281.845609 -364.798886)
			(xy 281.866065 -364.776397) (xy 281.876754 -364.76559) (xy 282.466542 -364.175802) (xy 282.492092 -364.150919)
			(xy 282.547843 -364.106438) (xy 282.608226 -364.068482) (xy 282.672481 -364.037529) (xy 282.7398 -364.013968)
			(xy 282.809333 -363.998097) (xy 282.880207 -363.990115) (xy 282.915868 -363.98962) (xy 283.426662 -363.98962)
			(xy 283.462324 -363.990099) (xy 283.5332 -363.998081) (xy 283.602737 -364.013949) (xy 283.67006 -364.037503)
			(xy 283.734322 -364.068446) (xy 283.794716 -364.106391) (xy 283.850481 -364.150859) (xy 283.900916 -364.201291)
			(xy 283.933459 -364.242096) (xy 284.829758 -364.242096) (xy 284.830254 -364.214056) (xy 284.838455 -364.158578)
			(xy 284.854681 -364.104896) (xy 284.878582 -364.054164) (xy 284.909644 -364.007472) (xy 284.928056 -363.986318)
			(xy 284.937658 -363.974842) (xy 284.950447 -363.947812) (xy 284.954843 -363.918234) (xy 284.950467 -363.888653)
			(xy 284.937697 -363.861615) (xy 284.928056 -363.850174) (xy 284.909643 -363.829017) (xy 284.878549 -363.782341)
			(xy 284.854632 -363.731612) (xy 284.83841 -363.677924) (xy 284.830233 -363.622439) (xy 284.829758 -363.594396)
			(xy 284.830244 -363.567145) (xy 284.838 -363.513197) (xy 284.853355 -363.460902) (xy 284.875997 -363.411325)
			(xy 284.905463 -363.365475) (xy 284.941154 -363.324284) (xy 284.982345 -363.288593) (xy 285.028195 -363.259127)
			(xy 285.077772 -363.236485) (xy 285.130067 -363.22113) (xy 285.184015 -363.213374) (xy 285.238517 -363.213374)
			(xy 285.292465 -363.22113) (xy 285.34476 -363.236485) (xy 285.394337 -363.259127) (xy 285.440187 -363.288593)
			(xy 285.481378 -363.324284) (xy 285.517069 -363.365475) (xy 285.546535 -363.411325) (xy 285.569177 -363.460902)
			(xy 285.584532 -363.513197) (xy 285.592288 -363.567145) (xy 285.592774 -363.594396) (xy 285.592291 -363.622437)
			(xy 285.584089 -363.677916) (xy 285.567862 -363.731598) (xy 285.543957 -363.78233) (xy 285.51289 -363.829021)
			(xy 285.494476 -363.850174) (xy 285.489947 -363.855508) (xy 292.807134 -363.855508) (xy 292.811205 -363.799886)
			(xy 292.823331 -363.745449) (xy 292.843254 -363.693358) (xy 292.87055 -363.644723) (xy 292.904636 -363.60058)
			(xy 292.944785 -363.561871) (xy 292.990143 -363.52942) (xy 293.039743 -363.503919) (xy 293.092527 -363.485912)
			(xy 293.14737 -363.475782) (xy 293.203104 -363.473745) (xy 293.258541 -363.479845) (xy 293.312498 -363.493951)
			(xy 293.363827 -363.515763) (xy 293.411433 -363.544817) (xy 293.454301 -363.580492) (xy 293.491518 -363.622029)
			(xy 293.522291 -363.668542) (xy 293.545963 -363.719039) (xy 293.562031 -363.772446) (xy 293.570151 -363.827622)
			(xy 293.57066 -363.855508) (xy 293.570151 -363.883394) (xy 293.562031 -363.93857) (xy 293.545963 -363.991977)
			(xy 293.522291 -364.042474) (xy 293.491518 -364.088987) (xy 293.454301 -364.130524) (xy 293.411433 -364.166199)
			(xy 293.363827 -364.195253) (xy 293.312498 -364.217065) (xy 293.258541 -364.231171) (xy 293.216963 -364.235746)
			(xy 294.51808 -364.235746) (xy 294.518554 -364.208376) (xy 294.526367 -364.154196) (xy 294.541853 -364.101692)
			(xy 294.564693 -364.051945) (xy 294.594418 -364.005979) (xy 294.61206 -363.985048) (xy 294.621255 -363.973689)
			(xy 294.633443 -363.947143) (xy 294.637626 -363.918235) (xy 294.633463 -363.889324) (xy 294.621293 -363.86277)
			(xy 294.61206 -363.851444) (xy 294.594421 -363.830512) (xy 294.564711 -363.784538) (xy 294.541875 -363.734791)
			(xy 294.526384 -363.68229) (xy 294.518554 -363.628115) (xy 294.51808 -363.600746) (xy 294.518566 -363.573495)
			(xy 294.526322 -363.519547) (xy 294.541677 -363.467252) (xy 294.564319 -363.417675) (xy 294.593785 -363.371825)
			(xy 294.629476 -363.330634) (xy 294.670667 -363.294943) (xy 294.716517 -363.265477) (xy 294.766094 -363.242835)
			(xy 294.818389 -363.22748) (xy 294.872337 -363.219724) (xy 294.926839 -363.219724) (xy 294.980787 -363.22748)
			(xy 295.033082 -363.242835) (xy 295.082659 -363.265477) (xy 295.128509 -363.294943) (xy 295.1697 -363.330634)
			(xy 295.205391 -363.371825) (xy 295.234857 -363.417675) (xy 295.257499 -363.467252) (xy 295.272854 -363.519547)
			(xy 295.28061 -363.573495) (xy 295.281096 -363.600746) (xy 295.280599 -363.628115) (xy 295.272789 -363.682293)
			(xy 295.257307 -363.734796) (xy 295.234472 -363.784543) (xy 295.204754 -363.830511) (xy 295.187116 -363.851444)
			(xy 295.180853 -363.859064) (xy 302.365154 -363.859064) (xy 302.369225 -363.803442) (xy 302.381351 -363.749005)
			(xy 302.401274 -363.696914) (xy 302.42857 -363.648279) (xy 302.462656 -363.604136) (xy 302.502805 -363.565427)
			(xy 302.548163 -363.532976) (xy 302.597763 -363.507475) (xy 302.650547 -363.489468) (xy 302.70539 -363.479338)
			(xy 302.761124 -363.477301) (xy 302.816561 -363.483401) (xy 302.870518 -363.497507) (xy 302.921847 -363.519319)
			(xy 302.969453 -363.548373) (xy 303.012321 -363.584048) (xy 303.049538 -363.625585) (xy 303.080311 -363.672098)
			(xy 303.103983 -363.722595) (xy 303.120051 -363.776002) (xy 303.128171 -363.831178) (xy 303.12868 -363.859064)
			(xy 303.128171 -363.88695) (xy 303.120051 -363.942126) (xy 303.103983 -363.995533) (xy 303.080311 -364.04603)
			(xy 303.049538 -364.092543) (xy 303.012321 -364.13408) (xy 302.969453 -364.169755) (xy 302.921847 -364.198809)
			(xy 302.870518 -364.220621) (xy 302.816561 -364.234727) (xy 302.761124 -364.240827) (xy 302.70539 -364.23879)
			(xy 302.650547 -364.22866) (xy 302.597763 -364.210653) (xy 302.548163 -364.185152) (xy 302.502805 -364.152701)
			(xy 302.462656 -364.113992) (xy 302.42857 -364.069849) (xy 302.401274 -364.021214) (xy 302.381351 -363.969123)
			(xy 302.369225 -363.914686) (xy 302.365154 -363.859064) (xy 295.180853 -363.859064) (xy 295.177834 -363.862738)
			(xy 295.16566 -363.889307) (xy 295.161495 -363.918235) (xy 295.165679 -363.94716) (xy 295.177871 -363.973721)
			(xy 295.187116 -363.985048) (xy 295.204747 -364.005987) (xy 295.234459 -364.051958) (xy 295.257297 -364.101704)
			(xy 295.27279 -364.154203) (xy 295.28062 -364.208377) (xy 295.281096 -364.235746) (xy 295.28061 -364.262997)
			(xy 295.272854 -364.316945) (xy 295.257499 -364.36924) (xy 295.234857 -364.418817) (xy 295.205391 -364.464667)
			(xy 295.1697 -364.505858) (xy 295.128509 -364.541549) (xy 295.082659 -364.571015) (xy 295.033082 -364.593657)
			(xy 294.980787 -364.609012) (xy 294.926839 -364.616768) (xy 294.872337 -364.616768) (xy 294.818389 -364.609012)
			(xy 294.766094 -364.593657) (xy 294.716517 -364.571015) (xy 294.670667 -364.541549) (xy 294.629476 -364.505858)
			(xy 294.593785 -364.464667) (xy 294.564319 -364.418817) (xy 294.541677 -364.36924) (xy 294.526322 -364.316945)
			(xy 294.518566 -364.262997) (xy 294.51808 -364.235746) (xy 293.216963 -364.235746) (xy 293.203104 -364.237271)
			(xy 293.14737 -364.235234) (xy 293.092527 -364.225104) (xy 293.039743 -364.207097) (xy 292.990143 -364.181596)
			(xy 292.944785 -364.149145) (xy 292.904636 -364.110436) (xy 292.87055 -364.066293) (xy 292.843254 -364.017658)
			(xy 292.823331 -363.965567) (xy 292.811205 -363.91113) (xy 292.807134 -363.855508) (xy 285.489947 -363.855508)
			(xy 285.484789 -363.861583) (xy 285.47202 -363.888638) (xy 285.467644 -363.918234) (xy 285.47204 -363.947827)
			(xy 285.484827 -363.974874) (xy 285.494476 -363.986318) (xy 285.512891 -364.007473) (xy 285.543984 -364.05415)
			(xy 285.567899 -364.10488) (xy 285.584121 -364.158568) (xy 285.592299 -364.214053) (xy 285.592774 -364.242096)
			(xy 285.592288 -364.269347) (xy 285.584532 -364.323295) (xy 285.569177 -364.37559) (xy 285.546535 -364.425167)
			(xy 285.517069 -364.471017) (xy 285.481378 -364.512208) (xy 285.440187 -364.547899) (xy 285.394337 -364.577365)
			(xy 285.34476 -364.600007) (xy 285.292465 -364.615362) (xy 285.238517 -364.623118) (xy 285.184015 -364.623118)
			(xy 285.130067 -364.615362) (xy 285.077772 -364.600007) (xy 285.028195 -364.577365) (xy 284.982345 -364.547899)
			(xy 284.941154 -364.512208) (xy 284.905463 -364.471017) (xy 284.875997 -364.425167) (xy 284.853355 -364.37559)
			(xy 284.838 -364.323295) (xy 284.830244 -364.269347) (xy 284.829758 -364.242096) (xy 283.933459 -364.242096)
			(xy 283.945387 -364.257053) (xy 283.983335 -364.317445) (xy 284.014283 -364.381705) (xy 284.037841 -364.449026)
			(xy 284.053712 -364.518562) (xy 284.061698 -364.589438) (xy 284.061698 -364.6383) (xy 289.07837 -364.6383)
			(xy 289.082538 -364.582684) (xy 289.094949 -364.52831) (xy 289.115327 -364.476394) (xy 289.143215 -364.428095)
			(xy 289.17799 -364.384492) (xy 289.218876 -364.34656) (xy 289.264959 -364.315146) (xy 289.31521 -364.290951)
			(xy 289.368506 -364.274517) (xy 289.423656 -364.26621) (xy 289.451542 -364.265718) (xy 289.478873 -364.26621)
			(xy 289.532952 -364.274177) (xy 289.585285 -364.289962) (xy 289.634749 -364.313227) (xy 289.680282 -364.343471)
			(xy 289.720905 -364.380046) (xy 289.755745 -364.422165) (xy 289.770312 -364.445296) (xy 289.778247 -364.457512)
			(xy 289.799715 -364.477184) (xy 289.825865 -364.48999) (xy 289.854568 -364.494887) (xy 289.883485 -364.491477)
			(xy 289.897058 -364.48619) (xy 289.920264 -364.47669) (xy 289.968599 -364.463343) (xy 290.01829 -364.456619)
			(xy 290.043362 -364.456218) (xy 290.068432 -364.456634) (xy 290.118115 -364.463387) (xy 290.166449 -364.476723)
			(xy 290.189666 -364.48619) (xy 290.203241 -364.491445) (xy 290.232143 -364.494811) (xy 290.260823 -364.4899)
			(xy 290.286959 -364.477108) (xy 290.308433 -364.457473) (xy 290.316412 -364.445296) (xy 290.330981 -364.422165)
			(xy 290.365824 -364.380044) (xy 290.406447 -364.343465) (xy 290.451978 -364.313214) (xy 290.50144 -364.289938)
			(xy 290.553771 -364.274138) (xy 290.60785 -364.266152) (xy 290.662514 -364.266152) (xy 290.716593 -364.274138)
			(xy 290.768924 -364.289938) (xy 290.818386 -364.313214) (xy 290.863917 -364.343465) (xy 290.90454 -364.380044)
			(xy 290.939383 -364.422165) (xy 290.953952 -364.445296) (xy 290.961849 -364.457539) (xy 290.983327 -364.477211)
			(xy 291.009488 -364.490013) (xy 291.038199 -364.494904) (xy 291.067123 -364.491483) (xy 291.080698 -364.48619)
			(xy 291.103911 -364.476708) (xy 291.152242 -364.463354) (xy 291.201931 -364.456623) (xy 291.227002 -364.456218)
			(xy 291.254319 -364.456686) (xy 291.308365 -364.464677) (xy 291.360665 -364.480472) (xy 291.410099 -364.503733)
			(xy 291.455607 -364.533963) (xy 291.496215 -364.570512) (xy 291.531052 -364.612598) (xy 291.559371 -364.659318)
			(xy 291.57041 -364.68431) (xy 291.575959 -364.69653) (xy 291.592461 -364.717688) (xy 291.613901 -364.733822)
			(xy 291.638801 -364.74382) (xy 291.665445 -364.746992) (xy 291.691997 -364.743119) (xy 291.716625 -364.73247)
			(xy 291.727382 -364.724442) (xy 291.747719 -364.708764) (xy 291.791824 -364.682466) (xy 291.839056 -364.662316)
			(xy 291.888563 -364.648679) (xy 291.939451 -364.641799) (xy 291.965126 -364.641384) (xy 291.983145 -364.641606)
			(xy 292.01902 -364.645039) (xy 292.036754 -364.648242) (xy 292.051967 -364.650546) (xy 292.082518 -364.64703)
			(xy 292.110636 -364.634578) (xy 292.133772 -364.614319) (xy 292.149827 -364.588091) (xy 292.154102 -364.573312)
			(xy 292.161484 -364.546264) (xy 292.183118 -364.494539) (xy 292.212086 -364.446535) (xy 292.247764 -364.403285)
			(xy 292.289385 -364.365719) (xy 292.336054 -364.334645) (xy 292.386766 -364.310733) (xy 292.44043 -364.294496)
			(xy 292.495893 -364.286284) (xy 292.523926 -364.285784) (xy 292.551178 -364.286254) (xy 292.605125 -364.294013)
			(xy 292.65742 -364.309371) (xy 292.706997 -364.332015) (xy 292.752847 -364.361483) (xy 292.794036 -364.397176)
			(xy 292.829728 -364.438368) (xy 292.859194 -364.484219) (xy 292.881835 -364.533797) (xy 292.89719 -364.586092)
			(xy 292.904698 -364.6383) (xy 298.766795 -364.6383) (xy 298.770962 -364.582695) (xy 298.783369 -364.528332)
			(xy 298.80374 -364.476425) (xy 298.831619 -364.428134) (xy 298.866383 -364.384537) (xy 298.907257 -364.346608)
			(xy 298.953327 -364.315194) (xy 299.003564 -364.290997) (xy 299.056846 -364.274557) (xy 299.111984 -364.266241)
			(xy 299.139864 -364.265718) (xy 299.167196 -364.266193) (xy 299.221275 -364.274163) (xy 299.273609 -364.289951)
			(xy 299.323073 -364.313218) (xy 299.368605 -364.343465) (xy 299.409228 -364.380043) (xy 299.444068 -364.422164)
			(xy 299.458634 -364.445296) (xy 299.466548 -364.457527) (xy 299.488021 -364.477199) (xy 299.514177 -364.490003)
			(xy 299.542885 -364.494896) (xy 299.571806 -364.49148) (xy 299.58538 -364.48619) (xy 299.608595 -364.476714)
			(xy 299.656925 -364.463358) (xy 299.706613 -364.456624) (xy 299.731684 -364.456218) (xy 299.756753 -364.45666)
			(xy 299.806435 -364.463402) (xy 299.85477 -364.476727) (xy 299.877988 -364.48619) (xy 299.891578 -364.491412)
			(xy 299.92048 -364.494797) (xy 299.949165 -364.489902) (xy 299.975309 -364.477123) (xy 299.996793 -364.457496)
			(xy 300.004734 -364.445296) (xy 300.019303 -364.422165) (xy 300.054146 -364.380044) (xy 300.094769 -364.343465)
			(xy 300.1403 -364.313214) (xy 300.189762 -364.289938) (xy 300.242093 -364.274138) (xy 300.296172 -364.266152)
			(xy 300.350836 -364.266152) (xy 300.404915 -364.274138) (xy 300.457246 -364.289938) (xy 300.506708 -364.313214)
			(xy 300.552239 -364.343465) (xy 300.592862 -364.380044) (xy 300.627705 -364.422165) (xy 300.642274 -364.445296)
			(xy 300.650245 -364.457486) (xy 300.671703 -364.477157) (xy 300.697843 -364.489967) (xy 300.726538 -364.494871)
			(xy 300.755449 -364.491471) (xy 300.76902 -364.48619) (xy 300.79223 -364.476701) (xy 300.840563 -364.46335)
			(xy 300.890252 -364.456622) (xy 300.915324 -364.456218) (xy 300.942169 -364.456634) (xy 300.995301 -364.464342)
			(xy 301.046778 -364.479596) (xy 301.095533 -364.50208) (xy 301.140556 -364.531328) (xy 301.180915 -364.566735)
			(xy 301.215776 -364.607567) (xy 301.244415 -364.65298) (xy 301.266241 -364.702032) (xy 301.273972 -364.727744)
			(xy 301.27869 -364.742221) (xy 301.295197 -364.767781) (xy 301.318501 -364.787346) (xy 301.346533 -364.799179)
			(xy 301.376807 -364.80223) (xy 301.406637 -364.796229) (xy 301.420276 -364.789466) (xy 301.448418 -364.774824)
			(xy 301.508371 -364.7541) (xy 301.570931 -364.743605) (xy 301.602648 -364.742984) (xy 301.620667 -364.743202)
			(xy 301.656542 -364.746638) (xy 301.674276 -364.749842) (xy 301.689487 -364.752168) (xy 301.720039 -364.748646)
			(xy 301.748159 -364.736189) (xy 301.771295 -364.715925) (xy 301.787349 -364.689693) (xy 301.791624 -364.674912)
			(xy 301.798986 -364.647858) (xy 301.820622 -364.596131) (xy 301.849592 -364.548127) (xy 301.885273 -364.504876)
			(xy 301.926896 -364.46731) (xy 301.973568 -364.436238) (xy 302.024282 -364.412327) (xy 302.077949 -364.396092)
			(xy 302.133414 -364.387882) (xy 302.161448 -364.387384) (xy 302.1887 -364.387833) (xy 302.242649 -364.395596)
			(xy 302.294944 -364.410957) (xy 302.34452 -364.433603) (xy 302.39037 -364.463073) (xy 302.43156 -364.498769)
			(xy 302.467251 -364.539962) (xy 302.496716 -364.585815) (xy 302.519357 -364.635394) (xy 302.534713 -364.68769)
			(xy 302.54247 -364.74164) (xy 302.542956 -364.768892) (xy 302.5425 -364.796467) (xy 302.534548 -364.851041)
			(xy 302.518822 -364.903902) (xy 302.49565 -364.953948) (xy 302.465515 -365.000137) (xy 302.429045 -365.041507)
			(xy 302.408336 -365.059722) (xy 302.397444 -365.069627) (xy 302.381366 -365.094274) (xy 302.372978 -365.122481)
			(xy 302.372977 -365.151909) (xy 302.381361 -365.180116) (xy 302.397437 -365.204765) (xy 302.408336 -365.214662)
			(xy 302.410355 -365.21644) (xy 354.854508 -365.21644) (xy 354.858579 -365.160818) (xy 354.870705 -365.106381)
			(xy 354.890628 -365.05429) (xy 354.917924 -365.005655) (xy 354.95201 -364.961512) (xy 354.992159 -364.922803)
			(xy 355.037517 -364.890352) (xy 355.087117 -364.864851) (xy 355.139901 -364.846844) (xy 355.194744 -364.836714)
			(xy 355.250478 -364.834677) (xy 355.305915 -364.840777) (xy 355.359872 -364.854883) (xy 355.411201 -364.876695)
			(xy 355.458807 -364.905749) (xy 355.501675 -364.941424) (xy 355.538892 -364.982961) (xy 355.569665 -365.029474)
			(xy 355.593337 -365.079971) (xy 355.609405 -365.133378) (xy 355.617525 -365.188554) (xy 355.618034 -365.21644)
			(xy 355.617525 -365.244326) (xy 355.609405 -365.299502) (xy 355.593337 -365.352909) (xy 355.569665 -365.403406)
			(xy 355.538892 -365.449919) (xy 355.501675 -365.491456) (xy 355.458807 -365.527131) (xy 355.411201 -365.556185)
			(xy 355.359872 -365.577997) (xy 355.305915 -365.592103) (xy 355.250478 -365.598203) (xy 355.194744 -365.596166)
			(xy 355.139901 -365.586036) (xy 355.087117 -365.568029) (xy 355.037517 -365.542528) (xy 354.992159 -365.510077)
			(xy 354.95201 -365.471368) (xy 354.917924 -365.427225) (xy 354.890628 -365.37859) (xy 354.870705 -365.326499)
			(xy 354.858579 -365.272062) (xy 354.854508 -365.21644) (xy 302.410355 -365.21644) (xy 302.429032 -365.232888)
			(xy 302.465492 -365.274259) (xy 302.495616 -365.320449) (xy 302.518776 -365.370494) (xy 302.53449 -365.423352)
			(xy 302.54243 -365.477922) (xy 302.542431 -365.533067) (xy 302.534492 -365.587637) (xy 302.51878 -365.640496)
			(xy 302.495621 -365.690542) (xy 302.465498 -365.736733) (xy 302.429039 -365.778105) (xy 302.408336 -365.796322)
			(xy 302.397444 -365.806227) (xy 302.381366 -365.830874) (xy 302.372978 -365.859081) (xy 302.372977 -365.888509)
			(xy 302.381361 -365.916716) (xy 302.397437 -365.941365) (xy 302.408336 -365.951262) (xy 302.429039 -365.969482)
			(xy 302.465509 -366.010849) (xy 302.495641 -366.057038) (xy 302.518808 -366.107084) (xy 302.534526 -366.159945)
			(xy 302.542469 -366.214518) (xy 302.542956 -366.242092) (xy 302.542415 -366.269341) (xy 302.534661 -366.323284)
			(xy 302.519309 -366.375575) (xy 302.496672 -366.425149) (xy 302.467211 -366.470997) (xy 302.431526 -366.512186)
			(xy 302.390342 -366.547878) (xy 302.344498 -366.577345) (xy 302.294927 -366.599989) (xy 302.242639 -366.615349)
			(xy 302.188697 -366.623111) (xy 302.161448 -366.6236) (xy 302.133594 -366.623034) (xy 302.07848 -366.614917)
			(xy 302.025131 -366.598878) (xy 301.974679 -366.575257) (xy 301.928194 -366.544555) (xy 301.886664 -366.507425)
			(xy 301.85097 -366.464655) (xy 301.82187 -366.417151) (xy 301.799981 -366.365923) (xy 301.792386 -366.33912)
			(xy 301.788085 -366.325013) (xy 301.772701 -366.29987) (xy 301.75079 -366.280153) (xy 301.724168 -366.2675)
			(xy 301.695043 -366.262958) (xy 301.680372 -366.264444) (xy 301.667356 -366.266114) (xy 301.641171 -366.267893)
			(xy 301.628048 -366.268) (xy 301.613899 -366.267901) (xy 301.585676 -366.26587) (xy 301.57166 -366.263936)
			(xy 301.558312 -366.262339) (xy 301.531617 -366.265436) (xy 301.506661 -366.275405) (xy 301.485179 -366.291553)
			(xy 301.468668 -366.312756) (xy 301.458275 -366.337539) (xy 301.45609 -366.350804) (xy 301.451996 -366.377957)
			(xy 301.437027 -366.430789) (xy 301.414638 -366.480929) (xy 301.385293 -366.527342) (xy 301.349596 -366.569067)
			(xy 301.308286 -366.605245) (xy 301.262217 -366.635126) (xy 301.21234 -366.658094) (xy 301.159685 -366.673674)
			(xy 301.10534 -366.681544) (xy 301.077884 -366.68202) (xy 301.050633 -366.681537) (xy 300.996686 -366.673779)
			(xy 300.944392 -366.658422) (xy 300.894815 -366.63578) (xy 300.848965 -366.606313) (xy 300.807776 -366.570622)
			(xy 300.772084 -366.529431) (xy 300.742618 -366.483581) (xy 300.719976 -366.434005) (xy 300.70462 -366.38171)
			(xy 300.696863 -366.327763) (xy 300.696376 -366.300512) (xy 300.696858 -366.272938) (xy 300.704809 -366.218366)
			(xy 300.720531 -366.165507) (xy 300.743698 -366.115461) (xy 300.773827 -366.069271) (xy 300.810291 -366.027899)
			(xy 300.830996 -366.009682) (xy 300.841881 -365.999771) (xy 300.857954 -365.975124) (xy 300.866339 -365.94692)
			(xy 300.866342 -365.917495) (xy 300.857961 -365.88929) (xy 300.841891 -365.864641) (xy 300.830996 -365.854742)
			(xy 300.810301 -365.836513) (xy 300.77383 -365.795148) (xy 300.743696 -365.748962) (xy 300.720527 -365.698917)
			(xy 300.704807 -365.646058) (xy 300.696864 -365.591486) (xy 300.696376 -365.563912) (xy 300.69686 -365.537412)
			(xy 300.704199 -365.484922) (xy 300.718737 -365.433955) (xy 300.740193 -365.385492) (xy 300.768154 -365.340468)
			(xy 300.784768 -365.319818) (xy 300.79424 -365.307695) (xy 300.806022 -365.279286) (xy 300.808838 -365.248661)
			(xy 300.802436 -365.218581) (xy 300.787392 -365.191757) (xy 300.765062 -365.170609) (xy 300.751494 -365.163354)
			(xy 300.727822 -365.15122) (xy 300.683837 -365.121307) (xy 300.644551 -365.085446) (xy 300.610762 -365.044364)
			(xy 300.596554 -365.021876) (xy 300.588658 -365.009633) (xy 300.567178 -364.989964) (xy 300.541017 -364.977164)
			(xy 300.512307 -364.972273) (xy 300.483383 -364.975691) (xy 300.469808 -364.980982) (xy 300.446594 -364.99046)
			(xy 300.398263 -365.003816) (xy 300.348575 -365.010548) (xy 300.323504 -365.010954) (xy 300.298435 -365.010518)
			(xy 300.248752 -365.003774) (xy 300.200418 -364.990446) (xy 300.1772 -364.980982) (xy 300.163598 -364.975809)
			(xy 300.13471 -364.972429) (xy 300.106041 -364.977324) (xy 300.079911 -364.990095) (xy 300.058436 -365.009709)
			(xy 300.050454 -365.021876) (xy 300.035885 -365.045007) (xy 300.001042 -365.087128) (xy 299.960419 -365.123707)
			(xy 299.914888 -365.153958) (xy 299.865426 -365.177234) (xy 299.813095 -365.193034) (xy 299.759016 -365.20102)
			(xy 299.704352 -365.20102) (xy 299.650273 -365.193034) (xy 299.597942 -365.177234) (xy 299.54848 -365.153958)
			(xy 299.502949 -365.123707) (xy 299.462326 -365.087128) (xy 299.427483 -365.045007) (xy 299.412914 -365.021876)
			(xy 299.404961 -365.009674) (xy 299.383497 -364.990005) (xy 299.357351 -364.977199) (xy 299.328654 -364.972298)
			(xy 299.299741 -364.9757) (xy 299.286168 -364.980982) (xy 299.262959 -364.990473) (xy 299.214626 -365.003824)
			(xy 299.164936 -365.010551) (xy 299.139864 -365.010954) (xy 299.111984 -365.010359) (xy 299.056846 -365.002043)
			(xy 299.003564 -364.985603) (xy 298.953327 -364.961406) (xy 298.907257 -364.929992) (xy 298.866383 -364.892063)
			(xy 298.831619 -364.848466) (xy 298.80374 -364.800175) (xy 298.783369 -364.748268) (xy 298.770962 -364.693905)
			(xy 298.766795 -364.6383) (xy 292.904698 -364.6383) (xy 292.904948 -364.64004) (xy 292.905434 -364.667292)
			(xy 292.904986 -364.694867) (xy 292.897033 -364.749442) (xy 292.881306 -364.802303) (xy 292.858133 -364.85235)
			(xy 292.827996 -364.898539) (xy 292.791524 -364.939908) (xy 292.770814 -364.958122) (xy 292.759924 -364.968028)
			(xy 292.743849 -364.992676) (xy 292.735464 -365.020882) (xy 292.735462 -365.050308) (xy 292.743845 -365.078515)
			(xy 292.759917 -365.103164) (xy 292.770814 -365.113062) (xy 292.791511 -365.131287) (xy 292.827973 -365.172658)
			(xy 292.858099 -365.218847) (xy 292.88126 -365.268892) (xy 292.896975 -365.321751) (xy 292.904916 -365.376322)
			(xy 292.904916 -365.431468) (xy 292.896977 -365.486038) (xy 292.881264 -365.538898) (xy 292.858104 -365.588944)
			(xy 292.827979 -365.635134) (xy 292.791518 -365.676506) (xy 292.770814 -365.694722) (xy 292.760482 -365.70412)
			(xy 295.309034 -365.70412) (xy 295.313105 -365.648498) (xy 295.325231 -365.594061) (xy 295.345154 -365.54197)
			(xy 295.37245 -365.493335) (xy 295.406536 -365.449192) (xy 295.446685 -365.410483) (xy 295.492043 -365.378032)
			(xy 295.541643 -365.352531) (xy 295.594427 -365.334524) (xy 295.64927 -365.324394) (xy 295.705004 -365.322357)
			(xy 295.760441 -365.328457) (xy 295.814398 -365.342563) (xy 295.865727 -365.364375) (xy 295.913333 -365.393429)
			(xy 295.956201 -365.429104) (xy 295.993418 -365.470641) (xy 296.024191 -365.517154) (xy 296.047863 -365.567651)
			(xy 296.063931 -365.621058) (xy 296.072051 -365.676234) (xy 296.07256 -365.70412) (xy 296.072051 -365.732006)
			(xy 296.063931 -365.787182) (xy 296.047863 -365.840589) (xy 296.024191 -365.891086) (xy 295.993418 -365.937599)
			(xy 295.956201 -365.979136) (xy 295.913333 -366.014811) (xy 295.865727 -366.043865) (xy 295.814398 -366.065677)
			(xy 295.760441 -366.079783) (xy 295.705004 -366.085883) (xy 295.64927 -366.083846) (xy 295.594427 -366.073716)
			(xy 295.541643 -366.055709) (xy 295.492043 -366.030208) (xy 295.446685 -365.997757) (xy 295.406536 -365.959048)
			(xy 295.37245 -365.914905) (xy 295.345154 -365.86627) (xy 295.325231 -365.814179) (xy 295.313105 -365.759742)
			(xy 295.309034 -365.70412) (xy 292.760482 -365.70412) (xy 292.759924 -365.704628) (xy 292.743849 -365.729276)
			(xy 292.735464 -365.757482) (xy 292.735462 -365.786908) (xy 292.743845 -365.815115) (xy 292.759917 -365.839764)
			(xy 292.770814 -365.849662) (xy 292.791513 -365.867886) (xy 292.827983 -365.909253) (xy 292.858117 -365.95544)
			(xy 292.881285 -366.005485) (xy 292.897004 -366.058345) (xy 292.904947 -366.112918) (xy 292.905434 -366.140492)
			(xy 292.904915 -366.167742) (xy 292.89716 -366.221687) (xy 292.881807 -366.27398) (xy 292.859169 -366.323555)
			(xy 292.829706 -366.369404) (xy 292.794018 -366.410594) (xy 292.752832 -366.446286) (xy 292.706985 -366.475753)
			(xy 292.657412 -366.498395) (xy 292.60512 -366.513753) (xy 292.551176 -366.521512) (xy 292.523926 -366.522)
			(xy 292.496072 -366.521453) (xy 292.440957 -366.513334) (xy 292.387607 -366.497291) (xy 292.337155 -366.473668)
			(xy 292.29067 -366.442964) (xy 292.24914 -366.405831) (xy 292.213447 -366.363059) (xy 292.184347 -366.315553)
			(xy 292.162459 -366.264324) (xy 292.154864 -366.23752) (xy 292.150585 -366.223406) (xy 292.135197 -366.19826)
			(xy 292.11328 -366.178543) (xy 292.086652 -366.165892) (xy 292.057523 -366.161355) (xy 292.04285 -366.162844)
			(xy 292.029834 -366.164516) (xy 292.003649 -366.166294) (xy 291.990526 -366.1664) (xy 291.966978 -366.166093)
			(xy 291.920234 -366.160356) (xy 291.897308 -366.15497) (xy 291.884306 -366.152198) (xy 291.857736 -366.152613)
			(xy 291.832177 -366.159878) (xy 291.809361 -366.1735) (xy 291.79084 -366.192554) (xy 291.77787 -366.215746)
			(xy 291.771332 -366.241501) (xy 291.77107 -366.254792) (xy 291.77107 -366.259872) (xy 291.770584 -366.287123)
			(xy 291.762828 -366.341071) (xy 291.747473 -366.393366) (xy 291.724831 -366.442943) (xy 291.695365 -366.488793)
			(xy 291.659674 -366.529984) (xy 291.618483 -366.565675) (xy 291.572633 -366.595141) (xy 291.523056 -366.617783)
			(xy 291.470761 -366.633138) (xy 291.416813 -366.640894) (xy 291.362311 -366.640894) (xy 291.308363 -366.633138)
			(xy 291.256068 -366.617783) (xy 291.206491 -366.595141) (xy 291.160641 -366.565675) (xy 291.11945 -366.529984)
			(xy 291.083759 -366.488793) (xy 291.054293 -366.442943) (xy 291.031651 -366.393366) (xy 291.016296 -366.341071)
			(xy 291.00854 -366.287123) (xy 291.008054 -366.259872) (xy 291.00855 -366.232298) (xy 291.016494 -366.177726)
			(xy 291.032212 -366.124866) (xy 291.055376 -366.074819) (xy 291.085504 -366.028629) (xy 291.121968 -365.987258)
			(xy 291.142674 -365.969042) (xy 291.153601 -365.959173) (xy 291.169676 -365.934515) (xy 291.178059 -365.906299)
			(xy 291.178054 -365.876865) (xy 291.169661 -365.848652) (xy 291.153577 -365.824) (xy 291.142674 -365.814102)
			(xy 291.121955 -365.795899) (xy 291.085487 -365.754528) (xy 291.055356 -365.708336) (xy 291.032192 -365.658287)
			(xy 291.016477 -365.605423) (xy 291.008539 -365.550847) (xy 291.008054 -365.523272) (xy 291.008619 -365.493749)
			(xy 291.017752 -365.435413) (xy 291.035766 -365.379181) (xy 291.062229 -365.326397) (xy 291.07892 -365.302038)
			(xy 291.08686 -365.290159) (xy 291.096379 -365.263229) (xy 291.098067 -365.234716) (xy 291.09179 -365.206852)
			(xy 291.078041 -365.181816) (xy 291.057895 -365.161568) (xy 291.045646 -365.15421) (xy 291.024749 -365.14215)
			(xy 290.985971 -365.113443) (xy 290.951219 -365.079973) (xy 290.921074 -365.042301) (xy 290.908232 -365.021876)
			(xy 290.900357 -365.009618) (xy 290.878871 -364.989949) (xy 290.852705 -364.977151) (xy 290.823989 -364.972264)
			(xy 290.795062 -364.975688) (xy 290.781486 -364.980982) (xy 290.758274 -364.990467) (xy 290.709942 -365.00382)
			(xy 290.660253 -365.01055) (xy 290.635182 -365.010954) (xy 290.610113 -365.010525) (xy 290.56043 -365.003778)
			(xy 290.512095 -364.990447) (xy 290.488878 -364.980982) (xy 290.475284 -364.975785) (xy 290.446392 -364.972411)
			(xy 290.41772 -364.977311) (xy 290.391589 -364.990088) (xy 290.370114 -365.009707) (xy 290.362132 -365.021876)
			(xy 290.347563 -365.045007) (xy 290.31272 -365.087128) (xy 290.272097 -365.123707) (xy 290.226566 -365.153958)
			(xy 290.177104 -365.177234) (xy 290.124773 -365.193034) (xy 290.070694 -365.20102) (xy 290.01603 -365.20102)
			(xy 289.961951 -365.193034) (xy 289.90962 -365.177234) (xy 289.860158 -365.153958) (xy 289.814627 -365.123707)
			(xy 289.774004 -365.087128) (xy 289.739161 -365.045007) (xy 289.724592 -365.021876) (xy 289.71666 -365.009659)
			(xy 289.69519 -364.98999) (xy 289.669039 -364.977186) (xy 289.640337 -364.972289) (xy 289.61142 -364.975697)
			(xy 289.597846 -364.980982) (xy 289.574639 -364.99048) (xy 289.526305 -365.003828) (xy 289.476614 -365.010553)
			(xy 289.451542 -365.010954) (xy 289.423656 -365.01039) (xy 289.368506 -365.002083) (xy 289.31521 -364.985649)
			(xy 289.264959 -364.961454) (xy 289.218876 -364.93004) (xy 289.17799 -364.892108) (xy 289.143215 -364.848505)
			(xy 289.115327 -364.800206) (xy 289.094949 -364.74829) (xy 289.082538 -364.693916) (xy 289.07837 -364.6383)
			(xy 284.061698 -364.6383) (xy 284.061698 -364.660762) (xy 284.053712 -364.731638) (xy 284.037841 -364.801174)
			(xy 284.014283 -364.868495) (xy 283.983335 -364.932755) (xy 283.945387 -364.993147) (xy 283.900916 -365.048909)
			(xy 283.850481 -365.099341) (xy 283.794716 -365.143809) (xy 283.734322 -365.181754) (xy 283.67006 -365.212697)
			(xy 283.602737 -365.236251) (xy 283.5332 -365.252119) (xy 283.462324 -365.260101) (xy 283.426662 -365.260636)
			(xy 283.179012 -365.260636) (xy 282.961588 -365.47806) (xy 282.961588 -365.70412) (xy 285.620712 -365.70412)
			(xy 285.624783 -365.648498) (xy 285.636909 -365.594061) (xy 285.656832 -365.54197) (xy 285.684128 -365.493335)
			(xy 285.718214 -365.449192) (xy 285.758363 -365.410483) (xy 285.803721 -365.378032) (xy 285.853321 -365.352531)
			(xy 285.906105 -365.334524) (xy 285.960948 -365.324394) (xy 286.016682 -365.322357) (xy 286.072119 -365.328457)
			(xy 286.126076 -365.342563) (xy 286.177405 -365.364375) (xy 286.225011 -365.393429) (xy 286.267879 -365.429104)
			(xy 286.305096 -365.470641) (xy 286.335869 -365.517154) (xy 286.359541 -365.567651) (xy 286.375609 -365.621058)
			(xy 286.383729 -365.676234) (xy 286.384238 -365.70412) (xy 286.383729 -365.732006) (xy 286.375609 -365.787182)
			(xy 286.359541 -365.840589) (xy 286.335869 -365.891086) (xy 286.305096 -365.937599) (xy 286.267879 -365.979136)
			(xy 286.225011 -366.014811) (xy 286.177405 -366.043865) (xy 286.126076 -366.065677) (xy 286.072119 -366.079783)
			(xy 286.016682 -366.085883) (xy 285.960948 -366.083846) (xy 285.906105 -366.073716) (xy 285.853321 -366.055709)
			(xy 285.803721 -366.030208) (xy 285.758363 -365.997757) (xy 285.718214 -365.959048) (xy 285.684128 -365.914905)
			(xy 285.656832 -365.86627) (xy 285.636909 -365.814179) (xy 285.624783 -365.759742) (xy 285.620712 -365.70412)
			(xy 282.961588 -365.70412) (xy 282.961588 -373.340884) (xy 283.543248 -373.340884) (xy 283.543248 -369.227608)
			(xy 283.543883 -369.202626) (xy 283.553619 -369.153619) (xy 283.57272 -369.107449) (xy 283.600452 -369.065887)
			(xy 283.61767 -369.047776) (xy 285.44139 -367.224056) (xy 285.450831 -367.214129) (xy 285.464334 -367.190299)
			(xy 285.471022 -367.163738) (xy 285.470412 -367.136355) (xy 285.462549 -367.110118) (xy 285.447998 -367.086912)
			(xy 285.427805 -367.068407) (xy 285.403421 -367.055932) (xy 285.376599 -367.050383) (xy 285.362904 -367.050828)
			(xy 285.338266 -367.05159) (xy 285.311018 -367.051085) (xy 285.257077 -367.043325) (xy 285.20479 -367.027968)
			(xy 285.155221 -367.005325) (xy 285.109378 -366.975859) (xy 285.068195 -366.940169) (xy 285.03251 -366.898982)
			(xy 285.00305 -366.853135) (xy 284.980415 -366.803562) (xy 284.965064 -366.751273) (xy 284.957311 -366.697331)
			(xy 284.957313 -366.642835) (xy 284.965071 -366.588894) (xy 284.980426 -366.536606) (xy 285.003066 -366.487036)
			(xy 285.03253 -366.441192) (xy 285.068218 -366.400007) (xy 285.109404 -366.364321) (xy 285.15525 -366.334859)
			(xy 285.204821 -366.312221) (xy 285.25711 -366.296868) (xy 285.311051 -366.289112) (xy 285.365547 -366.289112)
			(xy 285.419489 -366.296867) (xy 285.471777 -366.31222) (xy 285.521349 -366.334858) (xy 285.567194 -366.36432)
			(xy 285.608381 -366.400006) (xy 285.644069 -366.441191) (xy 285.673533 -366.487035) (xy 285.696173 -366.536605)
			(xy 285.711529 -366.588893) (xy 285.719287 -366.642834) (xy 285.719774 -366.670082) (xy 285.719012 -366.69472)
			(xy 285.718591 -366.708413) (xy 285.724121 -366.735232) (xy 285.736582 -366.759614) (xy 285.755079 -366.779806)
			(xy 285.778278 -366.794352) (xy 285.80451 -366.802206) (xy 285.831886 -366.802802) (xy 285.858436 -366.796097)
			(xy 285.882246 -366.782575) (xy 285.89224 -366.773206) (xy 286.07639 -366.589056) (xy 286.094505 -366.571821)
			(xy 286.136042 -366.544004) (xy 286.182207 -366.524825) (xy 286.231227 -366.51502) (xy 286.256222 -366.51438)
			(xy 286.424878 -366.51438) (xy 286.43072 -366.470438) (xy 286.434875 -366.44333) (xy 286.449931 -366.390596)
			(xy 286.472381 -366.34056) (xy 286.501762 -366.294253) (xy 286.537469 -366.252628) (xy 286.578766 -366.216544)
			(xy 286.624804 -366.186743) (xy 286.674633 -366.163839) (xy 286.727228 -366.148303) (xy 286.781505 -366.140457)
			(xy 286.808926 -366.139984) (xy 286.836178 -366.140454) (xy 286.890125 -366.148213) (xy 286.94242 -366.163571)
			(xy 286.991997 -366.186215) (xy 287.037847 -366.215683) (xy 287.079036 -366.251376) (xy 287.114728 -366.292568)
			(xy 287.144194 -366.338419) (xy 287.166835 -366.387997) (xy 287.18219 -366.440292) (xy 287.189948 -366.49424)
			(xy 287.190094 -366.502442) (xy 288.052764 -366.502442) (xy 288.05325 -366.475191) (xy 288.061006 -366.421243)
			(xy 288.076361 -366.368948) (xy 288.099003 -366.319371) (xy 288.128469 -366.273521) (xy 288.16416 -366.23233)
			(xy 288.205351 -366.196639) (xy 288.251201 -366.167173) (xy 288.300778 -366.144531) (xy 288.353073 -366.129176)
			(xy 288.407021 -366.12142) (xy 288.461523 -366.12142) (xy 288.515471 -366.129176) (xy 288.567766 -366.144531)
			(xy 288.617343 -366.167173) (xy 288.663193 -366.196639) (xy 288.704384 -366.23233) (xy 288.740075 -366.273521)
			(xy 288.769541 -366.319371) (xy 288.792183 -366.368948) (xy 288.807538 -366.421243) (xy 288.815294 -366.475191)
			(xy 288.81578 -366.502442) (xy 288.815548 -366.521109) (xy 288.811855 -366.558261) (xy 288.808414 -366.57661)
			(xy 288.806165 -366.590889) (xy 288.808676 -366.619667) (xy 288.819156 -366.646586) (xy 288.836762 -366.669487)
			(xy 288.853909 -366.68202) (xy 294.64457 -366.68202) (xy 294.648641 -366.626398) (xy 294.660767 -366.571961)
			(xy 294.68069 -366.51987) (xy 294.707986 -366.471235) (xy 294.742072 -366.427092) (xy 294.782221 -366.388383)
			(xy 294.827579 -366.355932) (xy 294.877179 -366.330431) (xy 294.929963 -366.312424) (xy 294.984806 -366.302294)
			(xy 295.04054 -366.300257) (xy 295.095977 -366.306357) (xy 295.149934 -366.320463) (xy 295.201263 -366.342275)
			(xy 295.248869 -366.371329) (xy 295.291737 -366.407004) (xy 295.328954 -366.448541) (xy 295.359727 -366.495054)
			(xy 295.383399 -366.545551) (xy 295.399467 -366.598958) (xy 295.407587 -366.654134) (xy 295.408096 -366.68202)
			(xy 295.407587 -366.709906) (xy 295.399467 -366.765082) (xy 295.383399 -366.818489) (xy 295.359727 -366.868986)
			(xy 295.328954 -366.915499) (xy 295.291737 -366.957036) (xy 295.248869 -366.992711) (xy 295.201263 -367.021765)
			(xy 295.149934 -367.043577) (xy 295.095977 -367.057683) (xy 295.04054 -367.063783) (xy 294.984806 -367.061746)
			(xy 294.929963 -367.051616) (xy 294.877179 -367.033609) (xy 294.827579 -367.008108) (xy 294.782221 -366.975657)
			(xy 294.742072 -366.936948) (xy 294.707986 -366.892805) (xy 294.68069 -366.84417) (xy 294.660767 -366.792079)
			(xy 294.648641 -366.737642) (xy 294.64457 -366.68202) (xy 288.853909 -366.68202) (xy 288.860084 -366.686533)
			(xy 288.887249 -366.696356) (xy 288.901632 -366.697768) (xy 288.930291 -366.700084) (xy 288.98646 -366.712378)
			(xy 289.040148 -366.732959) (xy 289.090142 -366.761361) (xy 289.135308 -366.796943) (xy 289.174624 -366.838898)
			(xy 289.207202 -366.886277) (xy 289.232302 -366.938007) (xy 289.249357 -366.992917) (xy 289.257982 -367.049765)
			(xy 289.258502 -367.078514) (xy 289.258016 -367.105765) (xy 289.25026 -367.159713) (xy 289.234905 -367.212008)
			(xy 289.212263 -367.261585) (xy 289.203734 -367.274856) (xy 296.11574 -367.274856) (xy 296.116241 -367.246409)
			(xy 296.124701 -367.190149) (xy 296.141428 -367.13577) (xy 296.166048 -367.084479) (xy 296.198017 -367.037417)
			(xy 296.236624 -366.995627) (xy 296.258488 -366.977422) (xy 296.269983 -366.967503) (xy 296.287 -366.942374)
			(xy 296.295897 -366.913358) (xy 296.295892 -366.883009) (xy 296.286985 -366.853997) (xy 296.269961 -366.828873)
			(xy 296.258488 -366.818926) (xy 296.236618 -366.800728) (xy 296.198016 -366.758936) (xy 296.166053 -366.711871)
			(xy 296.141438 -366.660579) (xy 296.124719 -366.606199) (xy 296.116266 -366.549938) (xy 296.11574 -366.521492)
			(xy 296.116148 -366.494237) (xy 296.123907 -366.440281) (xy 296.139267 -366.38798) (xy 296.161914 -366.338396)
			(xy 296.191387 -366.292541) (xy 296.227087 -366.251347) (xy 296.268286 -366.215653) (xy 296.314145 -366.186187)
			(xy 296.363732 -366.163547) (xy 296.416036 -366.148195) (xy 296.469993 -366.140444) (xy 296.497248 -366.139984)
			(xy 296.525381 -366.140444) (xy 296.581038 -366.148693) (xy 296.634878 -366.165035) (xy 296.68573 -366.189115)
			(xy 296.73249 -366.220409) (xy 296.774141 -366.258237) (xy 296.809778 -366.301778) (xy 296.838627 -366.350084)
			(xy 296.860061 -366.402107) (xy 296.867326 -366.42929) (xy 296.870882 -366.442752) (xy 296.930524 -366.502442)
			(xy 297.741086 -366.502442) (xy 297.741572 -366.475191) (xy 297.749328 -366.421243) (xy 297.764683 -366.368948)
			(xy 297.787325 -366.319371) (xy 297.816791 -366.273521) (xy 297.852482 -366.23233) (xy 297.893673 -366.196639)
			(xy 297.939523 -366.167173) (xy 297.9891 -366.144531) (xy 298.041395 -366.129176) (xy 298.095343 -366.12142)
			(xy 298.149845 -366.12142) (xy 298.203793 -366.129176) (xy 298.256088 -366.144531) (xy 298.305665 -366.167173)
			(xy 298.351515 -366.196639) (xy 298.392706 -366.23233) (xy 298.428397 -366.273521) (xy 298.457863 -366.319371)
			(xy 298.480505 -366.368948) (xy 298.49586 -366.421243) (xy 298.503616 -366.475191) (xy 298.504102 -366.502442)
			(xy 298.503863 -366.521109) (xy 298.50017 -366.55826) (xy 298.496736 -366.57661) (xy 298.494466 -366.590887)
			(xy 298.496978 -366.619669) (xy 298.50746 -366.646591) (xy 298.525071 -366.669494) (xy 298.548398 -366.686539)
			(xy 298.575569 -366.696359) (xy 298.589954 -366.697768) (xy 298.618607 -366.700151) (xy 298.674774 -366.712433)
			(xy 298.728462 -366.733004) (xy 298.778456 -366.761398) (xy 298.823623 -366.796971) (xy 298.862942 -366.83892)
			(xy 298.895521 -366.886292) (xy 298.920622 -366.938017) (xy 298.937679 -366.992923) (xy 298.946304 -367.049767)
			(xy 298.946824 -367.078514) (xy 298.946338 -367.105765) (xy 298.938582 -367.159713) (xy 298.923227 -367.212008)
			(xy 298.900585 -367.261585) (xy 298.871119 -367.307435) (xy 298.835428 -367.348626) (xy 298.794237 -367.384317)
			(xy 298.748387 -367.413783) (xy 298.69881 -367.436425) (xy 298.646515 -367.45178) (xy 298.592567 -367.459536)
			(xy 298.538065 -367.459536) (xy 298.484117 -367.45178) (xy 298.431822 -367.436425) (xy 298.382245 -367.413783)
			(xy 298.336395 -367.384317) (xy 298.295204 -367.348626) (xy 298.259513 -367.307435) (xy 298.230047 -367.261585)
			(xy 298.207405 -367.212008) (xy 298.19205 -367.159713) (xy 298.184294 -367.105765) (xy 298.183808 -367.078514)
			(xy 298.184048 -367.059847) (xy 298.187736 -367.022695) (xy 298.191174 -367.004346) (xy 298.193481 -366.990074)
			(xy 298.190958 -366.96129) (xy 298.180467 -366.934367) (xy 298.16285 -366.911464) (xy 298.139518 -366.894419)
			(xy 298.112343 -366.884598) (xy 298.097956 -366.883188) (xy 298.069302 -366.880827) (xy 298.013138 -366.868534)
			(xy 297.959454 -366.847956) (xy 297.909464 -366.819557) (xy 297.864299 -366.78398) (xy 297.824983 -366.742031)
			(xy 297.792405 -366.694658) (xy 297.767301 -366.642935) (xy 297.750241 -366.588031) (xy 297.74161 -366.531189)
			(xy 297.741086 -366.502442) (xy 296.930524 -366.502442) (xy 297.18762 -366.759744) (xy 297.198759 -366.771199)
			(xy 297.218369 -366.796424) (xy 297.226736 -366.810036) (xy 297.234818 -366.822784) (xy 297.257047 -366.843183)
			(xy 297.284274 -366.856183) (xy 297.314113 -366.860644) (xy 297.343951 -366.856175) (xy 297.3578 -366.850168)
			(xy 297.38342 -366.838629) (xy 297.437193 -366.822332) (xy 297.492774 -366.814092) (xy 297.520868 -366.813592)
			(xy 297.548122 -366.814053) (xy 297.602077 -366.821806) (xy 297.654378 -366.83716) (xy 297.703963 -366.8598)
			(xy 297.74982 -366.889267) (xy 297.791016 -366.924961) (xy 297.826713 -366.966155) (xy 297.856184 -367.012009)
			(xy 297.878829 -367.061592) (xy 297.894187 -367.113892) (xy 297.901945 -367.167846) (xy 297.901945 -367.222354)
			(xy 297.894187 -367.276308) (xy 297.878829 -367.328608) (xy 297.856184 -367.378191) (xy 297.826713 -367.424045)
			(xy 297.791016 -367.465239) (xy 297.74982 -367.500933) (xy 297.703963 -367.5304) (xy 297.654378 -367.55304)
			(xy 297.602077 -367.568394) (xy 297.548122 -367.576147) (xy 297.520868 -367.576608) (xy 297.489286 -367.57591)
			(xy 297.426992 -367.565443) (xy 297.396916 -367.55578) (xy 297.383685 -367.551676) (xy 297.356043 -367.550014)
			(xy 297.328974 -367.555849) (xy 297.304472 -367.568752) (xy 297.284344 -367.58777) (xy 297.270075 -367.611503)
			(xy 297.262716 -367.638199) (xy 297.262296 -367.652046) (xy 297.262296 -368.302286) (xy 299.39361 -370.4336)
			(xy 339.72881 -370.4336) (xy 344.675968 -365.486696) (xy 344.69404 -365.469414) (xy 344.735593 -365.441609)
			(xy 344.781772 -365.422443) (xy 344.830802 -365.412652) (xy 344.8558 -365.41202) (xy 347.35262 -365.41202)
			(xy 347.377617 -365.412645) (xy 347.42664 -365.422453) (xy 347.47281 -365.44163) (xy 347.514356 -365.46944)
			(xy 347.532452 -365.486696) (xy 347.96603 -365.92002) (xy 355.754432 -365.92002) (xy 355.779429 -365.920637)
			(xy 355.828452 -365.930448) (xy 355.874623 -365.949627) (xy 355.916168 -365.977439) (xy 355.934264 -365.994696)
			(xy 356.514654 -366.575086) (xy 356.53599 -366.575086) (xy 356.563266 -366.575523) (xy 356.617272 -366.583221)
			(xy 356.66963 -366.598532) (xy 356.719273 -366.621145) (xy 356.76519 -366.650598) (xy 356.806443 -366.686291)
			(xy 356.842192 -366.727496) (xy 356.871708 -366.773373) (xy 356.894388 -366.822986) (xy 356.90977 -366.875324)
			(xy 356.917541 -366.929318) (xy 356.918006 -366.956594) (xy 356.917539 -366.983847) (xy 356.909783 -367.037798)
			(xy 356.894428 -367.090096) (xy 356.871786 -367.139676) (xy 356.842318 -367.185529) (xy 356.806625 -367.226722)
			(xy 356.765432 -367.262416) (xy 356.719579 -367.291884) (xy 356.669999 -367.314526) (xy 356.617702 -367.329882)
			(xy 356.563751 -367.337639) (xy 356.536498 -367.338102) (xy 356.510119 -367.337631) (xy 356.457863 -367.330378)
			(xy 356.407104 -367.315997) (xy 356.358809 -367.294763) (xy 356.313899 -367.267078) (xy 356.27323 -367.233473)
			(xy 356.237577 -367.194586) (xy 356.207619 -367.151159) (xy 356.195376 -367.12779) (xy 356.188674 -367.115431)
			(xy 356.169699 -367.094703) (xy 356.145785 -367.079941) (xy 356.118749 -367.072269) (xy 356.090647 -367.072269)
			(xy 356.063611 -367.079941) (xy 356.039697 -367.094703) (xy 356.020722 -367.115431) (xy 356.01402 -367.12779)
			(xy 356.001775 -367.151159) (xy 355.971814 -367.194584) (xy 355.93616 -367.23347) (xy 355.895491 -367.267077)
			(xy 355.850582 -367.294764) (xy 355.80229 -367.316004) (xy 355.751532 -367.330393) (xy 355.699277 -367.337657)
			(xy 355.672898 -367.338102) (xy 355.645622 -367.337645) (xy 355.591625 -367.329875) (xy 355.539287 -367.314492)
			(xy 355.489672 -367.291812) (xy 355.443794 -367.262296) (xy 355.402588 -367.226546) (xy 355.366894 -367.185292)
			(xy 355.33744 -367.139374) (xy 355.314827 -367.089729) (xy 355.299516 -367.03737) (xy 355.291818 -366.983363)
			(xy 355.29139 -366.956086) (xy 355.29139 -366.93475) (xy 355.201982 -366.845596) (xy 347.738192 -366.845596)
			(xy 347.713196 -366.844959) (xy 347.664174 -366.835154) (xy 347.618004 -366.815981) (xy 347.576457 -366.788174)
			(xy 347.55836 -366.77092) (xy 347.089222 -366.302036) (xy 345.16949 -366.302036) (xy 344.372397 -367.099088)
			(xy 345.670122 -367.099088) (xy 345.674193 -367.043466) (xy 345.686319 -366.989029) (xy 345.706242 -366.936938)
			(xy 345.733538 -366.888303) (xy 345.767624 -366.84416) (xy 345.807773 -366.805451) (xy 345.853131 -366.773)
			(xy 345.902731 -366.747499) (xy 345.955515 -366.729492) (xy 346.010358 -366.719362) (xy 346.066092 -366.717325)
			(xy 346.121529 -366.723425) (xy 346.175486 -366.737531) (xy 346.226815 -366.759343) (xy 346.274421 -366.788397)
			(xy 346.317289 -366.824072) (xy 346.354506 -366.865609) (xy 346.385279 -366.912122) (xy 346.408951 -366.962619)
			(xy 346.425019 -367.016026) (xy 346.433139 -367.071202) (xy 346.433648 -367.099088) (xy 346.433139 -367.126974)
			(xy 346.425019 -367.18215) (xy 346.408951 -367.235557) (xy 346.385279 -367.286054) (xy 346.354506 -367.332567)
			(xy 346.317289 -367.374104) (xy 346.274421 -367.409779) (xy 346.226815 -367.438833) (xy 346.175486 -367.460645)
			(xy 346.121529 -367.474751) (xy 346.066092 -367.480851) (xy 346.010358 -367.478814) (xy 345.955515 -367.468684)
			(xy 345.902731 -367.450677) (xy 345.853131 -367.425176) (xy 345.807773 -367.392725) (xy 345.767624 -367.354016)
			(xy 345.733538 -367.309873) (xy 345.706242 -367.261238) (xy 345.686319 -367.209147) (xy 345.674193 -367.15471)
			(xy 345.670122 -367.099088) (xy 344.372397 -367.099088) (xy 343.36676 -368.104674) (xy 346.277182 -368.104674)
			(xy 346.281253 -368.049052) (xy 346.293379 -367.994615) (xy 346.313302 -367.942524) (xy 346.340598 -367.893889)
			(xy 346.374684 -367.849746) (xy 346.414833 -367.811037) (xy 346.460191 -367.778586) (xy 346.509791 -367.753085)
			(xy 346.562575 -367.735078) (xy 346.617418 -367.724948) (xy 346.673152 -367.722911) (xy 346.728589 -367.729011)
			(xy 346.782546 -367.743117) (xy 346.833875 -367.764929) (xy 346.881481 -367.793983) (xy 346.924349 -367.829658)
			(xy 346.961566 -367.871195) (xy 346.992339 -367.917708) (xy 347.016011 -367.968205) (xy 347.032079 -368.021612)
			(xy 347.040199 -368.076788) (xy 347.040708 -368.104674) (xy 347.040569 -368.112294) (xy 347.30385 -368.112294)
			(xy 347.307921 -368.056672) (xy 347.320047 -368.002235) (xy 347.33997 -367.950144) (xy 347.367266 -367.901509)
			(xy 347.401352 -367.857366) (xy 347.441501 -367.818657) (xy 347.486859 -367.786206) (xy 347.536459 -367.760705)
			(xy 347.589243 -367.742698) (xy 347.644086 -367.732568) (xy 347.69982 -367.730531) (xy 347.755257 -367.736631)
			(xy 347.809214 -367.750737) (xy 347.860543 -367.772549) (xy 347.908149 -367.801603) (xy 347.951017 -367.837278)
			(xy 347.988234 -367.878815) (xy 348.019007 -367.925328) (xy 348.042679 -367.975825) (xy 348.058747 -368.029232)
			(xy 348.066867 -368.084408) (xy 348.067376 -368.112294) (xy 348.066867 -368.14018) (xy 348.058747 -368.195356)
			(xy 348.042679 -368.248763) (xy 348.019007 -368.29926) (xy 347.988234 -368.345773) (xy 347.951017 -368.38731)
			(xy 347.908149 -368.422985) (xy 347.860543 -368.452039) (xy 347.809214 -368.473851) (xy 347.755257 -368.487957)
			(xy 347.69982 -368.494057) (xy 347.644086 -368.49202) (xy 347.589243 -368.48189) (xy 347.536459 -368.463883)
			(xy 347.486859 -368.438382) (xy 347.441501 -368.405931) (xy 347.401352 -368.367222) (xy 347.367266 -368.323079)
			(xy 347.33997 -368.274444) (xy 347.320047 -368.222353) (xy 347.307921 -368.167916) (xy 347.30385 -368.112294)
			(xy 347.040569 -368.112294) (xy 347.040199 -368.13256) (xy 347.032079 -368.187736) (xy 347.016011 -368.241143)
			(xy 346.992339 -368.29164) (xy 346.961566 -368.338153) (xy 346.924349 -368.37969) (xy 346.881481 -368.415365)
			(xy 346.833875 -368.444419) (xy 346.782546 -368.466231) (xy 346.728589 -368.480337) (xy 346.673152 -368.486437)
			(xy 346.617418 -368.4844) (xy 346.562575 -368.47427) (xy 346.509791 -368.456263) (xy 346.460191 -368.430762)
			(xy 346.414833 -368.398311) (xy 346.374684 -368.359602) (xy 346.340598 -368.315459) (xy 346.313302 -368.266824)
			(xy 346.293379 -368.214733) (xy 346.281253 -368.160296) (xy 346.277182 -368.104674) (xy 343.36676 -368.104674)
			(xy 341.830424 -369.640932) (xy 346.293341 -369.640932) (xy 346.293345 -369.586423) (xy 346.301105 -369.532469)
			(xy 346.316466 -369.480169) (xy 346.339113 -369.430588) (xy 346.368587 -369.384734) (xy 346.404286 -369.343541)
			(xy 346.445484 -369.307849) (xy 346.491343 -369.278383) (xy 346.540928 -369.255744) (xy 346.59323 -369.240392)
			(xy 346.647185 -369.23264) (xy 346.67444 -369.23218) (xy 346.695505 -369.232424) (xy 346.737385 -369.237011)
			(xy 346.758006 -369.241324) (xy 346.77144 -369.243944) (xy 346.79877 -369.24259) (xy 346.824757 -369.234019)
			(xy 346.847531 -369.218848) (xy 346.865453 -369.19817) (xy 346.877234 -369.173471) (xy 346.882025 -369.14653)
			(xy 346.881196 -369.132866) (xy 346.879672 -369.098068) (xy 346.880212 -369.070819) (xy 346.887973 -369.016877)
			(xy 346.903331 -368.964588) (xy 346.925974 -368.915018) (xy 346.955441 -368.869174) (xy 346.991133 -368.82799)
			(xy 347.032322 -368.792305) (xy 347.07817 -368.762845) (xy 347.127745 -368.74021) (xy 347.180036 -368.72486)
			(xy 347.233979 -368.717108) (xy 347.288477 -368.717112) (xy 347.342419 -368.724872) (xy 347.394708 -368.740229)
			(xy 347.444279 -368.762872) (xy 347.490123 -368.792339) (xy 347.531307 -368.82803) (xy 347.566993 -368.869219)
			(xy 347.596453 -368.915067) (xy 347.619089 -368.964641) (xy 347.634439 -369.016932) (xy 347.642192 -369.070875)
			(xy 347.642188 -369.125373) (xy 347.634429 -369.179315) (xy 347.619072 -369.231604) (xy 347.59643 -369.281175)
			(xy 347.566964 -369.32702) (xy 347.531273 -369.368204) (xy 347.490085 -369.40389) (xy 347.444237 -369.433351)
			(xy 347.394663 -369.455987) (xy 347.342372 -369.471338) (xy 347.288429 -369.479091) (xy 347.26118 -369.479576)
			(xy 347.240115 -369.479329) (xy 347.198235 -369.474745) (xy 347.177614 -369.470432) (xy 347.16417 -369.467881)
			(xy 347.136851 -369.469231) (xy 347.110873 -369.477794) (xy 347.088105 -369.492953) (xy 347.070184 -369.513618)
			(xy 347.0584 -369.538303) (xy 347.053601 -369.565231) (xy 347.054424 -369.57889) (xy 347.055948 -369.613688)
			(xy 347.055458 -369.640943) (xy 347.047702 -369.694897) (xy 347.032346 -369.747198) (xy 347.009703 -369.796782)
			(xy 346.980234 -369.842638) (xy 346.944539 -369.883834) (xy 346.903344 -369.91953) (xy 346.857488 -369.949)
			(xy 346.807905 -369.971644) (xy 346.755604 -369.987001) (xy 346.701649 -369.994757) (xy 346.64714 -369.994757)
			(xy 346.593186 -369.986998) (xy 346.540885 -369.97164) (xy 346.491303 -369.948995) (xy 346.445448 -369.919524)
			(xy 346.404254 -369.883826) (xy 346.368559 -369.84263) (xy 346.339092 -369.796773) (xy 346.31645 -369.747188)
			(xy 346.301096 -369.694887) (xy 346.293341 -369.640932) (xy 341.830424 -369.640932) (xy 341.362344 -370.108988)
			(xy 347.338902 -370.108988) (xy 347.342973 -370.053366) (xy 347.355099 -369.998929) (xy 347.375022 -369.946838)
			(xy 347.402318 -369.898203) (xy 347.436404 -369.85406) (xy 347.476553 -369.815351) (xy 347.521911 -369.7829)
			(xy 347.571511 -369.757399) (xy 347.624295 -369.739392) (xy 347.679138 -369.729262) (xy 347.734872 -369.727225)
			(xy 347.790309 -369.733325) (xy 347.844266 -369.747431) (xy 347.895595 -369.769243) (xy 347.943201 -369.798297)
			(xy 347.986069 -369.833972) (xy 348.023286 -369.875509) (xy 348.054059 -369.922022) (xy 348.077731 -369.972519)
			(xy 348.093799 -370.025926) (xy 348.101919 -370.081102) (xy 348.102428 -370.108988) (xy 348.101919 -370.136874)
			(xy 348.093799 -370.19205) (xy 348.077731 -370.245457) (xy 348.054059 -370.295954) (xy 348.023286 -370.342467)
			(xy 347.986069 -370.384004) (xy 347.943201 -370.419679) (xy 347.895595 -370.448733) (xy 347.844266 -370.470545)
			(xy 347.790309 -370.484651) (xy 347.734872 -370.490751) (xy 347.679138 -370.488714) (xy 347.624295 -370.478584)
			(xy 347.571511 -370.460577) (xy 347.521911 -370.435076) (xy 347.476553 -370.402625) (xy 347.436404 -370.363916)
			(xy 347.402318 -370.319773) (xy 347.375022 -370.271138) (xy 347.355099 -370.219047) (xy 347.342973 -370.16461)
			(xy 347.338902 -370.108988) (xy 341.362344 -370.108988) (xy 340.536294 -370.934996) (xy 347.608396 -370.934996)
			(xy 347.612467 -370.879374) (xy 347.624593 -370.824937) (xy 347.644516 -370.772846) (xy 347.671812 -370.724211)
			(xy 347.705898 -370.680068) (xy 347.746047 -370.641359) (xy 347.791405 -370.608908) (xy 347.841005 -370.583407)
			(xy 347.893789 -370.5654) (xy 347.948632 -370.55527) (xy 348.004366 -370.553233) (xy 348.059803 -370.559333)
			(xy 348.11376 -370.573439) (xy 348.165089 -370.595251) (xy 348.212695 -370.624305) (xy 348.255563 -370.65998)
			(xy 348.29278 -370.701517) (xy 348.323553 -370.74803) (xy 348.347225 -370.798527) (xy 348.363293 -370.851934)
			(xy 348.371413 -370.90711) (xy 348.371922 -370.934996) (xy 348.371413 -370.962882) (xy 348.363293 -371.018058)
			(xy 348.347225 -371.071465) (xy 348.323553 -371.121962) (xy 348.29278 -371.168475) (xy 348.255563 -371.210012)
			(xy 348.212695 -371.245687) (xy 348.165089 -371.274741) (xy 348.11376 -371.296553) (xy 348.059803 -371.310659)
			(xy 348.004366 -371.316759) (xy 347.948632 -371.314722) (xy 347.893789 -371.304592) (xy 347.841005 -371.286585)
			(xy 347.791405 -371.261084) (xy 347.746047 -371.228633) (xy 347.705898 -371.189924) (xy 347.671812 -371.145781)
			(xy 347.644516 -371.097146) (xy 347.624593 -371.045055) (xy 347.612467 -370.990618) (xy 347.608396 -370.934996)
			(xy 340.536294 -370.934996) (xy 340.186772 -371.2845) (xy 340.168682 -371.301762) (xy 340.127135 -371.329571)
			(xy 340.080962 -371.348743) (xy 340.031937 -371.35854) (xy 340.00694 -371.359176) (xy 299.0977 -371.359176)
			(xy 299.072704 -371.35854) (xy 299.023681 -371.348736) (xy 298.977511 -371.329562) (xy 298.935964 -371.301755)
			(xy 298.917868 -371.2845) (xy 296.317416 -368.684048) (xy 296.300145 -368.665966) (xy 296.272337 -368.624417)
			(xy 296.253168 -368.578241) (xy 296.243374 -368.529214) (xy 296.24274 -368.504216) (xy 296.24274 -367.559082)
			(xy 296.22315 -367.540886) (xy 296.188688 -367.500009) (xy 296.160271 -367.454721) (xy 296.138454 -367.405909)
			(xy 296.123664 -367.35453) (xy 296.116193 -367.301589) (xy 296.11574 -367.274856) (xy 289.203734 -367.274856)
			(xy 289.182797 -367.307435) (xy 289.147106 -367.348626) (xy 289.105915 -367.384317) (xy 289.060065 -367.413783)
			(xy 289.010488 -367.436425) (xy 288.958193 -367.45178) (xy 288.904245 -367.459536) (xy 288.849743 -367.459536)
			(xy 288.795795 -367.45178) (xy 288.7435 -367.436425) (xy 288.693923 -367.413783) (xy 288.648073 -367.384317)
			(xy 288.606882 -367.348626) (xy 288.571191 -367.307435) (xy 288.541725 -367.261585) (xy 288.519083 -367.212008)
			(xy 288.503728 -367.159713) (xy 288.495972 -367.105765) (xy 288.495486 -367.078514) (xy 288.495734 -367.059847)
			(xy 288.499421 -367.022696) (xy 288.502852 -367.004346) (xy 288.505179 -366.990076) (xy 288.502656 -366.961288)
			(xy 288.492163 -366.934361) (xy 288.474541 -366.911457) (xy 288.451204 -366.894413) (xy 288.424024 -366.884595)
			(xy 288.409634 -366.883188) (xy 288.380986 -366.88076) (xy 288.324824 -366.868479) (xy 288.27114 -366.84791)
			(xy 288.221149 -366.81952) (xy 288.175984 -366.783951) (xy 288.136666 -366.742009) (xy 288.104086 -366.694643)
			(xy 288.078981 -366.642924) (xy 288.06192 -366.588025) (xy 288.053288 -366.531187) (xy 288.052764 -366.502442)
			(xy 287.190094 -366.502442) (xy 287.190434 -366.521492) (xy 287.190004 -366.54683) (xy 287.183297 -366.59706)
			(xy 287.169998 -366.64596) (xy 287.150343 -366.692669) (xy 287.124677 -366.736364) (xy 287.093453 -366.776278)
			(xy 287.075626 -366.794288) (xy 287.066284 -366.80409) (xy 287.052572 -366.827425) (xy 287.045463 -366.853539)
			(xy 287.045456 -366.880604) (xy 287.05255 -366.906722) (xy 287.066249 -366.930064) (xy 287.075626 -366.93983)
			(xy 287.093474 -366.957822) (xy 287.124698 -366.997738) (xy 287.150364 -367.041438) (xy 287.170018 -367.08815)
			(xy 287.183315 -367.137053) (xy 287.190021 -367.187287) (xy 287.190314 -367.20526) (xy 287.442908 -367.20526)
			(xy 287.446979 -367.149638) (xy 287.459105 -367.095201) (xy 287.479028 -367.04311) (xy 287.506324 -366.994475)
			(xy 287.54041 -366.950332) (xy 287.580559 -366.911623) (xy 287.625917 -366.879172) (xy 287.675517 -366.853671)
			(xy 287.728301 -366.835664) (xy 287.783144 -366.825534) (xy 287.838878 -366.823497) (xy 287.894315 -366.829597)
			(xy 287.948272 -366.843703) (xy 287.999601 -366.865515) (xy 288.047207 -366.894569) (xy 288.090075 -366.930244)
			(xy 288.127292 -366.971781) (xy 288.158065 -367.018294) (xy 288.181737 -367.068791) (xy 288.197805 -367.122198)
			(xy 288.205925 -367.177374) (xy 288.206434 -367.20526) (xy 288.205925 -367.233146) (xy 288.197805 -367.288322)
			(xy 288.181737 -367.341729) (xy 288.158065 -367.392226) (xy 288.127292 -367.438739) (xy 288.090075 -367.480276)
			(xy 288.047207 -367.515951) (xy 287.999601 -367.545005) (xy 287.948272 -367.566817) (xy 287.894315 -367.580923)
			(xy 287.838878 -367.587023) (xy 287.783144 -367.584986) (xy 287.728301 -367.574856) (xy 287.675517 -367.556849)
			(xy 287.625917 -367.531348) (xy 287.580559 -367.498897) (xy 287.54041 -367.460188) (xy 287.506324 -367.416045)
			(xy 287.479028 -367.36741) (xy 287.459105 -367.315319) (xy 287.446979 -367.260882) (xy 287.442908 -367.20526)
			(xy 287.190314 -367.20526) (xy 287.190434 -367.212626) (xy 287.189946 -367.239877) (xy 287.182187 -367.293823)
			(xy 287.16683 -367.346116) (xy 287.144188 -367.395692) (xy 287.114721 -367.441541) (xy 287.07903 -367.48273)
			(xy 287.037841 -367.518421) (xy 286.991992 -367.547888) (xy 286.942416 -367.57053) (xy 286.890123 -367.585887)
			(xy 286.836177 -367.593646) (xy 286.808926 -367.594134) (xy 286.778875 -367.593555) (xy 286.719517 -367.584123)
			(xy 286.662372 -367.565503) (xy 286.608852 -367.538155) (xy 286.56028 -367.502757) (xy 286.53867 -367.481866)
			(xy 286.523938 -367.46688) (xy 286.457136 -367.46688) (xy 284.432756 -369.49126) (xy 284.432756 -372.987077)
			(xy 286.21657 -372.987077) (xy 286.220304 -372.933821) (xy 286.231425 -372.881605) (xy 286.249717 -372.83145)
			(xy 286.274821 -372.784334) (xy 286.306249 -372.741178) (xy 286.343386 -372.702825) (xy 286.364172 -372.686072)
			(xy 286.376017 -372.676217) (xy 286.393536 -372.650882) (xy 286.402709 -372.621478) (xy 286.402702 -372.590676)
			(xy 286.393516 -372.561275) (xy 286.375984 -372.535949) (xy 286.364172 -372.526052) (xy 286.341708 -372.507839)
			(xy 286.301972 -372.465823) (xy 286.269032 -372.418292) (xy 286.243641 -372.366335) (xy 286.22638 -372.311142)
			(xy 286.217645 -372.253977) (xy 286.217106 -372.225062) (xy 286.217607 -372.197693) (xy 286.225416 -372.143515)
			(xy 286.240897 -372.091013) (xy 286.263731 -372.041265) (xy 286.293448 -371.995297) (xy 286.311086 -371.974364)
			(xy 286.320361 -371.963065) (xy 286.332535 -371.936497) (xy 286.336701 -371.907571) (xy 286.332519 -371.878648)
			(xy 286.320329 -371.852087) (xy 286.311086 -371.84076) (xy 286.29341 -371.819857) (xy 286.26369 -371.773883)
			(xy 286.240849 -371.724131) (xy 286.225357 -371.671625) (xy 286.217533 -371.617443) (xy 286.217537 -371.562699)
			(xy 286.22537 -371.508519) (xy 286.240869 -371.456015) (xy 286.263717 -371.406267) (xy 286.293444 -371.360298)
			(xy 286.311086 -371.339364) (xy 286.320361 -371.328065) (xy 286.332535 -371.301497) (xy 286.336701 -371.272571)
			(xy 286.332519 -371.243648) (xy 286.320329 -371.217087) (xy 286.311086 -371.20576) (xy 286.293459 -371.184818)
			(xy 286.263746 -371.138848) (xy 286.240908 -371.089103) (xy 286.225414 -371.036604) (xy 286.217582 -370.98243)
			(xy 286.217106 -370.955062) (xy 286.217543 -370.927809) (xy 286.225305 -370.873859) (xy 286.240665 -370.821562)
			(xy 286.263312 -370.771984) (xy 286.292783 -370.726133) (xy 286.32848 -370.684943) (xy 286.369675 -370.649252)
			(xy 286.41553 -370.619787) (xy 286.465111 -370.597147) (xy 286.51741 -370.581793) (xy 286.571361 -370.574039)
			(xy 286.598614 -370.573554) (xy 286.625985 -370.573999) (xy 286.680166 -370.58182) (xy 286.73267 -370.597313)
			(xy 286.782416 -370.62016) (xy 286.828382 -370.64989) (xy 286.849312 -370.667534) (xy 286.86064 -370.67677)
			(xy 286.887197 -370.688946) (xy 286.916114 -370.693119) (xy 286.945031 -370.688946) (xy 286.971588 -370.67677)
			(xy 286.982916 -370.667534) (xy 287.003873 -370.649926) (xy 287.049839 -370.620208) (xy 287.09958 -370.597366)
			(xy 287.152075 -370.581868) (xy 287.206246 -370.574032) (xy 287.233614 -370.573554) (xy 287.26253 -370.574114)
			(xy 287.3197 -370.582831) (xy 287.374899 -370.60008) (xy 287.426861 -370.625464) (xy 287.474396 -370.658401)
			(xy 287.516413 -370.698137) (xy 287.534604 -370.72062) (xy 287.544501 -370.732425) (xy 287.569825 -370.749944)
			(xy 287.599218 -370.75912) (xy 287.63001 -370.75912) (xy 287.659403 -370.749944) (xy 287.684727 -370.732425)
			(xy 287.694624 -370.72062) (xy 287.712807 -370.698129) (xy 287.754827 -370.658394) (xy 287.802364 -370.625455)
			(xy 287.854327 -370.600068) (xy 287.909526 -370.582813) (xy 287.966697 -370.574087) (xy 287.995614 -370.573554)
			(xy 288.022864 -370.574065) (xy 288.076809 -370.581822) (xy 288.129101 -370.597177) (xy 288.178675 -370.619817)
			(xy 288.224524 -370.649281) (xy 288.265713 -370.68497) (xy 288.301404 -370.726157) (xy 288.330871 -370.772003)
			(xy 288.353515 -370.821577) (xy 288.368873 -370.873868) (xy 288.376634 -370.927812) (xy 288.377122 -370.955062)
			(xy 288.376653 -370.982432) (xy 288.368839 -371.036612) (xy 288.353351 -371.089116) (xy 288.33051 -371.138863)
			(xy 288.300784 -371.184829) (xy 288.283142 -371.20576) (xy 288.273946 -371.217117) (xy 288.261772 -371.243665)
			(xy 288.257594 -371.272571) (xy 288.261755 -371.30148) (xy 288.273915 -371.328035) (xy 288.283142 -371.339364)
			(xy 288.300747 -371.360326) (xy 288.330475 -371.406288) (xy 288.353325 -371.456029) (xy 288.368825 -371.508527)
			(xy 288.376658 -371.562702) (xy 288.376662 -371.617441) (xy 288.368838 -371.671617) (xy 288.353345 -371.724117)
			(xy 288.330503 -371.773862) (xy 288.300781 -371.819828) (xy 288.283142 -371.84076) (xy 288.273946 -371.852117)
			(xy 288.261772 -371.878665) (xy 288.257594 -371.907571) (xy 288.261755 -371.93648) (xy 288.273915 -371.963035)
			(xy 288.283142 -371.974364) (xy 288.300785 -371.995293) (xy 288.330495 -372.041267) (xy 288.353329 -372.091016)
			(xy 288.36882 -372.143517) (xy 288.376648 -372.197693) (xy 288.377122 -372.225062) (xy 288.376606 -372.253979)
			(xy 288.367881 -372.311152) (xy 288.350624 -372.366352) (xy 288.325232 -372.418315) (xy 288.292287 -372.465848)
			(xy 288.252543 -372.507863) (xy 288.230056 -372.526052) (xy 288.218285 -372.535989) (xy 288.200759 -372.561299)
			(xy 288.191575 -372.590684) (xy 288.191568 -372.62147) (xy 288.200738 -372.650858) (xy 288.218252 -372.676177)
			(xy 288.230056 -372.686072) (xy 288.250801 -372.702871) (xy 288.287929 -372.741219) (xy 288.319349 -372.784369)
			(xy 288.344448 -372.831477) (xy 288.362735 -372.881624) (xy 288.373854 -372.93383) (xy 288.375806 -372.961677)
			(xy 289.58207 -372.961677) (xy 289.585804 -372.908421) (xy 289.596925 -372.856205) (xy 289.615217 -372.80605)
			(xy 289.640321 -372.758934) (xy 289.671749 -372.715778) (xy 289.708886 -372.677425) (xy 289.729672 -372.660672)
			(xy 289.741517 -372.650817) (xy 289.759036 -372.625482) (xy 289.768209 -372.596078) (xy 289.768202 -372.565276)
			(xy 289.759016 -372.535875) (xy 289.741484 -372.510549) (xy 289.729672 -372.500652) (xy 289.707208 -372.482439)
			(xy 289.667472 -372.440423) (xy 289.634532 -372.392892) (xy 289.609141 -372.340935) (xy 289.59188 -372.285742)
			(xy 289.583145 -372.228577) (xy 289.582606 -372.199662) (xy 289.583107 -372.172293) (xy 289.590916 -372.118115)
			(xy 289.606397 -372.065613) (xy 289.629231 -372.015865) (xy 289.658948 -371.969897) (xy 289.676586 -371.948964)
			(xy 289.685861 -371.937665) (xy 289.698035 -371.911097) (xy 289.702201 -371.882171) (xy 289.698019 -371.853248)
			(xy 289.685829 -371.826687) (xy 289.676586 -371.81536) (xy 289.65891 -371.794457) (xy 289.62919 -371.748483)
			(xy 289.606349 -371.698731) (xy 289.590857 -371.646225) (xy 289.583033 -371.592043) (xy 289.583037 -371.537299)
			(xy 289.59087 -371.483119) (xy 289.606369 -371.430615) (xy 289.629217 -371.380867) (xy 289.658944 -371.334898)
			(xy 289.676586 -371.313964) (xy 289.685861 -371.302665) (xy 289.698035 -371.276097) (xy 289.702201 -371.247171)
			(xy 289.698019 -371.218248) (xy 289.685829 -371.191687) (xy 289.676586 -371.18036) (xy 289.658959 -371.159418)
			(xy 289.629246 -371.113448) (xy 289.606408 -371.063703) (xy 289.590914 -371.011204) (xy 289.583082 -370.95703)
			(xy 289.582606 -370.929662) (xy 289.583092 -370.902411) (xy 289.590848 -370.848463) (xy 289.606203 -370.796168)
			(xy 289.628845 -370.746591) (xy 289.658311 -370.700741) (xy 289.694002 -370.65955) (xy 289.735193 -370.623859)
			(xy 289.781043 -370.594393) (xy 289.83062 -370.571751) (xy 289.882915 -370.556396) (xy 289.936863 -370.54864)
			(xy 289.991365 -370.54864) (xy 290.045313 -370.556396) (xy 290.097608 -370.571751) (xy 290.147185 -370.594393)
			(xy 290.193035 -370.623859) (xy 290.234226 -370.65955) (xy 290.269917 -370.700741) (xy 290.295262 -370.740178)
			(xy 291.927026 -370.740178) (xy 291.927573 -370.711009) (xy 291.936476 -370.653353) (xy 291.954056 -370.597726)
			(xy 291.979902 -370.545425) (xy 292.013412 -370.497671) (xy 292.053803 -370.455576) (xy 292.076632 -370.43741)
			(xy 292.086966 -370.428937) (xy 292.103261 -370.407771) (xy 292.113508 -370.383104) (xy 292.117008 -370.356623)
			(xy 292.113521 -370.330141) (xy 292.103284 -370.305469) (xy 292.086999 -370.284296) (xy 292.076632 -370.275866)
			(xy 292.053819 -370.25768) (xy 292.013415 -370.215598) (xy 291.979897 -370.16785) (xy 291.954048 -370.115551)
			(xy 291.936473 -370.059924) (xy 291.927582 -370.002267) (xy 291.927026 -369.973098) (xy 291.927454 -369.945844)
			(xy 291.935212 -369.89189) (xy 291.95057 -369.839589) (xy 291.973215 -369.790007) (xy 292.002686 -369.744152)
			(xy 292.038384 -369.702958) (xy 292.079581 -369.667265) (xy 292.125438 -369.637798) (xy 292.175023 -369.615157)
			(xy 292.227325 -369.599804) (xy 292.28128 -369.592051) (xy 292.308534 -369.59159) (xy 292.337451 -369.592122)
			(xy 292.394623 -369.600843) (xy 292.449823 -369.618096) (xy 292.501786 -369.643485) (xy 292.549319 -369.676428)
			(xy 292.591335 -369.71617) (xy 292.609524 -369.738656) (xy 292.619421 -369.750461) (xy 292.644745 -369.76798)
			(xy 292.674138 -369.777156) (xy 292.70493 -369.777156) (xy 292.734323 -369.76798) (xy 292.759647 -369.750461)
			(xy 292.769544 -369.738656) (xy 292.787699 -369.716142) (xy 292.829728 -369.676411) (xy 292.87727 -369.643477)
			(xy 292.929239 -369.618094) (xy 292.984442 -369.600844) (xy 293.041616 -369.592122) (xy 293.070534 -369.59159)
			(xy 293.099081 -369.59211) (xy 293.155536 -369.600633) (xy 293.210091 -369.61747) (xy 293.26153 -369.642244)
			(xy 293.285418 -369.657884) (xy 293.296563 -369.664941) (xy 293.321415 -369.673747) (xy 293.347695 -369.675874)
			(xy 293.37364 -369.671181) (xy 293.39751 -369.659982) (xy 293.417702 -369.643028) (xy 293.425626 -369.632484)
			(xy 293.441057 -369.611486) (xy 293.476652 -369.573431) (xy 293.517093 -369.540572) (xy 293.561628 -369.513519)
			(xy 293.609429 -369.492776) (xy 293.659607 -369.478729) (xy 293.71123 -369.471638) (xy 293.737284 -369.471194)
			(xy 293.766202 -369.471688) (xy 293.823376 -369.480417) (xy 293.878577 -369.497677) (xy 293.93054 -369.523073)
			(xy 293.978072 -369.556023) (xy 294.020086 -369.595771) (xy 294.038274 -369.61826) (xy 294.048171 -369.630065)
			(xy 294.073495 -369.647584) (xy 294.102888 -369.65676) (xy 294.13368 -369.65676) (xy 294.163073 -369.647584)
			(xy 294.188397 -369.630065) (xy 294.198294 -369.61826) (xy 294.216478 -369.595771) (xy 294.258501 -369.556038)
			(xy 294.306037 -369.523101) (xy 294.358 -369.497714) (xy 294.413198 -369.480458) (xy 294.470368 -369.471729)
			(xy 294.499284 -369.471194) (xy 294.526537 -369.47167) (xy 294.580487 -369.479425) (xy 294.632785 -369.494779)
			(xy 294.682365 -369.51742) (xy 294.728218 -369.546886) (xy 294.769411 -369.582579) (xy 294.805105 -369.62377)
			(xy 294.834573 -369.669623) (xy 294.857216 -369.719202) (xy 294.872572 -369.771499) (xy 294.880329 -369.825449)
			(xy 294.880792 -369.852702) (xy 294.880362 -369.878745) (xy 294.873275 -369.930348) (xy 294.859233 -369.980506)
			(xy 294.838498 -370.028288) (xy 294.811455 -370.072804) (xy 294.778606 -370.113227) (xy 294.759888 -370.13134)
			(xy 294.749997 -370.141348) (xy 294.735529 -370.165464) (xy 294.72818 -370.19261) (xy 294.728505 -370.220731)
			(xy 294.73648 -370.247699) (xy 294.7515 -370.271474) (xy 294.761666 -370.2812) (xy 294.781236 -370.299374)
			(xy 294.815628 -370.340233) (xy 294.843987 -370.385488) (xy 294.865756 -370.434257) (xy 294.880511 -370.485585)
			(xy 294.887963 -370.538469) (xy 294.888412 -370.565172) (xy 294.887892 -370.592941) (xy 294.879843 -370.647893)
			(xy 294.863911 -370.701096) (xy 294.840433 -370.751428) (xy 294.809904 -370.797823) (xy 294.772971 -370.8393)
			(xy 294.752014 -370.857526) (xy 294.741396 -370.867082) (xy 294.725411 -370.890736) (xy 294.716616 -370.917896)
			(xy 294.7157 -370.94643) (xy 294.722736 -370.974099) (xy 294.737171 -370.998729) (xy 294.747188 -371.00891)
			(xy 294.765535 -371.026997) (xy 294.797707 -371.067237) (xy 294.824176 -371.111437) (xy 294.844461 -371.158796)
			(xy 294.858194 -371.208451) (xy 294.865127 -371.259502) (xy 294.865552 -371.285262) (xy 294.865075 -371.312632)
			(xy 294.857262 -371.366811) (xy 294.841776 -371.419315) (xy 294.818936 -371.469062) (xy 294.789213 -371.515028)
			(xy 294.771572 -371.53596) (xy 294.762374 -371.547316) (xy 294.750196 -371.573864) (xy 294.746017 -371.602771)
			(xy 294.750179 -371.631681) (xy 294.762343 -371.658236) (xy 294.771572 -371.669564) (xy 294.789176 -371.690527)
			(xy 294.818902 -371.736489) (xy 294.84175 -371.786231) (xy 294.857249 -371.838728) (xy 294.865081 -371.892903)
			(xy 294.865085 -371.94764) (xy 294.857261 -372.001816) (xy 294.84177 -372.054316) (xy 294.81893 -372.10406)
			(xy 294.78921 -372.150027) (xy 294.771572 -372.17096) (xy 294.762374 -372.182316) (xy 294.750196 -372.208864)
			(xy 294.746017 -372.237771) (xy 294.750179 -372.266681) (xy 294.762343 -372.293236) (xy 294.771572 -372.304564)
			(xy 294.789176 -372.325527) (xy 294.818902 -372.371489) (xy 294.84175 -372.421231) (xy 294.857249 -372.473728)
			(xy 294.860837 -372.49855) (xy 295.942254 -372.49855) (xy 295.942254 -372.413854) (xy 295.950305 -372.32954)
			(xy 295.966334 -372.246374) (xy 295.990195 -372.165107) (xy 296.021674 -372.086477) (xy 296.060485 -372.011196)
			(xy 296.106275 -371.939944) (xy 296.158631 -371.873368) (xy 296.217079 -371.81207) (xy 296.281089 -371.756605)
			(xy 296.350081 -371.707476) (xy 296.423431 -371.665127) (xy 296.500474 -371.629943) (xy 296.580513 -371.602241)
			(xy 296.662822 -371.582273) (xy 296.746657 -371.57022) (xy 296.831258 -371.56619) (xy 296.915859 -371.57022)
			(xy 296.999694 -371.582273) (xy 297.082003 -371.602241) (xy 297.162042 -371.629943) (xy 297.239085 -371.665127)
			(xy 297.312435 -371.707476) (xy 297.381427 -371.756605) (xy 297.445437 -371.81207) (xy 297.503885 -371.873368)
			(xy 297.556241 -371.939944) (xy 297.602031 -372.011196) (xy 297.640842 -372.086477) (xy 297.672321 -372.165107)
			(xy 297.696182 -372.246374) (xy 297.712211 -372.32954) (xy 297.720262 -372.413854) (xy 297.720766 -372.456202)
			(xy 298.466767 -372.456202) (xy 298.470803 -372.372755) (xy 298.482875 -372.290087) (xy 298.502868 -372.20897)
			(xy 298.530597 -372.130161) (xy 298.565803 -372.054396) (xy 298.608157 -371.982383) (xy 298.657263 -371.914794)
			(xy 298.712664 -371.85226) (xy 298.773841 -371.795365) (xy 298.840224 -371.744639) (xy 298.911192 -371.700558)
			(xy 298.986084 -371.663532) (xy 299.0642 -371.633906) (xy 299.14481 -371.611958) (xy 299.227162 -371.597893)
			(xy 299.310488 -371.591841) (xy 299.394008 -371.59386) (xy 299.476944 -371.60393) (xy 299.55852 -371.621958)
			(xy 299.637976 -371.647775) (xy 299.714569 -371.68114) (xy 299.787585 -371.721741) (xy 299.856341 -371.7692)
			(xy 299.920195 -371.823073) (xy 299.978552 -371.882858) (xy 300.030867 -371.947995) (xy 300.07665 -372.017878)
			(xy 300.115475 -372.091853) (xy 300.14698 -372.16923) (xy 300.170869 -372.249287) (xy 300.18692 -372.331275)
			(xy 300.194983 -372.41443) (xy 300.195488 -372.456202) (xy 300.194983 -372.497974) (xy 300.18692 -372.581129)
			(xy 300.170869 -372.663117) (xy 300.14698 -372.743174) (xy 300.115475 -372.820551) (xy 300.07665 -372.894526)
			(xy 300.030867 -372.964409) (xy 299.978552 -373.029546) (xy 299.920195 -373.089331) (xy 299.856341 -373.143204)
			(xy 299.787585 -373.190663) (xy 299.714569 -373.231264) (xy 299.637976 -373.264629) (xy 299.55852 -373.290446)
			(xy 299.476944 -373.308474) (xy 299.394008 -373.318544) (xy 299.310488 -373.320563) (xy 299.227162 -373.314511)
			(xy 299.14481 -373.300446) (xy 299.0642 -373.278498) (xy 298.986084 -373.248872) (xy 298.911192 -373.211846)
			(xy 298.840224 -373.167765) (xy 298.773841 -373.117039) (xy 298.712664 -373.060144) (xy 298.657263 -372.99761)
			(xy 298.608157 -372.930021) (xy 298.565803 -372.858008) (xy 298.530597 -372.782243) (xy 298.502868 -372.703434)
			(xy 298.482875 -372.622317) (xy 298.470803 -372.539649) (xy 298.466767 -372.456202) (xy 297.720766 -372.456202)
			(xy 297.720262 -372.49855) (xy 297.712211 -372.582864) (xy 297.696182 -372.66603) (xy 297.672321 -372.747297)
			(xy 297.640842 -372.825927) (xy 297.602031 -372.901208) (xy 297.556241 -372.97246) (xy 297.503885 -373.039036)
			(xy 297.445437 -373.100334) (xy 297.381427 -373.155799) (xy 297.312435 -373.204928) (xy 297.239085 -373.247277)
			(xy 297.162042 -373.282461) (xy 297.082003 -373.310163) (xy 296.999694 -373.330131) (xy 296.915859 -373.342184)
			(xy 296.831258 -373.346215) (xy 296.746657 -373.342184) (xy 296.662822 -373.330131) (xy 296.580513 -373.310163)
			(xy 296.500474 -373.282461) (xy 296.423431 -373.247277) (xy 296.350081 -373.204928) (xy 296.281089 -373.155799)
			(xy 296.217079 -373.100334) (xy 296.158631 -373.039036) (xy 296.106275 -372.97246) (xy 296.060485 -372.901208)
			(xy 296.021674 -372.825927) (xy 295.990195 -372.747297) (xy 295.966334 -372.66603) (xy 295.950305 -372.582864)
			(xy 295.942254 -372.49855) (xy 294.860837 -372.49855) (xy 294.865081 -372.527903) (xy 294.865085 -372.58264)
			(xy 294.857261 -372.636816) (xy 294.84177 -372.689316) (xy 294.81893 -372.73906) (xy 294.78921 -372.785027)
			(xy 294.771572 -372.80596) (xy 294.762374 -372.817316) (xy 294.750196 -372.843864) (xy 294.746017 -372.872771)
			(xy 294.750179 -372.901681) (xy 294.762343 -372.928236) (xy 294.771572 -372.939564) (xy 294.789203 -372.960502)
			(xy 294.818917 -373.006473) (xy 294.841755 -373.056219) (xy 294.857248 -373.108718) (xy 294.865077 -373.162893)
			(xy 294.865552 -373.190262) (xy 294.864987 -373.21751) (xy 294.857236 -373.271453) (xy 294.841888 -373.323743)
			(xy 294.819255 -373.373317) (xy 294.789797 -373.419166) (xy 294.754113 -373.460355) (xy 294.712932 -373.496047)
			(xy 294.667089 -373.525515) (xy 294.61752 -373.54816) (xy 294.565233 -373.563519) (xy 294.511292 -373.571281)
			(xy 294.484044 -373.57177) (xy 294.455128 -373.571232) (xy 294.397957 -373.562508) (xy 294.342758 -373.545255)
			(xy 294.290796 -373.519867) (xy 294.243262 -373.486927) (xy 294.201244 -373.447188) (xy 294.183054 -373.424704)
			(xy 294.173157 -373.412899) (xy 294.147833 -373.39538) (xy 294.11844 -373.386204) (xy 294.087648 -373.386204)
			(xy 294.058255 -373.39538) (xy 294.032931 -373.412899) (xy 294.023034 -373.424704) (xy 294.004825 -373.447172)
			(xy 293.962809 -373.486908) (xy 293.915278 -373.519849) (xy 293.86332 -373.54524) (xy 293.808126 -373.562499)
			(xy 293.750959 -373.571233) (xy 293.722044 -373.57177) (xy 293.694791 -373.571304) (xy 293.640838 -373.563552)
			(xy 293.588538 -373.548199) (xy 293.538955 -373.525559) (xy 293.4931 -373.496092) (xy 293.451906 -373.460399)
			(xy 293.416211 -373.419205) (xy 293.386744 -373.37335) (xy 293.364103 -373.323768) (xy 293.34875 -373.271468)
			(xy 293.340997 -373.217515) (xy 293.340536 -373.190262) (xy 293.34103 -373.162893) (xy 293.348839 -373.108714)
			(xy 293.364322 -373.056211) (xy 293.387157 -373.006464) (xy 293.416877 -372.960496) (xy 293.434516 -372.939564)
			(xy 293.443788 -372.928264) (xy 293.455959 -372.901696) (xy 293.460124 -372.872771) (xy 293.455943 -372.843849)
			(xy 293.443757 -372.817288) (xy 293.434516 -372.80596) (xy 293.416839 -372.785057) (xy 293.387116 -372.739084)
			(xy 293.364274 -372.689333) (xy 293.348781 -372.636826) (xy 293.340956 -372.582644) (xy 293.34096 -372.527899)
			(xy 293.348793 -372.473718) (xy 293.364294 -372.421214) (xy 293.387144 -372.371466) (xy 293.416873 -372.325497)
			(xy 293.434516 -372.304564) (xy 293.443788 -372.293264) (xy 293.455959 -372.266696) (xy 293.460124 -372.237771)
			(xy 293.455943 -372.208849) (xy 293.443757 -372.182288) (xy 293.434516 -372.17096) (xy 293.416839 -372.150057)
			(xy 293.387116 -372.104084) (xy 293.364274 -372.054333) (xy 293.348781 -372.001826) (xy 293.340956 -371.947644)
			(xy 293.34096 -371.892899) (xy 293.348793 -371.838718) (xy 293.364294 -371.786214) (xy 293.387144 -371.736466)
			(xy 293.416873 -371.690497) (xy 293.434516 -371.669564) (xy 293.443788 -371.658264) (xy 293.455959 -371.631696)
			(xy 293.460124 -371.602771) (xy 293.455943 -371.573849) (xy 293.443757 -371.547288) (xy 293.434516 -371.53596)
			(xy 293.416894 -371.515014) (xy 293.387179 -371.469045) (xy 293.36434 -371.419301) (xy 293.348845 -371.366804)
			(xy 293.341012 -371.31263) (xy 293.340536 -371.285262) (xy 293.340768 -371.266207) (xy 293.344587 -371.228289)
			(xy 293.348156 -371.20957) (xy 293.3505 -371.196098) (xy 293.348653 -371.168823) (xy 293.339636 -371.143015)
			(xy 293.324096 -371.120524) (xy 293.303147 -371.102961) (xy 293.278289 -371.091584) (xy 293.251304 -371.087209)
			(xy 293.224125 -371.09015) (xy 293.21125 -371.094762) (xy 293.188788 -371.103308) (xy 293.142245 -371.11529)
			(xy 293.094564 -371.121325) (xy 293.070534 -371.121686) (xy 293.041618 -371.121149) (xy 292.984447 -371.112424)
			(xy 292.929249 -371.09517) (xy 292.877287 -371.069782) (xy 292.829752 -371.036842) (xy 292.787735 -370.997104)
			(xy 292.769544 -370.97462) (xy 292.759647 -370.962815) (xy 292.734323 -370.945296) (xy 292.70493 -370.93612)
			(xy 292.674138 -370.93612) (xy 292.644745 -370.945296) (xy 292.619421 -370.962815) (xy 292.609524 -370.97462)
			(xy 292.591324 -370.997096) (xy 292.549306 -371.036831) (xy 292.501773 -371.06977) (xy 292.449813 -371.09516)
			(xy 292.394617 -371.112418) (xy 292.337449 -371.121149) (xy 292.308534 -371.121686) (xy 292.281281 -371.121213)
			(xy 292.227329 -371.11346) (xy 292.17503 -371.098107) (xy 292.125449 -371.075467) (xy 292.079594 -371.046001)
			(xy 292.038401 -371.010308) (xy 292.002707 -370.969115) (xy 291.973239 -370.923262) (xy 291.950597 -370.873681)
			(xy 291.935242 -370.821382) (xy 291.927488 -370.767431) (xy 291.927026 -370.740178) (xy 290.295262 -370.740178)
			(xy 290.299383 -370.746591) (xy 290.322025 -370.796168) (xy 290.33738 -370.848463) (xy 290.345136 -370.902411)
			(xy 290.345622 -370.929662) (xy 290.345153 -370.957032) (xy 290.337339 -371.011212) (xy 290.321851 -371.063716)
			(xy 290.29901 -371.113463) (xy 290.269284 -371.159429) (xy 290.251642 -371.18036) (xy 290.242446 -371.191717)
			(xy 290.230272 -371.218265) (xy 290.226094 -371.247171) (xy 290.230255 -371.27608) (xy 290.242415 -371.302635)
			(xy 290.251642 -371.313964) (xy 290.269247 -371.334926) (xy 290.298975 -371.380888) (xy 290.321825 -371.430629)
			(xy 290.337325 -371.483127) (xy 290.345158 -371.537302) (xy 290.345162 -371.592041) (xy 290.337338 -371.646217)
			(xy 290.321845 -371.698717) (xy 290.299003 -371.748462) (xy 290.269281 -371.794428) (xy 290.251642 -371.81536)
			(xy 290.242446 -371.826717) (xy 290.230272 -371.853265) (xy 290.226094 -371.882171) (xy 290.230255 -371.91108)
			(xy 290.242415 -371.937635) (xy 290.251642 -371.948964) (xy 290.269285 -371.969893) (xy 290.298995 -372.015867)
			(xy 290.321829 -372.065616) (xy 290.33732 -372.118117) (xy 290.345148 -372.172293) (xy 290.345622 -372.199662)
			(xy 290.345106 -372.228579) (xy 290.336381 -372.285752) (xy 290.319124 -372.340952) (xy 290.293732 -372.392915)
			(xy 290.260787 -372.440448) (xy 290.221043 -372.482463) (xy 290.198556 -372.500652) (xy 290.186785 -372.510589)
			(xy 290.169259 -372.535899) (xy 290.160075 -372.565284) (xy 290.160068 -372.59607) (xy 290.169238 -372.625458)
			(xy 290.186752 -372.650777) (xy 290.198556 -372.660672) (xy 290.219301 -372.677471) (xy 290.256429 -372.715819)
			(xy 290.287849 -372.758969) (xy 290.312948 -372.806077) (xy 290.331235 -372.856224) (xy 290.342354 -372.90843)
			(xy 290.346086 -372.961677) (xy 290.34236 -373.014924) (xy 290.331248 -373.067131) (xy 290.312967 -373.11728)
			(xy 290.287874 -373.164392) (xy 290.256459 -373.207545) (xy 290.219335 -373.245898) (xy 290.198556 -373.262652)
			(xy 290.186785 -373.272589) (xy 290.169259 -373.297899) (xy 290.160075 -373.327284) (xy 290.160068 -373.35807)
			(xy 290.169238 -373.387458) (xy 290.186752 -373.412777) (xy 290.198556 -373.422672) (xy 290.221017 -373.44089)
			(xy 290.260756 -373.482903) (xy 290.293698 -373.530432) (xy 290.319091 -373.582388) (xy 290.336352 -373.637581)
			(xy 290.345085 -373.694747) (xy 290.345622 -373.723662) (xy 290.345136 -373.750913) (xy 290.33738 -373.804861)
			(xy 290.322025 -373.857156) (xy 290.299383 -373.906733) (xy 290.269917 -373.952583) (xy 290.234226 -373.993774)
			(xy 290.193035 -374.029465) (xy 290.147185 -374.058931) (xy 290.097608 -374.081573) (xy 290.045313 -374.096928)
			(xy 289.991365 -374.104684) (xy 289.936863 -374.104684) (xy 289.882915 -374.096928) (xy 289.83062 -374.081573)
			(xy 289.781043 -374.058931) (xy 289.735193 -374.029465) (xy 289.694002 -373.993774) (xy 289.658311 -373.952583)
			(xy 289.628845 -373.906733) (xy 289.606203 -373.857156) (xy 289.590848 -373.804861) (xy 289.583092 -373.750913)
			(xy 289.582606 -373.723662) (xy 289.583167 -373.694747) (xy 289.591886 -373.637577) (xy 289.609136 -373.582379)
			(xy 289.63452 -373.530417) (xy 289.667456 -373.482882) (xy 289.70719 -373.440863) (xy 289.729672 -373.422672)
			(xy 289.741517 -373.412817) (xy 289.759036 -373.387482) (xy 289.768209 -373.358078) (xy 289.768202 -373.327276)
			(xy 289.759016 -373.297875) (xy 289.741484 -373.272549) (xy 289.729672 -373.262652) (xy 289.708851 -373.245944)
			(xy 289.671719 -373.207586) (xy 289.640296 -373.164426) (xy 289.615197 -373.117307) (xy 289.596912 -373.06715)
			(xy 289.585797 -373.014933) (xy 289.58207 -372.961677) (xy 288.375806 -372.961677) (xy 288.377586 -372.987077)
			(xy 288.37386 -373.040324) (xy 288.362748 -373.092531) (xy 288.344467 -373.14268) (xy 288.319374 -373.189792)
			(xy 288.287959 -373.232945) (xy 288.250835 -373.271298) (xy 288.230056 -373.288052) (xy 288.218285 -373.297989)
			(xy 288.200759 -373.323299) (xy 288.191575 -373.352684) (xy 288.191568 -373.38347) (xy 288.200738 -373.412858)
			(xy 288.218252 -373.438177) (xy 288.230056 -373.448072) (xy 288.252517 -373.46629) (xy 288.292256 -373.508303)
			(xy 288.325198 -373.555832) (xy 288.350591 -373.607788) (xy 288.367852 -373.662981) (xy 288.376585 -373.720147)
			(xy 288.377122 -373.749062) (xy 288.376609 -373.776313) (xy 288.368858 -373.830262) (xy 288.353507 -373.882558)
			(xy 288.33087 -373.932137) (xy 288.301408 -373.977989) (xy 288.265719 -374.019182) (xy 288.224531 -374.054876)
			(xy 288.178683 -374.084345) (xy 288.129107 -374.106989) (xy 288.076813 -374.122347) (xy 288.022865 -374.130106)
			(xy 287.995614 -374.13057) (xy 287.966697 -374.130053) (xy 287.909525 -374.121325) (xy 287.854326 -374.104068)
			(xy 287.802364 -374.078676) (xy 287.75483 -374.045732) (xy 287.712814 -374.00599) (xy 287.694624 -373.983504)
			(xy 287.684727 -373.971699) (xy 287.659403 -373.95418) (xy 287.63001 -373.945004) (xy 287.599218 -373.945004)
			(xy 287.569825 -373.95418) (xy 287.544501 -373.971699) (xy 287.534604 -373.983504) (xy 287.516412 -374.005986)
			(xy 287.474392 -374.045721) (xy 287.426857 -374.07866) (xy 287.374896 -374.104049) (xy 287.319699 -374.121306)
			(xy 287.26253 -374.130035) (xy 287.233614 -374.13057) (xy 287.206244 -374.130103) (xy 287.152064 -374.122287)
			(xy 287.099561 -374.106798) (xy 287.049814 -374.083956) (xy 287.003847 -374.054232) (xy 286.982916 -374.03659)
			(xy 286.971588 -374.027354) (xy 286.945031 -374.015178) (xy 286.916114 -374.011005) (xy 286.887197 -374.015178)
			(xy 286.86064 -374.027354) (xy 286.849312 -374.03659) (xy 286.828385 -374.054235) (xy 286.782411 -374.083947)
			(xy 286.732662 -374.106782) (xy 286.68016 -374.122271) (xy 286.625984 -374.130097) (xy 286.598614 -374.13057)
			(xy 286.57136 -374.130132) (xy 286.517406 -374.122375) (xy 286.465105 -374.107019) (xy 286.415523 -374.084376)
			(xy 286.369668 -374.054906) (xy 286.328474 -374.019209) (xy 286.29278 -373.978013) (xy 286.263313 -373.932156)
			(xy 286.240672 -373.882572) (xy 286.225319 -373.830271) (xy 286.217567 -373.776316) (xy 286.217106 -373.749062)
			(xy 286.217667 -373.720147) (xy 286.226386 -373.662977) (xy 286.243636 -373.607779) (xy 286.26902 -373.555817)
			(xy 286.301956 -373.508282) (xy 286.34169 -373.466263) (xy 286.364172 -373.448072) (xy 286.376017 -373.438217)
			(xy 286.393536 -373.412882) (xy 286.402709 -373.383478) (xy 286.402702 -373.352676) (xy 286.393516 -373.323275)
			(xy 286.375984 -373.297949) (xy 286.364172 -373.288052) (xy 286.343351 -373.271344) (xy 286.306219 -373.232986)
			(xy 286.274796 -373.189826) (xy 286.249697 -373.142707) (xy 286.231412 -373.09255) (xy 286.220297 -373.040333)
			(xy 286.21657 -372.987077) (xy 284.432756 -372.987077) (xy 284.432756 -373.077486) (xy 288.585402 -377.230132)
			(xy 305.859434 -377.230132) (xy 309.745888 -373.343678) (xy 309.763995 -373.326452) (xy 309.805554 -373.29871)
			(xy 309.851726 -373.279603) (xy 309.900736 -373.269865) (xy 309.92572 -373.269256) (xy 347.678248 -373.269256)
			(xy 352.914712 -368.032538) (xy 352.914712 -367.876582) (xy 352.883724 -367.84534) (xy 352.862388 -367.84534)
			(xy 352.835112 -367.844898) (xy 352.781109 -367.837198) (xy 352.728752 -367.821885) (xy 352.67911 -367.799272)
			(xy 352.633195 -367.769818) (xy 352.591942 -367.734126) (xy 352.556194 -367.692922) (xy 352.526678 -367.647047)
			(xy 352.503997 -367.597436) (xy 352.488612 -367.5451) (xy 352.480839 -367.491107) (xy 352.480372 -367.463832)
			(xy 352.480885 -367.436581) (xy 352.488637 -367.382633) (xy 352.503988 -367.330337) (xy 352.526625 -367.280758)
			(xy 352.556088 -367.234906) (xy 352.591777 -367.193714) (xy 352.632964 -367.158019) (xy 352.678813 -367.12855)
			(xy 352.728388 -367.105906) (xy 352.780682 -367.090548) (xy 352.834629 -367.082789) (xy 352.86188 -367.082324)
			(xy 352.888261 -367.082716) (xy 352.940522 -367.08998) (xy 352.991284 -367.104372) (xy 353.03958 -367.125618)
			(xy 353.084489 -367.153313) (xy 353.125157 -367.18693) (xy 353.160807 -367.225826) (xy 353.190761 -367.269262)
			(xy 353.203002 -367.292636) (xy 353.209704 -367.304995) (xy 353.228679 -367.325723) (xy 353.252593 -367.340485)
			(xy 353.279629 -367.348157) (xy 353.307731 -367.348157) (xy 353.334767 -367.340485) (xy 353.358681 -367.325723)
			(xy 353.377656 -367.304995) (xy 353.384358 -367.292636) (xy 353.396587 -367.269259) (xy 353.426553 -367.225837)
			(xy 353.462212 -367.186954) (xy 353.502883 -367.15335) (xy 353.547794 -367.125665) (xy 353.596088 -367.104425)
			(xy 353.646845 -367.090035) (xy 353.699101 -367.08277) (xy 353.72548 -367.082324) (xy 353.752734 -367.082774)
			(xy 353.806687 -367.090529) (xy 353.858987 -367.105884) (xy 353.908569 -367.128527) (xy 353.954424 -367.157996)
			(xy 353.995618 -367.193691) (xy 354.031312 -367.234886) (xy 354.060779 -367.280741) (xy 354.08342 -367.330324)
			(xy 354.098773 -367.382625) (xy 354.106527 -367.436578) (xy 354.106988 -367.463832) (xy 354.106513 -367.490566)
			(xy 354.099056 -367.54351) (xy 354.084279 -367.594894) (xy 354.062471 -367.643712) (xy 354.03406 -367.689005)
			(xy 353.999602 -367.729888) (xy 353.979988 -367.748058) (xy 353.979988 -368.120676) (xy 353.979334 -368.145671)
			(xy 353.969535 -368.194693) (xy 353.950366 -368.240863) (xy 353.922564 -368.282411) (xy 353.905312 -368.300508)
			(xy 348.121478 -374.084342) (xy 348.103389 -374.101587) (xy 348.061823 -374.129325) (xy 348.015646 -374.148426)
			(xy 347.966632 -374.158158) (xy 347.941646 -374.158764) (xy 310.189372 -374.158764) (xy 306.302918 -378.045218)
			(xy 306.284808 -378.06244) (xy 306.24325 -378.090183) (xy 306.197079 -378.109291) (xy 306.14807 -378.11903)
			(xy 306.123086 -378.11964) (xy 288.322004 -378.11964) (xy 288.297021 -378.119011) (xy 288.248014 -378.109273)
			(xy 288.201844 -378.090171) (xy 288.160283 -378.062437) (xy 288.142172 -378.045218) (xy 283.61767 -373.520716)
			(xy 283.600445 -373.502609) (xy 283.572703 -373.461049) (xy 283.553596 -373.414878) (xy 283.543857 -373.365868)
			(xy 283.543248 -373.340884) (xy 282.961588 -373.340884) (xy 282.961588 -374.747536) (xy 287.988756 -379.774704)
			(xy 419.013386 -379.774704)
		)
		(stroke
			(width 0)
			(type solid)
		)
		(fill yes)
		(layer "In11.Cu")
		(net "GND")
	)
	(gr_line
		(start 127.454406 -219.134436)
		(end 127.454406 -201.862436)
		(stroke
			(width 15.113)
			(type default)
		)
		(layer "In11.Cu")
	)
	(gr_line
		(start 127.454406 -201.862436)
		(end 149.679406 -179.637436)
		(stroke
			(width 15.113)
			(type default)
		)
		(layer "In11.Cu")
	)
	(gr_line
		(start 149.679406 -179.637436)
		(end 217.243406 -179.637436)
		(stroke
			(width 15.113)
			(type default)
		)
		(layer "In11.Cu")
	)
	(gr_line
		(start 217.243406 -179.637436)
		(end 225.371406 -187.765436)
		(stroke
			(width 15.113)
			(type default)
		)
		(layer "In11.Cu")
	)
	(gr_line
		(start 225.371406 -351.849436)
		(end 151.203406 -430.843436)
		(stroke
			(width 15.113)
			(type default)
		)
		(layer "In11.Cu")
	)
	(gr_line
		(start 225.371406 -187.765436)
		(end 225.371406 -351.849436)
		(stroke
			(width 15.113)
			(type default)
		)
		(layer "In11.Cu")
	)
	(gr_line
		(start 0 -77.671676)
		(end 0 -13.780008)
		(stroke
			(width 0.05)
			(type default)
		)
		(layer "Edge.Cuts")
	)
	(gr_arc
		(start 0 -77.671676)
		(mid 0.152237 -78.436936)
		(end 0.585724 -79.085694)
		(stroke
			(width 0.05)
			(type default)
		)
		(layer "Edge.Cuts")
	)
	(gr_line
		(start 1.414272 -79.914242)
		(end 0.585724 -79.085694)
		(stroke
			(width 0.05)
			(type default)
		)
		(layer "Edge.Cuts")
	)
	(gr_line
		(start 1.999996 -403.371558)
		(end 1.999996 -81.328514)
		(stroke
			(width 0.05)
			(type default)
		)
		(layer "Edge.Cuts")
	)
	(gr_arc
		(start 1.999996 -403.371558)
		(mid 2.152159 -404.136965)
		(end 2.58572 -404.78583)
		(stroke
			(width 0.05)
			(type default)
		)
		(layer "Edge.Cuts")
	)
	(gr_arc
		(start 1.999996 -81.328514)
		(mid 1.847755 -80.563149)
		(end 1.414272 -79.914242)
		(stroke
			(width 0.05)
			(type default)
		)
		(layer "Edge.Cuts")
	)
	(gr_arc
		(start 1.999996 -11.780012)
		(mid 0.585785 -12.365797)
		(end 0 -13.780008)
		(stroke
			(width 0.05)
			(type default)
		)
		(layer "Edge.Cuts")
	)
	(gr_line
		(start 1.999996 -11.780012)
		(end 11.102086 -11.780012)
		(stroke
			(width 0.05)
			(type default)
		)
		(layer "Edge.Cuts")
	)
	(gr_line
		(start 5.914136 -408.114246)
		(end 2.58572 -404.78583)
		(stroke
			(width 0.05)
			(type default)
		)
		(layer "Edge.Cuts")
	)
	(gr_line
		(start 6.500114 -439.989976)
		(end 6.500114 -409.528518)
		(stroke
			(width 0.05)
			(type default)
		)
		(layer "Edge.Cuts")
	)
	(gr_arc
		(start 6.500114 -439.989976)
		(mid 7.085891 -441.404199)
		(end 8.50011 -441.989972)
		(stroke
			(width 0.05)
			(type default)
		)
		(layer "Edge.Cuts")
	)
	(gr_arc
		(start 6.500114 -409.528518)
		(mid 6.347771 -408.763109)
		(end 5.914136 -408.114246)
		(stroke
			(width 0.05)
			(type default)
		)
		(layer "Edge.Cuts")
	)
	(gr_arc
		(start 11.102086 -11.780012)
		(mid 12.516297 -11.194227)
		(end 13.102082 -9.780016)
		(stroke
			(width 0.05)
			(type default)
		)
		(layer "Edge.Cuts")
	)
	(gr_line
		(start 13.102082 -9.780016)
		(end 13.102082 -0.500126)
		(stroke
			(width 0.05)
			(type default)
		)
		(layer "Edge.Cuts")
	)
	(gr_arc
		(start 13.601954 0)
		(mid 13.248421 -0.146513)
		(end 13.102082 -0.500126)
		(stroke
			(width 0.05)
			(type default)
		)
		(layer "Edge.Cuts")
	)
	(gr_line
		(start 13.601954 0)
		(end 81.202022 0)
		(stroke
			(width 0.05)
			(type default)
		)
		(layer "Edge.Cuts")
	)
	(gr_arc
		(start 81.701894 -9.780016)
		(mid 82.287679 -11.194227)
		(end 83.70189 -11.780012)
		(stroke
			(width 0.05)
			(type default)
		)
		(layer "Edge.Cuts")
	)
	(gr_arc
		(start 81.701894 -0.500126)
		(mid 81.555566 -0.146509)
		(end 81.202022 0)
		(stroke
			(width 0.05)
			(type default)
		)
		(layer "Edge.Cuts")
	)
	(gr_line
		(start 81.701894 -0.500126)
		(end 81.701894 -9.780016)
		(stroke
			(width 0.05)
			(type default)
		)
		(layer "Edge.Cuts")
	)
	(gr_line
		(start 83.70189 -11.780012)
		(end 124.102114 -11.780012)
		(stroke
			(width 0.05)
			(type default)
		)
		(layer "Edge.Cuts")
	)
	(gr_arc
		(start 124.102114 -11.780012)
		(mid 125.516325 -11.194227)
		(end 126.10211 -9.780016)
		(stroke
			(width 0.05)
			(type default)
		)
		(layer "Edge.Cuts")
	)
	(gr_line
		(start 126.10211 -9.780016)
		(end 126.10211 -5.780024)
		(stroke
			(width 0.05)
			(type default)
		)
		(layer "Edge.Cuts")
	)
	(gr_arc
		(start 126.601982 -5.279898)
		(mid 126.24843 -5.426401)
		(end 126.10211 -5.780024)
		(stroke
			(width 0.05)
			(type default)
		)
		(layer "Edge.Cuts")
	)
	(gr_line
		(start 126.601982 -5.279898)
		(end 194.20205 -5.279898)
		(stroke
			(width 0.05)
			(type default)
		)
		(layer "Edge.Cuts")
	)
	(gr_line
		(start 194.508628 -441.989972)
		(end 8.50011 -441.989972)
		(stroke
			(width 0.05)
			(type default)
		)
		(layer "Edge.Cuts")
	)
	(gr_arc
		(start 194.508628 -441.989972)
		(mid 194.862073 -441.843553)
		(end 195.0085 -441.4901)
		(stroke
			(width 0.05)
			(type default)
		)
		(layer "Edge.Cuts")
	)
	(gr_arc
		(start 194.701922 -9.780016)
		(mid 195.287707 -11.194227)
		(end 196.701918 -11.780012)
		(stroke
			(width 0.05)
			(type default)
		)
		(layer "Edge.Cuts")
	)
	(gr_arc
		(start 194.701922 -5.780024)
		(mid 194.555589 -5.426434)
		(end 194.20205 -5.279898)
		(stroke
			(width 0.05)
			(type default)
		)
		(layer "Edge.Cuts")
	)
	(gr_line
		(start 194.701922 -5.780024)
		(end 194.701922 -9.780016)
		(stroke
			(width 0.05)
			(type default)
		)
		(layer "Edge.Cuts")
	)
	(gr_line
		(start 195.0085 -441.110116)
		(end 195.0085 -441.4901)
		(stroke
			(width 0.05)
			(type default)
		)
		(layer "Edge.Cuts")
	)
	(gr_arc
		(start 195.50507 -440.669934)
		(mid 195.173295 -440.795826)
		(end 195.0085 -441.110116)
		(stroke
			(width 0.05)
			(type default)
		)
		(layer "Edge.Cuts")
	)
	(gr_line
		(start 196.701918 -11.780012)
		(end 221.30004 -11.780012)
		(stroke
			(width 0.05)
			(type default)
		)
		(layer "Edge.Cuts")
	)
	(gr_arc
		(start 223.300036 -33.275016)
		(mid 223.885821 -34.689227)
		(end 225.300032 -35.275012)
		(stroke
			(width 0.05)
			(type default)
		)
		(layer "Edge.Cuts")
	)
	(gr_arc
		(start 223.300036 -13.780008)
		(mid 222.714256 -12.365778)
		(end 221.30004 -11.780012)
		(stroke
			(width 0.05)
			(type default)
		)
		(layer "Edge.Cuts")
	)
	(gr_line
		(start 223.300036 -13.780008)
		(end 223.300036 -33.275016)
		(stroke
			(width 0.05)
			(type default)
		)
		(layer "Edge.Cuts")
	)
	(gr_line
		(start 225.300032 -35.275012)
		(end 256.800096 -35.275012)
		(stroke
			(width 0.05)
			(type default)
		)
		(layer "Edge.Cuts")
	)
	(gr_arc
		(start 256.800096 -35.275012)
		(mid 258.214307 -34.689227)
		(end 258.800092 -33.275016)
		(stroke
			(width 0.05)
			(type default)
		)
		(layer "Edge.Cuts")
	)
	(gr_line
		(start 258.800092 -33.275016)
		(end 258.800092 -13.780008)
		(stroke
			(width 0.05)
			(type default)
		)
		(layer "Edge.Cuts")
	)
	(gr_arc
		(start 260.800088 -11.780012)
		(mid 259.385888 -12.365802)
		(end 258.800092 -13.780008)
		(stroke
			(width 0.05)
			(type default)
		)
		(layer "Edge.Cuts")
	)
	(gr_line
		(start 260.800088 -11.780012)
		(end 385.601972 -11.780012)
		(stroke
			(width 0.05)
			(type default)
		)
		(layer "Edge.Cuts")
	)
	(gr_line
		(start 276.314916 -440.669934)
		(end 195.50507 -440.669934)
		(stroke
			(width 0.05)
			(type default)
		)
		(layer "Edge.Cuts")
	)
	(gr_line
		(start 276.811486 -441.4901)
		(end 276.811486 -441.110116)
		(stroke
			(width 0.05)
			(type default)
		)
		(layer "Edge.Cuts")
	)
	(gr_arc
		(start 276.811486 -441.4901)
		(mid 276.957893 -441.843578)
		(end 277.311358 -441.989972)
		(stroke
			(width 0.05)
			(type default)
		)
		(layer "Edge.Cuts")
	)
	(gr_arc
		(start 276.811486 -441.110116)
		(mid 276.646724 -440.795789)
		(end 276.314916 -440.669934)
		(stroke
			(width 0.05)
			(type default)
		)
		(layer "Edge.Cuts")
	)
	(gr_arc
		(start 385.601972 -11.780012)
		(mid 387.016183 -11.194227)
		(end 387.601968 -9.780016)
		(stroke
			(width 0.05)
			(type default)
		)
		(layer "Edge.Cuts")
	)
	(gr_line
		(start 387.601968 -9.780016)
		(end 387.601968 -0.500126)
		(stroke
			(width 0.05)
			(type default)
		)
		(layer "Edge.Cuts")
	)
	(gr_arc
		(start 388.102094 0)
		(mid 387.748465 -0.146487)
		(end 387.601968 -0.500126)
		(stroke
			(width 0.05)
			(type default)
		)
		(layer "Edge.Cuts")
	)
	(gr_line
		(start 388.102094 0)
		(end 455.701908 0)
		(stroke
			(width 0.05)
			(type default)
		)
		(layer "Edge.Cuts")
	)
	(gr_arc
		(start 456.202034 -9.780016)
		(mid 456.787819 -11.194227)
		(end 458.20203 -11.780012)
		(stroke
			(width 0.05)
			(type default)
		)
		(layer "Edge.Cuts")
	)
	(gr_arc
		(start 456.202034 -0.500126)
		(mid 456.05556 -0.146464)
		(end 455.701908 0)
		(stroke
			(width 0.05)
			(type default)
		)
		(layer "Edge.Cuts")
	)
	(gr_line
		(start 456.202034 -0.500126)
		(end 456.202034 -9.780016)
		(stroke
			(width 0.05)
			(type default)
		)
		(layer "Edge.Cuts")
	)
	(gr_line
		(start 458.20203 -11.780012)
		(end 469.799924 -11.780012)
		(stroke
			(width 0.05)
			(type default)
		)
		(layer "Edge.Cuts")
	)
	(gr_line
		(start 463.300064 -441.989972)
		(end 277.311358 -441.989972)
		(stroke
			(width 0.05)
			(type default)
		)
		(layer "Edge.Cuts")
	)
	(gr_arc
		(start 463.300064 -441.989972)
		(mid 464.71429 -441.404198)
		(end 465.30006 -439.989976)
		(stroke
			(width 0.05)
			(type default)
		)
		(layer "Edge.Cuts")
	)
	(gr_line
		(start 465.30006 -409.528518)
		(end 465.30006 -439.989976)
		(stroke
			(width 0.05)
			(type default)
		)
		(layer "Edge.Cuts")
	)
	(gr_arc
		(start 465.885784 -408.114246)
		(mid 465.452221 -408.76312)
		(end 465.30006 -409.528518)
		(stroke
			(width 0.05)
			(type default)
		)
		(layer "Edge.Cuts")
	)
	(gr_line
		(start 467.71433 -406.2857)
		(end 465.885784 -408.114246)
		(stroke
			(width 0.05)
			(type default)
		)
		(layer "Edge.Cuts")
	)
	(gr_arc
		(start 467.71433 -406.2857)
		(mid 468.147828 -405.636947)
		(end 468.300054 -404.871682)
		(stroke
			(width 0.05)
			(type default)
		)
		(layer "Edge.Cuts")
	)
	(gr_line
		(start 468.300054 -82.828384)
		(end 468.300054 -404.871682)
		(stroke
			(width 0.05)
			(type default)
		)
		(layer "Edge.Cuts")
	)
	(gr_arc
		(start 468.885778 -81.414112)
		(mid 468.452215 -82.062986)
		(end 468.300054 -82.828384)
		(stroke
			(width 0.05)
			(type default)
		)
		(layer "Edge.Cuts")
	)
	(gr_line
		(start 471.214196 -79.085694)
		(end 468.885778 -81.414112)
		(stroke
			(width 0.05)
			(type default)
		)
		(layer "Edge.Cuts")
	)
	(gr_arc
		(start 471.214196 -79.085694)
		(mid 471.6477 -78.436942)
		(end 471.79992 -77.671676)
		(stroke
			(width 0.05)
			(type default)
		)
		(layer "Edge.Cuts")
	)
	(gr_arc
		(start 471.79992 -13.780008)
		(mid 471.214139 -12.365784)
		(end 469.799924 -11.780012)
		(stroke
			(width 0.05)
			(type default)
		)
		(layer "Edge.Cuts")
	)
	(gr_line
		(start 471.79992 -13.780008)
		(end 471.79992 -77.671676)
		(stroke
			(width 0.05)
			(type default)
		)
		(layer "Edge.Cuts")
	)
	(gr_poly
		(pts
			(xy 230.38054 -434.93182)
			(arc
				(start 230.38054 -423.45356)
				(mid 230.404693 -423.332044)
				(end 230.473504 -423.229024)
			)
			(arc
				(start 232.983024 -420.719504)
				(mid 233.086056 -420.650723)
				(end 233.20756 -420.62654)
			)
			(xy 270.36522 -420.62654)
			(arc
				(start 275.456396 -415.535364)
				(mid 275.559428 -415.466583)
				(end 275.680932 -415.4424)
			)
			(xy 279.79624 -415.4424) (xy 280.19756 -415.04108) (xy 280.19756 -408.29992) (xy 279.96896 -408.07132)
			(xy 239.84458 -408.07132)
			(arc
				(start 233.163364 -414.752536)
				(mid 233.060332 -414.821317)
				(end 232.938828 -414.8455)
			)
			(xy 207.34528 -414.8455) (xy 206.49184 -415.69894) (xy 206.49184 -435.39156) (xy 207.63484 -436.53456)
			(xy 228.7778 -436.53456)
		)
		(stroke
			(width 0)
			(type solid)
		)
		(fill yes)
		(layer "In12.Cu")
		(net "P12V_PSU")
	)
	(gr_poly
		(pts
			(xy 531.7998 -462.520284) (xy 531.855607 -462.519775) (xy 531.96691 -462.511434) (xy 532.077278 -462.494798)
			(xy 532.186094 -462.469962) (xy 532.29275 -462.437062) (xy 532.396649 -462.396285) (xy 532.49721 -462.347857)
			(xy 532.593871 -462.292049) (xy 532.686092 -462.229174) (xy 532.773355 -462.159583) (xy 532.855174 -462.083666)
			(xy 532.931091 -462.001846) (xy 533.000681 -461.914582) (xy 533.063556 -461.822361) (xy 533.119362 -461.7257)
			(xy 533.16779 -461.625138) (xy 533.208566 -461.521239) (xy 533.241465 -461.414583) (xy 533.266301 -461.305766)
			(xy 533.282935 -461.195398) (xy 533.291275 -461.084095) (xy 533.291796 -461.028288) (xy 533.291796 -455.0283)
			(xy 533.291274 -454.972493) (xy 533.282933 -454.861191) (xy 533.266298 -454.750824) (xy 533.241462 -454.642008)
			(xy 533.208563 -454.535353) (xy 533.167786 -454.431454) (xy 533.119358 -454.330893) (xy 533.063551 -454.234233)
			(xy 533.000677 -454.142013) (xy 532.931086 -454.054749) (xy 532.85517 -453.97293) (xy 532.773351 -453.897014)
			(xy 532.686087 -453.827423) (xy 532.593867 -453.764549) (xy 532.497207 -453.708742) (xy 532.396646 -453.660314)
			(xy 532.292747 -453.619537) (xy 532.186092 -453.586638) (xy 532.077276 -453.561802) (xy 531.966909 -453.545167)
			(xy 531.855607 -453.536826) (xy 531.7998 -453.536304) (xy 516.019796 -453.536304) (xy 515.949442 -453.535811)
			(xy 515.808956 -453.527921) (xy 515.669133 -453.512166) (xy 515.530414 -453.488597) (xy 515.393234 -453.457286)
			(xy 515.258026 -453.418334) (xy 515.125215 -453.371861) (xy 514.995218 -453.318014) (xy 514.868445 -453.256963)
			(xy 514.745294 -453.188901) (xy 514.626154 -453.11404) (xy 514.511398 -453.032616) (xy 514.401389 -452.944887)
			(xy 514.296471 -452.851127) (xy 514.196976 -452.751632) (xy 514.103216 -452.646714) (xy 514.015486 -452.536705)
			(xy 513.934063 -452.421949) (xy 513.859201 -452.302809) (xy 513.791138 -452.179659) (xy 513.730087 -452.052886)
			(xy 513.676241 -451.922889) (xy 513.629768 -451.790078) (xy 513.590815 -451.65487) (xy 513.559504 -451.51769)
			(xy 513.535934 -451.378971) (xy 513.520179 -451.239148) (xy 513.512289 -451.098662) (xy 513.5118 -451.028308)
			(xy 513.5118 -312.408316) (xy 513.512284 -312.337962) (xy 513.520173 -312.197474) (xy 513.535926 -312.05765)
			(xy 513.559495 -311.91893) (xy 513.590805 -311.781749) (xy 513.629757 -311.646539) (xy 513.676229 -311.513726)
			(xy 513.730076 -311.383728) (xy 513.791126 -311.256954) (xy 513.859189 -311.133802) (xy 513.93405 -311.01466)
			(xy 514.015474 -310.899903) (xy 514.103203 -310.789893) (xy 514.196964 -310.684974) (xy 514.296459 -310.585477)
			(xy 514.401377 -310.491716) (xy 514.511387 -310.403986) (xy 514.626144 -310.322561) (xy 514.745285 -310.247699)
			(xy 514.868436 -310.179635) (xy 514.99521 -310.118584) (xy 515.125208 -310.064737) (xy 515.25802 -310.018263)
			(xy 515.393229 -309.97931) (xy 515.53041 -309.947999) (xy 515.669131 -309.924429) (xy 515.808954 -309.908674)
			(xy 515.949442 -309.900784) (xy 516.019796 -309.90032) (xy 531.7998 -309.90032) (xy 531.855607 -309.899798)
			(xy 531.96691 -309.891457) (xy 532.077278 -309.874822) (xy 532.186094 -309.849986) (xy 532.292751 -309.817087)
			(xy 532.39665 -309.77631) (xy 532.497211 -309.727883) (xy 532.593873 -309.672076) (xy 532.686094 -309.609202)
			(xy 532.773358 -309.539612) (xy 532.855178 -309.463695) (xy 532.931096 -309.381876) (xy 533.000687 -309.294613)
			(xy 533.063563 -309.202393) (xy 533.119372 -309.105733) (xy 533.167801 -309.005172) (xy 533.208579 -308.901273)
			(xy 533.24148 -308.794618) (xy 533.266318 -308.685802) (xy 533.282955 -308.575434) (xy 533.291297 -308.464131)
			(xy 533.291796 -308.408324) (xy 533.291796 10.40003) (xy 533.291273 10.455836) (xy 533.28293 10.567137)
			(xy 533.266293 10.677502) (xy 533.241455 10.786316) (xy 533.208555 10.89297) (xy 533.167777 10.996866)
			(xy 533.119348 11.097425) (xy 533.063541 11.194084) (xy 533.000666 11.286302) (xy 532.931076 11.373563)
			(xy 532.855159 11.45538) (xy 532.77334 11.531295) (xy 532.686078 11.600884) (xy 532.593858 11.663757)
			(xy 532.497199 11.719562) (xy 532.396639 11.767989) (xy 532.292741 11.808765) (xy 532.186087 11.841663)
			(xy 532.077273 11.866499) (xy 531.966907 11.883134) (xy 531.855606 11.891474) (xy 531.7998 11.892026)
			(xy 475.799912 11.892026) (xy 475.744104 11.891505) (xy 475.632801 11.883165) (xy 475.522432 11.86653)
			(xy 475.413615 11.841695) (xy 475.306958 11.808796) (xy 475.203057 11.76802) (xy 475.102495 11.719593)
			(xy 475.005832 11.663786) (xy 474.91361 11.600912) (xy 474.826345 11.531322) (xy 474.744524 11.455406)
			(xy 474.668605 11.373587) (xy 474.599013 11.286323) (xy 474.536136 11.194103) (xy 474.480327 11.097442)
			(xy 474.431897 10.996881) (xy 474.391117 10.892982) (xy 474.358216 10.786326) (xy 474.333378 10.677509)
			(xy 474.31674 10.567141) (xy 474.308397 10.455838) (xy 474.307916 10.40003) (xy 474.307916 7.335466)
			(xy 526.704041 7.335466) (xy 526.704041 7.464606) (xy 526.711991 7.593501) (xy 526.727861 7.721661)
			(xy 526.75159 7.848602) (xy 526.783089 7.973841) (xy 526.822238 8.096904) (xy 526.868889 8.217323)
			(xy 526.922864 8.334642) (xy 526.983959 8.448416) (xy 527.051942 8.558213) (xy 527.126556 8.663616)
			(xy 527.207517 8.764226) (xy 527.294517 8.859661) (xy 527.387228 8.94956) (xy 527.485298 9.033581)
			(xy 527.588353 9.111405) (xy 527.696004 9.182737) (xy 527.807843 9.247307) (xy 527.923444 9.304869)
			(xy 528.042369 9.355206) (xy 528.164168 9.398126) (xy 528.288378 9.433467) (xy 528.414527 9.461094)
			(xy 528.542139 9.480903) (xy 528.670728 9.492819) (xy 528.799806 9.496796) (xy 528.928884 9.492819)
			(xy 529.057473 9.480903) (xy 529.185085 9.461094) (xy 529.311234 9.433467) (xy 529.435444 9.398126)
			(xy 529.557243 9.355206) (xy 529.676168 9.304869) (xy 529.791769 9.247307) (xy 529.903608 9.182737)
			(xy 530.011259 9.111405) (xy 530.114314 9.033581) (xy 530.212384 8.94956) (xy 530.305095 8.859661)
			(xy 530.392095 8.764226) (xy 530.473056 8.663616) (xy 530.54767 8.558213) (xy 530.615653 8.448416)
			(xy 530.676748 8.334642) (xy 530.730723 8.217323) (xy 530.777374 8.096904) (xy 530.816523 7.973841)
			(xy 530.848022 7.848602) (xy 530.871751 7.721661) (xy 530.887621 7.593501) (xy 530.895571 7.464606)
			(xy 530.896068 7.400036) (xy 530.895571 7.335466) (xy 530.887621 7.206571) (xy 530.871751 7.078411)
			(xy 530.848022 6.95147) (xy 530.816523 6.826231) (xy 530.777374 6.703168) (xy 530.730723 6.582749)
			(xy 530.676748 6.46543) (xy 530.615653 6.351656) (xy 530.54767 6.241859) (xy 530.473056 6.136456)
			(xy 530.392095 6.035846) (xy 530.305095 5.940411) (xy 530.212384 5.850512) (xy 530.114314 5.766491)
			(xy 530.011259 5.688667) (xy 529.903608 5.617335) (xy 529.791769 5.552765) (xy 529.676168 5.495203)
			(xy 529.557243 5.444866) (xy 529.435444 5.401946) (xy 529.311234 5.366605) (xy 529.185085 5.338978)
			(xy 529.057473 5.319169) (xy 528.928884 5.307253) (xy 528.799806 5.303277) (xy 528.670728 5.307253)
			(xy 528.542139 5.319169) (xy 528.414527 5.338978) (xy 528.288378 5.366605) (xy 528.164168 5.401946)
			(xy 528.042369 5.444866) (xy 527.923444 5.495203) (xy 527.807843 5.552765) (xy 527.696004 5.617335)
			(xy 527.588353 5.688667) (xy 527.485298 5.766491) (xy 527.387228 5.850512) (xy 527.294517 5.940411)
			(xy 527.207517 6.035846) (xy 527.126556 6.136456) (xy 527.051942 6.241859) (xy 526.983959 6.351656)
			(xy 526.922864 6.46543) (xy 526.868889 6.582749) (xy 526.822238 6.703168) (xy 526.783089 6.826231)
			(xy 526.75159 6.95147) (xy 526.727861 7.078411) (xy 526.711991 7.206571) (xy 526.704041 7.335466)
			(xy 474.307916 7.335466) (xy 474.307916 -77.67193) (xy 474.307428 -77.765094) (xy 474.299715 -77.951262)
			(xy 474.284317 -78.136953) (xy 474.261258 -78.321849) (xy 474.23058 -78.505634) (xy 474.192333 -78.687994)
			(xy 474.146584 -78.868619) (xy 474.093411 -79.047199) (xy 474.032904 -79.223429) (xy 473.965167 -79.397008)
			(xy 473.890315 -79.56764) (xy 473.808477 -79.735034) (xy 473.719792 -79.898903) (xy 473.624411 -80.058968)
			(xy 473.522498 -80.214955) (xy 473.414227 -80.366597) (xy 473.299782 -80.513637) (xy 473.17936 -80.655821)
			(xy 473.053165 -80.792909) (xy 472.987624 -80.859122) (xy 471.245184 -82.601562) (xy 471.207836 -82.63956)
			(xy 471.138049 -82.720082) (xy 471.074185 -82.805378) (xy 471.01657 -82.895014) (xy 470.965496 -82.988531)
			(xy 470.921226 -83.085455) (xy 470.883983 -83.18529) (xy 470.853958 -83.287527) (xy 470.831304 -83.391646)
			(xy 470.816136 -83.497117) (xy 470.808532 -83.6034) (xy 470.80805 -83.656678) (xy 470.80805 -404.871936)
			(xy 470.807562 -404.9651) (xy 470.799849 -405.151268) (xy 470.78445 -405.336959) (xy 470.761392 -405.521855)
			(xy 470.730713 -405.70564) (xy 470.692467 -405.888001) (xy 470.646718 -406.068625) (xy 470.593544 -406.247205)
			(xy 470.533038 -406.423435) (xy 470.465301 -406.597015) (xy 470.39045 -406.767647) (xy 470.308612 -406.935041)
			(xy 470.219927 -407.098911) (xy 470.124547 -407.258976) (xy 470.022634 -407.414963) (xy 469.914363 -407.566606)
			(xy 469.799919 -407.713645) (xy 469.679497 -407.855831) (xy 469.553302 -407.992919) (xy 469.487758 -408.059128)
			(xy 468.244936 -409.30195) (xy 468.207612 -409.339964) (xy 468.137859 -409.4205) (xy 468.074028 -409.505805)
			(xy 468.016443 -409.595446) (xy 467.965398 -409.688966) (xy 467.921153 -409.785888) (xy 467.883933 -409.885719)
			(xy 467.853928 -409.98795) (xy 467.831291 -410.092061) (xy 467.816137 -410.197522) (xy 467.808543 -410.303794)
			(xy 467.808056 -410.357066) (xy 467.808056 -439.989976) (xy 467.808577 -440.045784) (xy 467.816916 -440.157089)
			(xy 467.83355 -440.267459) (xy 467.858385 -440.376277) (xy 467.891282 -440.482936) (xy 467.932058 -440.586837)
			(xy 467.980485 -440.687401) (xy 468.036291 -440.784065) (xy 468.099165 -440.876289) (xy 468.168754 -440.963556)
			(xy 468.244671 -441.045378) (xy 468.32649 -441.121299) (xy 468.413753 -441.190893) (xy 468.505974 -441.253771)
			(xy 468.602635 -441.309582) (xy 468.703197 -441.358013) (xy 468.807096 -441.398794) (xy 468.913753 -441.431697)
			(xy 469.02257 -441.456537) (xy 469.13294 -441.473176) (xy 469.244244 -441.48152) (xy 469.300052 -441.481972)
			(xy 471.79992 -441.481972) (xy 471.870274 -441.482466) (xy 472.01076 -441.490356) (xy 472.150582 -441.506112)
			(xy 472.289302 -441.529682) (xy 472.426481 -441.560993) (xy 472.561689 -441.599946) (xy 472.6945 -441.646419)
			(xy 472.824497 -441.700266) (xy 472.95127 -441.761317) (xy 473.07442 -441.82938) (xy 473.19356 -441.904241)
			(xy 473.308316 -441.985664) (xy 473.418325 -442.073394) (xy 473.523243 -442.167153) (xy 473.622738 -442.266648)
			(xy 473.716499 -442.371565) (xy 473.804229 -442.481575) (xy 473.885652 -442.59633) (xy 473.960514 -442.71547)
			(xy 474.028578 -442.83862) (xy 474.089629 -442.965392) (xy 474.143476 -443.095389) (xy 474.18995 -443.2282)
			(xy 474.228904 -443.363407) (xy 474.260216 -443.500587) (xy 474.283787 -443.639306) (xy 474.299543 -443.779128)
			(xy 474.307434 -443.919614) (xy 474.307916 -443.989968) (xy 474.307916 -458.092864) (xy 526.704041 -458.092864)
			(xy 526.704041 -457.963724) (xy 526.711991 -457.834829) (xy 526.727861 -457.706669) (xy 526.75159 -457.579728)
			(xy 526.783089 -457.454489) (xy 526.822238 -457.331426) (xy 526.868889 -457.211007) (xy 526.922864 -457.093688)
			(xy 526.983959 -456.979914) (xy 527.051942 -456.870117) (xy 527.126556 -456.764714) (xy 527.207517 -456.664104)
			(xy 527.294517 -456.568669) (xy 527.387228 -456.47877) (xy 527.485298 -456.394749) (xy 527.588353 -456.316925)
			(xy 527.696004 -456.245593) (xy 527.807843 -456.181023) (xy 527.923444 -456.123461) (xy 528.042369 -456.073124)
			(xy 528.164168 -456.030204) (xy 528.288378 -455.994863) (xy 528.414527 -455.967236) (xy 528.542139 -455.947427)
			(xy 528.670728 -455.935511) (xy 528.799806 -455.931535) (xy 528.928884 -455.935511) (xy 529.057473 -455.947427)
			(xy 529.185085 -455.967236) (xy 529.311234 -455.994863) (xy 529.435444 -456.030204) (xy 529.557243 -456.073124)
			(xy 529.676168 -456.123461) (xy 529.791769 -456.181023) (xy 529.903608 -456.245593) (xy 530.011259 -456.316925)
			(xy 530.114314 -456.394749) (xy 530.212384 -456.47877) (xy 530.305095 -456.568669) (xy 530.392095 -456.664104)
			(xy 530.473056 -456.764714) (xy 530.54767 -456.870117) (xy 530.615653 -456.979914) (xy 530.676748 -457.093688)
			(xy 530.730723 -457.211007) (xy 530.777374 -457.331426) (xy 530.816523 -457.454489) (xy 530.848022 -457.579728)
			(xy 530.871751 -457.706669) (xy 530.887621 -457.834829) (xy 530.895571 -457.963724) (xy 530.896068 -458.028294)
			(xy 530.895571 -458.092864) (xy 530.887621 -458.221759) (xy 530.871751 -458.349919) (xy 530.848022 -458.47686)
			(xy 530.816523 -458.602099) (xy 530.777374 -458.725162) (xy 530.730723 -458.845581) (xy 530.676748 -458.9629)
			(xy 530.615653 -459.076674) (xy 530.54767 -459.186471) (xy 530.473056 -459.291874) (xy 530.392095 -459.392484)
			(xy 530.305095 -459.487919) (xy 530.212384 -459.577818) (xy 530.114314 -459.661839) (xy 530.011259 -459.739663)
			(xy 529.903608 -459.810995) (xy 529.791769 -459.875565) (xy 529.676168 -459.933127) (xy 529.557243 -459.983464)
			(xy 529.435444 -460.026384) (xy 529.311234 -460.061725) (xy 529.185085 -460.089352) (xy 529.057473 -460.109161)
			(xy 528.928884 -460.121077) (xy 528.799806 -460.125054) (xy 528.670728 -460.121077) (xy 528.542139 -460.109161)
			(xy 528.414527 -460.089352) (xy 528.288378 -460.061725) (xy 528.164168 -460.026384) (xy 528.042369 -459.983464)
			(xy 527.923444 -459.933127) (xy 527.807843 -459.875565) (xy 527.696004 -459.810995) (xy 527.588353 -459.739663)
			(xy 527.485298 -459.661839) (xy 527.387228 -459.577818) (xy 527.294517 -459.487919) (xy 527.207517 -459.392484)
			(xy 527.126556 -459.291874) (xy 527.051942 -459.186471) (xy 526.983959 -459.076674) (xy 526.922864 -458.9629)
			(xy 526.868889 -458.845581) (xy 526.822238 -458.725162) (xy 526.783089 -458.602099) (xy 526.75159 -458.47686)
			(xy 526.727861 -458.349919) (xy 526.711991 -458.221759) (xy 526.704041 -458.092864) (xy 474.307916 -458.092864)
			(xy 474.307916 -461.028288) (xy 474.308425 -461.084096) (xy 474.316765 -461.195399) (xy 474.3334 -461.305768)
			(xy 474.358236 -461.414584) (xy 474.391134 -461.521241) (xy 474.431912 -461.625141) (xy 474.480339 -461.725703)
			(xy 474.536147 -461.822365) (xy 474.599022 -461.914586) (xy 474.668612 -462.00185) (xy 474.74453 -462.08367)
			(xy 474.82635 -462.159588) (xy 474.913614 -462.229178) (xy 475.005835 -462.292053) (xy 475.102497 -462.347861)
			(xy 475.203059 -462.396288) (xy 475.306959 -462.437066) (xy 475.413616 -462.469964) (xy 475.522432 -462.4948)
			(xy 475.632801 -462.511435) (xy 475.744104 -462.519775) (xy 475.799912 -462.520284)
		)
		(stroke
			(width 0)
			(type solid)
		)
		(fill yes)
		(layer "In12.Cu")
		(net "T1_GND")
	)
	(gr_poly
		(pts
			(xy 256.292096 -31.120588) (xy 256.292096 -11.780012) (xy 256.29258 -11.709658) (xy 256.300469 -11.56917)
			(xy 256.316223 -11.429347) (xy 256.339792 -11.290626) (xy 256.371101 -11.153445) (xy 256.410054 -11.018236)
			(xy 256.456527 -10.885423) (xy 256.510373 -10.755425) (xy 256.571423 -10.628651) (xy 256.639486 -10.505499)
			(xy 256.714347 -10.386357) (xy 256.795771 -10.2716) (xy 256.883501 -10.16159) (xy 256.977261 -10.056671)
			(xy 257.076757 -9.957175) (xy 257.181674 -9.863414) (xy 257.291684 -9.775683) (xy 257.406441 -9.694258)
			(xy 257.525582 -9.619396) (xy 257.648733 -9.551333) (xy 257.775507 -9.490281) (xy 257.905504 -9.436434)
			(xy 258.038317 -9.38996) (xy 258.173526 -9.351006) (xy 258.310706 -9.319695) (xy 258.449427 -9.296125)
			(xy 258.589251 -9.280371) (xy 258.729738 -9.272481) (xy 258.800092 -9.272016) (xy 383.601976 -9.272016)
			(xy 383.657784 -9.271508) (xy 383.769089 -9.263168) (xy 383.879459 -9.246534) (xy 383.988278 -9.221699)
			(xy 384.094936 -9.188801) (xy 384.198838 -9.148025) (xy 384.299402 -9.099598) (xy 384.396066 -9.043791)
			(xy 384.488289 -8.980916) (xy 384.575555 -8.911326) (xy 384.657377 -8.835408) (xy 384.733297 -8.753588)
			(xy 384.80289 -8.666324) (xy 384.865767 -8.574103) (xy 384.921577 -8.477441) (xy 384.970007 -8.376878)
			(xy 385.010787 -8.272978) (xy 385.043688 -8.16632) (xy 385.068526 -8.057503) (xy 385.085163 -7.947133)
			(xy 385.093506 -7.835828) (xy 385.093972 -7.78002) (xy 385.093972 0.999998) (xy 385.094465 1.070352)
			(xy 385.102355 1.210839) (xy 385.118109 1.350662) (xy 385.141678 1.489383) (xy 385.172988 1.626563)
			(xy 385.211941 1.761772) (xy 385.258413 1.894584) (xy 385.312259 2.024582) (xy 385.37331 2.151356)
			(xy 385.441373 2.274507) (xy 385.516233 2.393649) (xy 385.597656 2.508405) (xy 385.685386 2.618416)
			(xy 385.779146 2.723335) (xy 385.878641 2.822831) (xy 385.983558 2.916592) (xy 386.093567 3.004323)
			(xy 386.208323 3.085748) (xy 386.327463 3.16061) (xy 386.450614 3.228674) (xy 386.577387 3.289727)
			(xy 386.707384 3.343575) (xy 386.840195 3.390049) (xy 386.975404 3.429003) (xy 387.112584 3.460315)
			(xy 387.251304 3.483887) (xy 387.391127 3.499643) (xy 387.531614 3.507534) (xy 387.601968 3.507994)
			(xy 456.202034 3.507994) (xy 456.272387 3.5075) (xy 456.412872 3.499608) (xy 456.552693 3.483853)
			(xy 456.691411 3.460282) (xy 456.828589 3.42897) (xy 456.963796 3.390016) (xy 457.096605 3.343542)
			(xy 457.226601 3.289695) (xy 457.353372 3.228644) (xy 457.476521 3.16058) (xy 457.595659 3.085719)
			(xy 457.710413 3.004295) (xy 457.820421 2.916565) (xy 457.925337 2.822806) (xy 458.02483 2.723311)
			(xy 458.118589 2.618393) (xy 458.206317 2.508384) (xy 458.287739 2.393629) (xy 458.362598 2.27449)
			(xy 458.43066 2.15134) (xy 458.49171 2.024568) (xy 458.545555 1.894572) (xy 458.592027 1.761761)
			(xy 458.630979 1.626554) (xy 458.662289 1.489376) (xy 458.685858 1.350658) (xy 458.701612 1.210836)
			(xy 458.709501 1.070351) (xy 458.71003 0.999998) (xy 458.71003 -7.78002) (xy 458.71054 -7.835827)
			(xy 458.718882 -7.947128) (xy 458.735519 -8.057494) (xy 458.760357 -8.166309) (xy 458.793257 -8.272963)
			(xy 458.834035 -8.37686) (xy 458.882464 -8.47742) (xy 458.938272 -8.574079) (xy 459.001148 -8.666297)
			(xy 459.070739 -8.753559) (xy 459.146656 -8.835376) (xy 459.228476 -8.911291) (xy 459.31574 -8.98088)
			(xy 459.40796 -9.043752) (xy 459.504621 -9.099557) (xy 459.605182 -9.147983) (xy 459.70908 -9.188758)
			(xy 459.815736 -9.221655) (xy 459.924551 -9.24649) (xy 460.034918 -9.263123) (xy 460.146219 -9.271462)
			(xy 460.202026 -9.272016) (xy 464.327748 -9.272016) (xy 464.332574 -9.271) (xy 464.357024 -9.266474)
			(xy 464.406516 -9.261643) (xy 464.43138 -9.261348) (xy 464.456244 -9.26164) (xy 464.505735 -9.266479)
			(xy 464.530186 -9.271) (xy 464.535012 -9.272016) (xy 469.799924 -9.272016) (xy 469.855731 -9.271493)
			(xy 469.967032 -9.263151) (xy 470.077399 -9.246514) (xy 470.186213 -9.221677) (xy 470.292868 -9.188777)
			(xy 470.396765 -9.147999) (xy 470.497325 -9.099571) (xy 470.593985 -9.043764) (xy 470.686204 -8.980889)
			(xy 470.773467 -8.911299) (xy 470.855285 -8.835382) (xy 470.931202 -8.753564) (xy 471.000791 -8.666301)
			(xy 471.063666 -8.574082) (xy 471.119473 -8.477422) (xy 471.167901 -8.376862) (xy 471.208678 -8.272964)
			(xy 471.241578 -8.166309) (xy 471.266415 -8.057495) (xy 471.283051 -7.947128) (xy 471.291394 -7.835827)
			(xy 471.29192 -7.78002) (xy 471.29192 10.40003) (xy 471.291397 10.455837) (xy 471.283054 10.567138)
			(xy 471.266417 10.677504) (xy 471.241579 10.786319) (xy 471.208679 10.892973) (xy 471.167901 10.99687)
			(xy 471.119473 11.09743) (xy 471.063666 11.194089) (xy 471.000791 11.286308) (xy 470.931201 11.373571)
			(xy 470.855284 11.455389) (xy 470.773466 11.531305) (xy 470.686203 11.600895) (xy 470.593984 11.663769)
			(xy 470.497324 11.719576) (xy 470.396765 11.768004) (xy 470.292867 11.808781) (xy 470.186213 11.841681)
			(xy 470.077398 11.866518) (xy 469.967032 11.883155) (xy 469.855731 11.891497) (xy 469.799924 11.892026)
			(xy 1.999996 11.892026) (xy 1.944189 11.891504) (xy 1.832887 11.883163) (xy 1.72252 11.866527) (xy 1.613705 11.841691)
			(xy 1.50705 11.808792) (xy 1.403151 11.768014) (xy 1.302591 11.719587) (xy 1.20593 11.66378) (xy 1.113711 11.600905)
			(xy 1.026448 11.531315) (xy 0.944629 11.455398) (xy 0.868712 11.373579) (xy 0.799122 11.286316) (xy 0.736248 11.194096)
			(xy 0.680441 11.097436) (xy 0.632014 10.996875) (xy 0.591237 10.892977) (xy 0.558338 10.786321) (xy 0.533502 10.677506)
			(xy 0.516867 10.567139) (xy 0.508526 10.455837) (xy 0.508 10.40003) (xy 0.508 7.335466) (xy 2.904225 7.335466)
			(xy 2.904225 7.464606) (xy 2.912175 7.593501) (xy 2.928045 7.721661) (xy 2.951774 7.848602) (xy 2.983273 7.973841)
			(xy 3.022422 8.096904) (xy 3.069073 8.217323) (xy 3.123048 8.334642) (xy 3.184143 8.448416) (xy 3.252126 8.558213)
			(xy 3.32674 8.663616) (xy 3.407701 8.764226) (xy 3.494701 8.859661) (xy 3.587412 8.94956) (xy 3.685482 9.033581)
			(xy 3.788537 9.111405) (xy 3.896188 9.182737) (xy 4.008027 9.247307) (xy 4.123628 9.304869) (xy 4.242553 9.355206)
			(xy 4.364352 9.398126) (xy 4.488562 9.433467) (xy 4.614711 9.461094) (xy 4.742323 9.480903) (xy 4.870912 9.492819)
			(xy 4.99999 9.496796) (xy 5.129068 9.492819) (xy 5.257657 9.480903) (xy 5.385269 9.461094) (xy 5.511418 9.433467)
			(xy 5.635628 9.398126) (xy 5.757427 9.355206) (xy 5.876352 9.304869) (xy 5.991953 9.247307) (xy 6.020338 9.230919)
			(xy 256.921241 9.230919) (xy 256.921241 9.316669) (xy 256.929153 9.402052) (xy 256.944909 9.486342)
			(xy 256.968376 9.568818) (xy 256.999352 9.648777) (xy 257.037574 9.725537) (xy 257.082715 9.798443)
			(xy 257.134391 9.866872) (xy 257.19216 9.930242) (xy 257.25553 9.988011) (xy 257.323959 10.039687)
			(xy 257.396865 10.084828) (xy 257.473625 10.12305) (xy 257.553584 10.154026) (xy 257.63606 10.177493)
			(xy 257.72035 10.193249) (xy 257.805733 10.201161) (xy 257.891483 10.201161) (xy 257.976866 10.193249)
			(xy 258.061156 10.177493) (xy 258.143632 10.154026) (xy 258.223591 10.12305) (xy 258.300351 10.084828)
			(xy 258.373257 10.039687) (xy 258.441686 9.988011) (xy 258.505056 9.930242) (xy 258.562825 9.866872)
			(xy 258.614501 9.798443) (xy 258.659642 9.725537) (xy 258.697864 9.648777) (xy 258.72884 9.568818)
			(xy 258.752307 9.486342) (xy 258.768063 9.402052) (xy 258.775975 9.316669) (xy 258.77647 9.273794)
			(xy 258.775975 9.230919) (xy 263.271241 9.230919) (xy 263.271241 9.316669) (xy 263.279153 9.402052)
			(xy 263.294909 9.486342) (xy 263.318376 9.568818) (xy 263.349352 9.648777) (xy 263.387574 9.725537)
			(xy 263.432715 9.798443) (xy 263.484391 9.866872) (xy 263.54216 9.930242) (xy 263.60553 9.988011)
			(xy 263.673959 10.039687) (xy 263.746865 10.084828) (xy 263.823625 10.12305) (xy 263.903584 10.154026)
			(xy 263.98606 10.177493) (xy 264.07035 10.193249) (xy 264.155733 10.201161) (xy 264.241483 10.201161)
			(xy 264.326866 10.193249) (xy 264.411156 10.177493) (xy 264.493632 10.154026) (xy 264.573591 10.12305)
			(xy 264.650351 10.084828) (xy 264.723257 10.039687) (xy 264.791686 9.988011) (xy 264.855056 9.930242)
			(xy 264.912825 9.866872) (xy 264.964501 9.798443) (xy 265.009642 9.725537) (xy 265.047864 9.648777)
			(xy 265.07884 9.568818) (xy 265.102307 9.486342) (xy 265.118063 9.402052) (xy 265.125975 9.316669)
			(xy 265.12647 9.273794) (xy 265.125975 9.230919) (xy 324.845921 9.230919) (xy 324.845921 9.316669)
			(xy 324.853833 9.402052) (xy 324.869589 9.486342) (xy 324.893056 9.568818) (xy 324.924032 9.648777)
			(xy 324.962254 9.725537) (xy 325.007395 9.798443) (xy 325.059071 9.866872) (xy 325.11684 9.930242)
			(xy 325.18021 9.988011) (xy 325.248639 10.039687) (xy 325.321545 10.084828) (xy 325.398305 10.12305)
			(xy 325.478264 10.154026) (xy 325.56074 10.177493) (xy 325.64503 10.193249) (xy 325.730413 10.201161)
			(xy 325.816163 10.201161) (xy 325.901546 10.193249) (xy 325.985836 10.177493) (xy 326.068312 10.154026)
			(xy 326.148271 10.12305) (xy 326.225031 10.084828) (xy 326.297937 10.039687) (xy 326.366366 9.988011)
			(xy 326.429736 9.930242) (xy 326.487505 9.866872) (xy 326.539181 9.798443) (xy 326.584322 9.725537)
			(xy 326.622544 9.648777) (xy 326.65352 9.568818) (xy 326.676987 9.486342) (xy 326.692743 9.402052)
			(xy 326.700655 9.316669) (xy 326.70115 9.273794) (xy 326.700655 9.230919) (xy 331.195921 9.230919)
			(xy 331.195921 9.316669) (xy 331.203833 9.402052) (xy 331.219589 9.486342) (xy 331.243056 9.568818)
			(xy 331.274032 9.648777) (xy 331.312254 9.725537) (xy 331.357395 9.798443) (xy 331.409071 9.866872)
			(xy 331.46684 9.930242) (xy 331.53021 9.988011) (xy 331.598639 10.039687) (xy 331.671545 10.084828)
			(xy 331.748305 10.12305) (xy 331.828264 10.154026) (xy 331.91074 10.177493) (xy 331.99503 10.193249)
			(xy 332.080413 10.201161) (xy 332.166163 10.201161) (xy 332.251546 10.193249) (xy 332.335836 10.177493)
			(xy 332.418312 10.154026) (xy 332.498271 10.12305) (xy 332.575031 10.084828) (xy 332.647937 10.039687)
			(xy 332.716366 9.988011) (xy 332.779736 9.930242) (xy 332.837505 9.866872) (xy 332.889181 9.798443)
			(xy 332.934322 9.725537) (xy 332.972544 9.648777) (xy 333.00352 9.568818) (xy 333.026987 9.486342)
			(xy 333.042743 9.402052) (xy 333.050655 9.316669) (xy 333.05115 9.273794) (xy 333.050655 9.230919)
			(xy 335.488267 9.230919) (xy 335.488267 9.316669) (xy 335.496179 9.402052) (xy 335.511935 9.486342)
			(xy 335.535402 9.568818) (xy 335.566378 9.648777) (xy 335.6046 9.725537) (xy 335.649741 9.798443)
			(xy 335.701417 9.866872) (xy 335.759186 9.930242) (xy 335.822556 9.988011) (xy 335.890985 10.039687)
			(xy 335.963891 10.084828) (xy 336.040651 10.12305) (xy 336.12061 10.154026) (xy 336.203086 10.177493)
			(xy 336.287376 10.193249) (xy 336.372759 10.201161) (xy 336.458509 10.201161) (xy 336.543892 10.193249)
			(xy 336.628182 10.177493) (xy 336.710658 10.154026) (xy 336.790617 10.12305) (xy 336.867377 10.084828)
			(xy 336.940283 10.039687) (xy 337.008712 9.988011) (xy 337.072082 9.930242) (xy 337.129851 9.866872)
			(xy 337.181527 9.798443) (xy 337.226668 9.725537) (xy 337.26489 9.648777) (xy 337.295866 9.568818)
			(xy 337.319333 9.486342) (xy 337.335089 9.402052) (xy 337.343001 9.316669) (xy 337.343496 9.273794)
			(xy 337.343001 9.230919) (xy 341.838267 9.230919) (xy 341.838267 9.316669) (xy 341.846179 9.402052)
			(xy 341.861935 9.486342) (xy 341.885402 9.568818) (xy 341.916378 9.648777) (xy 341.9546 9.725537)
			(xy 341.999741 9.798443) (xy 342.051417 9.866872) (xy 342.109186 9.930242) (xy 342.172556 9.988011)
			(xy 342.240985 10.039687) (xy 342.313891 10.084828) (xy 342.390651 10.12305) (xy 342.47061 10.154026)
			(xy 342.553086 10.177493) (xy 342.637376 10.193249) (xy 342.722759 10.201161) (xy 342.808509 10.201161)
			(xy 342.893892 10.193249) (xy 342.978182 10.177493) (xy 343.060658 10.154026) (xy 343.140617 10.12305)
			(xy 343.217377 10.084828) (xy 343.290283 10.039687) (xy 343.358712 9.988011) (xy 343.422082 9.930242)
			(xy 343.479851 9.866872) (xy 343.531527 9.798443) (xy 343.576668 9.725537) (xy 343.61489 9.648777)
			(xy 343.645866 9.568818) (xy 343.669333 9.486342) (xy 343.685089 9.402052) (xy 343.693001 9.316669)
			(xy 343.693496 9.273794) (xy 343.693001 9.230919) (xy 373.705107 9.230919) (xy 373.705107 9.316669)
			(xy 373.713019 9.402052) (xy 373.728775 9.486342) (xy 373.752242 9.568818) (xy 373.783218 9.648777)
			(xy 373.82144 9.725537) (xy 373.866581 9.798443) (xy 373.918257 9.866872) (xy 373.976026 9.930242)
			(xy 374.039396 9.988011) (xy 374.107825 10.039687) (xy 374.180731 10.084828) (xy 374.257491 10.12305)
			(xy 374.33745 10.154026) (xy 374.419926 10.177493) (xy 374.504216 10.193249) (xy 374.589599 10.201161)
			(xy 374.675349 10.201161) (xy 374.760732 10.193249) (xy 374.845022 10.177493) (xy 374.927498 10.154026)
			(xy 375.007457 10.12305) (xy 375.084217 10.084828) (xy 375.157123 10.039687) (xy 375.225552 9.988011)
			(xy 375.288922 9.930242) (xy 375.346691 9.866872) (xy 375.398367 9.798443) (xy 375.443508 9.725537)
			(xy 375.48173 9.648777) (xy 375.512706 9.568818) (xy 375.536173 9.486342) (xy 375.551929 9.402052)
			(xy 375.559841 9.316669) (xy 375.560336 9.273794) (xy 375.559841 9.230919) (xy 380.055107 9.230919)
			(xy 380.055107 9.316669) (xy 380.063019 9.402052) (xy 380.078775 9.486342) (xy 380.102242 9.568818)
			(xy 380.133218 9.648777) (xy 380.17144 9.725537) (xy 380.216581 9.798443) (xy 380.268257 9.866872)
			(xy 380.326026 9.930242) (xy 380.389396 9.988011) (xy 380.457825 10.039687) (xy 380.530731 10.084828)
			(xy 380.607491 10.12305) (xy 380.68745 10.154026) (xy 380.769926 10.177493) (xy 380.854216 10.193249)
			(xy 380.939599 10.201161) (xy 381.025349 10.201161) (xy 381.110732 10.193249) (xy 381.195022 10.177493)
			(xy 381.277498 10.154026) (xy 381.357457 10.12305) (xy 381.434217 10.084828) (xy 381.507123 10.039687)
			(xy 381.575552 9.988011) (xy 381.638922 9.930242) (xy 381.696691 9.866872) (xy 381.748367 9.798443)
			(xy 381.793508 9.725537) (xy 381.83173 9.648777) (xy 381.862706 9.568818) (xy 381.886173 9.486342)
			(xy 381.901929 9.402052) (xy 381.909841 9.316669) (xy 381.910336 9.273794) (xy 381.909841 9.230919)
			(xy 381.901929 9.145536) (xy 381.886173 9.061246) (xy 381.862706 8.97877) (xy 381.83173 8.898811)
			(xy 381.793508 8.822051) (xy 381.748367 8.749145) (xy 381.696691 8.680716) (xy 381.638922 8.617346)
			(xy 381.575552 8.559577) (xy 381.507123 8.507901) (xy 381.434217 8.46276) (xy 381.357457 8.424538)
			(xy 381.277498 8.393562) (xy 381.195022 8.370095) (xy 381.110732 8.354339) (xy 381.025349 8.346427)
			(xy 380.939599 8.346427) (xy 380.854216 8.354339) (xy 380.769926 8.370095) (xy 380.68745 8.393562)
			(xy 380.607491 8.424538) (xy 380.530731 8.46276) (xy 380.457825 8.507901) (xy 380.389396 8.559577)
			(xy 380.326026 8.617346) (xy 380.268257 8.680716) (xy 380.216581 8.749145) (xy 380.17144 8.822051)
			(xy 380.133218 8.898811) (xy 380.102242 8.97877) (xy 380.078775 9.061246) (xy 380.063019 9.145536)
			(xy 380.055107 9.230919) (xy 375.559841 9.230919) (xy 375.551929 9.145536) (xy 375.536173 9.061246)
			(xy 375.512706 8.97877) (xy 375.48173 8.898811) (xy 375.443508 8.822051) (xy 375.398367 8.749145)
			(xy 375.346691 8.680716) (xy 375.288922 8.617346) (xy 375.225552 8.559577) (xy 375.157123 8.507901)
			(xy 375.084217 8.46276) (xy 375.007457 8.424538) (xy 374.927498 8.393562) (xy 374.845022 8.370095)
			(xy 374.760732 8.354339) (xy 374.675349 8.346427) (xy 374.589599 8.346427) (xy 374.504216 8.354339)
			(xy 374.419926 8.370095) (xy 374.33745 8.393562) (xy 374.257491 8.424538) (xy 374.180731 8.46276)
			(xy 374.107825 8.507901) (xy 374.039396 8.559577) (xy 373.976026 8.617346) (xy 373.918257 8.680716)
			(xy 373.866581 8.749145) (xy 373.82144 8.822051) (xy 373.783218 8.898811) (xy 373.752242 8.97877)
			(xy 373.728775 9.061246) (xy 373.713019 9.145536) (xy 373.705107 9.230919) (xy 343.693001 9.230919)
			(xy 343.685089 9.145536) (xy 343.669333 9.061246) (xy 343.645866 8.97877) (xy 343.61489 8.898811)
			(xy 343.576668 8.822051) (xy 343.531527 8.749145) (xy 343.479851 8.680716) (xy 343.422082 8.617346)
			(xy 343.358712 8.559577) (xy 343.290283 8.507901) (xy 343.217377 8.46276) (xy 343.140617 8.424538)
			(xy 343.060658 8.393562) (xy 342.978182 8.370095) (xy 342.893892 8.354339) (xy 342.808509 8.346427)
			(xy 342.722759 8.346427) (xy 342.637376 8.354339) (xy 342.553086 8.370095) (xy 342.47061 8.393562)
			(xy 342.390651 8.424538) (xy 342.313891 8.46276) (xy 342.240985 8.507901) (xy 342.172556 8.559577)
			(xy 342.109186 8.617346) (xy 342.051417 8.680716) (xy 341.999741 8.749145) (xy 341.9546 8.822051)
			(xy 341.916378 8.898811) (xy 341.885402 8.97877) (xy 341.861935 9.061246) (xy 341.846179 9.145536)
			(xy 341.838267 9.230919) (xy 337.343001 9.230919) (xy 337.335089 9.145536) (xy 337.319333 9.061246)
			(xy 337.295866 8.97877) (xy 337.26489 8.898811) (xy 337.226668 8.822051) (xy 337.181527 8.749145)
			(xy 337.129851 8.680716) (xy 337.072082 8.617346) (xy 337.008712 8.559577) (xy 336.940283 8.507901)
			(xy 336.867377 8.46276) (xy 336.790617 8.424538) (xy 336.710658 8.393562) (xy 336.628182 8.370095)
			(xy 336.543892 8.354339) (xy 336.458509 8.346427) (xy 336.372759 8.346427) (xy 336.287376 8.354339)
			(xy 336.203086 8.370095) (xy 336.12061 8.393562) (xy 336.040651 8.424538) (xy 335.963891 8.46276)
			(xy 335.890985 8.507901) (xy 335.822556 8.559577) (xy 335.759186 8.617346) (xy 335.701417 8.680716)
			(xy 335.649741 8.749145) (xy 335.6046 8.822051) (xy 335.566378 8.898811) (xy 335.535402 8.97877)
			(xy 335.511935 9.061246) (xy 335.496179 9.145536) (xy 335.488267 9.230919) (xy 333.050655 9.230919)
			(xy 333.042743 9.145536) (xy 333.026987 9.061246) (xy 333.00352 8.97877) (xy 332.972544 8.898811)
			(xy 332.934322 8.822051) (xy 332.889181 8.749145) (xy 332.837505 8.680716) (xy 332.779736 8.617346)
			(xy 332.716366 8.559577) (xy 332.647937 8.507901) (xy 332.575031 8.46276) (xy 332.498271 8.424538)
			(xy 332.418312 8.393562) (xy 332.335836 8.370095) (xy 332.251546 8.354339) (xy 332.166163 8.346427)
			(xy 332.080413 8.346427) (xy 331.99503 8.354339) (xy 331.91074 8.370095) (xy 331.828264 8.393562)
			(xy 331.748305 8.424538) (xy 331.671545 8.46276) (xy 331.598639 8.507901) (xy 331.53021 8.559577)
			(xy 331.46684 8.617346) (xy 331.409071 8.680716) (xy 331.357395 8.749145) (xy 331.312254 8.822051)
			(xy 331.274032 8.898811) (xy 331.243056 8.97877) (xy 331.219589 9.061246) (xy 331.203833 9.145536)
			(xy 331.195921 9.230919) (xy 326.700655 9.230919) (xy 326.692743 9.145536) (xy 326.676987 9.061246)
			(xy 326.65352 8.97877) (xy 326.622544 8.898811) (xy 326.584322 8.822051) (xy 326.539181 8.749145)
			(xy 326.487505 8.680716) (xy 326.429736 8.617346) (xy 326.366366 8.559577) (xy 326.297937 8.507901)
			(xy 326.225031 8.46276) (xy 326.148271 8.424538) (xy 326.068312 8.393562) (xy 325.985836 8.370095)
			(xy 325.901546 8.354339) (xy 325.816163 8.346427) (xy 325.730413 8.346427) (xy 325.64503 8.354339)
			(xy 325.56074 8.370095) (xy 325.478264 8.393562) (xy 325.398305 8.424538) (xy 325.321545 8.46276)
			(xy 325.248639 8.507901) (xy 325.18021 8.559577) (xy 325.11684 8.617346) (xy 325.059071 8.680716)
			(xy 325.007395 8.749145) (xy 324.962254 8.822051) (xy 324.924032 8.898811) (xy 324.893056 8.97877)
			(xy 324.869589 9.061246) (xy 324.853833 9.145536) (xy 324.845921 9.230919) (xy 265.125975 9.230919)
			(xy 265.118063 9.145536) (xy 265.102307 9.061246) (xy 265.07884 8.97877) (xy 265.047864 8.898811)
			(xy 265.009642 8.822051) (xy 264.964501 8.749145) (xy 264.912825 8.680716) (xy 264.855056 8.617346)
			(xy 264.791686 8.559577) (xy 264.723257 8.507901) (xy 264.650351 8.46276) (xy 264.573591 8.424538)
			(xy 264.493632 8.393562) (xy 264.411156 8.370095) (xy 264.326866 8.354339) (xy 264.241483 8.346427)
			(xy 264.155733 8.346427) (xy 264.07035 8.354339) (xy 263.98606 8.370095) (xy 263.903584 8.393562)
			(xy 263.823625 8.424538) (xy 263.746865 8.46276) (xy 263.673959 8.507901) (xy 263.60553 8.559577)
			(xy 263.54216 8.617346) (xy 263.484391 8.680716) (xy 263.432715 8.749145) (xy 263.387574 8.822051)
			(xy 263.349352 8.898811) (xy 263.318376 8.97877) (xy 263.294909 9.061246) (xy 263.279153 9.145536)
			(xy 263.271241 9.230919) (xy 258.775975 9.230919) (xy 258.768063 9.145536) (xy 258.752307 9.061246)
			(xy 258.72884 8.97877) (xy 258.697864 8.898811) (xy 258.659642 8.822051) (xy 258.614501 8.749145)
			(xy 258.562825 8.680716) (xy 258.505056 8.617346) (xy 258.441686 8.559577) (xy 258.373257 8.507901)
			(xy 258.300351 8.46276) (xy 258.223591 8.424538) (xy 258.143632 8.393562) (xy 258.061156 8.370095)
			(xy 257.976866 8.354339) (xy 257.891483 8.346427) (xy 257.805733 8.346427) (xy 257.72035 8.354339)
			(xy 257.63606 8.370095) (xy 257.553584 8.393562) (xy 257.473625 8.424538) (xy 257.396865 8.46276)
			(xy 257.323959 8.507901) (xy 257.25553 8.559577) (xy 257.19216 8.617346) (xy 257.134391 8.680716)
			(xy 257.082715 8.749145) (xy 257.037574 8.822051) (xy 256.999352 8.898811) (xy 256.968376 8.97877)
			(xy 256.944909 9.061246) (xy 256.929153 9.145536) (xy 256.921241 9.230919) (xy 6.020338 9.230919)
			(xy 6.103792 9.182737) (xy 6.211443 9.111405) (xy 6.314498 9.033581) (xy 6.412568 8.94956) (xy 6.505279 8.859661)
			(xy 6.592279 8.764226) (xy 6.67324 8.663616) (xy 6.747854 8.558213) (xy 6.815837 8.448416) (xy 6.876932 8.334642)
			(xy 6.930907 8.217323) (xy 6.977558 8.096904) (xy 7.016707 7.973841) (xy 7.048206 7.848602) (xy 7.071935 7.721661)
			(xy 7.087805 7.593501) (xy 7.095755 7.464606) (xy 7.096252 7.400036) (xy 7.095755 7.335466) (xy 7.087805 7.206571)
			(xy 7.071935 7.078411) (xy 7.048206 6.95147) (xy 7.016707 6.826231) (xy 6.977558 6.703168) (xy 6.97173 6.688125)
			(xy 178.335673 6.688125) (xy 178.335673 6.773875) (xy 178.343585 6.859258) (xy 178.359341 6.943548)
			(xy 178.382808 7.026024) (xy 178.413784 7.105983) (xy 178.452006 7.182743) (xy 178.497147 7.255649)
			(xy 178.548823 7.324078) (xy 178.606592 7.387448) (xy 178.669962 7.445217) (xy 178.738391 7.496893)
			(xy 178.811297 7.542034) (xy 178.888057 7.580256) (xy 178.968016 7.611232) (xy 179.050492 7.634699)
			(xy 179.134782 7.650455) (xy 179.220165 7.658367) (xy 179.305915 7.658367) (xy 179.391298 7.650455)
			(xy 179.475588 7.634699) (xy 179.558064 7.611232) (xy 179.638023 7.580256) (xy 179.714783 7.542034)
			(xy 179.787689 7.496893) (xy 179.856118 7.445217) (xy 179.919488 7.387448) (xy 179.977257 7.324078)
			(xy 180.028933 7.255649) (xy 180.074074 7.182743) (xy 180.112296 7.105983) (xy 180.143272 7.026024)
			(xy 180.166739 6.943548) (xy 180.182495 6.859258) (xy 180.190407 6.773875) (xy 180.190902 6.731)
			(xy 180.190407 6.688125) (xy 184.685673 6.688125) (xy 184.685673 6.773875) (xy 184.693585 6.859258)
			(xy 184.709341 6.943548) (xy 184.732808 7.026024) (xy 184.763784 7.105983) (xy 184.802006 7.182743)
			(xy 184.847147 7.255649) (xy 184.898823 7.324078) (xy 184.956592 7.387448) (xy 185.019962 7.445217)
			(xy 185.088391 7.496893) (xy 185.161297 7.542034) (xy 185.238057 7.580256) (xy 185.318016 7.611232)
			(xy 185.400492 7.634699) (xy 185.484782 7.650455) (xy 185.570165 7.658367) (xy 185.655915 7.658367)
			(xy 185.741298 7.650455) (xy 185.825588 7.634699) (xy 185.908064 7.611232) (xy 185.988023 7.580256)
			(xy 186.064783 7.542034) (xy 186.137689 7.496893) (xy 186.206118 7.445217) (xy 186.269488 7.387448)
			(xy 186.327257 7.324078) (xy 186.378933 7.255649) (xy 186.424074 7.182743) (xy 186.462296 7.105983)
			(xy 186.493272 7.026024) (xy 186.516739 6.943548) (xy 186.532495 6.859258) (xy 186.540407 6.773875)
			(xy 186.540902 6.731) (xy 186.540407 6.688125) (xy 246.260353 6.688125) (xy 246.260353 6.773875)
			(xy 246.268265 6.859258) (xy 246.284021 6.943548) (xy 246.307488 7.026024) (xy 246.338464 7.105983)
			(xy 246.376686 7.182743) (xy 246.421827 7.255649) (xy 246.473503 7.324078) (xy 246.531272 7.387448)
			(xy 246.594642 7.445217) (xy 246.663071 7.496893) (xy 246.735977 7.542034) (xy 246.812737 7.580256)
			(xy 246.892696 7.611232) (xy 246.975172 7.634699) (xy 247.059462 7.650455) (xy 247.144845 7.658367)
			(xy 247.230595 7.658367) (xy 247.315978 7.650455) (xy 247.400268 7.634699) (xy 247.482744 7.611232)
			(xy 247.562703 7.580256) (xy 247.639463 7.542034) (xy 247.712369 7.496893) (xy 247.780798 7.445217)
			(xy 247.844168 7.387448) (xy 247.901937 7.324078) (xy 247.953613 7.255649) (xy 247.998754 7.182743)
			(xy 248.036976 7.105983) (xy 248.067952 7.026024) (xy 248.091419 6.943548) (xy 248.107175 6.859258)
			(xy 248.115087 6.773875) (xy 248.115582 6.731) (xy 248.115087 6.688125) (xy 252.610353 6.688125)
			(xy 252.610353 6.773875) (xy 252.618265 6.859258) (xy 252.634021 6.943548) (xy 252.657488 7.026024)
			(xy 252.688464 7.105983) (xy 252.726686 7.182743) (xy 252.771827 7.255649) (xy 252.823503 7.324078)
			(xy 252.881272 7.387448) (xy 252.944642 7.445217) (xy 253.013071 7.496893) (xy 253.085977 7.542034)
			(xy 253.162737 7.580256) (xy 253.242696 7.611232) (xy 253.325172 7.634699) (xy 253.409462 7.650455)
			(xy 253.494845 7.658367) (xy 253.580595 7.658367) (xy 253.665978 7.650455) (xy 253.750268 7.634699)
			(xy 253.832744 7.611232) (xy 253.912703 7.580256) (xy 253.989463 7.542034) (xy 254.062369 7.496893)
			(xy 254.130798 7.445217) (xy 254.194168 7.387448) (xy 254.251937 7.324078) (xy 254.303613 7.255649)
			(xy 254.348754 7.182743) (xy 254.386976 7.105983) (xy 254.417952 7.026024) (xy 254.441419 6.943548)
			(xy 254.457175 6.859258) (xy 254.465087 6.773875) (xy 254.465582 6.731) (xy 254.465119 6.690919)
			(xy 256.921241 6.690919) (xy 256.921241 6.776669) (xy 256.929153 6.862052) (xy 256.944909 6.946342)
			(xy 256.968376 7.028818) (xy 256.999352 7.108777) (xy 257.037574 7.185537) (xy 257.082715 7.258443)
			(xy 257.134391 7.326872) (xy 257.19216 7.390242) (xy 257.25553 7.448011) (xy 257.323959 7.499687)
			(xy 257.396865 7.544828) (xy 257.473625 7.58305) (xy 257.553584 7.614026) (xy 257.63606 7.637493)
			(xy 257.72035 7.653249) (xy 257.805733 7.661161) (xy 257.891483 7.661161) (xy 257.976866 7.653249)
			(xy 258.061156 7.637493) (xy 258.143632 7.614026) (xy 258.223591 7.58305) (xy 258.245794 7.571994)
			(xy 261.85622 7.571994) (xy 261.85622 8.435594) (xy 261.856706 8.462863) (xy 261.864468 8.516847)
			(xy 261.879833 8.569177) (xy 261.90249 8.618787) (xy 261.931976 8.664668) (xy 261.967691 8.705885)
			(xy 262.008908 8.7416) (xy 262.054789 8.771086) (xy 262.104399 8.793743) (xy 262.156729 8.809108)
			(xy 262.210713 8.81687) (xy 262.265251 8.81687) (xy 262.319235 8.809108) (xy 262.371565 8.793743)
			(xy 262.421175 8.771086) (xy 262.467056 8.7416) (xy 262.508273 8.705885) (xy 262.543988 8.664668)
			(xy 262.573474 8.618787) (xy 262.596131 8.569177) (xy 262.611496 8.516847) (xy 262.619258 8.462863)
			(xy 262.619744 8.435594) (xy 262.619744 7.571994) (xy 262.619258 7.544725) (xy 262.611496 7.490741)
			(xy 262.596131 7.438411) (xy 262.573474 7.388801) (xy 262.543988 7.34292) (xy 262.508273 7.301703)
			(xy 262.467056 7.265988) (xy 262.421175 7.236502) (xy 262.371565 7.213845) (xy 262.319235 7.19848)
			(xy 262.265251 7.190718) (xy 262.210713 7.190718) (xy 262.156729 7.19848) (xy 262.104399 7.213845)
			(xy 262.054789 7.236502) (xy 262.008908 7.265988) (xy 261.967691 7.301703) (xy 261.931976 7.34292)
			(xy 261.90249 7.388801) (xy 261.879833 7.438411) (xy 261.864468 7.490741) (xy 261.856706 7.544725)
			(xy 261.85622 7.571994) (xy 258.245794 7.571994) (xy 258.300351 7.544828) (xy 258.373257 7.499687)
			(xy 258.441686 7.448011) (xy 258.505056 7.390242) (xy 258.562825 7.326872) (xy 258.614501 7.258443)
			(xy 258.659642 7.185537) (xy 258.697864 7.108777) (xy 258.72884 7.028818) (xy 258.752307 6.946342)
			(xy 258.768063 6.862052) (xy 258.775975 6.776669) (xy 258.77647 6.733794) (xy 258.775975 6.690919)
			(xy 263.271241 6.690919) (xy 263.271241 6.776669) (xy 263.279153 6.862052) (xy 263.294909 6.946342)
			(xy 263.318376 7.028818) (xy 263.349352 7.108777) (xy 263.387574 7.185537) (xy 263.432715 7.258443)
			(xy 263.484391 7.326872) (xy 263.54216 7.390242) (xy 263.60553 7.448011) (xy 263.673959 7.499687)
			(xy 263.746865 7.544828) (xy 263.823625 7.58305) (xy 263.903584 7.614026) (xy 263.98606 7.637493)
			(xy 264.07035 7.653249) (xy 264.155733 7.661161) (xy 264.241483 7.661161) (xy 264.326866 7.653249)
			(xy 264.411156 7.637493) (xy 264.493632 7.614026) (xy 264.573591 7.58305) (xy 264.650351 7.544828)
			(xy 264.723257 7.499687) (xy 264.791686 7.448011) (xy 264.855056 7.390242) (xy 264.912825 7.326872)
			(xy 264.964501 7.258443) (xy 265.009642 7.185537) (xy 265.047864 7.108777) (xy 265.07884 7.028818)
			(xy 265.102307 6.946342) (xy 265.118063 6.862052) (xy 265.125975 6.776669) (xy 265.12647 6.733794)
			(xy 265.125975 6.690919) (xy 324.845921 6.690919) (xy 324.845921 6.776669) (xy 324.853833 6.862052)
			(xy 324.869589 6.946342) (xy 324.893056 7.028818) (xy 324.924032 7.108777) (xy 324.962254 7.185537)
			(xy 325.007395 7.258443) (xy 325.059071 7.326872) (xy 325.11684 7.390242) (xy 325.18021 7.448011)
			(xy 325.248639 7.499687) (xy 325.321545 7.544828) (xy 325.398305 7.58305) (xy 325.478264 7.614026)
			(xy 325.56074 7.637493) (xy 325.64503 7.653249) (xy 325.730413 7.661161) (xy 325.816163 7.661161)
			(xy 325.901546 7.653249) (xy 325.985836 7.637493) (xy 326.068312 7.614026) (xy 326.148271 7.58305)
			(xy 326.170474 7.571994) (xy 327.352152 7.571994) (xy 327.352152 8.435594) (xy 327.352638 8.462863)
			(xy 327.3604 8.516847) (xy 327.375765 8.569177) (xy 327.398422 8.618787) (xy 327.427908 8.664668)
			(xy 327.463623 8.705885) (xy 327.50484 8.7416) (xy 327.550721 8.771086) (xy 327.600331 8.793743)
			(xy 327.652661 8.809108) (xy 327.706645 8.81687) (xy 327.761183 8.81687) (xy 327.815167 8.809108)
			(xy 327.867497 8.793743) (xy 327.917107 8.771086) (xy 327.962988 8.7416) (xy 328.004205 8.705885)
			(xy 328.03992 8.664668) (xy 328.069406 8.618787) (xy 328.092063 8.569177) (xy 328.107428 8.516847)
			(xy 328.11519 8.462863) (xy 328.115676 8.435594) (xy 328.115676 7.571994) (xy 328.11519 7.544725)
			(xy 328.107428 7.490741) (xy 328.092063 7.438411) (xy 328.069406 7.388801) (xy 328.03992 7.34292)
			(xy 328.004205 7.301703) (xy 327.962988 7.265988) (xy 327.917107 7.236502) (xy 327.867497 7.213845)
			(xy 327.815167 7.19848) (xy 327.761183 7.190718) (xy 327.706645 7.190718) (xy 327.652661 7.19848)
			(xy 327.600331 7.213845) (xy 327.550721 7.236502) (xy 327.50484 7.265988) (xy 327.463623 7.301703)
			(xy 327.427908 7.34292) (xy 327.398422 7.388801) (xy 327.375765 7.438411) (xy 327.3604 7.490741)
			(xy 327.352638 7.544725) (xy 327.352152 7.571994) (xy 326.170474 7.571994) (xy 326.225031 7.544828)
			(xy 326.297937 7.499687) (xy 326.366366 7.448011) (xy 326.429736 7.390242) (xy 326.487505 7.326872)
			(xy 326.539181 7.258443) (xy 326.584322 7.185537) (xy 326.622544 7.108777) (xy 326.65352 7.028818)
			(xy 326.676987 6.946342) (xy 326.692743 6.862052) (xy 326.700655 6.776669) (xy 326.70115 6.733794)
			(xy 326.700655 6.690919) (xy 331.195921 6.690919) (xy 331.195921 6.776669) (xy 331.203833 6.862052)
			(xy 331.219589 6.946342) (xy 331.243056 7.028818) (xy 331.274032 7.108777) (xy 331.312254 7.185537)
			(xy 331.357395 7.258443) (xy 331.409071 7.326872) (xy 331.46684 7.390242) (xy 331.53021 7.448011)
			(xy 331.598639 7.499687) (xy 331.671545 7.544828) (xy 331.748305 7.58305) (xy 331.828264 7.614026)
			(xy 331.91074 7.637493) (xy 331.99503 7.653249) (xy 332.080413 7.661161) (xy 332.166163 7.661161)
			(xy 332.251546 7.653249) (xy 332.335836 7.637493) (xy 332.418312 7.614026) (xy 332.498271 7.58305)
			(xy 332.575031 7.544828) (xy 332.647937 7.499687) (xy 332.716366 7.448011) (xy 332.779736 7.390242)
			(xy 332.837505 7.326872) (xy 332.889181 7.258443) (xy 332.934322 7.185537) (xy 332.972544 7.108777)
			(xy 333.00352 7.028818) (xy 333.026987 6.946342) (xy 333.042743 6.862052) (xy 333.050655 6.776669)
			(xy 333.05115 6.733794) (xy 333.050655 6.690919) (xy 335.488267 6.690919) (xy 335.488267 6.776669)
			(xy 335.496179 6.862052) (xy 335.511935 6.946342) (xy 335.535402 7.028818) (xy 335.566378 7.108777)
			(xy 335.6046 7.185537) (xy 335.649741 7.258443) (xy 335.701417 7.326872) (xy 335.759186 7.390242)
			(xy 335.822556 7.448011) (xy 335.890985 7.499687) (xy 335.963891 7.544828) (xy 336.040651 7.58305)
			(xy 336.12061 7.614026) (xy 336.203086 7.637493) (xy 336.287376 7.653249) (xy 336.372759 7.661161)
			(xy 336.458509 7.661161) (xy 336.543892 7.653249) (xy 336.628182 7.637493) (xy 336.710658 7.614026)
			(xy 336.790617 7.58305) (xy 336.81282 7.571994) (xy 340.4235 7.571994) (xy 340.4235 8.435594) (xy 340.423986 8.462845)
			(xy 340.431742 8.516793) (xy 340.447097 8.569088) (xy 340.469739 8.618665) (xy 340.499205 8.664515)
			(xy 340.534896 8.705706) (xy 340.576087 8.741397) (xy 340.621937 8.770863) (xy 340.671514 8.793505)
			(xy 340.723809 8.80886) (xy 340.777757 8.816616) (xy 340.832259 8.816616) (xy 340.886207 8.80886)
			(xy 340.938502 8.793505) (xy 340.988079 8.770863) (xy 341.033929 8.741397) (xy 341.07512 8.705706)
			(xy 341.110811 8.664515) (xy 341.140277 8.618665) (xy 341.162919 8.569088) (xy 341.178274 8.516793)
			(xy 341.18603 8.462845) (xy 341.186516 8.435594) (xy 341.186516 7.571994) (xy 341.18603 7.544743)
			(xy 341.178274 7.490795) (xy 341.162919 7.4385) (xy 341.140277 7.388923) (xy 341.110811 7.343073)
			(xy 341.07512 7.301882) (xy 341.033929 7.266191) (xy 340.988079 7.236725) (xy 340.938502 7.214083)
			(xy 340.886207 7.198728) (xy 340.832259 7.190972) (xy 340.777757 7.190972) (xy 340.723809 7.198728)
			(xy 340.671514 7.214083) (xy 340.621937 7.236725) (xy 340.576087 7.266191) (xy 340.534896 7.301882)
			(xy 340.499205 7.343073) (xy 340.469739 7.388923) (xy 340.447097 7.4385) (xy 340.431742 7.490795)
			(xy 340.423986 7.544743) (xy 340.4235 7.571994) (xy 336.81282 7.571994) (xy 336.867377 7.544828)
			(xy 336.940283 7.499687) (xy 337.008712 7.448011) (xy 337.072082 7.390242) (xy 337.129851 7.326872)
			(xy 337.181527 7.258443) (xy 337.226668 7.185537) (xy 337.26489 7.108777) (xy 337.295866 7.028818)
			(xy 337.319333 6.946342) (xy 337.335089 6.862052) (xy 337.343001 6.776669) (xy 337.343496 6.733794)
			(xy 337.343001 6.690919) (xy 341.838267 6.690919) (xy 341.838267 6.776669) (xy 341.846179 6.862052)
			(xy 341.861935 6.946342) (xy 341.885402 7.028818) (xy 341.916378 7.108777) (xy 341.9546 7.185537)
			(xy 341.999741 7.258443) (xy 342.051417 7.326872) (xy 342.109186 7.390242) (xy 342.172556 7.448011)
			(xy 342.240985 7.499687) (xy 342.313891 7.544828) (xy 342.390651 7.58305) (xy 342.47061 7.614026)
			(xy 342.553086 7.637493) (xy 342.637376 7.653249) (xy 342.722759 7.661161) (xy 342.808509 7.661161)
			(xy 342.893892 7.653249) (xy 342.978182 7.637493) (xy 343.060658 7.614026) (xy 343.140617 7.58305)
			(xy 343.217377 7.544828) (xy 343.290283 7.499687) (xy 343.358712 7.448011) (xy 343.422082 7.390242)
			(xy 343.479851 7.326872) (xy 343.531527 7.258443) (xy 343.576668 7.185537) (xy 343.61489 7.108777)
			(xy 343.645866 7.028818) (xy 343.669333 6.946342) (xy 343.685089 6.862052) (xy 343.693001 6.776669)
			(xy 343.693496 6.733794) (xy 343.693001 6.690919) (xy 373.705107 6.690919) (xy 373.705107 6.776669)
			(xy 373.713019 6.862052) (xy 373.728775 6.946342) (xy 373.752242 7.028818) (xy 373.783218 7.108777)
			(xy 373.82144 7.185537) (xy 373.866581 7.258443) (xy 373.918257 7.326872) (xy 373.976026 7.390242)
			(xy 374.039396 7.448011) (xy 374.107825 7.499687) (xy 374.180731 7.544828) (xy 374.257491 7.58305)
			(xy 374.33745 7.614026) (xy 374.419926 7.637493) (xy 374.504216 7.653249) (xy 374.589599 7.661161)
			(xy 374.675349 7.661161) (xy 374.760732 7.653249) (xy 374.845022 7.637493) (xy 374.927498 7.614026)
			(xy 375.007457 7.58305) (xy 375.02966 7.571994) (xy 376.211592 7.571994) (xy 376.211592 8.435594)
			(xy 376.212078 8.462845) (xy 376.219834 8.516793) (xy 376.235189 8.569088) (xy 376.257831 8.618665)
			(xy 376.287297 8.664515) (xy 376.322988 8.705706) (xy 376.364179 8.741397) (xy 376.410029 8.770863)
			(xy 376.459606 8.793505) (xy 376.511901 8.80886) (xy 376.565849 8.816616) (xy 376.620351 8.816616)
			(xy 376.674299 8.80886) (xy 376.726594 8.793505) (xy 376.776171 8.770863) (xy 376.822021 8.741397)
			(xy 376.863212 8.705706) (xy 376.898903 8.664515) (xy 376.928369 8.618665) (xy 376.951011 8.569088)
			(xy 376.966366 8.516793) (xy 376.974122 8.462845) (xy 376.974608 8.435594) (xy 376.974608 7.571994)
			(xy 376.974122 7.544743) (xy 376.966366 7.490795) (xy 376.951011 7.4385) (xy 376.928369 7.388923)
			(xy 376.898903 7.343073) (xy 376.863212 7.301882) (xy 376.822021 7.266191) (xy 376.776171 7.236725)
			(xy 376.726594 7.214083) (xy 376.674299 7.198728) (xy 376.620351 7.190972) (xy 376.565849 7.190972)
			(xy 376.511901 7.198728) (xy 376.459606 7.214083) (xy 376.410029 7.236725) (xy 376.364179 7.266191)
			(xy 376.322988 7.301882) (xy 376.287297 7.343073) (xy 376.257831 7.388923) (xy 376.235189 7.4385)
			(xy 376.219834 7.490795) (xy 376.212078 7.544743) (xy 376.211592 7.571994) (xy 375.02966 7.571994)
			(xy 375.084217 7.544828) (xy 375.157123 7.499687) (xy 375.225552 7.448011) (xy 375.288922 7.390242)
			(xy 375.346691 7.326872) (xy 375.398367 7.258443) (xy 375.443508 7.185537) (xy 375.48173 7.108777)
			(xy 375.512706 7.028818) (xy 375.536173 6.946342) (xy 375.551929 6.862052) (xy 375.559841 6.776669)
			(xy 375.560336 6.733794) (xy 375.559841 6.690919) (xy 380.055107 6.690919) (xy 380.055107 6.776669)
			(xy 380.063019 6.862052) (xy 380.078775 6.946342) (xy 380.102242 7.028818) (xy 380.133218 7.108777)
			(xy 380.17144 7.185537) (xy 380.216581 7.258443) (xy 380.268257 7.326872) (xy 380.326026 7.390242)
			(xy 380.389396 7.448011) (xy 380.457825 7.499687) (xy 380.530731 7.544828) (xy 380.607491 7.58305)
			(xy 380.68745 7.614026) (xy 380.769926 7.637493) (xy 380.854216 7.653249) (xy 380.939599 7.661161)
			(xy 381.025349 7.661161) (xy 381.110732 7.653249) (xy 381.195022 7.637493) (xy 381.277498 7.614026)
			(xy 381.357457 7.58305) (xy 381.434217 7.544828) (xy 381.507123 7.499687) (xy 381.575552 7.448011)
			(xy 381.638922 7.390242) (xy 381.688857 7.335466) (xy 464.704165 7.335466) (xy 464.704165 7.464606)
			(xy 464.712115 7.593501) (xy 464.727985 7.721661) (xy 464.751714 7.848602) (xy 464.783213 7.973841)
			(xy 464.822362 8.096904) (xy 464.869013 8.217323) (xy 464.922988 8.334642) (xy 464.984083 8.448416)
			(xy 465.052066 8.558213) (xy 465.12668 8.663616) (xy 465.207641 8.764226) (xy 465.294641 8.859661)
			(xy 465.387352 8.94956) (xy 465.485422 9.033581) (xy 465.588477 9.111405) (xy 465.696128 9.182737)
			(xy 465.807967 9.247307) (xy 465.923568 9.304869) (xy 466.042493 9.355206) (xy 466.164292 9.398126)
			(xy 466.288502 9.433467) (xy 466.414651 9.461094) (xy 466.542263 9.480903) (xy 466.670852 9.492819)
			(xy 466.79993 9.496796) (xy 466.929008 9.492819) (xy 467.057597 9.480903) (xy 467.185209 9.461094)
			(xy 467.311358 9.433467) (xy 467.435568 9.398126) (xy 467.557367 9.355206) (xy 467.676292 9.304869)
			(xy 467.791893 9.247307) (xy 467.903732 9.182737) (xy 468.011383 9.111405) (xy 468.114438 9.033581)
			(xy 468.212508 8.94956) (xy 468.305219 8.859661) (xy 468.392219 8.764226) (xy 468.47318 8.663616)
			(xy 468.547794 8.558213) (xy 468.615777 8.448416) (xy 468.676872 8.334642) (xy 468.730847 8.217323)
			(xy 468.777498 8.096904) (xy 468.816647 7.973841) (xy 468.848146 7.848602) (xy 468.871875 7.721661)
			(xy 468.887745 7.593501) (xy 468.895695 7.464606) (xy 468.896192 7.400036) (xy 468.895695 7.335466)
			(xy 468.887745 7.206571) (xy 468.871875 7.078411) (xy 468.848146 6.95147) (xy 468.816647 6.826231)
			(xy 468.777498 6.703168) (xy 468.730847 6.582749) (xy 468.676872 6.46543) (xy 468.615777 6.351656)
			(xy 468.547794 6.241859) (xy 468.47318 6.136456) (xy 468.392219 6.035846) (xy 468.305219 5.940411)
			(xy 468.212508 5.850512) (xy 468.114438 5.766491) (xy 468.011383 5.688667) (xy 467.903732 5.617335)
			(xy 467.791893 5.552765) (xy 467.676292 5.495203) (xy 467.557367 5.444866) (xy 467.435568 5.401946)
			(xy 467.311358 5.366605) (xy 467.185209 5.338978) (xy 467.057597 5.319169) (xy 466.929008 5.307253)
			(xy 466.79993 5.303277) (xy 466.670852 5.307253) (xy 466.542263 5.319169) (xy 466.414651 5.338978)
			(xy 466.288502 5.366605) (xy 466.164292 5.401946) (xy 466.042493 5.444866) (xy 465.923568 5.495203)
			(xy 465.807967 5.552765) (xy 465.696128 5.617335) (xy 465.588477 5.688667) (xy 465.485422 5.766491)
			(xy 465.387352 5.850512) (xy 465.294641 5.940411) (xy 465.207641 6.035846) (xy 465.12668 6.136456)
			(xy 465.052066 6.241859) (xy 464.984083 6.351656) (xy 464.922988 6.46543) (xy 464.869013 6.582749)
			(xy 464.822362 6.703168) (xy 464.783213 6.826231) (xy 464.751714 6.95147) (xy 464.727985 7.078411)
			(xy 464.712115 7.206571) (xy 464.704165 7.335466) (xy 381.688857 7.335466) (xy 381.696691 7.326872)
			(xy 381.748367 7.258443) (xy 381.793508 7.185537) (xy 381.83173 7.108777) (xy 381.862706 7.028818)
			(xy 381.886173 6.946342) (xy 381.901929 6.862052) (xy 381.909841 6.776669) (xy 381.910336 6.733794)
			(xy 381.909841 6.690919) (xy 381.901929 6.605536) (xy 381.886173 6.521246) (xy 381.862706 6.43877)
			(xy 381.83173 6.358811) (xy 381.793508 6.282051) (xy 381.748367 6.209145) (xy 381.696691 6.140716)
			(xy 381.638922 6.077346) (xy 381.575552 6.019577) (xy 381.507123 5.967901) (xy 381.434217 5.92276)
			(xy 381.357457 5.884538) (xy 381.277498 5.853562) (xy 381.195022 5.830095) (xy 381.110732 5.814339)
			(xy 381.025349 5.806427) (xy 380.939599 5.806427) (xy 380.854216 5.814339) (xy 380.769926 5.830095)
			(xy 380.68745 5.853562) (xy 380.607491 5.884538) (xy 380.530731 5.92276) (xy 380.457825 5.967901)
			(xy 380.389396 6.019577) (xy 380.326026 6.077346) (xy 380.268257 6.140716) (xy 380.216581 6.209145)
			(xy 380.17144 6.282051) (xy 380.133218 6.358811) (xy 380.102242 6.43877) (xy 380.078775 6.521246)
			(xy 380.063019 6.605536) (xy 380.055107 6.690919) (xy 375.559841 6.690919) (xy 375.551929 6.605536)
			(xy 375.536173 6.521246) (xy 375.512706 6.43877) (xy 375.48173 6.358811) (xy 375.443508 6.282051)
			(xy 375.398367 6.209145) (xy 375.346691 6.140716) (xy 375.288922 6.077346) (xy 375.225552 6.019577)
			(xy 375.157123 5.967901) (xy 375.084217 5.92276) (xy 375.007457 5.884538) (xy 374.927498 5.853562)
			(xy 374.845022 5.830095) (xy 374.760732 5.814339) (xy 374.675349 5.806427) (xy 374.589599 5.806427)
			(xy 374.504216 5.814339) (xy 374.419926 5.830095) (xy 374.33745 5.853562) (xy 374.257491 5.884538)
			(xy 374.180731 5.92276) (xy 374.107825 5.967901) (xy 374.039396 6.019577) (xy 373.976026 6.077346)
			(xy 373.918257 6.140716) (xy 373.866581 6.209145) (xy 373.82144 6.282051) (xy 373.783218 6.358811)
			(xy 373.752242 6.43877) (xy 373.728775 6.521246) (xy 373.713019 6.605536) (xy 373.705107 6.690919)
			(xy 343.693001 6.690919) (xy 343.685089 6.605536) (xy 343.669333 6.521246) (xy 343.645866 6.43877)
			(xy 343.61489 6.358811) (xy 343.576668 6.282051) (xy 343.531527 6.209145) (xy 343.479851 6.140716)
			(xy 343.422082 6.077346) (xy 343.358712 6.019577) (xy 343.290283 5.967901) (xy 343.217377 5.92276)
			(xy 343.140617 5.884538) (xy 343.060658 5.853562) (xy 342.978182 5.830095) (xy 342.893892 5.814339)
			(xy 342.808509 5.806427) (xy 342.722759 5.806427) (xy 342.637376 5.814339) (xy 342.553086 5.830095)
			(xy 342.47061 5.853562) (xy 342.390651 5.884538) (xy 342.313891 5.92276) (xy 342.240985 5.967901)
			(xy 342.172556 6.019577) (xy 342.109186 6.077346) (xy 342.051417 6.140716) (xy 341.999741 6.209145)
			(xy 341.9546 6.282051) (xy 341.916378 6.358811) (xy 341.885402 6.43877) (xy 341.861935 6.521246)
			(xy 341.846179 6.605536) (xy 341.838267 6.690919) (xy 337.343001 6.690919) (xy 337.335089 6.605536)
			(xy 337.319333 6.521246) (xy 337.295866 6.43877) (xy 337.26489 6.358811) (xy 337.226668 6.282051)
			(xy 337.181527 6.209145) (xy 337.129851 6.140716) (xy 337.072082 6.077346) (xy 337.008712 6.019577)
			(xy 336.940283 5.967901) (xy 336.867377 5.92276) (xy 336.790617 5.884538) (xy 336.710658 5.853562)
			(xy 336.628182 5.830095) (xy 336.543892 5.814339) (xy 336.458509 5.806427) (xy 336.372759 5.806427)
			(xy 336.287376 5.814339) (xy 336.203086 5.830095) (xy 336.12061 5.853562) (xy 336.040651 5.884538)
			(xy 335.963891 5.92276) (xy 335.890985 5.967901) (xy 335.822556 6.019577) (xy 335.759186 6.077346)
			(xy 335.701417 6.140716) (xy 335.649741 6.209145) (xy 335.6046 6.282051) (xy 335.566378 6.358811)
			(xy 335.535402 6.43877) (xy 335.511935 6.521246) (xy 335.496179 6.605536) (xy 335.488267 6.690919)
			(xy 333.050655 6.690919) (xy 333.042743 6.605536) (xy 333.026987 6.521246) (xy 333.00352 6.43877)
			(xy 332.972544 6.358811) (xy 332.934322 6.282051) (xy 332.889181 6.209145) (xy 332.837505 6.140716)
			(xy 332.779736 6.077346) (xy 332.716366 6.019577) (xy 332.647937 5.967901) (xy 332.575031 5.92276)
			(xy 332.498271 5.884538) (xy 332.418312 5.853562) (xy 332.335836 5.830095) (xy 332.251546 5.814339)
			(xy 332.166163 5.806427) (xy 332.080413 5.806427) (xy 331.99503 5.814339) (xy 331.91074 5.830095)
			(xy 331.828264 5.853562) (xy 331.748305 5.884538) (xy 331.671545 5.92276) (xy 331.598639 5.967901)
			(xy 331.53021 6.019577) (xy 331.46684 6.077346) (xy 331.409071 6.140716) (xy 331.357395 6.209145)
			(xy 331.312254 6.282051) (xy 331.274032 6.358811) (xy 331.243056 6.43877) (xy 331.219589 6.521246)
			(xy 331.203833 6.605536) (xy 331.195921 6.690919) (xy 326.700655 6.690919) (xy 326.692743 6.605536)
			(xy 326.676987 6.521246) (xy 326.65352 6.43877) (xy 326.622544 6.358811) (xy 326.584322 6.282051)
			(xy 326.539181 6.209145) (xy 326.487505 6.140716) (xy 326.429736 6.077346) (xy 326.366366 6.019577)
			(xy 326.297937 5.967901) (xy 326.225031 5.92276) (xy 326.148271 5.884538) (xy 326.068312 5.853562)
			(xy 325.985836 5.830095) (xy 325.901546 5.814339) (xy 325.816163 5.806427) (xy 325.730413 5.806427)
			(xy 325.64503 5.814339) (xy 325.56074 5.830095) (xy 325.478264 5.853562) (xy 325.398305 5.884538)
			(xy 325.321545 5.92276) (xy 325.248639 5.967901) (xy 325.18021 6.019577) (xy 325.11684 6.077346)
			(xy 325.059071 6.140716) (xy 325.007395 6.209145) (xy 324.962254 6.282051) (xy 324.924032 6.358811)
			(xy 324.893056 6.43877) (xy 324.869589 6.521246) (xy 324.853833 6.605536) (xy 324.845921 6.690919)
			(xy 265.125975 6.690919) (xy 265.118063 6.605536) (xy 265.102307 6.521246) (xy 265.07884 6.43877)
			(xy 265.047864 6.358811) (xy 265.009642 6.282051) (xy 264.964501 6.209145) (xy 264.912825 6.140716)
			(xy 264.855056 6.077346) (xy 264.791686 6.019577) (xy 264.723257 5.967901) (xy 264.650351 5.92276)
			(xy 264.573591 5.884538) (xy 264.493632 5.853562) (xy 264.411156 5.830095) (xy 264.326866 5.814339)
			(xy 264.241483 5.806427) (xy 264.155733 5.806427) (xy 264.07035 5.814339) (xy 263.98606 5.830095)
			(xy 263.903584 5.853562) (xy 263.823625 5.884538) (xy 263.746865 5.92276) (xy 263.673959 5.967901)
			(xy 263.60553 6.019577) (xy 263.54216 6.077346) (xy 263.484391 6.140716) (xy 263.432715 6.209145)
			(xy 263.387574 6.282051) (xy 263.349352 6.358811) (xy 263.318376 6.43877) (xy 263.294909 6.521246)
			(xy 263.279153 6.605536) (xy 263.271241 6.690919) (xy 258.775975 6.690919) (xy 258.768063 6.605536)
			(xy 258.752307 6.521246) (xy 258.72884 6.43877) (xy 258.697864 6.358811) (xy 258.659642 6.282051)
			(xy 258.614501 6.209145) (xy 258.562825 6.140716) (xy 258.505056 6.077346) (xy 258.441686 6.019577)
			(xy 258.373257 5.967901) (xy 258.300351 5.92276) (xy 258.223591 5.884538) (xy 258.143632 5.853562)
			(xy 258.061156 5.830095) (xy 257.976866 5.814339) (xy 257.891483 5.806427) (xy 257.805733 5.806427)
			(xy 257.72035 5.814339) (xy 257.63606 5.830095) (xy 257.553584 5.853562) (xy 257.473625 5.884538)
			(xy 257.396865 5.92276) (xy 257.323959 5.967901) (xy 257.25553 6.019577) (xy 257.19216 6.077346)
			(xy 257.134391 6.140716) (xy 257.082715 6.209145) (xy 257.037574 6.282051) (xy 256.999352 6.358811)
			(xy 256.968376 6.43877) (xy 256.944909 6.521246) (xy 256.929153 6.605536) (xy 256.921241 6.690919)
			(xy 254.465119 6.690919) (xy 254.465087 6.688125) (xy 254.457175 6.602742) (xy 254.441419 6.518452)
			(xy 254.417952 6.435976) (xy 254.386976 6.356017) (xy 254.348754 6.279257) (xy 254.303613 6.206351)
			(xy 254.251937 6.137922) (xy 254.194168 6.074552) (xy 254.130798 6.016783) (xy 254.062369 5.965107)
			(xy 253.989463 5.919966) (xy 253.912703 5.881744) (xy 253.832744 5.850768) (xy 253.750268 5.827301)
			(xy 253.665978 5.811545) (xy 253.580595 5.803633) (xy 253.494845 5.803633) (xy 253.409462 5.811545)
			(xy 253.325172 5.827301) (xy 253.242696 5.850768) (xy 253.162737 5.881744) (xy 253.085977 5.919966)
			(xy 253.013071 5.965107) (xy 252.944642 6.016783) (xy 252.881272 6.074552) (xy 252.823503 6.137922)
			(xy 252.771827 6.206351) (xy 252.726686 6.279257) (xy 252.688464 6.356017) (xy 252.657488 6.435976)
			(xy 252.634021 6.518452) (xy 252.618265 6.602742) (xy 252.610353 6.688125) (xy 248.115087 6.688125)
			(xy 248.107175 6.602742) (xy 248.091419 6.518452) (xy 248.067952 6.435976) (xy 248.036976 6.356017)
			(xy 247.998754 6.279257) (xy 247.953613 6.206351) (xy 247.901937 6.137922) (xy 247.844168 6.074552)
			(xy 247.780798 6.016783) (xy 247.712369 5.965107) (xy 247.639463 5.919966) (xy 247.562703 5.881744)
			(xy 247.482744 5.850768) (xy 247.400268 5.827301) (xy 247.315978 5.811545) (xy 247.230595 5.803633)
			(xy 247.144845 5.803633) (xy 247.059462 5.811545) (xy 246.975172 5.827301) (xy 246.892696 5.850768)
			(xy 246.812737 5.881744) (xy 246.735977 5.919966) (xy 246.663071 5.965107) (xy 246.594642 6.016783)
			(xy 246.531272 6.074552) (xy 246.473503 6.137922) (xy 246.421827 6.206351) (xy 246.376686 6.279257)
			(xy 246.338464 6.356017) (xy 246.307488 6.435976) (xy 246.284021 6.518452) (xy 246.268265 6.602742)
			(xy 246.260353 6.688125) (xy 186.540407 6.688125) (xy 186.532495 6.602742) (xy 186.516739 6.518452)
			(xy 186.493272 6.435976) (xy 186.462296 6.356017) (xy 186.424074 6.279257) (xy 186.378933 6.206351)
			(xy 186.327257 6.137922) (xy 186.269488 6.074552) (xy 186.206118 6.016783) (xy 186.137689 5.965107)
			(xy 186.064783 5.919966) (xy 185.988023 5.881744) (xy 185.908064 5.850768) (xy 185.825588 5.827301)
			(xy 185.741298 5.811545) (xy 185.655915 5.803633) (xy 185.570165 5.803633) (xy 185.484782 5.811545)
			(xy 185.400492 5.827301) (xy 185.318016 5.850768) (xy 185.238057 5.881744) (xy 185.161297 5.919966)
			(xy 185.088391 5.965107) (xy 185.019962 6.016783) (xy 184.956592 6.074552) (xy 184.898823 6.137922)
			(xy 184.847147 6.206351) (xy 184.802006 6.279257) (xy 184.763784 6.356017) (xy 184.732808 6.435976)
			(xy 184.709341 6.518452) (xy 184.693585 6.602742) (xy 184.685673 6.688125) (xy 180.190407 6.688125)
			(xy 180.182495 6.602742) (xy 180.166739 6.518452) (xy 180.143272 6.435976) (xy 180.112296 6.356017)
			(xy 180.074074 6.279257) (xy 180.028933 6.206351) (xy 179.977257 6.137922) (xy 179.919488 6.074552)
			(xy 179.856118 6.016783) (xy 179.787689 5.965107) (xy 179.714783 5.919966) (xy 179.638023 5.881744)
			(xy 179.558064 5.850768) (xy 179.475588 5.827301) (xy 179.391298 5.811545) (xy 179.305915 5.803633)
			(xy 179.220165 5.803633) (xy 179.134782 5.811545) (xy 179.050492 5.827301) (xy 178.968016 5.850768)
			(xy 178.888057 5.881744) (xy 178.811297 5.919966) (xy 178.738391 5.965107) (xy 178.669962 6.016783)
			(xy 178.606592 6.074552) (xy 178.548823 6.137922) (xy 178.497147 6.206351) (xy 178.452006 6.279257)
			(xy 178.413784 6.356017) (xy 178.382808 6.435976) (xy 178.359341 6.518452) (xy 178.343585 6.602742)
			(xy 178.335673 6.688125) (xy 6.97173 6.688125) (xy 6.930907 6.582749) (xy 6.876932 6.46543) (xy 6.815837 6.351656)
			(xy 6.747854 6.241859) (xy 6.67324 6.136456) (xy 6.592279 6.035846) (xy 6.505279 5.940411) (xy 6.412568 5.850512)
			(xy 6.314498 5.766491) (xy 6.211443 5.688667) (xy 6.103792 5.617335) (xy 5.991953 5.552765) (xy 5.876352 5.495203)
			(xy 5.757427 5.444866) (xy 5.635628 5.401946) (xy 5.511418 5.366605) (xy 5.385269 5.338978) (xy 5.257657 5.319169)
			(xy 5.129068 5.307253) (xy 4.99999 5.303277) (xy 4.870912 5.307253) (xy 4.742323 5.319169) (xy 4.614711 5.338978)
			(xy 4.488562 5.366605) (xy 4.364352 5.401946) (xy 4.242553 5.444866) (xy 4.123628 5.495203) (xy 4.008027 5.552765)
			(xy 3.896188 5.617335) (xy 3.788537 5.688667) (xy 3.685482 5.766491) (xy 3.587412 5.850512) (xy 3.494701 5.940411)
			(xy 3.407701 6.035846) (xy 3.32674 6.136456) (xy 3.252126 6.241859) (xy 3.184143 6.351656) (xy 3.123048 6.46543)
			(xy 3.069073 6.582749) (xy 3.022422 6.703168) (xy 2.983273 6.826231) (xy 2.951774 6.95147) (xy 2.928045 7.078411)
			(xy 2.912175 7.206571) (xy 2.904225 7.335466) (xy 0.508 7.335466) (xy 0.508 4.148125) (xy 178.335673 4.148125)
			(xy 178.335673 4.233875) (xy 178.343585 4.319258) (xy 178.359341 4.403548) (xy 178.382808 4.486024)
			(xy 178.413784 4.565983) (xy 178.452006 4.642743) (xy 178.497147 4.715649) (xy 178.548823 4.784078)
			(xy 178.606592 4.847448) (xy 178.669962 4.905217) (xy 178.738391 4.956893) (xy 178.811297 5.002034)
			(xy 178.888057 5.040256) (xy 178.968016 5.071232) (xy 179.050492 5.094699) (xy 179.134782 5.110455)
			(xy 179.220165 5.118367) (xy 179.305915 5.118367) (xy 179.391298 5.110455) (xy 179.475588 5.094699)
			(xy 179.558064 5.071232) (xy 179.638023 5.040256) (xy 179.660226 5.0292) (xy 183.270652 5.0292) (xy 183.270652 5.8928)
			(xy 183.271138 5.920069) (xy 183.2789 5.974053) (xy 183.294265 6.026383) (xy 183.316922 6.075993)
			(xy 183.346408 6.121874) (xy 183.382123 6.163091) (xy 183.42334 6.198806) (xy 183.469221 6.228292)
			(xy 183.518831 6.250949) (xy 183.571161 6.266314) (xy 183.625145 6.274076) (xy 183.679683 6.274076)
			(xy 183.733667 6.266314) (xy 183.785997 6.250949) (xy 183.835607 6.228292) (xy 183.881488 6.198806)
			(xy 183.922705 6.163091) (xy 183.95842 6.121874) (xy 183.987906 6.075993) (xy 184.010563 6.026383)
			(xy 184.025928 5.974053) (xy 184.03369 5.920069) (xy 184.034176 5.8928) (xy 184.034176 5.0292) (xy 184.03369 5.001931)
			(xy 184.025928 4.947947) (xy 184.010563 4.895617) (xy 183.987906 4.846007) (xy 183.95842 4.800126)
			(xy 183.922705 4.758909) (xy 183.881488 4.723194) (xy 183.835607 4.693708) (xy 183.785997 4.671051)
			(xy 183.733667 4.655686) (xy 183.679683 4.647924) (xy 183.625145 4.647924) (xy 183.571161 4.655686)
			(xy 183.518831 4.671051) (xy 183.469221 4.693708) (xy 183.42334 4.723194) (xy 183.382123 4.758909)
			(xy 183.346408 4.800126) (xy 183.316922 4.846007) (xy 183.294265 4.895617) (xy 183.2789 4.947947)
			(xy 183.271138 5.001931) (xy 183.270652 5.0292) (xy 179.660226 5.0292) (xy 179.714783 5.002034) (xy 179.787689 4.956893)
			(xy 179.856118 4.905217) (xy 179.919488 4.847448) (xy 179.977257 4.784078) (xy 180.028933 4.715649)
			(xy 180.074074 4.642743) (xy 180.112296 4.565983) (xy 180.143272 4.486024) (xy 180.166739 4.403548)
			(xy 180.182495 4.319258) (xy 180.190407 4.233875) (xy 180.190902 4.191) (xy 180.190407 4.148125)
			(xy 184.685673 4.148125) (xy 184.685673 4.233875) (xy 184.693585 4.319258) (xy 184.709341 4.403548)
			(xy 184.732808 4.486024) (xy 184.763784 4.565983) (xy 184.802006 4.642743) (xy 184.847147 4.715649)
			(xy 184.898823 4.784078) (xy 184.956592 4.847448) (xy 185.019962 4.905217) (xy 185.088391 4.956893)
			(xy 185.161297 5.002034) (xy 185.238057 5.040256) (xy 185.318016 5.071232) (xy 185.400492 5.094699)
			(xy 185.484782 5.110455) (xy 185.570165 5.118367) (xy 185.655915 5.118367) (xy 185.741298 5.110455)
			(xy 185.825588 5.094699) (xy 185.908064 5.071232) (xy 185.988023 5.040256) (xy 186.064783 5.002034)
			(xy 186.137689 4.956893) (xy 186.206118 4.905217) (xy 186.269488 4.847448) (xy 186.327257 4.784078)
			(xy 186.378933 4.715649) (xy 186.424074 4.642743) (xy 186.462296 4.565983) (xy 186.493272 4.486024)
			(xy 186.516739 4.403548) (xy 186.532495 4.319258) (xy 186.540407 4.233875) (xy 186.540902 4.191)
			(xy 186.540407 4.148125) (xy 246.260353 4.148125) (xy 246.260353 4.233875) (xy 246.268265 4.319258)
			(xy 246.284021 4.403548) (xy 246.307488 4.486024) (xy 246.338464 4.565983) (xy 246.376686 4.642743)
			(xy 246.421827 4.715649) (xy 246.473503 4.784078) (xy 246.531272 4.847448) (xy 246.594642 4.905217)
			(xy 246.663071 4.956893) (xy 246.735977 5.002034) (xy 246.812737 5.040256) (xy 246.892696 5.071232)
			(xy 246.975172 5.094699) (xy 247.059462 5.110455) (xy 247.144845 5.118367) (xy 247.230595 5.118367)
			(xy 247.315978 5.110455) (xy 247.400268 5.094699) (xy 247.482744 5.071232) (xy 247.562703 5.040256)
			(xy 247.584906 5.0292) (xy 248.766584 5.0292) (xy 248.766584 5.8928) (xy 248.76707 5.920069) (xy 248.774832 5.974053)
			(xy 248.790197 6.026383) (xy 248.812854 6.075993) (xy 248.84234 6.121874) (xy 248.878055 6.163091)
			(xy 248.919272 6.198806) (xy 248.965153 6.228292) (xy 249.014763 6.250949) (xy 249.067093 6.266314)
			(xy 249.121077 6.274076) (xy 249.175615 6.274076) (xy 249.229599 6.266314) (xy 249.281929 6.250949)
			(xy 249.331539 6.228292) (xy 249.37742 6.198806) (xy 249.418637 6.163091) (xy 249.454352 6.121874)
			(xy 249.483838 6.075993) (xy 249.506495 6.026383) (xy 249.52186 5.974053) (xy 249.529622 5.920069)
			(xy 249.530108 5.8928) (xy 249.530108 5.0292) (xy 249.529622 5.001931) (xy 249.52186 4.947947) (xy 249.506495 4.895617)
			(xy 249.483838 4.846007) (xy 249.454352 4.800126) (xy 249.418637 4.758909) (xy 249.37742 4.723194)
			(xy 249.331539 4.693708) (xy 249.281929 4.671051) (xy 249.229599 4.655686) (xy 249.175615 4.647924)
			(xy 249.121077 4.647924) (xy 249.067093 4.655686) (xy 249.014763 4.671051) (xy 248.965153 4.693708)
			(xy 248.919272 4.723194) (xy 248.878055 4.758909) (xy 248.84234 4.800126) (xy 248.812854 4.846007)
			(xy 248.790197 4.895617) (xy 248.774832 4.947947) (xy 248.76707 5.001931) (xy 248.766584 5.0292)
			(xy 247.584906 5.0292) (xy 247.639463 5.002034) (xy 247.712369 4.956893) (xy 247.780798 4.905217)
			(xy 247.844168 4.847448) (xy 247.901937 4.784078) (xy 247.953613 4.715649) (xy 247.998754 4.642743)
			(xy 248.036976 4.565983) (xy 248.067952 4.486024) (xy 248.091419 4.403548) (xy 248.107175 4.319258)
			(xy 248.115087 4.233875) (xy 248.115582 4.191) (xy 248.115087 4.148125) (xy 252.610353 4.148125)
			(xy 252.610353 4.233875) (xy 252.618265 4.319258) (xy 252.634021 4.403548) (xy 252.657488 4.486024)
			(xy 252.688464 4.565983) (xy 252.726686 4.642743) (xy 252.771827 4.715649) (xy 252.823503 4.784078)
			(xy 252.881272 4.847448) (xy 252.944642 4.905217) (xy 253.013071 4.956893) (xy 253.085977 5.002034)
			(xy 253.162737 5.040256) (xy 253.242696 5.071232) (xy 253.325172 5.094699) (xy 253.409462 5.110455)
			(xy 253.494845 5.118367) (xy 253.580595 5.118367) (xy 253.665978 5.110455) (xy 253.750268 5.094699)
			(xy 253.832744 5.071232) (xy 253.912703 5.040256) (xy 253.989463 5.002034) (xy 254.062369 4.956893)
			(xy 254.130798 4.905217) (xy 254.194168 4.847448) (xy 254.251937 4.784078) (xy 254.303613 4.715649)
			(xy 254.348754 4.642743) (xy 254.386976 4.565983) (xy 254.417952 4.486024) (xy 254.441419 4.403548)
			(xy 254.457175 4.319258) (xy 254.465087 4.233875) (xy 254.465582 4.191) (xy 254.465119 4.150919)
			(xy 256.921241 4.150919) (xy 256.921241 4.236669) (xy 256.929153 4.322052) (xy 256.944909 4.406342)
			(xy 256.968376 4.488818) (xy 256.999352 4.568777) (xy 257.037574 4.645537) (xy 257.082715 4.718443)
			(xy 257.134391 4.786872) (xy 257.19216 4.850242) (xy 257.25553 4.908011) (xy 257.323959 4.959687)
			(xy 257.396865 5.004828) (xy 257.473625 5.04305) (xy 257.553584 5.074026) (xy 257.63606 5.097493)
			(xy 257.72035 5.113249) (xy 257.805733 5.121161) (xy 257.891483 5.121161) (xy 257.976866 5.113249)
			(xy 258.061156 5.097493) (xy 258.143632 5.074026) (xy 258.223591 5.04305) (xy 258.245794 5.031994)
			(xy 261.85622 5.031994) (xy 261.85622 5.895594) (xy 261.856706 5.922863) (xy 261.864468 5.976847)
			(xy 261.879833 6.029177) (xy 261.90249 6.078787) (xy 261.931976 6.124668) (xy 261.967691 6.165885)
			(xy 262.008908 6.2016) (xy 262.054789 6.231086) (xy 262.104399 6.253743) (xy 262.156729 6.269108)
			(xy 262.210713 6.27687) (xy 262.265251 6.27687) (xy 262.319235 6.269108) (xy 262.371565 6.253743)
			(xy 262.421175 6.231086) (xy 262.467056 6.2016) (xy 262.508273 6.165885) (xy 262.543988 6.124668)
			(xy 262.573474 6.078787) (xy 262.596131 6.029177) (xy 262.611496 5.976847) (xy 262.619258 5.922863)
			(xy 262.619744 5.895594) (xy 262.619744 5.031994) (xy 262.619258 5.004725) (xy 262.611496 4.950741)
			(xy 262.596131 4.898411) (xy 262.573474 4.848801) (xy 262.543988 4.80292) (xy 262.508273 4.761703)
			(xy 262.467056 4.725988) (xy 262.421175 4.696502) (xy 262.371565 4.673845) (xy 262.319235 4.65848)
			(xy 262.265251 4.650718) (xy 262.210713 4.650718) (xy 262.156729 4.65848) (xy 262.104399 4.673845)
			(xy 262.054789 4.696502) (xy 262.008908 4.725988) (xy 261.967691 4.761703) (xy 261.931976 4.80292)
			(xy 261.90249 4.848801) (xy 261.879833 4.898411) (xy 261.864468 4.950741) (xy 261.856706 5.004725)
			(xy 261.85622 5.031994) (xy 258.245794 5.031994) (xy 258.300351 5.004828) (xy 258.373257 4.959687)
			(xy 258.441686 4.908011) (xy 258.505056 4.850242) (xy 258.562825 4.786872) (xy 258.614501 4.718443)
			(xy 258.659642 4.645537) (xy 258.697864 4.568777) (xy 258.72884 4.488818) (xy 258.752307 4.406342)
			(xy 258.768063 4.322052) (xy 258.775975 4.236669) (xy 258.77647 4.193794) (xy 258.775975 4.150919)
			(xy 263.271241 4.150919) (xy 263.271241 4.236669) (xy 263.279153 4.322052) (xy 263.294909 4.406342)
			(xy 263.318376 4.488818) (xy 263.349352 4.568777) (xy 263.387574 4.645537) (xy 263.432715 4.718443)
			(xy 263.484391 4.786872) (xy 263.54216 4.850242) (xy 263.60553 4.908011) (xy 263.673959 4.959687)
			(xy 263.746865 5.004828) (xy 263.823625 5.04305) (xy 263.903584 5.074026) (xy 263.98606 5.097493)
			(xy 264.07035 5.113249) (xy 264.155733 5.121161) (xy 264.241483 5.121161) (xy 264.326866 5.113249)
			(xy 264.411156 5.097493) (xy 264.493632 5.074026) (xy 264.573591 5.04305) (xy 264.650351 5.004828)
			(xy 264.723257 4.959687) (xy 264.791686 4.908011) (xy 264.855056 4.850242) (xy 264.912825 4.786872)
			(xy 264.964501 4.718443) (xy 265.009642 4.645537) (xy 265.047864 4.568777) (xy 265.07884 4.488818)
			(xy 265.102307 4.406342) (xy 265.118063 4.322052) (xy 265.125975 4.236669) (xy 265.12647 4.193794)
			(xy 265.125975 4.150919) (xy 324.845921 4.150919) (xy 324.845921 4.236669) (xy 324.853833 4.322052)
			(xy 324.869589 4.406342) (xy 324.893056 4.488818) (xy 324.924032 4.568777) (xy 324.962254 4.645537)
			(xy 325.007395 4.718443) (xy 325.059071 4.786872) (xy 325.11684 4.850242) (xy 325.18021 4.908011)
			(xy 325.248639 4.959687) (xy 325.321545 5.004828) (xy 325.398305 5.04305) (xy 325.478264 5.074026)
			(xy 325.56074 5.097493) (xy 325.64503 5.113249) (xy 325.730413 5.121161) (xy 325.816163 5.121161)
			(xy 325.901546 5.113249) (xy 325.985836 5.097493) (xy 326.068312 5.074026) (xy 326.148271 5.04305)
			(xy 326.170474 5.031994) (xy 327.352152 5.031994) (xy 327.352152 5.895594) (xy 327.352638 5.922863)
			(xy 327.3604 5.976847) (xy 327.375765 6.029177) (xy 327.398422 6.078787) (xy 327.427908 6.124668)
			(xy 327.463623 6.165885) (xy 327.50484 6.2016) (xy 327.550721 6.231086) (xy 327.600331 6.253743)
			(xy 327.652661 6.269108) (xy 327.706645 6.27687) (xy 327.761183 6.27687) (xy 327.815167 6.269108)
			(xy 327.867497 6.253743) (xy 327.917107 6.231086) (xy 327.962988 6.2016) (xy 328.004205 6.165885)
			(xy 328.03992 6.124668) (xy 328.069406 6.078787) (xy 328.092063 6.029177) (xy 328.107428 5.976847)
			(xy 328.11519 5.922863) (xy 328.115676 5.895594) (xy 328.115676 5.031994) (xy 328.11519 5.004725)
			(xy 328.107428 4.950741) (xy 328.092063 4.898411) (xy 328.069406 4.848801) (xy 328.03992 4.80292)
			(xy 328.004205 4.761703) (xy 327.962988 4.725988) (xy 327.917107 4.696502) (xy 327.867497 4.673845)
			(xy 327.815167 4.65848) (xy 327.761183 4.650718) (xy 327.706645 4.650718) (xy 327.652661 4.65848)
			(xy 327.600331 4.673845) (xy 327.550721 4.696502) (xy 327.50484 4.725988) (xy 327.463623 4.761703)
			(xy 327.427908 4.80292) (xy 327.398422 4.848801) (xy 327.375765 4.898411) (xy 327.3604 4.950741)
			(xy 327.352638 5.004725) (xy 327.352152 5.031994) (xy 326.170474 5.031994) (xy 326.225031 5.004828)
			(xy 326.297937 4.959687) (xy 326.366366 4.908011) (xy 326.429736 4.850242) (xy 326.487505 4.786872)
			(xy 326.539181 4.718443) (xy 326.584322 4.645537) (xy 326.622544 4.568777) (xy 326.65352 4.488818)
			(xy 326.676987 4.406342) (xy 326.692743 4.322052) (xy 326.700655 4.236669) (xy 326.70115 4.193794)
			(xy 326.700655 4.150919) (xy 331.195921 4.150919) (xy 331.195921 4.236669) (xy 331.203833 4.322052)
			(xy 331.219589 4.406342) (xy 331.243056 4.488818) (xy 331.274032 4.568777) (xy 331.312254 4.645537)
			(xy 331.357395 4.718443) (xy 331.409071 4.786872) (xy 331.46684 4.850242) (xy 331.53021 4.908011)
			(xy 331.598639 4.959687) (xy 331.671545 5.004828) (xy 331.748305 5.04305) (xy 331.828264 5.074026)
			(xy 331.91074 5.097493) (xy 331.99503 5.113249) (xy 332.080413 5.121161) (xy 332.166163 5.121161)
			(xy 332.251546 5.113249) (xy 332.335836 5.097493) (xy 332.418312 5.074026) (xy 332.498271 5.04305)
			(xy 332.575031 5.004828) (xy 332.647937 4.959687) (xy 332.716366 4.908011) (xy 332.779736 4.850242)
			(xy 332.837505 4.786872) (xy 332.889181 4.718443) (xy 332.934322 4.645537) (xy 332.972544 4.568777)
			(xy 333.00352 4.488818) (xy 333.026987 4.406342) (xy 333.042743 4.322052) (xy 333.050655 4.236669)
			(xy 333.05115 4.193794) (xy 333.050655 4.150919) (xy 335.488267 4.150919) (xy 335.488267 4.236669)
			(xy 335.496179 4.322052) (xy 335.511935 4.406342) (xy 335.535402 4.488818) (xy 335.566378 4.568777)
			(xy 335.6046 4.645537) (xy 335.649741 4.718443) (xy 335.701417 4.786872) (xy 335.759186 4.850242)
			(xy 335.822556 4.908011) (xy 335.890985 4.959687) (xy 335.963891 5.004828) (xy 336.040651 5.04305)
			(xy 336.12061 5.074026) (xy 336.203086 5.097493) (xy 336.287376 5.113249) (xy 336.372759 5.121161)
			(xy 336.458509 5.121161) (xy 336.543892 5.113249) (xy 336.628182 5.097493) (xy 336.710658 5.074026)
			(xy 336.790617 5.04305) (xy 336.81282 5.031994) (xy 340.4235 5.031994) (xy 340.4235 5.895594) (xy 340.423986 5.922845)
			(xy 340.431742 5.976793) (xy 340.447097 6.029088) (xy 340.469739 6.078665) (xy 340.499205 6.124515)
			(xy 340.534896 6.165706) (xy 340.576087 6.201397) (xy 340.621937 6.230863) (xy 340.671514 6.253505)
			(xy 340.723809 6.26886) (xy 340.777757 6.276616) (xy 340.832259 6.276616) (xy 340.886207 6.26886)
			(xy 340.938502 6.253505) (xy 340.988079 6.230863) (xy 341.033929 6.201397) (xy 341.07512 6.165706)
			(xy 341.110811 6.124515) (xy 341.140277 6.078665) (xy 341.162919 6.029088) (xy 341.178274 5.976793)
			(xy 341.18603 5.922845) (xy 341.186516 5.895594) (xy 341.186516 5.031994) (xy 341.18603 5.004743)
			(xy 341.178274 4.950795) (xy 341.162919 4.8985) (xy 341.140277 4.848923) (xy 341.110811 4.803073)
			(xy 341.07512 4.761882) (xy 341.033929 4.726191) (xy 340.988079 4.696725) (xy 340.938502 4.674083)
			(xy 340.886207 4.658728) (xy 340.832259 4.650972) (xy 340.777757 4.650972) (xy 340.723809 4.658728)
			(xy 340.671514 4.674083) (xy 340.621937 4.696725) (xy 340.576087 4.726191) (xy 340.534896 4.761882)
			(xy 340.499205 4.803073) (xy 340.469739 4.848923) (xy 340.447097 4.8985) (xy 340.431742 4.950795)
			(xy 340.423986 5.004743) (xy 340.4235 5.031994) (xy 336.81282 5.031994) (xy 336.867377 5.004828)
			(xy 336.940283 4.959687) (xy 337.008712 4.908011) (xy 337.072082 4.850242) (xy 337.129851 4.786872)
			(xy 337.181527 4.718443) (xy 337.226668 4.645537) (xy 337.26489 4.568777) (xy 337.295866 4.488818)
			(xy 337.319333 4.406342) (xy 337.335089 4.322052) (xy 337.343001 4.236669) (xy 337.343496 4.193794)
			(xy 337.343001 4.150919) (xy 341.838267 4.150919) (xy 341.838267 4.236669) (xy 341.846179 4.322052)
			(xy 341.861935 4.406342) (xy 341.885402 4.488818) (xy 341.916378 4.568777) (xy 341.9546 4.645537)
			(xy 341.999741 4.718443) (xy 342.051417 4.786872) (xy 342.109186 4.850242) (xy 342.172556 4.908011)
			(xy 342.240985 4.959687) (xy 342.313891 5.004828) (xy 342.390651 5.04305) (xy 342.47061 5.074026)
			(xy 342.553086 5.097493) (xy 342.637376 5.113249) (xy 342.722759 5.121161) (xy 342.808509 5.121161)
			(xy 342.893892 5.113249) (xy 342.978182 5.097493) (xy 343.060658 5.074026) (xy 343.140617 5.04305)
			(xy 343.217377 5.004828) (xy 343.290283 4.959687) (xy 343.358712 4.908011) (xy 343.422082 4.850242)
			(xy 343.479851 4.786872) (xy 343.531527 4.718443) (xy 343.576668 4.645537) (xy 343.61489 4.568777)
			(xy 343.645866 4.488818) (xy 343.669333 4.406342) (xy 343.685089 4.322052) (xy 343.693001 4.236669)
			(xy 343.693496 4.193794) (xy 343.693001 4.150919) (xy 373.705107 4.150919) (xy 373.705107 4.236669)
			(xy 373.713019 4.322052) (xy 373.728775 4.406342) (xy 373.752242 4.488818) (xy 373.783218 4.568777)
			(xy 373.82144 4.645537) (xy 373.866581 4.718443) (xy 373.918257 4.786872) (xy 373.976026 4.850242)
			(xy 374.039396 4.908011) (xy 374.107825 4.959687) (xy 374.180731 5.004828) (xy 374.257491 5.04305)
			(xy 374.33745 5.074026) (xy 374.419926 5.097493) (xy 374.504216 5.113249) (xy 374.589599 5.121161)
			(xy 374.675349 5.121161) (xy 374.760732 5.113249) (xy 374.845022 5.097493) (xy 374.927498 5.074026)
			(xy 375.007457 5.04305) (xy 375.02966 5.031994) (xy 376.211592 5.031994) (xy 376.211592 5.895594)
			(xy 376.212078 5.922845) (xy 376.219834 5.976793) (xy 376.235189 6.029088) (xy 376.257831 6.078665)
			(xy 376.287297 6.124515) (xy 376.322988 6.165706) (xy 376.364179 6.201397) (xy 376.410029 6.230863)
			(xy 376.459606 6.253505) (xy 376.511901 6.26886) (xy 376.565849 6.276616) (xy 376.620351 6.276616)
			(xy 376.674299 6.26886) (xy 376.726594 6.253505) (xy 376.776171 6.230863) (xy 376.822021 6.201397)
			(xy 376.863212 6.165706) (xy 376.898903 6.124515) (xy 376.928369 6.078665) (xy 376.951011 6.029088)
			(xy 376.966366 5.976793) (xy 376.974122 5.922845) (xy 376.974608 5.895594) (xy 376.974608 5.031994)
			(xy 376.974122 5.004743) (xy 376.966366 4.950795) (xy 376.951011 4.8985) (xy 376.928369 4.848923)
			(xy 376.898903 4.803073) (xy 376.863212 4.761882) (xy 376.822021 4.726191) (xy 376.776171 4.696725)
			(xy 376.726594 4.674083) (xy 376.674299 4.658728) (xy 376.620351 4.650972) (xy 376.565849 4.650972)
			(xy 376.511901 4.658728) (xy 376.459606 4.674083) (xy 376.410029 4.696725) (xy 376.364179 4.726191)
			(xy 376.322988 4.761882) (xy 376.287297 4.803073) (xy 376.257831 4.848923) (xy 376.235189 4.8985)
			(xy 376.219834 4.950795) (xy 376.212078 5.004743) (xy 376.211592 5.031994) (xy 375.02966 5.031994)
			(xy 375.084217 5.004828) (xy 375.157123 4.959687) (xy 375.225552 4.908011) (xy 375.288922 4.850242)
			(xy 375.346691 4.786872) (xy 375.398367 4.718443) (xy 375.443508 4.645537) (xy 375.48173 4.568777)
			(xy 375.512706 4.488818) (xy 375.536173 4.406342) (xy 375.551929 4.322052) (xy 375.559841 4.236669)
			(xy 375.560336 4.193794) (xy 375.559841 4.150919) (xy 380.055107 4.150919) (xy 380.055107 4.236669)
			(xy 380.063019 4.322052) (xy 380.078775 4.406342) (xy 380.102242 4.488818) (xy 380.133218 4.568777)
			(xy 380.17144 4.645537) (xy 380.216581 4.718443) (xy 380.268257 4.786872) (xy 380.326026 4.850242)
			(xy 380.389396 4.908011) (xy 380.457825 4.959687) (xy 380.530731 5.004828) (xy 380.607491 5.04305)
			(xy 380.68745 5.074026) (xy 380.769926 5.097493) (xy 380.854216 5.113249) (xy 380.939599 5.121161)
			(xy 381.025349 5.121161) (xy 381.110732 5.113249) (xy 381.195022 5.097493) (xy 381.277498 5.074026)
			(xy 381.357457 5.04305) (xy 381.434217 5.004828) (xy 381.507123 4.959687) (xy 381.575552 4.908011)
			(xy 381.638922 4.850242) (xy 381.696691 4.786872) (xy 381.748367 4.718443) (xy 381.793508 4.645537)
			(xy 381.83173 4.568777) (xy 381.862706 4.488818) (xy 381.886173 4.406342) (xy 381.901929 4.322052)
			(xy 381.909841 4.236669) (xy 381.910336 4.193794) (xy 381.909841 4.150919) (xy 381.901929 4.065536)
			(xy 381.886173 3.981246) (xy 381.862706 3.89877) (xy 381.83173 3.818811) (xy 381.793508 3.742051)
			(xy 381.748367 3.669145) (xy 381.696691 3.600716) (xy 381.638922 3.537346) (xy 381.575552 3.479577)
			(xy 381.507123 3.427901) (xy 381.434217 3.38276) (xy 381.357457 3.344538) (xy 381.277498 3.313562)
			(xy 381.195022 3.290095) (xy 381.110732 3.274339) (xy 381.025349 3.266427) (xy 380.939599 3.266427)
			(xy 380.854216 3.274339) (xy 380.769926 3.290095) (xy 380.68745 3.313562) (xy 380.607491 3.344538)
			(xy 380.530731 3.38276) (xy 380.457825 3.427901) (xy 380.389396 3.479577) (xy 380.326026 3.537346)
			(xy 380.268257 3.600716) (xy 380.216581 3.669145) (xy 380.17144 3.742051) (xy 380.133218 3.818811)
			(xy 380.102242 3.89877) (xy 380.078775 3.981246) (xy 380.063019 4.065536) (xy 380.055107 4.150919)
			(xy 375.559841 4.150919) (xy 375.551929 4.065536) (xy 375.536173 3.981246) (xy 375.512706 3.89877)
			(xy 375.48173 3.818811) (xy 375.443508 3.742051) (xy 375.398367 3.669145) (xy 375.346691 3.600716)
			(xy 375.288922 3.537346) (xy 375.225552 3.479577) (xy 375.157123 3.427901) (xy 375.084217 3.38276)
			(xy 375.007457 3.344538) (xy 374.927498 3.313562) (xy 374.845022 3.290095) (xy 374.760732 3.274339)
			(xy 374.675349 3.266427) (xy 374.589599 3.266427) (xy 374.504216 3.274339) (xy 374.419926 3.290095)
			(xy 374.33745 3.313562) (xy 374.257491 3.344538) (xy 374.180731 3.38276) (xy 374.107825 3.427901)
			(xy 374.039396 3.479577) (xy 373.976026 3.537346) (xy 373.918257 3.600716) (xy 373.866581 3.669145)
			(xy 373.82144 3.742051) (xy 373.783218 3.818811) (xy 373.752242 3.89877) (xy 373.728775 3.981246)
			(xy 373.713019 4.065536) (xy 373.705107 4.150919) (xy 343.693001 4.150919) (xy 343.685089 4.065536)
			(xy 343.669333 3.981246) (xy 343.645866 3.89877) (xy 343.61489 3.818811) (xy 343.576668 3.742051)
			(xy 343.531527 3.669145) (xy 343.479851 3.600716) (xy 343.422082 3.537346) (xy 343.358712 3.479577)
			(xy 343.290283 3.427901) (xy 343.217377 3.38276) (xy 343.140617 3.344538) (xy 343.060658 3.313562)
			(xy 342.978182 3.290095) (xy 342.893892 3.274339) (xy 342.808509 3.266427) (xy 342.722759 3.266427)
			(xy 342.637376 3.274339) (xy 342.553086 3.290095) (xy 342.47061 3.313562) (xy 342.390651 3.344538)
			(xy 342.313891 3.38276) (xy 342.240985 3.427901) (xy 342.172556 3.479577) (xy 342.109186 3.537346)
			(xy 342.051417 3.600716) (xy 341.999741 3.669145) (xy 341.9546 3.742051) (xy 341.916378 3.818811)
			(xy 341.885402 3.89877) (xy 341.861935 3.981246) (xy 341.846179 4.065536) (xy 341.838267 4.150919)
			(xy 337.343001 4.150919) (xy 337.335089 4.065536) (xy 337.319333 3.981246) (xy 337.295866 3.89877)
			(xy 337.26489 3.818811) (xy 337.226668 3.742051) (xy 337.181527 3.669145) (xy 337.129851 3.600716)
			(xy 337.072082 3.537346) (xy 337.008712 3.479577) (xy 336.940283 3.427901) (xy 336.867377 3.38276)
			(xy 336.790617 3.344538) (xy 336.710658 3.313562) (xy 336.628182 3.290095) (xy 336.543892 3.274339)
			(xy 336.458509 3.266427) (xy 336.372759 3.266427) (xy 336.287376 3.274339) (xy 336.203086 3.290095)
			(xy 336.12061 3.313562) (xy 336.040651 3.344538) (xy 335.963891 3.38276) (xy 335.890985 3.427901)
			(xy 335.822556 3.479577) (xy 335.759186 3.537346) (xy 335.701417 3.600716) (xy 335.649741 3.669145)
			(xy 335.6046 3.742051) (xy 335.566378 3.818811) (xy 335.535402 3.89877) (xy 335.511935 3.981246)
			(xy 335.496179 4.065536) (xy 335.488267 4.150919) (xy 333.050655 4.150919) (xy 333.042743 4.065536)
			(xy 333.026987 3.981246) (xy 333.00352 3.89877) (xy 332.972544 3.818811) (xy 332.934322 3.742051)
			(xy 332.889181 3.669145) (xy 332.837505 3.600716) (xy 332.779736 3.537346) (xy 332.716366 3.479577)
			(xy 332.647937 3.427901) (xy 332.575031 3.38276) (xy 332.498271 3.344538) (xy 332.418312 3.313562)
			(xy 332.335836 3.290095) (xy 332.251546 3.274339) (xy 332.166163 3.266427) (xy 332.080413 3.266427)
			(xy 331.99503 3.274339) (xy 331.91074 3.290095) (xy 331.828264 3.313562) (xy 331.748305 3.344538)
			(xy 331.671545 3.38276) (xy 331.598639 3.427901) (xy 331.53021 3.479577) (xy 331.46684 3.537346)
			(xy 331.409071 3.600716) (xy 331.357395 3.669145) (xy 331.312254 3.742051) (xy 331.274032 3.818811)
			(xy 331.243056 3.89877) (xy 331.219589 3.981246) (xy 331.203833 4.065536) (xy 331.195921 4.150919)
			(xy 326.700655 4.150919) (xy 326.692743 4.065536) (xy 326.676987 3.981246) (xy 326.65352 3.89877)
			(xy 326.622544 3.818811) (xy 326.584322 3.742051) (xy 326.539181 3.669145) (xy 326.487505 3.600716)
			(xy 326.429736 3.537346) (xy 326.366366 3.479577) (xy 326.297937 3.427901) (xy 326.225031 3.38276)
			(xy 326.148271 3.344538) (xy 326.068312 3.313562) (xy 325.985836 3.290095) (xy 325.901546 3.274339)
			(xy 325.816163 3.266427) (xy 325.730413 3.266427) (xy 325.64503 3.274339) (xy 325.56074 3.290095)
			(xy 325.478264 3.313562) (xy 325.398305 3.344538) (xy 325.321545 3.38276) (xy 325.248639 3.427901)
			(xy 325.18021 3.479577) (xy 325.11684 3.537346) (xy 325.059071 3.600716) (xy 325.007395 3.669145)
			(xy 324.962254 3.742051) (xy 324.924032 3.818811) (xy 324.893056 3.89877) (xy 324.869589 3.981246)
			(xy 324.853833 4.065536) (xy 324.845921 4.150919) (xy 265.125975 4.150919) (xy 265.118063 4.065536)
			(xy 265.102307 3.981246) (xy 265.07884 3.89877) (xy 265.047864 3.818811) (xy 265.009642 3.742051)
			(xy 264.964501 3.669145) (xy 264.912825 3.600716) (xy 264.855056 3.537346) (xy 264.791686 3.479577)
			(xy 264.723257 3.427901) (xy 264.650351 3.38276) (xy 264.573591 3.344538) (xy 264.493632 3.313562)
			(xy 264.411156 3.290095) (xy 264.326866 3.274339) (xy 264.241483 3.266427) (xy 264.155733 3.266427)
			(xy 264.07035 3.274339) (xy 263.98606 3.290095) (xy 263.903584 3.313562) (xy 263.823625 3.344538)
			(xy 263.746865 3.38276) (xy 263.673959 3.427901) (xy 263.60553 3.479577) (xy 263.54216 3.537346)
			(xy 263.484391 3.600716) (xy 263.432715 3.669145) (xy 263.387574 3.742051) (xy 263.349352 3.818811)
			(xy 263.318376 3.89877) (xy 263.294909 3.981246) (xy 263.279153 4.065536) (xy 263.271241 4.150919)
			(xy 258.775975 4.150919) (xy 258.768063 4.065536) (xy 258.752307 3.981246) (xy 258.72884 3.89877)
			(xy 258.697864 3.818811) (xy 258.659642 3.742051) (xy 258.614501 3.669145) (xy 258.562825 3.600716)
			(xy 258.505056 3.537346) (xy 258.441686 3.479577) (xy 258.373257 3.427901) (xy 258.300351 3.38276)
			(xy 258.223591 3.344538) (xy 258.143632 3.313562) (xy 258.061156 3.290095) (xy 257.976866 3.274339)
			(xy 257.891483 3.266427) (xy 257.805733 3.266427) (xy 257.72035 3.274339) (xy 257.63606 3.290095)
			(xy 257.553584 3.313562) (xy 257.473625 3.344538) (xy 257.396865 3.38276) (xy 257.323959 3.427901)
			(xy 257.25553 3.479577) (xy 257.19216 3.537346) (xy 257.134391 3.600716) (xy 257.082715 3.669145)
			(xy 257.037574 3.742051) (xy 256.999352 3.818811) (xy 256.968376 3.89877) (xy 256.944909 3.981246)
			(xy 256.929153 4.065536) (xy 256.921241 4.150919) (xy 254.465119 4.150919) (xy 254.465087 4.148125)
			(xy 254.457175 4.062742) (xy 254.441419 3.978452) (xy 254.417952 3.895976) (xy 254.386976 3.816017)
			(xy 254.348754 3.739257) (xy 254.303613 3.666351) (xy 254.251937 3.597922) (xy 254.194168 3.534552)
			(xy 254.130798 3.476783) (xy 254.062369 3.425107) (xy 253.989463 3.379966) (xy 253.912703 3.341744)
			(xy 253.832744 3.310768) (xy 253.750268 3.287301) (xy 253.665978 3.271545) (xy 253.580595 3.263633)
			(xy 253.494845 3.263633) (xy 253.409462 3.271545) (xy 253.325172 3.287301) (xy 253.242696 3.310768)
			(xy 253.162737 3.341744) (xy 253.085977 3.379966) (xy 253.013071 3.425107) (xy 252.944642 3.476783)
			(xy 252.881272 3.534552) (xy 252.823503 3.597922) (xy 252.771827 3.666351) (xy 252.726686 3.739257)
			(xy 252.688464 3.816017) (xy 252.657488 3.895976) (xy 252.634021 3.978452) (xy 252.618265 4.062742)
			(xy 252.610353 4.148125) (xy 248.115087 4.148125) (xy 248.107175 4.062742) (xy 248.091419 3.978452)
			(xy 248.067952 3.895976) (xy 248.036976 3.816017) (xy 247.998754 3.739257) (xy 247.953613 3.666351)
			(xy 247.901937 3.597922) (xy 247.844168 3.534552) (xy 247.780798 3.476783) (xy 247.712369 3.425107)
			(xy 247.639463 3.379966) (xy 247.562703 3.341744) (xy 247.482744 3.310768) (xy 247.400268 3.287301)
			(xy 247.315978 3.271545) (xy 247.230595 3.263633) (xy 247.144845 3.263633) (xy 247.059462 3.271545)
			(xy 246.975172 3.287301) (xy 246.892696 3.310768) (xy 246.812737 3.341744) (xy 246.735977 3.379966)
			(xy 246.663071 3.425107) (xy 246.594642 3.476783) (xy 246.531272 3.534552) (xy 246.473503 3.597922)
			(xy 246.421827 3.666351) (xy 246.376686 3.739257) (xy 246.338464 3.816017) (xy 246.307488 3.895976)
			(xy 246.284021 3.978452) (xy 246.268265 4.062742) (xy 246.260353 4.148125) (xy 186.540407 4.148125)
			(xy 186.532495 4.062742) (xy 186.516739 3.978452) (xy 186.493272 3.895976) (xy 186.462296 3.816017)
			(xy 186.424074 3.739257) (xy 186.378933 3.666351) (xy 186.327257 3.597922) (xy 186.269488 3.534552)
			(xy 186.206118 3.476783) (xy 186.137689 3.425107) (xy 186.064783 3.379966) (xy 185.988023 3.341744)
			(xy 185.908064 3.310768) (xy 185.825588 3.287301) (xy 185.741298 3.271545) (xy 185.655915 3.263633)
			(xy 185.570165 3.263633) (xy 185.484782 3.271545) (xy 185.400492 3.287301) (xy 185.318016 3.310768)
			(xy 185.238057 3.341744) (xy 185.161297 3.379966) (xy 185.088391 3.425107) (xy 185.019962 3.476783)
			(xy 184.956592 3.534552) (xy 184.898823 3.597922) (xy 184.847147 3.666351) (xy 184.802006 3.739257)
			(xy 184.763784 3.816017) (xy 184.732808 3.895976) (xy 184.709341 3.978452) (xy 184.693585 4.062742)
			(xy 184.685673 4.148125) (xy 180.190407 4.148125) (xy 180.182495 4.062742) (xy 180.166739 3.978452)
			(xy 180.143272 3.895976) (xy 180.112296 3.816017) (xy 180.074074 3.739257) (xy 180.028933 3.666351)
			(xy 179.977257 3.597922) (xy 179.919488 3.534552) (xy 179.856118 3.476783) (xy 179.787689 3.425107)
			(xy 179.714783 3.379966) (xy 179.638023 3.341744) (xy 179.558064 3.310768) (xy 179.475588 3.287301)
			(xy 179.391298 3.271545) (xy 179.305915 3.263633) (xy 179.220165 3.263633) (xy 179.134782 3.271545)
			(xy 179.050492 3.287301) (xy 178.968016 3.310768) (xy 178.888057 3.341744) (xy 178.811297 3.379966)
			(xy 178.738391 3.425107) (xy 178.669962 3.476783) (xy 178.606592 3.534552) (xy 178.548823 3.597922)
			(xy 178.497147 3.666351) (xy 178.452006 3.739257) (xy 178.413784 3.816017) (xy 178.382808 3.895976)
			(xy 178.359341 3.978452) (xy 178.343585 4.062742) (xy 178.335673 4.148125) (xy 0.508 4.148125) (xy 0.508 -7.78002)
			(xy 0.508522 -7.835827) (xy 0.516863 -7.947129) (xy 0.533498 -8.057497) (xy 0.558334 -8.166312) (xy 0.591233 -8.272968)
			(xy 0.63201 -8.376867) (xy 0.680438 -8.477428) (xy 0.736245 -8.574088) (xy 0.799119 -8.666308) (xy 0.868709 -8.753572)
			(xy 0.944626 -8.835391) (xy 1.026445 -8.911308) (xy 1.113708 -8.980898) (xy 1.205928 -9.043773) (xy 1.302589 -9.09958)
			(xy 1.40315 -9.148008) (xy 1.507048 -9.188786) (xy 1.613704 -9.221685) (xy 1.722519 -9.246521) (xy 1.832887 -9.263157)
			(xy 1.944189 -9.271498) (xy 1.999996 -9.272016) (xy 9.10209 -9.272016) (xy 9.157898 -9.271495) (xy 9.269201 -9.263154)
			(xy 9.379569 -9.24652) (xy 9.488386 -9.221684) (xy 9.595043 -9.188786) (xy 9.698942 -9.148009) (xy 9.799505 -9.099582)
			(xy 9.896167 -9.043775) (xy 9.988388 -8.980901) (xy 10.075653 -8.911311) (xy 10.157473 -8.835394)
			(xy 10.233392 -8.753575) (xy 10.302983 -8.666312) (xy 10.365859 -8.574092) (xy 10.421668 -8.477431)
			(xy 10.470097 -8.37687) (xy 10.510876 -8.272971) (xy 10.543776 -8.166315) (xy 10.568614 -8.057499)
			(xy 10.585251 -7.94713) (xy 10.593594 -7.835828) (xy 10.594086 -7.78002) (xy 10.594086 0.999998)
			(xy 10.59457 1.070352) (xy 10.60246 1.210839) (xy 10.618214 1.350662) (xy 10.641783 1.489382) (xy 10.673094 1.626562)
			(xy 10.712047 1.761771) (xy 10.758519 1.894583) (xy 10.812366 2.02458) (xy 10.873417 2.151354) (xy 10.94148 2.274505)
			(xy 11.016341 2.393646) (xy 11.097765 2.508402) (xy 11.185495 2.618411) (xy 11.279255 2.723329) (xy 11.378751 2.822825)
			(xy 11.483669 2.916585) (xy 11.593678 3.004315) (xy 11.708434 3.085739) (xy 11.827575 3.1606) (xy 11.950726 3.228663)
			(xy 12.0775 3.289714) (xy 12.207497 3.343561) (xy 12.340309 3.390033) (xy 12.475518 3.428986) (xy 12.612698 3.460297)
			(xy 12.751418 3.483866) (xy 12.891241 3.49962) (xy 13.031728 3.50751) (xy 13.102082 3.507994) (xy 81.701894 3.507994)
			(xy 81.772248 3.50751) (xy 81.912735 3.499621) (xy 82.052558 3.483867) (xy 82.191278 3.460297) (xy 82.328459 3.428987)
			(xy 82.463668 3.390034) (xy 82.59648 3.343562) (xy 82.726477 3.289715) (xy 82.853251 3.228664) (xy 82.976402 3.160601)
			(xy 83.095543 3.08574) (xy 83.2103 3.004317) (xy 83.32031 2.916587) (xy 83.425228 2.822826) (xy 83.524724 2.723331)
			(xy 83.618484 2.618413) (xy 83.706214 2.508403) (xy 83.787638 2.393647) (xy 83.862499 2.274506) (xy 83.930563 2.151355)
			(xy 83.991614 2.024581) (xy 84.04546 1.894584) (xy 84.091933 1.761772) (xy 84.130886 1.626563) (xy 84.135094 1.608125)
			(xy 178.335673 1.608125) (xy 178.335673 1.693875) (xy 178.343585 1.779258) (xy 178.359341 1.863548)
			(xy 178.382808 1.946024) (xy 178.413784 2.025983) (xy 178.452006 2.102743) (xy 178.497147 2.175649)
			(xy 178.548823 2.244078) (xy 178.606592 2.307448) (xy 178.669962 2.365217) (xy 178.738391 2.416893)
			(xy 178.811297 2.462034) (xy 178.888057 2.500256) (xy 178.968016 2.531232) (xy 179.050492 2.554699)
			(xy 179.134782 2.570455) (xy 179.220165 2.578367) (xy 179.305915 2.578367) (xy 179.391298 2.570455)
			(xy 179.475588 2.554699) (xy 179.558064 2.531232) (xy 179.638023 2.500256) (xy 179.660226 2.4892)
			(xy 183.270652 2.4892) (xy 183.270652 3.3528) (xy 183.271138 3.380069) (xy 183.2789 3.434053) (xy 183.294265 3.486383)
			(xy 183.316922 3.535993) (xy 183.346408 3.581874) (xy 183.382123 3.623091) (xy 183.42334 3.658806)
			(xy 183.469221 3.688292) (xy 183.518831 3.710949) (xy 183.571161 3.726314) (xy 183.625145 3.734076)
			(xy 183.679683 3.734076) (xy 183.733667 3.726314) (xy 183.785997 3.710949) (xy 183.835607 3.688292)
			(xy 183.881488 3.658806) (xy 183.922705 3.623091) (xy 183.95842 3.581874) (xy 183.987906 3.535993)
			(xy 184.010563 3.486383) (xy 184.025928 3.434053) (xy 184.03369 3.380069) (xy 184.034176 3.3528)
			(xy 184.034176 2.4892) (xy 184.03369 2.461931) (xy 184.025928 2.407947) (xy 184.010563 2.355617)
			(xy 183.987906 2.306007) (xy 183.95842 2.260126) (xy 183.922705 2.218909) (xy 183.881488 2.183194)
			(xy 183.835607 2.153708) (xy 183.785997 2.131051) (xy 183.733667 2.115686) (xy 183.679683 2.107924)
			(xy 183.625145 2.107924) (xy 183.571161 2.115686) (xy 183.518831 2.131051) (xy 183.469221 2.153708)
			(xy 183.42334 2.183194) (xy 183.382123 2.218909) (xy 183.346408 2.260126) (xy 183.316922 2.306007)
			(xy 183.294265 2.355617) (xy 183.2789 2.407947) (xy 183.271138 2.461931) (xy 183.270652 2.4892) (xy 179.660226 2.4892)
			(xy 179.714783 2.462034) (xy 179.787689 2.416893) (xy 179.856118 2.365217) (xy 179.919488 2.307448)
			(xy 179.977257 2.244078) (xy 180.028933 2.175649) (xy 180.074074 2.102743) (xy 180.112296 2.025983)
			(xy 180.143272 1.946024) (xy 180.166739 1.863548) (xy 180.182495 1.779258) (xy 180.190407 1.693875)
			(xy 180.190902 1.651) (xy 180.190407 1.608125) (xy 184.685673 1.608125) (xy 184.685673 1.693875)
			(xy 184.693585 1.779258) (xy 184.709341 1.863548) (xy 184.732808 1.946024) (xy 184.763784 2.025983)
			(xy 184.802006 2.102743) (xy 184.847147 2.175649) (xy 184.898823 2.244078) (xy 184.956592 2.307448)
			(xy 185.019962 2.365217) (xy 185.088391 2.416893) (xy 185.161297 2.462034) (xy 185.238057 2.500256)
			(xy 185.318016 2.531232) (xy 185.400492 2.554699) (xy 185.484782 2.570455) (xy 185.570165 2.578367)
			(xy 185.655915 2.578367) (xy 185.741298 2.570455) (xy 185.825588 2.554699) (xy 185.908064 2.531232)
			(xy 185.988023 2.500256) (xy 186.064783 2.462034) (xy 186.137689 2.416893) (xy 186.206118 2.365217)
			(xy 186.269488 2.307448) (xy 186.327257 2.244078) (xy 186.378933 2.175649) (xy 186.424074 2.102743)
			(xy 186.462296 2.025983) (xy 186.493272 1.946024) (xy 186.516739 1.863548) (xy 186.532495 1.779258)
			(xy 186.540407 1.693875) (xy 186.540902 1.651) (xy 186.540407 1.608125) (xy 246.260353 1.608125)
			(xy 246.260353 1.693875) (xy 246.268265 1.779258) (xy 246.284021 1.863548) (xy 246.307488 1.946024)
			(xy 246.338464 2.025983) (xy 246.376686 2.102743) (xy 246.421827 2.175649) (xy 246.473503 2.244078)
			(xy 246.531272 2.307448) (xy 246.594642 2.365217) (xy 246.663071 2.416893) (xy 246.735977 2.462034)
			(xy 246.812737 2.500256) (xy 246.892696 2.531232) (xy 246.975172 2.554699) (xy 247.059462 2.570455)
			(xy 247.144845 2.578367) (xy 247.230595 2.578367) (xy 247.315978 2.570455) (xy 247.400268 2.554699)
			(xy 247.482744 2.531232) (xy 247.562703 2.500256) (xy 247.584906 2.4892) (xy 248.766584 2.4892) (xy 248.766584 3.3528)
			(xy 248.76707 3.380069) (xy 248.774832 3.434053) (xy 248.790197 3.486383) (xy 248.812854 3.535993)
			(xy 248.84234 3.581874) (xy 248.878055 3.623091) (xy 248.919272 3.658806) (xy 248.965153 3.688292)
			(xy 249.014763 3.710949) (xy 249.067093 3.726314) (xy 249.121077 3.734076) (xy 249.175615 3.734076)
			(xy 249.229599 3.726314) (xy 249.281929 3.710949) (xy 249.331539 3.688292) (xy 249.37742 3.658806)
			(xy 249.418637 3.623091) (xy 249.454352 3.581874) (xy 249.483838 3.535993) (xy 249.506495 3.486383)
			(xy 249.52186 3.434053) (xy 249.529622 3.380069) (xy 249.530108 3.3528) (xy 249.530108 2.4892) (xy 249.529622 2.461931)
			(xy 249.52186 2.407947) (xy 249.506495 2.355617) (xy 249.483838 2.306007) (xy 249.454352 2.260126)
			(xy 249.418637 2.218909) (xy 249.37742 2.183194) (xy 249.331539 2.153708) (xy 249.281929 2.131051)
			(xy 249.229599 2.115686) (xy 249.175615 2.107924) (xy 249.121077 2.107924) (xy 249.067093 2.115686)
			(xy 249.014763 2.131051) (xy 248.965153 2.153708) (xy 248.919272 2.183194) (xy 248.878055 2.218909)
			(xy 248.84234 2.260126) (xy 248.812854 2.306007) (xy 248.790197 2.355617) (xy 248.774832 2.407947)
			(xy 248.76707 2.461931) (xy 248.766584 2.4892) (xy 247.584906 2.4892) (xy 247.639463 2.462034) (xy 247.712369 2.416893)
			(xy 247.780798 2.365217) (xy 247.844168 2.307448) (xy 247.901937 2.244078) (xy 247.953613 2.175649)
			(xy 247.998754 2.102743) (xy 248.036976 2.025983) (xy 248.067952 1.946024) (xy 248.091419 1.863548)
			(xy 248.107175 1.779258) (xy 248.115087 1.693875) (xy 248.115582 1.651) (xy 248.115087 1.608125)
			(xy 252.610353 1.608125) (xy 252.610353 1.693875) (xy 252.618265 1.779258) (xy 252.634021 1.863548)
			(xy 252.657488 1.946024) (xy 252.688464 2.025983) (xy 252.726686 2.102743) (xy 252.771827 2.175649)
			(xy 252.823503 2.244078) (xy 252.881272 2.307448) (xy 252.944642 2.365217) (xy 253.013071 2.416893)
			(xy 253.085977 2.462034) (xy 253.162737 2.500256) (xy 253.242696 2.531232) (xy 253.325172 2.554699)
			(xy 253.409462 2.570455) (xy 253.494845 2.578367) (xy 253.580595 2.578367) (xy 253.665978 2.570455)
			(xy 253.750268 2.554699) (xy 253.832744 2.531232) (xy 253.912703 2.500256) (xy 253.989463 2.462034)
			(xy 254.062369 2.416893) (xy 254.130798 2.365217) (xy 254.194168 2.307448) (xy 254.251937 2.244078)
			(xy 254.303613 2.175649) (xy 254.348754 2.102743) (xy 254.386976 2.025983) (xy 254.417952 1.946024)
			(xy 254.441419 1.863548) (xy 254.457175 1.779258) (xy 254.465087 1.693875) (xy 254.465582 1.651)
			(xy 254.465119 1.610919) (xy 256.921241 1.610919) (xy 256.921241 1.696669) (xy 256.929153 1.782052)
			(xy 256.944909 1.866342) (xy 256.968376 1.948818) (xy 256.999352 2.028777) (xy 257.037574 2.105537)
			(xy 257.082715 2.178443) (xy 257.134391 2.246872) (xy 257.19216 2.310242) (xy 257.25553 2.368011)
			(xy 257.323959 2.419687) (xy 257.396865 2.464828) (xy 257.473625 2.50305) (xy 257.553584 2.534026)
			(xy 257.63606 2.557493) (xy 257.72035 2.573249) (xy 257.805733 2.581161) (xy 257.891483 2.581161)
			(xy 257.976866 2.573249) (xy 258.061156 2.557493) (xy 258.143632 2.534026) (xy 258.223591 2.50305)
			(xy 258.245794 2.491994) (xy 261.85622 2.491994) (xy 261.85622 3.355594) (xy 261.856706 3.382863)
			(xy 261.864468 3.436847) (xy 261.879833 3.489177) (xy 261.90249 3.538787) (xy 261.931976 3.584668)
			(xy 261.967691 3.625885) (xy 262.008908 3.6616) (xy 262.054789 3.691086) (xy 262.104399 3.713743)
			(xy 262.156729 3.729108) (xy 262.210713 3.73687) (xy 262.265251 3.73687) (xy 262.319235 3.729108)
			(xy 262.371565 3.713743) (xy 262.421175 3.691086) (xy 262.467056 3.6616) (xy 262.508273 3.625885)
			(xy 262.543988 3.584668) (xy 262.573474 3.538787) (xy 262.596131 3.489177) (xy 262.611496 3.436847)
			(xy 262.619258 3.382863) (xy 262.619744 3.355594) (xy 262.619744 2.491994) (xy 262.619258 2.464725)
			(xy 262.611496 2.410741) (xy 262.596131 2.358411) (xy 262.573474 2.308801) (xy 262.543988 2.26292)
			(xy 262.508273 2.221703) (xy 262.467056 2.185988) (xy 262.421175 2.156502) (xy 262.371565 2.133845)
			(xy 262.319235 2.11848) (xy 262.265251 2.110718) (xy 262.210713 2.110718) (xy 262.156729 2.11848)
			(xy 262.104399 2.133845) (xy 262.054789 2.156502) (xy 262.008908 2.185988) (xy 261.967691 2.221703)
			(xy 261.931976 2.26292) (xy 261.90249 2.308801) (xy 261.879833 2.358411) (xy 261.864468 2.410741)
			(xy 261.856706 2.464725) (xy 261.85622 2.491994) (xy 258.245794 2.491994) (xy 258.300351 2.464828)
			(xy 258.373257 2.419687) (xy 258.441686 2.368011) (xy 258.505056 2.310242) (xy 258.562825 2.246872)
			(xy 258.614501 2.178443) (xy 258.659642 2.105537) (xy 258.697864 2.028777) (xy 258.72884 1.948818)
			(xy 258.752307 1.866342) (xy 258.768063 1.782052) (xy 258.775975 1.696669) (xy 258.77647 1.653794)
			(xy 258.775975 1.610919) (xy 263.271241 1.610919) (xy 263.271241 1.696669) (xy 263.279153 1.782052)
			(xy 263.294909 1.866342) (xy 263.318376 1.948818) (xy 263.349352 2.028777) (xy 263.387574 2.105537)
			(xy 263.432715 2.178443) (xy 263.484391 2.246872) (xy 263.54216 2.310242) (xy 263.60553 2.368011)
			(xy 263.673959 2.419687) (xy 263.746865 2.464828) (xy 263.823625 2.50305) (xy 263.903584 2.534026)
			(xy 263.98606 2.557493) (xy 264.07035 2.573249) (xy 264.155733 2.581161) (xy 264.241483 2.581161)
			(xy 264.326866 2.573249) (xy 264.411156 2.557493) (xy 264.493632 2.534026) (xy 264.573591 2.50305)
			(xy 264.650351 2.464828) (xy 264.723257 2.419687) (xy 264.791686 2.368011) (xy 264.855056 2.310242)
			(xy 264.912825 2.246872) (xy 264.964501 2.178443) (xy 265.009642 2.105537) (xy 265.047864 2.028777)
			(xy 265.07884 1.948818) (xy 265.102307 1.866342) (xy 265.118063 1.782052) (xy 265.125975 1.696669)
			(xy 265.12647 1.653794) (xy 265.125975 1.610919) (xy 324.845921 1.610919) (xy 324.845921 1.696669)
			(xy 324.853833 1.782052) (xy 324.869589 1.866342) (xy 324.893056 1.948818) (xy 324.924032 2.028777)
			(xy 324.962254 2.105537) (xy 325.007395 2.178443) (xy 325.059071 2.246872) (xy 325.11684 2.310242)
			(xy 325.18021 2.368011) (xy 325.248639 2.419687) (xy 325.321545 2.464828) (xy 325.398305 2.50305)
			(xy 325.478264 2.534026) (xy 325.56074 2.557493) (xy 325.64503 2.573249) (xy 325.730413 2.581161)
			(xy 325.816163 2.581161) (xy 325.901546 2.573249) (xy 325.985836 2.557493) (xy 326.068312 2.534026)
			(xy 326.148271 2.50305) (xy 326.170474 2.491994) (xy 327.352152 2.491994) (xy 327.352152 3.355594)
			(xy 327.352638 3.382863) (xy 327.3604 3.436847) (xy 327.375765 3.489177) (xy 327.398422 3.538787)
			(xy 327.427908 3.584668) (xy 327.463623 3.625885) (xy 327.50484 3.6616) (xy 327.550721 3.691086)
			(xy 327.600331 3.713743) (xy 327.652661 3.729108) (xy 327.706645 3.73687) (xy 327.761183 3.73687)
			(xy 327.815167 3.729108) (xy 327.867497 3.713743) (xy 327.917107 3.691086) (xy 327.962988 3.6616)
			(xy 328.004205 3.625885) (xy 328.03992 3.584668) (xy 328.069406 3.538787) (xy 328.092063 3.489177)
			(xy 328.107428 3.436847) (xy 328.11519 3.382863) (xy 328.115676 3.355594) (xy 328.115676 2.491994)
			(xy 328.11519 2.464725) (xy 328.107428 2.410741) (xy 328.092063 2.358411) (xy 328.069406 2.308801)
			(xy 328.03992 2.26292) (xy 328.004205 2.221703) (xy 327.962988 2.185988) (xy 327.917107 2.156502)
			(xy 327.867497 2.133845) (xy 327.815167 2.11848) (xy 327.761183 2.110718) (xy 327.706645 2.110718)
			(xy 327.652661 2.11848) (xy 327.600331 2.133845) (xy 327.550721 2.156502) (xy 327.50484 2.185988)
			(xy 327.463623 2.221703) (xy 327.427908 2.26292) (xy 327.398422 2.308801) (xy 327.375765 2.358411)
			(xy 327.3604 2.410741) (xy 327.352638 2.464725) (xy 327.352152 2.491994) (xy 326.170474 2.491994)
			(xy 326.225031 2.464828) (xy 326.297937 2.419687) (xy 326.366366 2.368011) (xy 326.429736 2.310242)
			(xy 326.487505 2.246872) (xy 326.539181 2.178443) (xy 326.584322 2.105537) (xy 326.622544 2.028777)
			(xy 326.65352 1.948818) (xy 326.676987 1.866342) (xy 326.692743 1.782052) (xy 326.700655 1.696669)
			(xy 326.70115 1.653794) (xy 326.700655 1.610919) (xy 331.195921 1.610919) (xy 331.195921 1.696669)
			(xy 331.203833 1.782052) (xy 331.219589 1.866342) (xy 331.243056 1.948818) (xy 331.274032 2.028777)
			(xy 331.312254 2.105537) (xy 331.357395 2.178443) (xy 331.409071 2.246872) (xy 331.46684 2.310242)
			(xy 331.53021 2.368011) (xy 331.598639 2.419687) (xy 331.671545 2.464828) (xy 331.748305 2.50305)
			(xy 331.828264 2.534026) (xy 331.91074 2.557493) (xy 331.99503 2.573249) (xy 332.080413 2.581161)
			(xy 332.166163 2.581161) (xy 332.251546 2.573249) (xy 332.335836 2.557493) (xy 332.418312 2.534026)
			(xy 332.498271 2.50305) (xy 332.575031 2.464828) (xy 332.647937 2.419687) (xy 332.716366 2.368011)
			(xy 332.779736 2.310242) (xy 332.837505 2.246872) (xy 332.889181 2.178443) (xy 332.934322 2.105537)
			(xy 332.972544 2.028777) (xy 333.00352 1.948818) (xy 333.026987 1.866342) (xy 333.042743 1.782052)
			(xy 333.050655 1.696669) (xy 333.05115 1.653794) (xy 333.050655 1.610919) (xy 335.488267 1.610919)
			(xy 335.488267 1.696669) (xy 335.496179 1.782052) (xy 335.511935 1.866342) (xy 335.535402 1.948818)
			(xy 335.566378 2.028777) (xy 335.6046 2.105537) (xy 335.649741 2.178443) (xy 335.701417 2.246872)
			(xy 335.759186 2.310242) (xy 335.822556 2.368011) (xy 335.890985 2.419687) (xy 335.963891 2.464828)
			(xy 336.040651 2.50305) (xy 336.12061 2.534026) (xy 336.203086 2.557493) (xy 336.287376 2.573249)
			(xy 336.372759 2.581161) (xy 336.458509 2.581161) (xy 336.543892 2.573249) (xy 336.628182 2.557493)
			(xy 336.710658 2.534026) (xy 336.790617 2.50305) (xy 336.81282 2.491994) (xy 340.4235 2.491994) (xy 340.4235 3.355594)
			(xy 340.423986 3.382845) (xy 340.431742 3.436793) (xy 340.447097 3.489088) (xy 340.469739 3.538665)
			(xy 340.499205 3.584515) (xy 340.534896 3.625706) (xy 340.576087 3.661397) (xy 340.621937 3.690863)
			(xy 340.671514 3.713505) (xy 340.723809 3.72886) (xy 340.777757 3.736616) (xy 340.832259 3.736616)
			(xy 340.886207 3.72886) (xy 340.938502 3.713505) (xy 340.988079 3.690863) (xy 341.033929 3.661397)
			(xy 341.07512 3.625706) (xy 341.110811 3.584515) (xy 341.140277 3.538665) (xy 341.162919 3.489088)
			(xy 341.178274 3.436793) (xy 341.18603 3.382845) (xy 341.186516 3.355594) (xy 341.186516 2.491994)
			(xy 341.18603 2.464743) (xy 341.178274 2.410795) (xy 341.162919 2.3585) (xy 341.140277 2.308923)
			(xy 341.110811 2.263073) (xy 341.07512 2.221882) (xy 341.033929 2.186191) (xy 340.988079 2.156725)
			(xy 340.938502 2.134083) (xy 340.886207 2.118728) (xy 340.832259 2.110972) (xy 340.777757 2.110972)
			(xy 340.723809 2.118728) (xy 340.671514 2.134083) (xy 340.621937 2.156725) (xy 340.576087 2.186191)
			(xy 340.534896 2.221882) (xy 340.499205 2.263073) (xy 340.469739 2.308923) (xy 340.447097 2.3585)
			(xy 340.431742 2.410795) (xy 340.423986 2.464743) (xy 340.4235 2.491994) (xy 336.81282 2.491994)
			(xy 336.867377 2.464828) (xy 336.940283 2.419687) (xy 337.008712 2.368011) (xy 337.072082 2.310242)
			(xy 337.129851 2.246872) (xy 337.181527 2.178443) (xy 337.226668 2.105537) (xy 337.26489 2.028777)
			(xy 337.295866 1.948818) (xy 337.319333 1.866342) (xy 337.335089 1.782052) (xy 337.343001 1.696669)
			(xy 337.343496 1.653794) (xy 337.343001 1.610919) (xy 341.838267 1.610919) (xy 341.838267 1.696669)
			(xy 341.846179 1.782052) (xy 341.861935 1.866342) (xy 341.885402 1.948818) (xy 341.916378 2.028777)
			(xy 341.9546 2.105537) (xy 341.999741 2.178443) (xy 342.051417 2.246872) (xy 342.109186 2.310242)
			(xy 342.172556 2.368011) (xy 342.240985 2.419687) (xy 342.313891 2.464828) (xy 342.390651 2.50305)
			(xy 342.47061 2.534026) (xy 342.553086 2.557493) (xy 342.637376 2.573249) (xy 342.722759 2.581161)
			(xy 342.808509 2.581161) (xy 342.893892 2.573249) (xy 342.978182 2.557493) (xy 343.060658 2.534026)
			(xy 343.140617 2.50305) (xy 343.217377 2.464828) (xy 343.290283 2.419687) (xy 343.358712 2.368011)
			(xy 343.422082 2.310242) (xy 343.479851 2.246872) (xy 343.531527 2.178443) (xy 343.576668 2.105537)
			(xy 343.61489 2.028777) (xy 343.645866 1.948818) (xy 343.669333 1.866342) (xy 343.685089 1.782052)
			(xy 343.693001 1.696669) (xy 343.693496 1.653794) (xy 343.693001 1.610919) (xy 373.705107 1.610919)
			(xy 373.705107 1.696669) (xy 373.713019 1.782052) (xy 373.728775 1.866342) (xy 373.752242 1.948818)
			(xy 373.783218 2.028777) (xy 373.82144 2.105537) (xy 373.866581 2.178443) (xy 373.918257 2.246872)
			(xy 373.976026 2.310242) (xy 374.039396 2.368011) (xy 374.107825 2.419687) (xy 374.180731 2.464828)
			(xy 374.257491 2.50305) (xy 374.33745 2.534026) (xy 374.419926 2.557493) (xy 374.504216 2.573249)
			(xy 374.589599 2.581161) (xy 374.675349 2.581161) (xy 374.760732 2.573249) (xy 374.845022 2.557493)
			(xy 374.927498 2.534026) (xy 375.007457 2.50305) (xy 375.02966 2.491994) (xy 376.211592 2.491994)
			(xy 376.211592 3.355594) (xy 376.212078 3.382845) (xy 376.219834 3.436793) (xy 376.235189 3.489088)
			(xy 376.257831 3.538665) (xy 376.287297 3.584515) (xy 376.322988 3.625706) (xy 376.364179 3.661397)
			(xy 376.410029 3.690863) (xy 376.459606 3.713505) (xy 376.511901 3.72886) (xy 376.565849 3.736616)
			(xy 376.620351 3.736616) (xy 376.674299 3.72886) (xy 376.726594 3.713505) (xy 376.776171 3.690863)
			(xy 376.822021 3.661397) (xy 376.863212 3.625706) (xy 376.898903 3.584515) (xy 376.928369 3.538665)
			(xy 376.951011 3.489088) (xy 376.966366 3.436793) (xy 376.974122 3.382845) (xy 376.974608 3.355594)
			(xy 376.974608 2.491994) (xy 376.974122 2.464743) (xy 376.966366 2.410795) (xy 376.951011 2.3585)
			(xy 376.928369 2.308923) (xy 376.898903 2.263073) (xy 376.863212 2.221882) (xy 376.822021 2.186191)
			(xy 376.776171 2.156725) (xy 376.726594 2.134083) (xy 376.674299 2.118728) (xy 376.620351 2.110972)
			(xy 376.565849 2.110972) (xy 376.511901 2.118728) (xy 376.459606 2.134083) (xy 376.410029 2.156725)
			(xy 376.364179 2.186191) (xy 376.322988 2.221882) (xy 376.287297 2.263073) (xy 376.257831 2.308923)
			(xy 376.235189 2.3585) (xy 376.219834 2.410795) (xy 376.212078 2.464743) (xy 376.211592 2.491994)
			(xy 375.02966 2.491994) (xy 375.084217 2.464828) (xy 375.157123 2.419687) (xy 375.225552 2.368011)
			(xy 375.288922 2.310242) (xy 375.346691 2.246872) (xy 375.398367 2.178443) (xy 375.443508 2.105537)
			(xy 375.48173 2.028777) (xy 375.512706 1.948818) (xy 375.536173 1.866342) (xy 375.551929 1.782052)
			(xy 375.559841 1.696669) (xy 375.560336 1.653794) (xy 375.559841 1.610919) (xy 380.055107 1.610919)
			(xy 380.055107 1.696669) (xy 380.063019 1.782052) (xy 380.078775 1.866342) (xy 380.102242 1.948818)
			(xy 380.133218 2.028777) (xy 380.17144 2.105537) (xy 380.216581 2.178443) (xy 380.268257 2.246872)
			(xy 380.326026 2.310242) (xy 380.389396 2.368011) (xy 380.457825 2.419687) (xy 380.530731 2.464828)
			(xy 380.607491 2.50305) (xy 380.68745 2.534026) (xy 380.769926 2.557493) (xy 380.854216 2.573249)
			(xy 380.939599 2.581161) (xy 381.025349 2.581161) (xy 381.110732 2.573249) (xy 381.195022 2.557493)
			(xy 381.277498 2.534026) (xy 381.357457 2.50305) (xy 381.434217 2.464828) (xy 381.507123 2.419687)
			(xy 381.575552 2.368011) (xy 381.638922 2.310242) (xy 381.696691 2.246872) (xy 381.748367 2.178443)
			(xy 381.793508 2.105537) (xy 381.83173 2.028777) (xy 381.862706 1.948818) (xy 381.886173 1.866342)
			(xy 381.901929 1.782052) (xy 381.909841 1.696669) (xy 381.910336 1.653794) (xy 381.909841 1.610919)
			(xy 381.901929 1.525536) (xy 381.886173 1.441246) (xy 381.862706 1.35877) (xy 381.83173 1.278811)
			(xy 381.793508 1.202051) (xy 381.748367 1.129145) (xy 381.696691 1.060716) (xy 381.638922 0.997346)
			(xy 381.575552 0.939577) (xy 381.507123 0.887901) (xy 381.434217 0.84276) (xy 381.357457 0.804538)
			(xy 381.277498 0.773562) (xy 381.195022 0.750095) (xy 381.110732 0.734339) (xy 381.025349 0.726427)
			(xy 380.939599 0.726427) (xy 380.854216 0.734339) (xy 380.769926 0.750095) (xy 380.68745 0.773562)
			(xy 380.607491 0.804538) (xy 380.530731 0.84276) (xy 380.457825 0.887901) (xy 380.389396 0.939577)
			(xy 380.326026 0.997346) (xy 380.268257 1.060716) (xy 380.216581 1.129145) (xy 380.17144 1.202051)
			(xy 380.133218 1.278811) (xy 380.102242 1.35877) (xy 380.078775 1.441246) (xy 380.063019 1.525536)
			(xy 380.055107 1.610919) (xy 375.559841 1.610919) (xy 375.551929 1.525536) (xy 375.536173 1.441246)
			(xy 375.512706 1.35877) (xy 375.48173 1.278811) (xy 375.443508 1.202051) (xy 375.398367 1.129145)
			(xy 375.346691 1.060716) (xy 375.288922 0.997346) (xy 375.225552 0.939577) (xy 375.157123 0.887901)
			(xy 375.084217 0.84276) (xy 375.007457 0.804538) (xy 374.927498 0.773562) (xy 374.845022 0.750095)
			(xy 374.760732 0.734339) (xy 374.675349 0.726427) (xy 374.589599 0.726427) (xy 374.504216 0.734339)
			(xy 374.419926 0.750095) (xy 374.33745 0.773562) (xy 374.257491 0.804538) (xy 374.180731 0.84276)
			(xy 374.107825 0.887901) (xy 374.039396 0.939577) (xy 373.976026 0.997346) (xy 373.918257 1.060716)
			(xy 373.866581 1.129145) (xy 373.82144 1.202051) (xy 373.783218 1.278811) (xy 373.752242 1.35877)
			(xy 373.728775 1.441246) (xy 373.713019 1.525536) (xy 373.705107 1.610919) (xy 343.693001 1.610919)
			(xy 343.685089 1.525536) (xy 343.669333 1.441246) (xy 343.645866 1.35877) (xy 343.61489 1.278811)
			(xy 343.576668 1.202051) (xy 343.531527 1.129145) (xy 343.479851 1.060716) (xy 343.422082 0.997346)
			(xy 343.358712 0.939577) (xy 343.290283 0.887901) (xy 343.217377 0.84276) (xy 343.140617 0.804538)
			(xy 343.060658 0.773562) (xy 342.978182 0.750095) (xy 342.893892 0.734339) (xy 342.808509 0.726427)
			(xy 342.722759 0.726427) (xy 342.637376 0.734339) (xy 342.553086 0.750095) (xy 342.47061 0.773562)
			(xy 342.390651 0.804538) (xy 342.313891 0.84276) (xy 342.240985 0.887901) (xy 342.172556 0.939577)
			(xy 342.109186 0.997346) (xy 342.051417 1.060716) (xy 341.999741 1.129145) (xy 341.9546 1.202051)
			(xy 341.916378 1.278811) (xy 341.885402 1.35877) (xy 341.861935 1.441246) (xy 341.846179 1.525536)
			(xy 341.838267 1.610919) (xy 337.343001 1.610919) (xy 337.335089 1.525536) (xy 337.319333 1.441246)
			(xy 337.295866 1.35877) (xy 337.26489 1.278811) (xy 337.226668 1.202051) (xy 337.181527 1.129145)
			(xy 337.129851 1.060716) (xy 337.072082 0.997346) (xy 337.008712 0.939577) (xy 336.940283 0.887901)
			(xy 336.867377 0.84276) (xy 336.790617 0.804538) (xy 336.710658 0.773562) (xy 336.628182 0.750095)
			(xy 336.543892 0.734339) (xy 336.458509 0.726427) (xy 336.372759 0.726427) (xy 336.287376 0.734339)
			(xy 336.203086 0.750095) (xy 336.12061 0.773562) (xy 336.040651 0.804538) (xy 335.963891 0.84276)
			(xy 335.890985 0.887901) (xy 335.822556 0.939577) (xy 335.759186 0.997346) (xy 335.701417 1.060716)
			(xy 335.649741 1.129145) (xy 335.6046 1.202051) (xy 335.566378 1.278811) (xy 335.535402 1.35877)
			(xy 335.511935 1.441246) (xy 335.496179 1.525536) (xy 335.488267 1.610919) (xy 333.050655 1.610919)
			(xy 333.042743 1.525536) (xy 333.026987 1.441246) (xy 333.00352 1.35877) (xy 332.972544 1.278811)
			(xy 332.934322 1.202051) (xy 332.889181 1.129145) (xy 332.837505 1.060716) (xy 332.779736 0.997346)
			(xy 332.716366 0.939577) (xy 332.647937 0.887901) (xy 332.575031 0.84276) (xy 332.498271 0.804538)
			(xy 332.418312 0.773562) (xy 332.335836 0.750095) (xy 332.251546 0.734339) (xy 332.166163 0.726427)
			(xy 332.080413 0.726427) (xy 331.99503 0.734339) (xy 331.91074 0.750095) (xy 331.828264 0.773562)
			(xy 331.748305 0.804538) (xy 331.671545 0.84276) (xy 331.598639 0.887901) (xy 331.53021 0.939577)
			(xy 331.46684 0.997346) (xy 331.409071 1.060716) (xy 331.357395 1.129145) (xy 331.312254 1.202051)
			(xy 331.274032 1.278811) (xy 331.243056 1.35877) (xy 331.219589 1.441246) (xy 331.203833 1.525536)
			(xy 331.195921 1.610919) (xy 326.700655 1.610919) (xy 326.692743 1.525536) (xy 326.676987 1.441246)
			(xy 326.65352 1.35877) (xy 326.622544 1.278811) (xy 326.584322 1.202051) (xy 326.539181 1.129145)
			(xy 326.487505 1.060716) (xy 326.429736 0.997346) (xy 326.366366 0.939577) (xy 326.297937 0.887901)
			(xy 326.225031 0.84276) (xy 326.148271 0.804538) (xy 326.068312 0.773562) (xy 325.985836 0.750095)
			(xy 325.901546 0.734339) (xy 325.816163 0.726427) (xy 325.730413 0.726427) (xy 325.64503 0.734339)
			(xy 325.56074 0.750095) (xy 325.478264 0.773562) (xy 325.398305 0.804538) (xy 325.321545 0.84276)
			(xy 325.248639 0.887901) (xy 325.18021 0.939577) (xy 325.11684 0.997346) (xy 325.059071 1.060716)
			(xy 325.007395 1.129145) (xy 324.962254 1.202051) (xy 324.924032 1.278811) (xy 324.893056 1.35877)
			(xy 324.869589 1.441246) (xy 324.853833 1.525536) (xy 324.845921 1.610919) (xy 265.125975 1.610919)
			(xy 265.118063 1.525536) (xy 265.102307 1.441246) (xy 265.07884 1.35877) (xy 265.047864 1.278811)
			(xy 265.009642 1.202051) (xy 264.964501 1.129145) (xy 264.912825 1.060716) (xy 264.855056 0.997346)
			(xy 264.791686 0.939577) (xy 264.723257 0.887901) (xy 264.650351 0.84276) (xy 264.573591 0.804538)
			(xy 264.493632 0.773562) (xy 264.411156 0.750095) (xy 264.326866 0.734339) (xy 264.241483 0.726427)
			(xy 264.155733 0.726427) (xy 264.07035 0.734339) (xy 263.98606 0.750095) (xy 263.903584 0.773562)
			(xy 263.823625 0.804538) (xy 263.746865 0.84276) (xy 263.673959 0.887901) (xy 263.60553 0.939577)
			(xy 263.54216 0.997346) (xy 263.484391 1.060716) (xy 263.432715 1.129145) (xy 263.387574 1.202051)
			(xy 263.349352 1.278811) (xy 263.318376 1.35877) (xy 263.294909 1.441246) (xy 263.279153 1.525536)
			(xy 263.271241 1.610919) (xy 258.775975 1.610919) (xy 258.768063 1.525536) (xy 258.752307 1.441246)
			(xy 258.72884 1.35877) (xy 258.697864 1.278811) (xy 258.659642 1.202051) (xy 258.614501 1.129145)
			(xy 258.562825 1.060716) (xy 258.505056 0.997346) (xy 258.441686 0.939577) (xy 258.373257 0.887901)
			(xy 258.300351 0.84276) (xy 258.223591 0.804538) (xy 258.143632 0.773562) (xy 258.061156 0.750095)
			(xy 257.976866 0.734339) (xy 257.891483 0.726427) (xy 257.805733 0.726427) (xy 257.72035 0.734339)
			(xy 257.63606 0.750095) (xy 257.553584 0.773562) (xy 257.473625 0.804538) (xy 257.396865 0.84276)
			(xy 257.323959 0.887901) (xy 257.25553 0.939577) (xy 257.19216 0.997346) (xy 257.134391 1.060716)
			(xy 257.082715 1.129145) (xy 257.037574 1.202051) (xy 256.999352 1.278811) (xy 256.968376 1.35877)
			(xy 256.944909 1.441246) (xy 256.929153 1.525536) (xy 256.921241 1.610919) (xy 254.465119 1.610919)
			(xy 254.465087 1.608125) (xy 254.457175 1.522742) (xy 254.441419 1.438452) (xy 254.417952 1.355976)
			(xy 254.386976 1.276017) (xy 254.348754 1.199257) (xy 254.303613 1.126351) (xy 254.251937 1.057922)
			(xy 254.194168 0.994552) (xy 254.130798 0.936783) (xy 254.062369 0.885107) (xy 253.989463 0.839966)
			(xy 253.912703 0.801744) (xy 253.832744 0.770768) (xy 253.750268 0.747301) (xy 253.665978 0.731545)
			(xy 253.580595 0.723633) (xy 253.494845 0.723633) (xy 253.409462 0.731545) (xy 253.325172 0.747301)
			(xy 253.242696 0.770768) (xy 253.162737 0.801744) (xy 253.085977 0.839966) (xy 253.013071 0.885107)
			(xy 252.944642 0.936783) (xy 252.881272 0.994552) (xy 252.823503 1.057922) (xy 252.771827 1.126351)
			(xy 252.726686 1.199257) (xy 252.688464 1.276017) (xy 252.657488 1.355976) (xy 252.634021 1.438452)
			(xy 252.618265 1.522742) (xy 252.610353 1.608125) (xy 248.115087 1.608125) (xy 248.107175 1.522742)
			(xy 248.091419 1.438452) (xy 248.067952 1.355976) (xy 248.036976 1.276017) (xy 247.998754 1.199257)
			(xy 247.953613 1.126351) (xy 247.901937 1.057922) (xy 247.844168 0.994552) (xy 247.780798 0.936783)
			(xy 247.712369 0.885107) (xy 247.639463 0.839966) (xy 247.562703 0.801744) (xy 247.482744 0.770768)
			(xy 247.400268 0.747301) (xy 247.315978 0.731545) (xy 247.230595 0.723633) (xy 247.144845 0.723633)
			(xy 247.059462 0.731545) (xy 246.975172 0.747301) (xy 246.892696 0.770768) (xy 246.812737 0.801744)
			(xy 246.735977 0.839966) (xy 246.663071 0.885107) (xy 246.594642 0.936783) (xy 246.531272 0.994552)
			(xy 246.473503 1.057922) (xy 246.421827 1.126351) (xy 246.376686 1.199257) (xy 246.338464 1.276017)
			(xy 246.307488 1.355976) (xy 246.284021 1.438452) (xy 246.268265 1.522742) (xy 246.260353 1.608125)
			(xy 186.540407 1.608125) (xy 186.532495 1.522742) (xy 186.516739 1.438452) (xy 186.493272 1.355976)
			(xy 186.462296 1.276017) (xy 186.424074 1.199257) (xy 186.378933 1.126351) (xy 186.327257 1.057922)
			(xy 186.269488 0.994552) (xy 186.206118 0.936783) (xy 186.137689 0.885107) (xy 186.064783 0.839966)
			(xy 185.988023 0.801744) (xy 185.908064 0.770768) (xy 185.825588 0.747301) (xy 185.741298 0.731545)
			(xy 185.655915 0.723633) (xy 185.570165 0.723633) (xy 185.484782 0.731545) (xy 185.400492 0.747301)
			(xy 185.318016 0.770768) (xy 185.238057 0.801744) (xy 185.161297 0.839966) (xy 185.088391 0.885107)
			(xy 185.019962 0.936783) (xy 184.956592 0.994552) (xy 184.898823 1.057922) (xy 184.847147 1.126351)
			(xy 184.802006 1.199257) (xy 184.763784 1.276017) (xy 184.732808 1.355976) (xy 184.709341 1.438452)
			(xy 184.693585 1.522742) (xy 184.685673 1.608125) (xy 180.190407 1.608125) (xy 180.182495 1.522742)
			(xy 180.166739 1.438452) (xy 180.143272 1.355976) (xy 180.112296 1.276017) (xy 180.074074 1.199257)
			(xy 180.028933 1.126351) (xy 179.977257 1.057922) (xy 179.919488 0.994552) (xy 179.856118 0.936783)
			(xy 179.787689 0.885107) (xy 179.714783 0.839966) (xy 179.638023 0.801744) (xy 179.558064 0.770768)
			(xy 179.475588 0.747301) (xy 179.391298 0.731545) (xy 179.305915 0.723633) (xy 179.220165 0.723633)
			(xy 179.134782 0.731545) (xy 179.050492 0.747301) (xy 178.968016 0.770768) (xy 178.888057 0.801744)
			(xy 178.811297 0.839966) (xy 178.738391 0.885107) (xy 178.669962 0.936783) (xy 178.606592 0.994552)
			(xy 178.548823 1.057922) (xy 178.497147 1.126351) (xy 178.452006 1.199257) (xy 178.413784 1.276017)
			(xy 178.382808 1.355976) (xy 178.359341 1.438452) (xy 178.343585 1.522742) (xy 178.335673 1.608125)
			(xy 84.135094 1.608125) (xy 84.162197 1.489382) (xy 84.185766 1.350662) (xy 84.20152 1.210839) (xy 84.20941 1.070352)
			(xy 84.20989 0.999998) (xy 84.20989 -0.931875) (xy 208.043513 -0.931875) (xy 208.043513 -0.846125)
			(xy 208.051425 -0.760742) (xy 208.067181 -0.676452) (xy 208.090648 -0.593976) (xy 208.121624 -0.514017)
			(xy 208.159846 -0.437257) (xy 208.204987 -0.364351) (xy 208.256663 -0.295922) (xy 208.314432 -0.232552)
			(xy 208.377802 -0.174783) (xy 208.446231 -0.123107) (xy 208.519137 -0.077966) (xy 208.595897 -0.039744)
			(xy 208.675856 -0.008768) (xy 208.758332 0.014699) (xy 208.842622 0.030455) (xy 208.928005 0.038367)
			(xy 209.013755 0.038367) (xy 209.099138 0.030455) (xy 209.183428 0.014699) (xy 209.265904 -0.008768)
			(xy 209.345863 -0.039744) (xy 209.422623 -0.077966) (xy 209.495529 -0.123107) (xy 209.563958 -0.174783)
			(xy 209.627328 -0.232552) (xy 209.685097 -0.295922) (xy 209.736773 -0.364351) (xy 209.781914 -0.437257)
			(xy 209.820136 -0.514017) (xy 209.851112 -0.593976) (xy 209.874579 -0.676452) (xy 209.890335 -0.760742)
			(xy 209.898247 -0.846125) (xy 209.898742 -0.889) (xy 209.898247 -0.931875) (xy 214.393513 -0.931875)
			(xy 214.393513 -0.846125) (xy 214.401425 -0.760742) (xy 214.417181 -0.676452) (xy 214.440648 -0.593976)
			(xy 214.471624 -0.514017) (xy 214.509846 -0.437257) (xy 214.554987 -0.364351) (xy 214.606663 -0.295922)
			(xy 214.664432 -0.232552) (xy 214.727802 -0.174783) (xy 214.796231 -0.123107) (xy 214.869137 -0.077966)
			(xy 214.945897 -0.039744) (xy 215.025856 -0.008768) (xy 215.108332 0.014699) (xy 215.192622 0.030455)
			(xy 215.278005 0.038367) (xy 215.363755 0.038367) (xy 215.449138 0.030455) (xy 215.533428 0.014699)
			(xy 215.615904 -0.008768) (xy 215.695863 -0.039744) (xy 215.772623 -0.077966) (xy 215.845529 -0.123107)
			(xy 215.913958 -0.174783) (xy 215.977328 -0.232552) (xy 216.035097 -0.295922) (xy 216.086773 -0.364351)
			(xy 216.131914 -0.437257) (xy 216.170136 -0.514017) (xy 216.201112 -0.593976) (xy 216.224579 -0.676452)
			(xy 216.240335 -0.760742) (xy 216.248247 -0.846125) (xy 216.248742 -0.889) (xy 216.248247 -0.931875)
			(xy 246.260353 -0.931875) (xy 246.260353 -0.846125) (xy 246.268265 -0.760742) (xy 246.284021 -0.676452)
			(xy 246.307488 -0.593976) (xy 246.338464 -0.514017) (xy 246.376686 -0.437257) (xy 246.421827 -0.364351)
			(xy 246.473503 -0.295922) (xy 246.531272 -0.232552) (xy 246.594642 -0.174783) (xy 246.663071 -0.123107)
			(xy 246.735977 -0.077966) (xy 246.812737 -0.039744) (xy 246.892696 -0.008768) (xy 246.975172 0.014699)
			(xy 247.059462 0.030455) (xy 247.144845 0.038367) (xy 247.230595 0.038367) (xy 247.315978 0.030455)
			(xy 247.400268 0.014699) (xy 247.482744 -0.008768) (xy 247.562703 -0.039744) (xy 247.639463 -0.077966)
			(xy 247.712369 -0.123107) (xy 247.780798 -0.174783) (xy 247.844168 -0.232552) (xy 247.901937 -0.295922)
			(xy 247.953613 -0.364351) (xy 247.998754 -0.437257) (xy 248.036976 -0.514017) (xy 248.067952 -0.593976)
			(xy 248.091419 -0.676452) (xy 248.107175 -0.760742) (xy 248.115087 -0.846125) (xy 248.115582 -0.889)
			(xy 248.115087 -0.931875) (xy 252.610353 -0.931875) (xy 252.610353 -0.846125) (xy 252.618265 -0.760742)
			(xy 252.634021 -0.676452) (xy 252.657488 -0.593976) (xy 252.688464 -0.514017) (xy 252.726686 -0.437257)
			(xy 252.771827 -0.364351) (xy 252.823503 -0.295922) (xy 252.881272 -0.232552) (xy 252.944642 -0.174783)
			(xy 253.013071 -0.123107) (xy 253.085977 -0.077966) (xy 253.162737 -0.039744) (xy 253.242696 -0.008768)
			(xy 253.325172 0.014699) (xy 253.409462 0.030455) (xy 253.494845 0.038367) (xy 253.580595 0.038367)
			(xy 253.665978 0.030455) (xy 253.750268 0.014699) (xy 253.832744 -0.008768) (xy 253.912703 -0.039744)
			(xy 253.989463 -0.077966) (xy 254.062369 -0.123107) (xy 254.130798 -0.174783) (xy 254.194168 -0.232552)
			(xy 254.251937 -0.295922) (xy 254.303613 -0.364351) (xy 254.348754 -0.437257) (xy 254.386976 -0.514017)
			(xy 254.417952 -0.593976) (xy 254.441419 -0.676452) (xy 254.457175 -0.760742) (xy 254.465087 -0.846125)
			(xy 254.465582 -0.889) (xy 254.465119 -0.929081) (xy 256.921241 -0.929081) (xy 256.921241 -0.843331)
			(xy 256.929153 -0.757948) (xy 256.944909 -0.673658) (xy 256.968376 -0.591182) (xy 256.999352 -0.511223)
			(xy 257.037574 -0.434463) (xy 257.082715 -0.361557) (xy 257.134391 -0.293128) (xy 257.19216 -0.229758)
			(xy 257.25553 -0.171989) (xy 257.323959 -0.120313) (xy 257.396865 -0.075172) (xy 257.473625 -0.03695)
			(xy 257.553584 -0.005974) (xy 257.63606 0.017493) (xy 257.72035 0.033249) (xy 257.805733 0.041161)
			(xy 257.891483 0.041161) (xy 257.976866 0.033249) (xy 258.061156 0.017493) (xy 258.143632 -0.005974)
			(xy 258.223591 -0.03695) (xy 258.245794 -0.048006) (xy 261.85622 -0.048006) (xy 261.85622 0.815594)
			(xy 261.856706 0.842863) (xy 261.864468 0.896847) (xy 261.879833 0.949177) (xy 261.90249 0.998787)
			(xy 261.931976 1.044668) (xy 261.967691 1.085885) (xy 262.008908 1.1216) (xy 262.054789 1.151086)
			(xy 262.104399 1.173743) (xy 262.156729 1.189108) (xy 262.210713 1.19687) (xy 262.265251 1.19687)
			(xy 262.319235 1.189108) (xy 262.371565 1.173743) (xy 262.421175 1.151086) (xy 262.467056 1.1216)
			(xy 262.508273 1.085885) (xy 262.543988 1.044668) (xy 262.573474 0.998787) (xy 262.596131 0.949177)
			(xy 262.611496 0.896847) (xy 262.619258 0.842863) (xy 262.619744 0.815594) (xy 262.619744 -0.048006)
			(xy 262.619258 -0.075275) (xy 262.611496 -0.129259) (xy 262.596131 -0.181589) (xy 262.573474 -0.231199)
			(xy 262.543988 -0.27708) (xy 262.508273 -0.318297) (xy 262.467056 -0.354012) (xy 262.421175 -0.383498)
			(xy 262.371565 -0.406155) (xy 262.319235 -0.42152) (xy 262.265251 -0.429282) (xy 262.210713 -0.429282)
			(xy 262.156729 -0.42152) (xy 262.104399 -0.406155) (xy 262.054789 -0.383498) (xy 262.008908 -0.354012)
			(xy 261.967691 -0.318297) (xy 261.931976 -0.27708) (xy 261.90249 -0.231199) (xy 261.879833 -0.181589)
			(xy 261.864468 -0.129259) (xy 261.856706 -0.075275) (xy 261.85622 -0.048006) (xy 258.245794 -0.048006)
			(xy 258.300351 -0.075172) (xy 258.373257 -0.120313) (xy 258.441686 -0.171989) (xy 258.505056 -0.229758)
			(xy 258.562825 -0.293128) (xy 258.614501 -0.361557) (xy 258.659642 -0.434463) (xy 258.697864 -0.511223)
			(xy 258.72884 -0.591182) (xy 258.752307 -0.673658) (xy 258.768063 -0.757948) (xy 258.775975 -0.843331)
			(xy 258.77647 -0.886206) (xy 258.775975 -0.929081) (xy 263.271241 -0.929081) (xy 263.271241 -0.843331)
			(xy 263.279153 -0.757948) (xy 263.294909 -0.673658) (xy 263.318376 -0.591182) (xy 263.349352 -0.511223)
			(xy 263.387574 -0.434463) (xy 263.432715 -0.361557) (xy 263.484391 -0.293128) (xy 263.54216 -0.229758)
			(xy 263.60553 -0.171989) (xy 263.673959 -0.120313) (xy 263.746865 -0.075172) (xy 263.823625 -0.03695)
			(xy 263.903584 -0.005974) (xy 263.98606 0.017493) (xy 264.07035 0.033249) (xy 264.155733 0.041161)
			(xy 264.241483 0.041161) (xy 264.326866 0.033249) (xy 264.411156 0.017493) (xy 264.493632 -0.005974)
			(xy 264.573591 -0.03695) (xy 264.650351 -0.075172) (xy 264.723257 -0.120313) (xy 264.791686 -0.171989)
			(xy 264.855056 -0.229758) (xy 264.912825 -0.293128) (xy 264.964501 -0.361557) (xy 265.009642 -0.434463)
			(xy 265.047864 -0.511223) (xy 265.07884 -0.591182) (xy 265.102307 -0.673658) (xy 265.118063 -0.757948)
			(xy 265.125975 -0.843331) (xy 265.12647 -0.886206) (xy 265.125975 -0.929081) (xy 324.845921 -0.929081)
			(xy 324.845921 -0.843331) (xy 324.853833 -0.757948) (xy 324.869589 -0.673658) (xy 324.893056 -0.591182)
			(xy 324.924032 -0.511223) (xy 324.962254 -0.434463) (xy 325.007395 -0.361557) (xy 325.059071 -0.293128)
			(xy 325.11684 -0.229758) (xy 325.18021 -0.171989) (xy 325.248639 -0.120313) (xy 325.321545 -0.075172)
			(xy 325.398305 -0.03695) (xy 325.478264 -0.005974) (xy 325.56074 0.017493) (xy 325.64503 0.033249)
			(xy 325.730413 0.041161) (xy 325.816163 0.041161) (xy 325.901546 0.033249) (xy 325.985836 0.017493)
			(xy 326.068312 -0.005974) (xy 326.148271 -0.03695) (xy 326.170474 -0.048006) (xy 327.352152 -0.048006)
			(xy 327.352152 0.815594) (xy 327.352638 0.842863) (xy 327.3604 0.896847) (xy 327.375765 0.949177)
			(xy 327.398422 0.998787) (xy 327.427908 1.044668) (xy 327.463623 1.085885) (xy 327.50484 1.1216)
			(xy 327.550721 1.151086) (xy 327.600331 1.173743) (xy 327.652661 1.189108) (xy 327.706645 1.19687)
			(xy 327.761183 1.19687) (xy 327.815167 1.189108) (xy 327.867497 1.173743) (xy 327.917107 1.151086)
			(xy 327.962988 1.1216) (xy 328.004205 1.085885) (xy 328.03992 1.044668) (xy 328.069406 0.998787)
			(xy 328.092063 0.949177) (xy 328.107428 0.896847) (xy 328.11519 0.842863) (xy 328.115676 0.815594)
			(xy 328.115676 -0.048006) (xy 328.11519 -0.075275) (xy 328.107428 -0.129259) (xy 328.092063 -0.181589)
			(xy 328.069406 -0.231199) (xy 328.03992 -0.27708) (xy 328.004205 -0.318297) (xy 327.962988 -0.354012)
			(xy 327.917107 -0.383498) (xy 327.867497 -0.406155) (xy 327.815167 -0.42152) (xy 327.761183 -0.429282)
			(xy 327.706645 -0.429282) (xy 327.652661 -0.42152) (xy 327.600331 -0.406155) (xy 327.550721 -0.383498)
			(xy 327.50484 -0.354012) (xy 327.463623 -0.318297) (xy 327.427908 -0.27708) (xy 327.398422 -0.231199)
			(xy 327.375765 -0.181589) (xy 327.3604 -0.129259) (xy 327.352638 -0.075275) (xy 327.352152 -0.048006)
			(xy 326.170474 -0.048006) (xy 326.225031 -0.075172) (xy 326.297937 -0.120313) (xy 326.366366 -0.171989)
			(xy 326.429736 -0.229758) (xy 326.487505 -0.293128) (xy 326.539181 -0.361557) (xy 326.584322 -0.434463)
			(xy 326.622544 -0.511223) (xy 326.65352 -0.591182) (xy 326.676987 -0.673658) (xy 326.692743 -0.757948)
			(xy 326.700655 -0.843331) (xy 326.70115 -0.886206) (xy 326.700655 -0.929081) (xy 331.195921 -0.929081)
			(xy 331.195921 -0.843331) (xy 331.203833 -0.757948) (xy 331.219589 -0.673658) (xy 331.243056 -0.591182)
			(xy 331.274032 -0.511223) (xy 331.312254 -0.434463) (xy 331.357395 -0.361557) (xy 331.409071 -0.293128)
			(xy 331.46684 -0.229758) (xy 331.53021 -0.171989) (xy 331.598639 -0.120313) (xy 331.671545 -0.075172)
			(xy 331.748305 -0.03695) (xy 331.828264 -0.005974) (xy 331.91074 0.017493) (xy 331.99503 0.033249)
			(xy 332.080413 0.041161) (xy 332.166163 0.041161) (xy 332.251546 0.033249) (xy 332.335836 0.017493)
			(xy 332.418312 -0.005974) (xy 332.498271 -0.03695) (xy 332.575031 -0.075172) (xy 332.647937 -0.120313)
			(xy 332.716366 -0.171989) (xy 332.779736 -0.229758) (xy 332.837505 -0.293128) (xy 332.889181 -0.361557)
			(xy 332.934322 -0.434463) (xy 332.972544 -0.511223) (xy 333.00352 -0.591182) (xy 333.026987 -0.673658)
			(xy 333.042743 -0.757948) (xy 333.050655 -0.843331) (xy 333.05115 -0.886206) (xy 333.050655 -0.929081)
			(xy 335.488267 -0.929081) (xy 335.488267 -0.843331) (xy 335.496179 -0.757948) (xy 335.511935 -0.673658)
			(xy 335.535402 -0.591182) (xy 335.566378 -0.511223) (xy 335.6046 -0.434463) (xy 335.649741 -0.361557)
			(xy 335.701417 -0.293128) (xy 335.759186 -0.229758) (xy 335.822556 -0.171989) (xy 335.890985 -0.120313)
			(xy 335.963891 -0.075172) (xy 336.040651 -0.03695) (xy 336.12061 -0.005974) (xy 336.203086 0.017493)
			(xy 336.287376 0.033249) (xy 336.372759 0.041161) (xy 336.458509 0.041161) (xy 336.543892 0.033249)
			(xy 336.628182 0.017493) (xy 336.710658 -0.005974) (xy 336.790617 -0.03695) (xy 336.81282 -0.048006)
			(xy 340.4235 -0.048006) (xy 340.4235 0.815594) (xy 340.423986 0.842845) (xy 340.431742 0.896793)
			(xy 340.447097 0.949088) (xy 340.469739 0.998665) (xy 340.499205 1.044515) (xy 340.534896 1.085706)
			(xy 340.576087 1.121397) (xy 340.621937 1.150863) (xy 340.671514 1.173505) (xy 340.723809 1.18886)
			(xy 340.777757 1.196616) (xy 340.832259 1.196616) (xy 340.886207 1.18886) (xy 340.938502 1.173505)
			(xy 340.988079 1.150863) (xy 341.033929 1.121397) (xy 341.07512 1.085706) (xy 341.110811 1.044515)
			(xy 341.140277 0.998665) (xy 341.162919 0.949088) (xy 341.178274 0.896793) (xy 341.18603 0.842845)
			(xy 341.186516 0.815594) (xy 341.186516 -0.048006) (xy 341.18603 -0.075257) (xy 341.178274 -0.129205)
			(xy 341.162919 -0.1815) (xy 341.140277 -0.231077) (xy 341.110811 -0.276927) (xy 341.07512 -0.318118)
			(xy 341.033929 -0.353809) (xy 340.988079 -0.383275) (xy 340.938502 -0.405917) (xy 340.886207 -0.421272)
			(xy 340.832259 -0.429028) (xy 340.777757 -0.429028) (xy 340.723809 -0.421272) (xy 340.671514 -0.405917)
			(xy 340.621937 -0.383275) (xy 340.576087 -0.353809) (xy 340.534896 -0.318118) (xy 340.499205 -0.276927)
			(xy 340.469739 -0.231077) (xy 340.447097 -0.1815) (xy 340.431742 -0.129205) (xy 340.423986 -0.075257)
			(xy 340.4235 -0.048006) (xy 336.81282 -0.048006) (xy 336.867377 -0.075172) (xy 336.940283 -0.120313)
			(xy 337.008712 -0.171989) (xy 337.072082 -0.229758) (xy 337.129851 -0.293128) (xy 337.181527 -0.361557)
			(xy 337.226668 -0.434463) (xy 337.26489 -0.511223) (xy 337.295866 -0.591182) (xy 337.319333 -0.673658)
			(xy 337.335089 -0.757948) (xy 337.343001 -0.843331) (xy 337.343496 -0.886206) (xy 337.343001 -0.929081)
			(xy 341.838267 -0.929081) (xy 341.838267 -0.843331) (xy 341.846179 -0.757948) (xy 341.861935 -0.673658)
			(xy 341.885402 -0.591182) (xy 341.916378 -0.511223) (xy 341.9546 -0.434463) (xy 341.999741 -0.361557)
			(xy 342.051417 -0.293128) (xy 342.109186 -0.229758) (xy 342.172556 -0.171989) (xy 342.240985 -0.120313)
			(xy 342.313891 -0.075172) (xy 342.390651 -0.03695) (xy 342.47061 -0.005974) (xy 342.553086 0.017493)
			(xy 342.637376 0.033249) (xy 342.722759 0.041161) (xy 342.808509 0.041161) (xy 342.893892 0.033249)
			(xy 342.978182 0.017493) (xy 343.060658 -0.005974) (xy 343.140617 -0.03695) (xy 343.217377 -0.075172)
			(xy 343.290283 -0.120313) (xy 343.358712 -0.171989) (xy 343.422082 -0.229758) (xy 343.479851 -0.293128)
			(xy 343.531527 -0.361557) (xy 343.576668 -0.434463) (xy 343.61489 -0.511223) (xy 343.645866 -0.591182)
			(xy 343.669333 -0.673658) (xy 343.685089 -0.757948) (xy 343.693001 -0.843331) (xy 343.693496 -0.886206)
			(xy 343.693001 -0.929081) (xy 373.705107 -0.929081) (xy 373.705107 -0.843331) (xy 373.713019 -0.757948)
			(xy 373.728775 -0.673658) (xy 373.752242 -0.591182) (xy 373.783218 -0.511223) (xy 373.82144 -0.434463)
			(xy 373.866581 -0.361557) (xy 373.918257 -0.293128) (xy 373.976026 -0.229758) (xy 374.039396 -0.171989)
			(xy 374.107825 -0.120313) (xy 374.180731 -0.075172) (xy 374.257491 -0.03695) (xy 374.33745 -0.005974)
			(xy 374.419926 0.017493) (xy 374.504216 0.033249) (xy 374.589599 0.041161) (xy 374.675349 0.041161)
			(xy 374.760732 0.033249) (xy 374.845022 0.017493) (xy 374.927498 -0.005974) (xy 375.007457 -0.03695)
			(xy 375.02966 -0.048006) (xy 376.211592 -0.048006) (xy 376.211592 0.815594) (xy 376.212078 0.842845)
			(xy 376.219834 0.896793) (xy 376.235189 0.949088) (xy 376.257831 0.998665) (xy 376.287297 1.044515)
			(xy 376.322988 1.085706) (xy 376.364179 1.121397) (xy 376.410029 1.150863) (xy 376.459606 1.173505)
			(xy 376.511901 1.18886) (xy 376.565849 1.196616) (xy 376.620351 1.196616) (xy 376.674299 1.18886)
			(xy 376.726594 1.173505) (xy 376.776171 1.150863) (xy 376.822021 1.121397) (xy 376.863212 1.085706)
			(xy 376.898903 1.044515) (xy 376.928369 0.998665) (xy 376.951011 0.949088) (xy 376.966366 0.896793)
			(xy 376.974122 0.842845) (xy 376.974608 0.815594) (xy 376.974608 -0.048006) (xy 376.974122 -0.075257)
			(xy 376.966366 -0.129205) (xy 376.951011 -0.1815) (xy 376.928369 -0.231077) (xy 376.898903 -0.276927)
			(xy 376.863212 -0.318118) (xy 376.822021 -0.353809) (xy 376.776171 -0.383275) (xy 376.726594 -0.405917)
			(xy 376.674299 -0.421272) (xy 376.620351 -0.429028) (xy 376.565849 -0.429028) (xy 376.511901 -0.421272)
			(xy 376.459606 -0.405917) (xy 376.410029 -0.383275) (xy 376.364179 -0.353809) (xy 376.322988 -0.318118)
			(xy 376.287297 -0.276927) (xy 376.257831 -0.231077) (xy 376.235189 -0.1815) (xy 376.219834 -0.129205)
			(xy 376.212078 -0.075257) (xy 376.211592 -0.048006) (xy 375.02966 -0.048006) (xy 375.084217 -0.075172)
			(xy 375.157123 -0.120313) (xy 375.225552 -0.171989) (xy 375.288922 -0.229758) (xy 375.346691 -0.293128)
			(xy 375.398367 -0.361557) (xy 375.443508 -0.434463) (xy 375.48173 -0.511223) (xy 375.512706 -0.591182)
			(xy 375.536173 -0.673658) (xy 375.551929 -0.757948) (xy 375.559841 -0.843331) (xy 375.560336 -0.886206)
			(xy 375.559841 -0.929081) (xy 380.055107 -0.929081) (xy 380.055107 -0.843331) (xy 380.063019 -0.757948)
			(xy 380.078775 -0.673658) (xy 380.102242 -0.591182) (xy 380.133218 -0.511223) (xy 380.17144 -0.434463)
			(xy 380.216581 -0.361557) (xy 380.268257 -0.293128) (xy 380.326026 -0.229758) (xy 380.389396 -0.171989)
			(xy 380.457825 -0.120313) (xy 380.530731 -0.075172) (xy 380.607491 -0.03695) (xy 380.68745 -0.005974)
			(xy 380.769926 0.017493) (xy 380.854216 0.033249) (xy 380.939599 0.041161) (xy 381.025349 0.041161)
			(xy 381.110732 0.033249) (xy 381.195022 0.017493) (xy 381.277498 -0.005974) (xy 381.357457 -0.03695)
			(xy 381.434217 -0.075172) (xy 381.507123 -0.120313) (xy 381.575552 -0.171989) (xy 381.638922 -0.229758)
			(xy 381.696691 -0.293128) (xy 381.748367 -0.361557) (xy 381.793508 -0.434463) (xy 381.83173 -0.511223)
			(xy 381.862706 -0.591182) (xy 381.886173 -0.673658) (xy 381.901929 -0.757948) (xy 381.909841 -0.843331)
			(xy 381.910336 -0.886206) (xy 381.909841 -0.929081) (xy 381.901929 -1.014464) (xy 381.886173 -1.098754)
			(xy 381.862706 -1.18123) (xy 381.83173 -1.261189) (xy 381.793508 -1.337949) (xy 381.748367 -1.410855)
			(xy 381.696691 -1.479284) (xy 381.638922 -1.542654) (xy 381.575552 -1.600423) (xy 381.507123 -1.652099)
			(xy 381.434217 -1.69724) (xy 381.357457 -1.735462) (xy 381.277498 -1.766438) (xy 381.195022 -1.789905)
			(xy 381.110732 -1.805661) (xy 381.025349 -1.813573) (xy 380.939599 -1.813573) (xy 380.854216 -1.805661)
			(xy 380.769926 -1.789905) (xy 380.68745 -1.766438) (xy 380.607491 -1.735462) (xy 380.530731 -1.69724)
			(xy 380.457825 -1.652099) (xy 380.389396 -1.600423) (xy 380.326026 -1.542654) (xy 380.268257 -1.479284)
			(xy 380.216581 -1.410855) (xy 380.17144 -1.337949) (xy 380.133218 -1.261189) (xy 380.102242 -1.18123)
			(xy 380.078775 -1.098754) (xy 380.063019 -1.014464) (xy 380.055107 -0.929081) (xy 375.559841 -0.929081)
			(xy 375.551929 -1.014464) (xy 375.536173 -1.098754) (xy 375.512706 -1.18123) (xy 375.48173 -1.261189)
			(xy 375.443508 -1.337949) (xy 375.398367 -1.410855) (xy 375.346691 -1.479284) (xy 375.288922 -1.542654)
			(xy 375.225552 -1.600423) (xy 375.157123 -1.652099) (xy 375.084217 -1.69724) (xy 375.007457 -1.735462)
			(xy 374.927498 -1.766438) (xy 374.845022 -1.789905) (xy 374.760732 -1.805661) (xy 374.675349 -1.813573)
			(xy 374.589599 -1.813573) (xy 374.504216 -1.805661) (xy 374.419926 -1.789905) (xy 374.33745 -1.766438)
			(xy 374.257491 -1.735462) (xy 374.180731 -1.69724) (xy 374.107825 -1.652099) (xy 374.039396 -1.600423)
			(xy 373.976026 -1.542654) (xy 373.918257 -1.479284) (xy 373.866581 -1.410855) (xy 373.82144 -1.337949)
			(xy 373.783218 -1.261189) (xy 373.752242 -1.18123) (xy 373.728775 -1.098754) (xy 373.713019 -1.014464)
			(xy 373.705107 -0.929081) (xy 343.693001 -0.929081) (xy 343.685089 -1.014464) (xy 343.669333 -1.098754)
			(xy 343.645866 -1.18123) (xy 343.61489 -1.261189) (xy 343.576668 -1.337949) (xy 343.531527 -1.410855)
			(xy 343.479851 -1.479284) (xy 343.422082 -1.542654) (xy 343.358712 -1.600423) (xy 343.290283 -1.652099)
			(xy 343.217377 -1.69724) (xy 343.140617 -1.735462) (xy 343.060658 -1.766438) (xy 342.978182 -1.789905)
			(xy 342.893892 -1.805661) (xy 342.808509 -1.813573) (xy 342.722759 -1.813573) (xy 342.637376 -1.805661)
			(xy 342.553086 -1.789905) (xy 342.47061 -1.766438) (xy 342.390651 -1.735462) (xy 342.313891 -1.69724)
			(xy 342.240985 -1.652099) (xy 342.172556 -1.600423) (xy 342.109186 -1.542654) (xy 342.051417 -1.479284)
			(xy 341.999741 -1.410855) (xy 341.9546 -1.337949) (xy 341.916378 -1.261189) (xy 341.885402 -1.18123)
			(xy 341.861935 -1.098754) (xy 341.846179 -1.014464) (xy 341.838267 -0.929081) (xy 337.343001 -0.929081)
			(xy 337.335089 -1.014464) (xy 337.319333 -1.098754) (xy 337.295866 -1.18123) (xy 337.26489 -1.261189)
			(xy 337.226668 -1.337949) (xy 337.181527 -1.410855) (xy 337.129851 -1.479284) (xy 337.072082 -1.542654)
			(xy 337.008712 -1.600423) (xy 336.940283 -1.652099) (xy 336.867377 -1.69724) (xy 336.790617 -1.735462)
			(xy 336.710658 -1.766438) (xy 336.628182 -1.789905) (xy 336.543892 -1.805661) (xy 336.458509 -1.813573)
			(xy 336.372759 -1.813573) (xy 336.287376 -1.805661) (xy 336.203086 -1.789905) (xy 336.12061 -1.766438)
			(xy 336.040651 -1.735462) (xy 335.963891 -1.69724) (xy 335.890985 -1.652099) (xy 335.822556 -1.600423)
			(xy 335.759186 -1.542654) (xy 335.701417 -1.479284) (xy 335.649741 -1.410855) (xy 335.6046 -1.337949)
			(xy 335.566378 -1.261189) (xy 335.535402 -1.18123) (xy 335.511935 -1.098754) (xy 335.496179 -1.014464)
			(xy 335.488267 -0.929081) (xy 333.050655 -0.929081) (xy 333.042743 -1.014464) (xy 333.026987 -1.098754)
			(xy 333.00352 -1.18123) (xy 332.972544 -1.261189) (xy 332.934322 -1.337949) (xy 332.889181 -1.410855)
			(xy 332.837505 -1.479284) (xy 332.779736 -1.542654) (xy 332.716366 -1.600423) (xy 332.647937 -1.652099)
			(xy 332.575031 -1.69724) (xy 332.498271 -1.735462) (xy 332.418312 -1.766438) (xy 332.335836 -1.789905)
			(xy 332.251546 -1.805661) (xy 332.166163 -1.813573) (xy 332.080413 -1.813573) (xy 331.99503 -1.805661)
			(xy 331.91074 -1.789905) (xy 331.828264 -1.766438) (xy 331.748305 -1.735462) (xy 331.671545 -1.69724)
			(xy 331.598639 -1.652099) (xy 331.53021 -1.600423) (xy 331.46684 -1.542654) (xy 331.409071 -1.479284)
			(xy 331.357395 -1.410855) (xy 331.312254 -1.337949) (xy 331.274032 -1.261189) (xy 331.243056 -1.18123)
			(xy 331.219589 -1.098754) (xy 331.203833 -1.014464) (xy 331.195921 -0.929081) (xy 326.700655 -0.929081)
			(xy 326.692743 -1.014464) (xy 326.676987 -1.098754) (xy 326.65352 -1.18123) (xy 326.622544 -1.261189)
			(xy 326.584322 -1.337949) (xy 326.539181 -1.410855) (xy 326.487505 -1.479284) (xy 326.429736 -1.542654)
			(xy 326.366366 -1.600423) (xy 326.297937 -1.652099) (xy 326.225031 -1.69724) (xy 326.148271 -1.735462)
			(xy 326.068312 -1.766438) (xy 325.985836 -1.789905) (xy 325.901546 -1.805661) (xy 325.816163 -1.813573)
			(xy 325.730413 -1.813573) (xy 325.64503 -1.805661) (xy 325.56074 -1.789905) (xy 325.478264 -1.766438)
			(xy 325.398305 -1.735462) (xy 325.321545 -1.69724) (xy 325.248639 -1.652099) (xy 325.18021 -1.600423)
			(xy 325.11684 -1.542654) (xy 325.059071 -1.479284) (xy 325.007395 -1.410855) (xy 324.962254 -1.337949)
			(xy 324.924032 -1.261189) (xy 324.893056 -1.18123) (xy 324.869589 -1.098754) (xy 324.853833 -1.014464)
			(xy 324.845921 -0.929081) (xy 265.125975 -0.929081) (xy 265.118063 -1.014464) (xy 265.102307 -1.098754)
			(xy 265.07884 -1.18123) (xy 265.047864 -1.261189) (xy 265.009642 -1.337949) (xy 264.964501 -1.410855)
			(xy 264.912825 -1.479284) (xy 264.855056 -1.542654) (xy 264.791686 -1.600423) (xy 264.723257 -1.652099)
			(xy 264.650351 -1.69724) (xy 264.573591 -1.735462) (xy 264.493632 -1.766438) (xy 264.411156 -1.789905)
			(xy 264.326866 -1.805661) (xy 264.241483 -1.813573) (xy 264.155733 -1.813573) (xy 264.07035 -1.805661)
			(xy 263.98606 -1.789905) (xy 263.903584 -1.766438) (xy 263.823625 -1.735462) (xy 263.746865 -1.69724)
			(xy 263.673959 -1.652099) (xy 263.60553 -1.600423) (xy 263.54216 -1.542654) (xy 263.484391 -1.479284)
			(xy 263.432715 -1.410855) (xy 263.387574 -1.337949) (xy 263.349352 -1.261189) (xy 263.318376 -1.18123)
			(xy 263.294909 -1.098754) (xy 263.279153 -1.014464) (xy 263.271241 -0.929081) (xy 258.775975 -0.929081)
			(xy 258.768063 -1.014464) (xy 258.752307 -1.098754) (xy 258.72884 -1.18123) (xy 258.697864 -1.261189)
			(xy 258.659642 -1.337949) (xy 258.614501 -1.410855) (xy 258.562825 -1.479284) (xy 258.505056 -1.542654)
			(xy 258.441686 -1.600423) (xy 258.373257 -1.652099) (xy 258.300351 -1.69724) (xy 258.223591 -1.735462)
			(xy 258.143632 -1.766438) (xy 258.061156 -1.789905) (xy 257.976866 -1.805661) (xy 257.891483 -1.813573)
			(xy 257.805733 -1.813573) (xy 257.72035 -1.805661) (xy 257.63606 -1.789905) (xy 257.553584 -1.766438)
			(xy 257.473625 -1.735462) (xy 257.396865 -1.69724) (xy 257.323959 -1.652099) (xy 257.25553 -1.600423)
			(xy 257.19216 -1.542654) (xy 257.134391 -1.479284) (xy 257.082715 -1.410855) (xy 257.037574 -1.337949)
			(xy 256.999352 -1.261189) (xy 256.968376 -1.18123) (xy 256.944909 -1.098754) (xy 256.929153 -1.014464)
			(xy 256.921241 -0.929081) (xy 254.465119 -0.929081) (xy 254.465087 -0.931875) (xy 254.457175 -1.017258)
			(xy 254.441419 -1.101548) (xy 254.417952 -1.184024) (xy 254.386976 -1.263983) (xy 254.348754 -1.340743)
			(xy 254.303613 -1.413649) (xy 254.251937 -1.482078) (xy 254.194168 -1.545448) (xy 254.130798 -1.603217)
			(xy 254.062369 -1.654893) (xy 253.989463 -1.700034) (xy 253.912703 -1.738256) (xy 253.832744 -1.769232)
			(xy 253.750268 -1.792699) (xy 253.665978 -1.808455) (xy 253.580595 -1.816367) (xy 253.494845 -1.816367)
			(xy 253.409462 -1.808455) (xy 253.325172 -1.792699) (xy 253.242696 -1.769232) (xy 253.162737 -1.738256)
			(xy 253.085977 -1.700034) (xy 253.013071 -1.654893) (xy 252.944642 -1.603217) (xy 252.881272 -1.545448)
			(xy 252.823503 -1.482078) (xy 252.771827 -1.413649) (xy 252.726686 -1.340743) (xy 252.688464 -1.263983)
			(xy 252.657488 -1.184024) (xy 252.634021 -1.101548) (xy 252.618265 -1.017258) (xy 252.610353 -0.931875)
			(xy 248.115087 -0.931875) (xy 248.107175 -1.017258) (xy 248.091419 -1.101548) (xy 248.067952 -1.184024)
			(xy 248.036976 -1.263983) (xy 247.998754 -1.340743) (xy 247.953613 -1.413649) (xy 247.901937 -1.482078)
			(xy 247.844168 -1.545448) (xy 247.780798 -1.603217) (xy 247.712369 -1.654893) (xy 247.639463 -1.700034)
			(xy 247.562703 -1.738256) (xy 247.482744 -1.769232) (xy 247.400268 -1.792699) (xy 247.315978 -1.808455)
			(xy 247.230595 -1.816367) (xy 247.144845 -1.816367) (xy 247.059462 -1.808455) (xy 246.975172 -1.792699)
			(xy 246.892696 -1.769232) (xy 246.812737 -1.738256) (xy 246.735977 -1.700034) (xy 246.663071 -1.654893)
			(xy 246.594642 -1.603217) (xy 246.531272 -1.545448) (xy 246.473503 -1.482078) (xy 246.421827 -1.413649)
			(xy 246.376686 -1.340743) (xy 246.338464 -1.263983) (xy 246.307488 -1.184024) (xy 246.284021 -1.101548)
			(xy 246.268265 -1.017258) (xy 246.260353 -0.931875) (xy 216.248247 -0.931875) (xy 216.240335 -1.017258)
			(xy 216.224579 -1.101548) (xy 216.201112 -1.184024) (xy 216.170136 -1.263983) (xy 216.131914 -1.340743)
			(xy 216.086773 -1.413649) (xy 216.035097 -1.482078) (xy 215.977328 -1.545448) (xy 215.913958 -1.603217)
			(xy 215.845529 -1.654893) (xy 215.772623 -1.700034) (xy 215.695863 -1.738256) (xy 215.615904 -1.769232)
			(xy 215.533428 -1.792699) (xy 215.449138 -1.808455) (xy 215.363755 -1.816367) (xy 215.278005 -1.816367)
			(xy 215.192622 -1.808455) (xy 215.108332 -1.792699) (xy 215.025856 -1.769232) (xy 214.945897 -1.738256)
			(xy 214.869137 -1.700034) (xy 214.796231 -1.654893) (xy 214.727802 -1.603217) (xy 214.664432 -1.545448)
			(xy 214.606663 -1.482078) (xy 214.554987 -1.413649) (xy 214.509846 -1.340743) (xy 214.471624 -1.263983)
			(xy 214.440648 -1.184024) (xy 214.417181 -1.101548) (xy 214.401425 -1.017258) (xy 214.393513 -0.931875)
			(xy 209.898247 -0.931875) (xy 209.890335 -1.017258) (xy 209.874579 -1.101548) (xy 209.851112 -1.184024)
			(xy 209.820136 -1.263983) (xy 209.781914 -1.340743) (xy 209.736773 -1.413649) (xy 209.685097 -1.482078)
			(xy 209.627328 -1.545448) (xy 209.563958 -1.603217) (xy 209.495529 -1.654893) (xy 209.422623 -1.700034)
			(xy 209.345863 -1.738256) (xy 209.265904 -1.769232) (xy 209.183428 -1.792699) (xy 209.099138 -1.808455)
			(xy 209.013755 -1.816367) (xy 208.928005 -1.816367) (xy 208.842622 -1.808455) (xy 208.758332 -1.792699)
			(xy 208.675856 -1.769232) (xy 208.595897 -1.738256) (xy 208.519137 -1.700034) (xy 208.446231 -1.654893)
			(xy 208.377802 -1.603217) (xy 208.314432 -1.545448) (xy 208.256663 -1.482078) (xy 208.204987 -1.413649)
			(xy 208.159846 -1.340743) (xy 208.121624 -1.263983) (xy 208.090648 -1.184024) (xy 208.067181 -1.101548)
			(xy 208.051425 -1.017258) (xy 208.043513 -0.931875) (xy 84.20989 -0.931875) (xy 84.20989 -7.78002)
			(xy 84.210412 -7.835827) (xy 84.218755 -7.947128) (xy 84.235391 -8.057495) (xy 84.260229 -8.16631)
			(xy 84.293128 -8.272964) (xy 84.333906 -8.376862) (xy 84.382334 -8.477422) (xy 84.438141 -8.574082)
			(xy 84.501016 -8.666301) (xy 84.570606 -8.753563) (xy 84.646523 -8.835382) (xy 84.728341 -8.911298)
			(xy 84.815604 -8.980888) (xy 84.907824 -9.043762) (xy 85.004484 -9.099569) (xy 85.105044 -9.147996)
			(xy 85.208942 -9.188774) (xy 85.315596 -9.221673) (xy 85.424411 -9.24651) (xy 85.534778 -9.263146)
			(xy 85.646079 -9.271488) (xy 85.701886 -9.272016) (xy 122.102118 -9.272016) (xy 122.157925 -9.271494)
			(xy 122.269226 -9.263152) (xy 122.379593 -9.246515) (xy 122.488409 -9.221678) (xy 122.595063 -9.188778)
			(xy 122.698961 -9.148001) (xy 122.799522 -9.099573) (xy 122.896182 -9.043766) (xy 122.988401 -8.980891)
			(xy 123.075664 -8.911301) (xy 123.157483 -8.835384) (xy 123.2334 -8.753566) (xy 123.30299 -8.666303)
			(xy 123.365865 -8.574084) (xy 123.421672 -8.477423) (xy 123.4701 -8.376863) (xy 123.510878 -8.272965)
			(xy 123.543777 -8.16631) (xy 123.568615 -8.057495) (xy 123.585251 -7.947128) (xy 123.593594 -7.835827)
			(xy 123.594114 -7.78002) (xy 123.594114 -4.2799) (xy 123.594598 -4.209546) (xy 123.602488 -4.06906)
			(xy 123.618242 -3.929237) (xy 123.641812 -3.790517) (xy 123.673122 -3.653337) (xy 123.712075 -3.518129)
			(xy 123.758548 -3.385317) (xy 123.812395 -3.25532) (xy 123.873446 -3.128547) (xy 123.941509 -3.005396)
			(xy 124.01637 -2.886255) (xy 124.097794 -2.7715) (xy 124.185524 -2.66149) (xy 124.279284 -2.556573)
			(xy 124.37878 -2.457077) (xy 124.483698 -2.363317) (xy 124.593708 -2.275588) (xy 124.708464 -2.194165)
			(xy 124.827605 -2.119304) (xy 124.950755 -2.051241) (xy 125.077529 -1.990191) (xy 125.207526 -1.936345)
			(xy 125.340338 -1.889872) (xy 125.475547 -1.85092) (xy 125.612727 -1.81961) (xy 125.751447 -1.796041)
			(xy 125.89127 -1.780287) (xy 126.031756 -1.772398) (xy 126.10211 -1.771904) (xy 194.701922 -1.771904)
			(xy 194.772275 -1.772398) (xy 194.912761 -1.780289) (xy 195.052582 -1.796044) (xy 195.191301 -1.819614)
			(xy 195.32848 -1.850925) (xy 195.463687 -1.889879) (xy 195.596497 -1.936352) (xy 195.726493 -1.990199)
			(xy 195.853265 -2.05125) (xy 195.976414 -2.119314) (xy 196.095554 -2.194175) (xy 196.210308 -2.275598)
			(xy 196.320316 -2.363328) (xy 196.425233 -2.457088) (xy 196.524727 -2.556583) (xy 196.618486 -2.6615)
			(xy 196.706215 -2.77151) (xy 196.787637 -2.886265) (xy 196.862497 -3.005405) (xy 196.93056 -3.128555)
			(xy 196.99161 -3.255327) (xy 197.045455 -3.385323) (xy 197.075741 -3.471875) (xy 208.043513 -3.471875)
			(xy 208.043513 -3.386125) (xy 208.051425 -3.300742) (xy 208.067181 -3.216452) (xy 208.090648 -3.133976)
			(xy 208.121624 -3.054017) (xy 208.159846 -2.977257) (xy 208.204987 -2.904351) (xy 208.256663 -2.835922)
			(xy 208.314432 -2.772552) (xy 208.377802 -2.714783) (xy 208.446231 -2.663107) (xy 208.519137 -2.617966)
			(xy 208.595897 -2.579744) (xy 208.675856 -2.548768) (xy 208.758332 -2.525301) (xy 208.842622 -2.509545)
			(xy 208.928005 -2.501633) (xy 209.013755 -2.501633) (xy 209.099138 -2.509545) (xy 209.183428 -2.525301)
			(xy 209.265904 -2.548768) (xy 209.345863 -2.579744) (xy 209.368066 -2.5908) (xy 212.978492 -2.5908)
			(xy 212.978492 -1.7272) (xy 212.978978 -1.699931) (xy 212.98674 -1.645947) (xy 213.002105 -1.593617)
			(xy 213.024762 -1.544007) (xy 213.054248 -1.498126) (xy 213.089963 -1.456909) (xy 213.13118 -1.421194)
			(xy 213.177061 -1.391708) (xy 213.226671 -1.369051) (xy 213.279001 -1.353686) (xy 213.332985 -1.345924)
			(xy 213.387523 -1.345924) (xy 213.441507 -1.353686) (xy 213.493837 -1.369051) (xy 213.543447 -1.391708)
			(xy 213.589328 -1.421194) (xy 213.630545 -1.456909) (xy 213.66626 -1.498126) (xy 213.695746 -1.544007)
			(xy 213.718403 -1.593617) (xy 213.733768 -1.645947) (xy 213.74153 -1.699931) (xy 213.742016 -1.7272)
			(xy 213.742016 -2.5908) (xy 213.74153 -2.618069) (xy 213.733768 -2.672053) (xy 213.718403 -2.724383)
			(xy 213.695746 -2.773993) (xy 213.66626 -2.819874) (xy 213.630545 -2.861091) (xy 213.589328 -2.896806)
			(xy 213.543447 -2.926292) (xy 213.493837 -2.948949) (xy 213.441507 -2.964314) (xy 213.387523 -2.972076)
			(xy 213.332985 -2.972076) (xy 213.279001 -2.964314) (xy 213.226671 -2.948949) (xy 213.177061 -2.926292)
			(xy 213.13118 -2.896806) (xy 213.089963 -2.861091) (xy 213.054248 -2.819874) (xy 213.024762 -2.773993)
			(xy 213.002105 -2.724383) (xy 212.98674 -2.672053) (xy 212.978978 -2.618069) (xy 212.978492 -2.5908)
			(xy 209.368066 -2.5908) (xy 209.422623 -2.617966) (xy 209.495529 -2.663107) (xy 209.563958 -2.714783)
			(xy 209.627328 -2.772552) (xy 209.685097 -2.835922) (xy 209.736773 -2.904351) (xy 209.781914 -2.977257)
			(xy 209.820136 -3.054017) (xy 209.851112 -3.133976) (xy 209.874579 -3.216452) (xy 209.890335 -3.300742)
			(xy 209.898247 -3.386125) (xy 209.898742 -3.429) (xy 209.898247 -3.471875) (xy 214.393513 -3.471875)
			(xy 214.393513 -3.386125) (xy 214.401425 -3.300742) (xy 214.417181 -3.216452) (xy 214.440648 -3.133976)
			(xy 214.471624 -3.054017) (xy 214.509846 -2.977257) (xy 214.554987 -2.904351) (xy 214.606663 -2.835922)
			(xy 214.664432 -2.772552) (xy 214.727802 -2.714783) (xy 214.796231 -2.663107) (xy 214.869137 -2.617966)
			(xy 214.945897 -2.579744) (xy 215.025856 -2.548768) (xy 215.108332 -2.525301) (xy 215.192622 -2.509545)
			(xy 215.278005 -2.501633) (xy 215.363755 -2.501633) (xy 215.449138 -2.509545) (xy 215.533428 -2.525301)
			(xy 215.615904 -2.548768) (xy 215.695863 -2.579744) (xy 215.772623 -2.617966) (xy 215.845529 -2.663107)
			(xy 215.913958 -2.714783) (xy 215.977328 -2.772552) (xy 216.035097 -2.835922) (xy 216.086773 -2.904351)
			(xy 216.131914 -2.977257) (xy 216.170136 -3.054017) (xy 216.201112 -3.133976) (xy 216.224579 -3.216452)
			(xy 216.240335 -3.300742) (xy 216.248247 -3.386125) (xy 216.248742 -3.429) (xy 216.248247 -3.471875)
			(xy 246.260353 -3.471875) (xy 246.260353 -3.386125) (xy 246.268265 -3.300742) (xy 246.284021 -3.216452)
			(xy 246.307488 -3.133976) (xy 246.338464 -3.054017) (xy 246.376686 -2.977257) (xy 246.421827 -2.904351)
			(xy 246.473503 -2.835922) (xy 246.531272 -2.772552) (xy 246.594642 -2.714783) (xy 246.663071 -2.663107)
			(xy 246.735977 -2.617966) (xy 246.812737 -2.579744) (xy 246.892696 -2.548768) (xy 246.975172 -2.525301)
			(xy 247.059462 -2.509545) (xy 247.144845 -2.501633) (xy 247.230595 -2.501633) (xy 247.315978 -2.509545)
			(xy 247.400268 -2.525301) (xy 247.482744 -2.548768) (xy 247.562703 -2.579744) (xy 247.584906 -2.5908)
			(xy 248.766584 -2.5908) (xy 248.766584 -1.7272) (xy 248.76707 -1.699931) (xy 248.774832 -1.645947)
			(xy 248.790197 -1.593617) (xy 248.812854 -1.544007) (xy 248.84234 -1.498126) (xy 248.878055 -1.456909)
			(xy 248.919272 -1.421194) (xy 248.965153 -1.391708) (xy 249.014763 -1.369051) (xy 249.067093 -1.353686)
			(xy 249.121077 -1.345924) (xy 249.175615 -1.345924) (xy 249.229599 -1.353686) (xy 249.281929 -1.369051)
			(xy 249.331539 -1.391708) (xy 249.37742 -1.421194) (xy 249.418637 -1.456909) (xy 249.454352 -1.498126)
			(xy 249.483838 -1.544007) (xy 249.506495 -1.593617) (xy 249.52186 -1.645947) (xy 249.529622 -1.699931)
			(xy 249.530108 -1.7272) (xy 249.530108 -2.5908) (xy 249.529622 -2.618069) (xy 249.52186 -2.672053)
			(xy 249.506495 -2.724383) (xy 249.483838 -2.773993) (xy 249.454352 -2.819874) (xy 249.418637 -2.861091)
			(xy 249.37742 -2.896806) (xy 249.331539 -2.926292) (xy 249.281929 -2.948949) (xy 249.229599 -2.964314)
			(xy 249.175615 -2.972076) (xy 249.121077 -2.972076) (xy 249.067093 -2.964314) (xy 249.014763 -2.948949)
			(xy 248.965153 -2.926292) (xy 248.919272 -2.896806) (xy 248.878055 -2.861091) (xy 248.84234 -2.819874)
			(xy 248.812854 -2.773993) (xy 248.790197 -2.724383) (xy 248.774832 -2.672053) (xy 248.76707 -2.618069)
			(xy 248.766584 -2.5908) (xy 247.584906 -2.5908) (xy 247.639463 -2.617966) (xy 247.712369 -2.663107)
			(xy 247.780798 -2.714783) (xy 247.844168 -2.772552) (xy 247.901937 -2.835922) (xy 247.953613 -2.904351)
			(xy 247.998754 -2.977257) (xy 248.036976 -3.054017) (xy 248.067952 -3.133976) (xy 248.091419 -3.216452)
			(xy 248.107175 -3.300742) (xy 248.115087 -3.386125) (xy 248.115582 -3.429) (xy 248.115087 -3.471875)
			(xy 252.610353 -3.471875) (xy 252.610353 -3.386125) (xy 252.618265 -3.300742) (xy 252.634021 -3.216452)
			(xy 252.657488 -3.133976) (xy 252.688464 -3.054017) (xy 252.726686 -2.977257) (xy 252.771827 -2.904351)
			(xy 252.823503 -2.835922) (xy 252.881272 -2.772552) (xy 252.944642 -2.714783) (xy 253.013071 -2.663107)
			(xy 253.085977 -2.617966) (xy 253.162737 -2.579744) (xy 253.242696 -2.548768) (xy 253.325172 -2.525301)
			(xy 253.409462 -2.509545) (xy 253.494845 -2.501633) (xy 253.580595 -2.501633) (xy 253.665978 -2.509545)
			(xy 253.750268 -2.525301) (xy 253.832744 -2.548768) (xy 253.912703 -2.579744) (xy 253.989463 -2.617966)
			(xy 254.062369 -2.663107) (xy 254.130798 -2.714783) (xy 254.194168 -2.772552) (xy 254.251937 -2.835922)
			(xy 254.303613 -2.904351) (xy 254.348754 -2.977257) (xy 254.386976 -3.054017) (xy 254.417952 -3.133976)
			(xy 254.441419 -3.216452) (xy 254.457175 -3.300742) (xy 254.465087 -3.386125) (xy 254.465582 -3.429)
			(xy 254.465119 -3.469081) (xy 256.921241 -3.469081) (xy 256.921241 -3.383331) (xy 256.929153 -3.297948)
			(xy 256.944909 -3.213658) (xy 256.968376 -3.131182) (xy 256.999352 -3.051223) (xy 257.037574 -2.974463)
			(xy 257.082715 -2.901557) (xy 257.134391 -2.833128) (xy 257.19216 -2.769758) (xy 257.25553 -2.711989)
			(xy 257.323959 -2.660313) (xy 257.396865 -2.615172) (xy 257.473625 -2.57695) (xy 257.553584 -2.545974)
			(xy 257.63606 -2.522507) (xy 257.72035 -2.506751) (xy 257.805733 -2.498839) (xy 257.891483 -2.498839)
			(xy 257.976866 -2.506751) (xy 258.061156 -2.522507) (xy 258.143632 -2.545974) (xy 258.223591 -2.57695)
			(xy 258.300351 -2.615172) (xy 258.373257 -2.660313) (xy 258.441686 -2.711989) (xy 258.505056 -2.769758)
			(xy 258.562825 -2.833128) (xy 258.614501 -2.901557) (xy 258.659642 -2.974463) (xy 258.697864 -3.051223)
			(xy 258.72884 -3.131182) (xy 258.752307 -3.213658) (xy 258.768063 -3.297948) (xy 258.775975 -3.383331)
			(xy 258.77647 -3.426206) (xy 258.775975 -3.469081) (xy 263.271241 -3.469081) (xy 263.271241 -3.383331)
			(xy 263.279153 -3.297948) (xy 263.294909 -3.213658) (xy 263.318376 -3.131182) (xy 263.349352 -3.051223)
			(xy 263.387574 -2.974463) (xy 263.432715 -2.901557) (xy 263.484391 -2.833128) (xy 263.54216 -2.769758)
			(xy 263.60553 -2.711989) (xy 263.673959 -2.660313) (xy 263.746865 -2.615172) (xy 263.823625 -2.57695)
			(xy 263.903584 -2.545974) (xy 263.98606 -2.522507) (xy 264.07035 -2.506751) (xy 264.155733 -2.498839)
			(xy 264.241483 -2.498839) (xy 264.326866 -2.506751) (xy 264.411156 -2.522507) (xy 264.493632 -2.545974)
			(xy 264.573591 -2.57695) (xy 264.650351 -2.615172) (xy 264.723257 -2.660313) (xy 264.791686 -2.711989)
			(xy 264.855056 -2.769758) (xy 264.912825 -2.833128) (xy 264.964501 -2.901557) (xy 265.009642 -2.974463)
			(xy 265.047864 -3.051223) (xy 265.07884 -3.131182) (xy 265.102307 -3.213658) (xy 265.118063 -3.297948)
			(xy 265.125975 -3.383331) (xy 265.12647 -3.426206) (xy 265.125975 -3.469081) (xy 324.845921 -3.469081)
			(xy 324.845921 -3.383331) (xy 324.853833 -3.297948) (xy 324.869589 -3.213658) (xy 324.893056 -3.131182)
			(xy 324.924032 -3.051223) (xy 324.962254 -2.974463) (xy 325.007395 -2.901557) (xy 325.059071 -2.833128)
			(xy 325.11684 -2.769758) (xy 325.18021 -2.711989) (xy 325.248639 -2.660313) (xy 325.321545 -2.615172)
			(xy 325.398305 -2.57695) (xy 325.478264 -2.545974) (xy 325.56074 -2.522507) (xy 325.64503 -2.506751)
			(xy 325.730413 -2.498839) (xy 325.816163 -2.498839) (xy 325.901546 -2.506751) (xy 325.985836 -2.522507)
			(xy 326.068312 -2.545974) (xy 326.148271 -2.57695) (xy 326.225031 -2.615172) (xy 326.297937 -2.660313)
			(xy 326.366366 -2.711989) (xy 326.429736 -2.769758) (xy 326.487505 -2.833128) (xy 326.539181 -2.901557)
			(xy 326.584322 -2.974463) (xy 326.622544 -3.051223) (xy 326.65352 -3.131182) (xy 326.676987 -3.213658)
			(xy 326.692743 -3.297948) (xy 326.700655 -3.383331) (xy 326.70115 -3.426206) (xy 326.700655 -3.469081)
			(xy 331.195921 -3.469081) (xy 331.195921 -3.383331) (xy 331.203833 -3.297948) (xy 331.219589 -3.213658)
			(xy 331.243056 -3.131182) (xy 331.274032 -3.051223) (xy 331.312254 -2.974463) (xy 331.357395 -2.901557)
			(xy 331.409071 -2.833128) (xy 331.46684 -2.769758) (xy 331.53021 -2.711989) (xy 331.598639 -2.660313)
			(xy 331.671545 -2.615172) (xy 331.748305 -2.57695) (xy 331.828264 -2.545974) (xy 331.91074 -2.522507)
			(xy 331.99503 -2.506751) (xy 332.080413 -2.498839) (xy 332.166163 -2.498839) (xy 332.251546 -2.506751)
			(xy 332.335836 -2.522507) (xy 332.418312 -2.545974) (xy 332.498271 -2.57695) (xy 332.575031 -2.615172)
			(xy 332.647937 -2.660313) (xy 332.716366 -2.711989) (xy 332.779736 -2.769758) (xy 332.837505 -2.833128)
			(xy 332.889181 -2.901557) (xy 332.934322 -2.974463) (xy 332.972544 -3.051223) (xy 333.00352 -3.131182)
			(xy 333.026987 -3.213658) (xy 333.042743 -3.297948) (xy 333.050655 -3.383331) (xy 333.05115 -3.426206)
			(xy 333.050655 -3.469081) (xy 335.488267 -3.469081) (xy 335.488267 -3.383331) (xy 335.496179 -3.297948)
			(xy 335.511935 -3.213658) (xy 335.535402 -3.131182) (xy 335.566378 -3.051223) (xy 335.6046 -2.974463)
			(xy 335.649741 -2.901557) (xy 335.701417 -2.833128) (xy 335.759186 -2.769758) (xy 335.822556 -2.711989)
			(xy 335.890985 -2.660313) (xy 335.963891 -2.615172) (xy 336.040651 -2.57695) (xy 336.12061 -2.545974)
			(xy 336.203086 -2.522507) (xy 336.287376 -2.506751) (xy 336.372759 -2.498839) (xy 336.458509 -2.498839)
			(xy 336.543892 -2.506751) (xy 336.628182 -2.522507) (xy 336.710658 -2.545974) (xy 336.790617 -2.57695)
			(xy 336.867377 -2.615172) (xy 336.940283 -2.660313) (xy 337.008712 -2.711989) (xy 337.072082 -2.769758)
			(xy 337.129851 -2.833128) (xy 337.181527 -2.901557) (xy 337.226668 -2.974463) (xy 337.26489 -3.051223)
			(xy 337.295866 -3.131182) (xy 337.319333 -3.213658) (xy 337.335089 -3.297948) (xy 337.343001 -3.383331)
			(xy 337.343496 -3.426206) (xy 337.343001 -3.469081) (xy 341.838267 -3.469081) (xy 341.838267 -3.383331)
			(xy 341.846179 -3.297948) (xy 341.861935 -3.213658) (xy 341.885402 -3.131182) (xy 341.916378 -3.051223)
			(xy 341.9546 -2.974463) (xy 341.999741 -2.901557) (xy 342.051417 -2.833128) (xy 342.109186 -2.769758)
			(xy 342.172556 -2.711989) (xy 342.240985 -2.660313) (xy 342.313891 -2.615172) (xy 342.390651 -2.57695)
			(xy 342.47061 -2.545974) (xy 342.553086 -2.522507) (xy 342.637376 -2.506751) (xy 342.722759 -2.498839)
			(xy 342.808509 -2.498839) (xy 342.893892 -2.506751) (xy 342.978182 -2.522507) (xy 343.060658 -2.545974)
			(xy 343.140617 -2.57695) (xy 343.217377 -2.615172) (xy 343.290283 -2.660313) (xy 343.358712 -2.711989)
			(xy 343.422082 -2.769758) (xy 343.479851 -2.833128) (xy 343.531527 -2.901557) (xy 343.576668 -2.974463)
			(xy 343.61489 -3.051223) (xy 343.645866 -3.131182) (xy 343.669333 -3.213658) (xy 343.685089 -3.297948)
			(xy 343.693001 -3.383331) (xy 343.693496 -3.426206) (xy 343.693001 -3.469081) (xy 373.705107 -3.469081)
			(xy 373.705107 -3.383331) (xy 373.713019 -3.297948) (xy 373.728775 -3.213658) (xy 373.752242 -3.131182)
			(xy 373.783218 -3.051223) (xy 373.82144 -2.974463) (xy 373.866581 -2.901557) (xy 373.918257 -2.833128)
			(xy 373.976026 -2.769758) (xy 374.039396 -2.711989) (xy 374.107825 -2.660313) (xy 374.180731 -2.615172)
			(xy 374.257491 -2.57695) (xy 374.33745 -2.545974) (xy 374.419926 -2.522507) (xy 374.504216 -2.506751)
			(xy 374.589599 -2.498839) (xy 374.675349 -2.498839) (xy 374.760732 -2.506751) (xy 374.845022 -2.522507)
			(xy 374.927498 -2.545974) (xy 375.007457 -2.57695) (xy 375.084217 -2.615172) (xy 375.157123 -2.660313)
			(xy 375.225552 -2.711989) (xy 375.288922 -2.769758) (xy 375.346691 -2.833128) (xy 375.398367 -2.901557)
			(xy 375.443508 -2.974463) (xy 375.48173 -3.051223) (xy 375.512706 -3.131182) (xy 375.536173 -3.213658)
			(xy 375.551929 -3.297948) (xy 375.559841 -3.383331) (xy 375.560336 -3.426206) (xy 375.559841 -3.469081)
			(xy 380.055107 -3.469081) (xy 380.055107 -3.383331) (xy 380.063019 -3.297948) (xy 380.078775 -3.213658)
			(xy 380.102242 -3.131182) (xy 380.133218 -3.051223) (xy 380.17144 -2.974463) (xy 380.216581 -2.901557)
			(xy 380.268257 -2.833128) (xy 380.326026 -2.769758) (xy 380.389396 -2.711989) (xy 380.457825 -2.660313)
			(xy 380.530731 -2.615172) (xy 380.607491 -2.57695) (xy 380.68745 -2.545974) (xy 380.769926 -2.522507)
			(xy 380.854216 -2.506751) (xy 380.939599 -2.498839) (xy 381.025349 -2.498839) (xy 381.110732 -2.506751)
			(xy 381.195022 -2.522507) (xy 381.277498 -2.545974) (xy 381.357457 -2.57695) (xy 381.434217 -2.615172)
			(xy 381.507123 -2.660313) (xy 381.575552 -2.711989) (xy 381.638922 -2.769758) (xy 381.696691 -2.833128)
			(xy 381.748367 -2.901557) (xy 381.793508 -2.974463) (xy 381.83173 -3.051223) (xy 381.862706 -3.131182)
			(xy 381.886173 -3.213658) (xy 381.901929 -3.297948) (xy 381.909841 -3.383331) (xy 381.910336 -3.426206)
			(xy 381.909841 -3.469081) (xy 381.901929 -3.554464) (xy 381.886173 -3.638754) (xy 381.862706 -3.72123)
			(xy 381.83173 -3.801189) (xy 381.793508 -3.877949) (xy 381.748367 -3.950855) (xy 381.696691 -4.019284)
			(xy 381.638922 -4.082654) (xy 381.575552 -4.140423) (xy 381.507123 -4.192099) (xy 381.434217 -4.23724)
			(xy 381.357457 -4.275462) (xy 381.277498 -4.306438) (xy 381.195022 -4.329905) (xy 381.110732 -4.345661)
			(xy 381.025349 -4.353573) (xy 380.939599 -4.353573) (xy 380.854216 -4.345661) (xy 380.769926 -4.329905)
			(xy 380.68745 -4.306438) (xy 380.607491 -4.275462) (xy 380.530731 -4.23724) (xy 380.457825 -4.192099)
			(xy 380.389396 -4.140423) (xy 380.326026 -4.082654) (xy 380.268257 -4.019284) (xy 380.216581 -3.950855)
			(xy 380.17144 -3.877949) (xy 380.133218 -3.801189) (xy 380.102242 -3.72123) (xy 380.078775 -3.638754)
			(xy 380.063019 -3.554464) (xy 380.055107 -3.469081) (xy 375.559841 -3.469081) (xy 375.551929 -3.554464)
			(xy 375.536173 -3.638754) (xy 375.512706 -3.72123) (xy 375.48173 -3.801189) (xy 375.443508 -3.877949)
			(xy 375.398367 -3.950855) (xy 375.346691 -4.019284) (xy 375.288922 -4.082654) (xy 375.225552 -4.140423)
			(xy 375.157123 -4.192099) (xy 375.084217 -4.23724) (xy 375.007457 -4.275462) (xy 374.927498 -4.306438)
			(xy 374.845022 -4.329905) (xy 374.760732 -4.345661) (xy 374.675349 -4.353573) (xy 374.589599 -4.353573)
			(xy 374.504216 -4.345661) (xy 374.419926 -4.329905) (xy 374.33745 -4.306438) (xy 374.257491 -4.275462)
			(xy 374.180731 -4.23724) (xy 374.107825 -4.192099) (xy 374.039396 -4.140423) (xy 373.976026 -4.082654)
			(xy 373.918257 -4.019284) (xy 373.866581 -3.950855) (xy 373.82144 -3.877949) (xy 373.783218 -3.801189)
			(xy 373.752242 -3.72123) (xy 373.728775 -3.638754) (xy 373.713019 -3.554464) (xy 373.705107 -3.469081)
			(xy 343.693001 -3.469081) (xy 343.685089 -3.554464) (xy 343.669333 -3.638754) (xy 343.645866 -3.72123)
			(xy 343.61489 -3.801189) (xy 343.576668 -3.877949) (xy 343.531527 -3.950855) (xy 343.479851 -4.019284)
			(xy 343.422082 -4.082654) (xy 343.358712 -4.140423) (xy 343.290283 -4.192099) (xy 343.217377 -4.23724)
			(xy 343.140617 -4.275462) (xy 343.060658 -4.306438) (xy 342.978182 -4.329905) (xy 342.893892 -4.345661)
			(xy 342.808509 -4.353573) (xy 342.722759 -4.353573) (xy 342.637376 -4.345661) (xy 342.553086 -4.329905)
			(xy 342.47061 -4.306438) (xy 342.390651 -4.275462) (xy 342.313891 -4.23724) (xy 342.240985 -4.192099)
			(xy 342.172556 -4.140423) (xy 342.109186 -4.082654) (xy 342.051417 -4.019284) (xy 341.999741 -3.950855)
			(xy 341.9546 -3.877949) (xy 341.916378 -3.801189) (xy 341.885402 -3.72123) (xy 341.861935 -3.638754)
			(xy 341.846179 -3.554464) (xy 341.838267 -3.469081) (xy 337.343001 -3.469081) (xy 337.335089 -3.554464)
			(xy 337.319333 -3.638754) (xy 337.295866 -3.72123) (xy 337.26489 -3.801189) (xy 337.226668 -3.877949)
			(xy 337.181527 -3.950855) (xy 337.129851 -4.019284) (xy 337.072082 -4.082654) (xy 337.008712 -4.140423)
			(xy 336.940283 -4.192099) (xy 336.867377 -4.23724) (xy 336.790617 -4.275462) (xy 336.710658 -4.306438)
			(xy 336.628182 -4.329905) (xy 336.543892 -4.345661) (xy 336.458509 -4.353573) (xy 336.372759 -4.353573)
			(xy 336.287376 -4.345661) (xy 336.203086 -4.329905) (xy 336.12061 -4.306438) (xy 336.040651 -4.275462)
			(xy 335.963891 -4.23724) (xy 335.890985 -4.192099) (xy 335.822556 -4.140423) (xy 335.759186 -4.082654)
			(xy 335.701417 -4.019284) (xy 335.649741 -3.950855) (xy 335.6046 -3.877949) (xy 335.566378 -3.801189)
			(xy 335.535402 -3.72123) (xy 335.511935 -3.638754) (xy 335.496179 -3.554464) (xy 335.488267 -3.469081)
			(xy 333.050655 -3.469081) (xy 333.042743 -3.554464) (xy 333.026987 -3.638754) (xy 333.00352 -3.72123)
			(xy 332.972544 -3.801189) (xy 332.934322 -3.877949) (xy 332.889181 -3.950855) (xy 332.837505 -4.019284)
			(xy 332.779736 -4.082654) (xy 332.716366 -4.140423) (xy 332.647937 -4.192099) (xy 332.575031 -4.23724)
			(xy 332.498271 -4.275462) (xy 332.418312 -4.306438) (xy 332.335836 -4.329905) (xy 332.251546 -4.345661)
			(xy 332.166163 -4.353573) (xy 332.080413 -4.353573) (xy 331.99503 -4.345661) (xy 331.91074 -4.329905)
			(xy 331.828264 -4.306438) (xy 331.748305 -4.275462) (xy 331.671545 -4.23724) (xy 331.598639 -4.192099)
			(xy 331.53021 -4.140423) (xy 331.46684 -4.082654) (xy 331.409071 -4.019284) (xy 331.357395 -3.950855)
			(xy 331.312254 -3.877949) (xy 331.274032 -3.801189) (xy 331.243056 -3.72123) (xy 331.219589 -3.638754)
			(xy 331.203833 -3.554464) (xy 331.195921 -3.469081) (xy 326.700655 -3.469081) (xy 326.692743 -3.554464)
			(xy 326.676987 -3.638754) (xy 326.65352 -3.72123) (xy 326.622544 -3.801189) (xy 326.584322 -3.877949)
			(xy 326.539181 -3.950855) (xy 326.487505 -4.019284) (xy 326.429736 -4.082654) (xy 326.366366 -4.140423)
			(xy 326.297937 -4.192099) (xy 326.225031 -4.23724) (xy 326.148271 -4.275462) (xy 326.068312 -4.306438)
			(xy 325.985836 -4.329905) (xy 325.901546 -4.345661) (xy 325.816163 -4.353573) (xy 325.730413 -4.353573)
			(xy 325.64503 -4.345661) (xy 325.56074 -4.329905) (xy 325.478264 -4.306438) (xy 325.398305 -4.275462)
			(xy 325.321545 -4.23724) (xy 325.248639 -4.192099) (xy 325.18021 -4.140423) (xy 325.11684 -4.082654)
			(xy 325.059071 -4.019284) (xy 325.007395 -3.950855) (xy 324.962254 -3.877949) (xy 324.924032 -3.801189)
			(xy 324.893056 -3.72123) (xy 324.869589 -3.638754) (xy 324.853833 -3.554464) (xy 324.845921 -3.469081)
			(xy 265.125975 -3.469081) (xy 265.118063 -3.554464) (xy 265.102307 -3.638754) (xy 265.07884 -3.72123)
			(xy 265.047864 -3.801189) (xy 265.009642 -3.877949) (xy 264.964501 -3.950855) (xy 264.912825 -4.019284)
			(xy 264.855056 -4.082654) (xy 264.791686 -4.140423) (xy 264.723257 -4.192099) (xy 264.650351 -4.23724)
			(xy 264.573591 -4.275462) (xy 264.493632 -4.306438) (xy 264.411156 -4.329905) (xy 264.326866 -4.345661)
			(xy 264.241483 -4.353573) (xy 264.155733 -4.353573) (xy 264.07035 -4.345661) (xy 263.98606 -4.329905)
			(xy 263.903584 -4.306438) (xy 263.823625 -4.275462) (xy 263.746865 -4.23724) (xy 263.673959 -4.192099)
			(xy 263.60553 -4.140423) (xy 263.54216 -4.082654) (xy 263.484391 -4.019284) (xy 263.432715 -3.950855)
			(xy 263.387574 -3.877949) (xy 263.349352 -3.801189) (xy 263.318376 -3.72123) (xy 263.294909 -3.638754)
			(xy 263.279153 -3.554464) (xy 263.271241 -3.469081) (xy 258.775975 -3.469081) (xy 258.768063 -3.554464)
			(xy 258.752307 -3.638754) (xy 258.72884 -3.72123) (xy 258.697864 -3.801189) (xy 258.659642 -3.877949)
			(xy 258.614501 -3.950855) (xy 258.562825 -4.019284) (xy 258.505056 -4.082654) (xy 258.441686 -4.140423)
			(xy 258.373257 -4.192099) (xy 258.300351 -4.23724) (xy 258.223591 -4.275462) (xy 258.143632 -4.306438)
			(xy 258.061156 -4.329905) (xy 257.976866 -4.345661) (xy 257.891483 -4.353573) (xy 257.805733 -4.353573)
			(xy 257.72035 -4.345661) (xy 257.63606 -4.329905) (xy 257.553584 -4.306438) (xy 257.473625 -4.275462)
			(xy 257.396865 -4.23724) (xy 257.323959 -4.192099) (xy 257.25553 -4.140423) (xy 257.19216 -4.082654)
			(xy 257.134391 -4.019284) (xy 257.082715 -3.950855) (xy 257.037574 -3.877949) (xy 256.999352 -3.801189)
			(xy 256.968376 -3.72123) (xy 256.944909 -3.638754) (xy 256.929153 -3.554464) (xy 256.921241 -3.469081)
			(xy 254.465119 -3.469081) (xy 254.465087 -3.471875) (xy 254.457175 -3.557258) (xy 254.441419 -3.641548)
			(xy 254.417952 -3.724024) (xy 254.386976 -3.803983) (xy 254.348754 -3.880743) (xy 254.303613 -3.953649)
			(xy 254.251937 -4.022078) (xy 254.194168 -4.085448) (xy 254.130798 -4.143217) (xy 254.062369 -4.194893)
			(xy 253.989463 -4.240034) (xy 253.912703 -4.278256) (xy 253.832744 -4.309232) (xy 253.750268 -4.332699)
			(xy 253.665978 -4.348455) (xy 253.580595 -4.356367) (xy 253.494845 -4.356367) (xy 253.409462 -4.348455)
			(xy 253.325172 -4.332699) (xy 253.242696 -4.309232) (xy 253.162737 -4.278256) (xy 253.085977 -4.240034)
			(xy 253.013071 -4.194893) (xy 252.944642 -4.143217) (xy 252.881272 -4.085448) (xy 252.823503 -4.022078)
			(xy 252.771827 -3.953649) (xy 252.726686 -3.880743) (xy 252.688464 -3.803983) (xy 252.657488 -3.724024)
			(xy 252.634021 -3.641548) (xy 252.618265 -3.557258) (xy 252.610353 -3.471875) (xy 248.115087 -3.471875)
			(xy 248.107175 -3.557258) (xy 248.091419 -3.641548) (xy 248.067952 -3.724024) (xy 248.036976 -3.803983)
			(xy 247.998754 -3.880743) (xy 247.953613 -3.953649) (xy 247.901937 -4.022078) (xy 247.844168 -4.085448)
			(xy 247.780798 -4.143217) (xy 247.712369 -4.194893) (xy 247.639463 -4.240034) (xy 247.562703 -4.278256)
			(xy 247.482744 -4.309232) (xy 247.400268 -4.332699) (xy 247.315978 -4.348455) (xy 247.230595 -4.356367)
			(xy 247.144845 -4.356367) (xy 247.059462 -4.348455) (xy 246.975172 -4.332699) (xy 246.892696 -4.309232)
			(xy 246.812737 -4.278256) (xy 246.735977 -4.240034) (xy 246.663071 -4.194893) (xy 246.594642 -4.143217)
			(xy 246.531272 -4.085448) (xy 246.473503 -4.022078) (xy 246.421827 -3.953649) (xy 246.376686 -3.880743)
			(xy 246.338464 -3.803983) (xy 246.307488 -3.724024) (xy 246.284021 -3.641548) (xy 246.268265 -3.557258)
			(xy 246.260353 -3.471875) (xy 216.248247 -3.471875) (xy 216.240335 -3.557258) (xy 216.224579 -3.641548)
			(xy 216.201112 -3.724024) (xy 216.170136 -3.803983) (xy 216.131914 -3.880743) (xy 216.086773 -3.953649)
			(xy 216.035097 -4.022078) (xy 215.977328 -4.085448) (xy 215.913958 -4.143217) (xy 215.845529 -4.194893)
			(xy 215.772623 -4.240034) (xy 215.695863 -4.278256) (xy 215.615904 -4.309232) (xy 215.533428 -4.332699)
			(xy 215.449138 -4.348455) (xy 215.363755 -4.356367) (xy 215.278005 -4.356367) (xy 215.192622 -4.348455)
			(xy 215.108332 -4.332699) (xy 215.025856 -4.309232) (xy 214.945897 -4.278256) (xy 214.869137 -4.240034)
			(xy 214.796231 -4.194893) (xy 214.727802 -4.143217) (xy 214.664432 -4.085448) (xy 214.606663 -4.022078)
			(xy 214.554987 -3.953649) (xy 214.509846 -3.880743) (xy 214.471624 -3.803983) (xy 214.440648 -3.724024)
			(xy 214.417181 -3.641548) (xy 214.401425 -3.557258) (xy 214.393513 -3.471875) (xy 209.898247 -3.471875)
			(xy 209.890335 -3.557258) (xy 209.874579 -3.641548) (xy 209.851112 -3.724024) (xy 209.820136 -3.803983)
			(xy 209.781914 -3.880743) (xy 209.736773 -3.953649) (xy 209.685097 -4.022078) (xy 209.627328 -4.085448)
			(xy 209.563958 -4.143217) (xy 209.495529 -4.194893) (xy 209.422623 -4.240034) (xy 209.345863 -4.278256)
			(xy 209.265904 -4.309232) (xy 209.183428 -4.332699) (xy 209.099138 -4.348455) (xy 209.013755 -4.356367)
			(xy 208.928005 -4.356367) (xy 208.842622 -4.348455) (xy 208.758332 -4.332699) (xy 208.675856 -4.309232)
			(xy 208.595897 -4.278256) (xy 208.519137 -4.240034) (xy 208.446231 -4.194893) (xy 208.377802 -4.143217)
			(xy 208.314432 -4.085448) (xy 208.256663 -4.022078) (xy 208.204987 -3.953649) (xy 208.159846 -3.880743)
			(xy 208.121624 -3.803983) (xy 208.090648 -3.724024) (xy 208.067181 -3.641548) (xy 208.051425 -3.557258)
			(xy 208.043513 -3.471875) (xy 197.075741 -3.471875) (xy 197.091928 -3.518134) (xy 197.13088 -3.653342)
			(xy 197.16219 -3.790521) (xy 197.185759 -3.929239) (xy 197.201513 -4.069061) (xy 197.209403 -4.209547)
			(xy 197.209918 -4.2799) (xy 197.209918 -6.011875) (xy 208.043513 -6.011875) (xy 208.043513 -5.926125)
			(xy 208.051425 -5.840742) (xy 208.067181 -5.756452) (xy 208.090648 -5.673976) (xy 208.121624 -5.594017)
			(xy 208.159846 -5.517257) (xy 208.204987 -5.444351) (xy 208.256663 -5.375922) (xy 208.314432 -5.312552)
			(xy 208.377802 -5.254783) (xy 208.446231 -5.203107) (xy 208.519137 -5.157966) (xy 208.595897 -5.119744)
			(xy 208.675856 -5.088768) (xy 208.758332 -5.065301) (xy 208.842622 -5.049545) (xy 208.928005 -5.041633)
			(xy 209.013755 -5.041633) (xy 209.099138 -5.049545) (xy 209.183428 -5.065301) (xy 209.265904 -5.088768)
			(xy 209.345863 -5.119744) (xy 209.368066 -5.1308) (xy 212.978492 -5.1308) (xy 212.978492 -4.2672)
			(xy 212.978978 -4.239931) (xy 212.98674 -4.185947) (xy 213.002105 -4.133617) (xy 213.024762 -4.084007)
			(xy 213.054248 -4.038126) (xy 213.089963 -3.996909) (xy 213.13118 -3.961194) (xy 213.177061 -3.931708)
			(xy 213.226671 -3.909051) (xy 213.279001 -3.893686) (xy 213.332985 -3.885924) (xy 213.387523 -3.885924)
			(xy 213.441507 -3.893686) (xy 213.493837 -3.909051) (xy 213.543447 -3.931708) (xy 213.589328 -3.961194)
			(xy 213.630545 -3.996909) (xy 213.66626 -4.038126) (xy 213.695746 -4.084007) (xy 213.718403 -4.133617)
			(xy 213.733768 -4.185947) (xy 213.74153 -4.239931) (xy 213.742016 -4.2672) (xy 213.742016 -5.1308)
			(xy 213.74153 -5.158069) (xy 213.733768 -5.212053) (xy 213.718403 -5.264383) (xy 213.695746 -5.313993)
			(xy 213.66626 -5.359874) (xy 213.630545 -5.401091) (xy 213.589328 -5.436806) (xy 213.543447 -5.466292)
			(xy 213.493837 -5.488949) (xy 213.441507 -5.504314) (xy 213.387523 -5.512076) (xy 213.332985 -5.512076)
			(xy 213.279001 -5.504314) (xy 213.226671 -5.488949) (xy 213.177061 -5.466292) (xy 213.13118 -5.436806)
			(xy 213.089963 -5.401091) (xy 213.054248 -5.359874) (xy 213.024762 -5.313993) (xy 213.002105 -5.264383)
			(xy 212.98674 -5.212053) (xy 212.978978 -5.158069) (xy 212.978492 -5.1308) (xy 209.368066 -5.1308)
			(xy 209.422623 -5.157966) (xy 209.495529 -5.203107) (xy 209.563958 -5.254783) (xy 209.627328 -5.312552)
			(xy 209.685097 -5.375922) (xy 209.736773 -5.444351) (xy 209.781914 -5.517257) (xy 209.820136 -5.594017)
			(xy 209.851112 -5.673976) (xy 209.874579 -5.756452) (xy 209.890335 -5.840742) (xy 209.898247 -5.926125)
			(xy 209.898742 -5.969) (xy 209.898247 -6.011875) (xy 214.393513 -6.011875) (xy 214.393513 -5.926125)
			(xy 214.401425 -5.840742) (xy 214.417181 -5.756452) (xy 214.440648 -5.673976) (xy 214.471624 -5.594017)
			(xy 214.509846 -5.517257) (xy 214.554987 -5.444351) (xy 214.606663 -5.375922) (xy 214.664432 -5.312552)
			(xy 214.727802 -5.254783) (xy 214.796231 -5.203107) (xy 214.869137 -5.157966) (xy 214.945897 -5.119744)
			(xy 215.025856 -5.088768) (xy 215.108332 -5.065301) (xy 215.192622 -5.049545) (xy 215.278005 -5.041633)
			(xy 215.363755 -5.041633) (xy 215.449138 -5.049545) (xy 215.533428 -5.065301) (xy 215.615904 -5.088768)
			(xy 215.695863 -5.119744) (xy 215.772623 -5.157966) (xy 215.845529 -5.203107) (xy 215.913958 -5.254783)
			(xy 215.977328 -5.312552) (xy 216.035097 -5.375922) (xy 216.086773 -5.444351) (xy 216.131914 -5.517257)
			(xy 216.170136 -5.594017) (xy 216.201112 -5.673976) (xy 216.224579 -5.756452) (xy 216.240335 -5.840742)
			(xy 216.248247 -5.926125) (xy 216.248742 -5.969) (xy 216.248247 -6.011875) (xy 246.260353 -6.011875)
			(xy 246.260353 -5.926125) (xy 246.268265 -5.840742) (xy 246.284021 -5.756452) (xy 246.307488 -5.673976)
			(xy 246.338464 -5.594017) (xy 246.376686 -5.517257) (xy 246.421827 -5.444351) (xy 246.473503 -5.375922)
			(xy 246.531272 -5.312552) (xy 246.594642 -5.254783) (xy 246.663071 -5.203107) (xy 246.735977 -5.157966)
			(xy 246.812737 -5.119744) (xy 246.892696 -5.088768) (xy 246.975172 -5.065301) (xy 247.059462 -5.049545)
			(xy 247.144845 -5.041633) (xy 247.230595 -5.041633) (xy 247.315978 -5.049545) (xy 247.400268 -5.065301)
			(xy 247.482744 -5.088768) (xy 247.562703 -5.119744) (xy 247.584906 -5.1308) (xy 248.766584 -5.1308)
			(xy 248.766584 -4.2672) (xy 248.76707 -4.239931) (xy 248.774832 -4.185947) (xy 248.790197 -4.133617)
			(xy 248.812854 -4.084007) (xy 248.84234 -4.038126) (xy 248.878055 -3.996909) (xy 248.919272 -3.961194)
			(xy 248.965153 -3.931708) (xy 249.014763 -3.909051) (xy 249.067093 -3.893686) (xy 249.121077 -3.885924)
			(xy 249.175615 -3.885924) (xy 249.229599 -3.893686) (xy 249.281929 -3.909051) (xy 249.331539 -3.931708)
			(xy 249.37742 -3.961194) (xy 249.418637 -3.996909) (xy 249.454352 -4.038126) (xy 249.483838 -4.084007)
			(xy 249.506495 -4.133617) (xy 249.52186 -4.185947) (xy 249.529622 -4.239931) (xy 249.530108 -4.2672)
			(xy 249.530108 -5.1308) (xy 249.529622 -5.158069) (xy 249.52186 -5.212053) (xy 249.506495 -5.264383)
			(xy 249.483838 -5.313993) (xy 249.454352 -5.359874) (xy 249.418637 -5.401091) (xy 249.37742 -5.436806)
			(xy 249.331539 -5.466292) (xy 249.281929 -5.488949) (xy 249.229599 -5.504314) (xy 249.175615 -5.512076)
			(xy 249.121077 -5.512076) (xy 249.067093 -5.504314) (xy 249.014763 -5.488949) (xy 248.965153 -5.466292)
			(xy 248.919272 -5.436806) (xy 248.878055 -5.401091) (xy 248.84234 -5.359874) (xy 248.812854 -5.313993)
			(xy 248.790197 -5.264383) (xy 248.774832 -5.212053) (xy 248.76707 -5.158069) (xy 248.766584 -5.1308)
			(xy 247.584906 -5.1308) (xy 247.639463 -5.157966) (xy 247.712369 -5.203107) (xy 247.780798 -5.254783)
			(xy 247.844168 -5.312552) (xy 247.901937 -5.375922) (xy 247.953613 -5.444351) (xy 247.998754 -5.517257)
			(xy 248.036976 -5.594017) (xy 248.067952 -5.673976) (xy 248.091419 -5.756452) (xy 248.107175 -5.840742)
			(xy 248.115087 -5.926125) (xy 248.115582 -5.969) (xy 248.115087 -6.011875) (xy 252.610353 -6.011875)
			(xy 252.610353 -5.926125) (xy 252.618265 -5.840742) (xy 252.634021 -5.756452) (xy 252.657488 -5.673976)
			(xy 252.688464 -5.594017) (xy 252.726686 -5.517257) (xy 252.771827 -5.444351) (xy 252.823503 -5.375922)
			(xy 252.881272 -5.312552) (xy 252.944642 -5.254783) (xy 253.013071 -5.203107) (xy 253.085977 -5.157966)
			(xy 253.162737 -5.119744) (xy 253.242696 -5.088768) (xy 253.325172 -5.065301) (xy 253.409462 -5.049545)
			(xy 253.494845 -5.041633) (xy 253.580595 -5.041633) (xy 253.665978 -5.049545) (xy 253.750268 -5.065301)
			(xy 253.832744 -5.088768) (xy 253.912703 -5.119744) (xy 253.989463 -5.157966) (xy 254.062369 -5.203107)
			(xy 254.130798 -5.254783) (xy 254.194168 -5.312552) (xy 254.251937 -5.375922) (xy 254.303613 -5.444351)
			(xy 254.348754 -5.517257) (xy 254.386976 -5.594017) (xy 254.417952 -5.673976) (xy 254.441419 -5.756452)
			(xy 254.457175 -5.840742) (xy 254.465087 -5.926125) (xy 254.465582 -5.969) (xy 254.465119 -6.009081)
			(xy 256.921241 -6.009081) (xy 256.921241 -5.923331) (xy 256.929153 -5.837948) (xy 256.944909 -5.753658)
			(xy 256.968376 -5.671182) (xy 256.999352 -5.591223) (xy 257.037574 -5.514463) (xy 257.082715 -5.441557)
			(xy 257.134391 -5.373128) (xy 257.19216 -5.309758) (xy 257.25553 -5.251989) (xy 257.323959 -5.200313)
			(xy 257.396865 -5.155172) (xy 257.473625 -5.11695) (xy 257.553584 -5.085974) (xy 257.63606 -5.062507)
			(xy 257.72035 -5.046751) (xy 257.805733 -5.038839) (xy 257.891483 -5.038839) (xy 257.976866 -5.046751)
			(xy 258.061156 -5.062507) (xy 258.143632 -5.085974) (xy 258.223591 -5.11695) (xy 258.300351 -5.155172)
			(xy 258.373257 -5.200313) (xy 258.441686 -5.251989) (xy 258.505056 -5.309758) (xy 258.562825 -5.373128)
			(xy 258.614501 -5.441557) (xy 258.659642 -5.514463) (xy 258.697864 -5.591223) (xy 258.72884 -5.671182)
			(xy 258.752307 -5.753658) (xy 258.768063 -5.837948) (xy 258.775975 -5.923331) (xy 258.77647 -5.966206)
			(xy 258.775975 -6.009081) (xy 263.271241 -6.009081) (xy 263.271241 -5.923331) (xy 263.279153 -5.837948)
			(xy 263.294909 -5.753658) (xy 263.318376 -5.671182) (xy 263.349352 -5.591223) (xy 263.387574 -5.514463)
			(xy 263.432715 -5.441557) (xy 263.484391 -5.373128) (xy 263.54216 -5.309758) (xy 263.60553 -5.251989)
			(xy 263.673959 -5.200313) (xy 263.746865 -5.155172) (xy 263.823625 -5.11695) (xy 263.903584 -5.085974)
			(xy 263.98606 -5.062507) (xy 264.07035 -5.046751) (xy 264.155733 -5.038839) (xy 264.241483 -5.038839)
			(xy 264.326866 -5.046751) (xy 264.411156 -5.062507) (xy 264.493632 -5.085974) (xy 264.573591 -5.11695)
			(xy 264.650351 -5.155172) (xy 264.723257 -5.200313) (xy 264.791686 -5.251989) (xy 264.855056 -5.309758)
			(xy 264.912825 -5.373128) (xy 264.964501 -5.441557) (xy 265.009642 -5.514463) (xy 265.047864 -5.591223)
			(xy 265.07884 -5.671182) (xy 265.102307 -5.753658) (xy 265.118063 -5.837948) (xy 265.125975 -5.923331)
			(xy 265.12647 -5.966206) (xy 265.125975 -6.009081) (xy 324.845921 -6.009081) (xy 324.845921 -5.923331)
			(xy 324.853833 -5.837948) (xy 324.869589 -5.753658) (xy 324.893056 -5.671182) (xy 324.924032 -5.591223)
			(xy 324.962254 -5.514463) (xy 325.007395 -5.441557) (xy 325.059071 -5.373128) (xy 325.11684 -5.309758)
			(xy 325.18021 -5.251989) (xy 325.248639 -5.200313) (xy 325.321545 -5.155172) (xy 325.398305 -5.11695)
			(xy 325.478264 -5.085974) (xy 325.56074 -5.062507) (xy 325.64503 -5.046751) (xy 325.730413 -5.038839)
			(xy 325.816163 -5.038839) (xy 325.901546 -5.046751) (xy 325.985836 -5.062507) (xy 326.068312 -5.085974)
			(xy 326.148271 -5.11695) (xy 326.225031 -5.155172) (xy 326.297937 -5.200313) (xy 326.366366 -5.251989)
			(xy 326.429736 -5.309758) (xy 326.487505 -5.373128) (xy 326.539181 -5.441557) (xy 326.584322 -5.514463)
			(xy 326.622544 -5.591223) (xy 326.65352 -5.671182) (xy 326.676987 -5.753658) (xy 326.692743 -5.837948)
			(xy 326.700655 -5.923331) (xy 326.70115 -5.966206) (xy 326.700655 -6.009081) (xy 331.195921 -6.009081)
			(xy 331.195921 -5.923331) (xy 331.203833 -5.837948) (xy 331.219589 -5.753658) (xy 331.243056 -5.671182)
			(xy 331.274032 -5.591223) (xy 331.312254 -5.514463) (xy 331.357395 -5.441557) (xy 331.409071 -5.373128)
			(xy 331.46684 -5.309758) (xy 331.53021 -5.251989) (xy 331.598639 -5.200313) (xy 331.671545 -5.155172)
			(xy 331.748305 -5.11695) (xy 331.828264 -5.085974) (xy 331.91074 -5.062507) (xy 331.99503 -5.046751)
			(xy 332.080413 -5.038839) (xy 332.166163 -5.038839) (xy 332.251546 -5.046751) (xy 332.335836 -5.062507)
			(xy 332.418312 -5.085974) (xy 332.498271 -5.11695) (xy 332.575031 -5.155172) (xy 332.647937 -5.200313)
			(xy 332.716366 -5.251989) (xy 332.779736 -5.309758) (xy 332.837505 -5.373128) (xy 332.889181 -5.441557)
			(xy 332.934322 -5.514463) (xy 332.972544 -5.591223) (xy 333.00352 -5.671182) (xy 333.026987 -5.753658)
			(xy 333.042743 -5.837948) (xy 333.050655 -5.923331) (xy 333.05115 -5.966206) (xy 333.050655 -6.009081)
			(xy 335.488267 -6.009081) (xy 335.488267 -5.923331) (xy 335.496179 -5.837948) (xy 335.511935 -5.753658)
			(xy 335.535402 -5.671182) (xy 335.566378 -5.591223) (xy 335.6046 -5.514463) (xy 335.649741 -5.441557)
			(xy 335.701417 -5.373128) (xy 335.759186 -5.309758) (xy 335.822556 -5.251989) (xy 335.890985 -5.200313)
			(xy 335.963891 -5.155172) (xy 336.040651 -5.11695) (xy 336.12061 -5.085974) (xy 336.203086 -5.062507)
			(xy 336.287376 -5.046751) (xy 336.372759 -5.038839) (xy 336.458509 -5.038839) (xy 336.543892 -5.046751)
			(xy 336.628182 -5.062507) (xy 336.710658 -5.085974) (xy 336.790617 -5.11695) (xy 336.867377 -5.155172)
			(xy 336.940283 -5.200313) (xy 337.008712 -5.251989) (xy 337.072082 -5.309758) (xy 337.129851 -5.373128)
			(xy 337.181527 -5.441557) (xy 337.226668 -5.514463) (xy 337.26489 -5.591223) (xy 337.295866 -5.671182)
			(xy 337.319333 -5.753658) (xy 337.335089 -5.837948) (xy 337.343001 -5.923331) (xy 337.343496 -5.966206)
			(xy 337.343001 -6.009081) (xy 341.838267 -6.009081) (xy 341.838267 -5.923331) (xy 341.846179 -5.837948)
			(xy 341.861935 -5.753658) (xy 341.885402 -5.671182) (xy 341.916378 -5.591223) (xy 341.9546 -5.514463)
			(xy 341.999741 -5.441557) (xy 342.051417 -5.373128) (xy 342.109186 -5.309758) (xy 342.172556 -5.251989)
			(xy 342.240985 -5.200313) (xy 342.313891 -5.155172) (xy 342.390651 -5.11695) (xy 342.47061 -5.085974)
			(xy 342.553086 -5.062507) (xy 342.637376 -5.046751) (xy 342.722759 -5.038839) (xy 342.808509 -5.038839)
			(xy 342.893892 -5.046751) (xy 342.978182 -5.062507) (xy 343.060658 -5.085974) (xy 343.140617 -5.11695)
			(xy 343.217377 -5.155172) (xy 343.290283 -5.200313) (xy 343.358712 -5.251989) (xy 343.422082 -5.309758)
			(xy 343.479851 -5.373128) (xy 343.531527 -5.441557) (xy 343.576668 -5.514463) (xy 343.61489 -5.591223)
			(xy 343.645866 -5.671182) (xy 343.669333 -5.753658) (xy 343.685089 -5.837948) (xy 343.693001 -5.923331)
			(xy 343.693496 -5.966206) (xy 343.693001 -6.009081) (xy 373.705107 -6.009081) (xy 373.705107 -5.923331)
			(xy 373.713019 -5.837948) (xy 373.728775 -5.753658) (xy 373.752242 -5.671182) (xy 373.783218 -5.591223)
			(xy 373.82144 -5.514463) (xy 373.866581 -5.441557) (xy 373.918257 -5.373128) (xy 373.976026 -5.309758)
			(xy 374.039396 -5.251989) (xy 374.107825 -5.200313) (xy 374.180731 -5.155172) (xy 374.257491 -5.11695)
			(xy 374.33745 -5.085974) (xy 374.419926 -5.062507) (xy 374.504216 -5.046751) (xy 374.589599 -5.038839)
			(xy 374.675349 -5.038839) (xy 374.760732 -5.046751) (xy 374.845022 -5.062507) (xy 374.927498 -5.085974)
			(xy 375.007457 -5.11695) (xy 375.084217 -5.155172) (xy 375.157123 -5.200313) (xy 375.225552 -5.251989)
			(xy 375.288922 -5.309758) (xy 375.346691 -5.373128) (xy 375.398367 -5.441557) (xy 375.443508 -5.514463)
			(xy 375.48173 -5.591223) (xy 375.512706 -5.671182) (xy 375.536173 -5.753658) (xy 375.551929 -5.837948)
			(xy 375.559841 -5.923331) (xy 375.560336 -5.966206) (xy 375.559841 -6.009081) (xy 380.055107 -6.009081)
			(xy 380.055107 -5.923331) (xy 380.063019 -5.837948) (xy 380.078775 -5.753658) (xy 380.102242 -5.671182)
			(xy 380.133218 -5.591223) (xy 380.17144 -5.514463) (xy 380.216581 -5.441557) (xy 380.268257 -5.373128)
			(xy 380.326026 -5.309758) (xy 380.389396 -5.251989) (xy 380.457825 -5.200313) (xy 380.530731 -5.155172)
			(xy 380.607491 -5.11695) (xy 380.68745 -5.085974) (xy 380.769926 -5.062507) (xy 380.854216 -5.046751)
			(xy 380.939599 -5.038839) (xy 381.025349 -5.038839) (xy 381.110732 -5.046751) (xy 381.195022 -5.062507)
			(xy 381.277498 -5.085974) (xy 381.357457 -5.11695) (xy 381.434217 -5.155172) (xy 381.507123 -5.200313)
			(xy 381.575552 -5.251989) (xy 381.638922 -5.309758) (xy 381.696691 -5.373128) (xy 381.748367 -5.441557)
			(xy 381.793508 -5.514463) (xy 381.83173 -5.591223) (xy 381.862706 -5.671182) (xy 381.886173 -5.753658)
			(xy 381.901929 -5.837948) (xy 381.909841 -5.923331) (xy 381.910336 -5.966206) (xy 381.909841 -6.009081)
			(xy 381.901929 -6.094464) (xy 381.886173 -6.178754) (xy 381.862706 -6.26123) (xy 381.83173 -6.341189)
			(xy 381.793508 -6.417949) (xy 381.748367 -6.490855) (xy 381.696691 -6.559284) (xy 381.638922 -6.622654)
			(xy 381.575552 -6.680423) (xy 381.507123 -6.732099) (xy 381.434217 -6.77724) (xy 381.357457 -6.815462)
			(xy 381.277498 -6.846438) (xy 381.195022 -6.869905) (xy 381.110732 -6.885661) (xy 381.025349 -6.893573)
			(xy 380.939599 -6.893573) (xy 380.854216 -6.885661) (xy 380.769926 -6.869905) (xy 380.68745 -6.846438)
			(xy 380.607491 -6.815462) (xy 380.530731 -6.77724) (xy 380.457825 -6.732099) (xy 380.389396 -6.680423)
			(xy 380.326026 -6.622654) (xy 380.268257 -6.559284) (xy 380.216581 -6.490855) (xy 380.17144 -6.417949)
			(xy 380.133218 -6.341189) (xy 380.102242 -6.26123) (xy 380.078775 -6.178754) (xy 380.063019 -6.094464)
			(xy 380.055107 -6.009081) (xy 375.559841 -6.009081) (xy 375.551929 -6.094464) (xy 375.536173 -6.178754)
			(xy 375.512706 -6.26123) (xy 375.48173 -6.341189) (xy 375.443508 -6.417949) (xy 375.398367 -6.490855)
			(xy 375.346691 -6.559284) (xy 375.288922 -6.622654) (xy 375.225552 -6.680423) (xy 375.157123 -6.732099)
			(xy 375.084217 -6.77724) (xy 375.007457 -6.815462) (xy 374.927498 -6.846438) (xy 374.845022 -6.869905)
			(xy 374.760732 -6.885661) (xy 374.675349 -6.893573) (xy 374.589599 -6.893573) (xy 374.504216 -6.885661)
			(xy 374.419926 -6.869905) (xy 374.33745 -6.846438) (xy 374.257491 -6.815462) (xy 374.180731 -6.77724)
			(xy 374.107825 -6.732099) (xy 374.039396 -6.680423) (xy 373.976026 -6.622654) (xy 373.918257 -6.559284)
			(xy 373.866581 -6.490855) (xy 373.82144 -6.417949) (xy 373.783218 -6.341189) (xy 373.752242 -6.26123)
			(xy 373.728775 -6.178754) (xy 373.713019 -6.094464) (xy 373.705107 -6.009081) (xy 343.693001 -6.009081)
			(xy 343.685089 -6.094464) (xy 343.669333 -6.178754) (xy 343.645866 -6.26123) (xy 343.61489 -6.341189)
			(xy 343.576668 -6.417949) (xy 343.531527 -6.490855) (xy 343.479851 -6.559284) (xy 343.422082 -6.622654)
			(xy 343.358712 -6.680423) (xy 343.290283 -6.732099) (xy 343.217377 -6.77724) (xy 343.140617 -6.815462)
			(xy 343.060658 -6.846438) (xy 342.978182 -6.869905) (xy 342.893892 -6.885661) (xy 342.808509 -6.893573)
			(xy 342.722759 -6.893573) (xy 342.637376 -6.885661) (xy 342.553086 -6.869905) (xy 342.47061 -6.846438)
			(xy 342.390651 -6.815462) (xy 342.313891 -6.77724) (xy 342.240985 -6.732099) (xy 342.172556 -6.680423)
			(xy 342.109186 -6.622654) (xy 342.051417 -6.559284) (xy 341.999741 -6.490855) (xy 341.9546 -6.417949)
			(xy 341.916378 -6.341189) (xy 341.885402 -6.26123) (xy 341.861935 -6.178754) (xy 341.846179 -6.094464)
			(xy 341.838267 -6.009081) (xy 337.343001 -6.009081) (xy 337.335089 -6.094464) (xy 337.319333 -6.178754)
			(xy 337.295866 -6.26123) (xy 337.26489 -6.341189) (xy 337.226668 -6.417949) (xy 337.181527 -6.490855)
			(xy 337.129851 -6.559284) (xy 337.072082 -6.622654) (xy 337.008712 -6.680423) (xy 336.940283 -6.732099)
			(xy 336.867377 -6.77724) (xy 336.790617 -6.815462) (xy 336.710658 -6.846438) (xy 336.628182 -6.869905)
			(xy 336.543892 -6.885661) (xy 336.458509 -6.893573) (xy 336.372759 -6.893573) (xy 336.287376 -6.885661)
			(xy 336.203086 -6.869905) (xy 336.12061 -6.846438) (xy 336.040651 -6.815462) (xy 335.963891 -6.77724)
			(xy 335.890985 -6.732099) (xy 335.822556 -6.680423) (xy 335.759186 -6.622654) (xy 335.701417 -6.559284)
			(xy 335.649741 -6.490855) (xy 335.6046 -6.417949) (xy 335.566378 -6.341189) (xy 335.535402 -6.26123)
			(xy 335.511935 -6.178754) (xy 335.496179 -6.094464) (xy 335.488267 -6.009081) (xy 333.050655 -6.009081)
			(xy 333.042743 -6.094464) (xy 333.026987 -6.178754) (xy 333.00352 -6.26123) (xy 332.972544 -6.341189)
			(xy 332.934322 -6.417949) (xy 332.889181 -6.490855) (xy 332.837505 -6.559284) (xy 332.779736 -6.622654)
			(xy 332.716366 -6.680423) (xy 332.647937 -6.732099) (xy 332.575031 -6.77724) (xy 332.498271 -6.815462)
			(xy 332.418312 -6.846438) (xy 332.335836 -6.869905) (xy 332.251546 -6.885661) (xy 332.166163 -6.893573)
			(xy 332.080413 -6.893573) (xy 331.99503 -6.885661) (xy 331.91074 -6.869905) (xy 331.828264 -6.846438)
			(xy 331.748305 -6.815462) (xy 331.671545 -6.77724) (xy 331.598639 -6.732099) (xy 331.53021 -6.680423)
			(xy 331.46684 -6.622654) (xy 331.409071 -6.559284) (xy 331.357395 -6.490855) (xy 331.312254 -6.417949)
			(xy 331.274032 -6.341189) (xy 331.243056 -6.26123) (xy 331.219589 -6.178754) (xy 331.203833 -6.094464)
			(xy 331.195921 -6.009081) (xy 326.700655 -6.009081) (xy 326.692743 -6.094464) (xy 326.676987 -6.178754)
			(xy 326.65352 -6.26123) (xy 326.622544 -6.341189) (xy 326.584322 -6.417949) (xy 326.539181 -6.490855)
			(xy 326.487505 -6.559284) (xy 326.429736 -6.622654) (xy 326.366366 -6.680423) (xy 326.297937 -6.732099)
			(xy 326.225031 -6.77724) (xy 326.148271 -6.815462) (xy 326.068312 -6.846438) (xy 325.985836 -6.869905)
			(xy 325.901546 -6.885661) (xy 325.816163 -6.893573) (xy 325.730413 -6.893573) (xy 325.64503 -6.885661)
			(xy 325.56074 -6.869905) (xy 325.478264 -6.846438) (xy 325.398305 -6.815462) (xy 325.321545 -6.77724)
			(xy 325.248639 -6.732099) (xy 325.18021 -6.680423) (xy 325.11684 -6.622654) (xy 325.059071 -6.559284)
			(xy 325.007395 -6.490855) (xy 324.962254 -6.417949) (xy 324.924032 -6.341189) (xy 324.893056 -6.26123)
			(xy 324.869589 -6.178754) (xy 324.853833 -6.094464) (xy 324.845921 -6.009081) (xy 265.125975 -6.009081)
			(xy 265.118063 -6.094464) (xy 265.102307 -6.178754) (xy 265.07884 -6.26123) (xy 265.047864 -6.341189)
			(xy 265.009642 -6.417949) (xy 264.964501 -6.490855) (xy 264.912825 -6.559284) (xy 264.855056 -6.622654)
			(xy 264.791686 -6.680423) (xy 264.723257 -6.732099) (xy 264.650351 -6.77724) (xy 264.573591 -6.815462)
			(xy 264.493632 -6.846438) (xy 264.411156 -6.869905) (xy 264.326866 -6.885661) (xy 264.241483 -6.893573)
			(xy 264.155733 -6.893573) (xy 264.07035 -6.885661) (xy 263.98606 -6.869905) (xy 263.903584 -6.846438)
			(xy 263.823625 -6.815462) (xy 263.746865 -6.77724) (xy 263.673959 -6.732099) (xy 263.60553 -6.680423)
			(xy 263.54216 -6.622654) (xy 263.484391 -6.559284) (xy 263.432715 -6.490855) (xy 263.387574 -6.417949)
			(xy 263.349352 -6.341189) (xy 263.318376 -6.26123) (xy 263.294909 -6.178754) (xy 263.279153 -6.094464)
			(xy 263.271241 -6.009081) (xy 258.775975 -6.009081) (xy 258.768063 -6.094464) (xy 258.752307 -6.178754)
			(xy 258.72884 -6.26123) (xy 258.697864 -6.341189) (xy 258.659642 -6.417949) (xy 258.614501 -6.490855)
			(xy 258.562825 -6.559284) (xy 258.505056 -6.622654) (xy 258.441686 -6.680423) (xy 258.373257 -6.732099)
			(xy 258.300351 -6.77724) (xy 258.223591 -6.815462) (xy 258.143632 -6.846438) (xy 258.061156 -6.869905)
			(xy 257.976866 -6.885661) (xy 257.891483 -6.893573) (xy 257.805733 -6.893573) (xy 257.72035 -6.885661)
			(xy 257.63606 -6.869905) (xy 257.553584 -6.846438) (xy 257.473625 -6.815462) (xy 257.396865 -6.77724)
			(xy 257.323959 -6.732099) (xy 257.25553 -6.680423) (xy 257.19216 -6.622654) (xy 257.134391 -6.559284)
			(xy 257.082715 -6.490855) (xy 257.037574 -6.417949) (xy 256.999352 -6.341189) (xy 256.968376 -6.26123)
			(xy 256.944909 -6.178754) (xy 256.929153 -6.094464) (xy 256.921241 -6.009081) (xy 254.465119 -6.009081)
			(xy 254.465087 -6.011875) (xy 254.457175 -6.097258) (xy 254.441419 -6.181548) (xy 254.417952 -6.264024)
			(xy 254.386976 -6.343983) (xy 254.348754 -6.420743) (xy 254.303613 -6.493649) (xy 254.251937 -6.562078)
			(xy 254.194168 -6.625448) (xy 254.130798 -6.683217) (xy 254.062369 -6.734893) (xy 253.989463 -6.780034)
			(xy 253.912703 -6.818256) (xy 253.832744 -6.849232) (xy 253.750268 -6.872699) (xy 253.665978 -6.888455)
			(xy 253.580595 -6.896367) (xy 253.494845 -6.896367) (xy 253.409462 -6.888455) (xy 253.325172 -6.872699)
			(xy 253.242696 -6.849232) (xy 253.162737 -6.818256) (xy 253.085977 -6.780034) (xy 253.013071 -6.734893)
			(xy 252.944642 -6.683217) (xy 252.881272 -6.625448) (xy 252.823503 -6.562078) (xy 252.771827 -6.493649)
			(xy 252.726686 -6.420743) (xy 252.688464 -6.343983) (xy 252.657488 -6.264024) (xy 252.634021 -6.181548)
			(xy 252.618265 -6.097258) (xy 252.610353 -6.011875) (xy 248.115087 -6.011875) (xy 248.107175 -6.097258)
			(xy 248.091419 -6.181548) (xy 248.067952 -6.264024) (xy 248.036976 -6.343983) (xy 247.998754 -6.420743)
			(xy 247.953613 -6.493649) (xy 247.901937 -6.562078) (xy 247.844168 -6.625448) (xy 247.780798 -6.683217)
			(xy 247.712369 -6.734893) (xy 247.639463 -6.780034) (xy 247.562703 -6.818256) (xy 247.482744 -6.849232)
			(xy 247.400268 -6.872699) (xy 247.315978 -6.888455) (xy 247.230595 -6.896367) (xy 247.144845 -6.896367)
			(xy 247.059462 -6.888455) (xy 246.975172 -6.872699) (xy 246.892696 -6.849232) (xy 246.812737 -6.818256)
			(xy 246.735977 -6.780034) (xy 246.663071 -6.734893) (xy 246.594642 -6.683217) (xy 246.531272 -6.625448)
			(xy 246.473503 -6.562078) (xy 246.421827 -6.493649) (xy 246.376686 -6.420743) (xy 246.338464 -6.343983)
			(xy 246.307488 -6.264024) (xy 246.284021 -6.181548) (xy 246.268265 -6.097258) (xy 246.260353 -6.011875)
			(xy 216.248247 -6.011875) (xy 216.240335 -6.097258) (xy 216.224579 -6.181548) (xy 216.201112 -6.264024)
			(xy 216.170136 -6.343983) (xy 216.131914 -6.420743) (xy 216.086773 -6.493649) (xy 216.035097 -6.562078)
			(xy 215.977328 -6.625448) (xy 215.913958 -6.683217) (xy 215.845529 -6.734893) (xy 215.772623 -6.780034)
			(xy 215.695863 -6.818256) (xy 215.615904 -6.849232) (xy 215.533428 -6.872699) (xy 215.449138 -6.888455)
			(xy 215.363755 -6.896367) (xy 215.278005 -6.896367) (xy 215.192622 -6.888455) (xy 215.108332 -6.872699)
			(xy 215.025856 -6.849232) (xy 214.945897 -6.818256) (xy 214.869137 -6.780034) (xy 214.796231 -6.734893)
			(xy 214.727802 -6.683217) (xy 214.664432 -6.625448) (xy 214.606663 -6.562078) (xy 214.554987 -6.493649)
			(xy 214.509846 -6.420743) (xy 214.471624 -6.343983) (xy 214.440648 -6.264024) (xy 214.417181 -6.181548)
			(xy 214.401425 -6.097258) (xy 214.393513 -6.011875) (xy 209.898247 -6.011875) (xy 209.890335 -6.097258)
			(xy 209.874579 -6.181548) (xy 209.851112 -6.264024) (xy 209.820136 -6.343983) (xy 209.781914 -6.420743)
			(xy 209.736773 -6.493649) (xy 209.685097 -6.562078) (xy 209.627328 -6.625448) (xy 209.563958 -6.683217)
			(xy 209.495529 -6.734893) (xy 209.422623 -6.780034) (xy 209.345863 -6.818256) (xy 209.265904 -6.849232)
			(xy 209.183428 -6.872699) (xy 209.099138 -6.888455) (xy 209.013755 -6.896367) (xy 208.928005 -6.896367)
			(xy 208.842622 -6.888455) (xy 208.758332 -6.872699) (xy 208.675856 -6.849232) (xy 208.595897 -6.818256)
			(xy 208.519137 -6.780034) (xy 208.446231 -6.734893) (xy 208.377802 -6.683217) (xy 208.314432 -6.625448)
			(xy 208.256663 -6.562078) (xy 208.204987 -6.493649) (xy 208.159846 -6.420743) (xy 208.121624 -6.343983)
			(xy 208.090648 -6.264024) (xy 208.067181 -6.181548) (xy 208.051425 -6.097258) (xy 208.043513 -6.011875)
			(xy 197.209918 -6.011875) (xy 197.209918 -7.78002) (xy 197.21044 -7.835826) (xy 197.218783 -7.947127)
			(xy 197.235419 -8.057493) (xy 197.260257 -8.166307) (xy 197.293157 -8.27296) (xy 197.333935 -8.376857)
			(xy 197.382363 -8.477416) (xy 197.43817 -8.574075) (xy 197.501045 -8.666293) (xy 197.570635 -8.753555)
			(xy 197.646552 -8.835372) (xy 197.728371 -8.911287) (xy 197.815634 -8.980875) (xy 197.907854 -9.043748)
			(xy 198.004514 -9.099553) (xy 198.105074 -9.147979) (xy 198.208972 -9.188755) (xy 198.315626 -9.221652)
			(xy 198.424441 -9.246487) (xy 198.534807 -9.263121) (xy 198.646108 -9.271461) (xy 198.701914 -9.272016)
			(xy 223.300036 -9.272016) (xy 223.370389 -9.27251) (xy 223.510873 -9.280402) (xy 223.650694 -9.296158)
			(xy 223.789412 -9.319729) (xy 223.92659 -9.35104) (xy 224.061796 -9.389995) (xy 224.194606 -9.436468)
			(xy 224.3246 -9.490316) (xy 224.451371 -9.551367) (xy 224.57452 -9.619431) (xy 224.693658 -9.694292)
			(xy 224.808411 -9.775716) (xy 224.918419 -9.863446) (xy 225.023334 -9.957206) (xy 225.122827 -10.056701)
			(xy 225.216585 -10.161618) (xy 225.304313 -10.271627) (xy 225.385734 -10.386382) (xy 225.460594 -10.505522)
			(xy 225.528655 -10.628671) (xy 225.589704 -10.755444) (xy 225.643549 -10.885439) (xy 225.69002 -11.01825)
			(xy 225.728972 -11.153457) (xy 225.760281 -11.290635) (xy 225.783849 -11.429353) (xy 225.799602 -11.569174)
			(xy 225.807491 -11.709659) (xy 225.808032 -11.780012) (xy 225.808032 -31.197296) (xy 227.377752 -32.767016)
			(xy 254.645668 -32.767016)
		)
		(stroke
			(width 0)
			(type solid)
		)
		(fill yes)
		(layer "In12.Cu")
		(net "DELTA_L_GND_1")
	)
	(gr_poly
		(pts
			(xy 194.495928 -441.17006) (xy 194.49641 -441.126022) (xy 194.50409 -441.03828) (xy 194.519387 -440.951542)
			(xy 194.542185 -440.866466) (xy 194.572311 -440.783702) (xy 194.609536 -440.703878) (xy 194.653576 -440.627602)
			(xy 194.704095 -440.555454) (xy 194.760711 -440.487984) (xy 194.822991 -440.425704) (xy 194.890462 -440.369089)
			(xy 194.96261 -440.31857) (xy 195.038887 -440.274531) (xy 195.118711 -440.237308) (xy 195.201476 -440.207182)
			(xy 195.286551 -440.184385) (xy 195.37329 -440.169088) (xy 195.461032 -440.16141) (xy 195.50507 -440.160918)
			(xy 276.314916 -440.160918) (xy 276.358955 -440.161399) (xy 276.446699 -440.169077) (xy 276.533439 -440.184372)
			(xy 276.618516 -440.207169) (xy 276.701283 -440.237294) (xy 276.781109 -440.274518) (xy 276.857388 -440.318557)
			(xy 276.929538 -440.369076) (xy 276.99701 -440.425692) (xy 277.059292 -440.487972) (xy 277.115909 -440.555443)
			(xy 277.16643 -440.627592) (xy 277.210471 -440.703869) (xy 277.247697 -440.783695) (xy 277.277823 -440.866461)
			(xy 277.300622 -440.951538) (xy 277.31592 -441.038278) (xy 277.3236 -441.126021) (xy 277.324058 -441.17006)
			(xy 277.324058 -441.480956) (xy 463.300064 -441.480956) (xy 463.355834 -441.480449) (xy 463.467062 -441.472116)
			(xy 463.577357 -441.455494) (xy 463.686101 -441.430676) (xy 463.792686 -441.397801) (xy 463.896517 -441.357052)
			(xy 463.997011 -441.308658) (xy 464.093608 -441.252889) (xy 464.185768 -441.190057) (xy 464.272974 -441.120513)
			(xy 464.354739 -441.044647) (xy 464.430606 -440.962883) (xy 464.50015 -440.875677) (xy 464.562982 -440.783519)
			(xy 464.618752 -440.686922) (xy 464.667147 -440.586428) (xy 464.707897 -440.482598) (xy 464.740773 -440.376013)
			(xy 464.765592 -440.267269) (xy 464.782215 -440.156974) (xy 464.790548 -440.045746) (xy 464.791044 -439.989976)
			(xy 464.791044 -419.236652) (xy 464.79206 -419.236652) (xy 464.79206 -419.160198) (xy 464.791552 -419.157912)
			(xy 464.783498 -419.125745) (xy 464.774831 -419.060003) (xy 464.77428 -419.026848) (xy 464.774826 -418.994155)
			(xy 464.783231 -418.929312) (xy 464.791044 -418.897562) (xy 464.791044 -409.528264) (xy 464.791527 -409.457889)
			(xy 464.799416 -409.317359) (xy 464.815173 -409.177493) (xy 464.838748 -409.03873) (xy 464.870067 -408.901508)
			(xy 464.909031 -408.766258) (xy 464.955519 -408.633405) (xy 465.009383 -408.503369) (xy 465.070454 -408.376557)
			(xy 465.138539 -408.25337) (xy 465.213426 -408.134194) (xy 465.294877 -408.019405) (xy 465.382637 -407.909364)
			(xy 465.47643 -407.804418) (xy 465.525866 -407.754328) (xy 467.354412 -405.925782) (xy 467.391723 -405.887821)
			(xy 467.461438 -405.807375) (xy 467.525236 -405.722161) (xy 467.582791 -405.632611) (xy 467.633809 -405.539182)
			(xy 467.678031 -405.442352) (xy 467.715231 -405.342613) (xy 467.74522 -405.240474) (xy 467.767844 -405.136455)
			(xy 467.782988 -405.031087) (xy 467.790575 -404.924907) (xy 467.791038 -404.871682) (xy 467.791038 -82.82813)
			(xy 467.791541 -82.757757) (xy 467.799451 -82.617233) (xy 467.815226 -82.477373) (xy 467.838815 -82.338618)
			(xy 467.870145 -82.201402) (xy 467.909116 -82.066159) (xy 467.955608 -81.933313) (xy 468.009473 -81.803282)
			(xy 468.070541 -81.676474) (xy 468.138622 -81.553289) (xy 468.213501 -81.434114) (xy 468.294942 -81.319323)
			(xy 468.382689 -81.209278) (xy 468.476467 -81.104324) (xy 468.52586 -81.054194) (xy 470.854278 -78.725776)
			(xy 470.891589 -78.687815) (xy 470.961306 -78.60737) (xy 471.025105 -78.522156) (xy 471.082661 -78.432606)
			(xy 471.13368 -78.339178) (xy 471.177903 -78.242348) (xy 471.215103 -78.142608) (xy 471.245092 -78.040469)
			(xy 471.267716 -77.93645) (xy 471.28286 -77.831082) (xy 471.290447 -77.724901) (xy 471.290904 -77.671676)
			(xy 471.290904 -13.780008) (xy 471.290383 -13.724238) (xy 471.282048 -13.613011) (xy 471.265425 -13.502718)
			(xy 471.240606 -13.393975) (xy 471.20773 -13.287391) (xy 471.166981 -13.183562) (xy 471.118587 -13.083068)
			(xy 471.062818 -12.986472) (xy 470.999987 -12.894314) (xy 470.930444 -12.807108) (xy 470.854579 -12.725344)
			(xy 470.772816 -12.649477) (xy 470.685612 -12.579932) (xy 470.593455 -12.517099) (xy 470.49686 -12.461328)
			(xy 470.396367 -12.412932) (xy 470.292539 -12.372181) (xy 470.185956 -12.339303) (xy 470.077214 -12.314481)
			(xy 469.966921 -12.297855) (xy 469.855694 -12.289518) (xy 469.799924 -12.289028) (xy 464.613244 -12.289028)
			(xy 464.613244 -12.288012) (xy 464.272376 -12.288012) (xy 464.272376 -12.289028) (xy 458.20203 -12.289028)
			(xy 458.131647 -12.288544) (xy 457.991102 -12.280653) (xy 457.85122 -12.264894) (xy 457.712443 -12.241316)
			(xy 457.575205 -12.209994) (xy 457.43994 -12.171027) (xy 457.307072 -12.124536) (xy 457.177021 -12.070668)
			(xy 457.050194 -12.009593) (xy 456.926991 -11.941503) (xy 456.8078 -11.866612) (xy 456.692996 -11.785156)
			(xy 456.582939 -11.69739) (xy 456.477977 -11.603592) (xy 456.378439 -11.504056) (xy 456.284639 -11.399096)
			(xy 456.196872 -11.289041) (xy 456.115413 -11.174238) (xy 456.04052 -11.055048) (xy 455.972428 -10.931847)
			(xy 455.911351 -10.805021) (xy 455.857481 -10.674971) (xy 455.810987 -10.542104) (xy 455.772017 -10.406839)
			(xy 455.740693 -10.269603) (xy 455.717113 -10.130825) (xy 455.701351 -9.990944) (xy 455.693457 -9.850399)
			(xy 455.693018 -9.780016) (xy 455.693018 -0.999998) (xy 455.692493 -0.967851) (xy 455.684101 -0.904107)
			(xy 455.667461 -0.842004) (xy 455.642857 -0.782603) (xy 455.610712 -0.726922) (xy 455.571573 -0.675913)
			(xy 455.526112 -0.630449) (xy 455.475106 -0.591307) (xy 455.419427 -0.559158) (xy 455.360029 -0.53455)
			(xy 455.297926 -0.517906) (xy 455.234183 -0.50951) (xy 455.202036 -0.509016) (xy 388.601966 -0.509016)
			(xy 388.569821 -0.509544) (xy 388.506082 -0.517939) (xy 388.443984 -0.534582) (xy 388.384589 -0.559188)
			(xy 388.328914 -0.591335) (xy 388.277911 -0.630474) (xy 388.232453 -0.675936) (xy 388.193318 -0.726941)
			(xy 388.161174 -0.782618) (xy 388.136572 -0.842014) (xy 388.119933 -0.904114) (xy 388.111542 -0.967853)
			(xy 388.110984 -0.999998) (xy 388.110984 -5.169916) (xy 388.850131 -5.169916) (xy 388.854136 -5.082008)
			(xy 388.866119 -4.994828) (xy 388.885979 -4.909099) (xy 388.913554 -4.825531) (xy 388.948613 -4.744817)
			(xy 388.990866 -4.667625) (xy 389.039964 -4.594596) (xy 389.0955 -4.526334) (xy 389.157012 -4.463404)
			(xy 389.223993 -4.40633) (xy 389.295886 -4.355582) (xy 389.372095 -4.311582) (xy 389.45199 -4.274695)
			(xy 389.534909 -4.245226) (xy 389.620164 -4.223419) (xy 389.707048 -4.209455) (xy 389.794842 -4.203449)
			(xy 389.882819 -4.205453) (xy 389.970249 -4.215448) (xy 390.056408 -4.233352) (xy 390.140582 -4.259016)
			(xy 390.222073 -4.292229) (xy 390.300207 -4.332715) (xy 390.374335 -4.380137) (xy 390.443843 -4.434104)
			(xy 390.508157 -4.494169) (xy 390.566741 -4.559833) (xy 390.619112 -4.630552) (xy 390.664835 -4.70574)
			(xy 390.703532 -4.784775) (xy 390.734881 -4.867001) (xy 390.758623 -4.951737) (xy 390.763638 -4.978969)
			(xy 394.947631 -4.978969) (xy 394.947631 -4.924431) (xy 394.955393 -4.870448) (xy 394.970758 -4.81812)
			(xy 394.993414 -4.76851) (xy 395.0229 -4.72263) (xy 395.058614 -4.681413) (xy 395.099832 -4.645698)
			(xy 395.145712 -4.616213) (xy 395.195321 -4.593557) (xy 395.24765 -4.578193) (xy 395.301633 -4.570431)
			(xy 395.328902 -4.569968) (xy 396.192502 -4.569968) (xy 396.219773 -4.570395) (xy 396.273761 -4.578157)
			(xy 396.326094 -4.593524) (xy 396.375708 -4.616182) (xy 396.421593 -4.64567) (xy 396.462813 -4.681388)
			(xy 396.498531 -4.722609) (xy 396.528019 -4.768493) (xy 396.550677 -4.818107) (xy 396.566043 -4.870441)
			(xy 396.573806 -4.924429) (xy 396.573806 -4.978971) (xy 398.547532 -4.978971) (xy 398.547532 -4.924429)
			(xy 398.555294 -4.870443) (xy 398.570661 -4.818111) (xy 398.593321 -4.768498) (xy 398.62281 -4.722616)
			(xy 398.658529 -4.681398) (xy 398.699751 -4.645684) (xy 398.745637 -4.616199) (xy 398.795252 -4.593546)
			(xy 398.847586 -4.578185) (xy 398.901573 -4.570428) (xy 398.928844 -4.569968) (xy 399.792444 -4.569968)
			(xy 399.819713 -4.570398) (xy 399.873697 -4.578165) (xy 399.926025 -4.593535) (xy 399.975633 -4.616196)
			(xy 400.021512 -4.645685) (xy 400.062728 -4.681403) (xy 400.098441 -4.722623) (xy 400.127925 -4.768505)
			(xy 400.15058 -4.818116) (xy 400.165944 -4.870447) (xy 400.173706 -4.92443) (xy 400.173706 -4.978967)
			(xy 402.147554 -4.978967) (xy 402.147554 -4.924433) (xy 402.155315 -4.870455) (xy 402.170678 -4.818131)
			(xy 402.193332 -4.768526) (xy 402.222814 -4.722649) (xy 402.258525 -4.681435) (xy 402.299738 -4.645722)
			(xy 402.345613 -4.616239) (xy 402.395218 -4.593583) (xy 402.447542 -4.578218) (xy 402.501519 -4.570455)
			(xy 402.528786 -4.569968) (xy 403.392386 -4.569968) (xy 403.41966 -4.570371) (xy 403.473652 -4.578132)
			(xy 403.525991 -4.593498) (xy 403.57561 -4.616157) (xy 403.621499 -4.645646) (xy 403.662724 -4.681366)
			(xy 403.698445 -4.72259) (xy 403.727937 -4.768478) (xy 403.750597 -4.818096) (xy 403.765965 -4.870434)
			(xy 403.773728 -4.924426) (xy 403.773728 -4.978966) (xy 405.747754 -4.978966) (xy 405.747754 -4.924434)
			(xy 405.755515 -4.870456) (xy 405.770878 -4.818132) (xy 405.793531 -4.768527) (xy 405.823013 -4.72265)
			(xy 405.858724 -4.681436) (xy 405.899936 -4.645724) (xy 405.945811 -4.61624) (xy 405.995415 -4.593584)
			(xy 406.047738 -4.578219) (xy 406.101716 -4.570456) (xy 406.128982 -4.569968) (xy 406.992582 -4.569968)
			(xy 407.019856 -4.57037) (xy 407.073849 -4.578131) (xy 407.126188 -4.593497) (xy 407.175807 -4.616155)
			(xy 407.221697 -4.645645) (xy 407.262922 -4.681365) (xy 407.298644 -4.722589) (xy 407.328136 -4.768477)
			(xy 407.350797 -4.818095) (xy 407.366165 -4.870433) (xy 407.373928 -4.924426) (xy 407.373928 -4.978971)
			(xy 414.857632 -4.978971) (xy 414.857632 -4.924429) (xy 414.865394 -4.870442) (xy 414.880762 -4.81811)
			(xy 414.903421 -4.768498) (xy 414.93291 -4.722616) (xy 414.96863 -4.681397) (xy 415.009852 -4.645683)
			(xy 415.055738 -4.616199) (xy 415.105353 -4.593546) (xy 415.157687 -4.578184) (xy 415.211675 -4.570428)
			(xy 415.238946 -4.569968) (xy 416.102546 -4.569968) (xy 416.129815 -4.570398) (xy 416.183798 -4.578165)
			(xy 416.236126 -4.593536) (xy 416.285735 -4.616196) (xy 416.331613 -4.645686) (xy 416.372829 -4.681404)
			(xy 416.408542 -4.722624) (xy 416.438026 -4.768506) (xy 416.46068 -4.818117) (xy 416.476045 -4.870447)
			(xy 416.483806 -4.924431) (xy 416.483806 -4.978967) (xy 418.457654 -4.978967) (xy 418.457654 -4.924433)
			(xy 418.465415 -4.870455) (xy 418.480779 -4.818131) (xy 418.503432 -4.768525) (xy 418.532915 -4.722648)
			(xy 418.568626 -4.681434) (xy 418.609839 -4.645722) (xy 418.655715 -4.616238) (xy 418.705319 -4.593583)
			(xy 418.757643 -4.578218) (xy 418.811621 -4.570455) (xy 418.838888 -4.569968) (xy 419.702488 -4.569968)
			(xy 419.729762 -4.570371) (xy 419.783754 -4.578132) (xy 419.836092 -4.593499) (xy 419.885711 -4.616157)
			(xy 419.9316 -4.645647) (xy 419.972824 -4.681367) (xy 420.008546 -4.722591) (xy 420.038037 -4.768479)
			(xy 420.060697 -4.818096) (xy 420.076065 -4.870434) (xy 420.083828 -4.924426) (xy 420.083828 -4.978966)
			(xy 426.067754 -4.978966) (xy 426.067754 -4.924434) (xy 426.075515 -4.870456) (xy 426.090878 -4.818132)
			(xy 426.113531 -4.768527) (xy 426.143013 -4.72265) (xy 426.178724 -4.681436) (xy 426.219936 -4.645724)
			(xy 426.265811 -4.61624) (xy 426.315415 -4.593584) (xy 426.367738 -4.578219) (xy 426.421716 -4.570456)
			(xy 426.448982 -4.569968) (xy 427.312582 -4.569968) (xy 427.339856 -4.57037) (xy 427.393849 -4.578131)
			(xy 427.446188 -4.593497) (xy 427.495807 -4.616155) (xy 427.541697 -4.645645) (xy 427.582922 -4.681365)
			(xy 427.618644 -4.722589) (xy 427.648136 -4.768477) (xy 427.670797 -4.818095) (xy 427.686165 -4.870433)
			(xy 427.693928 -4.924426) (xy 427.693928 -4.97897) (xy 429.667631 -4.97897) (xy 429.667631 -4.92443)
			(xy 429.675394 -4.870445) (xy 429.69076 -4.818115) (xy 429.713417 -4.768504) (xy 429.742905 -4.722623)
			(xy 429.778622 -4.681405) (xy 429.819842 -4.645691) (xy 429.865725 -4.616206) (xy 429.915337 -4.593552)
			(xy 429.967669 -4.578189) (xy 430.021654 -4.57043) (xy 430.048924 -4.569968) (xy 430.912524 -4.569968)
			(xy 430.939794 -4.570396) (xy 430.99378 -4.578161) (xy 431.04611 -4.59353) (xy 431.095721 -4.616189)
			(xy 431.141603 -4.645678) (xy 431.182821 -4.681396) (xy 431.218536 -4.722616) (xy 431.248022 -4.7685)
			(xy 431.270679 -4.818112) (xy 431.286044 -4.870444) (xy 431.293806 -4.92443) (xy 431.293806 -4.97897)
			(xy 431.286044 -5.032956) (xy 431.270679 -5.085288) (xy 431.248022 -5.1349) (xy 431.218536 -5.180784)
			(xy 431.182821 -5.222004) (xy 431.141603 -5.257722) (xy 431.095721 -5.287211) (xy 431.04611 -5.30987)
			(xy 430.99378 -5.325239) (xy 430.939794 -5.333004) (xy 430.912524 -5.333492) (xy 430.048924 -5.333492)
			(xy 430.021654 -5.33297) (xy 429.967669 -5.325211) (xy 429.915337 -5.309848) (xy 429.865725 -5.287194)
			(xy 429.819842 -5.257709) (xy 429.778622 -5.221995) (xy 429.742905 -5.180777) (xy 429.713417 -5.134896)
			(xy 429.69076 -5.085285) (xy 429.675394 -5.032955) (xy 429.667631 -4.97897) (xy 427.693928 -4.97897)
			(xy 427.693928 -4.978974) (xy 427.686165 -5.032967) (xy 427.670797 -5.085305) (xy 427.648136 -5.134923)
			(xy 427.618644 -5.180811) (xy 427.582922 -5.222035) (xy 427.541697 -5.257755) (xy 427.495807 -5.287245)
			(xy 427.446188 -5.309903) (xy 427.393849 -5.325269) (xy 427.339856 -5.33303) (xy 427.312582 -5.333492)
			(xy 426.448982 -5.333492) (xy 426.421716 -5.332944) (xy 426.367738 -5.325181) (xy 426.315415 -5.309816)
			(xy 426.265811 -5.28716) (xy 426.219936 -5.257676) (xy 426.178724 -5.221964) (xy 426.143013 -5.18075)
			(xy 426.113531 -5.134873) (xy 426.090878 -5.085268) (xy 426.075515 -5.032944) (xy 426.067754 -4.978966)
			(xy 420.083828 -4.978966) (xy 420.083828 -4.978974) (xy 420.076065 -5.032966) (xy 420.060697 -5.085304)
			(xy 420.038037 -5.134921) (xy 420.008546 -5.180809) (xy 419.972824 -5.222033) (xy 419.9316 -5.257753)
			(xy 419.885711 -5.287243) (xy 419.836092 -5.309901) (xy 419.783754 -5.325268) (xy 419.729762 -5.333029)
			(xy 419.702488 -5.333492) (xy 418.838888 -5.333492) (xy 418.811621 -5.332945) (xy 418.757643 -5.325182)
			(xy 418.705319 -5.309817) (xy 418.655715 -5.287162) (xy 418.609839 -5.257678) (xy 418.568626 -5.221966)
			(xy 418.532915 -5.180752) (xy 418.503432 -5.134875) (xy 418.480779 -5.085269) (xy 418.465415 -5.032945)
			(xy 418.457654 -4.978967) (xy 416.483806 -4.978967) (xy 416.483806 -4.978969) (xy 416.476045 -5.032953)
			(xy 416.46068 -5.085283) (xy 416.438026 -5.134894) (xy 416.408542 -5.180776) (xy 416.372829 -5.221996)
			(xy 416.331613 -5.257714) (xy 416.285735 -5.287204) (xy 416.236126 -5.309864) (xy 416.183798 -5.325235)
			(xy 416.129815 -5.333002) (xy 416.102546 -5.333492) (xy 415.238946 -5.333492) (xy 415.211675 -5.332972)
			(xy 415.157687 -5.325216) (xy 415.105353 -5.309854) (xy 415.055738 -5.287201) (xy 415.009852 -5.257717)
			(xy 414.96863 -5.222003) (xy 414.93291 -5.180784) (xy 414.903421 -5.134902) (xy 414.880762 -5.08529)
			(xy 414.865394 -5.032958) (xy 414.857632 -4.978971) (xy 407.373928 -4.978971) (xy 407.373928 -4.978974)
			(xy 407.366165 -5.032967) (xy 407.350797 -5.085305) (xy 407.328136 -5.134923) (xy 407.298644 -5.180811)
			(xy 407.262922 -5.222035) (xy 407.221697 -5.257755) (xy 407.175807 -5.287245) (xy 407.126188 -5.309903)
			(xy 407.073849 -5.325269) (xy 407.019856 -5.33303) (xy 406.992582 -5.333492) (xy 406.128982 -5.333492)
			(xy 406.101716 -5.332944) (xy 406.047738 -5.325181) (xy 405.995415 -5.309816) (xy 405.945811 -5.28716)
			(xy 405.899936 -5.257676) (xy 405.858724 -5.221964) (xy 405.823013 -5.18075) (xy 405.793531 -5.134873)
			(xy 405.770878 -5.085268) (xy 405.755515 -5.032944) (xy 405.747754 -4.978966) (xy 403.773728 -4.978966)
			(xy 403.773728 -4.978974) (xy 403.765965 -5.032966) (xy 403.750597 -5.085304) (xy 403.727937 -5.134922)
			(xy 403.698445 -5.18081) (xy 403.662724 -5.222034) (xy 403.621499 -5.257754) (xy 403.57561 -5.287243)
			(xy 403.525991 -5.309902) (xy 403.473652 -5.325268) (xy 403.41966 -5.333029) (xy 403.392386 -5.333492)
			(xy 402.528786 -5.333492) (xy 402.501519 -5.332945) (xy 402.447542 -5.325182) (xy 402.395218 -5.309817)
			(xy 402.345613 -5.287161) (xy 402.299738 -5.257678) (xy 402.258525 -5.221965) (xy 402.222814 -5.180751)
			(xy 402.193332 -5.134874) (xy 402.170678 -5.085269) (xy 402.155315 -5.032945) (xy 402.147554 -4.978967)
			(xy 400.173706 -4.978967) (xy 400.173706 -4.97897) (xy 400.165944 -5.032953) (xy 400.15058 -5.085284)
			(xy 400.127925 -5.134895) (xy 400.098441 -5.180777) (xy 400.062728 -5.221997) (xy 400.021512 -5.257715)
			(xy 399.975633 -5.287204) (xy 399.926025 -5.309865) (xy 399.873697 -5.325235) (xy 399.819713 -5.333002)
			(xy 399.792444 -5.333492) (xy 398.928844 -5.333492) (xy 398.901573 -5.332972) (xy 398.847586 -5.325215)
			(xy 398.795252 -5.309854) (xy 398.745637 -5.287201) (xy 398.699751 -5.257716) (xy 398.658529 -5.222002)
			(xy 398.62281 -5.180784) (xy 398.593321 -5.134902) (xy 398.570661 -5.085289) (xy 398.555294 -5.032957)
			(xy 398.547532 -4.978971) (xy 396.573806 -4.978971) (xy 396.566043 -5.032959) (xy 396.550677 -5.085293)
			(xy 396.528019 -5.134907) (xy 396.498531 -5.180791) (xy 396.462813 -5.222012) (xy 396.421593 -5.25773)
			(xy 396.375708 -5.287218) (xy 396.326094 -5.309876) (xy 396.273761 -5.325243) (xy 396.219773 -5.333005)
			(xy 396.192502 -5.333492) (xy 395.328902 -5.333492) (xy 395.301633 -5.332969) (xy 395.24765 -5.325207)
			(xy 395.195321 -5.309843) (xy 395.145712 -5.287187) (xy 395.099832 -5.257702) (xy 395.058614 -5.221987)
			(xy 395.0229 -5.18077) (xy 394.993414 -5.13489) (xy 394.970758 -5.08528) (xy 394.955393 -5.032952)
			(xy 394.947631 -4.978969) (xy 390.763638 -4.978969) (xy 390.774561 -5.038281) (xy 390.782563 -5.125916)
			(xy 390.783064 -5.169916) (xy 390.782563 -5.213916) (xy 390.774561 -5.301551) (xy 390.758623 -5.388095)
			(xy 390.734881 -5.472831) (xy 390.703532 -5.555057) (xy 390.664835 -5.634092) (xy 390.619112 -5.70928)
			(xy 390.566741 -5.779999) (xy 390.508157 -5.845663) (xy 390.443843 -5.905728) (xy 390.374335 -5.959695)
			(xy 390.300207 -6.007117) (xy 390.222073 -6.047603) (xy 390.140582 -6.080816) (xy 390.056408 -6.10648)
			(xy 389.970249 -6.124384) (xy 389.882819 -6.134379) (xy 389.794842 -6.136383) (xy 389.707048 -6.130377)
			(xy 389.620164 -6.116413) (xy 389.534909 -6.094606) (xy 389.45199 -6.065137) (xy 389.372095 -6.02825)
			(xy 389.295886 -5.98425) (xy 389.223993 -5.933502) (xy 389.157012 -5.876428) (xy 389.0955 -5.813498)
			(xy 389.039964 -5.745236) (xy 388.990866 -5.672207) (xy 388.948613 -5.595015) (xy 388.913554 -5.514301)
			(xy 388.885979 -5.430733) (xy 388.866119 -5.345004) (xy 388.854136 -5.257824) (xy 388.850131 -5.169916)
			(xy 388.110984 -5.169916) (xy 388.110984 -6.169914) (xy 453.015103 -6.169914) (xy 453.019108 -6.082006)
			(xy 453.031091 -5.994826) (xy 453.050951 -5.909097) (xy 453.078526 -5.825529) (xy 453.113585 -5.744815)
			(xy 453.155838 -5.667623) (xy 453.204936 -5.594594) (xy 453.260472 -5.526332) (xy 453.321984 -5.463402)
			(xy 453.388965 -5.406328) (xy 453.460858 -5.35558) (xy 453.537067 -5.31158) (xy 453.616962 -5.274693)
			(xy 453.699881 -5.245224) (xy 453.785136 -5.223417) (xy 453.87202 -5.209453) (xy 453.959814 -5.203447)
			(xy 454.047791 -5.205451) (xy 454.135221 -5.215446) (xy 454.22138 -5.23335) (xy 454.305554 -5.259014)
			(xy 454.387045 -5.292227) (xy 454.465179 -5.332713) (xy 454.539307 -5.380135) (xy 454.608815 -5.434102)
			(xy 454.673129 -5.494167) (xy 454.731713 -5.559831) (xy 454.784084 -5.63055) (xy 454.829807 -5.705738)
			(xy 454.868504 -5.784773) (xy 454.899853 -5.866999) (xy 454.923595 -5.951735) (xy 454.939533 -6.038279)
			(xy 454.947535 -6.125914) (xy 454.948036 -6.169914) (xy 454.947535 -6.213914) (xy 454.939533 -6.301549)
			(xy 454.923595 -6.388093) (xy 454.899853 -6.472829) (xy 454.868504 -6.555055) (xy 454.829807 -6.63409)
			(xy 454.784084 -6.709278) (xy 454.731713 -6.779997) (xy 454.673129 -6.845661) (xy 454.608815 -6.905726)
			(xy 454.539307 -6.959693) (xy 454.465179 -7.007115) (xy 454.387045 -7.047601) (xy 454.305554 -7.080814)
			(xy 454.22138 -7.106478) (xy 454.135221 -7.124382) (xy 454.047791 -7.134377) (xy 453.959814 -7.136381)
			(xy 453.87202 -7.130375) (xy 453.785136 -7.116411) (xy 453.699881 -7.094604) (xy 453.616962 -7.065135)
			(xy 453.537067 -7.028248) (xy 453.460858 -6.984248) (xy 453.388965 -6.9335) (xy 453.321984 -6.876426)
			(xy 453.260472 -6.813496) (xy 453.204936 -6.745234) (xy 453.155838 -6.672205) (xy 453.113585 -6.595013)
			(xy 453.078526 -6.514299) (xy 453.050951 -6.430731) (xy 453.031091 -6.345002) (xy 453.019108 -6.257822)
			(xy 453.015103 -6.169914) (xy 388.110984 -6.169914) (xy 388.110984 -6.740774) (xy 393.142876 -6.740774)
			(xy 393.142876 -6.686226) (xy 393.150639 -6.632232) (xy 393.166008 -6.579894) (xy 393.18867 -6.530275)
			(xy 393.218162 -6.484387) (xy 393.253885 -6.443163) (xy 393.295112 -6.407443) (xy 393.341003 -6.377954)
			(xy 393.390624 -6.355297) (xy 393.442964 -6.339932) (xy 393.496958 -6.332173) (xy 393.524232 -6.331712)
			(xy 394.387832 -6.331712) (xy 394.415098 -6.332253) (xy 394.469074 -6.340017) (xy 394.521397 -6.355384)
			(xy 394.570999 -6.378041) (xy 394.616873 -6.407526) (xy 394.658084 -6.443238) (xy 394.693794 -6.484452)
			(xy 394.723274 -6.530329) (xy 394.745927 -6.579933) (xy 394.761289 -6.632257) (xy 394.76905 -6.686234)
			(xy 394.76905 -6.740766) (xy 394.769049 -6.74077) (xy 396.742898 -6.74077) (xy 396.742898 -6.68623)
			(xy 396.75066 -6.632245) (xy 396.766025 -6.579914) (xy 396.788681 -6.530302) (xy 396.818166 -6.484419)
			(xy 396.853881 -6.4432) (xy 396.895099 -6.407482) (xy 396.940979 -6.377993) (xy 396.99059 -6.355334)
			(xy 397.04292 -6.339965) (xy 397.096904 -6.3322) (xy 397.124174 -6.331712) (xy 397.987774 -6.331712)
			(xy 398.015044 -6.332226) (xy 398.06903 -6.339984) (xy 398.121363 -6.355347) (xy 398.170976 -6.378002)
			(xy 398.216859 -6.407487) (xy 398.25808 -6.443202) (xy 398.293798 -6.48442) (xy 398.323286 -6.530301)
			(xy 398.345944 -6.579913) (xy 398.36131 -6.632244) (xy 398.369072 -6.68623) (xy 398.369072 -6.74077)
			(xy 398.369071 -6.740774) (xy 400.342776 -6.740774) (xy 400.342776 -6.686226) (xy 400.350539 -6.632234)
			(xy 400.365907 -6.579897) (xy 400.388567 -6.530279) (xy 400.418058 -6.484392) (xy 400.45378 -6.443168)
			(xy 400.495005 -6.407449) (xy 400.540893 -6.377959) (xy 400.590512 -6.355301) (xy 400.64285 -6.339935)
			(xy 400.696842 -6.332174) (xy 400.724116 -6.331712) (xy 401.587716 -6.331712) (xy 401.614983 -6.332251)
			(xy 401.668961 -6.340014) (xy 401.721285 -6.35538) (xy 401.77089 -6.378036) (xy 401.816766 -6.40752)
			(xy 401.857978 -6.443233) (xy 401.89369 -6.484447) (xy 401.923172 -6.530324) (xy 401.945825 -6.57993)
			(xy 401.961189 -6.632255) (xy 401.96895 -6.686233) (xy 401.96895 -6.740767) (xy 401.968949 -6.740773)
			(xy 403.942976 -6.740773) (xy 403.942976 -6.686227) (xy 403.950739 -6.632235) (xy 403.966106 -6.579898)
			(xy 403.988766 -6.53028) (xy 404.018257 -6.484393) (xy 404.053978 -6.44317) (xy 404.095203 -6.40745)
			(xy 404.141091 -6.377961) (xy 404.190709 -6.355302) (xy 404.243047 -6.339936) (xy 404.297039 -6.332175)
			(xy 404.324312 -6.331712) (xy 405.187912 -6.331712) (xy 405.215179 -6.332251) (xy 405.269158 -6.340014)
			(xy 405.321482 -6.355379) (xy 405.371087 -6.378034) (xy 405.416964 -6.407519) (xy 405.458177 -6.443231)
			(xy 405.493889 -6.484446) (xy 405.523371 -6.530323) (xy 405.546025 -6.579929) (xy 405.561389 -6.632254)
			(xy 405.56915 -6.686233) (xy 405.56915 -6.740767) (xy 405.56915 -6.74077) (xy 413.052998 -6.74077)
			(xy 413.052998 -6.68623) (xy 413.06076 -6.632245) (xy 413.076125 -6.579914) (xy 413.098781 -6.530302)
			(xy 413.128267 -6.484419) (xy 413.163982 -6.443199) (xy 413.205199 -6.407481) (xy 413.25108 -6.377993)
			(xy 413.300691 -6.355334) (xy 413.353021 -6.339965) (xy 413.407006 -6.3322) (xy 413.434276 -6.331712)
			(xy 414.297876 -6.331712) (xy 414.325146 -6.332226) (xy 414.379132 -6.339985) (xy 414.431464 -6.355348)
			(xy 414.481077 -6.378002) (xy 414.52696 -6.407487) (xy 414.568181 -6.443202) (xy 414.603898 -6.48442)
			(xy 414.633386 -6.530302) (xy 414.656044 -6.579913) (xy 414.67141 -6.632244) (xy 414.679173 -6.68623)
			(xy 414.679173 -6.74077) (xy 414.679172 -6.740774) (xy 416.652876 -6.740774) (xy 416.652876 -6.686226)
			(xy 416.660639 -6.632234) (xy 416.676007 -6.579897) (xy 416.698667 -6.530279) (xy 416.728159 -6.484391)
			(xy 416.763881 -6.443168) (xy 416.805106 -6.407448) (xy 416.850995 -6.377959) (xy 416.900613 -6.355301)
			(xy 416.952952 -6.339935) (xy 417.006944 -6.332174) (xy 417.034218 -6.331712) (xy 417.897818 -6.331712)
			(xy 417.925085 -6.332252) (xy 417.979063 -6.340015) (xy 418.031386 -6.355381) (xy 418.080991 -6.378036)
			(xy 418.126867 -6.407521) (xy 418.168079 -6.443234) (xy 418.20379 -6.484448) (xy 418.233272 -6.530325)
			(xy 418.255926 -6.57993) (xy 418.271289 -6.632255) (xy 418.27905 -6.686233) (xy 418.27905 -6.740767)
			(xy 418.279049 -6.740773) (xy 424.262976 -6.740773) (xy 424.262976 -6.686227) (xy 424.270739 -6.632235)
			(xy 424.286106 -6.579898) (xy 424.308766 -6.53028) (xy 424.338257 -6.484393) (xy 424.373978 -6.44317)
			(xy 424.415203 -6.40745) (xy 424.461091 -6.377961) (xy 424.510709 -6.355302) (xy 424.563047 -6.339936)
			(xy 424.617039 -6.332175) (xy 424.644312 -6.331712) (xy 425.507912 -6.331712) (xy 425.535179 -6.332251)
			(xy 425.589158 -6.340014) (xy 425.641482 -6.355379) (xy 425.691087 -6.378034) (xy 425.736964 -6.407519)
			(xy 425.778177 -6.443231) (xy 425.813889 -6.484446) (xy 425.843371 -6.530323) (xy 425.866025 -6.579929)
			(xy 425.881389 -6.632254) (xy 425.88915 -6.686233) (xy 425.88915 -6.740767) (xy 425.88915 -6.740769)
			(xy 427.862998 -6.740769) (xy 427.862998 -6.686231) (xy 427.870759 -6.632248) (xy 427.886123 -6.579918)
			(xy 427.908778 -6.530308) (xy 427.938261 -6.484426) (xy 427.973974 -6.443207) (xy 428.015189 -6.407489)
			(xy 428.061067 -6.378) (xy 428.110675 -6.35534) (xy 428.163003 -6.339969) (xy 428.216985 -6.332202)
			(xy 428.244254 -6.331712) (xy 429.107854 -6.331712) (xy 429.135125 -6.332224) (xy 429.189113 -6.339981)
			(xy 429.241448 -6.355342) (xy 429.291064 -6.377995) (xy 429.33695 -6.40748) (xy 429.378173 -6.443195)
			(xy 429.413893 -6.484413) (xy 429.443383 -6.530296) (xy 429.466042 -6.579909) (xy 429.48141 -6.632242)
			(xy 429.489172 -6.686229) (xy 429.489172 -6.740771) (xy 429.488151 -6.747873) (xy 431.473788 -6.747873)
			(xy 431.473788 -6.693327) (xy 431.48155 -6.639337) (xy 431.496918 -6.587001) (xy 431.519578 -6.537385)
			(xy 431.549068 -6.491498) (xy 431.584789 -6.450276) (xy 431.626013 -6.414558) (xy 431.6719 -6.385069)
			(xy 431.721518 -6.362412) (xy 431.773854 -6.347047) (xy 431.827845 -6.339286) (xy 431.855118 -6.338824)
			(xy 432.718718 -6.338824) (xy 432.745986 -6.33934) (xy 432.799965 -6.347103) (xy 432.852291 -6.362469)
			(xy 432.901897 -6.385126) (xy 432.947774 -6.414611) (xy 432.988988 -6.450325) (xy 433.0247 -6.491541)
			(xy 433.054183 -6.537419) (xy 433.076837 -6.587026) (xy 433.092201 -6.639352) (xy 433.099962 -6.693332)
			(xy 433.099962 -6.740771) (xy 445.457798 -6.740771) (xy 445.457798 -6.686229) (xy 445.46556 -6.632243)
			(xy 445.480926 -6.579911) (xy 445.503583 -6.530298) (xy 445.53307 -6.484415) (xy 445.568786 -6.443195)
			(xy 445.610005 -6.407477) (xy 445.655888 -6.377989) (xy 445.7055 -6.35533) (xy 445.757831 -6.339963)
			(xy 445.811817 -6.332199) (xy 445.839088 -6.331712) (xy 446.702688 -6.331712) (xy 446.729958 -6.332227)
			(xy 446.783942 -6.339987) (xy 446.836273 -6.355351) (xy 446.885884 -6.378006) (xy 446.931766 -6.407492)
			(xy 446.972985 -6.443207) (xy 447.008701 -6.484424) (xy 447.038188 -6.530305) (xy 447.060845 -6.579916)
			(xy 447.076211 -6.632246) (xy 447.083973 -6.68623) (xy 447.083973 -6.74077) (xy 447.076211 -6.794754)
			(xy 447.060845 -6.847084) (xy 447.038188 -6.896695) (xy 447.008701 -6.942576) (xy 446.972985 -6.983793)
			(xy 446.931766 -7.019508) (xy 446.885884 -7.048994) (xy 446.836273 -7.071649) (xy 446.783942 -7.087013)
			(xy 446.729958 -7.094773) (xy 446.702688 -7.095236) (xy 445.839088 -7.095236) (xy 445.811817 -7.094801)
			(xy 445.757831 -7.087037) (xy 445.7055 -7.07167) (xy 445.655888 -7.049011) (xy 445.610005 -7.019523)
			(xy 445.568786 -6.983805) (xy 445.53307 -6.942585) (xy 445.503583 -6.896702) (xy 445.480926 -6.847089)
			(xy 445.46556 -6.794757) (xy 445.457798 -6.740771) (xy 433.099962 -6.740771) (xy 433.099962 -6.747868)
			(xy 433.092201 -6.801848) (xy 433.076837 -6.854174) (xy 433.054183 -6.903781) (xy 433.0247 -6.949659)
			(xy 432.988988 -6.990875) (xy 432.947774 -7.026589) (xy 432.901897 -7.056074) (xy 432.852291 -7.078731)
			(xy 432.799965 -7.094097) (xy 432.745986 -7.10186) (xy 432.718718 -7.102348) (xy 431.855118 -7.102348)
			(xy 431.827845 -7.101914) (xy 431.773854 -7.094153) (xy 431.721518 -7.078788) (xy 431.6719 -7.056131)
			(xy 431.626013 -7.026642) (xy 431.584789 -6.990924) (xy 431.549068 -6.949702) (xy 431.519578 -6.903815)
			(xy 431.496918 -6.854199) (xy 431.48155 -6.801863) (xy 431.473788 -6.747873) (xy 429.488151 -6.747873)
			(xy 429.48141 -6.794758) (xy 429.466042 -6.847091) (xy 429.443383 -6.896704) (xy 429.413893 -6.942587)
			(xy 429.378173 -6.983805) (xy 429.33695 -7.01952) (xy 429.291064 -7.049005) (xy 429.241448 -7.071658)
			(xy 429.189113 -7.087019) (xy 429.135125 -7.094776) (xy 429.107854 -7.095236) (xy 428.244254 -7.095236)
			(xy 428.216985 -7.094798) (xy 428.163003 -7.087031) (xy 428.110675 -7.07166) (xy 428.061067 -7.049)
			(xy 428.015189 -7.019511) (xy 427.973974 -6.983793) (xy 427.938261 -6.942574) (xy 427.908778 -6.896692)
			(xy 427.886123 -6.847082) (xy 427.870759 -6.794752) (xy 427.862998 -6.740769) (xy 425.88915 -6.740769)
			(xy 425.881389 -6.794746) (xy 425.866025 -6.847071) (xy 425.843371 -6.896677) (xy 425.813889 -6.942554)
			(xy 425.778177 -6.983769) (xy 425.736964 -7.019481) (xy 425.691087 -7.048966) (xy 425.641482 -7.071621)
			(xy 425.589158 -7.086986) (xy 425.535179 -7.094749) (xy 425.507912 -7.095236) (xy 424.644312 -7.095236)
			(xy 424.617039 -7.094825) (xy 424.563047 -7.087064) (xy 424.510709 -7.071698) (xy 424.461091 -7.049039)
			(xy 424.415203 -7.01955) (xy 424.373978 -6.98383) (xy 424.338257 -6.942607) (xy 424.308766 -6.89672)
			(xy 424.286106 -6.847102) (xy 424.270739 -6.794765) (xy 424.262976 -6.740773) (xy 418.279049 -6.740773)
			(xy 418.271289 -6.794745) (xy 418.255926 -6.84707) (xy 418.233272 -6.896675) (xy 418.20379 -6.942552)
			(xy 418.168079 -6.983766) (xy 418.126867 -7.019479) (xy 418.080991 -7.048964) (xy 418.031386 -7.071619)
			(xy 417.979063 -7.086985) (xy 417.925085 -7.094748) (xy 417.897818 -7.095236) (xy 417.034218 -7.095236)
			(xy 417.006944 -7.094826) (xy 416.952952 -7.087065) (xy 416.900613 -7.071699) (xy 416.850995 -7.049041)
			(xy 416.805106 -7.019552) (xy 416.763881 -6.983832) (xy 416.728159 -6.942609) (xy 416.698667 -6.896721)
			(xy 416.676007 -6.847103) (xy 416.660639 -6.794766) (xy 416.652876 -6.740774) (xy 414.679172 -6.740774)
			(xy 414.67141 -6.794756) (xy 414.656044 -6.847087) (xy 414.633386 -6.896698) (xy 414.603898 -6.94258)
			(xy 414.568181 -6.983798) (xy 414.52696 -7.019513) (xy 414.481077 -7.048998) (xy 414.431464 -7.071652)
			(xy 414.379132 -7.087015) (xy 414.325146 -7.094774) (xy 414.297876 -7.095236) (xy 413.434276 -7.095236)
			(xy 413.407006 -7.0948) (xy 413.353021 -7.087035) (xy 413.300691 -7.071666) (xy 413.25108 -7.049007)
			(xy 413.205199 -7.019519) (xy 413.163982 -6.983801) (xy 413.128267 -6.942581) (xy 413.098781 -6.896698)
			(xy 413.076125 -6.847086) (xy 413.06076 -6.794755) (xy 413.052998 -6.74077) (xy 405.56915 -6.74077)
			(xy 405.561389 -6.794746) (xy 405.546025 -6.847071) (xy 405.523371 -6.896677) (xy 405.493889 -6.942554)
			(xy 405.458177 -6.983769) (xy 405.416964 -7.019481) (xy 405.371087 -7.048966) (xy 405.321482 -7.071621)
			(xy 405.269158 -7.086986) (xy 405.215179 -7.094749) (xy 405.187912 -7.095236) (xy 404.324312 -7.095236)
			(xy 404.297039 -7.094825) (xy 404.243047 -7.087064) (xy 404.190709 -7.071698) (xy 404.141091 -7.049039)
			(xy 404.095203 -7.01955) (xy 404.053978 -6.98383) (xy 404.018257 -6.942607) (xy 403.988766 -6.89672)
			(xy 403.966106 -6.847102) (xy 403.950739 -6.794765) (xy 403.942976 -6.740773) (xy 401.968949 -6.740773)
			(xy 401.961189 -6.794745) (xy 401.945825 -6.84707) (xy 401.923172 -6.896676) (xy 401.89369 -6.942553)
			(xy 401.857978 -6.983767) (xy 401.816766 -7.01948) (xy 401.77089 -7.048964) (xy 401.721285 -7.07162)
			(xy 401.668961 -7.086986) (xy 401.614983 -7.094749) (xy 401.587716 -7.095236) (xy 400.724116 -7.095236)
			(xy 400.696842 -7.094826) (xy 400.64285 -7.087065) (xy 400.590512 -7.071699) (xy 400.540893 -7.049041)
			(xy 400.495005 -7.019551) (xy 400.45378 -6.983832) (xy 400.418058 -6.942608) (xy 400.388567 -6.896721)
			(xy 400.365907 -6.847103) (xy 400.350539 -6.794766) (xy 400.342776 -6.740774) (xy 398.369071 -6.740774)
			(xy 398.36131 -6.794756) (xy 398.345944 -6.847087) (xy 398.323286 -6.896699) (xy 398.293798 -6.94258)
			(xy 398.25808 -6.983798) (xy 398.216859 -7.019513) (xy 398.170976 -7.048998) (xy 398.121363 -7.071653)
			(xy 398.06903 -7.087016) (xy 398.015044 -7.094774) (xy 397.987774 -7.095236) (xy 397.124174 -7.095236)
			(xy 397.096904 -7.0948) (xy 397.04292 -7.087035) (xy 396.99059 -7.071666) (xy 396.940979 -7.049007)
			(xy 396.895099 -7.019518) (xy 396.853881 -6.9838) (xy 396.818166 -6.942581) (xy 396.788681 -6.896698)
			(xy 396.766025 -6.847086) (xy 396.75066 -6.794755) (xy 396.742898 -6.74077) (xy 394.769049 -6.74077)
			(xy 394.761289 -6.794743) (xy 394.745927 -6.847067) (xy 394.723274 -6.896671) (xy 394.693794 -6.942548)
			(xy 394.658084 -6.983762) (xy 394.616873 -7.019474) (xy 394.570999 -7.048959) (xy 394.521397 -7.071616)
			(xy 394.469074 -7.086983) (xy 394.415098 -7.094747) (xy 394.387832 -7.095236) (xy 393.524232 -7.095236)
			(xy 393.496958 -7.094827) (xy 393.442964 -7.087068) (xy 393.390624 -7.071703) (xy 393.341003 -7.049046)
			(xy 393.295112 -7.019557) (xy 393.253885 -6.983837) (xy 393.218162 -6.942613) (xy 393.18867 -6.896725)
			(xy 393.166008 -6.847106) (xy 393.150639 -6.794768) (xy 393.142876 -6.740774) (xy 388.110984 -6.740774)
			(xy 388.110984 -9.780016) (xy 388.110499 -9.850398) (xy 388.102605 -9.99094) (xy 388.086844 -10.130819)
			(xy 388.063264 -10.269594) (xy 388.03194 -10.406828) (xy 387.992971 -10.54209) (xy 387.946478 -10.674954)
			(xy 387.892609 -10.805003) (xy 387.831533 -10.931826) (xy 387.763442 -11.055026) (xy 387.68855 -11.174213)
			(xy 387.607093 -11.289014) (xy 387.519328 -11.399067) (xy 387.425529 -11.504025) (xy 387.325993 -11.60356)
			(xy 387.221033 -11.697356) (xy 387.110979 -11.78512) (xy 386.996176 -11.866575) (xy 386.876988 -11.941465)
			(xy 386.753787 -12.009554) (xy 386.626963 -12.070627) (xy 386.496913 -12.124494) (xy 386.364048 -12.170984)
			(xy 386.228785 -12.209951) (xy 386.091551 -12.241273) (xy 385.952775 -12.26485) (xy 385.812896 -12.280609)
			(xy 385.672354 -12.2885) (xy 385.601972 -12.289028) (xy 260.800088 -12.289028) (xy 260.744319 -12.28955)
			(xy 260.633094 -12.297886) (xy 260.522803 -12.314511) (xy 260.414062 -12.339331) (xy 260.30748 -12.372208)
			(xy 260.203654 -12.412958) (xy 260.103162 -12.461353) (xy 260.006569 -12.517122) (xy 259.914413 -12.579954)
			(xy 259.82721 -12.649497) (xy 259.745448 -12.725362) (xy 259.669584 -12.807125) (xy 259.601847 -12.892065)
			(xy 431.46197 -12.892065) (xy 431.46197 -12.837535) (xy 431.46973 -12.783559) (xy 431.485093 -12.731238)
			(xy 431.507745 -12.681635) (xy 431.537225 -12.635761) (xy 431.572934 -12.594548) (xy 431.614145 -12.558837)
			(xy 431.660017 -12.529355) (xy 431.709619 -12.5067) (xy 431.76194 -12.491335) (xy 431.815915 -12.483572)
			(xy 431.84318 -12.483084) (xy 432.70678 -12.483084) (xy 432.734055 -12.483454) (xy 432.788051 -12.491215)
			(xy 432.840392 -12.506581) (xy 432.890014 -12.529241) (xy 432.935905 -12.558731) (xy 432.977133 -12.594453)
			(xy 433.012857 -12.635678) (xy 433.04235 -12.681569) (xy 433.065012 -12.731189) (xy 433.080381 -12.78353)
			(xy 433.088144 -12.837525) (xy 433.088144 -12.864846) (xy 445.45631 -12.864846) (xy 445.45631 -12.864592)
			(xy 445.456564 -12.850622) (xy 445.45717 -12.823469) (xy 445.46523 -12.769758) (xy 445.48082 -12.717731)
			(xy 445.503625 -12.668439) (xy 445.533186 -12.622876) (xy 445.568905 -12.581962) (xy 445.610062 -12.546522)
			(xy 445.655826 -12.517273) (xy 445.705273 -12.494804) (xy 445.757405 -12.47957) (xy 445.81117 -12.471876)
			(xy 445.838326 -12.4714) (xy 446.701926 -12.4714) (xy 446.72908 -12.471883) (xy 446.782838 -12.479582)
			(xy 446.834964 -12.494821) (xy 446.884404 -12.517293) (xy 446.93016 -12.546543) (xy 446.971311 -12.581982)
			(xy 447.007024 -12.622895) (xy 447.03658 -12.668455) (xy 447.059381 -12.717744) (xy 447.074968 -12.769766)
			(xy 447.083027 -12.823472) (xy 447.083688 -12.850622) (xy 447.083942 -12.864592) (xy 447.083942 -12.864846)
			(xy 447.083472 -12.892133) (xy 447.0757 -12.946152) (xy 447.06032 -12.998515) (xy 447.037645 -13.048157)
			(xy 447.008137 -13.094067) (xy 446.972397 -13.135311) (xy 446.931151 -13.171049) (xy 446.885239 -13.200555)
			(xy 446.835597 -13.223227) (xy 446.783233 -13.238604) (xy 446.729214 -13.246374) (xy 446.701926 -13.246862)
			(xy 446.679426 -13.246581) (xy 446.634732 -13.241355) (xy 446.612772 -13.236448) (xy 446.60693 -13.234924)
			(xy 445.933322 -13.234924) (xy 445.92748 -13.236448) (xy 445.905519 -13.241348) (xy 445.860825 -13.246566)
			(xy 445.838326 -13.246862) (xy 445.811041 -13.246305) (xy 445.757027 -13.238543) (xy 445.704666 -13.223173)
			(xy 445.655026 -13.200508) (xy 445.609117 -13.17101) (xy 445.567873 -13.135278) (xy 445.532133 -13.094041)
			(xy 445.502626 -13.048137) (xy 445.479952 -12.998501) (xy 445.464572 -12.946144) (xy 445.4568 -12.892131)
			(xy 445.45631 -12.864846) (xy 433.088144 -12.864846) (xy 433.088144 -12.892075) (xy 433.080381 -12.94607)
			(xy 433.065012 -12.998411) (xy 433.04235 -13.048031) (xy 433.012857 -13.093921) (xy 432.977133 -13.135147)
			(xy 432.935905 -13.170869) (xy 432.890014 -13.200359) (xy 432.840392 -13.223019) (xy 432.788051 -13.238385)
			(xy 432.734055 -13.246146) (xy 432.70678 -13.246608) (xy 431.84318 -13.246608) (xy 431.815915 -13.246028)
			(xy 431.76194 -13.238265) (xy 431.709619 -13.2229) (xy 431.660017 -13.200245) (xy 431.614145 -13.170763)
			(xy 431.572934 -13.135052) (xy 431.537225 -13.093839) (xy 431.507745 -13.047965) (xy 431.485093 -12.998362)
			(xy 431.46973 -12.946041) (xy 431.46197 -12.892065) (xy 259.601847 -12.892065) (xy 259.600042 -12.894329)
			(xy 259.537211 -12.986486) (xy 259.481443 -13.08308) (xy 259.43305 -13.183572) (xy 259.392301 -13.287399)
			(xy 259.359426 -13.393981) (xy 259.334607 -13.502722) (xy 259.317984 -13.613014) (xy 259.309649 -13.724239)
			(xy 259.309108 -13.780008) (xy 259.309108 -17.628666) (xy 389.660162 -17.628666) (xy 389.660162 -17.574134)
			(xy 389.667923 -17.520157) (xy 389.683286 -17.467834) (xy 389.705939 -17.41823) (xy 389.73542 -17.372354)
			(xy 389.77113 -17.331141) (xy 389.812342 -17.29543) (xy 389.858216 -17.265946) (xy 389.907819 -17.243291)
			(xy 389.960142 -17.227926) (xy 390.014118 -17.220163) (xy 390.041384 -17.219676) (xy 390.904984 -17.219676)
			(xy 390.932258 -17.220062) (xy 390.986252 -17.227824) (xy 391.038592 -17.24319) (xy 391.088212 -17.265849)
			(xy 391.134103 -17.295339) (xy 391.175329 -17.33106) (xy 391.211051 -17.372285) (xy 391.240543 -17.418174)
			(xy 391.263204 -17.467793) (xy 391.278573 -17.520132) (xy 391.286336 -17.574126) (xy 391.286336 -17.628666)
			(xy 395.248162 -17.628666) (xy 395.248162 -17.574134) (xy 395.255923 -17.520157) (xy 395.271286 -17.467834)
			(xy 395.293939 -17.41823) (xy 395.32342 -17.372354) (xy 395.35913 -17.331141) (xy 395.400342 -17.29543)
			(xy 395.446216 -17.265946) (xy 395.495819 -17.243291) (xy 395.548142 -17.227926) (xy 395.602118 -17.220163)
			(xy 395.629384 -17.219676) (xy 396.492984 -17.219676) (xy 396.520258 -17.220062) (xy 396.574252 -17.227824)
			(xy 396.626592 -17.24319) (xy 396.676212 -17.265849) (xy 396.722103 -17.295339) (xy 396.763329 -17.33106)
			(xy 396.799051 -17.372285) (xy 396.828543 -17.418174) (xy 396.851204 -17.467793) (xy 396.866573 -17.520132)
			(xy 396.874336 -17.574126) (xy 396.874336 -17.628666) (xy 400.836162 -17.628666) (xy 400.836162 -17.574134)
			(xy 400.843923 -17.520157) (xy 400.859286 -17.467834) (xy 400.881939 -17.41823) (xy 400.91142 -17.372354)
			(xy 400.94713 -17.331141) (xy 400.988342 -17.29543) (xy 401.034216 -17.265946) (xy 401.083819 -17.243291)
			(xy 401.136142 -17.227926) (xy 401.190118 -17.220163) (xy 401.217384 -17.219676) (xy 402.080984 -17.219676)
			(xy 402.108258 -17.220062) (xy 402.162252 -17.227824) (xy 402.214592 -17.24319) (xy 402.264212 -17.265849)
			(xy 402.310103 -17.295339) (xy 402.351329 -17.33106) (xy 402.387051 -17.372285) (xy 402.416543 -17.418174)
			(xy 402.439204 -17.467793) (xy 402.454573 -17.520132) (xy 402.462336 -17.574126) (xy 402.462336 -17.628666)
			(xy 406.424162 -17.628666) (xy 406.424162 -17.574134) (xy 406.431923 -17.520157) (xy 406.447286 -17.467834)
			(xy 406.469939 -17.41823) (xy 406.49942 -17.372354) (xy 406.53513 -17.331141) (xy 406.576342 -17.29543)
			(xy 406.622216 -17.265946) (xy 406.671819 -17.243291) (xy 406.724142 -17.227926) (xy 406.778118 -17.220163)
			(xy 406.805384 -17.219676) (xy 407.668984 -17.219676) (xy 407.696258 -17.220062) (xy 407.750252 -17.227824)
			(xy 407.802592 -17.24319) (xy 407.852212 -17.265849) (xy 407.898103 -17.295339) (xy 407.939329 -17.33106)
			(xy 407.975051 -17.372285) (xy 408.004543 -17.418174) (xy 408.027204 -17.467793) (xy 408.042573 -17.520132)
			(xy 408.050336 -17.574126) (xy 408.050336 -17.628666) (xy 412.012162 -17.628666) (xy 412.012162 -17.574134)
			(xy 412.019923 -17.520157) (xy 412.035286 -17.467834) (xy 412.057939 -17.41823) (xy 412.08742 -17.372354)
			(xy 412.12313 -17.331141) (xy 412.164342 -17.29543) (xy 412.210216 -17.265946) (xy 412.259819 -17.243291)
			(xy 412.312142 -17.227926) (xy 412.366118 -17.220163) (xy 412.393384 -17.219676) (xy 413.256984 -17.219676)
			(xy 413.284258 -17.220062) (xy 413.338252 -17.227824) (xy 413.390592 -17.24319) (xy 413.440212 -17.265849)
			(xy 413.486103 -17.295339) (xy 413.527329 -17.33106) (xy 413.563051 -17.372285) (xy 413.592543 -17.418174)
			(xy 413.615204 -17.467793) (xy 413.630573 -17.520132) (xy 413.638336 -17.574126) (xy 413.638336 -17.628667)
			(xy 417.905962 -17.628667) (xy 417.905962 -17.574133) (xy 417.913723 -17.520155) (xy 417.929087 -17.467831)
			(xy 417.951741 -17.418226) (xy 417.981224 -17.372349) (xy 418.016936 -17.331136) (xy 418.058149 -17.295424)
			(xy 418.104026 -17.265941) (xy 418.153631 -17.243287) (xy 418.205955 -17.227923) (xy 418.259933 -17.220162)
			(xy 418.2872 -17.219676) (xy 419.1508 -17.219676) (xy 419.178072 -17.220087) (xy 419.232061 -17.227849)
			(xy 419.284396 -17.243216) (xy 419.334011 -17.265874) (xy 419.379896 -17.295363) (xy 419.421118 -17.331082)
			(xy 419.456837 -17.372304) (xy 419.486326 -17.418189) (xy 419.508984 -17.467804) (xy 419.524351 -17.520139)
			(xy 419.532113 -17.574128) (xy 419.532113 -17.628667) (xy 423.493962 -17.628667) (xy 423.493962 -17.574133)
			(xy 423.501723 -17.520155) (xy 423.517087 -17.467831) (xy 423.539741 -17.418226) (xy 423.569224 -17.372349)
			(xy 423.604936 -17.331136) (xy 423.646149 -17.295424) (xy 423.692026 -17.265941) (xy 423.741631 -17.243287)
			(xy 423.793955 -17.227923) (xy 423.847933 -17.220162) (xy 423.8752 -17.219676) (xy 424.7388 -17.219676)
			(xy 424.766072 -17.220087) (xy 424.820061 -17.227849) (xy 424.872396 -17.243216) (xy 424.922011 -17.265874)
			(xy 424.967896 -17.295363) (xy 425.009118 -17.331082) (xy 425.044837 -17.372304) (xy 425.074326 -17.418189)
			(xy 425.096984 -17.467804) (xy 425.112351 -17.520139) (xy 425.120113 -17.574128) (xy 425.120113 -17.62867)
			(xy 429.11594 -17.62867) (xy 429.11594 -17.57413) (xy 429.123702 -17.520145) (xy 429.139068 -17.467815)
			(xy 429.161726 -17.418204) (xy 429.191214 -17.372324) (xy 429.226932 -17.331107) (xy 429.268152 -17.295393)
			(xy 429.314036 -17.265909) (xy 429.363649 -17.243256) (xy 429.415981 -17.227894) (xy 429.469966 -17.220137)
			(xy 429.497236 -17.219676) (xy 430.360836 -17.219676) (xy 430.388106 -17.220089) (xy 430.442091 -17.227856)
			(xy 430.494422 -17.243226) (xy 430.544032 -17.265886) (xy 430.589913 -17.295376) (xy 430.631131 -17.331095)
			(xy 430.666846 -17.372315) (xy 430.696331 -17.418199) (xy 430.718987 -17.467812) (xy 430.734352 -17.520144)
			(xy 430.742114 -17.57413) (xy 430.742114 -17.62867) (xy 430.734352 -17.682656) (xy 430.718987 -17.734988)
			(xy 430.696331 -17.784601) (xy 430.666846 -17.830485) (xy 430.631131 -17.871705) (xy 430.589913 -17.907424)
			(xy 430.544032 -17.936914) (xy 430.494422 -17.959574) (xy 430.442091 -17.974944) (xy 430.388106 -17.982711)
			(xy 430.360836 -17.9832) (xy 429.497236 -17.9832) (xy 429.469966 -17.982663) (xy 429.415981 -17.974906)
			(xy 429.363649 -17.959544) (xy 429.314036 -17.936891) (xy 429.268152 -17.907407) (xy 429.226932 -17.871693)
			(xy 429.191214 -17.830476) (xy 429.161726 -17.784596) (xy 429.139068 -17.734985) (xy 429.123702 -17.682655)
			(xy 429.11594 -17.62867) (xy 425.120113 -17.62867) (xy 425.120113 -17.628672) (xy 425.112351 -17.682661)
			(xy 425.096984 -17.734996) (xy 425.074326 -17.784611) (xy 425.044837 -17.830496) (xy 425.009118 -17.871718)
			(xy 424.967896 -17.907437) (xy 424.922011 -17.936926) (xy 424.872396 -17.959584) (xy 424.820061 -17.974951)
			(xy 424.766072 -17.982713) (xy 424.7388 -17.9832) (xy 423.8752 -17.9832) (xy 423.847933 -17.982638)
			(xy 423.793955 -17.974877) (xy 423.741631 -17.959513) (xy 423.692026 -17.936859) (xy 423.646149 -17.907376)
			(xy 423.604936 -17.871664) (xy 423.569224 -17.830451) (xy 423.539741 -17.784574) (xy 423.517087 -17.734969)
			(xy 423.501723 -17.682645) (xy 423.493962 -17.628667) (xy 419.532113 -17.628667) (xy 419.532113 -17.628672)
			(xy 419.524351 -17.682661) (xy 419.508984 -17.734996) (xy 419.486326 -17.784611) (xy 419.456837 -17.830496)
			(xy 419.421118 -17.871718) (xy 419.379896 -17.907437) (xy 419.334011 -17.936926) (xy 419.284396 -17.959584)
			(xy 419.232061 -17.974951) (xy 419.178072 -17.982713) (xy 419.1508 -17.9832) (xy 418.2872 -17.9832)
			(xy 418.259933 -17.982638) (xy 418.205955 -17.974877) (xy 418.153631 -17.959513) (xy 418.104026 -17.936859)
			(xy 418.058149 -17.907376) (xy 418.016936 -17.871664) (xy 417.981224 -17.830451) (xy 417.951741 -17.784574)
			(xy 417.929087 -17.734969) (xy 417.913723 -17.682645) (xy 417.905962 -17.628667) (xy 413.638336 -17.628667)
			(xy 413.638336 -17.628674) (xy 413.630573 -17.682668) (xy 413.615204 -17.735007) (xy 413.592543 -17.784626)
			(xy 413.563051 -17.830515) (xy 413.527329 -17.87174) (xy 413.486103 -17.907461) (xy 413.440212 -17.936951)
			(xy 413.390592 -17.95961) (xy 413.338252 -17.974976) (xy 413.284258 -17.982738) (xy 413.256984 -17.9832)
			(xy 412.393384 -17.9832) (xy 412.366118 -17.982637) (xy 412.312142 -17.974874) (xy 412.259819 -17.959509)
			(xy 412.210216 -17.936854) (xy 412.164342 -17.90737) (xy 412.12313 -17.871659) (xy 412.08742 -17.830446)
			(xy 412.057939 -17.78457) (xy 412.035286 -17.734966) (xy 412.019923 -17.682643) (xy 412.012162 -17.628666)
			(xy 408.050336 -17.628666) (xy 408.050336 -17.628674) (xy 408.042573 -17.682668) (xy 408.027204 -17.735007)
			(xy 408.004543 -17.784626) (xy 407.975051 -17.830515) (xy 407.939329 -17.87174) (xy 407.898103 -17.907461)
			(xy 407.852212 -17.936951) (xy 407.802592 -17.95961) (xy 407.750252 -17.974976) (xy 407.696258 -17.982738)
			(xy 407.668984 -17.9832) (xy 406.805384 -17.9832) (xy 406.778118 -17.982637) (xy 406.724142 -17.974874)
			(xy 406.671819 -17.959509) (xy 406.622216 -17.936854) (xy 406.576342 -17.90737) (xy 406.53513 -17.871659)
			(xy 406.49942 -17.830446) (xy 406.469939 -17.78457) (xy 406.447286 -17.734966) (xy 406.431923 -17.682643)
			(xy 406.424162 -17.628666) (xy 402.462336 -17.628666) (xy 402.462336 -17.628674) (xy 402.454573 -17.682668)
			(xy 402.439204 -17.735007) (xy 402.416543 -17.784626) (xy 402.387051 -17.830515) (xy 402.351329 -17.87174)
			(xy 402.310103 -17.907461) (xy 402.264212 -17.936951) (xy 402.214592 -17.95961) (xy 402.162252 -17.974976)
			(xy 402.108258 -17.982738) (xy 402.080984 -17.9832) (xy 401.217384 -17.9832) (xy 401.190118 -17.982637)
			(xy 401.136142 -17.974874) (xy 401.083819 -17.959509) (xy 401.034216 -17.936854) (xy 400.988342 -17.90737)
			(xy 400.94713 -17.871659) (xy 400.91142 -17.830446) (xy 400.881939 -17.78457) (xy 400.859286 -17.734966)
			(xy 400.843923 -17.682643) (xy 400.836162 -17.628666) (xy 396.874336 -17.628666) (xy 396.874336 -17.628674)
			(xy 396.866573 -17.682668) (xy 396.851204 -17.735007) (xy 396.828543 -17.784626) (xy 396.799051 -17.830515)
			(xy 396.763329 -17.87174) (xy 396.722103 -17.907461) (xy 396.676212 -17.936951) (xy 396.626592 -17.95961)
			(xy 396.574252 -17.974976) (xy 396.520258 -17.982738) (xy 396.492984 -17.9832) (xy 395.629384 -17.9832)
			(xy 395.602118 -17.982637) (xy 395.548142 -17.974874) (xy 395.495819 -17.959509) (xy 395.446216 -17.936854)
			(xy 395.400342 -17.90737) (xy 395.35913 -17.871659) (xy 395.32342 -17.830446) (xy 395.293939 -17.78457)
			(xy 395.271286 -17.734966) (xy 395.255923 -17.682643) (xy 395.248162 -17.628666) (xy 391.286336 -17.628666)
			(xy 391.286336 -17.628674) (xy 391.278573 -17.682668) (xy 391.263204 -17.735007) (xy 391.240543 -17.784626)
			(xy 391.211051 -17.830515) (xy 391.175329 -17.87174) (xy 391.134103 -17.907461) (xy 391.088212 -17.936951)
			(xy 391.038592 -17.95961) (xy 390.986252 -17.974976) (xy 390.932258 -17.982738) (xy 390.904984 -17.9832)
			(xy 390.041384 -17.9832) (xy 390.014118 -17.982637) (xy 389.960142 -17.974874) (xy 389.907819 -17.959509)
			(xy 389.858216 -17.936854) (xy 389.812342 -17.90737) (xy 389.77113 -17.871659) (xy 389.73542 -17.830446)
			(xy 389.705939 -17.78457) (xy 389.683286 -17.734966) (xy 389.667923 -17.682643) (xy 389.660162 -17.628666)
			(xy 259.309108 -17.628666) (xy 259.309108 -19.152666) (xy 392.454162 -19.152666) (xy 392.454162 -19.098134)
			(xy 392.461923 -19.044157) (xy 392.477286 -18.991834) (xy 392.499939 -18.94223) (xy 392.52942 -18.896354)
			(xy 392.56513 -18.855141) (xy 392.606342 -18.81943) (xy 392.652216 -18.789946) (xy 392.701819 -18.767291)
			(xy 392.754142 -18.751926) (xy 392.808118 -18.744163) (xy 392.835384 -18.743676) (xy 393.698984 -18.743676)
			(xy 393.726258 -18.744062) (xy 393.780252 -18.751824) (xy 393.832592 -18.76719) (xy 393.882212 -18.789849)
			(xy 393.928103 -18.819339) (xy 393.969329 -18.85506) (xy 394.005051 -18.896285) (xy 394.034543 -18.942174)
			(xy 394.057204 -18.991793) (xy 394.072573 -19.044132) (xy 394.080336 -19.098126) (xy 394.080336 -19.152666)
			(xy 398.042162 -19.152666) (xy 398.042162 -19.098134) (xy 398.049923 -19.044157) (xy 398.065286 -18.991834)
			(xy 398.087939 -18.94223) (xy 398.11742 -18.896354) (xy 398.15313 -18.855141) (xy 398.194342 -18.81943)
			(xy 398.240216 -18.789946) (xy 398.289819 -18.767291) (xy 398.342142 -18.751926) (xy 398.396118 -18.744163)
			(xy 398.423384 -18.743676) (xy 399.286984 -18.743676) (xy 399.314258 -18.744062) (xy 399.368252 -18.751824)
			(xy 399.420592 -18.76719) (xy 399.470212 -18.789849) (xy 399.516103 -18.819339) (xy 399.557329 -18.85506)
			(xy 399.593051 -18.896285) (xy 399.622543 -18.942174) (xy 399.645204 -18.991793) (xy 399.660573 -19.044132)
			(xy 399.668336 -19.098126) (xy 399.668336 -19.152666) (xy 403.630162 -19.152666) (xy 403.630162 -19.098134)
			(xy 403.637923 -19.044157) (xy 403.653286 -18.991834) (xy 403.675939 -18.94223) (xy 403.70542 -18.896354)
			(xy 403.74113 -18.855141) (xy 403.782342 -18.81943) (xy 403.828216 -18.789946) (xy 403.877819 -18.767291)
			(xy 403.930142 -18.751926) (xy 403.984118 -18.744163) (xy 404.011384 -18.743676) (xy 404.874984 -18.743676)
			(xy 404.902258 -18.744062) (xy 404.956252 -18.751824) (xy 405.008592 -18.76719) (xy 405.058212 -18.789849)
			(xy 405.104103 -18.819339) (xy 405.145329 -18.85506) (xy 405.181051 -18.896285) (xy 405.210543 -18.942174)
			(xy 405.233204 -18.991793) (xy 405.248573 -19.044132) (xy 405.256336 -19.098126) (xy 405.256336 -19.152666)
			(xy 409.218162 -19.152666) (xy 409.218162 -19.098134) (xy 409.225923 -19.044157) (xy 409.241286 -18.991834)
			(xy 409.263939 -18.94223) (xy 409.29342 -18.896354) (xy 409.32913 -18.855141) (xy 409.370342 -18.81943)
			(xy 409.416216 -18.789946) (xy 409.465819 -18.767291) (xy 409.518142 -18.751926) (xy 409.572118 -18.744163)
			(xy 409.599384 -18.743676) (xy 410.462984 -18.743676) (xy 410.490258 -18.744062) (xy 410.544252 -18.751824)
			(xy 410.596592 -18.76719) (xy 410.646212 -18.789849) (xy 410.692103 -18.819339) (xy 410.733329 -18.85506)
			(xy 410.769051 -18.896285) (xy 410.798543 -18.942174) (xy 410.821204 -18.991793) (xy 410.836573 -19.044132)
			(xy 410.844336 -19.098126) (xy 410.844336 -19.152667) (xy 415.111962 -19.152667) (xy 415.111962 -19.098133)
			(xy 415.119723 -19.044155) (xy 415.135087 -18.991831) (xy 415.157741 -18.942226) (xy 415.187224 -18.896349)
			(xy 415.222936 -18.855136) (xy 415.264149 -18.819424) (xy 415.310026 -18.789941) (xy 415.359631 -18.767287)
			(xy 415.411955 -18.751923) (xy 415.465933 -18.744162) (xy 415.4932 -18.743676) (xy 416.3568 -18.743676)
			(xy 416.384072 -18.744087) (xy 416.438061 -18.751849) (xy 416.490396 -18.767216) (xy 416.540011 -18.789874)
			(xy 416.585896 -18.819363) (xy 416.627118 -18.855082) (xy 416.662837 -18.896304) (xy 416.692326 -18.942189)
			(xy 416.714984 -18.991804) (xy 416.730351 -19.044139) (xy 416.738113 -19.098128) (xy 416.738113 -19.152667)
			(xy 420.699962 -19.152667) (xy 420.699962 -19.098133) (xy 420.707723 -19.044155) (xy 420.723087 -18.991831)
			(xy 420.745741 -18.942226) (xy 420.775224 -18.896349) (xy 420.810936 -18.855136) (xy 420.852149 -18.819424)
			(xy 420.898026 -18.789941) (xy 420.947631 -18.767287) (xy 420.999955 -18.751923) (xy 421.053933 -18.744162)
			(xy 421.0812 -18.743676) (xy 421.9448 -18.743676) (xy 421.972072 -18.744087) (xy 422.026061 -18.751849)
			(xy 422.078396 -18.767216) (xy 422.128011 -18.789874) (xy 422.173896 -18.819363) (xy 422.215118 -18.855082)
			(xy 422.250837 -18.896304) (xy 422.280326 -18.942189) (xy 422.302984 -18.991804) (xy 422.318351 -19.044139)
			(xy 422.326113 -19.098128) (xy 422.326113 -19.15267) (xy 426.32194 -19.15267) (xy 426.32194 -19.09813)
			(xy 426.329702 -19.044145) (xy 426.345068 -18.991815) (xy 426.367726 -18.942204) (xy 426.397214 -18.896324)
			(xy 426.432932 -18.855107) (xy 426.474152 -18.819393) (xy 426.520036 -18.789909) (xy 426.569649 -18.767256)
			(xy 426.621981 -18.751894) (xy 426.675966 -18.744137) (xy 426.703236 -18.743676) (xy 427.566836 -18.743676)
			(xy 427.594106 -18.744089) (xy 427.648091 -18.751856) (xy 427.700422 -18.767226) (xy 427.750032 -18.789886)
			(xy 427.795913 -18.819376) (xy 427.837131 -18.855095) (xy 427.872846 -18.896315) (xy 427.902331 -18.942199)
			(xy 427.924987 -18.991812) (xy 427.940352 -19.044144) (xy 427.948114 -19.09813) (xy 427.948114 -19.15267)
			(xy 431.90994 -19.15267) (xy 431.90994 -19.09813) (xy 431.917702 -19.044145) (xy 431.933068 -18.991815)
			(xy 431.955726 -18.942204) (xy 431.985214 -18.896324) (xy 432.020932 -18.855107) (xy 432.062152 -18.819393)
			(xy 432.108036 -18.789909) (xy 432.157649 -18.767256) (xy 432.209981 -18.751894) (xy 432.263966 -18.744137)
			(xy 432.291236 -18.743676) (xy 433.154836 -18.743676) (xy 433.182106 -18.744089) (xy 433.236091 -18.751856)
			(xy 433.288422 -18.767226) (xy 433.338032 -18.789886) (xy 433.383913 -18.819376) (xy 433.425131 -18.855095)
			(xy 433.460846 -18.896315) (xy 433.490331 -18.942199) (xy 433.512987 -18.991812) (xy 433.528352 -19.044144)
			(xy 433.536114 -19.09813) (xy 433.536114 -19.15267) (xy 433.528352 -19.206656) (xy 433.512987 -19.258988)
			(xy 433.490331 -19.308601) (xy 433.460846 -19.354485) (xy 433.425131 -19.395705) (xy 433.383913 -19.431424)
			(xy 433.338032 -19.460914) (xy 433.288422 -19.483574) (xy 433.236091 -19.498944) (xy 433.182106 -19.506711)
			(xy 433.154836 -19.5072) (xy 432.291236 -19.5072) (xy 432.263966 -19.506663) (xy 432.209981 -19.498906)
			(xy 432.157649 -19.483544) (xy 432.108036 -19.460891) (xy 432.062152 -19.431407) (xy 432.020932 -19.395693)
			(xy 431.985214 -19.354476) (xy 431.955726 -19.308596) (xy 431.933068 -19.258985) (xy 431.917702 -19.206655)
			(xy 431.90994 -19.15267) (xy 427.948114 -19.15267) (xy 427.940352 -19.206656) (xy 427.924987 -19.258988)
			(xy 427.902331 -19.308601) (xy 427.872846 -19.354485) (xy 427.837131 -19.395705) (xy 427.795913 -19.431424)
			(xy 427.750032 -19.460914) (xy 427.700422 -19.483574) (xy 427.648091 -19.498944) (xy 427.594106 -19.506711)
			(xy 427.566836 -19.5072) (xy 426.703236 -19.5072) (xy 426.675966 -19.506663) (xy 426.621981 -19.498906)
			(xy 426.569649 -19.483544) (xy 426.520036 -19.460891) (xy 426.474152 -19.431407) (xy 426.432932 -19.395693)
			(xy 426.397214 -19.354476) (xy 426.367726 -19.308596) (xy 426.345068 -19.258985) (xy 426.329702 -19.206655)
			(xy 426.32194 -19.15267) (xy 422.326113 -19.15267) (xy 422.326113 -19.152672) (xy 422.318351 -19.206661)
			(xy 422.302984 -19.258996) (xy 422.280326 -19.308611) (xy 422.250837 -19.354496) (xy 422.215118 -19.395718)
			(xy 422.173896 -19.431437) (xy 422.128011 -19.460926) (xy 422.078396 -19.483584) (xy 422.026061 -19.498951)
			(xy 421.972072 -19.506713) (xy 421.9448 -19.5072) (xy 421.0812 -19.5072) (xy 421.053933 -19.506638)
			(xy 420.999955 -19.498877) (xy 420.947631 -19.483513) (xy 420.898026 -19.460859) (xy 420.852149 -19.431376)
			(xy 420.810936 -19.395664) (xy 420.775224 -19.354451) (xy 420.745741 -19.308574) (xy 420.723087 -19.258969)
			(xy 420.707723 -19.206645) (xy 420.699962 -19.152667) (xy 416.738113 -19.152667) (xy 416.738113 -19.152672)
			(xy 416.730351 -19.206661) (xy 416.714984 -19.258996) (xy 416.692326 -19.308611) (xy 416.662837 -19.354496)
			(xy 416.627118 -19.395718) (xy 416.585896 -19.431437) (xy 416.540011 -19.460926) (xy 416.490396 -19.483584)
			(xy 416.438061 -19.498951) (xy 416.384072 -19.506713) (xy 416.3568 -19.5072) (xy 415.4932 -19.5072)
			(xy 415.465933 -19.506638) (xy 415.411955 -19.498877) (xy 415.359631 -19.483513) (xy 415.310026 -19.460859)
			(xy 415.264149 -19.431376) (xy 415.222936 -19.395664) (xy 415.187224 -19.354451) (xy 415.157741 -19.308574)
			(xy 415.135087 -19.258969) (xy 415.119723 -19.206645) (xy 415.111962 -19.152667) (xy 410.844336 -19.152667)
			(xy 410.844336 -19.152674) (xy 410.836573 -19.206668) (xy 410.821204 -19.259007) (xy 410.798543 -19.308626)
			(xy 410.769051 -19.354515) (xy 410.733329 -19.39574) (xy 410.692103 -19.431461) (xy 410.646212 -19.460951)
			(xy 410.596592 -19.48361) (xy 410.544252 -19.498976) (xy 410.490258 -19.506738) (xy 410.462984 -19.5072)
			(xy 409.599384 -19.5072) (xy 409.572118 -19.506637) (xy 409.518142 -19.498874) (xy 409.465819 -19.483509)
			(xy 409.416216 -19.460854) (xy 409.370342 -19.43137) (xy 409.32913 -19.395659) (xy 409.29342 -19.354446)
			(xy 409.263939 -19.30857) (xy 409.241286 -19.258966) (xy 409.225923 -19.206643) (xy 409.218162 -19.152666)
			(xy 405.256336 -19.152666) (xy 405.256336 -19.152674) (xy 405.248573 -19.206668) (xy 405.233204 -19.259007)
			(xy 405.210543 -19.308626) (xy 405.181051 -19.354515) (xy 405.145329 -19.39574) (xy 405.104103 -19.431461)
			(xy 405.058212 -19.460951) (xy 405.008592 -19.48361) (xy 404.956252 -19.498976) (xy 404.902258 -19.506738)
			(xy 404.874984 -19.5072) (xy 404.011384 -19.5072) (xy 403.984118 -19.506637) (xy 403.930142 -19.498874)
			(xy 403.877819 -19.483509) (xy 403.828216 -19.460854) (xy 403.782342 -19.43137) (xy 403.74113 -19.395659)
			(xy 403.70542 -19.354446) (xy 403.675939 -19.30857) (xy 403.653286 -19.258966) (xy 403.637923 -19.206643)
			(xy 403.630162 -19.152666) (xy 399.668336 -19.152666) (xy 399.668336 -19.152674) (xy 399.660573 -19.206668)
			(xy 399.645204 -19.259007) (xy 399.622543 -19.308626) (xy 399.593051 -19.354515) (xy 399.557329 -19.39574)
			(xy 399.516103 -19.431461) (xy 399.470212 -19.460951) (xy 399.420592 -19.48361) (xy 399.368252 -19.498976)
			(xy 399.314258 -19.506738) (xy 399.286984 -19.5072) (xy 398.423384 -19.5072) (xy 398.396118 -19.506637)
			(xy 398.342142 -19.498874) (xy 398.289819 -19.483509) (xy 398.240216 -19.460854) (xy 398.194342 -19.43137)
			(xy 398.15313 -19.395659) (xy 398.11742 -19.354446) (xy 398.087939 -19.30857) (xy 398.065286 -19.258966)
			(xy 398.049923 -19.206643) (xy 398.042162 -19.152666) (xy 394.080336 -19.152666) (xy 394.080336 -19.152674)
			(xy 394.072573 -19.206668) (xy 394.057204 -19.259007) (xy 394.034543 -19.308626) (xy 394.005051 -19.354515)
			(xy 393.969329 -19.39574) (xy 393.928103 -19.431461) (xy 393.882212 -19.460951) (xy 393.832592 -19.48361)
			(xy 393.780252 -19.498976) (xy 393.726258 -19.506738) (xy 393.698984 -19.5072) (xy 392.835384 -19.5072)
			(xy 392.808118 -19.506637) (xy 392.754142 -19.498874) (xy 392.701819 -19.483509) (xy 392.652216 -19.460854)
			(xy 392.606342 -19.43137) (xy 392.56513 -19.395659) (xy 392.52942 -19.354446) (xy 392.499939 -19.30857)
			(xy 392.477286 -19.258966) (xy 392.461923 -19.206643) (xy 392.454162 -19.152666) (xy 259.309108 -19.152666)
			(xy 259.309108 -25.468351) (xy 388.406603 -25.468351) (xy 388.406603 -25.413849) (xy 388.41436 -25.359901)
			(xy 388.429716 -25.307607) (xy 388.452359 -25.25803) (xy 388.481827 -25.212181) (xy 388.517521 -25.170992)
			(xy 388.558713 -25.135303) (xy 388.604565 -25.10584) (xy 388.654144 -25.083202) (xy 388.70644 -25.067852)
			(xy 388.760389 -25.0601) (xy 388.78764 -25.05964) (xy 389.65124 -25.05964) (xy 389.678493 -25.060033)
			(xy 389.732443 -25.067795) (xy 389.78474 -25.083155) (xy 389.834318 -25.105802) (xy 389.880169 -25.135273)
			(xy 389.92136 -25.170969) (xy 389.957051 -25.212163) (xy 389.986518 -25.258017) (xy 390.009159 -25.307598)
			(xy 390.024514 -25.359896) (xy 390.03227 -25.413847) (xy 390.03227 -25.468353) (xy 390.024514 -25.522304)
			(xy 390.009159 -25.574602) (xy 389.986518 -25.624183) (xy 389.957051 -25.670037) (xy 389.92136 -25.711231)
			(xy 389.880169 -25.746927) (xy 389.834318 -25.776398) (xy 389.78474 -25.799045) (xy 389.732443 -25.814405)
			(xy 389.678493 -25.822167) (xy 389.65124 -25.822656) (xy 388.78764 -25.822656) (xy 388.760389 -25.8221)
			(xy 388.70644 -25.814348) (xy 388.654144 -25.798998) (xy 388.604565 -25.77636) (xy 388.558713 -25.746897)
			(xy 388.517521 -25.711208) (xy 388.481827 -25.670019) (xy 388.452359 -25.62417) (xy 388.429716 -25.574593)
			(xy 388.41436 -25.522299) (xy 388.406603 -25.468351) (xy 259.309108 -25.468351) (xy 259.309108 -28.450032)
			(xy 354.840804 -28.450032) (xy 354.844787 -28.322014) (xy 354.856722 -28.194492) (xy 354.876561 -28.067958)
			(xy 354.904228 -27.942902) (xy 354.939617 -27.819809) (xy 354.98259 -27.699153) (xy 355.032981 -27.581403)
			(xy 355.090595 -27.467013) (xy 355.155209 -27.356426) (xy 355.226573 -27.25007) (xy 355.304411 -27.148357)
			(xy 355.388422 -27.051679) (xy 355.478281 -26.960412) (xy 355.57364 -26.874907) (xy 355.674131 -26.795497)
			(xy 355.779364 -26.722487) (xy 355.888933 -26.656161) (xy 356.002413 -26.596775) (xy 356.119365 -26.544559)
			(xy 356.239338 -26.499715) (xy 356.361866 -26.462417) (xy 356.486477 -26.432808) (xy 356.612686 -26.411003)
			(xy 356.740008 -26.397087) (xy 356.867948 -26.391113) (xy 356.996012 -26.393105) (xy 357.123705 -26.403055)
			(xy 357.250532 -26.420924) (xy 357.376003 -26.446643) (xy 357.499632 -26.480113) (xy 357.620941 -26.521204)
			(xy 357.739461 -26.569758) (xy 357.854733 -26.625586) (xy 357.966311 -26.688472) (xy 358.073764 -26.758174)
			(xy 358.176676 -26.834421) (xy 358.274648 -26.916918) (xy 358.367302 -27.005347) (xy 358.454279 -27.099365)
			(xy 358.535243 -27.198608) (xy 358.60988 -27.302693) (xy 358.677902 -27.411217) (xy 358.739046 -27.52376)
			(xy 358.793074 -27.639886) (xy 358.839779 -27.759147) (xy 358.878979 -27.88108) (xy 358.910522 -28.005215)
			(xy 358.934287 -28.131071) (xy 358.950181 -28.25816) (xy 358.958144 -28.385992) (xy 358.958642 -28.450032)
			(xy 358.958144 -28.514072) (xy 358.950181 -28.641904) (xy 358.934287 -28.768993) (xy 358.910522 -28.894849)
			(xy 358.878979 -29.018984) (xy 358.839779 -29.140917) (xy 358.793074 -29.260178) (xy 358.739046 -29.376304)
			(xy 358.677902 -29.488847) (xy 358.60988 -29.597371) (xy 358.535243 -29.701456) (xy 358.454279 -29.800699)
			(xy 358.367302 -29.894717) (xy 358.274648 -29.983146) (xy 358.176676 -30.065643) (xy 358.073764 -30.14189)
			(xy 357.966311 -30.211592) (xy 357.854733 -30.274478) (xy 357.739461 -30.330306) (xy 357.620941 -30.37886)
			(xy 357.499632 -30.419951) (xy 357.376003 -30.453421) (xy 357.250532 -30.47914) (xy 357.123705 -30.497009)
			(xy 356.996012 -30.506959) (xy 356.867948 -30.508951) (xy 356.740008 -30.502977) (xy 356.612686 -30.489061)
			(xy 356.486477 -30.467256) (xy 356.361866 -30.437647) (xy 356.239338 -30.400349) (xy 356.119365 -30.355505)
			(xy 356.002413 -30.303289) (xy 355.888933 -30.243903) (xy 355.779364 -30.177577) (xy 355.674131 -30.104567)
			(xy 355.57364 -30.025157) (xy 355.478281 -29.939652) (xy 355.388422 -29.848385) (xy 355.304411 -29.751707)
			(xy 355.226573 -29.649994) (xy 355.155209 -29.543638) (xy 355.090595 -29.433051) (xy 355.032981 -29.318661)
			(xy 354.98259 -29.200911) (xy 354.939617 -29.080255) (xy 354.904228 -28.957162) (xy 354.876561 -28.832106)
			(xy 354.856722 -28.705572) (xy 354.844787 -28.57805) (xy 354.840804 -28.450032) (xy 259.309108 -28.450032)
			(xy 259.309108 -33.275016) (xy 259.308614 -33.345398) (xy 259.30072 -33.48594) (xy 259.284959 -33.625819)
			(xy 259.261379 -33.764594) (xy 259.230448 -33.90011) (xy 462.69148 -33.90011) (xy 462.69148 -32.29991)
			(xy 462.691988 -32.23523) (xy 462.700111 -32.106124) (xy 462.716324 -31.977784) (xy 462.740564 -31.850714)
			(xy 462.772734 -31.725418) (xy 462.812709 -31.602388) (xy 462.86033 -31.482112) (xy 462.915409 -31.365063)
			(xy 462.977729 -31.251703) (xy 463.047044 -31.14248) (xy 463.12308 -31.037825) (xy 463.205538 -30.938151)
			(xy 463.294091 -30.843851) (xy 463.388391 -30.755298) (xy 463.488065 -30.67284) (xy 463.59272 -30.596804)
			(xy 463.701943 -30.527489) (xy 463.815303 -30.465169) (xy 463.932352 -30.41009) (xy 464.052628 -30.362469)
			(xy 464.175658 -30.322494) (xy 464.300954 -30.290324) (xy 464.428024 -30.266084) (xy 464.556364 -30.249871)
			(xy 464.68547 -30.241748) (xy 464.81483 -30.241748) (xy 464.943936 -30.249871) (xy 465.072276 -30.266084)
			(xy 465.199346 -30.290324) (xy 465.324642 -30.322494) (xy 465.447672 -30.362469) (xy 465.567948 -30.41009)
			(xy 465.684997 -30.465169) (xy 465.798357 -30.527489) (xy 465.90758 -30.596804) (xy 466.012235 -30.67284)
			(xy 466.111909 -30.755298) (xy 466.206209 -30.843851) (xy 466.294762 -30.938151) (xy 466.37722 -31.037825)
			(xy 466.453256 -31.14248) (xy 466.522571 -31.251703) (xy 466.584891 -31.365063) (xy 466.63997 -31.482112)
			(xy 466.687591 -31.602388) (xy 466.727566 -31.725418) (xy 466.759736 -31.850714) (xy 466.783976 -31.977784)
			(xy 466.800189 -32.106124) (xy 466.808312 -32.23523) (xy 466.80882 -32.29991) (xy 466.80882 -33.90011)
			(xy 466.808312 -33.96479) (xy 466.800189 -34.093896) (xy 466.783976 -34.222236) (xy 466.759736 -34.349306)
			(xy 466.727566 -34.474602) (xy 466.687591 -34.597632) (xy 466.63997 -34.717908) (xy 466.584891 -34.834957)
			(xy 466.522571 -34.948317) (xy 466.453256 -35.05754) (xy 466.37722 -35.162195) (xy 466.294762 -35.261869)
			(xy 466.206209 -35.356169) (xy 466.111909 -35.444722) (xy 466.012235 -35.52718) (xy 465.90758 -35.603216)
			(xy 465.798357 -35.672531) (xy 465.684997 -35.734851) (xy 465.567948 -35.78993) (xy 465.447672 -35.837551)
			(xy 465.324642 -35.877526) (xy 465.199346 -35.909696) (xy 465.072276 -35.933936) (xy 464.943936 -35.950149)
			(xy 464.81483 -35.958272) (xy 464.68547 -35.958272) (xy 464.556364 -35.950149) (xy 464.428024 -35.933936)
			(xy 464.300954 -35.909696) (xy 464.175658 -35.877526) (xy 464.052628 -35.837551) (xy 463.932352 -35.78993)
			(xy 463.815303 -35.734851) (xy 463.701943 -35.672531) (xy 463.59272 -35.603216) (xy 463.488065 -35.52718)
			(xy 463.388391 -35.444722) (xy 463.294091 -35.356169) (xy 463.205538 -35.261869) (xy 463.12308 -35.162195)
			(xy 463.047044 -35.05754) (xy 462.977729 -34.948317) (xy 462.915409 -34.834957) (xy 462.86033 -34.717908)
			(xy 462.812709 -34.597632) (xy 462.772734 -34.474602) (xy 462.740564 -34.349306) (xy 462.716324 -34.222236)
			(xy 462.700111 -34.093896) (xy 462.691988 -33.96479) (xy 462.69148 -33.90011) (xy 259.230448 -33.90011)
			(xy 259.230056 -33.901828) (xy 259.191086 -34.03709) (xy 259.144594 -34.169955) (xy 259.090726 -34.300003)
			(xy 259.02965 -34.426827) (xy 258.961559 -34.550026) (xy 258.886668 -34.669214) (xy 258.805211 -34.784015)
			(xy 258.717446 -34.894068) (xy 258.623648 -34.999027) (xy 258.524113 -35.098562) (xy 258.419153 -35.192359)
			(xy 258.324611 -35.267753) (xy 356.989346 -35.267753) (xy 356.989346 -35.213247) (xy 356.997102 -35.159297)
			(xy 357.012458 -35.106999) (xy 357.035099 -35.057419) (xy 357.064566 -35.011566) (xy 357.100259 -34.970373)
			(xy 357.14145 -34.934678) (xy 357.187302 -34.905209) (xy 357.236881 -34.882565) (xy 357.289177 -34.867207)
			(xy 357.343127 -34.859447) (xy 357.37038 -34.85896) (xy 358.23398 -34.85896) (xy 358.261232 -34.859486)
			(xy 358.31518 -34.86724) (xy 358.367476 -34.882593) (xy 358.417054 -34.905232) (xy 358.462906 -34.934697)
			(xy 358.504098 -34.970388) (xy 358.539791 -35.011578) (xy 358.569258 -35.057428) (xy 358.5919 -35.107005)
			(xy 358.607256 -35.1593) (xy 358.615013 -35.213249) (xy 358.615013 -35.267751) (xy 358.607256 -35.3217)
			(xy 358.5919 -35.373995) (xy 358.569258 -35.423572) (xy 358.539791 -35.469422) (xy 358.504098 -35.510612)
			(xy 358.462906 -35.546303) (xy 358.417054 -35.575768) (xy 358.367476 -35.598407) (xy 358.31518 -35.61376)
			(xy 358.261232 -35.621514) (xy 358.23398 -35.621976) (xy 357.37038 -35.621976) (xy 357.343127 -35.621553)
			(xy 357.289177 -35.613793) (xy 357.236881 -35.598435) (xy 357.187302 -35.575791) (xy 357.14145 -35.546322)
			(xy 357.100259 -35.510627) (xy 357.064566 -35.469434) (xy 357.035099 -35.423581) (xy 357.012458 -35.374001)
			(xy 356.997102 -35.321703) (xy 356.989346 -35.267753) (xy 258.324611 -35.267753) (xy 258.309099 -35.280123)
			(xy 258.194297 -35.361579) (xy 258.075109 -35.436469) (xy 257.951909 -35.504559) (xy 257.825085 -35.565634)
			(xy 257.695036 -35.619502) (xy 257.562171 -35.665993) (xy 257.426909 -35.704961) (xy 257.289674 -35.736283)
			(xy 257.150899 -35.759862) (xy 257.01102 -35.775622) (xy 256.870478 -35.783514) (xy 256.800096 -35.784028)
			(xy 225.300032 -35.784028) (xy 225.229649 -35.783544) (xy 225.089104 -35.775653) (xy 224.949222 -35.759894)
			(xy 224.810444 -35.736316) (xy 224.673207 -35.704995) (xy 224.537941 -35.666027) (xy 224.405074 -35.619536)
			(xy 224.275022 -35.565669) (xy 224.148195 -35.504594) (xy 224.024992 -35.436504) (xy 223.905801 -35.361613)
			(xy 223.790997 -35.280156) (xy 223.68094 -35.192391) (xy 223.575978 -35.098593) (xy 223.47644 -34.999057)
			(xy 223.38264 -34.894096) (xy 223.294872 -34.784042) (xy 223.213414 -34.669239) (xy 223.138521 -34.550049)
			(xy 223.070428 -34.426848) (xy 223.009351 -34.300022) (xy 222.955481 -34.169971) (xy 222.908988 -34.037104)
			(xy 222.870017 -33.90184) (xy 222.838693 -33.764603) (xy 222.815113 -33.625825) (xy 222.799351 -33.485944)
			(xy 222.791457 -33.345399) (xy 222.79102 -33.275016) (xy 222.79102 -13.780008) (xy 222.790499 -13.724238)
			(xy 222.782164 -13.613011) (xy 222.765541 -13.502717) (xy 222.740722 -13.393974) (xy 222.707846 -13.287389)
			(xy 222.667097 -13.183559) (xy 222.618703 -13.083065) (xy 222.562935 -12.986469) (xy 222.500103 -12.894309)
			(xy 222.430561 -12.807103) (xy 222.354696 -12.725338) (xy 222.272933 -12.64947) (xy 222.185729 -12.579925)
			(xy 222.093572 -12.517091) (xy 221.996977 -12.461319) (xy 221.896485 -12.412922) (xy 221.792656 -12.37217)
			(xy 221.686073 -12.339291) (xy 221.57733 -12.314468) (xy 221.467037 -12.297841) (xy 221.35581 -12.289503)
			(xy 221.30004 -12.289028) (xy 196.701918 -12.289028) (xy 196.631535 -12.288544) (xy 196.49099 -12.280652)
			(xy 196.35111 -12.264892) (xy 196.212332 -12.241314) (xy 196.075095 -12.209992) (xy 195.939831 -12.171024)
			(xy 195.806964 -12.124532) (xy 195.676913 -12.070665) (xy 195.550086 -12.009589) (xy 195.426884 -11.941499)
			(xy 195.307694 -11.866608) (xy 195.19289 -11.785152) (xy 195.082834 -11.697386) (xy 194.977873 -11.603588)
			(xy 194.878335 -11.504052) (xy 194.784536 -11.399092) (xy 194.696769 -11.289037) (xy 194.615311 -11.174234)
			(xy 194.540418 -11.055045) (xy 194.472326 -10.931844) (xy 194.411249 -10.805018) (xy 194.35738 -10.674968)
			(xy 194.310887 -10.542102) (xy 194.271917 -10.406837) (xy 194.240593 -10.269601) (xy 194.217013 -10.130824)
			(xy 194.201251 -9.990943) (xy 194.193357 -9.850399) (xy 194.192906 -9.780016) (xy 194.192906 -6.279896)
			(xy 194.19238 -6.247749) (xy 194.183988 -6.184006) (xy 194.167348 -6.121904) (xy 194.142744 -6.062504)
			(xy 194.110598 -6.006824) (xy 194.07146 -5.955816) (xy 194.025999 -5.910353) (xy 193.974992 -5.871213)
			(xy 193.919314 -5.839064) (xy 193.859915 -5.814458) (xy 193.797813 -5.797816) (xy 193.734071 -5.789421)
			(xy 193.701924 -5.788914) (xy 127.102108 -5.788914) (xy 127.06996 -5.789416) (xy 127.006214 -5.797808)
			(xy 126.944108 -5.814448) (xy 126.884706 -5.839052) (xy 126.829023 -5.8712) (xy 126.778013 -5.91034)
			(xy 126.732548 -5.955804) (xy 126.693406 -6.006813) (xy 126.661257 -6.062495) (xy 126.636652 -6.121897)
			(xy 126.62001 -6.184002) (xy 126.611617 -6.247748) (xy 126.611126 -6.279896) (xy 126.611126 -9.780016)
			(xy 126.610632 -9.850398) (xy 126.602738 -9.990941) (xy 126.586977 -10.13082) (xy 126.563397 -10.269595)
			(xy 126.532074 -10.40683) (xy 126.519617 -10.450068) (xy 127.350273 -10.450068) (xy 127.354278 -10.36216)
			(xy 127.366261 -10.27498) (xy 127.386121 -10.189251) (xy 127.413696 -10.105683) (xy 127.448755 -10.024969)
			(xy 127.491008 -9.947777) (xy 127.540106 -9.874748) (xy 127.595642 -9.806486) (xy 127.657154 -9.743556)
			(xy 127.724135 -9.686482) (xy 127.796028 -9.635734) (xy 127.872237 -9.591734) (xy 127.952132 -9.554847)
			(xy 128.035051 -9.525378) (xy 128.120306 -9.503571) (xy 128.20719 -9.489607) (xy 128.294984 -9.483601)
			(xy 128.382961 -9.485605) (xy 128.470391 -9.4956) (xy 128.55655 -9.513504) (xy 128.640724 -9.539168)
			(xy 128.722215 -9.572381) (xy 128.800349 -9.612867) (xy 128.874477 -9.660289) (xy 128.943985 -9.714256)
			(xy 129.008299 -9.774321) (xy 129.066883 -9.839985) (xy 129.119254 -9.910704) (xy 129.164977 -9.985892)
			(xy 129.203674 -10.064927) (xy 129.235023 -10.147153) (xy 129.258765 -10.231889) (xy 129.265884 -10.270548)
			(xy 131.63909 -10.270548) (xy 131.63909 -10.216052) (xy 131.646845 -10.16211) (xy 131.662198 -10.10982)
			(xy 131.684835 -10.060247) (xy 131.714296 -10.014401) (xy 131.749982 -9.973213) (xy 131.791165 -9.937522)
			(xy 131.837009 -9.908056) (xy 131.886579 -9.885413) (xy 131.938866 -9.870055) (xy 131.992808 -9.862293)
			(xy 132.020056 -9.861804) (xy 132.883656 -9.861804) (xy 132.910912 -9.86224) (xy 132.964869 -9.869992)
			(xy 133.017174 -9.885345) (xy 133.066761 -9.907985) (xy 133.112622 -9.937453) (xy 133.153821 -9.973148)
			(xy 133.18952 -10.014343) (xy 133.218993 -10.0602) (xy 133.24164 -10.109785) (xy 133.256999 -10.162088)
			(xy 133.264757 -10.216044) (xy 133.264757 -10.270556) (xy 133.256999 -10.324512) (xy 133.24164 -10.376815)
			(xy 133.218993 -10.4264) (xy 133.18952 -10.472257) (xy 133.153821 -10.513452) (xy 133.112622 -10.549147)
			(xy 133.066761 -10.578615) (xy 133.017174 -10.601255) (xy 132.964869 -10.616608) (xy 132.910912 -10.62436)
			(xy 132.883656 -10.62482) (xy 132.020056 -10.62482) (xy 131.992808 -10.624307) (xy 131.938866 -10.616545)
			(xy 131.886579 -10.601187) (xy 131.837009 -10.578544) (xy 131.791165 -10.549078) (xy 131.749982 -10.513387)
			(xy 131.714296 -10.472199) (xy 131.684835 -10.426353) (xy 131.662198 -10.37678) (xy 131.646845 -10.32449)
			(xy 131.63909 -10.270548) (xy 129.265884 -10.270548) (xy 129.274703 -10.318433) (xy 129.282705 -10.406068)
			(xy 129.283206 -10.450068) (xy 129.282705 -10.494068) (xy 129.274703 -10.581703) (xy 129.258765 -10.668247)
			(xy 129.235023 -10.752983) (xy 129.203674 -10.835209) (xy 129.164977 -10.914244) (xy 129.119254 -10.989432)
			(xy 129.087321 -11.032553) (xy 168.158867 -11.032553) (xy 168.158867 -10.978047) (xy 168.166625 -10.924096)
			(xy 168.181981 -10.871798) (xy 168.204625 -10.822218) (xy 168.234094 -10.776365) (xy 168.269789 -10.735173)
			(xy 168.310983 -10.699481) (xy 168.356837 -10.670014) (xy 168.406419 -10.647374) (xy 168.458717 -10.63202)
			(xy 168.512669 -10.624266) (xy 168.539922 -10.623804) (xy 169.403522 -10.623804) (xy 169.430773 -10.624267)
			(xy 169.48472 -10.632027) (xy 169.537014 -10.647384) (xy 169.58659 -10.670027) (xy 169.632439 -10.699495)
			(xy 169.673628 -10.735188) (xy 169.709318 -10.776379) (xy 169.738783 -10.822229) (xy 169.761424 -10.871807)
			(xy 169.776778 -10.924101) (xy 169.784534 -10.978049) (xy 169.784534 -11.032551) (xy 169.776778 -11.086499)
			(xy 169.761424 -11.138793) (xy 169.738783 -11.188371) (xy 169.709318 -11.234221) (xy 169.673628 -11.275412)
			(xy 169.632439 -11.311105) (xy 169.58659 -11.340573) (xy 169.537014 -11.363216) (xy 169.48472 -11.378573)
			(xy 169.430773 -11.386333) (xy 169.403522 -11.38682) (xy 168.539922 -11.38682) (xy 168.512669 -11.386334)
			(xy 168.458717 -11.37858) (xy 168.406419 -11.363226) (xy 168.356837 -11.340586) (xy 168.310983 -11.311119)
			(xy 168.269789 -11.275427) (xy 168.234094 -11.234235) (xy 168.204625 -11.188382) (xy 168.181981 -11.138802)
			(xy 168.166625 -11.086504) (xy 168.158867 -11.032553) (xy 129.087321 -11.032553) (xy 129.066883 -11.060151)
			(xy 129.008299 -11.125815) (xy 128.943985 -11.18588) (xy 128.874477 -11.239847) (xy 128.800349 -11.287269)
			(xy 128.722215 -11.327755) (xy 128.640724 -11.360968) (xy 128.55655 -11.386632) (xy 128.470391 -11.404536)
			(xy 128.382961 -11.414531) (xy 128.294984 -11.416535) (xy 128.20719 -11.410529) (xy 128.120306 -11.396565)
			(xy 128.035051 -11.374758) (xy 127.952132 -11.345289) (xy 127.872237 -11.308402) (xy 127.796028 -11.264402)
			(xy 127.724135 -11.213654) (xy 127.657154 -11.15658) (xy 127.595642 -11.09365) (xy 127.540106 -11.025388)
			(xy 127.491008 -10.952359) (xy 127.448755 -10.875167) (xy 127.413696 -10.794453) (xy 127.386121 -10.710885)
			(xy 127.366261 -10.625156) (xy 127.354278 -10.537976) (xy 127.350273 -10.450068) (xy 126.519617 -10.450068)
			(xy 126.493105 -10.542092) (xy 126.446613 -10.674957) (xy 126.392744 -10.805006) (xy 126.331668 -10.93183)
			(xy 126.263578 -11.05503) (xy 126.188687 -11.174218) (xy 126.10723 -11.28902) (xy 126.019465 -11.399074)
			(xy 125.973895 -11.450066) (xy 191.515245 -11.450066) (xy 191.51925 -11.362158) (xy 191.531233 -11.274978)
			(xy 191.551093 -11.189249) (xy 191.578668 -11.105681) (xy 191.613727 -11.024967) (xy 191.65598 -10.947775)
			(xy 191.705078 -10.874746) (xy 191.760614 -10.806484) (xy 191.822126 -10.743554) (xy 191.889107 -10.68648)
			(xy 191.961 -10.635732) (xy 192.037209 -10.591732) (xy 192.117104 -10.554845) (xy 192.200023 -10.525376)
			(xy 192.285278 -10.503569) (xy 192.372162 -10.489605) (xy 192.459956 -10.483599) (xy 192.547933 -10.485603)
			(xy 192.635363 -10.495598) (xy 192.721522 -10.513502) (xy 192.805696 -10.539166) (xy 192.887187 -10.572379)
			(xy 192.965321 -10.612865) (xy 193.039449 -10.660287) (xy 193.108957 -10.714254) (xy 193.173271 -10.774319)
			(xy 193.231855 -10.839983) (xy 193.284226 -10.910702) (xy 193.329949 -10.98589) (xy 193.368646 -11.064925)
			(xy 193.399995 -11.147151) (xy 193.423737 -11.231887) (xy 193.439675 -11.318431) (xy 193.447677 -11.406066)
			(xy 193.448178 -11.450066) (xy 193.447677 -11.494066) (xy 193.439675 -11.581701) (xy 193.423737 -11.668245)
			(xy 193.399995 -11.752981) (xy 193.368646 -11.835207) (xy 193.329949 -11.914242) (xy 193.284226 -11.98943)
			(xy 193.231855 -12.060149) (xy 193.173271 -12.125813) (xy 193.108957 -12.185878) (xy 193.039449 -12.239845)
			(xy 192.965321 -12.287267) (xy 192.887187 -12.327753) (xy 192.805696 -12.360966) (xy 192.721522 -12.38663)
			(xy 192.635363 -12.404534) (xy 192.547933 -12.414529) (xy 192.459956 -12.416533) (xy 192.372162 -12.410527)
			(xy 192.285278 -12.396563) (xy 192.200023 -12.374756) (xy 192.117104 -12.345287) (xy 192.037209 -12.3084)
			(xy 191.961 -12.2644) (xy 191.889107 -12.213652) (xy 191.822126 -12.156578) (xy 191.760614 -12.093648)
			(xy 191.705078 -12.025386) (xy 191.65598 -11.952357) (xy 191.613727 -11.875165) (xy 191.578668 -11.794451)
			(xy 191.551093 -11.710883) (xy 191.531233 -11.625154) (xy 191.51925 -11.537974) (xy 191.515245 -11.450066)
			(xy 125.973895 -11.450066) (xy 125.925667 -11.504033) (xy 125.826132 -11.603569) (xy 125.721172 -11.697366)
			(xy 125.611118 -11.785131) (xy 125.496317 -11.866588) (xy 125.377128 -11.941479) (xy 125.253928 -12.009569)
			(xy 125.206611 -12.032356) (xy 166.354411 -12.032356) (xy 166.354411 -11.977844) (xy 166.362169 -11.923886)
			(xy 166.377527 -11.871582) (xy 166.400173 -11.821995) (xy 166.429645 -11.776137) (xy 166.465343 -11.734939)
			(xy 166.506541 -11.699241) (xy 166.552401 -11.66977) (xy 166.601987 -11.647125) (xy 166.654292 -11.631768)
			(xy 166.70825 -11.624011) (xy 166.735506 -11.623548) (xy 167.599106 -11.623548) (xy 167.626354 -11.624123)
			(xy 167.680295 -11.631879) (xy 167.732583 -11.647233) (xy 167.782153 -11.669872) (xy 167.827998 -11.699335)
			(xy 167.869182 -11.735022) (xy 167.904869 -11.776207) (xy 167.934331 -11.822052) (xy 167.956969 -11.871623)
			(xy 167.972322 -11.923911) (xy 167.980078 -11.977852) (xy 167.980078 -12.032348) (xy 167.980077 -12.032358)
			(xy 169.954311 -12.032358) (xy 169.954311 -11.977842) (xy 169.96207 -11.92388) (xy 169.97743 -11.871573)
			(xy 170.000079 -11.821984) (xy 170.029555 -11.776123) (xy 170.065258 -11.734924) (xy 170.106461 -11.699226)
			(xy 170.152326 -11.669756) (xy 170.201918 -11.647114) (xy 170.254227 -11.63176) (xy 170.30819 -11.624008)
			(xy 170.335448 -11.623548) (xy 171.199048 -11.623548) (xy 171.226294 -11.624125) (xy 171.28023 -11.631887)
			(xy 171.332513 -11.647244) (xy 171.382078 -11.669885) (xy 171.427917 -11.699349) (xy 171.469097 -11.735037)
			(xy 171.504779 -11.776221) (xy 171.534238 -11.822064) (xy 171.556873 -11.871632) (xy 171.572224 -11.923917)
			(xy 171.579978 -11.977854) (xy 171.579978 -12.032346) (xy 171.572224 -12.086283) (xy 171.556873 -12.138568)
			(xy 171.534238 -12.188136) (xy 171.504779 -12.233979) (xy 171.469097 -12.275163) (xy 171.427917 -12.310851)
			(xy 171.382078 -12.340315) (xy 171.332513 -12.362956) (xy 171.28023 -12.378313) (xy 171.226294 -12.386075)
			(xy 171.199048 -12.386564) (xy 170.335448 -12.386564) (xy 170.30819 -12.386192) (xy 170.254227 -12.37844)
			(xy 170.201918 -12.363086) (xy 170.152326 -12.340444) (xy 170.106461 -12.310974) (xy 170.065258 -12.275276)
			(xy 170.029555 -12.234077) (xy 170.000079 -12.188216) (xy 169.97743 -12.138627) (xy 169.96207 -12.08632)
			(xy 169.954311 -12.032358) (xy 167.980077 -12.032358) (xy 167.972322 -12.086289) (xy 167.956969 -12.138577)
			(xy 167.934331 -12.188148) (xy 167.904869 -12.233993) (xy 167.869182 -12.275178) (xy 167.827998 -12.310865)
			(xy 167.782153 -12.340328) (xy 167.732583 -12.362967) (xy 167.680295 -12.378321) (xy 167.626354 -12.386077)
			(xy 167.599106 -12.386564) (xy 166.735506 -12.386564) (xy 166.70825 -12.386189) (xy 166.654292 -12.378432)
			(xy 166.601987 -12.363075) (xy 166.552401 -12.34043) (xy 166.506541 -12.310959) (xy 166.465343 -12.275261)
			(xy 166.429645 -12.234063) (xy 166.400173 -12.188205) (xy 166.377527 -12.138618) (xy 166.362169 -12.086314)
			(xy 166.354411 -12.032356) (xy 125.206611 -12.032356) (xy 125.127104 -12.070645) (xy 124.997055 -12.124513)
			(xy 124.86419 -12.171005) (xy 124.728928 -12.209974) (xy 124.591693 -12.241298) (xy 124.452918 -12.264877)
			(xy 124.313039 -12.280639) (xy 124.172496 -12.288532) (xy 124.102114 -12.289028) (xy 83.70189 -12.289028)
			(xy 83.631508 -12.288534) (xy 83.490965 -12.280641) (xy 83.351086 -12.26488) (xy 83.21231 -12.2413)
			(xy 83.075075 -12.209977) (xy 82.939812 -12.171008) (xy 82.806947 -12.124516) (xy 82.676898 -12.070648)
			(xy 82.550073 -12.009572) (xy 82.426873 -11.941482) (xy 82.307684 -11.866591) (xy 82.192882 -11.785134)
			(xy 82.082828 -11.697369) (xy 81.977868 -11.603571) (xy 81.878333 -11.504036) (xy 81.784535 -11.399076)
			(xy 81.696769 -11.289022) (xy 81.615313 -11.174221) (xy 81.540421 -11.055032) (xy 81.47233 -10.931832)
			(xy 81.411254 -10.805008) (xy 81.357386 -10.674959) (xy 81.310894 -10.542094) (xy 81.271924 -10.406831)
			(xy 81.240601 -10.269596) (xy 81.217021 -10.13082) (xy 81.20126 -9.990941) (xy 81.193366 -9.850398)
			(xy 81.192878 -9.780016) (xy 81.192878 -0.999998) (xy 81.192375 -0.96785) (xy 81.183982 -0.904106)
			(xy 81.167341 -0.842001) (xy 81.142736 -0.782601) (xy 81.110589 -0.72692) (xy 81.071448 -0.675911)
			(xy 81.025984 -0.630448) (xy 80.974975 -0.591308) (xy 80.919294 -0.559161) (xy 80.859893 -0.534557)
			(xy 80.797789 -0.517916) (xy 80.734044 -0.509525) (xy 80.701896 -0.509016) (xy 14.10208 -0.509016)
			(xy 14.069935 -0.509543) (xy 14.006194 -0.517937) (xy 13.944095 -0.534579) (xy 13.884698 -0.559184)
			(xy 13.829022 -0.59133) (xy 13.778017 -0.630469) (xy 13.732558 -0.675931) (xy 13.69342 -0.726937)
			(xy 13.661276 -0.782614) (xy 13.636673 -0.842012) (xy 13.620034 -0.904112) (xy 13.611642 -0.967853)
			(xy 13.611098 -0.999998) (xy 13.611098 -5.184498) (xy 14.350702 -5.184498) (xy 14.35331 -5.097781)
			(xy 14.363685 -5.011647) (xy 14.381743 -4.926791) (xy 14.40734 -4.843896) (xy 14.440268 -4.763631)
			(xy 14.480262 -4.686643) (xy 14.526999 -4.613552) (xy 14.580104 -4.544948) (xy 14.639148 -4.481383)
			(xy 14.703655 -4.42337) (xy 14.738096 -4.396994) (xy 14.773029 -4.371293) (xy 14.846784 -4.325653)
			(xy 14.924335 -4.28681) (xy 15.005056 -4.255076) (xy 15.088297 -4.230709) (xy 15.173387 -4.213903)
			(xy 15.259642 -4.204794) (xy 15.346366 -4.203455) (xy 15.432861 -4.209898) (xy 15.518429 -4.224071)
			(xy 15.602382 -4.245858) (xy 15.684044 -4.275086) (xy 15.762756 -4.311517) (xy 15.837884 -4.35486)
			(xy 15.908824 -4.404764) (xy 15.975003 -4.460828) (xy 16.035889 -4.5226) (xy 16.090991 -4.589582)
			(xy 16.139865 -4.661235) (xy 16.182118 -4.736981) (xy 16.217409 -4.816211) (xy 16.245454 -4.898286)
			(xy 16.266027 -4.982545) (xy 16.267136 -4.989901) (xy 20.44038 -4.989901) (xy 20.44038 -4.935399)
			(xy 20.448136 -4.881452) (xy 20.463491 -4.829158) (xy 20.486132 -4.779581) (xy 20.515597 -4.733731)
			(xy 20.551288 -4.692541) (xy 20.592478 -4.65685) (xy 20.638328 -4.627384) (xy 20.687904 -4.604742)
			(xy 20.740198 -4.589387) (xy 20.794145 -4.58163) (xy 20.821396 -4.581144) (xy 21.684996 -4.581144)
			(xy 21.712249 -4.581603) (xy 21.766201 -4.58936) (xy 21.818499 -4.604715) (xy 21.86808 -4.627358)
			(xy 21.913934 -4.656826) (xy 21.955128 -4.69252) (xy 21.990822 -4.733713) (xy 22.02029 -4.779566)
			(xy 22.042933 -4.829147) (xy 22.05829 -4.881445) (xy 22.066047 -4.935397) (xy 22.066047 -4.989901)
			(xy 24.04032 -4.989901) (xy 24.04032 -4.935399) (xy 24.048076 -4.881452) (xy 24.063431 -4.829157)
			(xy 24.086072 -4.779581) (xy 24.115538 -4.73373) (xy 24.151229 -4.692541) (xy 24.192419 -4.656849)
			(xy 24.238269 -4.627383) (xy 24.287846 -4.604742) (xy 24.34014 -4.589387) (xy 24.394087 -4.58163)
			(xy 24.421338 -4.581144) (xy 25.284938 -4.581144) (xy 25.312191 -4.581603) (xy 25.366143 -4.58936)
			(xy 25.418441 -4.604716) (xy 25.468021 -4.627358) (xy 25.513875 -4.656827) (xy 25.555068 -4.69252)
			(xy 25.590762 -4.733713) (xy 25.620231 -4.779567) (xy 25.642873 -4.829147) (xy 25.65823 -4.881446)
			(xy 25.665987 -4.935397) (xy 25.665987 -4.989903) (xy 25.66598 -4.989954) (xy 27.64023 -4.989954)
			(xy 27.64023 -4.935446) (xy 27.647987 -4.881493) (xy 27.663343 -4.829194) (xy 27.685985 -4.779612)
			(xy 27.715454 -4.733756) (xy 27.751147 -4.692562) (xy 27.79234 -4.656866) (xy 27.838194 -4.627395)
			(xy 27.887775 -4.60475) (xy 27.940074 -4.589391) (xy 27.994026 -4.581631) (xy 28.02128 -4.581144)
			(xy 28.88488 -4.581144) (xy 28.91213 -4.581702) (xy 28.966077 -4.589456) (xy 29.01837 -4.604808)
			(xy 29.067947 -4.627446) (xy 29.113797 -4.65691) (xy 29.154986 -4.692599) (xy 29.190678 -4.733787)
			(xy 29.220144 -4.779636) (xy 29.242785 -4.829211) (xy 29.25814 -4.881504) (xy 29.265897 -4.93545)
			(xy 29.265897 -4.98995) (xy 29.265896 -4.989954) (xy 31.24043 -4.989954) (xy 31.24043 -4.935446)
			(xy 31.248187 -4.881494) (xy 31.263543 -4.829195) (xy 31.286185 -4.779613) (xy 31.315653 -4.733758)
			(xy 31.351346 -4.692563) (xy 31.392538 -4.656867) (xy 31.438392 -4.627396) (xy 31.487972 -4.604751)
			(xy 31.540271 -4.589392) (xy 31.594222 -4.581632) (xy 31.621476 -4.581144) (xy 32.485076 -4.581144)
			(xy 32.512327 -4.581702) (xy 32.566273 -4.589455) (xy 32.618567 -4.604807) (xy 32.668144 -4.627445)
			(xy 32.713995 -4.656909) (xy 32.755185 -4.692598) (xy 32.790877 -4.733786) (xy 32.820343 -4.779635)
			(xy 32.842985 -4.82921) (xy 32.85834 -4.881503) (xy 32.866097 -4.935449) (xy 32.866097 -4.989951)
			(xy 32.866096 -4.989958) (xy 40.350307 -4.989958) (xy 40.350307 -4.935442) (xy 40.358066 -4.881481)
			(xy 40.373426 -4.829173) (xy 40.396074 -4.779584) (xy 40.42555 -4.733723) (xy 40.461252 -4.692524)
			(xy 40.502455 -4.656826) (xy 40.548319 -4.627355) (xy 40.59791 -4.604712) (xy 40.65022 -4.589358)
			(xy 40.704182 -4.581604) (xy 40.73144 -4.581144) (xy 41.59504 -4.581144) (xy 41.622286 -4.581729)
			(xy 41.676222 -4.589489) (xy 41.728506 -4.604846) (xy 41.778072 -4.627486) (xy 41.823911 -4.65695)
			(xy 41.865091 -4.692637) (xy 41.900774 -4.733821) (xy 41.930233 -4.779663) (xy 41.952868 -4.829232)
			(xy 41.968219 -4.881517) (xy 41.975974 -4.935454) (xy 41.975974 -4.989946) (xy 41.975973 -4.989954)
			(xy 43.95033 -4.989954) (xy 43.95033 -4.935446) (xy 43.958087 -4.881493) (xy 43.973443 -4.829193)
			(xy 43.996086 -4.779611) (xy 44.025554 -4.733756) (xy 44.061248 -4.692561) (xy 44.102441 -4.656865)
			(xy 44.148295 -4.627394) (xy 44.197876 -4.604749) (xy 44.250176 -4.589391) (xy 44.304128 -4.581631)
			(xy 44.331382 -4.581144) (xy 45.194982 -4.581144) (xy 45.222232 -4.581702) (xy 45.276178 -4.589456)
			(xy 45.328472 -4.604808) (xy 45.378048 -4.627447) (xy 45.423898 -4.656911) (xy 45.465087 -4.6926)
			(xy 45.500778 -4.733788) (xy 45.530244 -4.779636) (xy 45.552885 -4.829211) (xy 45.56824 -4.881504)
			(xy 45.575997 -4.93545) (xy 45.575997 -4.98995) (xy 45.575996 -4.989954) (xy 51.56043 -4.989954)
			(xy 51.56043 -4.935446) (xy 51.568187 -4.881494) (xy 51.583543 -4.829195) (xy 51.606185 -4.779613)
			(xy 51.635653 -4.733758) (xy 51.671346 -4.692563) (xy 51.712538 -4.656867) (xy 51.758392 -4.627396)
			(xy 51.807972 -4.604751) (xy 51.860271 -4.589392) (xy 51.914222 -4.581632) (xy 51.941476 -4.581144)
			(xy 52.805076 -4.581144) (xy 52.832327 -4.581702) (xy 52.886273 -4.589455) (xy 52.938567 -4.604807)
			(xy 52.988144 -4.627445) (xy 53.033995 -4.656909) (xy 53.075185 -4.692598) (xy 53.110877 -4.733786)
			(xy 53.140343 -4.779635) (xy 53.162985 -4.82921) (xy 53.17834 -4.881503) (xy 53.186097 -4.935449)
			(xy 53.186097 -4.989951) (xy 53.186096 -4.989957) (xy 55.160307 -4.989957) (xy 55.160307 -4.935443)
			(xy 55.168065 -4.881484) (xy 55.183424 -4.829178) (xy 55.206071 -4.77959) (xy 55.235544 -4.73373)
			(xy 55.271245 -4.692532) (xy 55.312445 -4.656834) (xy 55.358306 -4.627362) (xy 55.407894 -4.604718)
			(xy 55.460201 -4.589362) (xy 55.514161 -4.581606) (xy 55.541418 -4.581144) (xy 56.405018 -4.581144)
			(xy 56.432265 -4.581727) (xy 56.486204 -4.589485) (xy 56.53849 -4.60484) (xy 56.588058 -4.627479)
			(xy 56.633901 -4.656942) (xy 56.675084 -4.692629) (xy 56.710769 -4.733814) (xy 56.74023 -4.779657)
			(xy 56.762867 -4.829227) (xy 56.778219 -4.881514) (xy 56.785974 -4.935453) (xy 56.785974 -4.989947)
			(xy 56.778219 -5.043886) (xy 56.762867 -5.096173) (xy 56.74023 -5.145743) (xy 56.710769 -5.191586)
			(xy 56.675084 -5.232771) (xy 56.633901 -5.268458) (xy 56.588058 -5.297921) (xy 56.53849 -5.32056)
			(xy 56.486204 -5.335915) (xy 56.432265 -5.343673) (xy 56.405018 -5.34416) (xy 55.541418 -5.34416)
			(xy 55.514161 -5.343794) (xy 55.460201 -5.336038) (xy 55.407894 -5.320682) (xy 55.358306 -5.298038)
			(xy 55.312445 -5.268566) (xy 55.271245 -5.232868) (xy 55.235544 -5.19167) (xy 55.206071 -5.14581)
			(xy 55.183424 -5.096222) (xy 55.168065 -5.043916) (xy 55.160307 -4.989957) (xy 53.186096 -4.989957)
			(xy 53.17834 -5.043897) (xy 53.162985 -5.09619) (xy 53.140343 -5.145765) (xy 53.110877 -5.191614)
			(xy 53.075185 -5.232802) (xy 53.033995 -5.268491) (xy 52.988144 -5.297955) (xy 52.938567 -5.320593)
			(xy 52.886273 -5.335945) (xy 52.832327 -5.343698) (xy 52.805076 -5.34416) (xy 51.941476 -5.34416)
			(xy 51.914222 -5.343768) (xy 51.860271 -5.336008) (xy 51.807972 -5.320649) (xy 51.758392 -5.298004)
			(xy 51.712538 -5.268533) (xy 51.671346 -5.232837) (xy 51.635653 -5.191642) (xy 51.606185 -5.145787)
			(xy 51.583543 -5.096205) (xy 51.568187 -5.043906) (xy 51.56043 -4.989954) (xy 45.575996 -4.989954)
			(xy 45.56824 -5.043896) (xy 45.552885 -5.096189) (xy 45.530244 -5.145764) (xy 45.500778 -5.191612)
			(xy 45.465087 -5.2328) (xy 45.423898 -5.268489) (xy 45.378048 -5.297953) (xy 45.328472 -5.320592)
			(xy 45.276178 -5.335944) (xy 45.222232 -5.343698) (xy 45.194982 -5.34416) (xy 44.331382 -5.34416)
			(xy 44.304128 -5.343769) (xy 44.250176 -5.336009) (xy 44.197876 -5.320651) (xy 44.148295 -5.298006)
			(xy 44.102441 -5.268535) (xy 44.061248 -5.232839) (xy 44.025554 -5.191644) (xy 43.996086 -5.145789)
			(xy 43.973443 -5.096207) (xy 43.958087 -5.043907) (xy 43.95033 -4.989954) (xy 41.975973 -4.989954)
			(xy 41.968219 -5.043883) (xy 41.952868 -5.096168) (xy 41.930233 -5.145737) (xy 41.900774 -5.191579)
			(xy 41.865091 -5.232763) (xy 41.823911 -5.26845) (xy 41.778072 -5.297914) (xy 41.728506 -5.320554)
			(xy 41.676222 -5.335911) (xy 41.622286 -5.343671) (xy 41.59504 -5.34416) (xy 40.73144 -5.34416) (xy 40.704182 -5.343796)
			(xy 40.65022 -5.336042) (xy 40.59791 -5.320688) (xy 40.548319 -5.298045) (xy 40.502455 -5.268574)
			(xy 40.461252 -5.232876) (xy 40.42555 -5.191677) (xy 40.396074 -5.145816) (xy 40.373426 -5.096227)
			(xy 40.358066 -5.043919) (xy 40.350307 -4.989958) (xy 32.866096 -4.989958) (xy 32.85834 -5.043897)
			(xy 32.842985 -5.09619) (xy 32.820343 -5.145765) (xy 32.790877 -5.191614) (xy 32.755185 -5.232802)
			(xy 32.713995 -5.268491) (xy 32.668144 -5.297955) (xy 32.618567 -5.320593) (xy 32.566273 -5.335945)
			(xy 32.512327 -5.343698) (xy 32.485076 -5.34416) (xy 31.621476 -5.34416) (xy 31.594222 -5.343768)
			(xy 31.540271 -5.336008) (xy 31.487972 -5.320649) (xy 31.438392 -5.298004) (xy 31.392538 -5.268533)
			(xy 31.351346 -5.232837) (xy 31.315653 -5.191642) (xy 31.286185 -5.145787) (xy 31.263543 -5.096205)
			(xy 31.248187 -5.043906) (xy 31.24043 -4.989954) (xy 29.265896 -4.989954) (xy 29.25814 -5.043896)
			(xy 29.242785 -5.096189) (xy 29.220144 -5.145764) (xy 29.190678 -5.191613) (xy 29.154986 -5.232801)
			(xy 29.113797 -5.26849) (xy 29.067947 -5.297954) (xy 29.01837 -5.320592) (xy 28.966077 -5.335944)
			(xy 28.91213 -5.343698) (xy 28.88488 -5.34416) (xy 28.02128 -5.34416) (xy 27.994026 -5.343769) (xy 27.940074 -5.336009)
			(xy 27.887775 -5.32065) (xy 27.838194 -5.298005) (xy 27.79234 -5.268534) (xy 27.751147 -5.232838)
			(xy 27.715454 -5.191644) (xy 27.685985 -5.145788) (xy 27.663343 -5.096206) (xy 27.647987 -5.043907)
			(xy 27.64023 -4.989954) (xy 25.66598 -4.989954) (xy 25.65823 -5.043854) (xy 25.642873 -5.096153)
			(xy 25.620231 -5.145733) (xy 25.590762 -5.191587) (xy 25.555068 -5.23278) (xy 25.513875 -5.268473)
			(xy 25.468021 -5.297942) (xy 25.418441 -5.320584) (xy 25.366143 -5.33594) (xy 25.312191 -5.343697)
			(xy 25.284938 -5.34416) (xy 24.421338 -5.34416) (xy 24.394087 -5.34367) (xy 24.34014 -5.335913) (xy 24.287846 -5.320558)
			(xy 24.238269 -5.297917) (xy 24.192419 -5.268451) (xy 24.151229 -5.232759) (xy 24.115538 -5.19157)
			(xy 24.086072 -5.145719) (xy 24.063431 -5.096143) (xy 24.048076 -5.043848) (xy 24.04032 -4.989901)
			(xy 22.066047 -4.989901) (xy 22.066047 -4.989903) (xy 22.05829 -5.043855) (xy 22.042933 -5.096153)
			(xy 22.02029 -5.145734) (xy 21.990822 -5.191587) (xy 21.955128 -5.23278) (xy 21.913934 -5.268474)
			(xy 21.86808 -5.297942) (xy 21.818499 -5.320585) (xy 21.766201 -5.33594) (xy 21.712249 -5.343697)
			(xy 21.684996 -5.34416) (xy 20.821396 -5.34416) (xy 20.794145 -5.34367) (xy 20.740198 -5.335913)
			(xy 20.687904 -5.320558) (xy 20.638328 -5.297916) (xy 20.592478 -5.26845) (xy 20.551288 -5.232759)
			(xy 20.515597 -5.191569) (xy 20.486132 -5.145719) (xy 20.463491 -5.096142) (xy 20.448136 -5.043848)
			(xy 20.44038 -4.989901) (xy 16.267136 -4.989901) (xy 16.278962 -5.06831) (xy 16.284155 -5.154889)
			(xy 16.281564 -5.241584) (xy 16.27121 -5.327698) (xy 16.253177 -5.412537) (xy 16.22761 -5.495418)
			(xy 16.194714 -5.575672) (xy 16.154755 -5.652653) (xy 16.108054 -5.725741) (xy 16.054988 -5.794348)
			(xy 15.995985 -5.85792) (xy 15.931519 -5.915946) (xy 15.897098 -5.94233) (xy 15.862132 -5.968006)
			(xy 15.788377 -6.013689) (xy 15.710822 -6.052572) (xy 15.630093 -6.084344) (xy 15.546839 -6.108746)
			(xy 15.461732 -6.125584) (xy 15.375458 -6.13472) (xy 15.288712 -6.136082) (xy 15.202194 -6.129659)
			(xy 15.116601 -6.115502) (xy 15.032622 -6.093724) (xy 14.950935 -6.064503) (xy 14.872197 -6.028073)
			(xy 14.797045 -5.984729) (xy 14.726083 -5.934818) (xy 14.659883 -5.878744) (xy 14.598979 -5.816959)
			(xy 14.543862 -5.749961) (xy 14.494977 -5.678289) (xy 14.452716 -5.602521) (xy 14.417421 -5.523269)
			(xy 14.389376 -5.44117) (xy 14.368808 -5.356887) (xy 14.355882 -5.271099) (xy 14.350702 -5.184498)
			(xy 13.611098 -5.184498) (xy 13.611098 -6.169914) (xy 78.515217 -6.169914) (xy 78.519222 -6.082006)
			(xy 78.531205 -5.994826) (xy 78.551065 -5.909097) (xy 78.57864 -5.825529) (xy 78.613699 -5.744815)
			(xy 78.655952 -5.667623) (xy 78.70505 -5.594594) (xy 78.760586 -5.526332) (xy 78.822098 -5.463402)
			(xy 78.889079 -5.406328) (xy 78.960972 -5.35558) (xy 79.037181 -5.31158) (xy 79.117076 -5.274693)
			(xy 79.199995 -5.245224) (xy 79.28525 -5.223417) (xy 79.372134 -5.209453) (xy 79.459928 -5.203447)
			(xy 79.547905 -5.205451) (xy 79.635335 -5.215446) (xy 79.721494 -5.23335) (xy 79.805668 -5.259014)
			(xy 79.887159 -5.292227) (xy 79.965293 -5.332713) (xy 80.039421 -5.380135) (xy 80.108929 -5.434102)
			(xy 80.173243 -5.494167) (xy 80.231827 -5.559831) (xy 80.284198 -5.63055) (xy 80.329921 -5.705738)
			(xy 80.368618 -5.784773) (xy 80.399967 -5.866999) (xy 80.423709 -5.951735) (xy 80.439647 -6.038279)
			(xy 80.447649 -6.125914) (xy 80.44815 -6.169914) (xy 80.447649 -6.213914) (xy 80.439647 -6.301549)
			(xy 80.423709 -6.388093) (xy 80.399967 -6.472829) (xy 80.368618 -6.555055) (xy 80.329921 -6.63409)
			(xy 80.284198 -6.709278) (xy 80.231827 -6.779997) (xy 80.173243 -6.845661) (xy 80.108929 -6.905726)
			(xy 80.039421 -6.959693) (xy 79.965293 -7.007115) (xy 79.887159 -7.047601) (xy 79.805668 -7.080814)
			(xy 79.721494 -7.106478) (xy 79.635335 -7.124382) (xy 79.547905 -7.134377) (xy 79.459928 -7.136381)
			(xy 79.372134 -7.130375) (xy 79.28525 -7.116411) (xy 79.199995 -7.094604) (xy 79.117076 -7.065135)
			(xy 79.037181 -7.028248) (xy 78.960972 -6.984248) (xy 78.889079 -6.9335) (xy 78.822098 -6.876426)
			(xy 78.760586 -6.813496) (xy 78.70505 -6.745234) (xy 78.655952 -6.672205) (xy 78.613699 -6.595013)
			(xy 78.57864 -6.514299) (xy 78.551065 -6.430731) (xy 78.531205 -6.345002) (xy 78.519222 -6.257822)
			(xy 78.515217 -6.169914) (xy 13.611098 -6.169914) (xy 13.611098 -6.751654) (xy 18.635651 -6.751654)
			(xy 18.635651 -6.697146) (xy 18.643409 -6.643192) (xy 18.658767 -6.590891) (xy 18.681411 -6.541309)
			(xy 18.710882 -6.495454) (xy 18.746579 -6.45426) (xy 18.787775 -6.418566) (xy 18.833632 -6.389099)
			(xy 18.883216 -6.366458) (xy 18.935517 -6.351104) (xy 18.989472 -6.34335) (xy 19.016726 -6.342888)
			(xy 19.880326 -6.342888) (xy 19.907576 -6.343384) (xy 19.96152 -6.351143) (xy 20.013811 -6.3665)
			(xy 20.063385 -6.389143) (xy 20.109231 -6.418609) (xy 20.150418 -6.4543) (xy 20.186106 -6.49549)
			(xy 20.21557 -6.541338) (xy 20.238209 -6.590913) (xy 20.253563 -6.643205) (xy 20.261318 -6.69715)
			(xy 20.261318 -6.75165) (xy 22.235674 -6.75165) (xy 22.235674 -6.69715) (xy 22.243429 -6.643204)
			(xy 22.258783 -6.590912) (xy 22.281422 -6.541336) (xy 22.310886 -6.495487) (xy 22.346574 -6.454297)
			(xy 22.387761 -6.418605) (xy 22.433608 -6.389138) (xy 22.483182 -6.366494) (xy 22.535473 -6.351136)
			(xy 22.589418 -6.343376) (xy 22.616668 -6.342888) (xy 23.480268 -6.342888) (xy 23.507522 -6.343357)
			(xy 23.561476 -6.35111) (xy 23.613777 -6.366463) (xy 23.663361 -6.389104) (xy 23.709217 -6.418571)
			(xy 23.750413 -6.454264) (xy 23.78611 -6.495457) (xy 23.815581 -6.541311) (xy 23.838225 -6.590893)
			(xy 23.853583 -6.643193) (xy 23.861341 -6.697146) (xy 23.861341 -6.751654) (xy 25.835551 -6.751654)
			(xy 25.835551 -6.697146) (xy 25.843309 -6.643194) (xy 25.858665 -6.590895) (xy 25.881309 -6.541314)
			(xy 25.910778 -6.495459) (xy 25.946473 -6.454266) (xy 25.987667 -6.418572) (xy 26.033522 -6.389104)
			(xy 26.083104 -6.366462) (xy 26.135404 -6.351107) (xy 26.189356 -6.343351) (xy 26.21661 -6.342888)
			(xy 27.08021 -6.342888) (xy 27.10746 -6.343382) (xy 27.161407 -6.35114) (xy 27.2137 -6.366496) (xy 27.263275 -6.389137)
			(xy 27.309124 -6.418604) (xy 27.350312 -6.454295) (xy 27.386002 -6.495484) (xy 27.415467 -6.541334)
			(xy 27.438108 -6.59091) (xy 27.453462 -6.643203) (xy 27.461218 -6.697149) (xy 27.461218 -6.751651)
			(xy 27.461218 -6.751653) (xy 29.435751 -6.751653) (xy 29.435751 -6.697147) (xy 29.443509 -6.643195)
			(xy 29.458865 -6.590896) (xy 29.481508 -6.541315) (xy 29.510977 -6.495461) (xy 29.546672 -6.454268)
			(xy 29.587866 -6.418574) (xy 29.63372 -6.389105) (xy 29.683301 -6.366463) (xy 29.7356 -6.351107)
			(xy 29.789553 -6.343351) (xy 29.816806 -6.342888) (xy 30.680406 -6.342888) (xy 30.707657 -6.343382)
			(xy 30.761603 -6.351139) (xy 30.813897 -6.366495) (xy 30.863473 -6.389136) (xy 30.909322 -6.418602)
			(xy 30.950511 -6.454293) (xy 30.986201 -6.495483) (xy 31.015667 -6.541333) (xy 31.038307 -6.590909)
			(xy 31.053662 -6.643203) (xy 31.061418 -6.697149) (xy 31.061418 -6.75165) (xy 38.545774 -6.75165)
			(xy 38.545774 -6.69715) (xy 38.55353 -6.643204) (xy 38.568883 -6.590911) (xy 38.591522 -6.541336)
			(xy 38.620986 -6.495486) (xy 38.656675 -6.454296) (xy 38.697862 -6.418604) (xy 38.743709 -6.389137)
			(xy 38.793283 -6.366494) (xy 38.845575 -6.351136) (xy 38.89952 -6.343376) (xy 38.92677 -6.342888)
			(xy 39.79037 -6.342888) (xy 39.817624 -6.343357) (xy 39.871578 -6.351111) (xy 39.923878 -6.366464)
			(xy 39.973462 -6.389105) (xy 40.019318 -6.418571) (xy 40.060514 -6.454265) (xy 40.096211 -6.495458)
			(xy 40.125681 -6.541312) (xy 40.148326 -6.590893) (xy 40.163683 -6.643193) (xy 40.171441 -6.697146)
			(xy 40.171441 -6.751654) (xy 42.145651 -6.751654) (xy 42.145651 -6.697146) (xy 42.153409 -6.643194)
			(xy 42.168766 -6.590894) (xy 42.191409 -6.541313) (xy 42.220879 -6.495459) (xy 42.256574 -6.454265)
			(xy 42.297768 -6.418571) (xy 42.343624 -6.389103) (xy 42.393206 -6.366461) (xy 42.445506 -6.351106)
			(xy 42.499458 -6.343351) (xy 42.526712 -6.342888) (xy 43.390312 -6.342888) (xy 43.417562 -6.343383)
			(xy 43.471508 -6.35114) (xy 43.523801 -6.366496) (xy 43.573376 -6.389138) (xy 43.619225 -6.418604)
			(xy 43.660413 -6.454295) (xy 43.696103 -6.495485) (xy 43.725568 -6.541334) (xy 43.748208 -6.59091)
			(xy 43.763562 -6.643203) (xy 43.771318 -6.69715) (xy 43.771318 -6.75165) (xy 43.771318 -6.751653)
			(xy 49.755751 -6.751653) (xy 49.755751 -6.697147) (xy 49.763509 -6.643195) (xy 49.778865 -6.590896)
			(xy 49.801508 -6.541315) (xy 49.830977 -6.495461) (xy 49.866672 -6.454268) (xy 49.907866 -6.418574)
			(xy 49.95372 -6.389105) (xy 50.003301 -6.366463) (xy 50.0556 -6.351107) (xy 50.109553 -6.343351)
			(xy 50.136806 -6.342888) (xy 51.000406 -6.342888) (xy 51.027657 -6.343382) (xy 51.081603 -6.351139)
			(xy 51.133897 -6.366495) (xy 51.183473 -6.389136) (xy 51.229322 -6.418602) (xy 51.270511 -6.454293)
			(xy 51.306201 -6.495483) (xy 51.335667 -6.541333) (xy 51.358307 -6.590909) (xy 51.373662 -6.643203)
			(xy 51.381418 -6.697149) (xy 51.381418 -6.751651) (xy 51.381417 -6.751655) (xy 53.355652 -6.751655)
			(xy 53.355652 -6.697145) (xy 53.36341 -6.643189) (xy 53.378768 -6.590887) (xy 53.401415 -6.541303)
			(xy 53.430887 -6.495447) (xy 53.466587 -6.454253) (xy 53.507785 -6.418559) (xy 53.553645 -6.389092)
			(xy 53.603232 -6.366452) (xy 53.655536 -6.3511) (xy 53.709493 -6.343348) (xy 53.736748 -6.342888)
			(xy 54.600348 -6.342888) (xy 54.627597 -6.343385) (xy 54.681539 -6.351147) (xy 54.733827 -6.366506)
			(xy 54.783398 -6.38915) (xy 54.829242 -6.418617) (xy 54.870426 -6.454308) (xy 54.906112 -6.495497)
			(xy 54.935573 -6.541344) (xy 54.958211 -6.590918) (xy 54.973563 -6.643208) (xy 54.981318 -6.697151)
			(xy 54.981318 -6.751649) (xy 54.981318 -6.751651) (xy 56.955674 -6.751651) (xy 56.955674 -6.697149)
			(xy 56.96343 -6.643201) (xy 56.978785 -6.590907) (xy 57.001426 -6.54133) (xy 57.030891 -6.49548)
			(xy 57.066582 -6.454289) (xy 57.107771 -6.418597) (xy 57.153621 -6.38913) (xy 57.203198 -6.366488)
			(xy 57.255492 -6.351132) (xy 57.309439 -6.343374) (xy 57.33669 -6.342888) (xy 58.20029 -6.342888)
			(xy 58.227543 -6.343359) (xy 58.281494 -6.351114) (xy 58.333793 -6.366469) (xy 58.383374 -6.389111)
			(xy 58.429228 -6.418578) (xy 58.470421 -6.454272) (xy 58.506116 -6.495464) (xy 58.535584 -6.541317)
			(xy 58.558227 -6.590898) (xy 58.573583 -6.643196) (xy 58.581341 -6.697147) (xy 58.581341 -6.751651)
			(xy 70.950574 -6.751651) (xy 70.950574 -6.697149) (xy 70.95833 -6.643203) (xy 70.973684 -6.590909)
			(xy 70.996324 -6.541332) (xy 71.025789 -6.495482) (xy 71.061479 -6.454292) (xy 71.102668 -6.4186)
			(xy 71.148516 -6.389133) (xy 71.198092 -6.366491) (xy 71.250385 -6.351134) (xy 71.304331 -6.343375)
			(xy 71.331582 -6.342888) (xy 72.195182 -6.342888) (xy 72.222435 -6.343358) (xy 72.276388 -6.351113)
			(xy 72.328687 -6.366467) (xy 72.378269 -6.389108) (xy 72.424124 -6.418576) (xy 72.465318 -6.454269)
			(xy 72.501014 -6.495462) (xy 72.530483 -6.541315) (xy 72.553126 -6.590896) (xy 72.568483 -6.643195)
			(xy 72.576241 -6.697147) (xy 72.576241 -6.751653) (xy 72.568483 -6.805605) (xy 72.553126 -6.857904)
			(xy 72.530483 -6.907485) (xy 72.501014 -6.953338) (xy 72.465318 -6.994531) (xy 72.424124 -7.030224)
			(xy 72.378269 -7.059692) (xy 72.328687 -7.082333) (xy 72.276388 -7.097687) (xy 72.222435 -7.105442)
			(xy 72.195182 -7.105904) (xy 71.331582 -7.105904) (xy 71.304331 -7.105425) (xy 71.250385 -7.097666)
			(xy 71.198092 -7.082309) (xy 71.148516 -7.059667) (xy 71.102668 -7.0302) (xy 71.061479 -6.994508)
			(xy 71.025789 -6.953318) (xy 70.996324 -6.907468) (xy 70.973684 -6.857891) (xy 70.95833 -6.805597)
			(xy 70.950574 -6.751651) (xy 58.581341 -6.751651) (xy 58.581341 -6.751653) (xy 58.573583 -6.805604)
			(xy 58.558227 -6.857902) (xy 58.535584 -6.907483) (xy 58.506116 -6.953336) (xy 58.470421 -6.994528)
			(xy 58.429228 -7.030222) (xy 58.383374 -7.059689) (xy 58.333793 -7.082331) (xy 58.281494 -7.097686)
			(xy 58.227543 -7.105441) (xy 58.20029 -7.105904) (xy 57.33669 -7.105904) (xy 57.309439 -7.105426)
			(xy 57.255492 -7.097668) (xy 57.203198 -7.082312) (xy 57.153621 -7.05967) (xy 57.107771 -7.030203)
			(xy 57.066582 -6.994511) (xy 57.030891 -6.95332) (xy 57.001426 -6.90747) (xy 56.978785 -6.857893)
			(xy 56.96343 -6.805599) (xy 56.955674 -6.751651) (xy 54.981318 -6.751651) (xy 54.973563 -6.805592)
			(xy 54.958211 -6.857882) (xy 54.935573 -6.907456) (xy 54.906112 -6.953303) (xy 54.870426 -6.994492)
			(xy 54.829242 -7.030183) (xy 54.783398 -7.05965) (xy 54.733827 -7.082294) (xy 54.681539 -7.097653)
			(xy 54.627597 -7.105415) (xy 54.600348 -7.105904) (xy 53.736748 -7.105904) (xy 53.709493 -7.105452)
			(xy 53.655536 -7.0977) (xy 53.603232 -7.082348) (xy 53.553645 -7.059708) (xy 53.507785 -7.030241)
			(xy 53.466587 -6.994547) (xy 53.430887 -6.953353) (xy 53.401415 -6.907497) (xy 53.378768 -6.857913)
			(xy 53.36341 -6.805611) (xy 53.355652 -6.751655) (xy 51.381417 -6.751655) (xy 51.373662 -6.805597)
			(xy 51.358307 -6.857891) (xy 51.335667 -6.907467) (xy 51.306201 -6.953317) (xy 51.270511 -6.994507)
			(xy 51.229322 -7.030198) (xy 51.183473 -7.059664) (xy 51.133897 -7.082305) (xy 51.081603 -7.097661)
			(xy 51.027657 -7.105418) (xy 51.000406 -7.105904) (xy 50.136806 -7.105904) (xy 50.109553 -7.105449)
			(xy 50.0556 -7.097693) (xy 50.003301 -7.082337) (xy 49.95372 -7.059695) (xy 49.907866 -7.030226)
			(xy 49.866672 -6.994532) (xy 49.830977 -6.953339) (xy 49.801508 -6.907485) (xy 49.778865 -6.857904)
			(xy 49.763509 -6.805605) (xy 49.755751 -6.751653) (xy 43.771318 -6.751653) (xy 43.763562 -6.805597)
			(xy 43.748208 -6.85789) (xy 43.725568 -6.907466) (xy 43.696103 -6.953315) (xy 43.660413 -6.994505)
			(xy 43.619225 -7.030196) (xy 43.573376 -7.059662) (xy 43.523801 -7.082304) (xy 43.471508 -7.09766)
			(xy 43.417562 -7.105417) (xy 43.390312 -7.105904) (xy 42.526712 -7.105904) (xy 42.499458 -7.105449)
			(xy 42.445506 -7.097694) (xy 42.393206 -7.082339) (xy 42.343624 -7.059697) (xy 42.297768 -7.030229)
			(xy 42.256574 -6.994535) (xy 42.220879 -6.953341) (xy 42.191409 -6.907487) (xy 42.168766 -6.857906)
			(xy 42.153409 -6.805606) (xy 42.145651 -6.751654) (xy 40.171441 -6.751654) (xy 40.163683 -6.805607)
			(xy 40.148326 -6.857907) (xy 40.125681 -6.907488) (xy 40.096211 -6.953342) (xy 40.060514 -6.994535)
			(xy 40.019318 -7.030229) (xy 39.973462 -7.059695) (xy 39.923878 -7.082336) (xy 39.871578 -7.097689)
			(xy 39.817624 -7.105443) (xy 39.79037 -7.105904) (xy 38.92677 -7.105904) (xy 38.89952 -7.105424)
			(xy 38.845575 -7.097664) (xy 38.793283 -7.082306) (xy 38.743709 -7.059663) (xy 38.697862 -7.030196)
			(xy 38.656675 -6.994504) (xy 38.620986 -6.953314) (xy 38.591522 -6.907464) (xy 38.568883 -6.857889)
			(xy 38.55353 -6.805596) (xy 38.545774 -6.75165) (xy 31.061418 -6.75165) (xy 31.061418 -6.751651)
			(xy 31.053662 -6.805597) (xy 31.038307 -6.857891) (xy 31.015667 -6.907467) (xy 30.986201 -6.953317)
			(xy 30.950511 -6.994507) (xy 30.909322 -7.030198) (xy 30.863473 -7.059664) (xy 30.813897 -7.082305)
			(xy 30.761603 -7.097661) (xy 30.707657 -7.105418) (xy 30.680406 -7.105904) (xy 29.816806 -7.105904)
			(xy 29.789553 -7.105449) (xy 29.7356 -7.097693) (xy 29.683301 -7.082337) (xy 29.63372 -7.059695)
			(xy 29.587866 -7.030226) (xy 29.546672 -6.994532) (xy 29.510977 -6.953339) (xy 29.481508 -6.907485)
			(xy 29.458865 -6.857904) (xy 29.443509 -6.805605) (xy 29.435751 -6.751653) (xy 27.461218 -6.751653)
			(xy 27.453462 -6.805597) (xy 27.438108 -6.85789) (xy 27.415467 -6.907466) (xy 27.386002 -6.953316)
			(xy 27.350312 -6.994505) (xy 27.309124 -7.030196) (xy 27.263275 -7.059663) (xy 27.2137 -7.082304)
			(xy 27.161407 -7.09766) (xy 27.10746 -7.105418) (xy 27.08021 -7.105904) (xy 26.21661 -7.105904) (xy 26.189356 -7.105449)
			(xy 26.135404 -7.097693) (xy 26.083104 -7.082338) (xy 26.033522 -7.059696) (xy 25.987667 -7.030228)
			(xy 25.946473 -6.994534) (xy 25.910778 -6.953341) (xy 25.881309 -6.907486) (xy 25.858665 -6.857905)
			(xy 25.843309 -6.805606) (xy 25.835551 -6.751654) (xy 23.861341 -6.751654) (xy 23.853583 -6.805607)
			(xy 23.838225 -6.857907) (xy 23.815581 -6.907489) (xy 23.78611 -6.953343) (xy 23.750413 -6.994536)
			(xy 23.709217 -7.030229) (xy 23.663361 -7.059696) (xy 23.613777 -7.082337) (xy 23.561476 -7.09769)
			(xy 23.507522 -7.105443) (xy 23.480268 -7.105904) (xy 22.616668 -7.105904) (xy 22.589418 -7.105424)
			(xy 22.535473 -7.097664) (xy 22.483182 -7.082306) (xy 22.433608 -7.059662) (xy 22.387761 -7.030195)
			(xy 22.346574 -6.994503) (xy 22.310886 -6.953313) (xy 22.281422 -6.907464) (xy 22.258783 -6.857888)
			(xy 22.243429 -6.805596) (xy 22.235674 -6.75165) (xy 20.261318 -6.75165) (xy 20.253563 -6.805595)
			(xy 20.238209 -6.857887) (xy 20.21557 -6.907462) (xy 20.186106 -6.95331) (xy 20.150418 -6.9945) (xy 20.109231 -7.030191)
			(xy 20.063385 -7.059657) (xy 20.013811 -7.0823) (xy 19.96152 -7.097657) (xy 19.907576 -7.105416)
			(xy 19.880326 -7.105904) (xy 19.016726 -7.105904) (xy 18.989472 -7.10545) (xy 18.935517 -7.097696)
			(xy 18.883216 -7.082342) (xy 18.833632 -7.059701) (xy 18.787775 -7.030234) (xy 18.746579 -6.99454)
			(xy 18.710882 -6.953346) (xy 18.681411 -6.907491) (xy 18.658767 -6.857909) (xy 18.643409 -6.805608)
			(xy 18.635651 -6.751654) (xy 13.611098 -6.751654) (xy 13.611098 -9.780016) (xy 13.610604 -9.850398)
			(xy 13.602711 -9.990941) (xy 13.58695 -10.13082) (xy 13.563371 -10.269596) (xy 13.532048 -10.406831)
			(xy 13.493079 -10.542094) (xy 13.446587 -10.674959) (xy 13.392719 -10.805008) (xy 13.331643 -10.931832)
			(xy 13.263553 -11.055033) (xy 13.188662 -11.174221) (xy 13.107205 -11.289023) (xy 13.01944 -11.399077)
			(xy 12.925642 -11.504037) (xy 12.826107 -11.603572) (xy 12.721147 -11.69737) (xy 12.611093 -11.785135)
			(xy 12.496291 -11.866592) (xy 12.377103 -11.941483) (xy 12.253902 -12.009573) (xy 12.127078 -12.070649)
			(xy 11.997029 -12.124517) (xy 11.864164 -12.171009) (xy 11.728901 -12.209978) (xy 11.591666 -12.241301)
			(xy 11.45289 -12.26488) (xy 11.313011 -12.280641) (xy 11.172468 -12.288534) (xy 11.102086 -12.289028)
			(xy 1.999996 -12.289028) (xy 1.944227 -12.289537) (xy 1.833 -12.297872) (xy 1.722707 -12.314497)
			(xy 1.613965 -12.339317) (xy 1.507382 -12.372193) (xy 1.403554 -12.412943) (xy 1.303061 -12.461339)
			(xy 1.206466 -12.517108) (xy 1.114309 -12.579941) (xy 1.027105 -12.649484) (xy 0.945341 -12.72535)
			(xy 0.869476 -12.807114) (xy 0.802299 -12.891351) (xy 56.954662 -12.891351) (xy 56.954662 -12.836849)
			(xy 56.962418 -12.782901) (xy 56.977772 -12.730606) (xy 57.000413 -12.681029) (xy 57.029878 -12.635178)
			(xy 57.065568 -12.593986) (xy 57.106757 -12.558293) (xy 57.152606 -12.528825) (xy 57.202182 -12.506181)
			(xy 57.254476 -12.490823) (xy 57.308423 -12.483064) (xy 57.335674 -12.482576) (xy 58.199274 -12.482576)
			(xy 58.226527 -12.48307) (xy 58.280478 -12.490823) (xy 58.332777 -12.506176) (xy 58.382358 -12.528816)
			(xy 58.428213 -12.558282) (xy 58.469407 -12.593975) (xy 58.505102 -12.635166) (xy 58.534571 -12.681019)
			(xy 58.557215 -12.730598) (xy 58.572571 -12.782896) (xy 58.580329 -12.836847) (xy 58.580329 -12.891353)
			(xy 58.580329 -12.891355) (xy 70.949739 -12.891355) (xy 70.949739 -12.836845) (xy 70.957497 -12.78289)
			(xy 70.972854 -12.730588) (xy 70.995499 -12.681005) (xy 71.024971 -12.635149) (xy 71.060668 -12.593954)
			(xy 71.101865 -12.558259) (xy 71.147722 -12.52879) (xy 71.197307 -12.506147) (xy 71.24961 -12.490793)
			(xy 71.303565 -12.483038) (xy 71.33082 -12.482576) (xy 72.19442 -12.482576) (xy 72.221669 -12.483096)
			(xy 72.275612 -12.490854) (xy 72.327902 -12.50621) (xy 72.377475 -12.528852) (xy 72.423321 -12.558317)
			(xy 72.464507 -12.594007) (xy 72.500195 -12.635195) (xy 72.529658 -12.681043) (xy 72.552297 -12.730616)
			(xy 72.56765 -12.782907) (xy 72.575406 -12.836851) (xy 72.575406 -12.891349) (xy 72.56765 -12.945293)
			(xy 72.552297 -12.997584) (xy 72.529658 -13.047157) (xy 72.500195 -13.093005) (xy 72.464507 -13.134193)
			(xy 72.423321 -13.169883) (xy 72.377475 -13.199348) (xy 72.327902 -13.22199) (xy 72.275612 -13.237346)
			(xy 72.221669 -13.245104) (xy 72.19442 -13.245592) (xy 71.33082 -13.245592) (xy 71.303565 -13.245162)
			(xy 71.24961 -13.237407) (xy 71.197307 -13.222053) (xy 71.147722 -13.19941) (xy 71.101865 -13.169941)
			(xy 71.060668 -13.134246) (xy 71.024971 -13.093051) (xy 70.995499 -13.047195) (xy 70.972854 -12.997612)
			(xy 70.957497 -12.94531) (xy 70.949739 -12.891355) (xy 58.580329 -12.891355) (xy 58.572571 -12.945304)
			(xy 58.557215 -12.997602) (xy 58.534571 -13.047181) (xy 58.505102 -13.093034) (xy 58.469407 -13.134225)
			(xy 58.428213 -13.169918) (xy 58.382358 -13.199384) (xy 58.332777 -13.222024) (xy 58.280478 -13.237377)
			(xy 58.226527 -13.24513) (xy 58.199274 -13.245592) (xy 57.335674 -13.245592) (xy 57.308423 -13.245136)
			(xy 57.254476 -13.237377) (xy 57.202182 -13.222019) (xy 57.152606 -13.199375) (xy 57.106757 -13.169907)
			(xy 57.065568 -13.134214) (xy 57.029878 -13.093022) (xy 57.000413 -13.047171) (xy 56.977772 -12.997594)
			(xy 56.962418 -12.945299) (xy 56.954662 -12.891351) (xy 0.802299 -12.891351) (xy 0.799933 -12.894318)
			(xy 0.737102 -12.986476) (xy 0.681333 -13.083072) (xy 0.632939 -13.183565) (xy 0.59219 -13.287393)
			(xy 0.559313 -13.393977) (xy 0.534494 -13.502719) (xy 0.517871 -13.613012) (xy 0.509536 -13.724239)
			(xy 0.509016 -13.780008) (xy 0.509016 -15.222054) (xy 135.233343 -15.222054) (xy 135.233343 -15.167546)
			(xy 135.2411 -15.113592) (xy 135.256457 -15.061292) (xy 135.279101 -15.011709) (xy 135.308571 -14.965854)
			(xy 135.344267 -14.92466) (xy 135.385462 -14.888965) (xy 135.431318 -14.859497) (xy 135.480901 -14.836854)
			(xy 135.533202 -14.821498) (xy 135.587156 -14.813742) (xy 135.61441 -14.81328) (xy 136.47801 -14.81328)
			(xy 136.50526 -14.813791) (xy 136.559205 -14.821548) (xy 136.611497 -14.836904) (xy 136.661071 -14.859545)
			(xy 136.706919 -14.88901) (xy 136.748106 -14.924701) (xy 136.783796 -14.965889) (xy 136.81326 -15.011738)
			(xy 136.8359 -15.061313) (xy 136.851254 -15.113605) (xy 136.85901 -15.16755) (xy 136.85901 -15.22205)
			(xy 136.851254 -15.275995) (xy 136.8359 -15.328287) (xy 136.81326 -15.377862) (xy 136.783796 -15.423711)
			(xy 136.748106 -15.464899) (xy 136.706919 -15.50059) (xy 136.661071 -15.530055) (xy 136.611497 -15.552696)
			(xy 136.559205 -15.568052) (xy 136.50526 -15.575809) (xy 136.47801 -15.576296) (xy 135.61441 -15.576296)
			(xy 135.587156 -15.575858) (xy 135.533202 -15.568102) (xy 135.480901 -15.552746) (xy 135.431318 -15.530103)
			(xy 135.385462 -15.500635) (xy 135.344267 -15.46494) (xy 135.308571 -15.423746) (xy 135.279101 -15.377891)
			(xy 135.256457 -15.328308) (xy 135.2411 -15.276008) (xy 135.233343 -15.222054) (xy 0.509016 -15.222054)
			(xy 0.509016 -17.639611) (xy 15.152858 -17.639611) (xy 15.152858 -17.585109) (xy 15.160614 -17.531161)
			(xy 15.175969 -17.478867) (xy 15.19861 -17.42929) (xy 15.228076 -17.383439) (xy 15.263768 -17.342249)
			(xy 15.304958 -17.306558) (xy 15.350808 -17.277091) (xy 15.400385 -17.25445) (xy 15.452679 -17.239095)
			(xy 15.506627 -17.231338) (xy 15.533878 -17.230852) (xy 16.397478 -17.230852) (xy 16.424731 -17.231315)
			(xy 16.478682 -17.239072) (xy 16.53098 -17.254428) (xy 16.580561 -17.27707) (xy 16.626414 -17.306538)
			(xy 16.667607 -17.342232) (xy 16.703301 -17.383424) (xy 16.732769 -17.429278) (xy 16.755412 -17.478858)
			(xy 16.770768 -17.531156) (xy 16.778525 -17.585107) (xy 16.778525 -17.639611) (xy 20.740858 -17.639611)
			(xy 20.740858 -17.585109) (xy 20.748614 -17.531161) (xy 20.763969 -17.478867) (xy 20.78661 -17.42929)
			(xy 20.816076 -17.383439) (xy 20.851768 -17.342249) (xy 20.892958 -17.306558) (xy 20.938808 -17.277091)
			(xy 20.988385 -17.25445) (xy 21.040679 -17.239095) (xy 21.094627 -17.231338) (xy 21.121878 -17.230852)
			(xy 21.985478 -17.230852) (xy 22.012729 -17.231394) (xy 22.066677 -17.239147) (xy 22.118972 -17.2545)
			(xy 22.168549 -17.277139) (xy 22.2144 -17.306603) (xy 22.255591 -17.342293) (xy 22.291284 -17.383482)
			(xy 22.320751 -17.429331) (xy 22.343392 -17.478908) (xy 22.358748 -17.531202) (xy 22.366505 -17.585149)
			(xy 22.366505 -17.639651) (xy 22.366505 -17.639653) (xy 26.328838 -17.639653) (xy 26.328838 -17.585147)
			(xy 26.336595 -17.531195) (xy 26.35195 -17.478897) (xy 26.374592 -17.429316) (xy 26.404059 -17.383462)
			(xy 26.439752 -17.342268) (xy 26.480944 -17.306573) (xy 26.526797 -17.277103) (xy 26.576376 -17.254458)
			(xy 26.628674 -17.239099) (xy 26.682625 -17.231339) (xy 26.709878 -17.230852) (xy 27.573478 -17.230852)
			(xy 27.600729 -17.231394) (xy 27.654677 -17.239147) (xy 27.706972 -17.2545) (xy 27.756549 -17.277139)
			(xy 27.8024 -17.306603) (xy 27.843591 -17.342293) (xy 27.879284 -17.383482) (xy 27.908751 -17.429331)
			(xy 27.931392 -17.478908) (xy 27.946748 -17.531202) (xy 27.954505 -17.585149) (xy 27.954505 -17.639651)
			(xy 27.954505 -17.639653) (xy 31.916838 -17.639653) (xy 31.916838 -17.585147) (xy 31.924595 -17.531195)
			(xy 31.93995 -17.478897) (xy 31.962592 -17.429316) (xy 31.992059 -17.383462) (xy 32.027752 -17.342268)
			(xy 32.068944 -17.306573) (xy 32.114797 -17.277103) (xy 32.164376 -17.254458) (xy 32.216674 -17.239099)
			(xy 32.270625 -17.231339) (xy 32.297878 -17.230852) (xy 33.161478 -17.230852) (xy 33.188729 -17.231394)
			(xy 33.242677 -17.239147) (xy 33.294972 -17.2545) (xy 33.344549 -17.277139) (xy 33.3904 -17.306603)
			(xy 33.431591 -17.342293) (xy 33.467284 -17.383482) (xy 33.496751 -17.429331) (xy 33.519392 -17.478908)
			(xy 33.534748 -17.531202) (xy 33.542505 -17.585149) (xy 33.542505 -17.639651) (xy 33.542505 -17.639653)
			(xy 37.504838 -17.639653) (xy 37.504838 -17.585147) (xy 37.512595 -17.531195) (xy 37.52795 -17.478897)
			(xy 37.550592 -17.429316) (xy 37.580059 -17.383462) (xy 37.615752 -17.342268) (xy 37.656944 -17.306573)
			(xy 37.702797 -17.277103) (xy 37.752376 -17.254458) (xy 37.804674 -17.239099) (xy 37.858625 -17.231339)
			(xy 37.885878 -17.230852) (xy 38.749478 -17.230852) (xy 38.776729 -17.231394) (xy 38.830677 -17.239147)
			(xy 38.882972 -17.2545) (xy 38.932549 -17.277139) (xy 38.9784 -17.306603) (xy 39.019591 -17.342293)
			(xy 39.055284 -17.383482) (xy 39.084751 -17.429331) (xy 39.107392 -17.478908) (xy 39.122748 -17.531202)
			(xy 39.130505 -17.585149) (xy 39.130505 -17.639651) (xy 39.130505 -17.639654) (xy 43.398638 -17.639654)
			(xy 43.398638 -17.585146) (xy 43.406395 -17.531193) (xy 43.421751 -17.478894) (xy 43.444395 -17.429312)
			(xy 43.473863 -17.383457) (xy 43.509558 -17.342262) (xy 43.550752 -17.306567) (xy 43.596606 -17.277097)
			(xy 43.646188 -17.254454) (xy 43.698487 -17.239096) (xy 43.75244 -17.231338) (xy 43.779694 -17.230852)
			(xy 44.643294 -17.230852) (xy 44.670544 -17.231395) (xy 44.72449 -17.23915) (xy 44.776783 -17.254504)
			(xy 44.826359 -17.277144) (xy 44.872208 -17.306609) (xy 44.913397 -17.342299) (xy 44.949088 -17.383487)
			(xy 44.978553 -17.429336) (xy 45.001194 -17.478911) (xy 45.016548 -17.531204) (xy 45.024305 -17.58515)
			(xy 45.024305 -17.63965) (xy 45.024304 -17.639654) (xy 48.986638 -17.639654) (xy 48.986638 -17.585146)
			(xy 48.994395 -17.531193) (xy 49.009751 -17.478894) (xy 49.032395 -17.429312) (xy 49.061863 -17.383457)
			(xy 49.097558 -17.342262) (xy 49.138752 -17.306567) (xy 49.184606 -17.277097) (xy 49.234188 -17.254454)
			(xy 49.286487 -17.239096) (xy 49.34044 -17.231338) (xy 49.367694 -17.230852) (xy 50.231294 -17.230852)
			(xy 50.258544 -17.231395) (xy 50.31249 -17.23915) (xy 50.364783 -17.254504) (xy 50.414359 -17.277144)
			(xy 50.460208 -17.306609) (xy 50.501397 -17.342299) (xy 50.537088 -17.383487) (xy 50.566553 -17.429336)
			(xy 50.589194 -17.478911) (xy 50.604548 -17.531204) (xy 50.612305 -17.58515) (xy 50.612305 -17.63965)
			(xy 50.612304 -17.639657) (xy 54.608615 -17.639657) (xy 54.608615 -17.585143) (xy 54.616374 -17.531184)
			(xy 54.631733 -17.478878) (xy 54.65438 -17.42929) (xy 54.683854 -17.383431) (xy 54.719554 -17.342233)
			(xy 54.760755 -17.306536) (xy 54.806617 -17.277065) (xy 54.856206 -17.254422) (xy 54.908513 -17.239067)
			(xy 54.962473 -17.231313) (xy 54.98973 -17.230852) (xy 55.85333 -17.230852) (xy 55.880577 -17.23142)
			(xy 55.934516 -17.239179) (xy 55.986801 -17.254535) (xy 56.03637 -17.277176) (xy 56.082211 -17.30664)
			(xy 56.123394 -17.342328) (xy 56.159078 -17.383513) (xy 56.188538 -17.429357) (xy 56.211175 -17.478927)
			(xy 56.226527 -17.531214) (xy 56.234282 -17.585153) (xy 56.234282 -17.639647) (xy 56.226527 -17.693586)
			(xy 56.211175 -17.745873) (xy 56.188538 -17.795443) (xy 56.159078 -17.841287) (xy 56.123394 -17.882472)
			(xy 56.082211 -17.91816) (xy 56.03637 -17.947624) (xy 55.986801 -17.970265) (xy 55.934516 -17.985621)
			(xy 55.880577 -17.99338) (xy 55.85333 -17.993868) (xy 54.98973 -17.993868) (xy 54.962473 -17.993487)
			(xy 54.908513 -17.985733) (xy 54.856206 -17.970378) (xy 54.806617 -17.947735) (xy 54.760755 -17.918264)
			(xy 54.719554 -17.882567) (xy 54.683854 -17.841369) (xy 54.65438 -17.79551) (xy 54.631733 -17.745922)
			(xy 54.616374 -17.693616) (xy 54.608615 -17.639657) (xy 50.612304 -17.639657) (xy 50.604548 -17.693596)
			(xy 50.589194 -17.745889) (xy 50.566553 -17.795464) (xy 50.537088 -17.841313) (xy 50.501397 -17.882501)
			(xy 50.460208 -17.918191) (xy 50.414359 -17.947656) (xy 50.364783 -17.970296) (xy 50.31249 -17.98565)
			(xy 50.258544 -17.993405) (xy 50.231294 -17.993868) (xy 49.367694 -17.993868) (xy 49.34044 -17.993462)
			(xy 49.286487 -17.985704) (xy 49.234188 -17.970346) (xy 49.184606 -17.947703) (xy 49.138752 -17.918233)
			(xy 49.097558 -17.882538) (xy 49.061863 -17.841343) (xy 49.032395 -17.795488) (xy 49.009751 -17.745906)
			(xy 48.994395 -17.693607) (xy 48.986638 -17.639654) (xy 45.024304 -17.639654) (xy 45.016548 -17.693596)
			(xy 45.001194 -17.745889) (xy 44.978553 -17.795464) (xy 44.949088 -17.841313) (xy 44.913397 -17.882501)
			(xy 44.872208 -17.918191) (xy 44.826359 -17.947656) (xy 44.776783 -17.970296) (xy 44.72449 -17.98565)
			(xy 44.670544 -17.993405) (xy 44.643294 -17.993868) (xy 43.779694 -17.993868) (xy 43.75244 -17.993462)
			(xy 43.698487 -17.985704) (xy 43.646188 -17.970346) (xy 43.596606 -17.947703) (xy 43.550752 -17.918233)
			(xy 43.509558 -17.882538) (xy 43.473863 -17.841343) (xy 43.444395 -17.795488) (xy 43.421751 -17.745906)
			(xy 43.406395 -17.693607) (xy 43.398638 -17.639654) (xy 39.130505 -17.639654) (xy 39.122748 -17.693598)
			(xy 39.107392 -17.745892) (xy 39.084751 -17.795469) (xy 39.055284 -17.841318) (xy 39.019591 -17.882507)
			(xy 38.9784 -17.918197) (xy 38.932549 -17.947661) (xy 38.882972 -17.9703) (xy 38.830677 -17.985653)
			(xy 38.776729 -17.993406) (xy 38.749478 -17.993868) (xy 37.885878 -17.993868) (xy 37.858625 -17.993461)
			(xy 37.804674 -17.985701) (xy 37.752376 -17.970342) (xy 37.702797 -17.947697) (xy 37.656944 -17.918227)
			(xy 37.615752 -17.882532) (xy 37.580059 -17.841338) (xy 37.550592 -17.795484) (xy 37.52795 -17.745903)
			(xy 37.512595 -17.693605) (xy 37.504838 -17.639653) (xy 33.542505 -17.639653) (xy 33.534748 -17.693598)
			(xy 33.519392 -17.745892) (xy 33.496751 -17.795469) (xy 33.467284 -17.841318) (xy 33.431591 -17.882507)
			(xy 33.3904 -17.918197) (xy 33.344549 -17.947661) (xy 33.294972 -17.9703) (xy 33.242677 -17.985653)
			(xy 33.188729 -17.993406) (xy 33.161478 -17.993868) (xy 32.297878 -17.993868) (xy 32.270625 -17.993461)
			(xy 32.216674 -17.985701) (xy 32.164376 -17.970342) (xy 32.114797 -17.947697) (xy 32.068944 -17.918227)
			(xy 32.027752 -17.882532) (xy 31.992059 -17.841338) (xy 31.962592 -17.795484) (xy 31.93995 -17.745903)
			(xy 31.924595 -17.693605) (xy 31.916838 -17.639653) (xy 27.954505 -17.639653) (xy 27.946748 -17.693598)
			(xy 27.931392 -17.745892) (xy 27.908751 -17.795469) (xy 27.879284 -17.841318) (xy 27.843591 -17.882507)
			(xy 27.8024 -17.918197) (xy 27.756549 -17.947661) (xy 27.706972 -17.9703) (xy 27.654677 -17.985653)
			(xy 27.600729 -17.993406) (xy 27.573478 -17.993868) (xy 26.709878 -17.993868) (xy 26.682625 -17.993461)
			(xy 26.628674 -17.985701) (xy 26.576376 -17.970342) (xy 26.526797 -17.947697) (xy 26.480944 -17.918227)
			(xy 26.439752 -17.882532) (xy 26.404059 -17.841338) (xy 26.374592 -17.795484) (xy 26.35195 -17.745903)
			(xy 26.336595 -17.693605) (xy 26.328838 -17.639653) (xy 22.366505 -17.639653) (xy 22.358748 -17.693598)
			(xy 22.343392 -17.745892) (xy 22.320751 -17.795469) (xy 22.291284 -17.841318) (xy 22.255591 -17.882507)
			(xy 22.2144 -17.918197) (xy 22.168549 -17.947661) (xy 22.118972 -17.9703) (xy 22.066677 -17.985653)
			(xy 22.012729 -17.993406) (xy 21.985478 -17.993868) (xy 21.121878 -17.993868) (xy 21.094627 -17.993382)
			(xy 21.040679 -17.985625) (xy 20.988385 -17.97027) (xy 20.938808 -17.947629) (xy 20.892958 -17.918162)
			(xy 20.851768 -17.882471) (xy 20.816076 -17.841281) (xy 20.78661 -17.79543) (xy 20.763969 -17.745853)
			(xy 20.748614 -17.693559) (xy 20.740858 -17.639611) (xy 16.778525 -17.639611) (xy 16.778525 -17.639613)
			(xy 16.770768 -17.693564) (xy 16.755412 -17.745862) (xy 16.732769 -17.795442) (xy 16.703301 -17.841296)
			(xy 16.667607 -17.882488) (xy 16.626414 -17.918182) (xy 16.580561 -17.94765) (xy 16.53098 -17.970292)
			(xy 16.478682 -17.985648) (xy 16.424731 -17.993405) (xy 16.397478 -17.993868) (xy 15.533878 -17.993868)
			(xy 15.506627 -17.993382) (xy 15.452679 -17.985625) (xy 15.400385 -17.97027) (xy 15.350808 -17.947629)
			(xy 15.304958 -17.918162) (xy 15.263768 -17.882471) (xy 15.228076 -17.841281) (xy 15.19861 -17.79543)
			(xy 15.175969 -17.745853) (xy 15.160614 -17.693559) (xy 15.152858 -17.639611) (xy 0.509016 -17.639611)
			(xy 0.509016 -18.171947) (xy 131.633522 -18.171947) (xy 131.633522 -18.117453) (xy 131.641277 -18.063515)
			(xy 131.656629 -18.011229) (xy 131.679265 -17.961659) (xy 131.708725 -17.915816) (xy 131.744409 -17.874631)
			(xy 131.78559 -17.838944) (xy 131.831431 -17.80948) (xy 131.880999 -17.78684) (xy 131.933283 -17.771484)
			(xy 131.987221 -17.763724) (xy 132.014468 -17.763236) (xy 132.878068 -17.763236) (xy 132.905326 -17.763609)
			(xy 132.959286 -17.771363) (xy 133.011594 -17.786718) (xy 133.061184 -17.809361) (xy 133.107046 -17.838832)
			(xy 133.148248 -17.87453) (xy 133.183949 -17.915728) (xy 133.213423 -17.961588) (xy 133.236071 -18.011176)
			(xy 133.25143 -18.063483) (xy 133.259189 -18.117443) (xy 133.259189 -18.17195) (xy 137.033499 -18.17195)
			(xy 137.033499 -18.11745) (xy 137.041256 -18.063505) (xy 137.05661 -18.011212) (xy 137.079251 -17.961637)
			(xy 137.108716 -17.915789) (xy 137.144406 -17.874601) (xy 137.185595 -17.838911) (xy 137.231444 -17.809447)
			(xy 137.28102 -17.786807) (xy 137.333312 -17.771454) (xy 137.387258 -17.763699) (xy 137.414508 -17.763236)
			(xy 138.278108 -17.763236) (xy 138.305362 -17.763634) (xy 138.359315 -17.771393) (xy 138.411615 -17.78675)
			(xy 138.461197 -17.809395) (xy 138.507052 -17.838864) (xy 138.548246 -17.87456) (xy 138.58394 -17.915755)
			(xy 138.613409 -17.96161) (xy 138.636052 -18.011193) (xy 138.651409 -18.063493) (xy 138.659166 -18.117446)
			(xy 138.659166 -18.171946) (xy 140.633522 -18.171946) (xy 140.633522 -18.117454) (xy 140.641276 -18.063517)
			(xy 140.656627 -18.011232) (xy 140.679262 -17.961664) (xy 140.70872 -17.915822) (xy 140.744402 -17.874638)
			(xy 140.785582 -17.83895) (xy 140.83142 -17.809486) (xy 140.880986 -17.786845) (xy 140.933268 -17.771487)
			(xy 140.987204 -17.763726) (xy 141.01445 -17.763236) (xy 141.87805 -17.763236) (xy 141.905308 -17.763608)
			(xy 141.959271 -17.77136) (xy 142.011581 -17.786713) (xy 142.061173 -17.809355) (xy 142.107038 -17.838825)
			(xy 142.148241 -17.874523) (xy 142.183945 -17.915722) (xy 142.213421 -17.961583) (xy 142.236069 -18.011172)
			(xy 142.25143 -18.06348) (xy 142.259189 -18.117442) (xy 142.259189 -18.171951) (xy 185.748399 -18.171951)
			(xy 185.748399 -18.117449) (xy 185.756156 -18.063503) (xy 185.771511 -18.011209) (xy 185.794153 -17.961633)
			(xy 185.823619 -17.915784) (xy 185.859311 -17.874596) (xy 185.900502 -17.838906) (xy 185.946353 -17.809442)
			(xy 185.99593 -17.786804) (xy 186.048224 -17.771451) (xy 186.102171 -17.763698) (xy 186.129422 -17.763236)
			(xy 186.993022 -17.763236) (xy 187.020275 -17.763635) (xy 187.074227 -17.771395) (xy 187.126525 -17.786754)
			(xy 187.176105 -17.809399) (xy 187.201242 -17.825555) (xy 218.803143 -17.825555) (xy 218.803143 -17.771045)
			(xy 218.810901 -17.717091) (xy 218.826258 -17.66479) (xy 218.848903 -17.615207) (xy 218.878374 -17.569351)
			(xy 218.914071 -17.528157) (xy 218.955267 -17.492462) (xy 219.001124 -17.462993) (xy 219.050709 -17.440351)
			(xy 219.10301 -17.424996) (xy 219.156965 -17.417242) (xy 219.18422 -17.41678) (xy 220.04782 -17.41678)
			(xy 220.075069 -17.417292) (xy 220.129013 -17.42505) (xy 220.181304 -17.440407) (xy 220.230877 -17.463048)
			(xy 220.276723 -17.492514) (xy 220.31791 -17.528204) (xy 220.353598 -17.569393) (xy 220.383062 -17.615241)
			(xy 220.4057 -17.664815) (xy 220.421054 -17.717106) (xy 220.42881 -17.771051) (xy 220.42881 -17.825549)
			(xy 220.421054 -17.879494) (xy 220.4057 -17.931785) (xy 220.383062 -17.981359) (xy 220.353598 -18.027207)
			(xy 220.31791 -18.068396) (xy 220.276723 -18.104086) (xy 220.230877 -18.133552) (xy 220.181304 -18.156193)
			(xy 220.129013 -18.17155) (xy 220.075069 -18.179308) (xy 220.04782 -18.179796) (xy 219.18422 -18.179796)
			(xy 219.156965 -18.179358) (xy 219.10301 -18.171604) (xy 219.050709 -18.156249) (xy 219.001124 -18.133607)
			(xy 218.955267 -18.104138) (xy 218.914071 -18.068443) (xy 218.878374 -18.027249) (xy 218.848903 -17.981393)
			(xy 218.826258 -17.93181) (xy 218.810901 -17.879509) (xy 218.803143 -17.825555) (xy 187.201242 -17.825555)
			(xy 187.221958 -17.838869) (xy 187.263151 -17.874565) (xy 187.298844 -17.915759) (xy 187.328311 -17.961614)
			(xy 187.350954 -18.011196) (xy 187.366309 -18.063495) (xy 187.374066 -18.117447) (xy 187.374066 -18.171953)
			(xy 187.366309 -18.225905) (xy 187.350954 -18.278204) (xy 187.328311 -18.327786) (xy 187.298844 -18.373641)
			(xy 187.263151 -18.414835) (xy 187.221958 -18.450531) (xy 187.176105 -18.480001) (xy 187.126525 -18.502646)
			(xy 187.074227 -18.518005) (xy 187.020275 -18.525765) (xy 186.993022 -18.526252) (xy 186.129422 -18.526252)
			(xy 186.102171 -18.525702) (xy 186.048224 -18.517949) (xy 185.99593 -18.502596) (xy 185.946353 -18.479958)
			(xy 185.900502 -18.450494) (xy 185.859311 -18.414804) (xy 185.823619 -18.373616) (xy 185.794153 -18.327767)
			(xy 185.771511 -18.278191) (xy 185.756156 -18.225897) (xy 185.748399 -18.171951) (xy 142.259189 -18.171951)
			(xy 142.259189 -18.171958) (xy 142.25143 -18.22592) (xy 142.236069 -18.278228) (xy 142.213421 -18.327817)
			(xy 142.183945 -18.373678) (xy 142.148241 -18.414877) (xy 142.107038 -18.450575) (xy 142.061173 -18.480045)
			(xy 142.011581 -18.502687) (xy 141.959271 -18.51804) (xy 141.905308 -18.525792) (xy 141.87805 -18.526252)
			(xy 141.01445 -18.526252) (xy 140.987204 -18.525674) (xy 140.933268 -18.517913) (xy 140.880986 -18.502555)
			(xy 140.83142 -18.479914) (xy 140.785582 -18.45045) (xy 140.744402 -18.414762) (xy 140.70872 -18.373578)
			(xy 140.679262 -18.327736) (xy 140.656627 -18.278168) (xy 140.641276 -18.225883) (xy 140.633522 -18.171946)
			(xy 138.659166 -18.171946) (xy 138.659166 -18.171954) (xy 138.651409 -18.225907) (xy 138.636052 -18.278207)
			(xy 138.613409 -18.32779) (xy 138.58394 -18.373645) (xy 138.548246 -18.41484) (xy 138.507052 -18.450536)
			(xy 138.461197 -18.480005) (xy 138.411615 -18.50265) (xy 138.359315 -18.518007) (xy 138.305362 -18.525766)
			(xy 138.278108 -18.526252) (xy 137.414508 -18.526252) (xy 137.387258 -18.525701) (xy 137.333312 -18.517946)
			(xy 137.28102 -18.502593) (xy 137.231444 -18.479953) (xy 137.185595 -18.450489) (xy 137.144406 -18.414799)
			(xy 137.108716 -18.373611) (xy 137.079251 -18.327763) (xy 137.05661 -18.278188) (xy 137.041256 -18.225895)
			(xy 137.033499 -18.17195) (xy 133.259189 -18.17195) (xy 133.259189 -18.171957) (xy 133.25143 -18.225917)
			(xy 133.236071 -18.278224) (xy 133.213423 -18.327812) (xy 133.183949 -18.373672) (xy 133.148248 -18.41487)
			(xy 133.107046 -18.450568) (xy 133.061184 -18.480039) (xy 133.011594 -18.502682) (xy 132.959286 -18.518037)
			(xy 132.905326 -18.525791) (xy 132.878068 -18.526252) (xy 132.014468 -18.526252) (xy 131.987221 -18.525676)
			(xy 131.933283 -18.517916) (xy 131.880999 -18.50256) (xy 131.831431 -18.47992) (xy 131.78559 -18.450456)
			(xy 131.744409 -18.414769) (xy 131.708725 -18.373584) (xy 131.679265 -18.327741) (xy 131.656629 -18.278171)
			(xy 131.641277 -18.225885) (xy 131.633522 -18.171947) (xy 0.509016 -18.171947) (xy 0.509016 -19.163611)
			(xy 17.946858 -19.163611) (xy 17.946858 -19.109109) (xy 17.954614 -19.055161) (xy 17.969969 -19.002867)
			(xy 17.99261 -18.95329) (xy 18.022076 -18.907439) (xy 18.057768 -18.866249) (xy 18.098958 -18.830558)
			(xy 18.144808 -18.801091) (xy 18.194385 -18.77845) (xy 18.246679 -18.763095) (xy 18.300627 -18.755338)
			(xy 18.327878 -18.754852) (xy 19.191478 -18.754852) (xy 19.218731 -18.755315) (xy 19.272682 -18.763072)
			(xy 19.32498 -18.778428) (xy 19.374561 -18.80107) (xy 19.420414 -18.830538) (xy 19.461607 -18.866232)
			(xy 19.497301 -18.907424) (xy 19.526769 -18.953278) (xy 19.549412 -19.002858) (xy 19.564768 -19.055156)
			(xy 19.572525 -19.109107) (xy 19.572525 -19.163613) (xy 19.572519 -19.163653) (xy 23.534838 -19.163653)
			(xy 23.534838 -19.109147) (xy 23.542595 -19.055195) (xy 23.55795 -19.002897) (xy 23.580592 -18.953316)
			(xy 23.610059 -18.907462) (xy 23.645752 -18.866268) (xy 23.686944 -18.830573) (xy 23.732797 -18.801103)
			(xy 23.782376 -18.778458) (xy 23.834674 -18.763099) (xy 23.888625 -18.755339) (xy 23.915878 -18.754852)
			(xy 24.779478 -18.754852) (xy 24.806729 -18.755394) (xy 24.860677 -18.763147) (xy 24.912972 -18.7785)
			(xy 24.962549 -18.801139) (xy 25.0084 -18.830603) (xy 25.049591 -18.866293) (xy 25.085284 -18.907482)
			(xy 25.114751 -18.953331) (xy 25.137392 -19.002908) (xy 25.152748 -19.055202) (xy 25.160505 -19.109149)
			(xy 25.160505 -19.163651) (xy 25.160505 -19.163653) (xy 29.122838 -19.163653) (xy 29.122838 -19.109147)
			(xy 29.130595 -19.055195) (xy 29.14595 -19.002897) (xy 29.168592 -18.953316) (xy 29.198059 -18.907462)
			(xy 29.233752 -18.866268) (xy 29.274944 -18.830573) (xy 29.320797 -18.801103) (xy 29.370376 -18.778458)
			(xy 29.422674 -18.763099) (xy 29.476625 -18.755339) (xy 29.503878 -18.754852) (xy 30.367478 -18.754852)
			(xy 30.394729 -18.755394) (xy 30.448677 -18.763147) (xy 30.500972 -18.7785) (xy 30.550549 -18.801139)
			(xy 30.5964 -18.830603) (xy 30.637591 -18.866293) (xy 30.673284 -18.907482) (xy 30.702751 -18.953331)
			(xy 30.725392 -19.002908) (xy 30.740748 -19.055202) (xy 30.748505 -19.109149) (xy 30.748505 -19.163651)
			(xy 30.748505 -19.163653) (xy 34.710838 -19.163653) (xy 34.710838 -19.109147) (xy 34.718595 -19.055195)
			(xy 34.73395 -19.002897) (xy 34.756592 -18.953316) (xy 34.786059 -18.907462) (xy 34.821752 -18.866268)
			(xy 34.862944 -18.830573) (xy 34.908797 -18.801103) (xy 34.958376 -18.778458) (xy 35.010674 -18.763099)
			(xy 35.064625 -18.755339) (xy 35.091878 -18.754852) (xy 35.955478 -18.754852) (xy 35.982729 -18.755394)
			(xy 36.036677 -18.763147) (xy 36.088972 -18.7785) (xy 36.138549 -18.801139) (xy 36.1844 -18.830603)
			(xy 36.225591 -18.866293) (xy 36.261284 -18.907482) (xy 36.290751 -18.953331) (xy 36.313392 -19.002908)
			(xy 36.328748 -19.055202) (xy 36.336505 -19.109149) (xy 36.336505 -19.163651) (xy 36.336505 -19.163654)
			(xy 40.604638 -19.163654) (xy 40.604638 -19.109146) (xy 40.612395 -19.055193) (xy 40.627751 -19.002894)
			(xy 40.650395 -18.953312) (xy 40.679863 -18.907457) (xy 40.715558 -18.866262) (xy 40.756752 -18.830567)
			(xy 40.802606 -18.801097) (xy 40.852188 -18.778454) (xy 40.904487 -18.763096) (xy 40.95844 -18.755338)
			(xy 40.985694 -18.754852) (xy 41.849294 -18.754852) (xy 41.876544 -18.755395) (xy 41.93049 -18.76315)
			(xy 41.982783 -18.778504) (xy 42.032359 -18.801144) (xy 42.078208 -18.830609) (xy 42.119397 -18.866299)
			(xy 42.155088 -18.907487) (xy 42.184553 -18.953336) (xy 42.207194 -19.002911) (xy 42.222548 -19.055204)
			(xy 42.230305 -19.10915) (xy 42.230305 -19.16365) (xy 42.230304 -19.163654) (xy 46.192638 -19.163654)
			(xy 46.192638 -19.109146) (xy 46.200395 -19.055193) (xy 46.215751 -19.002894) (xy 46.238395 -18.953312)
			(xy 46.267863 -18.907457) (xy 46.303558 -18.866262) (xy 46.344752 -18.830567) (xy 46.390606 -18.801097)
			(xy 46.440188 -18.778454) (xy 46.492487 -18.763096) (xy 46.54644 -18.755338) (xy 46.573694 -18.754852)
			(xy 47.437294 -18.754852) (xy 47.464544 -18.755395) (xy 47.51849 -18.76315) (xy 47.570783 -18.778504)
			(xy 47.620359 -18.801144) (xy 47.666208 -18.830609) (xy 47.707397 -18.866299) (xy 47.743088 -18.907487)
			(xy 47.772553 -18.953336) (xy 47.795194 -19.002911) (xy 47.810548 -19.055204) (xy 47.818305 -19.10915)
			(xy 47.818305 -19.16365) (xy 47.818304 -19.163657) (xy 51.814615 -19.163657) (xy 51.814615 -19.109143)
			(xy 51.822374 -19.055184) (xy 51.837733 -19.002878) (xy 51.86038 -18.95329) (xy 51.889854 -18.907431)
			(xy 51.925554 -18.866233) (xy 51.966755 -18.830536) (xy 52.012617 -18.801065) (xy 52.062206 -18.778422)
			(xy 52.114513 -18.763067) (xy 52.168473 -18.755313) (xy 52.19573 -18.754852) (xy 53.05933 -18.754852)
			(xy 53.086577 -18.75542) (xy 53.140516 -18.763179) (xy 53.192801 -18.778535) (xy 53.24237 -18.801176)
			(xy 53.288211 -18.83064) (xy 53.329394 -18.866328) (xy 53.365078 -18.907513) (xy 53.394538 -18.953357)
			(xy 53.417175 -19.002927) (xy 53.432527 -19.055214) (xy 53.440282 -19.109153) (xy 53.440282 -19.163647)
			(xy 53.440281 -19.163657) (xy 57.402615 -19.163657) (xy 57.402615 -19.109143) (xy 57.410374 -19.055184)
			(xy 57.425733 -19.002878) (xy 57.44838 -18.95329) (xy 57.477854 -18.907431) (xy 57.513554 -18.866233)
			(xy 57.554755 -18.830536) (xy 57.600617 -18.801065) (xy 57.650206 -18.778422) (xy 57.702513 -18.763067)
			(xy 57.756473 -18.755313) (xy 57.78373 -18.754852) (xy 58.64733 -18.754852) (xy 58.674577 -18.75542)
			(xy 58.728516 -18.763179) (xy 58.780801 -18.778535) (xy 58.83037 -18.801176) (xy 58.876211 -18.83064)
			(xy 58.917394 -18.866328) (xy 58.953078 -18.907513) (xy 58.982538 -18.953357) (xy 59.005175 -19.002927)
			(xy 59.020527 -19.055214) (xy 59.028282 -19.109153) (xy 59.028282 -19.163647) (xy 59.020527 -19.217586)
			(xy 59.005175 -19.269873) (xy 58.982538 -19.319443) (xy 58.953078 -19.365287) (xy 58.917394 -19.406472)
			(xy 58.876211 -19.44216) (xy 58.83037 -19.471624) (xy 58.780801 -19.494265) (xy 58.728516 -19.509621)
			(xy 58.674577 -19.51738) (xy 58.64733 -19.517868) (xy 57.78373 -19.517868) (xy 57.756473 -19.517487)
			(xy 57.702513 -19.509733) (xy 57.650206 -19.494378) (xy 57.600617 -19.471735) (xy 57.554755 -19.442264)
			(xy 57.513554 -19.406567) (xy 57.477854 -19.365369) (xy 57.44838 -19.31951) (xy 57.425733 -19.269922)
			(xy 57.410374 -19.217616) (xy 57.402615 -19.163657) (xy 53.440281 -19.163657) (xy 53.432527 -19.217586)
			(xy 53.417175 -19.269873) (xy 53.394538 -19.319443) (xy 53.365078 -19.365287) (xy 53.329394 -19.406472)
			(xy 53.288211 -19.44216) (xy 53.24237 -19.471624) (xy 53.192801 -19.494265) (xy 53.140516 -19.509621)
			(xy 53.086577 -19.51738) (xy 53.05933 -19.517868) (xy 52.19573 -19.517868) (xy 52.168473 -19.517487)
			(xy 52.114513 -19.509733) (xy 52.062206 -19.494378) (xy 52.012617 -19.471735) (xy 51.966755 -19.442264)
			(xy 51.925554 -19.406567) (xy 51.889854 -19.365369) (xy 51.86038 -19.31951) (xy 51.837733 -19.269922)
			(xy 51.822374 -19.217616) (xy 51.814615 -19.163657) (xy 47.818304 -19.163657) (xy 47.810548 -19.217596)
			(xy 47.795194 -19.269889) (xy 47.772553 -19.319464) (xy 47.743088 -19.365313) (xy 47.707397 -19.406501)
			(xy 47.666208 -19.442191) (xy 47.620359 -19.471656) (xy 47.570783 -19.494296) (xy 47.51849 -19.50965)
			(xy 47.464544 -19.517405) (xy 47.437294 -19.517868) (xy 46.573694 -19.517868) (xy 46.54644 -19.517462)
			(xy 46.492487 -19.509704) (xy 46.440188 -19.494346) (xy 46.390606 -19.471703) (xy 46.344752 -19.442233)
			(xy 46.303558 -19.406538) (xy 46.267863 -19.365343) (xy 46.238395 -19.319488) (xy 46.215751 -19.269906)
			(xy 46.200395 -19.217607) (xy 46.192638 -19.163654) (xy 42.230304 -19.163654) (xy 42.222548 -19.217596)
			(xy 42.207194 -19.269889) (xy 42.184553 -19.319464) (xy 42.155088 -19.365313) (xy 42.119397 -19.406501)
			(xy 42.078208 -19.442191) (xy 42.032359 -19.471656) (xy 41.982783 -19.494296) (xy 41.93049 -19.50965)
			(xy 41.876544 -19.517405) (xy 41.849294 -19.517868) (xy 40.985694 -19.517868) (xy 40.95844 -19.517462)
			(xy 40.904487 -19.509704) (xy 40.852188 -19.494346) (xy 40.802606 -19.471703) (xy 40.756752 -19.442233)
			(xy 40.715558 -19.406538) (xy 40.679863 -19.365343) (xy 40.650395 -19.319488) (xy 40.627751 -19.269906)
			(xy 40.612395 -19.217607) (xy 40.604638 -19.163654) (xy 36.336505 -19.163654) (xy 36.328748 -19.217598)
			(xy 36.313392 -19.269892) (xy 36.290751 -19.319469) (xy 36.261284 -19.365318) (xy 36.225591 -19.406507)
			(xy 36.1844 -19.442197) (xy 36.138549 -19.471661) (xy 36.088972 -19.4943) (xy 36.036677 -19.509653)
			(xy 35.982729 -19.517406) (xy 35.955478 -19.517868) (xy 35.091878 -19.517868) (xy 35.064625 -19.517461)
			(xy 35.010674 -19.509701) (xy 34.958376 -19.494342) (xy 34.908797 -19.471697) (xy 34.862944 -19.442227)
			(xy 34.821752 -19.406532) (xy 34.786059 -19.365338) (xy 34.756592 -19.319484) (xy 34.73395 -19.269903)
			(xy 34.718595 -19.217605) (xy 34.710838 -19.163653) (xy 30.748505 -19.163653) (xy 30.740748 -19.217598)
			(xy 30.725392 -19.269892) (xy 30.702751 -19.319469) (xy 30.673284 -19.365318) (xy 30.637591 -19.406507)
			(xy 30.5964 -19.442197) (xy 30.550549 -19.471661) (xy 30.500972 -19.4943) (xy 30.448677 -19.509653)
			(xy 30.394729 -19.517406) (xy 30.367478 -19.517868) (xy 29.503878 -19.517868) (xy 29.476625 -19.517461)
			(xy 29.422674 -19.509701) (xy 29.370376 -19.494342) (xy 29.320797 -19.471697) (xy 29.274944 -19.442227)
			(xy 29.233752 -19.406532) (xy 29.198059 -19.365338) (xy 29.168592 -19.319484) (xy 29.14595 -19.269903)
			(xy 29.130595 -19.217605) (xy 29.122838 -19.163653) (xy 25.160505 -19.163653) (xy 25.152748 -19.217598)
			(xy 25.137392 -19.269892) (xy 25.114751 -19.319469) (xy 25.085284 -19.365318) (xy 25.049591 -19.406507)
			(xy 25.0084 -19.442197) (xy 24.962549 -19.471661) (xy 24.912972 -19.4943) (xy 24.860677 -19.509653)
			(xy 24.806729 -19.517406) (xy 24.779478 -19.517868) (xy 23.915878 -19.517868) (xy 23.888625 -19.517461)
			(xy 23.834674 -19.509701) (xy 23.782376 -19.494342) (xy 23.732797 -19.471697) (xy 23.686944 -19.442227)
			(xy 23.645752 -19.406532) (xy 23.610059 -19.365338) (xy 23.580592 -19.319484) (xy 23.55795 -19.269903)
			(xy 23.542595 -19.217605) (xy 23.534838 -19.163653) (xy 19.572519 -19.163653) (xy 19.564768 -19.217564)
			(xy 19.549412 -19.269862) (xy 19.526769 -19.319442) (xy 19.497301 -19.365296) (xy 19.461607 -19.406488)
			(xy 19.420414 -19.442182) (xy 19.374561 -19.47165) (xy 19.32498 -19.494292) (xy 19.272682 -19.509648)
			(xy 19.218731 -19.517405) (xy 19.191478 -19.517868) (xy 18.327878 -19.517868) (xy 18.300627 -19.517382)
			(xy 18.246679 -19.509625) (xy 18.194385 -19.49427) (xy 18.144808 -19.471629) (xy 18.098958 -19.442162)
			(xy 18.057768 -19.406471) (xy 18.022076 -19.365281) (xy 17.99261 -19.31943) (xy 17.969969 -19.269853)
			(xy 17.954614 -19.217559) (xy 17.946858 -19.163611) (xy 0.509016 -19.163611) (xy 0.509016 -20.187751)
			(xy 138.828766 -20.187751) (xy 138.828766 -20.133249) (xy 138.836522 -20.079301) (xy 138.851877 -20.027006)
			(xy 138.874517 -19.977429) (xy 138.903982 -19.931578) (xy 138.939673 -19.890387) (xy 138.980862 -19.854694)
			(xy 139.026711 -19.825227) (xy 139.076288 -19.802584) (xy 139.128582 -19.787226) (xy 139.182529 -19.779467)
			(xy 139.20978 -19.77898) (xy 140.07338 -19.77898) (xy 140.100633 -19.779466) (xy 140.154584 -19.78722)
			(xy 140.206883 -19.802574) (xy 140.256464 -19.825215) (xy 140.302318 -19.854681) (xy 140.343512 -19.890374)
			(xy 140.379207 -19.931566) (xy 140.408676 -19.977418) (xy 140.431319 -20.026998) (xy 140.446675 -20.079296)
			(xy 140.454433 -20.133247) (xy 140.454433 -20.187753) (xy 140.446675 -20.241704) (xy 140.431319 -20.294002)
			(xy 140.408676 -20.343582) (xy 140.379207 -20.389434) (xy 140.343512 -20.430626) (xy 140.302318 -20.466319)
			(xy 140.256464 -20.495785) (xy 140.206883 -20.518426) (xy 140.154584 -20.53378) (xy 140.100633 -20.541534)
			(xy 140.07338 -20.541996) (xy 139.20978 -20.541996) (xy 139.182529 -20.541533) (xy 139.128582 -20.533774)
			(xy 139.076288 -20.518416) (xy 139.026711 -20.495773) (xy 138.980862 -20.466306) (xy 138.939673 -20.430613)
			(xy 138.903982 -20.389422) (xy 138.874517 -20.343571) (xy 138.851877 -20.293994) (xy 138.836522 -20.241699)
			(xy 138.828766 -20.187751) (xy 0.509016 -20.187751) (xy 0.509016 -21.521251) (xy 15.232366 -21.521251)
			(xy 15.232366 -21.466749) (xy 15.240122 -21.412801) (xy 15.255477 -21.360506) (xy 15.278117 -21.310929)
			(xy 15.307582 -21.265078) (xy 15.343273 -21.223887) (xy 15.384462 -21.188194) (xy 15.430311 -21.158727)
			(xy 15.479888 -21.136084) (xy 15.532182 -21.120726) (xy 15.586129 -21.112967) (xy 15.61338 -21.11248)
			(xy 16.47698 -21.11248) (xy 16.504233 -21.112966) (xy 16.558184 -21.12072) (xy 16.610483 -21.136074)
			(xy 16.660064 -21.158715) (xy 16.705918 -21.188181) (xy 16.747112 -21.223874) (xy 16.782807 -21.265066)
			(xy 16.812276 -21.310918) (xy 16.834919 -21.360498) (xy 16.850275 -21.412796) (xy 16.858033 -21.466747)
			(xy 16.858033 -21.521253) (xy 16.850275 -21.575204) (xy 16.834919 -21.627502) (xy 16.812276 -21.677082)
			(xy 16.782807 -21.722934) (xy 16.747112 -21.764126) (xy 16.705918 -21.799819) (xy 16.660064 -21.829285)
			(xy 16.610483 -21.851926) (xy 16.558184 -21.86728) (xy 16.504233 -21.875034) (xy 16.47698 -21.875496)
			(xy 15.61338 -21.875496) (xy 15.586129 -21.875033) (xy 15.532182 -21.867274) (xy 15.479888 -21.851916)
			(xy 15.430311 -21.829273) (xy 15.384462 -21.799806) (xy 15.343273 -21.764113) (xy 15.307582 -21.722922)
			(xy 15.278117 -21.677071) (xy 15.255477 -21.627494) (xy 15.240122 -21.575199) (xy 15.232366 -21.521251)
			(xy 0.509016 -21.521251) (xy 0.509016 -24.929338) (xy 133.555232 -24.929338) (xy 133.555232 -24.065738)
			(xy 133.555718 -24.038487) (xy 133.563474 -23.984539) (xy 133.578829 -23.932244) (xy 133.601471 -23.882667)
			(xy 133.630937 -23.836817) (xy 133.666628 -23.795626) (xy 133.707819 -23.759935) (xy 133.753669 -23.730469)
			(xy 133.803246 -23.707827) (xy 133.855541 -23.692472) (xy 133.909489 -23.684716) (xy 133.963991 -23.684716)
			(xy 134.017939 -23.692472) (xy 134.070234 -23.707827) (xy 134.119811 -23.730469) (xy 134.165661 -23.759935)
			(xy 134.206852 -23.795626) (xy 134.242543 -23.836817) (xy 134.272009 -23.882667) (xy 134.294651 -23.932244)
			(xy 134.310006 -23.984539) (xy 134.317762 -24.038487) (xy 134.318248 -24.065738) (xy 134.318248 -24.929338)
			(xy 134.317762 -24.956589) (xy 134.310006 -25.010537) (xy 134.294651 -25.062832) (xy 134.272009 -25.112409)
			(xy 134.242543 -25.158259) (xy 134.206852 -25.19945) (xy 134.165661 -25.235141) (xy 134.119811 -25.264607)
			(xy 134.070234 -25.287249) (xy 134.017939 -25.302604) (xy 133.963991 -25.31036) (xy 133.909489 -25.31036)
			(xy 133.855541 -25.302604) (xy 133.803246 -25.287249) (xy 133.753669 -25.264607) (xy 133.707819 -25.235141)
			(xy 133.666628 -25.19945) (xy 133.630937 -25.158259) (xy 133.601471 -25.112409) (xy 133.578829 -25.062832)
			(xy 133.563474 -25.010537) (xy 133.555718 -24.956589) (xy 133.555232 -24.929338) (xy 0.509016 -24.929338)
			(xy 0.509016 -29.070615) (xy 12.244307 -29.070615) (xy 12.252198 -28.941486) (xy 12.268182 -28.813107)
			(xy 12.292195 -28.685984) (xy 12.324144 -28.560621) (xy 12.363901 -28.437511) (xy 12.41131 -28.31714)
			(xy 12.466183 -28.199984) (xy 12.528305 -28.086504) (xy 12.59743 -27.97715) (xy 12.673285 -27.872351)
			(xy 12.75557 -27.772522) (xy 12.843962 -27.678057) (xy 12.938111 -27.589329) (xy 13.037646 -27.506688)
			(xy 13.142173 -27.43046) (xy 13.25128 -27.360945) (xy 13.364537 -27.298419) (xy 13.481497 -27.243128)
			(xy 13.601698 -27.19529) (xy 13.724665 -27.155093) (xy 13.849914 -27.122698) (xy 13.97695 -27.098231)
			(xy 14.105271 -27.081789) (xy 14.234372 -27.073437) (xy 14.363742 -27.073208) (xy 14.492871 -27.081103)
			(xy 14.62125 -27.097091) (xy 14.748372 -27.121108) (xy 14.873734 -27.15306) (xy 14.996843 -27.19282)
			(xy 15.117212 -27.240232) (xy 15.234367 -27.295109) (xy 15.347845 -27.357234) (xy 15.457198 -27.426362)
			(xy 15.561994 -27.50222) (xy 15.661821 -27.584508) (xy 15.709392 -27.628342) (xy 16.877792 -28.721304)
			(xy 16.92464 -28.765906) (xy 17.013363 -28.860052) (xy 17.096 -28.959584) (xy 17.172224 -29.064107)
			(xy 17.241734 -29.17321) (xy 17.304257 -29.286463) (xy 17.359545 -29.403418) (xy 17.407381 -29.523614)
			(xy 17.447575 -29.646576) (xy 17.479969 -29.771819) (xy 17.504435 -29.898849) (xy 17.520877 -30.027165)
			(xy 17.529229 -30.15626) (xy 17.529459 -30.285624) (xy 17.521566 -30.414748) (xy 17.50558 -30.543122)
			(xy 17.481566 -30.670238) (xy 17.449617 -30.795596) (xy 17.40986 -30.9187) (xy 17.362452 -31.039065)
			(xy 17.30758 -31.156215) (xy 17.24546 -31.26969) (xy 17.176338 -31.379039) (xy 17.100486 -31.483833)
			(xy 17.018204 -31.583657) (xy 16.929816 -31.678118) (xy 16.835671 -31.766843) (xy 16.736141 -31.849481)
			(xy 16.631619 -31.925706) (xy 16.522517 -31.995218) (xy 16.409265 -32.057743) (xy 16.292311 -32.113033)
			(xy 16.172116 -32.16087) (xy 16.049154 -32.201066) (xy 15.923911 -32.233462) (xy 15.796882 -32.25793)
			(xy 15.668566 -32.274374) (xy 15.539471 -32.282728) (xy 15.410107 -32.28296) (xy 15.280983 -32.275069)
			(xy 15.152609 -32.259085) (xy 15.025493 -32.235073) (xy 14.900134 -32.203126) (xy 14.77703 -32.163371)
			(xy 14.656664 -32.115965) (xy 14.539512 -32.061094) (xy 14.426037 -31.998976) (xy 14.316687 -31.929855)
			(xy 14.211892 -31.854005) (xy 14.112066 -31.771724) (xy 14.064488 -31.727902) (xy 12.896088 -30.63494)
			(xy 12.849198 -30.590378) (xy 12.760467 -30.496232) (xy 12.677823 -30.3967) (xy 12.601592 -30.292174)
			(xy 12.532074 -30.183069) (xy 12.469545 -30.069814) (xy 12.41425 -29.952855) (xy 12.366409 -29.832656)
			(xy 12.32621 -29.70969) (xy 12.293811 -29.584442) (xy 12.26934 -29.457407) (xy 12.252895 -29.329086)
			(xy 12.244539 -29.199985) (xy 12.244307 -29.070615) (xy 0.509016 -29.070615) (xy 0.509016 -37.099629)
			(xy 170.600616 -37.099629) (xy 170.600616 -37.000299) (xy 170.608608 -36.901292) (xy 170.624542 -36.803249)
			(xy 170.648313 -36.706806) (xy 170.679768 -36.612588) (xy 170.718701 -36.521208) (xy 170.764862 -36.433256)
			(xy 170.81795 -36.349304) (xy 170.877621 -36.269895) (xy 170.943489 -36.195546) (xy 171.015126 -36.126738)
			(xy 171.092067 -36.063918) (xy 171.173813 -36.007493) (xy 171.259835 -35.957828) (xy 171.349574 -35.915246)
			(xy 171.442448 -35.880024) (xy 171.537856 -35.852388) (xy 171.635178 -35.83252) (xy 171.733783 -35.820547)
			(xy 171.833032 -35.816548) (xy 171.932281 -35.820547) (xy 172.030886 -35.83252) (xy 172.128208 -35.852388)
			(xy 172.223616 -35.880024) (xy 172.31649 -35.915246) (xy 172.406229 -35.957828) (xy 172.492251 -36.007493)
			(xy 172.573997 -36.063918) (xy 172.650938 -36.126738) (xy 172.722575 -36.195546) (xy 172.788443 -36.269895)
			(xy 172.848114 -36.349304) (xy 172.901202 -36.433256) (xy 172.947363 -36.521208) (xy 172.986296 -36.612588)
			(xy 173.017751 -36.706806) (xy 173.041522 -36.803249) (xy 173.057456 -36.901292) (xy 173.065448 -37.000299)
			(xy 173.065948 -37.049964) (xy 173.065448 -37.099629) (xy 173.057456 -37.198636) (xy 173.041522 -37.296679)
			(xy 173.017751 -37.393122) (xy 172.986296 -37.48734) (xy 172.947363 -37.57872) (xy 172.901202 -37.666672)
			(xy 172.848114 -37.750624) (xy 172.788443 -37.830033) (xy 172.722575 -37.904382) (xy 172.650938 -37.97319)
			(xy 172.573997 -38.03601) (xy 172.492251 -38.092435) (xy 172.406229 -38.1421) (xy 172.31649 -38.184682)
			(xy 172.223616 -38.219904) (xy 172.128208 -38.24754) (xy 172.030886 -38.267408) (xy 171.932281 -38.279381)
			(xy 171.833032 -38.283381) (xy 171.733783 -38.279381) (xy 171.635178 -38.267408) (xy 171.537856 -38.24754)
			(xy 171.442448 -38.219904) (xy 171.349574 -38.184682) (xy 171.259835 -38.1421) (xy 171.173813 -38.092435)
			(xy 171.092067 -38.03601) (xy 171.015126 -37.97319) (xy 170.943489 -37.904382) (xy 170.877621 -37.830033)
			(xy 170.81795 -37.750624) (xy 170.764862 -37.666672) (xy 170.718701 -37.57872) (xy 170.679768 -37.48734)
			(xy 170.648313 -37.393122) (xy 170.624542 -37.296679) (xy 170.608608 -37.198636) (xy 170.600616 -37.099629)
			(xy 0.509016 -37.099629) (xy 0.509016 -39.657528) (xy 357.003604 -39.657528) (xy 357.003604 -38.793928)
			(xy 357.00409 -38.766659) (xy 357.011852 -38.712675) (xy 357.027217 -38.660345) (xy 357.049874 -38.610735)
			(xy 357.07936 -38.564854) (xy 357.115075 -38.523637) (xy 357.156292 -38.487922) (xy 357.202173 -38.458436)
			(xy 357.251783 -38.435779) (xy 357.304113 -38.420414) (xy 357.358097 -38.412652) (xy 357.412635 -38.412652)
			(xy 357.466619 -38.420414) (xy 357.518949 -38.435779) (xy 357.568559 -38.458436) (xy 357.61444 -38.487922)
			(xy 357.655657 -38.523637) (xy 357.691372 -38.564854) (xy 357.720858 -38.610735) (xy 357.743515 -38.660345)
			(xy 357.75888 -38.712675) (xy 357.766642 -38.766659) (xy 357.767128 -38.793928) (xy 357.767128 -39.657528)
			(xy 357.766642 -39.684797) (xy 357.75888 -39.738781) (xy 357.743515 -39.791111) (xy 357.720858 -39.840721)
			(xy 357.691372 -39.886602) (xy 357.655657 -39.927819) (xy 357.61444 -39.963534) (xy 357.568559 -39.99302)
			(xy 357.518949 -40.015677) (xy 357.466619 -40.031042) (xy 357.412635 -40.038804) (xy 357.358097 -40.038804)
			(xy 357.304113 -40.031042) (xy 357.251783 -40.015677) (xy 357.202173 -39.99302) (xy 357.156292 -39.963534)
			(xy 357.115075 -39.927819) (xy 357.07936 -39.886602) (xy 357.049874 -39.840721) (xy 357.027217 -39.791111)
			(xy 357.011852 -39.738781) (xy 357.00409 -39.684797) (xy 357.003604 -39.657528) (xy 0.509016 -39.657528)
			(xy 0.509016 -40.744902) (xy 235.083357 -40.744902) (xy 235.087362 -40.656994) (xy 235.099345 -40.569814)
			(xy 235.119205 -40.484085) (xy 235.14678 -40.400517) (xy 235.181839 -40.319803) (xy 235.224092 -40.242611)
			(xy 235.27319 -40.169582) (xy 235.328726 -40.10132) (xy 235.390238 -40.03839) (xy 235.457219 -39.981316)
			(xy 235.529112 -39.930568) (xy 235.605321 -39.886568) (xy 235.685216 -39.849681) (xy 235.768135 -39.820212)
			(xy 235.85339 -39.798405) (xy 235.940274 -39.784441) (xy 236.028068 -39.778435) (xy 236.116045 -39.780439)
			(xy 236.203475 -39.790434) (xy 236.289634 -39.808338) (xy 236.373808 -39.834002) (xy 236.455299 -39.867215)
			(xy 236.533433 -39.907701) (xy 236.607561 -39.955123) (xy 236.677069 -40.00909) (xy 236.741383 -40.069155)
			(xy 236.799967 -40.134819) (xy 236.852338 -40.205538) (xy 236.898061 -40.280726) (xy 236.936758 -40.359761)
			(xy 236.968107 -40.441987) (xy 236.991849 -40.526723) (xy 237.007787 -40.613267) (xy 237.015789 -40.700902)
			(xy 237.01629 -40.744902) (xy 237.015789 -40.788902) (xy 237.007787 -40.876537) (xy 236.991849 -40.963081)
			(xy 236.968107 -41.047817) (xy 236.936758 -41.130043) (xy 236.898061 -41.209078) (xy 236.852338 -41.284266)
			(xy 236.799967 -41.354985) (xy 236.741383 -41.420649) (xy 236.677069 -41.480714) (xy 236.607561 -41.534681)
			(xy 236.533433 -41.582103) (xy 236.455299 -41.622589) (xy 236.373808 -41.655802) (xy 236.289634 -41.681466)
			(xy 236.203475 -41.69937) (xy 236.116045 -41.709365) (xy 236.028068 -41.711369) (xy 235.940274 -41.705363)
			(xy 235.85339 -41.691399) (xy 235.768135 -41.669592) (xy 235.685216 -41.640123) (xy 235.605321 -41.603236)
			(xy 235.529112 -41.559236) (xy 235.457219 -41.508488) (xy 235.390238 -41.451414) (xy 235.328726 -41.388484)
			(xy 235.27319 -41.320222) (xy 235.224092 -41.247193) (xy 235.181839 -41.170001) (xy 235.14678 -41.089287)
			(xy 235.119205 -41.005719) (xy 235.099345 -40.91999) (xy 235.087362 -40.83281) (xy 235.083357 -40.744902)
			(xy 0.509016 -40.744902) (xy 0.509016 -43.999912) (xy 16.983969 -43.999912) (xy 16.987993 -43.914144)
			(xy 17.000031 -43.82913) (xy 17.019978 -43.745616) (xy 17.047657 -43.664337) (xy 17.082825 -43.586008)
			(xy 17.125174 -43.511315) (xy 17.174331 -43.440917) (xy 17.229864 -43.375431) (xy 17.291286 -43.315433)
			(xy 17.358055 -43.26145) (xy 17.429587 -43.213957) (xy 17.505251 -43.173371) (xy 17.584384 -43.140048)
			(xy 17.666289 -43.114282) (xy 17.750247 -43.096299) (xy 17.835521 -43.086257) (xy 17.92136 -43.084244)
			(xy 18.00701 -43.090278) (xy 18.091718 -43.104306) (xy 18.174741 -43.126205) (xy 18.255349 -43.155782)
			(xy 18.332833 -43.192777) (xy 18.406512 -43.236865) (xy 18.475738 -43.287659) (xy 18.539905 -43.344712)
			(xy 18.598446 -43.407523) (xy 18.650849 -43.47554) (xy 18.696652 -43.548165) (xy 18.735453 -43.62476)
			(xy 18.766912 -43.704652) (xy 18.790751 -43.787139) (xy 18.806761 -43.871496) (xy 18.814801 -43.956981)
			(xy 18.815304 -43.999912) (xy 18.814801 -44.042843) (xy 18.806761 -44.128328) (xy 18.790751 -44.212685)
			(xy 18.766912 -44.295172) (xy 18.735453 -44.375064) (xy 18.696652 -44.451659) (xy 18.650849 -44.524284)
			(xy 18.598446 -44.592301) (xy 18.539905 -44.655112) (xy 18.475738 -44.712165) (xy 18.406512 -44.762959)
			(xy 18.332833 -44.807047) (xy 18.255349 -44.844042) (xy 18.174741 -44.873619) (xy 18.091718 -44.895518)
			(xy 18.00701 -44.909546) (xy 17.92136 -44.91558) (xy 17.835521 -44.913567) (xy 17.750247 -44.903525)
			(xy 17.666289 -44.885542) (xy 17.584384 -44.859776) (xy 17.505251 -44.826453) (xy 17.429587 -44.785867)
			(xy 17.358055 -44.738374) (xy 17.291286 -44.684391) (xy 17.229864 -44.624393) (xy 17.174331 -44.558907)
			(xy 17.125174 -44.488509) (xy 17.082825 -44.413816) (xy 17.047657 -44.335487) (xy 17.019978 -44.254208)
			(xy 17.000031 -44.170694) (xy 16.987993 -44.08568) (xy 16.983969 -43.999912) (xy 0.509016 -43.999912)
			(xy 0.509016 -47.049813) (xy 59.781451 -47.049813) (xy 59.785436 -46.895317) (xy 59.79737 -46.74123)
			(xy 59.817219 -46.587962) (xy 59.844933 -46.43592) (xy 59.880436 -46.285505) (xy 59.923635 -46.137118)
			(xy 59.974415 -45.991151) (xy 60.032642 -45.847991) (xy 60.098162 -45.708019) (xy 60.1708 -45.571605)
			(xy 60.250363 -45.439111) (xy 60.336642 -45.310889) (xy 60.429407 -45.187278) (xy 60.528412 -45.068606)
			(xy 60.633395 -44.955188) (xy 60.744077 -44.847324) (xy 60.860165 -44.745302) (xy 60.981351 -44.64939)
			(xy 61.107313 -44.559844) (xy 61.237718 -44.476901) (xy 61.37222 -44.400781) (xy 61.510462 -44.331685)
			(xy 61.652077 -44.269798) (xy 61.796691 -44.215282) (xy 61.943919 -44.168283) (xy 62.093371 -44.128926)
			(xy 62.244652 -44.097314) (xy 62.397358 -44.073531) (xy 62.551087 -44.057641) (xy 62.70543 -44.049685)
			(xy 62.782704 -44.049188) (xy 64.383158 -44.049188) (xy 64.460432 -44.049684) (xy 64.614774 -44.057653)
			(xy 64.768502 -44.073557) (xy 64.921207 -44.097353) (xy 65.072484 -44.128978) (xy 65.221933 -44.168349)
			(xy 65.369158 -44.21536) (xy 65.513767 -44.269888) (xy 65.655377 -44.331788) (xy 65.793613 -44.400896)
			(xy 65.928108 -44.477028) (xy 66.058506 -44.559982) (xy 66.184461 -44.649539) (xy 66.305639 -44.745461)
			(xy 66.421718 -44.847494) (xy 66.532391 -44.955367) (xy 66.637364 -45.068794) (xy 66.736359 -45.187475)
			(xy 66.829113 -45.311094) (xy 66.915381 -45.439324) (xy 66.994934 -45.571824) (xy 67.06756 -45.708245)
			(xy 67.133068 -45.848223) (xy 67.191283 -45.991387) (xy 67.242051 -46.137359) (xy 67.285237 -46.28575)
			(xy 67.320727 -46.436168) (xy 67.348428 -46.588213) (xy 67.368264 -46.741483) (xy 67.380185 -46.89557)
			(xy 67.384154 -47.04994) (xy 89.78165 -47.04994) (xy 89.78563 -46.895439) (xy 89.797557 -46.741349)
			(xy 89.817402 -46.588076) (xy 89.84511 -46.436028) (xy 89.880608 -46.285609) (xy 89.923803 -46.137216)
			(xy 89.97458 -45.991243) (xy 90.032804 -45.848078) (xy 90.098321 -45.708101) (xy 90.170957 -45.571681)
			(xy 90.250519 -45.439181) (xy 90.336796 -45.310953) (xy 90.42956 -45.187337) (xy 90.528565 -45.068659)
			(xy 90.633548 -44.955236) (xy 90.74423 -44.847368) (xy 90.860319 -44.74534) (xy 90.981506 -44.649424)
			(xy 91.10747 -44.559873) (xy 91.237877 -44.476926) (xy 91.372381 -44.400801) (xy 91.510626 -44.331702)
			(xy 91.652244 -44.269811) (xy 91.796861 -44.215293) (xy 91.944092 -44.168291) (xy 92.093548 -44.128931)
			(xy 92.244832 -44.097317) (xy 92.397543 -44.073533) (xy 92.551275 -44.057642) (xy 92.705622 -44.049686)
			(xy 92.782898 -44.049188) (xy 94.383098 -44.049188) (xy 94.460374 -44.049669) (xy 94.614722 -44.057625)
			(xy 94.768456 -44.073516) (xy 94.921168 -44.0973) (xy 95.072452 -44.128914) (xy 95.221909 -44.168274)
			(xy 95.369142 -44.215276) (xy 95.513759 -44.269795) (xy 95.655379 -44.331686) (xy 95.793624 -44.400785)
			(xy 95.928129 -44.47691) (xy 96.058537 -44.559858) (xy 96.184502 -44.649409) (xy 96.30569 -44.745326)
			(xy 96.421779 -44.847354) (xy 96.532463 -44.955223) (xy 96.637446 -45.068647) (xy 96.736452 -45.187325)
			(xy 96.829216 -45.310943) (xy 96.915495 -45.439171) (xy 96.995057 -45.571672) (xy 97.038059 -45.652436)
			(xy 155.97378 -45.652436) (xy 155.97378 -44.788836) (xy 155.974266 -44.761567) (xy 155.982028 -44.707583)
			(xy 155.997393 -44.655253) (xy 156.02005 -44.605643) (xy 156.049536 -44.559762) (xy 156.085251 -44.518545)
			(xy 156.126468 -44.48283) (xy 156.172349 -44.453344) (xy 156.221959 -44.430687) (xy 156.274289 -44.415322)
			(xy 156.328273 -44.40756) (xy 156.382811 -44.40756) (xy 156.436795 -44.415322) (xy 156.489125 -44.430687)
			(xy 156.538735 -44.453344) (xy 156.584616 -44.48283) (xy 156.625833 -44.518545) (xy 156.661548 -44.559762)
			(xy 156.691034 -44.605643) (xy 156.713691 -44.655253) (xy 156.72159 -44.682156) (xy 159.179768 -44.682156)
			(xy 159.179768 -43.818556) (xy 159.180254 -43.791287) (xy 159.188016 -43.737303) (xy 159.203381 -43.684973)
			(xy 159.226038 -43.635363) (xy 159.255524 -43.589482) (xy 159.291239 -43.548265) (xy 159.332456 -43.51255)
			(xy 159.378337 -43.483064) (xy 159.427947 -43.460407) (xy 159.480277 -43.445042) (xy 159.534261 -43.43728)
			(xy 159.588799 -43.43728) (xy 159.642783 -43.445042) (xy 159.695113 -43.460407) (xy 159.74185 -43.481752)
			(xy 178.891692 -43.481752) (xy 178.891692 -42.618152) (xy 178.892178 -42.590901) (xy 178.899934 -42.536953)
			(xy 178.915289 -42.484658) (xy 178.937931 -42.435081) (xy 178.967397 -42.389231) (xy 179.003088 -42.34804)
			(xy 179.044279 -42.312349) (xy 179.090129 -42.282883) (xy 179.139706 -42.260241) (xy 179.192001 -42.244886)
			(xy 179.245949 -42.23713) (xy 179.300451 -42.23713) (xy 179.354399 -42.244886) (xy 179.406694 -42.260241)
			(xy 179.456271 -42.282883) (xy 179.502121 -42.312349) (xy 179.543312 -42.34804) (xy 179.579003 -42.389231)
			(xy 179.608469 -42.435081) (xy 179.631111 -42.484658) (xy 179.646466 -42.536953) (xy 179.654222 -42.590901)
			(xy 179.654708 -42.618152) (xy 179.654708 -43.481752) (xy 179.654222 -43.509003) (xy 179.647839 -43.5534)
			(xy 353.767583 -43.5534) (xy 353.771544 -43.500544) (xy 353.783339 -43.44887) (xy 353.802705 -43.39953)
			(xy 353.829208 -43.353628) (xy 353.862256 -43.312189) (xy 353.901112 -43.276139) (xy 353.944908 -43.246283)
			(xy 353.992664 -43.223289) (xy 354.043314 -43.207669) (xy 354.095726 -43.199773) (xy 354.122228 -43.199304)
			(xy 354.122736 -43.199304) (xy 354.153713 -43.199978) (xy 354.214715 -43.210807) (xy 354.272905 -43.232077)
			(xy 354.300028 -43.247056) (xy 354.328004 -43.238767) (xy 354.385663 -43.229845) (xy 354.414836 -43.229276)
			(xy 354.99548 -43.229276) (xy 355.004624 -43.225466) (xy 355.025917 -43.217194) (xy 355.070087 -43.205543)
			(xy 355.115388 -43.199665) (xy 355.138228 -43.199304) (xy 355.162681 -43.199729) (xy 355.211118 -43.206478)
			(xy 355.25817 -43.219815) (xy 355.280722 -43.229276) (xy 355.307866 -43.229907) (xy 355.361565 -43.237931)
			(xy 355.413585 -43.253486) (xy 355.462874 -43.276259) (xy 355.508436 -43.305789) (xy 355.549352 -43.341481)
			(xy 355.584795 -43.382612) (xy 355.61405 -43.428352) (xy 355.636524 -43.477777) (xy 355.651765 -43.52989)
			(xy 355.659465 -43.583636) (xy 355.659944 -43.610784) (xy 355.659468 -43.634951) (xy 356.178591 -43.634951)
			(xy 356.178591 -43.580449) (xy 356.186348 -43.526502) (xy 356.201703 -43.474208) (xy 356.224344 -43.424632)
			(xy 356.253811 -43.378783) (xy 356.289502 -43.337594) (xy 356.330692 -43.301903) (xy 356.376543 -43.272438)
			(xy 356.42612 -43.249799) (xy 356.478414 -43.234445) (xy 356.532361 -43.22669) (xy 356.559612 -43.226228)
			(xy 357.423212 -43.226228) (xy 357.450465 -43.226643) (xy 357.504417 -43.234401) (xy 357.556715 -43.249759)
			(xy 357.606295 -43.272403) (xy 357.652149 -43.301872) (xy 357.693341 -43.337567) (xy 357.729035 -43.378761)
			(xy 357.758503 -43.424615) (xy 357.781145 -43.474196) (xy 357.796501 -43.526495) (xy 357.804258 -43.580447)
			(xy 357.804258 -43.634953) (xy 357.803812 -43.638056) (xy 358.339039 -43.638056) (xy 358.339039 -43.583544)
			(xy 358.346797 -43.529588) (xy 358.362156 -43.477285) (xy 358.384802 -43.4277) (xy 358.414274 -43.381843)
			(xy 358.449974 -43.340648) (xy 358.491172 -43.304953) (xy 358.537032 -43.275485) (xy 358.586619 -43.252843)
			(xy 358.638923 -43.23749) (xy 358.69288 -43.229736) (xy 358.720136 -43.229276) (xy 359.583736 -43.229276)
			(xy 359.610984 -43.229797) (xy 359.664926 -43.237557) (xy 359.717214 -43.252915) (xy 359.766785 -43.275557)
			(xy 359.812629 -43.305023) (xy 359.853813 -43.340713) (xy 359.889499 -43.3819) (xy 359.91896 -43.427747)
			(xy 359.941598 -43.47732) (xy 359.956951 -43.529609) (xy 359.964706 -43.583552) (xy 359.964706 -43.638048)
			(xy 359.956951 -43.691991) (xy 359.941598 -43.74428) (xy 359.91896 -43.793853) (xy 359.889499 -43.8397)
			(xy 359.853813 -43.880887) (xy 359.812629 -43.916577) (xy 359.766785 -43.946043) (xy 359.717214 -43.968685)
			(xy 359.664926 -43.984043) (xy 359.610984 -43.991803) (xy 359.583736 -43.992292) (xy 358.720136 -43.992292)
			(xy 358.69288 -43.991864) (xy 358.638923 -43.98411) (xy 358.586619 -43.968757) (xy 358.537032 -43.946115)
			(xy 358.491172 -43.916647) (xy 358.449974 -43.880952) (xy 358.414274 -43.839757) (xy 358.384802 -43.7939)
			(xy 358.362156 -43.744315) (xy 358.346797 -43.692012) (xy 358.339039 -43.638056) (xy 357.803812 -43.638056)
			(xy 357.796501 -43.688905) (xy 357.781145 -43.741204) (xy 357.758503 -43.790785) (xy 357.729035 -43.836639)
			(xy 357.693341 -43.877833) (xy 357.652149 -43.913528) (xy 357.606295 -43.942997) (xy 357.556715 -43.965641)
			(xy 357.504417 -43.980999) (xy 357.450465 -43.988757) (xy 357.423212 -43.989244) (xy 356.559612 -43.989244)
			(xy 356.532361 -43.98871) (xy 356.478414 -43.980955) (xy 356.42612 -43.965601) (xy 356.376543 -43.942962)
			(xy 356.330692 -43.913497) (xy 356.289502 -43.877806) (xy 356.253811 -43.836617) (xy 356.224344 -43.790768)
			(xy 356.201703 -43.741192) (xy 356.186348 -43.688898) (xy 356.178591 -43.634951) (xy 355.659468 -43.634951)
			(xy 355.659407 -43.638033) (xy 355.651654 -43.691977) (xy 355.636302 -43.744269) (xy 355.613666 -43.793843)
			(xy 355.584204 -43.839692) (xy 355.548518 -43.880882) (xy 355.507334 -43.916573) (xy 355.461489 -43.946041)
			(xy 355.411917 -43.968684) (xy 355.359628 -43.984043) (xy 355.305685 -43.991803) (xy 355.278436 -43.992292)
			(xy 354.414836 -43.992292) (xy 354.388369 -43.991825) (xy 354.335944 -43.984518) (xy 354.285033 -43.970025)
			(xy 354.236619 -43.948625) (xy 354.191633 -43.920731) (xy 354.170996 -43.904154) (xy 354.158864 -43.905712)
			(xy 354.134459 -43.907367) (xy 354.122228 -43.907456) (xy 354.095726 -43.907027) (xy 354.043314 -43.899131)
			(xy 353.992664 -43.883511) (xy 353.944908 -43.860517) (xy 353.901112 -43.830661) (xy 353.862256 -43.794611)
			(xy 353.829208 -43.753172) (xy 353.802705 -43.70727) (xy 353.783339 -43.65793) (xy 353.771544 -43.606256)
			(xy 353.767583 -43.5534) (xy 179.647839 -43.5534) (xy 179.646466 -43.562951) (xy 179.631111 -43.615246)
			(xy 179.608469 -43.664823) (xy 179.579003 -43.710673) (xy 179.543312 -43.751864) (xy 179.502121 -43.787555)
			(xy 179.456271 -43.817021) (xy 179.406694 -43.839663) (xy 179.354399 -43.855018) (xy 179.300451 -43.862774)
			(xy 179.245949 -43.862774) (xy 179.192001 -43.855018) (xy 179.139706 -43.839663) (xy 179.090129 -43.817021)
			(xy 179.044279 -43.787555) (xy 179.003088 -43.751864) (xy 178.967397 -43.710673) (xy 178.937931 -43.664823)
			(xy 178.915289 -43.615246) (xy 178.899934 -43.562951) (xy 178.892178 -43.509003) (xy 178.891692 -43.481752)
			(xy 159.74185 -43.481752) (xy 159.744723 -43.483064) (xy 159.790604 -43.51255) (xy 159.831821 -43.548265)
			(xy 159.867536 -43.589482) (xy 159.897022 -43.635363) (xy 159.919679 -43.684973) (xy 159.935044 -43.737303)
			(xy 159.942806 -43.791287) (xy 159.943292 -43.818556) (xy 159.943292 -44.682156) (xy 159.942806 -44.709425)
			(xy 159.935044 -44.763409) (xy 159.919679 -44.815739) (xy 159.897022 -44.865349) (xy 159.867536 -44.91123)
			(xy 159.831821 -44.952447) (xy 159.79991 -44.980098) (xy 181.659784 -44.980098) (xy 181.659784 -44.116498)
			(xy 181.66027 -44.089247) (xy 181.668026 -44.035299) (xy 181.683381 -43.983004) (xy 181.706023 -43.933427)
			(xy 181.735489 -43.887577) (xy 181.77118 -43.846386) (xy 181.812371 -43.810695) (xy 181.858221 -43.781229)
			(xy 181.907798 -43.758587) (xy 181.960093 -43.743232) (xy 182.014041 -43.735476) (xy 182.068543 -43.735476)
			(xy 182.122491 -43.743232) (xy 182.174786 -43.758587) (xy 182.224363 -43.781229) (xy 182.270213 -43.810695)
			(xy 182.311404 -43.846386) (xy 182.347095 -43.887577) (xy 182.376561 -43.933427) (xy 182.399203 -43.983004)
			(xy 182.414558 -44.035299) (xy 182.422314 -44.089247) (xy 182.4228 -44.116498) (xy 182.4228 -44.840452)
			(xy 348.511075 -44.840452) (xy 348.511075 -44.785948) (xy 348.518832 -44.731999) (xy 348.534188 -44.679702)
			(xy 348.556831 -44.630124) (xy 348.586298 -44.584273) (xy 348.621992 -44.543082) (xy 348.663184 -44.50739)
			(xy 348.709036 -44.477924) (xy 348.758616 -44.455283) (xy 348.810912 -44.439929) (xy 348.864862 -44.432174)
			(xy 348.892114 -44.431712) (xy 349.755714 -44.431712) (xy 349.782966 -44.432159) (xy 349.836915 -44.439917)
			(xy 349.889211 -44.455274) (xy 349.938789 -44.477918) (xy 349.98464 -44.507386) (xy 350.025831 -44.543079)
			(xy 350.061523 -44.584271) (xy 350.090989 -44.630123) (xy 350.11363 -44.679702) (xy 350.128986 -44.731999)
			(xy 350.136742 -44.785948) (xy 350.136742 -44.840452) (xy 350.128986 -44.894401) (xy 350.11363 -44.946698)
			(xy 350.090989 -44.996277) (xy 350.072098 -45.025673) (xy 355.559288 -45.025673) (xy 355.559288 -44.971127)
			(xy 355.56705 -44.917137) (xy 355.582418 -44.864802) (xy 355.605077 -44.815186) (xy 355.634567 -44.7693)
			(xy 355.670288 -44.728078) (xy 355.711511 -44.692359) (xy 355.757398 -44.662871) (xy 355.807015 -44.640213)
			(xy 355.859351 -44.624847) (xy 355.913341 -44.617087) (xy 355.940614 -44.616624) (xy 356.804214 -44.616624)
			(xy 356.831482 -44.617139) (xy 356.885462 -44.624902) (xy 356.937788 -44.640268) (xy 356.987394 -44.662925)
			(xy 357.033272 -44.69241) (xy 357.074486 -44.728124) (xy 357.110199 -44.769339) (xy 357.139682 -44.815218)
			(xy 357.162337 -44.864825) (xy 357.177701 -44.917152) (xy 357.185462 -44.971132) (xy 357.185462 -45.025668)
			(xy 357.177701 -45.079648) (xy 357.162337 -45.131975) (xy 357.139682 -45.181582) (xy 357.110199 -45.227461)
			(xy 357.074486 -45.268676) (xy 357.033272 -45.30439) (xy 356.987394 -45.333875) (xy 356.937788 -45.356532)
			(xy 356.885462 -45.371898) (xy 356.831482 -45.379661) (xy 356.804214 -45.380148) (xy 355.940614 -45.380148)
			(xy 355.913341 -45.379713) (xy 355.859351 -45.371953) (xy 355.807015 -45.356587) (xy 355.757398 -45.333929)
			(xy 355.711511 -45.304441) (xy 355.670288 -45.268722) (xy 355.634567 -45.2275) (xy 355.605077 -45.181614)
			(xy 355.582418 -45.131998) (xy 355.56705 -45.079663) (xy 355.559288 -45.025673) (xy 350.072098 -45.025673)
			(xy 350.061523 -45.042129) (xy 350.025831 -45.083321) (xy 349.98464 -45.119014) (xy 349.938789 -45.148482)
			(xy 349.889211 -45.171126) (xy 349.836915 -45.186483) (xy 349.782966 -45.194241) (xy 349.755714 -45.194728)
			(xy 348.892114 -45.194728) (xy 348.864862 -45.194226) (xy 348.810912 -45.186471) (xy 348.758616 -45.171117)
			(xy 348.709036 -45.148476) (xy 348.663184 -45.11901) (xy 348.621992 -45.083318) (xy 348.586298 -45.042127)
			(xy 348.556831 -44.996276) (xy 348.534188 -44.946698) (xy 348.518832 -44.894401) (xy 348.511075 -44.840452)
			(xy 182.4228 -44.840452) (xy 182.4228 -44.980098) (xy 182.422314 -45.007349) (xy 182.414558 -45.061297)
			(xy 182.399203 -45.113592) (xy 182.376561 -45.163169) (xy 182.347095 -45.209019) (xy 182.311404 -45.25021)
			(xy 182.270213 -45.285901) (xy 182.224363 -45.315367) (xy 182.174786 -45.338009) (xy 182.122491 -45.353364)
			(xy 182.068543 -45.36112) (xy 182.014041 -45.36112) (xy 181.960093 -45.353364) (xy 181.907798 -45.338009)
			(xy 181.858221 -45.315367) (xy 181.812371 -45.285901) (xy 181.77118 -45.25021) (xy 181.735489 -45.209019)
			(xy 181.706023 -45.163169) (xy 181.683381 -45.113592) (xy 181.668026 -45.061297) (xy 181.66027 -45.007349)
			(xy 181.659784 -44.980098) (xy 159.79991 -44.980098) (xy 159.790604 -44.988162) (xy 159.744723 -45.017648)
			(xy 159.695113 -45.040305) (xy 159.642783 -45.05567) (xy 159.588799 -45.063432) (xy 159.534261 -45.063432)
			(xy 159.480277 -45.05567) (xy 159.427947 -45.040305) (xy 159.378337 -45.017648) (xy 159.332456 -44.988162)
			(xy 159.291239 -44.952447) (xy 159.255524 -44.91123) (xy 159.226038 -44.865349) (xy 159.203381 -44.815739)
			(xy 159.188016 -44.763409) (xy 159.180254 -44.709425) (xy 159.179768 -44.682156) (xy 156.72159 -44.682156)
			(xy 156.729056 -44.707583) (xy 156.736818 -44.761567) (xy 156.737304 -44.788836) (xy 156.737304 -45.652436)
			(xy 156.736818 -45.679705) (xy 156.729056 -45.733689) (xy 156.713691 -45.786019) (xy 156.691034 -45.835629)
			(xy 156.661548 -45.88151) (xy 156.625833 -45.922727) (xy 156.584616 -45.958442) (xy 156.538735 -45.987928)
			(xy 156.489125 -46.010585) (xy 156.436795 -46.02595) (xy 156.382811 -46.033712) (xy 156.328273 -46.033712)
			(xy 156.274289 -46.02595) (xy 156.221959 -46.010585) (xy 156.172349 -45.987928) (xy 156.126468 -45.958442)
			(xy 156.085251 -45.922727) (xy 156.049536 -45.88151) (xy 156.02005 -45.835629) (xy 155.997393 -45.786019)
			(xy 155.982028 -45.733689) (xy 155.974266 -45.679705) (xy 155.97378 -45.652436) (xy 97.038059 -45.652436)
			(xy 97.067693 -45.708092) (xy 97.133211 -45.848071) (xy 97.191435 -45.991237) (xy 97.242212 -46.13721)
			(xy 97.285407 -46.285604) (xy 97.320906 -46.436025) (xy 97.329238 -46.481746) (xy 178.630072 -46.481746)
			(xy 178.630072 -45.618146) (xy 178.630558 -45.590895) (xy 178.638314 -45.536947) (xy 178.653669 -45.484652)
			(xy 178.676311 -45.435075) (xy 178.705777 -45.389225) (xy 178.741468 -45.348034) (xy 178.782659 -45.312343)
			(xy 178.828509 -45.282877) (xy 178.878086 -45.260235) (xy 178.930381 -45.24488) (xy 178.984329 -45.237124)
			(xy 179.038831 -45.237124) (xy 179.092779 -45.24488) (xy 179.145074 -45.260235) (xy 179.194651 -45.282877)
			(xy 179.240501 -45.312343) (xy 179.281692 -45.348034) (xy 179.317383 -45.389225) (xy 179.346849 -45.435075)
			(xy 179.369491 -45.484652) (xy 179.384846 -45.536947) (xy 179.392602 -45.590895) (xy 179.393088 -45.618146)
			(xy 179.393088 -46.481746) (xy 179.392602 -46.508997) (xy 179.384846 -46.562945) (xy 179.369491 -46.61524)
			(xy 179.346849 -46.664817) (xy 179.317383 -46.710667) (xy 179.281692 -46.751858) (xy 179.240501 -46.787549)
			(xy 179.194651 -46.817015) (xy 179.145074 -46.839657) (xy 179.092779 -46.855012) (xy 179.038831 -46.862768)
			(xy 178.984329 -46.862768) (xy 178.930381 -46.855012) (xy 178.878086 -46.839657) (xy 178.828509 -46.817015)
			(xy 178.782659 -46.787549) (xy 178.741468 -46.751858) (xy 178.705777 -46.710667) (xy 178.676311 -46.664817)
			(xy 178.653669 -46.61524) (xy 178.638314 -46.562945) (xy 178.630558 -46.508997) (xy 178.630072 -46.481746)
			(xy 97.329238 -46.481746) (xy 97.348615 -46.588073) (xy 97.368459 -46.741347) (xy 97.380387 -46.895438)
			(xy 97.384366 -47.04994) (xy 97.380387 -47.204442) (xy 97.368459 -47.358533) (xy 97.348615 -47.511807)
			(xy 97.320906 -47.663855) (xy 97.285407 -47.814276) (xy 97.242212 -47.96267) (xy 97.239575 -47.97025)
			(xy 155.567386 -47.97025) (xy 155.567386 -47.91575) (xy 155.575142 -47.861805) (xy 155.590495 -47.809513)
			(xy 155.613135 -47.759938) (xy 155.642598 -47.71409) (xy 155.678287 -47.672901) (xy 155.719474 -47.63721)
			(xy 155.765321 -47.607744) (xy 155.814895 -47.585102) (xy 155.867186 -47.569746) (xy 155.92113 -47.561987)
			(xy 155.94838 -47.5615) (xy 156.81198 -47.5615) (xy 156.839234 -47.561946) (xy 156.893189 -47.569701)
			(xy 156.94549 -47.585055) (xy 156.995074 -47.607697) (xy 157.04093 -47.637165) (xy 157.082126 -47.67286)
			(xy 157.117823 -47.714054) (xy 157.147293 -47.759909) (xy 157.169938 -47.809491) (xy 157.185295 -47.861792)
			(xy 157.193053 -47.915746) (xy 157.193053 -47.970249) (xy 158.785586 -47.970249) (xy 158.785586 -47.915751)
			(xy 158.793341 -47.861808) (xy 158.808694 -47.809518) (xy 158.831331 -47.759944) (xy 158.860793 -47.714097)
			(xy 158.89648 -47.672908) (xy 158.937664 -47.637217) (xy 158.983509 -47.607751) (xy 159.03308 -47.585108)
			(xy 159.085369 -47.569749) (xy 159.139311 -47.561988) (xy 159.16656 -47.5615) (xy 160.03016 -47.5615)
			(xy 160.057415 -47.561945) (xy 160.111372 -47.569697) (xy 160.163675 -47.58505) (xy 160.213262 -47.607691)
			(xy 160.259121 -47.637158) (xy 160.300319 -47.672853) (xy 160.336018 -47.714047) (xy 160.36549 -47.759903)
			(xy 160.388136 -47.809487) (xy 160.403494 -47.861789) (xy 160.411253 -47.915745) (xy 160.411253 -47.970255)
			(xy 160.403494 -48.024211) (xy 160.402353 -48.028098) (xy 181.659784 -48.028098) (xy 181.659784 -47.164498)
			(xy 181.66027 -47.137247) (xy 181.668026 -47.083299) (xy 181.683381 -47.031004) (xy 181.706023 -46.981427)
			(xy 181.735489 -46.935577) (xy 181.77118 -46.894386) (xy 181.812371 -46.858695) (xy 181.858221 -46.829229)
			(xy 181.907798 -46.806587) (xy 181.960093 -46.791232) (xy 182.014041 -46.783476) (xy 182.068543 -46.783476)
			(xy 182.122491 -46.791232) (xy 182.174786 -46.806587) (xy 182.224363 -46.829229) (xy 182.225669 -46.830068)
			(xy 356.445326 -46.830068) (xy 356.445326 -46.775532) (xy 356.453087 -46.721552) (xy 356.468451 -46.669225)
			(xy 356.491104 -46.619618) (xy 356.520587 -46.573739) (xy 356.556298 -46.532522) (xy 356.597512 -46.496807)
			(xy 356.643388 -46.467321) (xy 356.692994 -46.444663) (xy 356.745319 -46.429294) (xy 356.799298 -46.421529)
			(xy 356.826566 -46.42104) (xy 357.690166 -46.42104) (xy 357.717439 -46.421497) (xy 357.77143 -46.429255)
			(xy 357.823767 -46.444619) (xy 357.873384 -46.467275) (xy 357.919272 -46.496761) (xy 357.960497 -46.532479)
			(xy 357.996218 -46.5737) (xy 358.025709 -46.619586) (xy 358.048369 -46.669202) (xy 358.063737 -46.721537)
			(xy 358.0715 -46.775527) (xy 358.0715 -46.830069) (xy 358.762026 -46.830069) (xy 358.762026 -46.775531)
			(xy 358.769788 -46.721547) (xy 358.785153 -46.669218) (xy 358.807809 -46.619608) (xy 358.837295 -46.573728)
			(xy 358.87301 -46.53251) (xy 358.914228 -46.496795) (xy 358.960108 -46.467309) (xy 359.009718 -46.444653)
			(xy 359.062047 -46.429288) (xy 359.116031 -46.421526) (xy 359.1433 -46.42104) (xy 360.0069 -46.42104)
			(xy 360.03417 -46.421522) (xy 360.088153 -46.429284) (xy 360.140483 -46.44465) (xy 360.190094 -46.467306)
			(xy 360.235975 -46.496792) (xy 360.277193 -46.532507) (xy 360.312908 -46.573725) (xy 360.342394 -46.619606)
			(xy 360.36505 -46.669217) (xy 360.380416 -46.721547) (xy 360.388178 -46.77553) (xy 360.388178 -46.83007)
			(xy 360.388178 -46.830073) (xy 361.088604 -46.830073) (xy 361.088604 -46.775527) (xy 361.096367 -46.721537)
			(xy 361.111735 -46.669202) (xy 361.134395 -46.619586) (xy 361.163887 -46.573701) (xy 361.199608 -46.53248)
			(xy 361.240833 -46.496763) (xy 361.286721 -46.467276) (xy 361.336339 -46.444621) (xy 361.388676 -46.429258)
			(xy 361.442667 -46.421501) (xy 361.46994 -46.42104) (xy 362.33354 -46.42104) (xy 362.360808 -46.421525)
			(xy 362.414787 -46.429291) (xy 362.467112 -46.44466) (xy 362.516718 -46.467319) (xy 362.562594 -46.496806)
			(xy 362.603807 -46.532522) (xy 362.639518 -46.573738) (xy 362.669 -46.619618) (xy 362.691654 -46.669225)
			(xy 362.707017 -46.721552) (xy 362.714778 -46.775532) (xy 362.714778 -46.830068) (xy 362.707017 -46.884048)
			(xy 362.691654 -46.936375) (xy 362.672751 -46.977768) (xy 396.642323 -46.977768) (xy 396.642323 -46.891996)
			(xy 396.650237 -46.806588) (xy 396.665998 -46.722276) (xy 396.689471 -46.639777) (xy 396.720456 -46.559796)
			(xy 396.758688 -46.483015) (xy 396.803842 -46.41009) (xy 396.855532 -46.341642) (xy 396.913317 -46.278255)
			(xy 396.976704 -46.22047) (xy 397.045152 -46.16878) (xy 397.118077 -46.123626) (xy 397.194858 -46.085394)
			(xy 397.274839 -46.054409) (xy 397.357338 -46.030936) (xy 397.44165 -46.015175) (xy 397.527058 -46.007261)
			(xy 397.61283 -46.007261) (xy 397.698238 -46.015175) (xy 397.78255 -46.030936) (xy 397.865049 -46.054409)
			(xy 397.94503 -46.085394) (xy 398.021811 -46.123626) (xy 398.094736 -46.16878) (xy 398.163184 -46.22047)
			(xy 398.226571 -46.278255) (xy 398.284356 -46.341642) (xy 398.336046 -46.41009) (xy 398.3812 -46.483015)
			(xy 398.419432 -46.559796) (xy 398.450417 -46.639777) (xy 398.47389 -46.722276) (xy 398.489651 -46.806588)
			(xy 398.497565 -46.891996) (xy 398.49806 -46.934882) (xy 398.497565 -46.977768) (xy 398.489651 -47.063176)
			(xy 398.47389 -47.147488) (xy 398.450417 -47.229987) (xy 398.419432 -47.309968) (xy 398.3812 -47.386749)
			(xy 398.336046 -47.459674) (xy 398.284356 -47.528122) (xy 398.226571 -47.591509) (xy 398.163184 -47.649294)
			(xy 398.094736 -47.700984) (xy 398.021811 -47.746138) (xy 397.94503 -47.78437) (xy 397.865049 -47.815355)
			(xy 397.78255 -47.838828) (xy 397.698238 -47.854589) (xy 397.61283 -47.862503) (xy 397.527058 -47.862503)
			(xy 397.44165 -47.854589) (xy 397.357338 -47.838828) (xy 397.274839 -47.815355) (xy 397.194858 -47.78437)
			(xy 397.118077 -47.746138) (xy 397.045152 -47.700984) (xy 396.976704 -47.649294) (xy 396.913317 -47.591509)
			(xy 396.855532 -47.528122) (xy 396.803842 -47.459674) (xy 396.758688 -47.386749) (xy 396.720456 -47.309968)
			(xy 396.689471 -47.229987) (xy 396.665998 -47.147488) (xy 396.650237 -47.063176) (xy 396.642323 -46.977768)
			(xy 362.672751 -46.977768) (xy 362.669 -46.985982) (xy 362.639518 -47.031862) (xy 362.603807 -47.073078)
			(xy 362.562594 -47.108794) (xy 362.516718 -47.138281) (xy 362.467112 -47.16094) (xy 362.414787 -47.176309)
			(xy 362.360808 -47.184075) (xy 362.33354 -47.184564) (xy 361.46994 -47.184564) (xy 361.442667 -47.184099)
			(xy 361.388676 -47.176342) (xy 361.336339 -47.160979) (xy 361.286721 -47.138324) (xy 361.240833 -47.108837)
			(xy 361.199608 -47.07312) (xy 361.163887 -47.031899) (xy 361.134395 -46.986014) (xy 361.111735 -46.936398)
			(xy 361.096367 -46.884063) (xy 361.088604 -46.830073) (xy 360.388178 -46.830073) (xy 360.380416 -46.884053)
			(xy 360.36505 -46.936383) (xy 360.342394 -46.985994) (xy 360.312908 -47.031875) (xy 360.277193 -47.073093)
			(xy 360.235975 -47.108808) (xy 360.190094 -47.138294) (xy 360.140483 -47.16095) (xy 360.088153 -47.176316)
			(xy 360.03417 -47.184078) (xy 360.0069 -47.184564) (xy 359.1433 -47.184564) (xy 359.116031 -47.184074)
			(xy 359.062047 -47.176312) (xy 359.009718 -47.160947) (xy 358.960108 -47.138291) (xy 358.914228 -47.108805)
			(xy 358.87301 -47.07309) (xy 358.837295 -47.031872) (xy 358.807809 -46.985992) (xy 358.785153 -46.936382)
			(xy 358.769788 -46.884053) (xy 358.762026 -46.830069) (xy 358.0715 -46.830069) (xy 358.0715 -46.830073)
			(xy 358.063737 -46.884063) (xy 358.048369 -46.936398) (xy 358.025709 -46.986014) (xy 357.996218 -47.0319)
			(xy 357.960497 -47.073121) (xy 357.919272 -47.108839) (xy 357.873384 -47.138325) (xy 357.823767 -47.160981)
			(xy 357.77143 -47.176345) (xy 357.717439 -47.184103) (xy 357.690166 -47.184564) (xy 356.826566 -47.184564)
			(xy 356.799298 -47.184071) (xy 356.745319 -47.176306) (xy 356.692994 -47.160937) (xy 356.643388 -47.138279)
			(xy 356.597512 -47.108793) (xy 356.556298 -47.073078) (xy 356.520587 -47.031861) (xy 356.491104 -46.985982)
			(xy 356.468451 -46.936375) (xy 356.453087 -46.884048) (xy 356.445326 -46.830068) (xy 182.225669 -46.830068)
			(xy 182.270213 -46.858695) (xy 182.311404 -46.894386) (xy 182.347095 -46.935577) (xy 182.376561 -46.981427)
			(xy 182.399203 -47.031004) (xy 182.414558 -47.083299) (xy 182.422314 -47.137247) (xy 182.4228 -47.164498)
			(xy 182.4228 -48.028098) (xy 182.422314 -48.055349) (xy 182.414558 -48.109297) (xy 182.399203 -48.161592)
			(xy 182.376561 -48.211169) (xy 182.347095 -48.257019) (xy 182.311404 -48.29821) (xy 182.270213 -48.333901)
			(xy 182.224363 -48.363367) (xy 182.174786 -48.386009) (xy 182.122491 -48.401364) (xy 182.068543 -48.40912)
			(xy 182.014041 -48.40912) (xy 181.960093 -48.401364) (xy 181.907798 -48.386009) (xy 181.858221 -48.363367)
			(xy 181.812371 -48.333901) (xy 181.77118 -48.29821) (xy 181.735489 -48.257019) (xy 181.706023 -48.211169)
			(xy 181.683381 -48.161592) (xy 181.668026 -48.109297) (xy 181.66027 -48.055349) (xy 181.659784 -48.028098)
			(xy 160.402353 -48.028098) (xy 160.388136 -48.076513) (xy 160.36549 -48.126097) (xy 160.336018 -48.171953)
			(xy 160.300319 -48.213147) (xy 160.259121 -48.248842) (xy 160.213262 -48.278309) (xy 160.163675 -48.30095)
			(xy 160.111372 -48.316303) (xy 160.057415 -48.324055) (xy 160.03016 -48.324516) (xy 159.16656 -48.324516)
			(xy 159.139311 -48.324012) (xy 159.085369 -48.316251) (xy 159.03308 -48.300892) (xy 158.983509 -48.278249)
			(xy 158.937664 -48.248783) (xy 158.89648 -48.213092) (xy 158.860793 -48.171903) (xy 158.831331 -48.126056)
			(xy 158.808694 -48.076482) (xy 158.793341 -48.024192) (xy 158.785586 -47.970249) (xy 157.193053 -47.970249)
			(xy 157.193053 -47.970254) (xy 157.185295 -48.024208) (xy 157.169938 -48.076509) (xy 157.147293 -48.126091)
			(xy 157.117823 -48.171946) (xy 157.082126 -48.21314) (xy 157.04093 -48.248835) (xy 156.995074 -48.278303)
			(xy 156.94549 -48.300945) (xy 156.893189 -48.316299) (xy 156.839234 -48.324054) (xy 156.81198 -48.324516)
			(xy 155.94838 -48.324516) (xy 155.92113 -48.324013) (xy 155.867186 -48.316254) (xy 155.814895 -48.300898)
			(xy 155.765321 -48.278256) (xy 155.719474 -48.24879) (xy 155.678287 -48.213099) (xy 155.642598 -48.17191)
			(xy 155.613135 -48.126062) (xy 155.590495 -48.076487) (xy 155.575142 -48.024195) (xy 155.567386 -47.97025)
			(xy 97.239575 -47.97025) (xy 97.191435 -48.108643) (xy 97.133211 -48.251809) (xy 97.067693 -48.391788)
			(xy 96.995057 -48.528208) (xy 96.915495 -48.660709) (xy 96.829216 -48.788937) (xy 96.736452 -48.912555)
			(xy 96.637446 -49.031233) (xy 96.532463 -49.144657) (xy 96.421779 -49.252526) (xy 96.30569 -49.354554)
			(xy 96.184502 -49.450471) (xy 96.140518 -49.48174) (xy 178.630072 -49.48174) (xy 178.630072 -48.61814)
			(xy 178.630558 -48.590889) (xy 178.638314 -48.536941) (xy 178.653669 -48.484646) (xy 178.676311 -48.435069)
			(xy 178.705777 -48.389219) (xy 178.741468 -48.348028) (xy 178.782659 -48.312337) (xy 178.828509 -48.282871)
			(xy 178.878086 -48.260229) (xy 178.930381 -48.244874) (xy 178.984329 -48.237118) (xy 179.038831 -48.237118)
			(xy 179.092779 -48.244874) (xy 179.145074 -48.260229) (xy 179.194651 -48.282871) (xy 179.240501 -48.312337)
			(xy 179.281692 -48.348028) (xy 179.317383 -48.389219) (xy 179.346849 -48.435069) (xy 179.369491 -48.484646)
			(xy 179.384846 -48.536941) (xy 179.392602 -48.590889) (xy 179.393088 -48.61814) (xy 179.393088 -49.48174)
			(xy 179.392602 -49.508991) (xy 179.384846 -49.562939) (xy 179.369491 -49.615234) (xy 179.346849 -49.664811)
			(xy 179.317383 -49.710661) (xy 179.281692 -49.751852) (xy 179.240501 -49.787543) (xy 179.194651 -49.817009)
			(xy 179.145074 -49.839651) (xy 179.092779 -49.855006) (xy 179.038831 -49.862762) (xy 178.984329 -49.862762)
			(xy 178.930381 -49.855006) (xy 178.878086 -49.839651) (xy 178.828509 -49.817009) (xy 178.782659 -49.787543)
			(xy 178.741468 -49.751852) (xy 178.705777 -49.710661) (xy 178.676311 -49.664811) (xy 178.653669 -49.615234)
			(xy 178.638314 -49.562939) (xy 178.630558 -49.508991) (xy 178.630072 -49.48174) (xy 96.140518 -49.48174)
			(xy 96.058537 -49.540022) (xy 95.928129 -49.62297) (xy 95.793624 -49.699095) (xy 95.655379 -49.768194)
			(xy 95.513759 -49.830085) (xy 95.369142 -49.884604) (xy 95.221909 -49.931606) (xy 95.072452 -49.970966)
			(xy 94.921168 -50.00258) (xy 94.768456 -50.026364) (xy 94.614722 -50.042255) (xy 94.460374 -50.050211)
			(xy 94.383098 -50.0507) (xy 92.782898 -50.0507) (xy 92.705622 -50.050194) (xy 92.551275 -50.042238)
			(xy 92.397543 -50.026347) (xy 92.244832 -50.002563) (xy 92.093548 -49.970949) (xy 91.944092 -49.931589)
			(xy 91.796861 -49.884587) (xy 91.652244 -49.830069) (xy 91.510626 -49.768178) (xy 91.372381 -49.699079)
			(xy 91.237877 -49.622954) (xy 91.10747 -49.540007) (xy 90.981506 -49.450456) (xy 90.860319 -49.35454)
			(xy 90.74423 -49.252512) (xy 90.633548 -49.144644) (xy 90.528565 -49.031221) (xy 90.42956 -48.912543)
			(xy 90.336796 -48.788927) (xy 90.250519 -48.660699) (xy 90.170957 -48.528199) (xy 90.098321 -48.391779)
			(xy 90.032804 -48.251802) (xy 89.97458 -48.108637) (xy 89.923803 -47.962664) (xy 89.880608 -47.814271)
			(xy 89.84511 -47.663852) (xy 89.817402 -47.511804) (xy 89.797557 -47.358531) (xy 89.78563 -47.204441)
			(xy 89.78165 -47.04994) (xy 67.384154 -47.04994) (xy 67.384157 -47.050067) (xy 67.380172 -47.204564)
			(xy 67.368238 -47.35865) (xy 67.348389 -47.511918) (xy 67.320675 -47.663961) (xy 67.285172 -47.814376)
			(xy 67.241973 -47.962763) (xy 67.191193 -48.108731) (xy 67.132966 -48.25189) (xy 67.067447 -48.391863)
			(xy 66.994809 -48.528277) (xy 66.915245 -48.660771) (xy 66.828966 -48.788993) (xy 66.736201 -48.912605)
			(xy 66.637196 -49.031277) (xy 66.532213 -49.144695) (xy 66.421531 -49.252559) (xy 66.305444 -49.354582)
			(xy 66.184258 -49.450493) (xy 66.058295 -49.54004) (xy 65.927891 -49.622983) (xy 65.793389 -49.699104)
			(xy 65.655147 -49.768199) (xy 65.513531 -49.830087) (xy 65.368918 -49.884603) (xy 65.22169 -49.931602)
			(xy 65.072237 -49.970961) (xy 64.920957 -50.002573) (xy 64.76825 -50.026356) (xy 64.614521 -50.042247)
			(xy 64.460178 -50.050202) (xy 64.382904 -50.0507) (xy 62.78245 -50.0507) (xy 62.705176 -50.050188)
			(xy 62.550834 -50.04222) (xy 62.397107 -50.026316) (xy 62.244402 -50.002521) (xy 62.093124 -49.970896)
			(xy 61.943675 -49.931526) (xy 61.796451 -49.884514) (xy 61.651842 -49.829987) (xy 61.510232 -49.768087)
			(xy 61.371996 -49.69898) (xy 61.2375 -49.622848) (xy 61.107102 -49.539894) (xy 60.981148 -49.450337)
			(xy 60.85997 -49.354416) (xy 60.743891 -49.252383) (xy 60.633218 -49.14451) (xy 60.528245 -49.031083)
			(xy 60.429249 -48.912403) (xy 60.336495 -48.788784) (xy 60.250227 -48.660555) (xy 60.170674 -48.528054)
			(xy 60.098048 -48.391634) (xy 60.032541 -48.251656) (xy 59.974326 -48.108492) (xy 59.923558 -47.96252)
			(xy 59.880371 -47.814129) (xy 59.844881 -47.663712) (xy 59.81718 -47.511667) (xy 59.797344 -47.358397)
			(xy 59.785423 -47.20431) (xy 59.781451 -47.049813) (xy 0.509016 -47.049813) (xy 0.509016 -50.949098)
			(xy 181.659784 -50.949098) (xy 181.659784 -50.085498) (xy 181.66027 -50.058247) (xy 181.668026 -50.004299)
			(xy 181.683381 -49.952004) (xy 181.706023 -49.902427) (xy 181.735489 -49.856577) (xy 181.77118 -49.815386)
			(xy 181.812371 -49.779695) (xy 181.858221 -49.750229) (xy 181.907798 -49.727587) (xy 181.960093 -49.712232)
			(xy 182.014041 -49.704476) (xy 182.068543 -49.704476) (xy 182.122491 -49.712232) (xy 182.174786 -49.727587)
			(xy 182.224363 -49.750229) (xy 182.270213 -49.779695) (xy 182.311404 -49.815386) (xy 182.347095 -49.856577)
			(xy 182.376561 -49.902427) (xy 182.399203 -49.952004) (xy 182.414558 -50.004299) (xy 182.422314 -50.058247)
			(xy 182.4228 -50.085498) (xy 182.4228 -50.949098) (xy 182.422314 -50.976349) (xy 182.414558 -51.030297)
			(xy 182.399203 -51.082592) (xy 182.376561 -51.132169) (xy 182.347095 -51.178019) (xy 182.311404 -51.21921)
			(xy 182.270213 -51.254901) (xy 182.224363 -51.284367) (xy 182.174786 -51.307009) (xy 182.122491 -51.322364)
			(xy 182.068543 -51.33012) (xy 182.014041 -51.33012) (xy 181.960093 -51.322364) (xy 181.907798 -51.307009)
			(xy 181.858221 -51.284367) (xy 181.812371 -51.254901) (xy 181.77118 -51.21921) (xy 181.735489 -51.178019)
			(xy 181.706023 -51.132169) (xy 181.683381 -51.082592) (xy 181.668026 -51.030297) (xy 181.66027 -50.976349)
			(xy 181.659784 -50.949098) (xy 0.509016 -50.949098) (xy 0.509016 -52.481734) (xy 178.630072 -52.481734)
			(xy 178.630072 -51.618134) (xy 178.630558 -51.590883) (xy 178.638314 -51.536935) (xy 178.653669 -51.48464)
			(xy 178.676311 -51.435063) (xy 178.705777 -51.389213) (xy 178.741468 -51.348022) (xy 178.782659 -51.312331)
			(xy 178.828509 -51.282865) (xy 178.878086 -51.260223) (xy 178.930381 -51.244868) (xy 178.984329 -51.237112)
			(xy 179.038831 -51.237112) (xy 179.092779 -51.244868) (xy 179.145074 -51.260223) (xy 179.194651 -51.282865)
			(xy 179.240501 -51.312331) (xy 179.281692 -51.348022) (xy 179.317383 -51.389213) (xy 179.346849 -51.435063)
			(xy 179.369491 -51.48464) (xy 179.384846 -51.536935) (xy 179.392602 -51.590883) (xy 179.393088 -51.618134)
			(xy 179.393088 -51.999896) (xy 201.367397 -51.999896) (xy 201.371407 -51.837793) (xy 201.38343 -51.676088)
			(xy 201.403434 -51.515174) (xy 201.431372 -51.355447) (xy 201.467175 -51.197297) (xy 201.510755 -51.041111)
			(xy 201.562006 -50.887271) (xy 201.620802 -50.736154) (xy 201.687 -50.58813) (xy 201.760436 -50.44356)
			(xy 201.840933 -50.302799) (xy 201.928292 -50.166191) (xy 202.0223 -50.034071) (xy 202.122727 -49.906761)
			(xy 202.229327 -49.784573) (xy 202.341839 -49.667807) (xy 202.459987 -49.556748) (xy 202.583484 -49.451667)
			(xy 202.712026 -49.352823) (xy 202.845299 -49.260456) (xy 202.982977 -49.174793) (xy 203.124723 -49.096044)
			(xy 203.27019 -49.024401) (xy 203.419022 -48.960039) (xy 203.570854 -48.903117) (xy 203.725316 -48.853773)
			(xy 203.882029 -48.812128) (xy 204.04061 -48.778283) (xy 204.200671 -48.752323) (xy 204.361819 -48.73431)
			(xy 204.523661 -48.724289) (xy 204.685801 -48.722283) (xy 204.847842 -48.728299) (xy 205.009386 -48.74232)
			(xy 205.17004 -48.764313) (xy 205.32941 -48.794225) (xy 205.487105 -48.831981) (xy 205.64274 -48.877489)
			(xy 205.795934 -48.930639) (xy 205.946312 -48.9913) (xy 206.093507 -49.059323) (xy 206.237157 -49.134542)
			(xy 206.376912 -49.216773) (xy 206.512428 -49.305815) (xy 206.643376 -49.40145) (xy 206.769434 -49.503444)
			(xy 206.890294 -49.611547) (xy 207.00566 -49.725494) (xy 207.115249 -49.845008) (xy 207.218794 -49.969795)
			(xy 207.316041 -50.09955) (xy 207.406753 -50.233955) (xy 207.424818 -50.263806) (xy 239.457992 -50.263806)
			(xy 239.457992 -49.400206) (xy 239.458478 -49.372955) (xy 239.466234 -49.319007) (xy 239.481589 -49.266712)
			(xy 239.504231 -49.217135) (xy 239.533697 -49.171285) (xy 239.569388 -49.130094) (xy 239.610579 -49.094403)
			(xy 239.656429 -49.064937) (xy 239.706006 -49.042295) (xy 239.758301 -49.02694) (xy 239.812249 -49.019184)
			(xy 239.866751 -49.019184) (xy 239.920699 -49.02694) (xy 239.972994 -49.042295) (xy 240.022571 -49.064937)
			(xy 240.068421 -49.094403) (xy 240.109612 -49.130094) (xy 240.145303 -49.171285) (xy 240.174769 -49.217135)
			(xy 240.197411 -49.266712) (xy 240.212766 -49.319007) (xy 240.220522 -49.372955) (xy 240.221008 -49.400206)
			(xy 240.221008 -50.263806) (xy 240.220522 -50.291057) (xy 240.212766 -50.345005) (xy 240.197411 -50.3973)
			(xy 240.174769 -50.446877) (xy 240.145303 -50.492727) (xy 240.109612 -50.533918) (xy 240.068421 -50.569609)
			(xy 240.022571 -50.599075) (xy 239.972994 -50.621717) (xy 239.920699 -50.637072) (xy 239.866751 -50.644828)
			(xy 239.812249 -50.644828) (xy 239.758301 -50.637072) (xy 239.706006 -50.621717) (xy 239.656429 -50.599075)
			(xy 239.610579 -50.569609) (xy 239.569388 -50.533918) (xy 239.533697 -50.492727) (xy 239.504231 -50.446877)
			(xy 239.481589 -50.3973) (xy 239.466234 -50.345005) (xy 239.458478 -50.291057) (xy 239.457992 -50.263806)
			(xy 207.424818 -50.263806) (xy 207.490706 -50.372682) (xy 207.567696 -50.515391) (xy 207.637535 -50.661732)
			(xy 207.70005 -50.811349) (xy 207.755091 -50.963874) (xy 207.802521 -51.118934) (xy 207.842224 -51.27615)
			(xy 207.874105 -51.435138) (xy 207.898083 -51.595507) (xy 207.914102 -51.756866) (xy 207.922121 -51.91882)
			(xy 207.922622 -51.999896) (xy 207.922121 -52.080972) (xy 207.914102 -52.242926) (xy 207.898083 -52.404285)
			(xy 207.874105 -52.564654) (xy 207.842224 -52.723642) (xy 207.802521 -52.880858) (xy 207.794624 -52.906676)
			(xy 228.815392 -52.906676) (xy 228.815392 -52.043076) (xy 228.815878 -52.015825) (xy 228.823634 -51.961877)
			(xy 228.838989 -51.909582) (xy 228.861631 -51.860005) (xy 228.891097 -51.814155) (xy 228.926788 -51.772964)
			(xy 228.967979 -51.737273) (xy 229.013829 -51.707807) (xy 229.063406 -51.685165) (xy 229.115701 -51.66981)
			(xy 229.169649 -51.662054) (xy 229.224151 -51.662054) (xy 229.278099 -51.66981) (xy 229.330394 -51.685165)
			(xy 229.379971 -51.707807) (xy 229.425821 -51.737273) (xy 229.467012 -51.772964) (xy 229.502703 -51.814155)
			(xy 229.532169 -51.860005) (xy 229.554811 -51.909582) (xy 229.570166 -51.961877) (xy 229.577922 -52.015825)
			(xy 229.578408 -52.043076) (xy 229.578408 -52.90185) (xy 241.926872 -52.90185) (xy 241.926872 -52.03825)
			(xy 241.927358 -52.010999) (xy 241.935114 -51.957051) (xy 241.950469 -51.904756) (xy 241.973111 -51.855179)
			(xy 242.002577 -51.809329) (xy 242.038268 -51.768138) (xy 242.079459 -51.732447) (xy 242.125309 -51.702981)
			(xy 242.174886 -51.680339) (xy 242.227181 -51.664984) (xy 242.281129 -51.657228) (xy 242.335631 -51.657228)
			(xy 242.389579 -51.664984) (xy 242.441874 -51.680339) (xy 242.491451 -51.702981) (xy 242.537301 -51.732447)
			(xy 242.578492 -51.768138) (xy 242.614183 -51.809329) (xy 242.643649 -51.855179) (xy 242.666291 -51.904756)
			(xy 242.681646 -51.957051) (xy 242.687806 -51.999896) (xy 265.367269 -51.999896) (xy 265.371279 -51.837793)
			(xy 265.383302 -51.676088) (xy 265.403306 -51.515174) (xy 265.431244 -51.355447) (xy 265.467047 -51.197297)
			(xy 265.510627 -51.041111) (xy 265.561878 -50.887271) (xy 265.620674 -50.736154) (xy 265.686872 -50.58813)
			(xy 265.760308 -50.44356) (xy 265.840805 -50.302799) (xy 265.928164 -50.166191) (xy 266.022172 -50.034071)
			(xy 266.122599 -49.906761) (xy 266.229199 -49.784573) (xy 266.341711 -49.667807) (xy 266.459859 -49.556748)
			(xy 266.583356 -49.451667) (xy 266.711898 -49.352823) (xy 266.845171 -49.260456) (xy 266.982849 -49.174793)
			(xy 267.124595 -49.096044) (xy 267.270062 -49.024401) (xy 267.418894 -48.960039) (xy 267.570726 -48.903117)
			(xy 267.725188 -48.853773) (xy 267.881901 -48.812128) (xy 268.040482 -48.778283) (xy 268.200543 -48.752323)
			(xy 268.361691 -48.73431) (xy 268.523533 -48.724289) (xy 268.685673 -48.722283) (xy 268.847714 -48.728299)
			(xy 269.009258 -48.74232) (xy 269.169912 -48.764313) (xy 269.329282 -48.794225) (xy 269.486977 -48.831981)
			(xy 269.642612 -48.877489) (xy 269.795806 -48.930639) (xy 269.946184 -48.9913) (xy 270.093379 -49.059323)
			(xy 270.237029 -49.134542) (xy 270.376784 -49.216773) (xy 270.5123 -49.305815) (xy 270.643248 -49.40145)
			(xy 270.769306 -49.503444) (xy 270.890166 -49.611547) (xy 271.005532 -49.725494) (xy 271.115121 -49.845008)
			(xy 271.218666 -49.969795) (xy 271.315913 -50.09955) (xy 271.406625 -50.233955) (xy 271.40723 -50.234955)
			(xy 350.291827 -50.234955) (xy 350.291827 -50.180445) (xy 350.299585 -50.126489) (xy 350.314942 -50.074187)
			(xy 350.337587 -50.024602) (xy 350.367058 -49.978745) (xy 350.402755 -49.937549) (xy 350.443952 -49.901853)
			(xy 350.489809 -49.872383) (xy 350.539394 -49.849739) (xy 350.591697 -49.834383) (xy 350.645653 -49.826626)
			(xy 350.672908 -49.826164) (xy 351.536508 -49.826164) (xy 351.563757 -49.826707) (xy 351.6177 -49.834464)
			(xy 351.66999 -49.849818) (xy 351.719562 -49.872458) (xy 351.765408 -49.901922) (xy 351.806594 -49.937611)
			(xy 351.842282 -49.978798) (xy 351.871746 -50.024645) (xy 351.894385 -50.074218) (xy 351.909738 -50.126508)
			(xy 351.917494 -50.180451) (xy 351.917494 -50.234949) (xy 351.917493 -50.234956) (xy 352.489927 -50.234956)
			(xy 352.489927 -50.180444) (xy 352.497685 -50.126487) (xy 352.513044 -50.074183) (xy 352.535689 -50.024598)
			(xy 352.565162 -49.97874) (xy 352.600861 -49.937544) (xy 352.642059 -49.901848) (xy 352.687919 -49.872378)
			(xy 352.737506 -49.849735) (xy 352.78981 -49.83438) (xy 352.843768 -49.826625) (xy 352.871024 -49.826164)
			(xy 353.734624 -49.826164) (xy 353.761872 -49.826708) (xy 353.815813 -49.834467) (xy 353.868101 -49.849823)
			(xy 353.917672 -49.872463) (xy 353.963516 -49.901928) (xy 354.0047 -49.937617) (xy 354.040386 -49.978804)
			(xy 354.069848 -50.024649) (xy 354.092486 -50.074221) (xy 354.107839 -50.12651) (xy 354.115594 -50.180452)
			(xy 354.115594 -50.234948) (xy 354.115593 -50.234956) (xy 354.712427 -50.234956) (xy 354.712427 -50.180444)
			(xy 354.720185 -50.126487) (xy 354.735544 -50.074183) (xy 354.758189 -50.024598) (xy 354.787662 -49.97874)
			(xy 354.823361 -49.937544) (xy 354.864559 -49.901848) (xy 354.910419 -49.872378) (xy 354.960006 -49.849735)
			(xy 355.01231 -49.83438) (xy 355.066268 -49.826625) (xy 355.093524 -49.826164) (xy 355.957124 -49.826164)
			(xy 355.984372 -49.826708) (xy 356.038313 -49.834467) (xy 356.090601 -49.849823) (xy 356.140172 -49.872463)
			(xy 356.186016 -49.901928) (xy 356.2272 -49.937617) (xy 356.262886 -49.978804) (xy 356.292348 -50.024649)
			(xy 356.314986 -50.074221) (xy 356.330339 -50.12651) (xy 356.338094 -50.180452) (xy 356.338094 -50.234948)
			(xy 356.338093 -50.234957) (xy 356.942527 -50.234957) (xy 356.942527 -50.180443) (xy 356.950286 -50.126484)
			(xy 356.965645 -50.074179) (xy 356.988293 -50.024592) (xy 357.017767 -49.978734) (xy 357.053468 -49.937537)
			(xy 357.094669 -49.90184) (xy 357.140531 -49.872371) (xy 357.19012 -49.84973) (xy 357.242427 -49.834376)
			(xy 357.296387 -49.826624) (xy 357.323644 -49.826164) (xy 358.187244 -49.826164) (xy 358.214491 -49.826709)
			(xy 358.26843 -49.83447) (xy 358.320716 -49.849828) (xy 358.370284 -49.87247) (xy 358.416125 -49.901935)
			(xy 358.457307 -49.937624) (xy 358.492991 -49.97881) (xy 358.522451 -50.024655) (xy 358.545087 -50.074226)
			(xy 358.560439 -50.126513) (xy 358.568194 -50.180453) (xy 358.568194 -50.234947) (xy 358.560439 -50.288887)
			(xy 358.545087 -50.341174) (xy 358.522451 -50.390745) (xy 358.492991 -50.43659) (xy 358.457307 -50.477776)
			(xy 358.416125 -50.513465) (xy 358.370284 -50.54293) (xy 358.320716 -50.565572) (xy 358.26843 -50.58093)
			(xy 358.214491 -50.588691) (xy 358.187244 -50.58918) (xy 357.323644 -50.58918) (xy 357.296387 -50.588776)
			(xy 357.242427 -50.581024) (xy 357.19012 -50.56567) (xy 357.140531 -50.543029) (xy 357.094669 -50.51356)
			(xy 357.053468 -50.477863) (xy 357.017767 -50.436666) (xy 356.988293 -50.390808) (xy 356.965645 -50.341221)
			(xy 356.950286 -50.288916) (xy 356.942527 -50.234957) (xy 356.338093 -50.234957) (xy 356.330339 -50.28889)
			(xy 356.314986 -50.341179) (xy 356.292348 -50.390751) (xy 356.262886 -50.436596) (xy 356.2272 -50.477783)
			(xy 356.186016 -50.513472) (xy 356.140172 -50.542937) (xy 356.090601 -50.565577) (xy 356.038313 -50.580933)
			(xy 355.984372 -50.588692) (xy 355.957124 -50.58918) (xy 355.093524 -50.58918) (xy 355.066268 -50.588775)
			(xy 355.01231 -50.58102) (xy 354.960006 -50.565665) (xy 354.910419 -50.543022) (xy 354.864559 -50.513552)
			(xy 354.823361 -50.477856) (xy 354.787662 -50.43666) (xy 354.758189 -50.390802) (xy 354.735544 -50.341217)
			(xy 354.720185 -50.288913) (xy 354.712427 -50.234956) (xy 354.115593 -50.234956) (xy 354.107839 -50.28889)
			(xy 354.092486 -50.341179) (xy 354.069848 -50.390751) (xy 354.040386 -50.436596) (xy 354.0047 -50.477783)
			(xy 353.963516 -50.513472) (xy 353.917672 -50.542937) (xy 353.868101 -50.565577) (xy 353.815813 -50.580933)
			(xy 353.761872 -50.588692) (xy 353.734624 -50.58918) (xy 352.871024 -50.58918) (xy 352.843768 -50.588775)
			(xy 352.78981 -50.58102) (xy 352.737506 -50.565665) (xy 352.687919 -50.543022) (xy 352.642059 -50.513552)
			(xy 352.600861 -50.477856) (xy 352.565162 -50.43666) (xy 352.535689 -50.390802) (xy 352.513044 -50.341217)
			(xy 352.497685 -50.288913) (xy 352.489927 -50.234956) (xy 351.917493 -50.234956) (xy 351.909738 -50.288892)
			(xy 351.894385 -50.341182) (xy 351.871746 -50.390755) (xy 351.842282 -50.436602) (xy 351.806594 -50.477789)
			(xy 351.765408 -50.513477) (xy 351.719562 -50.542942) (xy 351.66999 -50.565582) (xy 351.6177 -50.580936)
			(xy 351.563757 -50.588693) (xy 351.536508 -50.58918) (xy 350.672908 -50.58918) (xy 350.645653 -50.588774)
			(xy 350.591697 -50.581017) (xy 350.539394 -50.565661) (xy 350.489809 -50.543017) (xy 350.443952 -50.513547)
			(xy 350.402755 -50.477851) (xy 350.367058 -50.436655) (xy 350.337587 -50.390798) (xy 350.314942 -50.341213)
			(xy 350.299585 -50.288911) (xy 350.291827 -50.234955) (xy 271.40723 -50.234955) (xy 271.490578 -50.372682)
			(xy 271.567568 -50.515391) (xy 271.637407 -50.661732) (xy 271.699922 -50.811349) (xy 271.754963 -50.963874)
			(xy 271.802393 -51.118934) (xy 271.842096 -51.27615) (xy 271.873977 -51.435138) (xy 271.897955 -51.595507)
			(xy 271.913974 -51.756866) (xy 271.921993 -51.91882) (xy 271.922494 -51.999896) (xy 271.921993 -52.080972)
			(xy 271.913974 -52.242926) (xy 271.897955 -52.404285) (xy 271.873977 -52.564654) (xy 271.842096 -52.723642)
			(xy 271.802393 -52.880858) (xy 271.754963 -53.035918) (xy 271.699922 -53.188443) (xy 271.637407 -53.33806)
			(xy 271.567568 -53.484401) (xy 271.490578 -53.62711) (xy 271.406625 -53.765837) (xy 271.315913 -53.900242)
			(xy 271.218666 -54.029997) (xy 271.115121 -54.154784) (xy 271.005532 -54.274298) (xy 270.890166 -54.388245)
			(xy 270.769306 -54.496348) (xy 270.643248 -54.598342) (xy 270.5123 -54.693977) (xy 270.376784 -54.783019)
			(xy 270.237029 -54.86525) (xy 270.093379 -54.940469) (xy 269.946184 -55.008492) (xy 269.795806 -55.069153)
			(xy 269.642612 -55.122303) (xy 269.486977 -55.167811) (xy 269.329282 -55.205567) (xy 269.169912 -55.235479)
			(xy 269.009258 -55.257472) (xy 268.847714 -55.271493) (xy 268.685673 -55.277509) (xy 268.523533 -55.275503)
			(xy 268.361691 -55.265482) (xy 268.200543 -55.247469) (xy 268.040482 -55.221509) (xy 267.881901 -55.187664)
			(xy 267.725188 -55.146019) (xy 267.570726 -55.096675) (xy 267.418894 -55.039753) (xy 267.270062 -54.975391)
			(xy 267.124595 -54.903748) (xy 266.982849 -54.824999) (xy 266.845171 -54.739336) (xy 266.711898 -54.646969)
			(xy 266.583356 -54.548125) (xy 266.459859 -54.443044) (xy 266.341711 -54.331985) (xy 266.229199 -54.215219)
			(xy 266.122599 -54.093031) (xy 266.022172 -53.965721) (xy 265.928164 -53.833601) (xy 265.840805 -53.696993)
			(xy 265.760308 -53.556232) (xy 265.686872 -53.411662) (xy 265.620674 -53.263638) (xy 265.561878 -53.112521)
			(xy 265.510627 -52.958681) (xy 265.467047 -52.802495) (xy 265.431244 -52.644345) (xy 265.403306 -52.484618)
			(xy 265.383302 -52.323704) (xy 265.371279 -52.161999) (xy 265.367269 -51.999896) (xy 242.687806 -51.999896)
			(xy 242.689402 -52.010999) (xy 242.689888 -52.03825) (xy 242.689888 -52.90185) (xy 242.689402 -52.929101)
			(xy 242.681646 -52.983049) (xy 242.666291 -53.035344) (xy 242.643649 -53.084921) (xy 242.614183 -53.130771)
			(xy 242.578492 -53.171962) (xy 242.537301 -53.207653) (xy 242.491451 -53.237119) (xy 242.441874 -53.259761)
			(xy 242.389579 -53.275116) (xy 242.335631 -53.282872) (xy 242.281129 -53.282872) (xy 242.227181 -53.275116)
			(xy 242.174886 -53.259761) (xy 242.125309 -53.237119) (xy 242.079459 -53.207653) (xy 242.038268 -53.171962)
			(xy 242.002577 -53.130771) (xy 241.973111 -53.084921) (xy 241.950469 -53.035344) (xy 241.935114 -52.983049)
			(xy 241.927358 -52.929101) (xy 241.926872 -52.90185) (xy 229.578408 -52.90185) (xy 229.578408 -52.906676)
			(xy 229.577922 -52.933927) (xy 229.570166 -52.987875) (xy 229.554811 -53.04017) (xy 229.532169 -53.089747)
			(xy 229.502703 -53.135597) (xy 229.467012 -53.176788) (xy 229.425821 -53.212479) (xy 229.379971 -53.241945)
			(xy 229.330394 -53.264587) (xy 229.278099 -53.279942) (xy 229.224151 -53.287698) (xy 229.169649 -53.287698)
			(xy 229.115701 -53.279942) (xy 229.063406 -53.264587) (xy 229.013829 -53.241945) (xy 228.967979 -53.212479)
			(xy 228.926788 -53.176788) (xy 228.891097 -53.135597) (xy 228.861631 -53.089747) (xy 228.838989 -53.04017)
			(xy 228.823634 -52.987875) (xy 228.815878 -52.933927) (xy 228.815392 -52.906676) (xy 207.794624 -52.906676)
			(xy 207.755091 -53.035918) (xy 207.70005 -53.188443) (xy 207.637535 -53.33806) (xy 207.567696 -53.484401)
			(xy 207.490706 -53.62711) (xy 207.406753 -53.765837) (xy 207.316041 -53.900242) (xy 207.218794 -54.029997)
			(xy 207.115249 -54.154784) (xy 207.00566 -54.274298) (xy 206.890294 -54.388245) (xy 206.769434 -54.496348)
			(xy 206.643376 -54.598342) (xy 206.512428 -54.693977) (xy 206.493338 -54.70652) (xy 230.115872 -54.70652)
			(xy 230.115872 -53.84292) (xy 230.116358 -53.815669) (xy 230.124114 -53.761721) (xy 230.139469 -53.709426)
			(xy 230.162111 -53.659849) (xy 230.191577 -53.613999) (xy 230.227268 -53.572808) (xy 230.268459 -53.537117)
			(xy 230.314309 -53.507651) (xy 230.363886 -53.485009) (xy 230.416181 -53.469654) (xy 230.470129 -53.461898)
			(xy 230.524631 -53.461898) (xy 230.578579 -53.469654) (xy 230.630874 -53.485009) (xy 230.680451 -53.507651)
			(xy 230.726301 -53.537117) (xy 230.767492 -53.572808) (xy 230.803183 -53.613999) (xy 230.832649 -53.659849)
			(xy 230.855291 -53.709426) (xy 230.870646 -53.761721) (xy 230.878402 -53.815669) (xy 230.878888 -53.84292)
			(xy 230.878888 -54.70652) (xy 230.878811 -54.710838) (xy 240.282476 -54.710838) (xy 240.282476 -53.847238)
			(xy 240.282962 -53.819987) (xy 240.290718 -53.766039) (xy 240.306073 -53.713744) (xy 240.328715 -53.664167)
			(xy 240.358181 -53.618317) (xy 240.393872 -53.577126) (xy 240.435063 -53.541435) (xy 240.480913 -53.511969)
			(xy 240.53049 -53.489327) (xy 240.582785 -53.473972) (xy 240.636733 -53.466216) (xy 240.691235 -53.466216)
			(xy 240.745183 -53.473972) (xy 240.797478 -53.489327) (xy 240.847055 -53.511969) (xy 240.892905 -53.541435)
			(xy 240.934096 -53.577126) (xy 240.969787 -53.618317) (xy 240.999253 -53.664167) (xy 241.021895 -53.713744)
			(xy 241.03725 -53.766039) (xy 241.045006 -53.819987) (xy 241.045492 -53.847238) (xy 241.045492 -54.710838)
			(xy 241.045006 -54.738089) (xy 241.03725 -54.792037) (xy 241.021895 -54.844332) (xy 240.999253 -54.893909)
			(xy 240.969787 -54.939759) (xy 240.934096 -54.98095) (xy 240.892905 -55.016641) (xy 240.847055 -55.046107)
			(xy 240.797478 -55.068749) (xy 240.745183 -55.084104) (xy 240.691235 -55.09186) (xy 240.636733 -55.09186)
			(xy 240.582785 -55.084104) (xy 240.53049 -55.068749) (xy 240.480913 -55.046107) (xy 240.435063 -55.016641)
			(xy 240.393872 -54.98095) (xy 240.358181 -54.939759) (xy 240.328715 -54.893909) (xy 240.306073 -54.844332)
			(xy 240.290718 -54.792037) (xy 240.282962 -54.738089) (xy 240.282476 -54.710838) (xy 230.878811 -54.710838)
			(xy 230.878402 -54.733771) (xy 230.870646 -54.787719) (xy 230.855291 -54.840014) (xy 230.832649 -54.889591)
			(xy 230.803183 -54.935441) (xy 230.767492 -54.976632) (xy 230.726301 -55.012323) (xy 230.680451 -55.041789)
			(xy 230.630874 -55.064431) (xy 230.578579 -55.079786) (xy 230.524631 -55.087542) (xy 230.470129 -55.087542)
			(xy 230.416181 -55.079786) (xy 230.363886 -55.064431) (xy 230.314309 -55.041789) (xy 230.268459 -55.012323)
			(xy 230.227268 -54.976632) (xy 230.191577 -54.935441) (xy 230.162111 -54.889591) (xy 230.139469 -54.840014)
			(xy 230.124114 -54.787719) (xy 230.116358 -54.733771) (xy 230.115872 -54.70652) (xy 206.493338 -54.70652)
			(xy 206.376912 -54.783019) (xy 206.237157 -54.86525) (xy 206.093507 -54.940469) (xy 205.946312 -55.008492)
			(xy 205.795934 -55.069153) (xy 205.64274 -55.122303) (xy 205.487105 -55.167811) (xy 205.32941 -55.205567)
			(xy 205.17004 -55.235479) (xy 205.009386 -55.257472) (xy 204.847842 -55.271493) (xy 204.685801 -55.277509)
			(xy 204.523661 -55.275503) (xy 204.361819 -55.265482) (xy 204.200671 -55.247469) (xy 204.04061 -55.221509)
			(xy 203.882029 -55.187664) (xy 203.725316 -55.146019) (xy 203.570854 -55.096675) (xy 203.419022 -55.039753)
			(xy 203.27019 -54.975391) (xy 203.124723 -54.903748) (xy 202.982977 -54.824999) (xy 202.845299 -54.739336)
			(xy 202.712026 -54.646969) (xy 202.583484 -54.548125) (xy 202.459987 -54.443044) (xy 202.341839 -54.331985)
			(xy 202.229327 -54.215219) (xy 202.122727 -54.093031) (xy 202.0223 -53.965721) (xy 201.928292 -53.833601)
			(xy 201.840933 -53.696993) (xy 201.760436 -53.556232) (xy 201.687 -53.411662) (xy 201.620802 -53.263638)
			(xy 201.562006 -53.112521) (xy 201.510755 -52.958681) (xy 201.467175 -52.802495) (xy 201.431372 -52.644345)
			(xy 201.403434 -52.484618) (xy 201.38343 -52.323704) (xy 201.371407 -52.161999) (xy 201.367397 -51.999896)
			(xy 179.393088 -51.999896) (xy 179.393088 -52.481734) (xy 179.392602 -52.508985) (xy 179.384846 -52.562933)
			(xy 179.369491 -52.615228) (xy 179.346849 -52.664805) (xy 179.317383 -52.710655) (xy 179.281692 -52.751846)
			(xy 179.240501 -52.787537) (xy 179.194651 -52.817003) (xy 179.145074 -52.839645) (xy 179.092779 -52.855)
			(xy 179.038831 -52.862756) (xy 178.984329 -52.862756) (xy 178.930381 -52.855) (xy 178.878086 -52.839645)
			(xy 178.828509 -52.817003) (xy 178.782659 -52.787537) (xy 178.741468 -52.751846) (xy 178.705777 -52.710655)
			(xy 178.676311 -52.664805) (xy 178.653669 -52.615228) (xy 178.638314 -52.562933) (xy 178.630558 -52.508985)
			(xy 178.630072 -52.481734) (xy 0.509016 -52.481734) (xy 0.509016 -53.954934) (xy 181.659784 -53.954934)
			(xy 181.659784 -53.091334) (xy 181.66027 -53.064083) (xy 181.668026 -53.010135) (xy 181.683381 -52.95784)
			(xy 181.706023 -52.908263) (xy 181.735489 -52.862413) (xy 181.77118 -52.821222) (xy 181.812371 -52.785531)
			(xy 181.858221 -52.756065) (xy 181.907798 -52.733423) (xy 181.960093 -52.718068) (xy 182.014041 -52.710312)
			(xy 182.068543 -52.710312) (xy 182.122491 -52.718068) (xy 182.174786 -52.733423) (xy 182.224363 -52.756065)
			(xy 182.270213 -52.785531) (xy 182.311404 -52.821222) (xy 182.347095 -52.862413) (xy 182.376561 -52.908263)
			(xy 182.399203 -52.95784) (xy 182.414558 -53.010135) (xy 182.422314 -53.064083) (xy 182.4228 -53.091334)
			(xy 182.4228 -53.954934) (xy 182.422314 -53.982185) (xy 182.414558 -54.036133) (xy 182.399203 -54.088428)
			(xy 182.376561 -54.138005) (xy 182.347095 -54.183855) (xy 182.311404 -54.225046) (xy 182.270213 -54.260737)
			(xy 182.224363 -54.290203) (xy 182.174786 -54.312845) (xy 182.122491 -54.3282) (xy 182.068543 -54.335956)
			(xy 182.014041 -54.335956) (xy 181.960093 -54.3282) (xy 181.907798 -54.312845) (xy 181.858221 -54.290203)
			(xy 181.812371 -54.260737) (xy 181.77118 -54.225046) (xy 181.735489 -54.183855) (xy 181.706023 -54.138005)
			(xy 181.683381 -54.088428) (xy 181.668026 -54.036133) (xy 181.66027 -53.982185) (xy 181.659784 -53.954934)
			(xy 0.509016 -53.954934) (xy 0.509016 -55.481728) (xy 178.630072 -55.481728) (xy 178.630072 -54.618128)
			(xy 178.630558 -54.590877) (xy 178.638314 -54.536929) (xy 178.653669 -54.484634) (xy 178.676311 -54.435057)
			(xy 178.705777 -54.389207) (xy 178.741468 -54.348016) (xy 178.782659 -54.312325) (xy 178.828509 -54.282859)
			(xy 178.878086 -54.260217) (xy 178.930381 -54.244862) (xy 178.984329 -54.237106) (xy 179.038831 -54.237106)
			(xy 179.092779 -54.244862) (xy 179.145074 -54.260217) (xy 179.194651 -54.282859) (xy 179.240501 -54.312325)
			(xy 179.281692 -54.348016) (xy 179.317383 -54.389207) (xy 179.346849 -54.435057) (xy 179.369491 -54.484634)
			(xy 179.384846 -54.536929) (xy 179.392602 -54.590877) (xy 179.393088 -54.618128) (xy 179.393088 -55.481728)
			(xy 179.392602 -55.508979) (xy 179.384846 -55.562927) (xy 179.369491 -55.615222) (xy 179.346849 -55.664799)
			(xy 179.317383 -55.710649) (xy 179.281692 -55.75184) (xy 179.240501 -55.787531) (xy 179.194651 -55.816997)
			(xy 179.145074 -55.839639) (xy 179.092779 -55.854994) (xy 179.038831 -55.86275) (xy 178.984329 -55.86275)
			(xy 178.930381 -55.854994) (xy 178.878086 -55.839639) (xy 178.828509 -55.816997) (xy 178.782659 -55.787531)
			(xy 178.741468 -55.75184) (xy 178.705777 -55.710649) (xy 178.676311 -55.664799) (xy 178.653669 -55.615222)
			(xy 178.638314 -55.562927) (xy 178.630558 -55.508979) (xy 178.630072 -55.481728) (xy 0.509016 -55.481728)
			(xy 0.509016 -57.094435) (xy 170.841915 -57.094435) (xy 170.841915 -57.005413) (xy 170.849895 -56.916749)
			(xy 170.865791 -56.829158) (xy 170.889474 -56.743343) (xy 170.920754 -56.659998) (xy 170.95938 -56.579792)
			(xy 171.005039 -56.503371) (xy 171.057365 -56.43135) (xy 171.115936 -56.36431) (xy 171.180281 -56.30279)
			(xy 171.249881 -56.247286) (xy 171.324177 -56.198244) (xy 171.402569 -56.156059) (xy 171.484428 -56.121071)
			(xy 171.569093 -56.093562) (xy 171.655883 -56.073752) (xy 171.744099 -56.061802) (xy 171.833032 -56.057809)
			(xy 171.921965 -56.061802) (xy 172.010181 -56.073752) (xy 172.096971 -56.093562) (xy 172.181636 -56.121071)
			(xy 172.263495 -56.156059) (xy 172.341887 -56.198244) (xy 172.416183 -56.247286) (xy 172.485783 -56.30279)
			(xy 172.550128 -56.36431) (xy 172.608699 -56.43135) (xy 172.661025 -56.503371) (xy 172.663117 -56.506872)
			(xy 228.815392 -56.506872) (xy 228.815392 -55.643272) (xy 228.815878 -55.616021) (xy 228.823634 -55.562073)
			(xy 228.838989 -55.509778) (xy 228.861631 -55.460201) (xy 228.891097 -55.414351) (xy 228.926788 -55.37316)
			(xy 228.967979 -55.337469) (xy 229.013829 -55.308003) (xy 229.063406 -55.285361) (xy 229.115701 -55.270006)
			(xy 229.169649 -55.26225) (xy 229.224151 -55.26225) (xy 229.278099 -55.270006) (xy 229.330394 -55.285361)
			(xy 229.379971 -55.308003) (xy 229.425821 -55.337469) (xy 229.467012 -55.37316) (xy 229.502703 -55.414351)
			(xy 229.532169 -55.460201) (xy 229.554811 -55.509778) (xy 229.570166 -55.562073) (xy 229.577922 -55.616021)
			(xy 229.578408 -55.643272) (xy 229.578408 -55.911852) (xy 357.10365 -55.911852) (xy 357.10365 -55.857348)
			(xy 357.111406 -55.803398) (xy 357.126762 -55.751101) (xy 357.149403 -55.701521) (xy 357.17887 -55.655668)
			(xy 357.214562 -55.614476) (xy 357.255752 -55.578782) (xy 357.301604 -55.549313) (xy 357.351182 -55.526669)
			(xy 357.403478 -55.511311) (xy 357.457428 -55.503551) (xy 357.48468 -55.503064) (xy 358.34828 -55.503064)
			(xy 358.375532 -55.503582) (xy 358.429481 -55.511336) (xy 358.481777 -55.526689) (xy 358.531356 -55.549329)
			(xy 358.577209 -55.578794) (xy 358.618401 -55.614485) (xy 358.654094 -55.655675) (xy 358.683562 -55.701526)
			(xy 358.706204 -55.751104) (xy 358.72156 -55.8034) (xy 358.729317 -55.857348) (xy 358.729317 -55.911852)
			(xy 358.729316 -55.911856) (xy 359.950927 -55.911856) (xy 359.950927 -55.857344) (xy 359.958685 -55.803388)
			(xy 359.974043 -55.751084) (xy 359.996689 -55.701499) (xy 360.026161 -55.655642) (xy 360.061859 -55.614445)
			(xy 360.103058 -55.578749) (xy 360.148917 -55.549279) (xy 360.198503 -55.526636) (xy 360.250807 -55.511281)
			(xy 360.304764 -55.503526) (xy 360.33202 -55.503064) (xy 361.19562 -55.503064) (xy 361.222868 -55.503608)
			(xy 361.27681 -55.511366) (xy 361.329098 -55.526722) (xy 361.378669 -55.549362) (xy 361.424514 -55.578827)
			(xy 361.465699 -55.614516) (xy 361.501385 -55.655702) (xy 361.530847 -55.701548) (xy 361.553485 -55.75112)
			(xy 361.568838 -55.80341) (xy 361.576594 -55.857352) (xy 361.576594 -55.911848) (xy 361.576593 -55.911857)
			(xy 363.514527 -55.911857) (xy 363.514527 -55.857343) (xy 363.522286 -55.803385) (xy 363.537645 -55.75108)
			(xy 363.560292 -55.701493) (xy 363.589766 -55.655635) (xy 363.625466 -55.614438) (xy 363.666667 -55.578742)
			(xy 363.712529 -55.549273) (xy 363.762117 -55.526631) (xy 363.814424 -55.511277) (xy 363.868383 -55.503524)
			(xy 363.89564 -55.503064) (xy 364.75924 -55.503064) (xy 364.786487 -55.503609) (xy 364.840427 -55.511369)
			(xy 364.892713 -55.526727) (xy 364.942281 -55.549369) (xy 364.988123 -55.578834) (xy 365.029306 -55.614523)
			(xy 365.06499 -55.655709) (xy 365.094451 -55.701554) (xy 365.117087 -55.751125) (xy 365.132439 -55.803412)
			(xy 365.140194 -55.857353) (xy 365.140194 -55.911847) (xy 365.132439 -55.965788) (xy 365.117087 -56.018075)
			(xy 365.094451 -56.067646) (xy 365.06499 -56.113491) (xy 365.029306 -56.154677) (xy 364.988123 -56.190366)
			(xy 364.942281 -56.219831) (xy 364.892713 -56.242473) (xy 364.840427 -56.257831) (xy 364.786487 -56.265591)
			(xy 364.75924 -56.26608) (xy 363.89564 -56.26608) (xy 363.868383 -56.265676) (xy 363.814424 -56.257923)
			(xy 363.762117 -56.242569) (xy 363.712529 -56.219927) (xy 363.666667 -56.190458) (xy 363.625466 -56.154762)
			(xy 363.589766 -56.113565) (xy 363.560292 -56.067707) (xy 363.537645 -56.01812) (xy 363.522286 -55.965815)
			(xy 363.514527 -55.911857) (xy 361.576593 -55.911857) (xy 361.568838 -55.96579) (xy 361.553485 -56.01808)
			(xy 361.530847 -56.067652) (xy 361.501385 -56.113498) (xy 361.465699 -56.154684) (xy 361.424514 -56.190373)
			(xy 361.378669 -56.219838) (xy 361.329098 -56.242478) (xy 361.27681 -56.257834) (xy 361.222868 -56.265592)
			(xy 361.19562 -56.26608) (xy 360.33202 -56.26608) (xy 360.304764 -56.265674) (xy 360.250807 -56.257919)
			(xy 360.198503 -56.242564) (xy 360.148917 -56.219921) (xy 360.103058 -56.190451) (xy 360.061859 -56.154755)
			(xy 360.026161 -56.113558) (xy 359.996689 -56.067701) (xy 359.974043 -56.018116) (xy 359.958685 -55.965812)
			(xy 359.950927 -55.911856) (xy 358.729316 -55.911856) (xy 358.72156 -55.9658) (xy 358.706204 -56.018096)
			(xy 358.683562 -56.067674) (xy 358.654094 -56.113525) (xy 358.618401 -56.154715) (xy 358.577209 -56.190406)
			(xy 358.531356 -56.219871) (xy 358.481777 -56.242511) (xy 358.429481 -56.257864) (xy 358.375532 -56.265618)
			(xy 358.34828 -56.26608) (xy 357.48468 -56.26608) (xy 357.457428 -56.265649) (xy 357.403478 -56.257889)
			(xy 357.351182 -56.242531) (xy 357.301604 -56.219887) (xy 357.255752 -56.190418) (xy 357.214562 -56.154724)
			(xy 357.17887 -56.113532) (xy 357.149403 -56.067679) (xy 357.126762 -56.018099) (xy 357.111406 -55.965802)
			(xy 357.10365 -55.911852) (xy 229.578408 -55.911852) (xy 229.578408 -56.506872) (xy 229.577922 -56.534123)
			(xy 229.570166 -56.588071) (xy 229.554811 -56.640366) (xy 229.532169 -56.689943) (xy 229.502703 -56.735793)
			(xy 229.467012 -56.776984) (xy 229.425821 -56.812675) (xy 229.379971 -56.842141) (xy 229.330394 -56.864783)
			(xy 229.278099 -56.880138) (xy 229.224151 -56.887894) (xy 229.169649 -56.887894) (xy 229.115701 -56.880138)
			(xy 229.063406 -56.864783) (xy 229.013829 -56.842141) (xy 228.967979 -56.812675) (xy 228.926788 -56.776984)
			(xy 228.891097 -56.735793) (xy 228.861631 -56.689943) (xy 228.838989 -56.640366) (xy 228.823634 -56.588071)
			(xy 228.815878 -56.534123) (xy 228.815392 -56.506872) (xy 172.663117 -56.506872) (xy 172.706684 -56.579792)
			(xy 172.74531 -56.659998) (xy 172.77659 -56.743343) (xy 172.800273 -56.829158) (xy 172.816169 -56.916749)
			(xy 172.824149 -57.005413) (xy 172.824648 -57.049924) (xy 172.824149 -57.094435) (xy 172.816169 -57.183099)
			(xy 172.800273 -57.27069) (xy 172.77659 -57.356505) (xy 172.74531 -57.43985) (xy 172.706684 -57.520056)
			(xy 172.661025 -57.596477) (xy 172.608699 -57.668498) (xy 172.550128 -57.735538) (xy 172.485783 -57.797058)
			(xy 172.416183 -57.852562) (xy 172.341887 -57.901604) (xy 172.263495 -57.943789) (xy 172.181636 -57.978777)
			(xy 172.096971 -58.006286) (xy 172.010181 -58.026096) (xy 171.921965 -58.038046) (xy 171.833032 -58.04204)
			(xy 171.744099 -58.038046) (xy 171.655883 -58.026096) (xy 171.569093 -58.006286) (xy 171.484428 -57.978777)
			(xy 171.402569 -57.943789) (xy 171.324177 -57.901604) (xy 171.249881 -57.852562) (xy 171.180281 -57.797058)
			(xy 171.115936 -57.735538) (xy 171.057365 -57.668498) (xy 171.005039 -57.596477) (xy 170.95938 -57.520056)
			(xy 170.920754 -57.43985) (xy 170.889474 -57.356505) (xy 170.865791 -57.27069) (xy 170.849895 -57.183099)
			(xy 170.841915 -57.094435) (xy 0.509016 -57.094435) (xy 0.509016 -58.306716) (xy 230.115872 -58.306716)
			(xy 230.115872 -57.443116) (xy 230.116358 -57.415865) (xy 230.124114 -57.361917) (xy 230.139469 -57.309622)
			(xy 230.162111 -57.260045) (xy 230.191577 -57.214195) (xy 230.227268 -57.173004) (xy 230.268459 -57.137313)
			(xy 230.314309 -57.107847) (xy 230.363886 -57.085205) (xy 230.416181 -57.06985) (xy 230.470129 -57.062094)
			(xy 230.524631 -57.062094) (xy 230.578579 -57.06985) (xy 230.630874 -57.085205) (xy 230.680451 -57.107847)
			(xy 230.726301 -57.137313) (xy 230.767492 -57.173004) (xy 230.803183 -57.214195) (xy 230.832649 -57.260045)
			(xy 230.855291 -57.309622) (xy 230.870646 -57.361917) (xy 230.878402 -57.415865) (xy 230.878888 -57.443116)
			(xy 230.878888 -58.30189) (xy 240.282476 -58.30189) (xy 240.282476 -57.43829) (xy 240.282962 -57.411039)
			(xy 240.290718 -57.357091) (xy 240.306073 -57.304796) (xy 240.328715 -57.255219) (xy 240.358181 -57.209369)
			(xy 240.393872 -57.168178) (xy 240.435063 -57.132487) (xy 240.480913 -57.103021) (xy 240.53049 -57.080379)
			(xy 240.582785 -57.065024) (xy 240.636733 -57.057268) (xy 240.691235 -57.057268) (xy 240.745183 -57.065024)
			(xy 240.797478 -57.080379) (xy 240.847055 -57.103021) (xy 240.892905 -57.132487) (xy 240.934096 -57.168178)
			(xy 240.969787 -57.209369) (xy 240.999253 -57.255219) (xy 241.021895 -57.304796) (xy 241.03725 -57.357091)
			(xy 241.045006 -57.411039) (xy 241.045492 -57.43829) (xy 241.045492 -58.30189) (xy 241.045006 -58.329141)
			(xy 241.03725 -58.383089) (xy 241.021895 -58.435384) (xy 240.999253 -58.484961) (xy 240.969787 -58.530811)
			(xy 240.941894 -58.563002) (xy 242.736116 -58.563002) (xy 242.736116 -57.699402) (xy 242.736602 -57.672151)
			(xy 242.744358 -57.618203) (xy 242.759713 -57.565908) (xy 242.782355 -57.516331) (xy 242.811821 -57.470481)
			(xy 242.847512 -57.42929) (xy 242.888703 -57.393599) (xy 242.934553 -57.364133) (xy 242.98413 -57.341491)
			(xy 243.036425 -57.326136) (xy 243.090373 -57.31838) (xy 243.144875 -57.31838) (xy 243.198823 -57.326136)
			(xy 243.251118 -57.341491) (xy 243.300695 -57.364133) (xy 243.346545 -57.393599) (xy 243.387736 -57.42929)
			(xy 243.423427 -57.470481) (xy 243.452893 -57.516331) (xy 243.475535 -57.565908) (xy 243.49089 -57.618203)
			(xy 243.498646 -57.672151) (xy 243.499132 -57.699402) (xy 243.499132 -58.563002) (xy 243.498646 -58.590253)
			(xy 243.49089 -58.644201) (xy 243.475535 -58.696496) (xy 243.452893 -58.746073) (xy 243.423427 -58.791923)
			(xy 243.387736 -58.833114) (xy 243.346545 -58.868805) (xy 243.300695 -58.898271) (xy 243.251118 -58.920913)
			(xy 243.198823 -58.936268) (xy 243.144875 -58.944024) (xy 243.090373 -58.944024) (xy 243.036425 -58.936268)
			(xy 242.98413 -58.920913) (xy 242.934553 -58.898271) (xy 242.888703 -58.868805) (xy 242.847512 -58.833114)
			(xy 242.811821 -58.791923) (xy 242.782355 -58.746073) (xy 242.759713 -58.696496) (xy 242.744358 -58.644201)
			(xy 242.736602 -58.590253) (xy 242.736116 -58.563002) (xy 240.941894 -58.563002) (xy 240.934096 -58.572002)
			(xy 240.892905 -58.607693) (xy 240.847055 -58.637159) (xy 240.797478 -58.659801) (xy 240.745183 -58.675156)
			(xy 240.691235 -58.682912) (xy 240.636733 -58.682912) (xy 240.582785 -58.675156) (xy 240.53049 -58.659801)
			(xy 240.480913 -58.637159) (xy 240.435063 -58.607693) (xy 240.393872 -58.572002) (xy 240.358181 -58.530811)
			(xy 240.328715 -58.484961) (xy 240.306073 -58.435384) (xy 240.290718 -58.383089) (xy 240.282962 -58.329141)
			(xy 240.282476 -58.30189) (xy 230.878888 -58.30189) (xy 230.878888 -58.306716) (xy 230.878402 -58.333967)
			(xy 230.870646 -58.387915) (xy 230.855291 -58.44021) (xy 230.832649 -58.489787) (xy 230.803183 -58.535637)
			(xy 230.767492 -58.576828) (xy 230.726301 -58.612519) (xy 230.680451 -58.641985) (xy 230.630874 -58.664627)
			(xy 230.578579 -58.679982) (xy 230.524631 -58.687738) (xy 230.470129 -58.687738) (xy 230.416181 -58.679982)
			(xy 230.363886 -58.664627) (xy 230.314309 -58.641985) (xy 230.268459 -58.612519) (xy 230.227268 -58.576828)
			(xy 230.191577 -58.535637) (xy 230.162111 -58.489787) (xy 230.139469 -58.44021) (xy 230.124114 -58.387915)
			(xy 230.116358 -58.333967) (xy 230.115872 -58.306716) (xy 0.509016 -58.306716) (xy 0.509016 -59.99988)
			(xy 16.983969 -59.99988) (xy 16.987993 -59.914112) (xy 17.000031 -59.829098) (xy 17.019978 -59.745584)
			(xy 17.047657 -59.664305) (xy 17.082825 -59.585976) (xy 17.125174 -59.511283) (xy 17.174331 -59.440885)
			(xy 17.229864 -59.375399) (xy 17.291286 -59.315401) (xy 17.358055 -59.261418) (xy 17.429587 -59.213925)
			(xy 17.505251 -59.173339) (xy 17.584384 -59.140016) (xy 17.666289 -59.11425) (xy 17.750247 -59.096267)
			(xy 17.835521 -59.086225) (xy 17.92136 -59.084212) (xy 18.00701 -59.090246) (xy 18.091718 -59.104274)
			(xy 18.174741 -59.126173) (xy 18.255349 -59.15575) (xy 18.332833 -59.192745) (xy 18.406512 -59.236833)
			(xy 18.475738 -59.287627) (xy 18.539905 -59.34468) (xy 18.598446 -59.407491) (xy 18.650849 -59.475508)
			(xy 18.696652 -59.548133) (xy 18.735453 -59.624728) (xy 18.766912 -59.70462) (xy 18.790751 -59.787107)
			(xy 18.806761 -59.871464) (xy 18.814801 -59.956949) (xy 18.815304 -59.99988) (xy 18.814801 -60.042811)
			(xy 18.806761 -60.128296) (xy 18.790751 -60.212653) (xy 18.766912 -60.29514) (xy 18.735453 -60.375032)
			(xy 18.73545 -60.375038) (xy 233.333297 -60.375038) (xy 233.337302 -60.28713) (xy 233.349285 -60.19995)
			(xy 233.369145 -60.114221) (xy 233.39672 -60.030653) (xy 233.431779 -59.949939) (xy 233.474032 -59.872747)
			(xy 233.52313 -59.799718) (xy 233.578666 -59.731456) (xy 233.640178 -59.668526) (xy 233.707159 -59.611452)
			(xy 233.779052 -59.560704) (xy 233.855261 -59.516704) (xy 233.935156 -59.479817) (xy 234.018075 -59.450348)
			(xy 234.10333 -59.428541) (xy 234.190214 -59.414577) (xy 234.278008 -59.408571) (xy 234.365985 -59.410575)
			(xy 234.453415 -59.42057) (xy 234.539574 -59.438474) (xy 234.623748 -59.464138) (xy 234.705239 -59.497351)
			(xy 234.783373 -59.537837) (xy 234.857501 -59.585259) (xy 234.927009 -59.639226) (xy 234.991323 -59.699291)
			(xy 235.049907 -59.764955) (xy 235.102278 -59.835674) (xy 235.148001 -59.910862) (xy 235.186698 -59.989897)
			(xy 235.218047 -60.072123) (xy 235.241789 -60.156859) (xy 235.257727 -60.243403) (xy 235.265729 -60.331038)
			(xy 235.26623 -60.375038) (xy 235.265729 -60.419038) (xy 235.257727 -60.506673) (xy 235.241789 -60.593217)
			(xy 235.218047 -60.677953) (xy 235.186698 -60.760179) (xy 235.148001 -60.839214) (xy 235.102278 -60.914402)
			(xy 235.049907 -60.985121) (xy 234.991323 -61.050785) (xy 234.927009 -61.11085) (xy 234.857501 -61.164817)
			(xy 234.783373 -61.212239) (xy 234.705239 -61.252725) (xy 234.623748 -61.285938) (xy 234.539574 -61.311602)
			(xy 234.453415 -61.329506) (xy 234.365985 -61.339501) (xy 234.278008 -61.341505) (xy 234.190214 -61.335499)
			(xy 234.10333 -61.321535) (xy 234.018075 -61.299728) (xy 233.935156 -61.270259) (xy 233.855261 -61.233372)
			(xy 233.779052 -61.189372) (xy 233.707159 -61.138624) (xy 233.640178 -61.08155) (xy 233.578666 -61.01862)
			(xy 233.52313 -60.950358) (xy 233.474032 -60.877329) (xy 233.431779 -60.800137) (xy 233.39672 -60.719423)
			(xy 233.369145 -60.635855) (xy 233.349285 -60.550126) (xy 233.337302 -60.462946) (xy 233.333297 -60.375038)
			(xy 18.73545 -60.375038) (xy 18.696652 -60.451627) (xy 18.650849 -60.524252) (xy 18.598446 -60.592269)
			(xy 18.539905 -60.65508) (xy 18.475738 -60.712133) (xy 18.406512 -60.762927) (xy 18.332833 -60.807015)
			(xy 18.255349 -60.84401) (xy 18.174741 -60.873587) (xy 18.091718 -60.895486) (xy 18.00701 -60.909514)
			(xy 17.92136 -60.915548) (xy 17.835521 -60.913535) (xy 17.750247 -60.903493) (xy 17.666289 -60.88551)
			(xy 17.584384 -60.859744) (xy 17.505251 -60.826421) (xy 17.429587 -60.785835) (xy 17.358055 -60.738342)
			(xy 17.291286 -60.684359) (xy 17.229864 -60.624361) (xy 17.174331 -60.558875) (xy 17.125174 -60.488477)
			(xy 17.082825 -60.413784) (xy 17.047657 -60.335455) (xy 17.019978 -60.254176) (xy 17.000031 -60.170662)
			(xy 16.987993 -60.085648) (xy 16.983969 -59.99988) (xy 0.509016 -59.99988) (xy 0.509016 -74.760836)
			(xy 39.554404 -74.760836) (xy 39.554404 -66.060828) (xy 39.554909 -65.955304) (xy 39.562993 -65.74441)
			(xy 39.579149 -65.533981) (xy 39.603352 -65.324324) (xy 39.635569 -65.115749) (xy 39.675751 -64.908561)
			(xy 39.723839 -64.703064) (xy 39.779763 -64.49956) (xy 39.84344 -64.298347) (xy 39.914778 -64.09972)
			(xy 39.993672 -63.903972) (xy 40.080005 -63.71139) (xy 40.173652 -63.522255) (xy 40.274474 -63.336846)
			(xy 40.382324 -63.155435) (xy 40.497043 -62.978288) (xy 40.618463 -62.805666) (xy 40.746406 -62.63782)
			(xy 40.880684 -62.474998) (xy 41.0211 -62.317439) (xy 41.167448 -62.165374) (xy 41.319513 -62.019026)
			(xy 41.477072 -61.87861) (xy 41.639894 -61.744332) (xy 41.80774 -61.616389) (xy 41.980362 -61.494969)
			(xy 42.157509 -61.38025) (xy 42.33892 -61.2724) (xy 42.524329 -61.171578) (xy 42.713464 -61.077931)
			(xy 42.906046 -60.991598) (xy 43.101794 -60.912704) (xy 43.300421 -60.841366) (xy 43.501634 -60.777689)
			(xy 43.705138 -60.721765) (xy 43.910635 -60.673677) (xy 44.117823 -60.633495) (xy 44.326398 -60.601278)
			(xy 44.536055 -60.577075) (xy 44.746484 -60.560919) (xy 44.957378 -60.552835) (xy 45.168426 -60.552835)
			(xy 45.37932 -60.560919) (xy 45.589749 -60.577075) (xy 45.799406 -60.601278) (xy 46.007981 -60.633495)
			(xy 46.215169 -60.673677) (xy 46.420666 -60.721765) (xy 46.62417 -60.777689) (xy 46.825383 -60.841366)
			(xy 47.02401 -60.912704) (xy 47.219758 -60.991598) (xy 47.41234 -61.077931) (xy 47.601475 -61.171578)
			(xy 47.786884 -61.2724) (xy 47.968295 -61.38025) (xy 48.145442 -61.494969) (xy 48.318064 -61.616389)
			(xy 48.48591 -61.744332) (xy 48.648732 -61.87861) (xy 48.806291 -62.019026) (xy 48.958356 -62.165374)
			(xy 49.104704 -62.317439) (xy 49.24512 -62.474998) (xy 49.379398 -62.63782) (xy 49.507341 -62.805666)
			(xy 49.628761 -62.978288) (xy 49.74348 -63.155435) (xy 49.85133 -63.336846) (xy 49.952152 -63.522255)
			(xy 50.045799 -63.71139) (xy 50.132132 -63.903972) (xy 50.211026 -64.09972) (xy 50.282364 -64.298347)
			(xy 50.346041 -64.49956) (xy 50.401965 -64.703064) (xy 50.450053 -64.908561) (xy 50.490235 -65.115749)
			(xy 50.522452 -65.324324) (xy 50.546655 -65.533981) (xy 50.562811 -65.74441) (xy 50.570895 -65.955304)
			(xy 50.5714 -66.060828) (xy 50.5714 -74.760836) (xy 50.571366 -74.767948) (xy 173.354492 -74.767948)
			(xy 173.354492 -66.06794) (xy 173.354997 -65.962416) (xy 173.363081 -65.751522) (xy 173.379237 -65.541093)
			(xy 173.40344 -65.331436) (xy 173.435657 -65.122861) (xy 173.475839 -64.915673) (xy 173.523927 -64.710176)
			(xy 173.579851 -64.506672) (xy 173.643528 -64.305459) (xy 173.714866 -64.106832) (xy 173.79376 -63.911084)
			(xy 173.880093 -63.718502) (xy 173.97374 -63.529367) (xy 174.074562 -63.343958) (xy 174.182412 -63.162547)
			(xy 174.297131 -62.9854) (xy 174.418551 -62.812778) (xy 174.546494 -62.644932) (xy 174.680772 -62.48211)
			(xy 174.821188 -62.324551) (xy 174.967536 -62.172486) (xy 175.119601 -62.026138) (xy 175.27716 -61.885722)
			(xy 175.439982 -61.751444) (xy 175.607828 -61.623501) (xy 175.78045 -61.502081) (xy 175.957597 -61.387362)
			(xy 176.139008 -61.279512) (xy 176.324417 -61.17869) (xy 176.513552 -61.085043) (xy 176.706134 -60.99871)
			(xy 176.901882 -60.919816) (xy 177.100509 -60.848478) (xy 177.301722 -60.784801) (xy 177.505226 -60.728877)
			(xy 177.710723 -60.680789) (xy 177.917911 -60.640607) (xy 178.126486 -60.60839) (xy 178.336143 -60.584187)
			(xy 178.546572 -60.568031) (xy 178.757466 -60.559947) (xy 178.968514 -60.559947) (xy 179.179408 -60.568031)
			(xy 179.389837 -60.584187) (xy 179.599494 -60.60839) (xy 179.808069 -60.640607) (xy 180.015257 -60.680789)
			(xy 180.220754 -60.728877) (xy 180.424258 -60.784801) (xy 180.625471 -60.848478) (xy 180.824098 -60.919816)
			(xy 181.019846 -60.99871) (xy 181.212428 -61.085043) (xy 181.401563 -61.17869) (xy 181.586972 -61.279512)
			(xy 181.768383 -61.387362) (xy 181.94553 -61.502081) (xy 182.118152 -61.623501) (xy 182.285998 -61.751444)
			(xy 182.44882 -61.885722) (xy 182.606379 -62.026138) (xy 182.758444 -62.172486) (xy 182.904792 -62.324551)
			(xy 183.045208 -62.48211) (xy 183.179486 -62.644932) (xy 183.307429 -62.812778) (xy 183.428849 -62.9854)
			(xy 183.543568 -63.162547) (xy 183.651418 -63.343958) (xy 183.75224 -63.529367) (xy 183.845887 -63.718502)
			(xy 183.93222 -63.911084) (xy 184.011114 -64.106832) (xy 184.082452 -64.305459) (xy 184.146129 -64.506672)
			(xy 184.202053 -64.710176) (xy 184.250141 -64.915673) (xy 184.290323 -65.122861) (xy 184.32254 -65.331436)
			(xy 184.346743 -65.541093) (xy 184.362899 -65.751522) (xy 184.370983 -65.962416) (xy 184.371488 -66.06794)
			(xy 184.371488 -74.760836) (xy 287.494472 -74.760836) (xy 287.494472 -66.060828) (xy 287.494977 -65.955304)
			(xy 287.503061 -65.74441) (xy 287.519217 -65.533981) (xy 287.54342 -65.324324) (xy 287.575637 -65.115749)
			(xy 287.615819 -64.908561) (xy 287.663907 -64.703064) (xy 287.719831 -64.49956) (xy 287.783508 -64.298347)
			(xy 287.854846 -64.09972) (xy 287.93374 -63.903972) (xy 288.020073 -63.71139) (xy 288.11372 -63.522255)
			(xy 288.214542 -63.336846) (xy 288.322392 -63.155435) (xy 288.437111 -62.978288) (xy 288.558531 -62.805666)
			(xy 288.686474 -62.63782) (xy 288.820752 -62.474998) (xy 288.961168 -62.317439) (xy 289.107516 -62.165374)
			(xy 289.259581 -62.019026) (xy 289.41714 -61.87861) (xy 289.579962 -61.744332) (xy 289.747808 -61.616389)
			(xy 289.92043 -61.494969) (xy 290.097577 -61.38025) (xy 290.278988 -61.2724) (xy 290.464397 -61.171578)
			(xy 290.653532 -61.077931) (xy 290.846114 -60.991598) (xy 291.041862 -60.912704) (xy 291.240489 -60.841366)
			(xy 291.441702 -60.777689) (xy 291.645206 -60.721765) (xy 291.850703 -60.673677) (xy 292.057891 -60.633495)
			(xy 292.266466 -60.601278) (xy 292.476123 -60.577075) (xy 292.686552 -60.560919) (xy 292.897446 -60.552835)
			(xy 293.108494 -60.552835) (xy 293.319388 -60.560919) (xy 293.529817 -60.577075) (xy 293.739474 -60.601278)
			(xy 293.948049 -60.633495) (xy 294.155237 -60.673677) (xy 294.360734 -60.721765) (xy 294.564238 -60.777689)
			(xy 294.765451 -60.841366) (xy 294.964078 -60.912704) (xy 295.159826 -60.991598) (xy 295.352408 -61.077931)
			(xy 295.541543 -61.171578) (xy 295.726952 -61.2724) (xy 295.908363 -61.38025) (xy 296.063868 -61.480954)
			(xy 351.822512 -61.480954) (xy 351.822512 -60.617354) (xy 351.822998 -60.590103) (xy 351.830754 -60.536155)
			(xy 351.846109 -60.48386) (xy 351.868751 -60.434283) (xy 351.898217 -60.388433) (xy 351.933908 -60.347242)
			(xy 351.975099 -60.311551) (xy 352.020949 -60.282085) (xy 352.070526 -60.259443) (xy 352.122821 -60.244088)
			(xy 352.176769 -60.236332) (xy 352.231271 -60.236332) (xy 352.285219 -60.244088) (xy 352.337514 -60.259443)
			(xy 352.387091 -60.282085) (xy 352.432941 -60.311551) (xy 352.474132 -60.347242) (xy 352.509823 -60.388433)
			(xy 352.539289 -60.434283) (xy 352.561931 -60.48386) (xy 352.577286 -60.536155) (xy 352.585042 -60.590103)
			(xy 352.585528 -60.617354) (xy 352.585528 -61.223271) (xy 355.46889 -61.223271) (xy 355.46889 -61.168729)
			(xy 355.476653 -61.114741) (xy 355.492019 -61.062408) (xy 355.514676 -61.012794) (xy 355.544164 -60.966909)
			(xy 355.579881 -60.925688) (xy 355.621101 -60.88997) (xy 355.666985 -60.860481) (xy 355.716598 -60.837822)
			(xy 355.768931 -60.822455) (xy 355.822919 -60.814691) (xy 355.85019 -60.814204) (xy 356.71379 -60.814204)
			(xy 356.741059 -60.814735) (xy 356.795042 -60.822495) (xy 356.847371 -60.837859) (xy 356.896981 -60.860514)
			(xy 356.942862 -60.889999) (xy 356.98408 -60.925713) (xy 357.019795 -60.96693) (xy 357.049281 -61.01281)
			(xy 357.071937 -61.062419) (xy 357.087303 -61.114748) (xy 357.095065 -61.168731) (xy 357.095065 -61.223269)
			(xy 357.087303 -61.277252) (xy 357.071937 -61.329581) (xy 357.049281 -61.37919) (xy 357.019795 -61.42507)
			(xy 356.98408 -61.466287) (xy 356.942862 -61.502001) (xy 356.896981 -61.531486) (xy 356.847371 -61.554141)
			(xy 356.795042 -61.569505) (xy 356.741059 -61.577265) (xy 356.71379 -61.577728) (xy 355.85019 -61.577728)
			(xy 355.822919 -61.577309) (xy 355.768931 -61.569545) (xy 355.716598 -61.554178) (xy 355.666985 -61.531519)
			(xy 355.621101 -61.50203) (xy 355.579881 -61.466312) (xy 355.544164 -61.425091) (xy 355.514676 -61.379206)
			(xy 355.492019 -61.329592) (xy 355.476653 -61.277259) (xy 355.46889 -61.223271) (xy 352.585528 -61.223271)
			(xy 352.585528 -61.480954) (xy 352.585042 -61.508205) (xy 352.577286 -61.562153) (xy 352.561931 -61.614448)
			(xy 352.539289 -61.664025) (xy 352.509823 -61.709875) (xy 352.474132 -61.751066) (xy 352.432941 -61.786757)
			(xy 352.387091 -61.816223) (xy 352.337514 -61.838865) (xy 352.285219 -61.85422) (xy 352.231271 -61.861976)
			(xy 352.176769 -61.861976) (xy 352.122821 -61.85422) (xy 352.070526 -61.838865) (xy 352.020949 -61.816223)
			(xy 351.975099 -61.786757) (xy 351.933908 -61.751066) (xy 351.898217 -61.709875) (xy 351.868751 -61.664025)
			(xy 351.846109 -61.614448) (xy 351.830754 -61.562153) (xy 351.822998 -61.508205) (xy 351.822512 -61.480954)
			(xy 296.063868 -61.480954) (xy 296.08551 -61.494969) (xy 296.258132 -61.616389) (xy 296.425978 -61.744332)
			(xy 296.5888 -61.87861) (xy 296.746359 -62.019026) (xy 296.898424 -62.165374) (xy 297.044772 -62.317439)
			(xy 297.185188 -62.474998) (xy 297.319466 -62.63782) (xy 297.447409 -62.805666) (xy 297.568829 -62.978288)
			(xy 297.683548 -63.155435) (xy 297.751584 -63.269876) (xy 350.300544 -63.269876) (xy 350.300544 -62.406276)
			(xy 350.30103 -62.379025) (xy 350.308786 -62.325077) (xy 350.324141 -62.272782) (xy 350.346783 -62.223205)
			(xy 350.376249 -62.177355) (xy 350.41194 -62.136164) (xy 350.453131 -62.100473) (xy 350.498981 -62.071007)
			(xy 350.548558 -62.048365) (xy 350.600853 -62.03301) (xy 350.654801 -62.025254) (xy 350.709303 -62.025254)
			(xy 350.763251 -62.03301) (xy 350.815546 -62.048365) (xy 350.865123 -62.071007) (xy 350.910973 -62.100473)
			(xy 350.952164 -62.136164) (xy 350.987855 -62.177355) (xy 351.017321 -62.223205) (xy 351.039963 -62.272782)
			(xy 351.055318 -62.325077) (xy 351.063074 -62.379025) (xy 351.06356 -62.406276) (xy 351.06356 -63.269876)
			(xy 351.063074 -63.297127) (xy 351.055318 -63.351075) (xy 351.039963 -63.40337) (xy 351.017321 -63.452947)
			(xy 350.987855 -63.498797) (xy 350.952164 -63.539988) (xy 350.910973 -63.575679) (xy 350.865123 -63.605145)
			(xy 350.815546 -63.627787) (xy 350.763251 -63.643142) (xy 350.709303 -63.650898) (xy 350.654801 -63.650898)
			(xy 350.600853 -63.643142) (xy 350.548558 -63.627787) (xy 350.498981 -63.605145) (xy 350.453131 -63.575679)
			(xy 350.41194 -63.539988) (xy 350.376249 -63.498797) (xy 350.346783 -63.452947) (xy 350.324141 -63.40337)
			(xy 350.308786 -63.351075) (xy 350.30103 -63.297127) (xy 350.300544 -63.269876) (xy 297.751584 -63.269876)
			(xy 297.791398 -63.336846) (xy 297.89222 -63.522255) (xy 297.985867 -63.71139) (xy 298.0722 -63.903972)
			(xy 298.151094 -64.09972) (xy 298.222432 -64.298347) (xy 298.286109 -64.49956) (xy 298.342033 -64.703064)
			(xy 298.390121 -64.908561) (xy 298.396302 -64.940434) (xy 325.410068 -64.940434) (xy 325.410068 -64.076834)
			(xy 325.410554 -64.049565) (xy 325.418316 -63.995581) (xy 325.433681 -63.943251) (xy 325.456338 -63.893641)
			(xy 325.485824 -63.84776) (xy 325.521539 -63.806543) (xy 325.562756 -63.770828) (xy 325.608637 -63.741342)
			(xy 325.658247 -63.718685) (xy 325.710577 -63.70332) (xy 325.764561 -63.695558) (xy 325.819099 -63.695558)
			(xy 325.873083 -63.70332) (xy 325.925413 -63.718685) (xy 325.975023 -63.741342) (xy 326.020904 -63.770828)
			(xy 326.062121 -63.806543) (xy 326.097836 -63.84776) (xy 326.127322 -63.893641) (xy 326.149979 -63.943251)
			(xy 326.165344 -63.995581) (xy 326.173106 -64.049565) (xy 326.173592 -64.076834) (xy 326.173592 -64.940434)
			(xy 326.173106 -64.967703) (xy 326.165344 -65.021687) (xy 326.149979 -65.074017) (xy 326.127322 -65.123627)
			(xy 326.097836 -65.169508) (xy 326.062121 -65.210725) (xy 326.020904 -65.24644) (xy 325.975023 -65.275926)
			(xy 325.925413 -65.298583) (xy 325.873083 -65.313948) (xy 325.819099 -65.32171) (xy 325.764561 -65.32171)
			(xy 325.710577 -65.313948) (xy 325.658247 -65.298583) (xy 325.608637 -65.275926) (xy 325.562756 -65.24644)
			(xy 325.521539 -65.210725) (xy 325.485824 -65.169508) (xy 325.456338 -65.123627) (xy 325.433681 -65.074017)
			(xy 325.418316 -65.021687) (xy 325.410554 -64.967703) (xy 325.410068 -64.940434) (xy 298.396302 -64.940434)
			(xy 298.430303 -65.115749) (xy 298.46252 -65.324324) (xy 298.463125 -65.329562) (xy 352.362008 -65.329562)
			(xy 352.362008 -64.465962) (xy 352.362494 -64.438711) (xy 352.37025 -64.384763) (xy 352.385605 -64.332468)
			(xy 352.408247 -64.282891) (xy 352.437713 -64.237041) (xy 352.473404 -64.19585) (xy 352.514595 -64.160159)
			(xy 352.560445 -64.130693) (xy 352.610022 -64.108051) (xy 352.662317 -64.092696) (xy 352.716265 -64.08494)
			(xy 352.770767 -64.08494) (xy 352.824715 -64.092696) (xy 352.87701 -64.108051) (xy 352.926587 -64.130693)
			(xy 352.972437 -64.160159) (xy 353.013628 -64.19585) (xy 353.049319 -64.237041) (xy 353.078785 -64.282891)
			(xy 353.101427 -64.332468) (xy 353.116782 -64.384763) (xy 353.124538 -64.438711) (xy 353.125024 -64.465962)
			(xy 353.125024 -65.329562) (xy 353.124538 -65.356813) (xy 353.116782 -65.410761) (xy 353.101427 -65.463056)
			(xy 353.078785 -65.512633) (xy 353.049319 -65.558483) (xy 353.013628 -65.599674) (xy 352.972437 -65.635365)
			(xy 352.926587 -65.664831) (xy 352.87701 -65.687473) (xy 352.824715 -65.702828) (xy 352.770767 -65.710584)
			(xy 352.716265 -65.710584) (xy 352.662317 -65.702828) (xy 352.610022 -65.687473) (xy 352.560445 -65.664831)
			(xy 352.514595 -65.635365) (xy 352.473404 -65.599674) (xy 352.437713 -65.558483) (xy 352.408247 -65.512633)
			(xy 352.385605 -65.463056) (xy 352.37025 -65.410761) (xy 352.362494 -65.356813) (xy 352.362008 -65.329562)
			(xy 298.463125 -65.329562) (xy 298.486723 -65.533981) (xy 298.502879 -65.74441) (xy 298.510963 -65.955304)
			(xy 298.511468 -66.060828) (xy 298.511468 -68.449952) (xy 314.840884 -68.449952) (xy 314.844867 -68.321934)
			(xy 314.856802 -68.194412) (xy 314.876641 -68.067878) (xy 314.904308 -67.942822) (xy 314.939697 -67.819729)
			(xy 314.98267 -67.699073) (xy 315.033061 -67.581323) (xy 315.090675 -67.466933) (xy 315.155289 -67.356346)
			(xy 315.226653 -67.24999) (xy 315.304491 -67.148277) (xy 315.388502 -67.051599) (xy 315.478361 -66.960332)
			(xy 315.57372 -66.874827) (xy 315.674211 -66.795417) (xy 315.779444 -66.722407) (xy 315.889013 -66.656081)
			(xy 316.002493 -66.596695) (xy 316.119445 -66.544479) (xy 316.239418 -66.499635) (xy 316.361946 -66.462337)
			(xy 316.486557 -66.432728) (xy 316.612766 -66.410923) (xy 316.740088 -66.397007) (xy 316.868028 -66.391033)
			(xy 316.996092 -66.393025) (xy 317.123785 -66.402975) (xy 317.250612 -66.420844) (xy 317.376083 -66.446563)
			(xy 317.499712 -66.480033) (xy 317.621021 -66.521124) (xy 317.739541 -66.569678) (xy 317.854813 -66.625506)
			(xy 317.966391 -66.688392) (xy 318.073844 -66.758094) (xy 318.176756 -66.834341) (xy 318.274728 -66.916838)
			(xy 318.323666 -66.963544) (xy 350.27108 -66.963544) (xy 350.27108 -66.099944) (xy 350.271566 -66.072693)
			(xy 350.279322 -66.018745) (xy 350.294677 -65.96645) (xy 350.317319 -65.916873) (xy 350.346785 -65.871023)
			(xy 350.382476 -65.829832) (xy 350.423667 -65.794141) (xy 350.469517 -65.764675) (xy 350.519094 -65.742033)
			(xy 350.571389 -65.726678) (xy 350.625337 -65.718922) (xy 350.679839 -65.718922) (xy 350.733787 -65.726678)
			(xy 350.786082 -65.742033) (xy 350.835659 -65.764675) (xy 350.881509 -65.794141) (xy 350.9227 -65.829832)
			(xy 350.958391 -65.871023) (xy 350.987857 -65.916873) (xy 351.010499 -65.96645) (xy 351.025854 -66.018745)
			(xy 351.03361 -66.072693) (xy 351.034096 -66.099944) (xy 351.034096 -66.963544) (xy 351.03361 -66.990795)
			(xy 351.025854 -67.044743) (xy 351.010499 -67.097038) (xy 351.005595 -67.107776) (xy 396.642323 -67.107776)
			(xy 396.642323 -67.022004) (xy 396.650237 -66.936596) (xy 396.665998 -66.852284) (xy 396.689471 -66.769785)
			(xy 396.720456 -66.689804) (xy 396.758688 -66.613023) (xy 396.803842 -66.540098) (xy 396.855532 -66.47165)
			(xy 396.913317 -66.408263) (xy 396.976704 -66.350478) (xy 397.045152 -66.298788) (xy 397.118077 -66.253634)
			(xy 397.194858 -66.215402) (xy 397.274839 -66.184417) (xy 397.357338 -66.160944) (xy 397.44165 -66.145183)
			(xy 397.527058 -66.137269) (xy 397.61283 -66.137269) (xy 397.698238 -66.145183) (xy 397.78255 -66.160944)
			(xy 397.865049 -66.184417) (xy 397.94503 -66.215402) (xy 398.021811 -66.253634) (xy 398.094736 -66.298788)
			(xy 398.163184 -66.350478) (xy 398.226571 -66.408263) (xy 398.284356 -66.47165) (xy 398.336046 -66.540098)
			(xy 398.3812 -66.613023) (xy 398.419432 -66.689804) (xy 398.450417 -66.769785) (xy 398.47389 -66.852284)
			(xy 398.489651 -66.936596) (xy 398.497565 -67.022004) (xy 398.49806 -67.06489) (xy 398.497565 -67.107776)
			(xy 398.489651 -67.193184) (xy 398.47389 -67.277496) (xy 398.450417 -67.359995) (xy 398.419432 -67.439976)
			(xy 398.3812 -67.516757) (xy 398.336046 -67.589682) (xy 398.284356 -67.65813) (xy 398.226571 -67.721517)
			(xy 398.163184 -67.779302) (xy 398.094736 -67.830992) (xy 398.021811 -67.876146) (xy 397.94503 -67.914378)
			(xy 397.865049 -67.945363) (xy 397.78255 -67.968836) (xy 397.698238 -67.984597) (xy 397.61283 -67.992511)
			(xy 397.527058 -67.992511) (xy 397.44165 -67.984597) (xy 397.357338 -67.968836) (xy 397.274839 -67.945363)
			(xy 397.194858 -67.914378) (xy 397.118077 -67.876146) (xy 397.045152 -67.830992) (xy 396.976704 -67.779302)
			(xy 396.913317 -67.721517) (xy 396.855532 -67.65813) (xy 396.803842 -67.589682) (xy 396.758688 -67.516757)
			(xy 396.720456 -67.439976) (xy 396.689471 -67.359995) (xy 396.665998 -67.277496) (xy 396.650237 -67.193184)
			(xy 396.642323 -67.107776) (xy 351.005595 -67.107776) (xy 350.987857 -67.146615) (xy 350.958391 -67.192465)
			(xy 350.9227 -67.233656) (xy 350.881509 -67.269347) (xy 350.835659 -67.298813) (xy 350.786082 -67.321455)
			(xy 350.733787 -67.33681) (xy 350.679839 -67.344566) (xy 350.625337 -67.344566) (xy 350.571389 -67.33681)
			(xy 350.519094 -67.321455) (xy 350.469517 -67.298813) (xy 350.423667 -67.269347) (xy 350.382476 -67.233656)
			(xy 350.346785 -67.192465) (xy 350.317319 -67.146615) (xy 350.294677 -67.097038) (xy 350.279322 -67.044743)
			(xy 350.271566 -66.990795) (xy 350.27108 -66.963544) (xy 318.323666 -66.963544) (xy 318.367382 -67.005267)
			(xy 318.454359 -67.099285) (xy 318.535323 -67.198528) (xy 318.60996 -67.302613) (xy 318.677982 -67.411137)
			(xy 318.739126 -67.52368) (xy 318.793154 -67.639806) (xy 318.839859 -67.759067) (xy 318.879059 -67.881)
			(xy 318.910602 -68.005135) (xy 318.934367 -68.130991) (xy 318.950261 -68.25808) (xy 318.958224 -68.385912)
			(xy 318.958722 -68.449952) (xy 318.958224 -68.513992) (xy 318.950261 -68.641824) (xy 318.934367 -68.768913)
			(xy 318.910602 -68.894769) (xy 318.879059 -69.018904) (xy 318.851129 -69.10578) (xy 351.73158 -69.10578)
			(xy 351.73158 -68.24218) (xy 351.732066 -68.214911) (xy 351.739828 -68.160927) (xy 351.755193 -68.108597)
			(xy 351.77785 -68.058987) (xy 351.807336 -68.013106) (xy 351.843051 -67.971889) (xy 351.884268 -67.936174)
			(xy 351.930149 -67.906688) (xy 351.979759 -67.884031) (xy 352.032089 -67.868666) (xy 352.086073 -67.860904)
			(xy 352.140611 -67.860904) (xy 352.194595 -67.868666) (xy 352.246925 -67.884031) (xy 352.296535 -67.906688)
			(xy 352.342416 -67.936174) (xy 352.383633 -67.971889) (xy 352.419348 -68.013106) (xy 352.448834 -68.058987)
			(xy 352.471491 -68.108597) (xy 352.486856 -68.160927) (xy 352.494618 -68.214911) (xy 352.495104 -68.24218)
			(xy 352.495104 -69.10578) (xy 352.494618 -69.133049) (xy 352.486856 -69.187033) (xy 352.471491 -69.239363)
			(xy 352.448834 -69.288973) (xy 352.419348 -69.334854) (xy 352.383633 -69.376071) (xy 352.342416 -69.411786)
			(xy 352.296535 -69.441272) (xy 352.246925 -69.463929) (xy 352.194595 -69.479294) (xy 352.140611 -69.487056)
			(xy 352.086073 -69.487056) (xy 352.032089 -69.479294) (xy 351.979759 -69.463929) (xy 351.930149 -69.441272)
			(xy 351.884268 -69.411786) (xy 351.843051 -69.376071) (xy 351.807336 -69.334854) (xy 351.77785 -69.288973)
			(xy 351.755193 -69.239363) (xy 351.739828 -69.187033) (xy 351.732066 -69.133049) (xy 351.73158 -69.10578)
			(xy 318.851129 -69.10578) (xy 318.839859 -69.140837) (xy 318.793154 -69.260098) (xy 318.739126 -69.376224)
			(xy 318.677982 -69.488767) (xy 318.60996 -69.597291) (xy 318.535323 -69.701376) (xy 318.454359 -69.800619)
			(xy 318.367382 -69.894637) (xy 318.274728 -69.983066) (xy 318.176756 -70.065563) (xy 318.073844 -70.14181)
			(xy 317.966391 -70.211512) (xy 317.854813 -70.274398) (xy 317.739541 -70.330226) (xy 317.621021 -70.37878)
			(xy 317.499712 -70.419871) (xy 317.376083 -70.453341) (xy 317.250612 -70.47906) (xy 317.123785 -70.496929)
			(xy 316.996092 -70.506879) (xy 316.868028 -70.508871) (xy 316.740088 -70.502897) (xy 316.612766 -70.488981)
			(xy 316.486557 -70.467176) (xy 316.361946 -70.437567) (xy 316.239418 -70.400269) (xy 316.119445 -70.355425)
			(xy 316.002493 -70.303209) (xy 315.889013 -70.243823) (xy 315.779444 -70.177497) (xy 315.674211 -70.104487)
			(xy 315.57372 -70.025077) (xy 315.478361 -69.939572) (xy 315.388502 -69.848305) (xy 315.304491 -69.751627)
			(xy 315.226653 -69.649914) (xy 315.155289 -69.543558) (xy 315.090675 -69.432971) (xy 315.033061 -69.318581)
			(xy 314.98267 -69.200831) (xy 314.939697 -69.080175) (xy 314.904308 -68.957082) (xy 314.876641 -68.832026)
			(xy 314.856802 -68.705492) (xy 314.844867 -68.57797) (xy 314.840884 -68.449952) (xy 298.511468 -68.449952)
			(xy 298.511468 -71.213074) (xy 341.168388 -71.213074) (xy 341.168388 -71.158526) (xy 341.176151 -71.104534)
			(xy 341.19152 -71.052197) (xy 341.214181 -71.00258) (xy 341.243673 -70.956692) (xy 341.279395 -70.91547)
			(xy 341.320621 -70.879751) (xy 341.366511 -70.850263) (xy 341.416131 -70.827607) (xy 341.46847 -70.812243)
			(xy 341.522462 -70.804485) (xy 341.549736 -70.804024) (xy 342.413336 -70.804024) (xy 342.440603 -70.804541)
			(xy 342.49458 -70.812306) (xy 342.546904 -70.827674) (xy 342.596508 -70.850332) (xy 342.642382 -70.879817)
			(xy 342.683594 -70.915531) (xy 342.719304 -70.956747) (xy 342.748786 -71.002624) (xy 342.771438 -71.05223)
			(xy 342.786801 -71.104555) (xy 342.794562 -71.158533) (xy 342.794562 -71.213067) (xy 342.786801 -71.267045)
			(xy 342.771438 -71.31937) (xy 342.748786 -71.368976) (xy 342.719304 -71.414853) (xy 342.683594 -71.456069)
			(xy 342.642382 -71.491783) (xy 342.596508 -71.521268) (xy 342.546904 -71.543926) (xy 342.49458 -71.559294)
			(xy 342.440603 -71.567059) (xy 342.413336 -71.567548) (xy 341.549736 -71.567548) (xy 341.522462 -71.567115)
			(xy 341.46847 -71.559357) (xy 341.416131 -71.543993) (xy 341.366511 -71.521337) (xy 341.320621 -71.491849)
			(xy 341.279395 -71.45613) (xy 341.243673 -71.414908) (xy 341.214181 -71.36902) (xy 341.19152 -71.319403)
			(xy 341.176151 -71.267066) (xy 341.168388 -71.213074) (xy 298.511468 -71.213074) (xy 298.511468 -71.844253)
			(xy 346.360454 -71.844253) (xy 346.360454 -71.789747) (xy 346.368211 -71.735796) (xy 346.383567 -71.683499)
			(xy 346.406209 -71.633919) (xy 346.435677 -71.588066) (xy 346.47137 -71.546873) (xy 346.512562 -71.511179)
			(xy 346.558415 -71.481711) (xy 346.607995 -71.459068) (xy 346.660293 -71.443712) (xy 346.714243 -71.435954)
			(xy 346.741496 -71.435468) (xy 347.605096 -71.435468) (xy 347.632347 -71.435979) (xy 347.686295 -71.443735)
			(xy 347.73859 -71.45909) (xy 347.788168 -71.481731) (xy 347.834019 -71.511197) (xy 347.875209 -71.546888)
			(xy 347.910901 -71.588078) (xy 347.940367 -71.633929) (xy 347.963009 -71.683506) (xy 347.978364 -71.735801)
			(xy 347.986121 -71.789749) (xy 347.986121 -71.844251) (xy 347.978364 -71.898199) (xy 347.963009 -71.950494)
			(xy 347.940367 -72.000071) (xy 347.910901 -72.045922) (xy 347.875209 -72.087112) (xy 347.834019 -72.122803)
			(xy 347.788168 -72.152269) (xy 347.73859 -72.17491) (xy 347.686295 -72.190265) (xy 347.632347 -72.198021)
			(xy 347.605096 -72.198484) (xy 346.741496 -72.198484) (xy 346.714243 -72.198046) (xy 346.660293 -72.190288)
			(xy 346.607995 -72.174932) (xy 346.558415 -72.152289) (xy 346.512562 -72.122821) (xy 346.47137 -72.087127)
			(xy 346.435677 -72.045934) (xy 346.406209 -72.000081) (xy 346.383567 -71.950501) (xy 346.368211 -71.898204)
			(xy 346.360454 -71.844253) (xy 298.511468 -71.844253) (xy 298.511468 -72.404055) (xy 332.037847 -72.404055)
			(xy 332.037847 -72.349545) (xy 332.045606 -72.295589) (xy 332.060964 -72.243286) (xy 332.083611 -72.193702)
			(xy 332.113083 -72.147846) (xy 332.148782 -72.106651) (xy 332.189981 -72.070957) (xy 332.235841 -72.041489)
			(xy 332.285427 -72.018849) (xy 332.337732 -72.003496) (xy 332.391689 -71.995744) (xy 332.418944 -71.995284)
			(xy 333.282544 -71.995284) (xy 333.309793 -71.995789) (xy 333.363734 -72.00355) (xy 333.416023 -72.018909)
			(xy 333.465593 -72.041552) (xy 333.511437 -72.071019) (xy 333.552622 -72.10671) (xy 333.588308 -72.147898)
			(xy 333.617769 -72.193745) (xy 333.640407 -72.243318) (xy 333.655759 -72.295609) (xy 333.660251 -72.326853)
			(xy 343.845854 -72.326853) (xy 343.845854 -72.272347) (xy 343.853611 -72.218396) (xy 343.868967 -72.166099)
			(xy 343.891609 -72.116519) (xy 343.921077 -72.070666) (xy 343.95677 -72.029473) (xy 343.997962 -71.993779)
			(xy 344.043815 -71.964311) (xy 344.093395 -71.941668) (xy 344.145693 -71.926312) (xy 344.199643 -71.918554)
			(xy 344.226896 -71.918068) (xy 345.090496 -71.918068) (xy 345.117747 -71.918579) (xy 345.171695 -71.926335)
			(xy 345.22399 -71.94169) (xy 345.273568 -71.964331) (xy 345.319419 -71.993797) (xy 345.360609 -72.029488)
			(xy 345.396301 -72.070678) (xy 345.425767 -72.116529) (xy 345.448409 -72.166106) (xy 345.463764 -72.218401)
			(xy 345.471521 -72.272349) (xy 345.471521 -72.326851) (xy 345.463764 -72.380799) (xy 345.448409 -72.433094)
			(xy 345.425767 -72.482671) (xy 345.396301 -72.528522) (xy 345.360609 -72.569712) (xy 345.319419 -72.605403)
			(xy 345.273568 -72.634869) (xy 345.22399 -72.65751) (xy 345.171695 -72.672865) (xy 345.117747 -72.680621)
			(xy 345.090496 -72.681084) (xy 344.226896 -72.681084) (xy 344.199643 -72.680646) (xy 344.145693 -72.672888)
			(xy 344.093395 -72.657532) (xy 344.043815 -72.634889) (xy 343.997962 -72.605421) (xy 343.95677 -72.569727)
			(xy 343.921077 -72.528534) (xy 343.891609 -72.482681) (xy 343.868967 -72.433101) (xy 343.853611 -72.380804)
			(xy 343.845854 -72.326853) (xy 333.660251 -72.326853) (xy 333.663514 -72.349551) (xy 333.663514 -72.404049)
			(xy 333.655759 -72.457991) (xy 333.640407 -72.510282) (xy 333.617769 -72.559855) (xy 333.588308 -72.605702)
			(xy 333.552622 -72.64689) (xy 333.511437 -72.682581) (xy 333.465593 -72.712048) (xy 333.416023 -72.734691)
			(xy 333.363734 -72.75005) (xy 333.309793 -72.757811) (xy 333.282544 -72.7583) (xy 332.418944 -72.7583)
			(xy 332.391689 -72.757856) (xy 332.337732 -72.750104) (xy 332.285427 -72.734751) (xy 332.235841 -72.712111)
			(xy 332.189981 -72.682643) (xy 332.148782 -72.646949) (xy 332.113083 -72.605754) (xy 332.083611 -72.559898)
			(xy 332.060964 -72.510314) (xy 332.045606 -72.458011) (xy 332.037847 -72.404055) (xy 298.511468 -72.404055)
			(xy 298.511468 -74.617072) (xy 327.277726 -74.617072) (xy 327.281813 -74.561227) (xy 327.293988 -74.506573)
			(xy 327.31399 -74.454274) (xy 327.341395 -74.405445) (xy 327.375617 -74.361126) (xy 327.415927 -74.322262)
			(xy 327.461466 -74.289681) (xy 327.511264 -74.264078) (xy 327.564259 -74.245999) (xy 327.619321 -74.235828)
			(xy 327.675278 -74.233783) (xy 327.730936 -74.239908) (xy 327.785109 -74.25407) (xy 327.836643 -74.27597)
			(xy 327.884439 -74.305139) (xy 327.927478 -74.340957) (xy 327.941626 -74.356747) (xy 330.744122 -74.356747)
			(xy 330.744122 -74.302253) (xy 330.751877 -74.248315) (xy 330.767229 -74.196029) (xy 330.789865 -74.146459)
			(xy 330.819325 -74.100616) (xy 330.855009 -74.059431) (xy 330.89619 -74.023744) (xy 330.942031 -73.99428)
			(xy 330.991599 -73.97164) (xy 331.043883 -73.956284) (xy 331.097821 -73.948524) (xy 331.125068 -73.948036)
			(xy 331.988668 -73.948036) (xy 332.015926 -73.948409) (xy 332.069886 -73.956163) (xy 332.122194 -73.971518)
			(xy 332.171784 -73.994161) (xy 332.217646 -74.023632) (xy 332.258848 -74.05933) (xy 332.294549 -74.100528)
			(xy 332.324023 -74.146388) (xy 332.346671 -74.195976) (xy 332.36203 -74.248283) (xy 332.369789 -74.302243)
			(xy 332.369789 -74.356757) (xy 332.36203 -74.410717) (xy 332.346671 -74.463024) (xy 332.324023 -74.512612)
			(xy 332.294549 -74.558472) (xy 332.26684 -74.590448) (xy 336.274202 -74.590448) (xy 336.274202 -74.535953)
			(xy 336.281957 -74.482012) (xy 336.297309 -74.429724) (xy 336.319945 -74.380153) (xy 336.349406 -74.334308)
			(xy 336.38509 -74.293121) (xy 336.426272 -74.257432) (xy 336.472114 -74.227966) (xy 336.521683 -74.205324)
			(xy 336.573969 -74.189966) (xy 336.627909 -74.182205) (xy 336.655156 -74.181716) (xy 337.518756 -74.181716)
			(xy 337.546013 -74.182128) (xy 337.599972 -74.18988) (xy 337.652278 -74.205233) (xy 337.701867 -74.227875)
			(xy 337.747729 -74.257344) (xy 337.788929 -74.29304) (xy 337.82463 -74.334236) (xy 337.854104 -74.380094)
			(xy 337.876751 -74.42968) (xy 337.89211 -74.481985) (xy 337.899869 -74.535943) (xy 337.899869 -74.55185)
			(xy 339.156294 -74.55185) (xy 339.156294 -74.49735) (xy 339.16405 -74.443405) (xy 339.179404 -74.391113)
			(xy 339.202044 -74.341539) (xy 339.231509 -74.29569) (xy 339.267198 -74.254502) (xy 339.308386 -74.218812)
			(xy 339.354233 -74.189347) (xy 339.403808 -74.166707) (xy 339.456099 -74.151352) (xy 339.510044 -74.143595)
			(xy 339.537294 -74.143108) (xy 340.400894 -74.143108) (xy 340.428148 -74.143538) (xy 340.482102 -74.151295)
			(xy 340.534403 -74.166651) (xy 340.583986 -74.189294) (xy 340.629842 -74.218763) (xy 340.671037 -74.254459)
			(xy 340.706733 -74.295653) (xy 340.736203 -74.341509) (xy 340.758847 -74.391091) (xy 340.774204 -74.443392)
			(xy 340.781961 -74.497346) (xy 340.781961 -74.551854) (xy 340.774204 -74.605808) (xy 340.758847 -74.658109)
			(xy 340.736203 -74.707691) (xy 340.706733 -74.753547) (xy 340.694254 -74.767948) (xy 421.29456 -74.767948)
			(xy 421.29456 -66.06794) (xy 421.295065 -65.962416) (xy 421.303149 -65.751522) (xy 421.319305 -65.541093)
			(xy 421.343508 -65.331436) (xy 421.375725 -65.122861) (xy 421.415907 -64.915673) (xy 421.463995 -64.710176)
			(xy 421.519919 -64.506672) (xy 421.583596 -64.305459) (xy 421.654934 -64.106832) (xy 421.733828 -63.911084)
			(xy 421.820161 -63.718502) (xy 421.913808 -63.529367) (xy 422.01463 -63.343958) (xy 422.12248 -63.162547)
			(xy 422.237199 -62.9854) (xy 422.358619 -62.812778) (xy 422.486562 -62.644932) (xy 422.62084 -62.48211)
			(xy 422.761256 -62.324551) (xy 422.907604 -62.172486) (xy 423.059669 -62.026138) (xy 423.217228 -61.885722)
			(xy 423.38005 -61.751444) (xy 423.547896 -61.623501) (xy 423.720518 -61.502081) (xy 423.897665 -61.387362)
			(xy 424.079076 -61.279512) (xy 424.264485 -61.17869) (xy 424.45362 -61.085043) (xy 424.646202 -60.99871)
			(xy 424.84195 -60.919816) (xy 425.040577 -60.848478) (xy 425.24179 -60.784801) (xy 425.445294 -60.728877)
			(xy 425.650791 -60.680789) (xy 425.857979 -60.640607) (xy 426.066554 -60.60839) (xy 426.276211 -60.584187)
			(xy 426.48664 -60.568031) (xy 426.697534 -60.559947) (xy 426.908582 -60.559947) (xy 427.119476 -60.568031)
			(xy 427.329905 -60.584187) (xy 427.539562 -60.60839) (xy 427.748137 -60.640607) (xy 427.955325 -60.680789)
			(xy 428.160822 -60.728877) (xy 428.364326 -60.784801) (xy 428.565539 -60.848478) (xy 428.764166 -60.919816)
			(xy 428.959914 -60.99871) (xy 429.152496 -61.085043) (xy 429.341631 -61.17869) (xy 429.52704 -61.279512)
			(xy 429.708451 -61.387362) (xy 429.885598 -61.502081) (xy 430.05822 -61.623501) (xy 430.226066 -61.751444)
			(xy 430.388888 -61.885722) (xy 430.546447 -62.026138) (xy 430.698512 -62.172486) (xy 430.84486 -62.324551)
			(xy 430.985276 -62.48211) (xy 431.119554 -62.644932) (xy 431.247497 -62.812778) (xy 431.368917 -62.9854)
			(xy 431.483636 -63.162547) (xy 431.591486 -63.343958) (xy 431.692308 -63.529367) (xy 431.785955 -63.718502)
			(xy 431.872288 -63.911084) (xy 431.951182 -64.106832) (xy 432.02252 -64.305459) (xy 432.086197 -64.506672)
			(xy 432.142121 -64.710176) (xy 432.190209 -64.915673) (xy 432.230391 -65.122861) (xy 432.262608 -65.331436)
			(xy 432.286811 -65.541093) (xy 432.302967 -65.751522) (xy 432.311051 -65.962416) (xy 432.311556 -66.06794)
			(xy 432.311556 -74.767948) (xy 432.311051 -74.873472) (xy 432.302967 -75.084366) (xy 432.286811 -75.294795)
			(xy 432.262608 -75.504452) (xy 432.230391 -75.713027) (xy 432.190209 -75.920215) (xy 432.142121 -76.125712)
			(xy 432.086197 -76.329216) (xy 432.02252 -76.530429) (xy 431.951182 -76.729056) (xy 431.872288 -76.924804)
			(xy 431.785955 -77.117386) (xy 431.692308 -77.306521) (xy 431.591486 -77.49193) (xy 431.483636 -77.673341)
			(xy 431.368917 -77.850488) (xy 431.247497 -78.02311) (xy 431.119554 -78.190956) (xy 430.985276 -78.353778)
			(xy 430.84486 -78.511337) (xy 430.698512 -78.663402) (xy 430.546447 -78.80975) (xy 430.388888 -78.950166)
			(xy 430.226066 -79.084444) (xy 430.05822 -79.212387) (xy 429.885598 -79.333807) (xy 429.708451 -79.448526)
			(xy 429.52704 -79.556376) (xy 429.341631 -79.657198) (xy 429.152496 -79.750845) (xy 428.959914 -79.837178)
			(xy 428.764166 -79.916072) (xy 428.565539 -79.98741) (xy 428.364326 -80.051087) (xy 428.160822 -80.107011)
			(xy 427.955325 -80.155099) (xy 427.748137 -80.195281) (xy 427.539562 -80.227498) (xy 427.329905 -80.251701)
			(xy 427.119476 -80.267857) (xy 426.908582 -80.275941) (xy 426.697534 -80.275941) (xy 426.48664 -80.267857)
			(xy 426.276211 -80.251701) (xy 426.066554 -80.227498) (xy 425.857979 -80.195281) (xy 425.650791 -80.155099)
			(xy 425.445294 -80.107011) (xy 425.24179 -80.051087) (xy 425.040577 -79.98741) (xy 424.84195 -79.916072)
			(xy 424.646202 -79.837178) (xy 424.45362 -79.750845) (xy 424.264485 -79.657198) (xy 424.079076 -79.556376)
			(xy 423.897665 -79.448526) (xy 423.720518 -79.333807) (xy 423.547896 -79.212387) (xy 423.38005 -79.084444)
			(xy 423.217228 -78.950166) (xy 423.059669 -78.80975) (xy 422.907604 -78.663402) (xy 422.761256 -78.511337)
			(xy 422.62084 -78.353778) (xy 422.486562 -78.190956) (xy 422.358619 -78.02311) (xy 422.237199 -77.850488)
			(xy 422.12248 -77.673341) (xy 422.01463 -77.49193) (xy 421.913808 -77.306521) (xy 421.820161 -77.117386)
			(xy 421.733828 -76.924804) (xy 421.654934 -76.729056) (xy 421.583596 -76.530429) (xy 421.519919 -76.329216)
			(xy 421.463995 -76.125712) (xy 421.415907 -75.920215) (xy 421.375725 -75.713027) (xy 421.343508 -75.504452)
			(xy 421.319305 -75.294795) (xy 421.303149 -75.084366) (xy 421.295065 -74.873472) (xy 421.29456 -74.767948)
			(xy 340.694254 -74.767948) (xy 340.671037 -74.794741) (xy 340.629842 -74.830437) (xy 340.583986 -74.859906)
			(xy 340.534403 -74.882549) (xy 340.482102 -74.897905) (xy 340.428148 -74.905662) (xy 340.400894 -74.906124)
			(xy 339.537294 -74.906124) (xy 339.510044 -74.905605) (xy 339.456099 -74.897848) (xy 339.403808 -74.882493)
			(xy 339.354233 -74.859853) (xy 339.308386 -74.830388) (xy 339.267198 -74.794698) (xy 339.231509 -74.75351)
			(xy 339.202044 -74.707661) (xy 339.179404 -74.658087) (xy 339.16405 -74.605795) (xy 339.156294 -74.55185)
			(xy 337.899869 -74.55185) (xy 337.899869 -74.590457) (xy 337.89211 -74.644415) (xy 337.876751 -74.69672)
			(xy 337.854104 -74.746306) (xy 337.82463 -74.792164) (xy 337.788929 -74.83336) (xy 337.747729 -74.869056)
			(xy 337.701867 -74.898525) (xy 337.652278 -74.921167) (xy 337.599972 -74.93652) (xy 337.546013 -74.944272)
			(xy 337.518756 -74.944732) (xy 336.655156 -74.944732) (xy 336.627909 -74.944195) (xy 336.573969 -74.936434)
			(xy 336.521683 -74.921076) (xy 336.472114 -74.898434) (xy 336.426272 -74.868968) (xy 336.38509 -74.833279)
			(xy 336.349406 -74.792092) (xy 336.319945 -74.746247) (xy 336.297309 -74.696676) (xy 336.281957 -74.644388)
			(xy 336.274202 -74.590448) (xy 332.26684 -74.590448) (xy 332.258848 -74.59967) (xy 332.217646 -74.635368)
			(xy 332.171784 -74.664839) (xy 332.122194 -74.687482) (xy 332.069886 -74.702837) (xy 332.015926 -74.710591)
			(xy 331.988668 -74.711052) (xy 331.125068 -74.711052) (xy 331.097821 -74.710476) (xy 331.043883 -74.702716)
			(xy 330.991599 -74.68736) (xy 330.942031 -74.66472) (xy 330.89619 -74.635256) (xy 330.855009 -74.599569)
			(xy 330.819325 -74.558384) (xy 330.789865 -74.512541) (xy 330.767229 -74.462971) (xy 330.751877 -74.410685)
			(xy 330.744122 -74.356747) (xy 327.941626 -74.356747) (xy 327.964844 -74.38266) (xy 327.99574 -74.429358)
			(xy 328.019507 -74.480058) (xy 328.035639 -74.533678) (xy 328.043791 -74.589075) (xy 328.044302 -74.617072)
			(xy 328.043791 -74.645069) (xy 328.035639 -74.700466) (xy 328.019507 -74.754086) (xy 327.99574 -74.804786)
			(xy 327.964844 -74.851484) (xy 327.927478 -74.893187) (xy 327.884439 -74.929005) (xy 327.836643 -74.958174)
			(xy 327.785109 -74.980074) (xy 327.730936 -74.994236) (xy 327.675278 -75.000361) (xy 327.619321 -74.998316)
			(xy 327.564259 -74.988145) (xy 327.511264 -74.970066) (xy 327.461466 -74.944463) (xy 327.415927 -74.911882)
			(xy 327.375617 -74.873018) (xy 327.341395 -74.828699) (xy 327.31399 -74.77987) (xy 327.293988 -74.727571)
			(xy 327.281813 -74.672917) (xy 327.277726 -74.617072) (xy 298.511468 -74.617072) (xy 298.511468 -74.760836)
			(xy 298.510963 -74.86636) (xy 298.502879 -75.077254) (xy 298.486723 -75.287683) (xy 298.46252 -75.49734)
			(xy 298.430303 -75.705915) (xy 298.390121 -75.913103) (xy 298.342033 -76.1186) (xy 298.333664 -76.149054)
			(xy 327.558346 -76.149054) (xy 327.558346 -76.094546) (xy 327.566103 -76.040594) (xy 327.581459 -75.988295)
			(xy 327.604102 -75.938714) (xy 327.633571 -75.892859) (xy 327.669266 -75.851666) (xy 327.710459 -75.815971)
			(xy 327.756314 -75.786502) (xy 327.805895 -75.763859) (xy 327.858194 -75.748503) (xy 327.912146 -75.740746)
			(xy 327.9394 -75.74026) (xy 328.803 -75.74026) (xy 328.830249 -75.74081) (xy 328.884192 -75.748566)
			(xy 328.936482 -75.76392) (xy 328.986055 -75.786559) (xy 329.031902 -75.816023) (xy 329.073089 -75.851711)
			(xy 329.108777 -75.892898) (xy 329.138241 -75.938745) (xy 329.16088 -75.988318) (xy 329.169581 -76.017949)
			(xy 334.874382 -76.017949) (xy 334.874382 -75.963451) (xy 334.882137 -75.909507) (xy 334.89749 -75.857216)
			(xy 334.920128 -75.807642) (xy 334.949591 -75.761793) (xy 334.985278 -75.720605) (xy 335.026463 -75.684914)
			(xy 335.072308 -75.655447) (xy 335.12188 -75.632803) (xy 335.17417 -75.617445) (xy 335.228113 -75.609684)
			(xy 335.255362 -75.609196) (xy 336.118962 -75.609196) (xy 336.146217 -75.609649) (xy 336.200173 -75.617401)
			(xy 336.252475 -75.632754) (xy 336.302061 -75.655395) (xy 336.347919 -75.684862) (xy 336.389117 -75.720556)
			(xy 336.424815 -75.76175) (xy 336.454287 -75.807606) (xy 336.476932 -75.857189) (xy 336.49229 -75.90949)
			(xy 336.500049 -75.963445) (xy 336.500049 -76.017955) (xy 336.49229 -76.07191) (xy 336.476932 -76.124211)
			(xy 336.454287 -76.173794) (xy 336.424815 -76.21965) (xy 336.389117 -76.260844) (xy 336.347919 -76.296538)
			(xy 336.302061 -76.326005) (xy 336.252475 -76.348646) (xy 336.200173 -76.363999) (xy 336.146217 -76.371751)
			(xy 336.118962 -76.372212) (xy 335.255362 -76.372212) (xy 335.228113 -76.371716) (xy 335.17417 -76.363955)
			(xy 335.12188 -76.348597) (xy 335.072308 -76.325953) (xy 335.026463 -76.296486) (xy 334.985278 -76.260795)
			(xy 334.949591 -76.219607) (xy 334.920128 -76.173758) (xy 334.89749 -76.124184) (xy 334.882137 -76.071893)
			(xy 334.874382 -76.017949) (xy 329.169581 -76.017949) (xy 329.176234 -76.040608) (xy 329.18399 -76.094551)
			(xy 329.18399 -76.149049) (xy 329.176234 -76.202992) (xy 329.16088 -76.255282) (xy 329.138241 -76.304855)
			(xy 329.108777 -76.350702) (xy 329.073089 -76.391889) (xy 329.031902 -76.427577) (xy 328.986055 -76.457041)
			(xy 328.936482 -76.47968) (xy 328.884192 -76.495034) (xy 328.830249 -76.50279) (xy 328.803 -76.503276)
			(xy 327.9394 -76.503276) (xy 327.912146 -76.502854) (xy 327.858194 -76.495097) (xy 327.805895 -76.479741)
			(xy 327.756314 -76.457098) (xy 327.710459 -76.427629) (xy 327.669266 -76.391934) (xy 327.633571 -76.350741)
			(xy 327.604102 -76.304886) (xy 327.581459 -76.255305) (xy 327.566103 -76.203006) (xy 327.558346 -76.149054)
			(xy 298.333664 -76.149054) (xy 298.286109 -76.322104) (xy 298.222432 -76.523317) (xy 298.151094 -76.721944)
			(xy 298.0722 -76.917692) (xy 297.985867 -77.110274) (xy 297.89222 -77.299409) (xy 297.791398 -77.484818)
			(xy 297.683548 -77.666229) (xy 297.568829 -77.843376) (xy 297.455321 -78.00475) (xy 330.84567 -78.00475)
			(xy 330.84567 -77.95025) (xy 330.853426 -77.896304) (xy 330.868779 -77.84401) (xy 330.891419 -77.794434)
			(xy 330.920883 -77.748584) (xy 330.956571 -77.707394) (xy 330.997759 -77.671702) (xy 331.043606 -77.642234)
			(xy 331.09318 -77.619591) (xy 331.145472 -77.604232) (xy 331.199418 -77.596472) (xy 331.226668 -77.595984)
			(xy 332.090268 -77.595984) (xy 332.117522 -77.596461) (xy 332.171475 -77.604214) (xy 332.223776 -77.619567)
			(xy 332.273359 -77.642207) (xy 332.319215 -77.671674) (xy 332.360411 -77.707367) (xy 332.396107 -77.748559)
			(xy 332.425577 -77.794413) (xy 332.448222 -77.843994) (xy 332.463579 -77.896294) (xy 332.471337 -77.950246)
			(xy 332.471337 -78.004754) (xy 332.463579 -78.058706) (xy 332.448222 -78.111006) (xy 332.425577 -78.160587)
			(xy 332.396107 -78.206441) (xy 332.360411 -78.247633) (xy 332.319215 -78.283326) (xy 332.273359 -78.312793)
			(xy 332.223776 -78.335433) (xy 332.171475 -78.350786) (xy 332.117522 -78.358539) (xy 332.090268 -78.359)
			(xy 331.226668 -78.359) (xy 331.199418 -78.358528) (xy 331.145472 -78.350768) (xy 331.09318 -78.335409)
			(xy 331.043606 -78.312766) (xy 330.997759 -78.283298) (xy 330.956571 -78.247606) (xy 330.920883 -78.206416)
			(xy 330.891419 -78.160566) (xy 330.868779 -78.11099) (xy 330.853426 -78.058696) (xy 330.84567 -78.00475)
			(xy 297.455321 -78.00475) (xy 297.447409 -78.015998) (xy 297.319466 -78.183844) (xy 297.185188 -78.346666)
			(xy 297.044772 -78.504225) (xy 296.898424 -78.65629) (xy 296.746359 -78.802638) (xy 296.5888 -78.943054)
			(xy 296.425978 -79.077332) (xy 296.258132 -79.205275) (xy 296.08551 -79.326695) (xy 295.908363 -79.441414)
			(xy 295.726952 -79.549264) (xy 295.541543 -79.650086) (xy 295.352408 -79.743733) (xy 295.159826 -79.830066)
			(xy 294.964078 -79.90896) (xy 294.765451 -79.980298) (xy 294.564238 -80.043975) (xy 294.360734 -80.099899)
			(xy 294.155237 -80.147987) (xy 293.948049 -80.188169) (xy 293.739474 -80.220386) (xy 293.529817 -80.244589)
			(xy 293.319388 -80.260745) (xy 293.108494 -80.268829) (xy 292.897446 -80.268829) (xy 292.686552 -80.260745)
			(xy 292.476123 -80.244589) (xy 292.266466 -80.220386) (xy 292.057891 -80.188169) (xy 291.850703 -80.147987)
			(xy 291.645206 -80.099899) (xy 291.441702 -80.043975) (xy 291.240489 -79.980298) (xy 291.041862 -79.90896)
			(xy 290.846114 -79.830066) (xy 290.653532 -79.743733) (xy 290.464397 -79.650086) (xy 290.278988 -79.549264)
			(xy 290.097577 -79.441414) (xy 289.92043 -79.326695) (xy 289.747808 -79.205275) (xy 289.579962 -79.077332)
			(xy 289.41714 -78.943054) (xy 289.259581 -78.802638) (xy 289.107516 -78.65629) (xy 288.961168 -78.504225)
			(xy 288.820752 -78.346666) (xy 288.686474 -78.183844) (xy 288.558531 -78.015998) (xy 288.437111 -77.843376)
			(xy 288.322392 -77.666229) (xy 288.214542 -77.484818) (xy 288.11372 -77.299409) (xy 288.020073 -77.110274)
			(xy 287.93374 -76.917692) (xy 287.854846 -76.721944) (xy 287.783508 -76.523317) (xy 287.719831 -76.322104)
			(xy 287.663907 -76.1186) (xy 287.615819 -75.913103) (xy 287.575637 -75.705915) (xy 287.54342 -75.49734)
			(xy 287.519217 -75.287683) (xy 287.503061 -75.077254) (xy 287.494977 -74.86636) (xy 287.494472 -74.760836)
			(xy 184.371488 -74.760836) (xy 184.371488 -74.767948) (xy 184.370983 -74.873472) (xy 184.362899 -75.084366)
			(xy 184.346743 -75.294795) (xy 184.32254 -75.504452) (xy 184.290323 -75.713027) (xy 184.250141 -75.920215)
			(xy 184.202053 -76.125712) (xy 184.146129 -76.329216) (xy 184.082452 -76.530429) (xy 184.011114 -76.729056)
			(xy 183.93222 -76.924804) (xy 183.845887 -77.117386) (xy 183.75224 -77.306521) (xy 183.651418 -77.49193)
			(xy 183.543568 -77.673341) (xy 183.428849 -77.850488) (xy 183.307429 -78.02311) (xy 183.179486 -78.190956)
			(xy 183.045208 -78.353778) (xy 182.904792 -78.511337) (xy 182.758444 -78.663402) (xy 182.606379 -78.80975)
			(xy 182.44882 -78.950166) (xy 182.285998 -79.084444) (xy 182.118152 -79.212387) (xy 181.94553 -79.333807)
			(xy 181.768383 -79.448526) (xy 181.586972 -79.556376) (xy 181.401563 -79.657198) (xy 181.212428 -79.750845)
			(xy 181.019846 -79.837178) (xy 180.824098 -79.916072) (xy 180.625471 -79.98741) (xy 180.424258 -80.051087)
			(xy 180.220754 -80.107011) (xy 180.015257 -80.155099) (xy 179.808069 -80.195281) (xy 179.599494 -80.227498)
			(xy 179.389837 -80.251701) (xy 179.179408 -80.267857) (xy 178.968514 -80.275941) (xy 178.757466 -80.275941)
			(xy 178.546572 -80.267857) (xy 178.336143 -80.251701) (xy 178.126486 -80.227498) (xy 177.917911 -80.195281)
			(xy 177.710723 -80.155099) (xy 177.505226 -80.107011) (xy 177.301722 -80.051087) (xy 177.100509 -79.98741)
			(xy 176.901882 -79.916072) (xy 176.706134 -79.837178) (xy 176.513552 -79.750845) (xy 176.324417 -79.657198)
			(xy 176.139008 -79.556376) (xy 175.957597 -79.448526) (xy 175.78045 -79.333807) (xy 175.607828 -79.212387)
			(xy 175.439982 -79.084444) (xy 175.27716 -78.950166) (xy 175.119601 -78.80975) (xy 174.967536 -78.663402)
			(xy 174.821188 -78.511337) (xy 174.680772 -78.353778) (xy 174.546494 -78.190956) (xy 174.418551 -78.02311)
			(xy 174.297131 -77.850488) (xy 174.182412 -77.673341) (xy 174.074562 -77.49193) (xy 173.97374 -77.306521)
			(xy 173.880093 -77.117386) (xy 173.79376 -76.924804) (xy 173.714866 -76.729056) (xy 173.643528 -76.530429)
			(xy 173.579851 -76.329216) (xy 173.523927 -76.125712) (xy 173.475839 -75.920215) (xy 173.435657 -75.713027)
			(xy 173.40344 -75.504452) (xy 173.379237 -75.294795) (xy 173.363081 -75.084366) (xy 173.354997 -74.873472)
			(xy 173.354492 -74.767948) (xy 50.571366 -74.767948) (xy 50.570895 -74.86636) (xy 50.562811 -75.077254)
			(xy 50.546655 -75.287683) (xy 50.522452 -75.49734) (xy 50.490235 -75.705915) (xy 50.450053 -75.913103)
			(xy 50.401965 -76.1186) (xy 50.346041 -76.322104) (xy 50.282364 -76.523317) (xy 50.211026 -76.721944)
			(xy 50.132132 -76.917692) (xy 50.045799 -77.110274) (xy 49.952152 -77.299409) (xy 49.85133 -77.484818)
			(xy 49.74348 -77.666229) (xy 49.628761 -77.843376) (xy 49.507341 -78.015998) (xy 49.379398 -78.183844)
			(xy 49.24512 -78.346666) (xy 49.104704 -78.504225) (xy 48.958356 -78.65629) (xy 48.806291 -78.802638)
			(xy 48.648732 -78.943054) (xy 48.48591 -79.077332) (xy 48.318064 -79.205275) (xy 48.145442 -79.326695)
			(xy 47.968295 -79.441414) (xy 47.786884 -79.549264) (xy 47.601475 -79.650086) (xy 47.41234 -79.743733)
			(xy 47.219758 -79.830066) (xy 47.02401 -79.90896) (xy 46.825383 -79.980298) (xy 46.62417 -80.043975)
			(xy 46.420666 -80.099899) (xy 46.215169 -80.147987) (xy 46.007981 -80.188169) (xy 45.799406 -80.220386)
			(xy 45.589749 -80.244589) (xy 45.37932 -80.260745) (xy 45.168426 -80.268829) (xy 44.957378 -80.268829)
			(xy 44.746484 -80.260745) (xy 44.536055 -80.244589) (xy 44.326398 -80.220386) (xy 44.117823 -80.188169)
			(xy 43.910635 -80.147987) (xy 43.705138 -80.099899) (xy 43.501634 -80.043975) (xy 43.300421 -79.980298)
			(xy 43.101794 -79.90896) (xy 42.906046 -79.830066) (xy 42.713464 -79.743733) (xy 42.524329 -79.650086)
			(xy 42.33892 -79.549264) (xy 42.157509 -79.441414) (xy 41.980362 -79.326695) (xy 41.80774 -79.205275)
			(xy 41.639894 -79.077332) (xy 41.477072 -78.943054) (xy 41.319513 -78.802638) (xy 41.167448 -78.65629)
			(xy 41.0211 -78.504225) (xy 40.880684 -78.346666) (xy 40.746406 -78.183844) (xy 40.618463 -78.015998)
			(xy 40.497043 -77.843376) (xy 40.382324 -77.666229) (xy 40.274474 -77.484818) (xy 40.173652 -77.299409)
			(xy 40.080005 -77.110274) (xy 39.993672 -76.917692) (xy 39.914778 -76.721944) (xy 39.84344 -76.523317)
			(xy 39.779763 -76.322104) (xy 39.723839 -76.1186) (xy 39.675751 -75.913103) (xy 39.635569 -75.705915)
			(xy 39.603352 -75.49734) (xy 39.579149 -75.287683) (xy 39.562993 -75.077254) (xy 39.554909 -74.86636)
			(xy 39.554404 -74.760836) (xy 0.509016 -74.760836) (xy 0.509016 -77.671676) (xy 0.509504 -77.724899)
			(xy 0.51712 -77.831071) (xy 0.532286 -77.93643) (xy 0.554925 -78.04044) (xy 0.584921 -78.142572)
			(xy 0.622123 -78.242305) (xy 0.666339 -78.339132) (xy 0.717347 -78.43256) (xy 0.774885 -78.522114)
			(xy 0.838661 -78.607338) (xy 0.908351 -78.687799) (xy 0.945642 -78.725776) (xy 1.77419 -79.554324)
			(xy 1.823602 -79.604436) (xy 1.917388 -79.709385) (xy 2.005143 -79.819428) (xy 2.08659 -79.934217)
			(xy 2.161473 -80.053392) (xy 2.229556 -80.176578) (xy 2.290626 -80.303388) (xy 2.344491 -80.433422)
			(xy 2.39098 -80.566271) (xy 2.429948 -80.701518) (xy 2.461272 -80.838737) (xy 2.484853 -80.977496)
			(xy 2.500618 -81.117359) (xy 2.508516 -81.257886) (xy 2.509012 -81.32826) (xy 2.509012 -81.69181)
			(xy 232.140667 -81.69181) (xy 232.145062 -81.517977) (xy 232.15749 -81.344533) (xy 232.177927 -81.171849)
			(xy 232.206328 -81.000295) (xy 232.242632 -80.830238) (xy 232.286762 -80.662042) (xy 232.338623 -80.496067)
			(xy 232.398104 -80.332668) (xy 232.465078 -80.172194) (xy 232.539402 -80.01499) (xy 232.620917 -79.86139)
			(xy 232.709448 -79.711725) (xy 232.804805 -79.566315) (xy 232.906785 -79.425469) (xy 233.01517 -79.289491)
			(xy 233.129727 -79.158671) (xy 233.250212 -79.033288) (xy 233.376366 -78.913612) (xy 233.50792 -78.799897)
			(xy 233.644592 -78.692389) (xy 233.715052 -78.641448) (xy 238.08436 -78.641448) (xy 238.15482 -78.692389)
			(xy 238.291492 -78.799897) (xy 238.423046 -78.913612) (xy 238.5492 -79.033288) (xy 238.669685 -79.158671)
			(xy 238.784242 -79.289491) (xy 238.892627 -79.425469) (xy 238.994607 -79.566315) (xy 239.089964 -79.711725)
			(xy 239.178495 -79.86139) (xy 239.26001 -80.01499) (xy 239.334334 -80.172194) (xy 239.401308 -80.332668)
			(xy 239.460789 -80.496067) (xy 239.51265 -80.662042) (xy 239.553507 -80.817765) (xy 333.938166 -80.817765)
			(xy 333.938166 -80.763235) (xy 333.945926 -80.70926) (xy 333.961289 -80.656938) (xy 333.98394 -80.607335)
			(xy 334.01342 -80.561461) (xy 334.049129 -80.520248) (xy 334.090338 -80.484537) (xy 334.136211 -80.455054)
			(xy 334.185812 -80.432398) (xy 334.238132 -80.417032) (xy 334.292107 -80.409268) (xy 334.319372 -80.40878)
			(xy 335.182972 -80.40878) (xy 335.210247 -80.409158) (xy 335.264243 -80.416917) (xy 335.316585 -80.432283)
			(xy 335.366207 -80.454941) (xy 335.412099 -80.484432) (xy 335.453327 -80.520153) (xy 335.489052 -80.561378)
			(xy 335.518545 -80.607268) (xy 335.541207 -80.656889) (xy 335.556577 -80.709229) (xy 335.56434 -80.763225)
			(xy 335.56434 -80.817775) (xy 335.556577 -80.871771) (xy 335.541207 -80.924111) (xy 335.518545 -80.973732)
			(xy 335.489052 -81.019622) (xy 335.453327 -81.060847) (xy 335.412099 -81.096568) (xy 335.366207 -81.126059)
			(xy 335.316585 -81.148717) (xy 335.264243 -81.164083) (xy 335.210247 -81.171842) (xy 335.182972 -81.172304)
			(xy 334.319372 -81.172304) (xy 334.292107 -81.171732) (xy 334.238132 -81.163968) (xy 334.185812 -81.148602)
			(xy 334.136211 -81.125946) (xy 334.090338 -81.096463) (xy 334.049129 -81.060752) (xy 334.01342 -81.019539)
			(xy 333.98394 -80.973665) (xy 333.961289 -80.924062) (xy 333.945926 -80.87174) (xy 333.938166 -80.817765)
			(xy 239.553507 -80.817765) (xy 239.55678 -80.830238) (xy 239.593084 -81.000295) (xy 239.621485 -81.171849)
			(xy 239.641922 -81.344533) (xy 239.65435 -81.517977) (xy 239.658745 -81.69181) (xy 239.655095 -81.865661)
			(xy 239.643409 -82.039157) (xy 239.640092 -82.06825) (xy 331.768962 -82.06825) (xy 331.768962 -82.01375)
			(xy 331.776717 -81.959803) (xy 331.792071 -81.90751) (xy 331.81471 -81.857933) (xy 331.844174 -81.812083)
			(xy 331.879862 -81.770892) (xy 331.921049 -81.735199) (xy 331.966896 -81.70573) (xy 332.01647 -81.683086)
			(xy 332.068762 -81.667726) (xy 332.122708 -81.659965) (xy 332.149958 -81.659476) (xy 333.013558 -81.659476)
			(xy 333.040812 -81.659968) (xy 333.094765 -81.66772) (xy 333.147066 -81.683072) (xy 333.196649 -81.705711)
			(xy 333.242505 -81.735177) (xy 333.283701 -81.770869) (xy 333.319398 -81.812061) (xy 333.348869 -81.857914)
			(xy 333.371513 -81.907495) (xy 333.386871 -81.959794) (xy 333.394629 -82.013746) (xy 333.394629 -82.068254)
			(xy 333.386871 -82.122206) (xy 333.371513 -82.174505) (xy 333.348869 -82.224086) (xy 333.319398 -82.269939)
			(xy 333.294774 -82.298353) (xy 336.189263 -82.298353) (xy 336.189263 -82.243847) (xy 336.197021 -82.189895)
			(xy 336.212377 -82.137597) (xy 336.235021 -82.088017) (xy 336.26449 -82.042163) (xy 336.300185 -82.000971)
			(xy 336.341379 -81.965278) (xy 336.387234 -81.935811) (xy 336.436816 -81.91317) (xy 336.489115 -81.897816)
			(xy 336.543067 -81.890062) (xy 336.57032 -81.8896) (xy 337.43392 -81.8896) (xy 337.461171 -81.890071)
			(xy 337.515118 -81.89783) (xy 337.567411 -81.913187) (xy 337.616987 -81.93583) (xy 337.662836 -81.965298)
			(xy 337.692804 -81.991267) (xy 339.478646 -81.991267) (xy 339.478646 -81.936733) (xy 339.486407 -81.882755)
			(xy 339.50177 -81.830431) (xy 339.524423 -81.780825) (xy 339.553905 -81.734948) (xy 339.589615 -81.693734)
			(xy 339.630827 -81.65802) (xy 339.676702 -81.628535) (xy 339.726306 -81.605879) (xy 339.77863 -81.590512)
			(xy 339.832607 -81.582748) (xy 339.859874 -81.58226) (xy 340.723474 -81.58226) (xy 340.750748 -81.582678)
			(xy 340.804741 -81.590437) (xy 340.857079 -81.605802) (xy 340.906699 -81.62846) (xy 340.952588 -81.657948)
			(xy 340.993814 -81.693668) (xy 341.029536 -81.734891) (xy 341.059028 -81.780778) (xy 341.081689 -81.830396)
			(xy 341.097057 -81.882734) (xy 341.10482 -81.936726) (xy 341.10482 -81.991274) (xy 341.097057 -82.045266)
			(xy 341.081689 -82.097604) (xy 341.059028 -82.147222) (xy 341.029536 -82.193109) (xy 340.993814 -82.234332)
			(xy 340.952588 -82.270052) (xy 340.906699 -82.29954) (xy 340.857079 -82.322198) (xy 340.804741 -82.337563)
			(xy 340.750748 -82.345322) (xy 340.723474 -82.345784) (xy 339.859874 -82.345784) (xy 339.832607 -82.345252)
			(xy 339.77863 -82.337488) (xy 339.726306 -82.322121) (xy 339.676702 -82.299465) (xy 339.630827 -82.26998)
			(xy 339.589615 -82.234266) (xy 339.553905 -82.193052) (xy 339.524423 -82.147175) (xy 339.50177 -82.097569)
			(xy 339.486407 -82.045245) (xy 339.478646 -81.991267) (xy 337.692804 -81.991267) (xy 337.704024 -82.00099)
			(xy 337.739714 -82.04218) (xy 337.76918 -82.088031) (xy 337.79182 -82.137608) (xy 337.807174 -82.189902)
			(xy 337.81493 -82.243849) (xy 337.81493 -82.298351) (xy 337.807174 -82.352298) (xy 337.79182 -82.404592)
			(xy 337.769179 -82.454169) (xy 337.739714 -82.50002) (xy 337.704024 -82.54121) (xy 337.662836 -82.576902)
			(xy 337.616987 -82.60637) (xy 337.567411 -82.629013) (xy 337.515118 -82.64437) (xy 337.461171 -82.652129)
			(xy 337.43392 -82.652616) (xy 336.57032 -82.652616) (xy 336.543067 -82.652138) (xy 336.489115 -82.644384)
			(xy 336.436816 -82.62903) (xy 336.387234 -82.606389) (xy 336.341379 -82.576922) (xy 336.300185 -82.541229)
			(xy 336.26449 -82.500037) (xy 336.235021 -82.454183) (xy 336.212377 -82.404603) (xy 336.197021 -82.352305)
			(xy 336.189263 -82.298353) (xy 333.294774 -82.298353) (xy 333.283701 -82.311131) (xy 333.242505 -82.346823)
			(xy 333.196649 -82.376289) (xy 333.147066 -82.398928) (xy 333.094765 -82.41428) (xy 333.040812 -82.422032)
			(xy 333.013558 -82.422492) (xy 332.149958 -82.422492) (xy 332.122708 -82.422035) (xy 332.068762 -82.414274)
			(xy 332.01647 -82.398914) (xy 331.966896 -82.37627) (xy 331.921049 -82.346801) (xy 331.879862 -82.311108)
			(xy 331.844174 -82.269917) (xy 331.81471 -82.224067) (xy 331.792071 -82.17449) (xy 331.776717 -82.122197)
			(xy 331.768962 -82.06825) (xy 239.640092 -82.06825) (xy 239.623713 -82.211927) (xy 239.596047 -82.383601)
			(xy 239.560472 -82.553811) (xy 239.517063 -82.722195) (xy 239.465913 -82.888391) (xy 239.407133 -83.052043)
			(xy 239.340846 -83.212802) (xy 239.267197 -83.370324) (xy 239.186341 -83.524271) (xy 239.148735 -83.588471)
			(xy 341.356398 -83.588471) (xy 341.356398 -83.533929) (xy 341.364161 -83.479942) (xy 341.379527 -83.427609)
			(xy 341.402184 -83.377996) (xy 341.431672 -83.332112) (xy 341.467389 -83.290892) (xy 341.508609 -83.255174)
			(xy 341.554492 -83.225686) (xy 341.604106 -83.203028) (xy 341.656438 -83.187661) (xy 341.710425 -83.179899)
			(xy 341.737696 -83.179412) (xy 342.601296 -83.179412) (xy 342.628565 -83.179927) (xy 342.682549 -83.187688)
			(xy 342.734879 -83.203053) (xy 342.784489 -83.225709) (xy 342.83037 -83.255194) (xy 342.871588 -83.290909)
			(xy 342.907303 -83.332127) (xy 342.936789 -83.378008) (xy 342.959445 -83.427618) (xy 342.974811 -83.479947)
			(xy 342.982573 -83.533931) (xy 342.982573 -83.588469) (xy 342.974811 -83.642453) (xy 342.959445 -83.694782)
			(xy 342.936789 -83.744392) (xy 342.907303 -83.790273) (xy 342.871588 -83.831491) (xy 342.83037 -83.867206)
			(xy 342.784489 -83.896691) (xy 342.734879 -83.919347) (xy 342.682549 -83.934712) (xy 342.628565 -83.942473)
			(xy 342.601296 -83.942936) (xy 341.737696 -83.942936) (xy 341.710425 -83.942501) (xy 341.656438 -83.934739)
			(xy 341.604106 -83.919372) (xy 341.554492 -83.896714) (xy 341.508609 -83.867226) (xy 341.467389 -83.831508)
			(xy 341.431672 -83.790288) (xy 341.402184 -83.744404) (xy 341.379527 -83.694791) (xy 341.364161 -83.642458)
			(xy 341.356398 -83.588471) (xy 239.148735 -83.588471) (xy 239.098452 -83.674314) (xy 239.003718 -83.820132)
			(xy 238.902342 -83.961413) (xy 238.794541 -84.097854) (xy 238.680545 -84.229164) (xy 238.560599 -84.355062)
			(xy 238.434958 -84.475277) (xy 238.393119 -84.511757) (xy 337.882119 -84.511757) (xy 337.882119 -84.457243)
			(xy 337.889878 -84.403284) (xy 337.905237 -84.350979) (xy 337.927883 -84.301392) (xy 337.957357 -84.255533)
			(xy 337.993057 -84.214336) (xy 338.034257 -84.178639) (xy 338.080119 -84.149169) (xy 338.129707 -84.126526)
			(xy 338.182014 -84.111171) (xy 338.235973 -84.103417) (xy 338.26323 -84.102956) (xy 339.12683 -84.102956)
			(xy 339.154077 -84.103516) (xy 339.208017 -84.111275) (xy 339.260303 -84.126632) (xy 339.309871 -84.149272)
			(xy 339.355714 -84.178737) (xy 339.396896 -84.214425) (xy 339.432581 -84.25561) (xy 339.462042 -84.301455)
			(xy 339.484679 -84.351025) (xy 339.500031 -84.403313) (xy 339.503159 -84.425069) (xy 344.644951 -84.425069)
			(xy 344.644951 -84.370531) (xy 344.652713 -84.316548) (xy 344.668079 -84.26422) (xy 344.690737 -84.214611)
			(xy 344.720223 -84.168731) (xy 344.75594 -84.127516) (xy 344.797159 -84.091803) (xy 344.843041 -84.06232)
			(xy 344.892652 -84.039668) (xy 344.944981 -84.024306) (xy 344.998965 -84.016549) (xy 345.026234 -84.016088)
			(xy 345.889834 -84.016088) (xy 345.917105 -84.016477) (xy 345.971092 -84.024243) (xy 346.023425 -84.039614)
			(xy 346.073037 -84.062275) (xy 346.11892 -84.091766) (xy 346.160139 -84.127485) (xy 346.195855 -84.168708)
			(xy 346.225341 -84.214593) (xy 346.247998 -84.264207) (xy 346.263364 -84.316541) (xy 346.271126 -84.370529)
			(xy 346.271126 -84.425071) (xy 346.263364 -84.479059) (xy 346.247998 -84.531393) (xy 346.225341 -84.581007)
			(xy 346.195855 -84.626892) (xy 346.160139 -84.668115) (xy 346.11892 -84.703834) (xy 346.073037 -84.733325)
			(xy 346.023425 -84.755986) (xy 345.971092 -84.771357) (xy 345.917105 -84.779123) (xy 345.889834 -84.779612)
			(xy 345.026234 -84.779612) (xy 344.998965 -84.779051) (xy 344.944981 -84.771294) (xy 344.892652 -84.755932)
			(xy 344.843041 -84.73328) (xy 344.797159 -84.703797) (xy 344.75594 -84.668084) (xy 344.720223 -84.626869)
			(xy 344.690737 -84.580989) (xy 344.668079 -84.53138) (xy 344.652713 -84.479052) (xy 344.644951 -84.425069)
			(xy 339.503159 -84.425069) (xy 339.507786 -84.457253) (xy 339.507786 -84.511747) (xy 339.500031 -84.565687)
			(xy 339.484679 -84.617975) (xy 339.462042 -84.667545) (xy 339.432581 -84.71339) (xy 339.396896 -84.754575)
			(xy 339.355714 -84.790263) (xy 339.309871 -84.819728) (xy 339.260303 -84.842368) (xy 339.208017 -84.857725)
			(xy 339.154077 -84.865484) (xy 339.12683 -84.865972) (xy 338.26323 -84.865972) (xy 338.235973 -84.865583)
			(xy 338.182014 -84.857829) (xy 338.129707 -84.842474) (xy 338.080119 -84.819831) (xy 338.034257 -84.790361)
			(xy 337.993057 -84.754664) (xy 337.957357 -84.713467) (xy 337.927883 -84.667608) (xy 337.905237 -84.618021)
			(xy 337.889878 -84.565716) (xy 337.882119 -84.511757) (xy 238.393119 -84.511757) (xy 238.303893 -84.589554)
			(xy 238.167683 -84.697647) (xy 238.02662 -84.799326) (xy 237.881005 -84.894371) (xy 237.73115 -84.982581)
			(xy 237.577377 -85.063767) (xy 237.420014 -85.137754) (xy 237.259397 -85.204384) (xy 237.095871 -85.263515)
			(xy 236.929785 -85.315021) (xy 236.761494 -85.35879) (xy 236.59136 -85.39473) (xy 236.419746 -85.422763)
			(xy 236.247019 -85.44283) (xy 236.073548 -85.454887) (xy 235.899706 -85.458909) (xy 235.725864 -85.454887)
			(xy 235.552393 -85.44283) (xy 235.379666 -85.422763) (xy 235.208052 -85.39473) (xy 235.037918 -85.35879)
			(xy 234.869627 -85.315021) (xy 234.703541 -85.263515) (xy 234.540015 -85.204384) (xy 234.379398 -85.137754)
			(xy 234.222035 -85.063767) (xy 234.068262 -84.982581) (xy 233.918407 -84.894371) (xy 233.772792 -84.799326)
			(xy 233.631729 -84.697647) (xy 233.495519 -84.589554) (xy 233.364454 -84.475277) (xy 233.238813 -84.355062)
			(xy 233.118867 -84.229164) (xy 233.004871 -84.097854) (xy 232.89707 -83.961413) (xy 232.795694 -83.820132)
			(xy 232.70096 -83.674314) (xy 232.613071 -83.524271) (xy 232.532215 -83.370324) (xy 232.458566 -83.212802)
			(xy 232.392279 -83.052043) (xy 232.333499 -82.888391) (xy 232.282349 -82.722195) (xy 232.23894 -82.553811)
			(xy 232.203365 -82.383601) (xy 232.175699 -82.211927) (xy 232.156003 -82.039157) (xy 232.144317 -81.865661)
			(xy 232.140667 -81.69181) (xy 2.509012 -81.69181) (xy 2.509012 -85.764678) (xy 10.421355 -85.764678)
			(xy 10.421355 -85.635538) (xy 10.429305 -85.506643) (xy 10.445175 -85.378483) (xy 10.468904 -85.251542)
			(xy 10.500403 -85.126303) (xy 10.539552 -85.00324) (xy 10.586203 -84.882821) (xy 10.640178 -84.765502)
			(xy 10.701273 -84.651728) (xy 10.769256 -84.541931) (xy 10.84387 -84.436528) (xy 10.924831 -84.335918)
			(xy 11.011831 -84.240483) (xy 11.104542 -84.150584) (xy 11.202612 -84.066563) (xy 11.305667 -83.988739)
			(xy 11.413318 -83.917407) (xy 11.525157 -83.852837) (xy 11.640758 -83.795275) (xy 11.759683 -83.744938)
			(xy 11.881482 -83.702018) (xy 12.005692 -83.666677) (xy 12.131841 -83.63905) (xy 12.259453 -83.619241)
			(xy 12.388042 -83.607325) (xy 12.51712 -83.603349) (xy 12.646198 -83.607325) (xy 12.774787 -83.619241)
			(xy 12.902399 -83.63905) (xy 13.028548 -83.666677) (xy 13.152758 -83.702018) (xy 13.274557 -83.744938)
			(xy 13.393482 -83.795275) (xy 13.509083 -83.852837) (xy 13.620922 -83.917407) (xy 13.728573 -83.988739)
			(xy 13.831628 -84.066563) (xy 13.929698 -84.150584) (xy 14.022409 -84.240483) (xy 14.109409 -84.335918)
			(xy 14.19037 -84.436528) (xy 14.264984 -84.541931) (xy 14.332967 -84.651728) (xy 14.394062 -84.765502)
			(xy 14.448037 -84.882821) (xy 14.494688 -85.00324) (xy 14.533837 -85.126303) (xy 14.565336 -85.251542)
			(xy 14.589065 -85.378483) (xy 14.604935 -85.506643) (xy 14.612885 -85.635538) (xy 14.613382 -85.700108)
			(xy 14.612885 -85.764678) (xy 14.608278 -85.839368) (xy 342.975946 -85.839368) (xy 342.975946 -85.784832)
			(xy 342.983708 -85.730852) (xy 342.999072 -85.678525) (xy 343.021727 -85.628918) (xy 343.051211 -85.58304)
			(xy 343.086924 -85.541824) (xy 343.12814 -85.506111) (xy 343.174018 -85.476627) (xy 343.223625 -85.453972)
			(xy 343.275952 -85.438608) (xy 343.329932 -85.430846) (xy 343.3572 -85.43036) (xy 344.2208 -85.43036)
			(xy 344.248071 -85.430802) (xy 344.302058 -85.438565) (xy 344.35439 -85.453931) (xy 344.404003 -85.476588)
			(xy 344.449887 -85.506076) (xy 344.491107 -85.541793) (xy 344.526824 -85.583013) (xy 344.556312 -85.628897)
			(xy 344.578969 -85.67851) (xy 344.594335 -85.730842) (xy 344.602098 -85.784829) (xy 344.602098 -85.839371)
			(xy 344.594335 -85.893358) (xy 344.578969 -85.94569) (xy 344.556312 -85.995303) (xy 344.526824 -86.041187)
			(xy 344.491107 -86.082407) (xy 344.449887 -86.118124) (xy 344.404003 -86.147612) (xy 344.35439 -86.170269)
			(xy 344.302058 -86.185635) (xy 344.248071 -86.193398) (xy 344.2208 -86.193884) (xy 343.3572 -86.193884)
			(xy 343.329932 -86.193354) (xy 343.275952 -86.185592) (xy 343.223625 -86.170228) (xy 343.174018 -86.147573)
			(xy 343.12814 -86.118089) (xy 343.086924 -86.082376) (xy 343.051211 -86.04116) (xy 343.021727 -85.995282)
			(xy 342.999072 -85.945675) (xy 342.983708 -85.893348) (xy 342.975946 -85.839368) (xy 14.608278 -85.839368)
			(xy 14.604935 -85.893573) (xy 14.589065 -86.021733) (xy 14.565336 -86.148674) (xy 14.533837 -86.273913)
			(xy 14.494688 -86.396976) (xy 14.448037 -86.517395) (xy 14.394062 -86.634714) (xy 14.332967 -86.748488)
			(xy 14.264984 -86.858285) (xy 14.19037 -86.963688) (xy 14.109409 -87.064298) (xy 14.022409 -87.159733)
			(xy 13.929698 -87.249632) (xy 13.831628 -87.333653) (xy 13.728573 -87.411477) (xy 13.620922 -87.482809)
			(xy 13.509083 -87.547379) (xy 13.393482 -87.604941) (xy 13.274557 -87.655278) (xy 13.152758 -87.698198)
			(xy 13.028548 -87.733539) (xy 12.902399 -87.761166) (xy 12.774787 -87.780975) (xy 12.646198 -87.792891)
			(xy 12.51712 -87.796868) (xy 12.388042 -87.792891) (xy 12.259453 -87.780975) (xy 12.131841 -87.761166)
			(xy 12.005692 -87.733539) (xy 11.881482 -87.698198) (xy 11.759683 -87.655278) (xy 11.640758 -87.604941)
			(xy 11.525157 -87.547379) (xy 11.413318 -87.482809) (xy 11.305667 -87.411477) (xy 11.202612 -87.333653)
			(xy 11.104542 -87.249632) (xy 11.011831 -87.159733) (xy 10.924831 -87.064298) (xy 10.84387 -86.963688)
			(xy 10.769256 -86.858285) (xy 10.701273 -86.748488) (xy 10.640178 -86.634714) (xy 10.586203 -86.517395)
			(xy 10.539552 -86.396976) (xy 10.500403 -86.273913) (xy 10.468904 -86.148674) (xy 10.445175 -86.021733)
			(xy 10.429305 -85.893573) (xy 10.421355 -85.764678) (xy 2.509012 -85.764678) (xy 2.509012 -98.341434)
			(xy 261.733792 -98.341434) (xy 261.733792 -97.477834) (xy 261.734278 -97.450583) (xy 261.742034 -97.396635)
			(xy 261.757389 -97.34434) (xy 261.780031 -97.294763) (xy 261.809497 -97.248913) (xy 261.845188 -97.207722)
			(xy 261.886379 -97.172031) (xy 261.932229 -97.142565) (xy 261.981806 -97.119923) (xy 262.034101 -97.104568)
			(xy 262.088049 -97.096812) (xy 262.142551 -97.096812) (xy 262.196499 -97.104568) (xy 262.248794 -97.119923)
			(xy 262.298371 -97.142565) (xy 262.344221 -97.172031) (xy 262.385412 -97.207722) (xy 262.421103 -97.248913)
			(xy 262.450569 -97.294763) (xy 262.473211 -97.34434) (xy 262.488566 -97.396635) (xy 262.496322 -97.450583)
			(xy 262.496808 -97.477834) (xy 262.496808 -98.341434) (xy 262.496322 -98.368685) (xy 262.488566 -98.422633)
			(xy 262.473211 -98.474928) (xy 262.450569 -98.524505) (xy 262.421103 -98.570355) (xy 262.385412 -98.611546)
			(xy 262.344221 -98.647237) (xy 262.298371 -98.676703) (xy 262.248794 -98.699345) (xy 262.196499 -98.7147)
			(xy 262.142551 -98.722456) (xy 262.088049 -98.722456) (xy 262.034101 -98.7147) (xy 261.981806 -98.699345)
			(xy 261.932229 -98.676703) (xy 261.886379 -98.647237) (xy 261.845188 -98.611546) (xy 261.809497 -98.570355)
			(xy 261.780031 -98.524505) (xy 261.757389 -98.474928) (xy 261.742034 -98.422633) (xy 261.734278 -98.368685)
			(xy 261.733792 -98.341434) (xy 2.509012 -98.341434) (xy 2.509012 -106.40187) (xy 11.713464 -106.40187)
			(xy 11.713464 -105.53827) (xy 11.71395 -105.511001) (xy 11.721712 -105.457017) (xy 11.737077 -105.404687)
			(xy 11.759734 -105.355077) (xy 11.78922 -105.309196) (xy 11.824935 -105.267979) (xy 11.866152 -105.232264)
			(xy 11.912033 -105.202778) (xy 11.961643 -105.180121) (xy 12.013973 -105.164756) (xy 12.067957 -105.156994)
			(xy 12.122495 -105.156994) (xy 12.176479 -105.164756) (xy 12.228809 -105.180121) (xy 12.278419 -105.202778)
			(xy 12.3243 -105.232264) (xy 12.365517 -105.267979) (xy 12.401232 -105.309196) (xy 12.430718 -105.355077)
			(xy 12.453375 -105.404687) (xy 12.46874 -105.457017) (xy 12.476502 -105.511001) (xy 12.476988 -105.53827)
			(xy 12.476988 -105.664) (xy 15.57274 -105.664) (xy 15.57274 -104.8004) (xy 15.573226 -104.773131)
			(xy 15.580988 -104.719147) (xy 15.596353 -104.666817) (xy 15.61901 -104.617207) (xy 15.648496 -104.571326)
			(xy 15.684211 -104.530109) (xy 15.725428 -104.494394) (xy 15.771309 -104.464908) (xy 15.820919 -104.442251)
			(xy 15.873249 -104.426886) (xy 15.927233 -104.419124) (xy 15.981771 -104.419124) (xy 16.035755 -104.426886)
			(xy 16.088085 -104.442251) (xy 16.137695 -104.464908) (xy 16.183576 -104.494394) (xy 16.224793 -104.530109)
			(xy 16.260508 -104.571326) (xy 16.289994 -104.617207) (xy 16.312651 -104.666817) (xy 16.328016 -104.719147)
			(xy 16.335778 -104.773131) (xy 16.336264 -104.8004) (xy 16.336264 -105.664) (xy 16.335778 -105.691269)
			(xy 16.328016 -105.745253) (xy 16.312651 -105.797583) (xy 16.289994 -105.847193) (xy 16.260508 -105.893074)
			(xy 16.224793 -105.934291) (xy 16.183576 -105.970006) (xy 16.137695 -105.999492) (xy 16.088085 -106.022149)
			(xy 16.035755 -106.037514) (xy 15.981771 -106.045276) (xy 15.927233 -106.045276) (xy 15.873249 -106.037514)
			(xy 15.820919 -106.022149) (xy 15.771309 -105.999492) (xy 15.725428 -105.970006) (xy 15.684211 -105.934291)
			(xy 15.648496 -105.893074) (xy 15.61901 -105.847193) (xy 15.596353 -105.797583) (xy 15.580988 -105.745253)
			(xy 15.573226 -105.691269) (xy 15.57274 -105.664) (xy 12.476988 -105.664) (xy 12.476988 -106.40187)
			(xy 12.476502 -106.429139) (xy 12.46874 -106.483123) (xy 12.453375 -106.535453) (xy 12.430718 -106.585063)
			(xy 12.401232 -106.630944) (xy 12.365517 -106.672161) (xy 12.3243 -106.707876) (xy 12.278419 -106.737362)
			(xy 12.228809 -106.760019) (xy 12.176479 -106.775384) (xy 12.122495 -106.783146) (xy 12.067957 -106.783146)
			(xy 12.013973 -106.775384) (xy 11.961643 -106.760019) (xy 11.912033 -106.737362) (xy 11.866152 -106.707876)
			(xy 11.824935 -106.672161) (xy 11.78922 -106.630944) (xy 11.759734 -106.585063) (xy 11.737077 -106.535453)
			(xy 11.721712 -106.483123) (xy 11.71395 -106.429139) (xy 11.713464 -106.40187) (xy 2.509012 -106.40187)
			(xy 2.509012 -108.943971) (xy 11.292822 -108.943971) (xy 11.292822 -108.889469) (xy 11.300578 -108.835522)
			(xy 11.315933 -108.783228) (xy 11.338574 -108.733651) (xy 11.36804 -108.687801) (xy 11.403731 -108.646611)
			(xy 11.444921 -108.61092) (xy 11.490771 -108.581454) (xy 11.540348 -108.558813) (xy 11.592642 -108.543458)
			(xy 11.646589 -108.535702) (xy 11.67384 -108.535216) (xy 12.53744 -108.535216) (xy 12.564692 -108.535694)
			(xy 12.61864 -108.54345) (xy 12.670935 -108.558806) (xy 12.720513 -108.581447) (xy 12.766364 -108.610914)
			(xy 12.807554 -108.646606) (xy 12.843246 -108.687796) (xy 12.872713 -108.733647) (xy 12.895354 -108.783225)
			(xy 12.91071 -108.83552) (xy 12.918466 -108.889468) (xy 12.918466 -108.943972) (xy 12.918466 -108.943973)
			(xy 15.156389 -108.943973) (xy 15.156389 -108.889467) (xy 15.164146 -108.835517) (xy 15.179502 -108.783219)
			(xy 15.202145 -108.733639) (xy 15.231613 -108.687786) (xy 15.267307 -108.646594) (xy 15.308499 -108.610901)
			(xy 15.354353 -108.581433) (xy 15.403933 -108.558791) (xy 15.45623 -108.543435) (xy 15.510181 -108.535679)
			(xy 15.537434 -108.535216) (xy 16.401034 -108.535216) (xy 16.428285 -108.535694) (xy 16.482233 -108.543451)
			(xy 16.534528 -108.558807) (xy 16.584105 -108.581448) (xy 16.629956 -108.610915) (xy 16.671146 -108.646607)
			(xy 16.706837 -108.687798) (xy 16.707863 -108.689394) (xy 238.647224 -108.689394) (xy 238.647224 -107.825794)
			(xy 238.64771 -107.798525) (xy 238.655472 -107.744541) (xy 238.670837 -107.692211) (xy 238.693494 -107.642601)
			(xy 238.72298 -107.59672) (xy 238.758695 -107.555503) (xy 238.799912 -107.519788) (xy 238.845793 -107.490302)
			(xy 238.895403 -107.467645) (xy 238.947733 -107.45228) (xy 239.001717 -107.444518) (xy 239.056255 -107.444518)
			(xy 239.110239 -107.45228) (xy 239.162569 -107.467645) (xy 239.212179 -107.490302) (xy 239.25806 -107.519788)
			(xy 239.299277 -107.555503) (xy 239.334992 -107.59672) (xy 239.364478 -107.642601) (xy 239.387135 -107.692211)
			(xy 239.4025 -107.744541) (xy 239.410262 -107.798525) (xy 239.410748 -107.825794) (xy 239.410748 -108.689394)
			(xy 239.410262 -108.716663) (xy 239.4025 -108.770647) (xy 239.387135 -108.822977) (xy 239.364478 -108.872587)
			(xy 239.334992 -108.918468) (xy 239.299277 -108.959685) (xy 239.25806 -108.9954) (xy 239.212179 -109.024886)
			(xy 239.162569 -109.047543) (xy 239.110239 -109.062908) (xy 239.056255 -109.07067) (xy 239.001717 -109.07067)
			(xy 238.947733 -109.062908) (xy 238.895403 -109.047543) (xy 238.845793 -109.024886) (xy 238.799912 -108.9954)
			(xy 238.758695 -108.959685) (xy 238.72298 -108.918468) (xy 238.693494 -108.872587) (xy 238.670837 -108.822977)
			(xy 238.655472 -108.770647) (xy 238.64771 -108.716663) (xy 238.647224 -108.689394) (xy 16.707863 -108.689394)
			(xy 16.736304 -108.733648) (xy 16.758945 -108.783226) (xy 16.7743 -108.835521) (xy 16.782056 -108.889469)
			(xy 16.782056 -108.943971) (xy 16.7743 -108.997919) (xy 16.758945 -109.050214) (xy 16.736304 -109.099792)
			(xy 16.706837 -109.145642) (xy 16.671146 -109.186833) (xy 16.629956 -109.222525) (xy 16.584105 -109.251992)
			(xy 16.534528 -109.274633) (xy 16.482233 -109.289989) (xy 16.428285 -109.297746) (xy 16.401034 -109.298232)
			(xy 15.537434 -109.298232) (xy 15.510181 -109.297761) (xy 15.45623 -109.290005) (xy 15.403933 -109.274649)
			(xy 15.354353 -109.252007) (xy 15.308499 -109.222539) (xy 15.267307 -109.186846) (xy 15.231613 -109.145654)
			(xy 15.202145 -109.099801) (xy 15.179502 -109.050221) (xy 15.164146 -108.997923) (xy 15.156389 -108.943973)
			(xy 12.918466 -108.943973) (xy 12.91071 -108.99792) (xy 12.895354 -109.050215) (xy 12.872713 -109.099793)
			(xy 12.843246 -109.145644) (xy 12.807554 -109.186834) (xy 12.766364 -109.222526) (xy 12.720513 -109.251993)
			(xy 12.670935 -109.274634) (xy 12.61864 -109.28999) (xy 12.564692 -109.297746) (xy 12.53744 -109.298232)
			(xy 11.67384 -109.298232) (xy 11.646589 -109.297738) (xy 11.592642 -109.289982) (xy 11.540348 -109.274627)
			(xy 11.490771 -109.251986) (xy 11.444921 -109.22252) (xy 11.403731 -109.186829) (xy 11.36804 -109.145639)
			(xy 11.338574 -109.099789) (xy 11.315933 -109.050212) (xy 11.300578 -108.997918) (xy 11.292822 -108.943971)
			(xy 2.509012 -108.943971) (xy 2.509012 -109.550266) (xy 250.428546 -109.550266) (xy 250.428546 -109.495734)
			(xy 250.436306 -109.441757) (xy 250.451669 -109.389434) (xy 250.474321 -109.339829) (xy 250.503801 -109.293953)
			(xy 250.53951 -109.252739) (xy 250.580721 -109.217025) (xy 250.626594 -109.18754) (xy 250.676196 -109.164883)
			(xy 250.728518 -109.149515) (xy 250.782494 -109.141749) (xy 250.80976 -109.14126) (xy 251.67336 -109.14126)
			(xy 251.700634 -109.141677) (xy 251.754629 -109.149435) (xy 251.806969 -109.164798) (xy 251.85659 -109.187455)
			(xy 251.902482 -109.216943) (xy 251.943709 -109.252663) (xy 251.979433 -109.293886) (xy 252.008926 -109.339775)
			(xy 252.031588 -109.389393) (xy 252.046957 -109.441732) (xy 252.05472 -109.495726) (xy 252.05472 -109.550274)
			(xy 252.046957 -109.604268) (xy 252.031588 -109.656607) (xy 252.008926 -109.706225) (xy 251.979433 -109.752114)
			(xy 251.943709 -109.793337) (xy 251.902482 -109.829057) (xy 251.85659 -109.858545) (xy 251.806969 -109.881202)
			(xy 251.754629 -109.896565) (xy 251.700634 -109.904323) (xy 251.67336 -109.904784) (xy 250.80976 -109.904784)
			(xy 250.782494 -109.904251) (xy 250.728518 -109.896485) (xy 250.676196 -109.881117) (xy 250.626594 -109.85846)
			(xy 250.580721 -109.828975) (xy 250.53951 -109.793262) (xy 250.503801 -109.752047) (xy 250.474321 -109.706171)
			(xy 250.451669 -109.656566) (xy 250.436306 -109.604243) (xy 250.428546 -109.550266) (xy 2.509012 -109.550266)
			(xy 2.509012 -111.158274) (xy 239.40262 -111.158274) (xy 239.40262 -110.294674) (xy 239.403106 -110.267423)
			(xy 239.410862 -110.213475) (xy 239.426217 -110.16118) (xy 239.448859 -110.111603) (xy 239.478325 -110.065753)
			(xy 239.514016 -110.024562) (xy 239.555207 -109.988871) (xy 239.601057 -109.959405) (xy 239.650634 -109.936763)
			(xy 239.702929 -109.921408) (xy 239.756877 -109.913652) (xy 239.811379 -109.913652) (xy 239.865327 -109.921408)
			(xy 239.917622 -109.936763) (xy 239.967199 -109.959405) (xy 240.000574 -109.980854) (xy 256.88563 -109.980854)
			(xy 256.88563 -109.926346) (xy 256.893387 -109.872392) (xy 256.908744 -109.820091) (xy 256.931388 -109.770508)
			(xy 256.960857 -109.724652) (xy 256.996552 -109.683457) (xy 257.037747 -109.647761) (xy 257.083602 -109.61829)
			(xy 257.133185 -109.595646) (xy 257.185486 -109.580288) (xy 257.23944 -109.57253) (xy 257.266694 -109.572044)
			(xy 258.130294 -109.572044) (xy 258.157544 -109.572603) (xy 258.211488 -109.580358) (xy 258.26378 -109.595712)
			(xy 258.313355 -109.618351) (xy 258.359203 -109.647815) (xy 258.400391 -109.683504) (xy 258.436081 -109.724692)
			(xy 258.465546 -109.77054) (xy 258.488186 -109.820114) (xy 258.503541 -109.872406) (xy 258.511297 -109.92635)
			(xy 258.511297 -109.98085) (xy 258.503541 -110.034794) (xy 258.488186 -110.087086) (xy 258.465546 -110.13666)
			(xy 258.436081 -110.182508) (xy 258.400391 -110.223696) (xy 258.359203 -110.259385) (xy 258.313355 -110.288849)
			(xy 258.26378 -110.311488) (xy 258.211488 -110.326842) (xy 258.157544 -110.334597) (xy 258.130294 -110.33506)
			(xy 257.266694 -110.33506) (xy 257.23944 -110.33467) (xy 257.185486 -110.326912) (xy 257.133185 -110.311554)
			(xy 257.083602 -110.28891) (xy 257.037747 -110.259439) (xy 256.996552 -110.223743) (xy 256.960857 -110.182548)
			(xy 256.931388 -110.136692) (xy 256.908744 -110.087109) (xy 256.893387 -110.034808) (xy 256.88563 -109.980854)
			(xy 240.000574 -109.980854) (xy 240.013049 -109.988871) (xy 240.05424 -110.024562) (xy 240.089931 -110.065753)
			(xy 240.119397 -110.111603) (xy 240.142039 -110.16118) (xy 240.157394 -110.213475) (xy 240.16515 -110.267423)
			(xy 240.165636 -110.294674) (xy 240.165636 -111.158274) (xy 240.16515 -111.185525) (xy 240.157394 -111.239473)
			(xy 240.142039 -111.291768) (xy 240.119397 -111.341345) (xy 240.089931 -111.387195) (xy 240.05424 -111.428386)
			(xy 240.013049 -111.464077) (xy 239.967199 -111.493543) (xy 239.917622 -111.516185) (xy 239.865327 -111.53154)
			(xy 239.811379 -111.539296) (xy 239.756877 -111.539296) (xy 239.702929 -111.53154) (xy 239.650634 -111.516185)
			(xy 239.601057 -111.493543) (xy 239.555207 -111.464077) (xy 239.514016 -111.428386) (xy 239.478325 -111.387195)
			(xy 239.448859 -111.341345) (xy 239.426217 -111.291768) (xy 239.410862 -111.239473) (xy 239.403106 -111.185525)
			(xy 239.40262 -111.158274) (xy 2.509012 -111.158274) (xy 2.509012 -114.734161) (xy 11.255226 -114.734161)
			(xy 11.255226 -114.679659) (xy 11.262982 -114.625711) (xy 11.278337 -114.573416) (xy 11.300979 -114.523839)
			(xy 11.330445 -114.477988) (xy 11.366136 -114.436798) (xy 11.407326 -114.401106) (xy 11.453177 -114.371639)
			(xy 11.502754 -114.348998) (xy 11.555049 -114.333643) (xy 11.608997 -114.325886) (xy 11.636248 -114.3254)
			(xy 12.499848 -114.3254) (xy 12.527101 -114.325867) (xy 12.581052 -114.333624) (xy 12.633349 -114.34898)
			(xy 12.68293 -114.371622) (xy 12.728783 -114.40109) (xy 12.769975 -114.436783) (xy 12.805669 -114.477976)
			(xy 12.835137 -114.523829) (xy 12.85778 -114.573409) (xy 12.873136 -114.625706) (xy 12.880893 -114.679657)
			(xy 12.880893 -114.734163) (xy 12.873136 -114.788114) (xy 12.85778 -114.840411) (xy 12.835137 -114.889991)
			(xy 12.805669 -114.935844) (xy 12.769975 -114.977037) (xy 12.728783 -115.01273) (xy 12.68293 -115.042198)
			(xy 12.633349 -115.06484) (xy 12.581052 -115.080196) (xy 12.527101 -115.087953) (xy 12.499848 -115.088416)
			(xy 11.636248 -115.088416) (xy 11.608997 -115.087934) (xy 11.555049 -115.080177) (xy 11.502754 -115.064822)
			(xy 11.453177 -115.042181) (xy 11.407326 -115.012714) (xy 11.366136 -114.977022) (xy 11.330445 -114.935832)
			(xy 11.300979 -114.889981) (xy 11.278337 -114.840404) (xy 11.262982 -114.788109) (xy 11.255226 -114.734161)
			(xy 2.509012 -114.734161) (xy 2.509012 -116.393573) (xy 230.652992 -116.393573) (xy 230.652992 -116.339027)
			(xy 230.660755 -116.285035) (xy 230.676123 -116.232698) (xy 230.698784 -116.183081) (xy 230.728276 -116.137195)
			(xy 230.763998 -116.095973) (xy 230.805224 -116.060254) (xy 230.851113 -116.030767) (xy 230.900732 -116.008111)
			(xy 230.95307 -115.992747) (xy 231.007063 -115.984989) (xy 231.034336 -115.984528) (xy 231.897936 -115.984528)
			(xy 231.925203 -115.985037) (xy 231.979181 -115.992802) (xy 232.031505 -116.008171) (xy 232.081109 -116.030828)
			(xy 232.126985 -116.060314) (xy 232.168197 -116.096029) (xy 232.203907 -116.137244) (xy 232.233389 -116.183122)
			(xy 232.256042 -116.232729) (xy 232.271405 -116.285054) (xy 232.277026 -116.324151) (xy 236.866903 -116.324151)
			(xy 236.866903 -116.269649) (xy 236.87466 -116.215701) (xy 236.890016 -116.163407) (xy 236.912659 -116.113831)
			(xy 236.942127 -116.067981) (xy 236.97782 -116.026793) (xy 237.019012 -115.991104) (xy 237.064864 -115.961641)
			(xy 237.114443 -115.939003) (xy 237.166739 -115.923652) (xy 237.220687 -115.915901) (xy 237.247938 -115.91544)
			(xy 238.111538 -115.91544) (xy 238.138791 -115.915832) (xy 238.192741 -115.923594) (xy 238.245038 -115.938955)
			(xy 238.294617 -115.961601) (xy 238.340468 -115.991072) (xy 238.381659 -116.026768) (xy 238.417351 -116.067962)
			(xy 238.446817 -116.113817) (xy 238.469459 -116.163398) (xy 238.484814 -116.215696) (xy 238.49257 -116.269647)
			(xy 238.49257 -116.324153) (xy 238.484814 -116.378104) (xy 238.469459 -116.430402) (xy 238.446817 -116.479983)
			(xy 238.417351 -116.525838) (xy 238.381659 -116.567032) (xy 238.340468 -116.602728) (xy 238.294617 -116.632199)
			(xy 238.245038 -116.654845) (xy 238.192741 -116.670206) (xy 238.138791 -116.677968) (xy 238.111538 -116.678456)
			(xy 237.247938 -116.678456) (xy 237.220687 -116.677899) (xy 237.166739 -116.670148) (xy 237.114443 -116.654797)
			(xy 237.064864 -116.632159) (xy 237.019012 -116.602696) (xy 236.97782 -116.567007) (xy 236.942127 -116.525819)
			(xy 236.912659 -116.479969) (xy 236.890016 -116.430393) (xy 236.87466 -116.378099) (xy 236.866903 -116.324151)
			(xy 232.277026 -116.324151) (xy 232.279166 -116.339033) (xy 232.279166 -116.393567) (xy 232.271405 -116.447546)
			(xy 232.256042 -116.499871) (xy 232.233389 -116.549478) (xy 232.203907 -116.595356) (xy 232.168197 -116.636571)
			(xy 232.126985 -116.672286) (xy 232.081109 -116.701772) (xy 232.031505 -116.724429) (xy 231.979181 -116.739798)
			(xy 231.925203 -116.747563) (xy 231.897936 -116.748052) (xy 231.034336 -116.748052) (xy 231.007063 -116.747611)
			(xy 230.95307 -116.739853) (xy 230.900732 -116.724489) (xy 230.851113 -116.701833) (xy 230.805224 -116.672346)
			(xy 230.763998 -116.636627) (xy 230.728276 -116.595405) (xy 230.698784 -116.549519) (xy 230.676123 -116.499902)
			(xy 230.660755 -116.447565) (xy 230.652992 -116.393573) (xy 2.509012 -116.393573) (xy 2.509012 -117.632251)
			(xy 233.564903 -117.632251) (xy 233.564903 -117.577749) (xy 233.57266 -117.523801) (xy 233.588016 -117.471507)
			(xy 233.610659 -117.421931) (xy 233.640127 -117.376081) (xy 233.67582 -117.334893) (xy 233.717012 -117.299204)
			(xy 233.762864 -117.269741) (xy 233.812443 -117.247103) (xy 233.864739 -117.231752) (xy 233.918687 -117.224001)
			(xy 233.945938 -117.22354) (xy 234.809538 -117.22354) (xy 234.836791 -117.223932) (xy 234.890741 -117.231694)
			(xy 234.943038 -117.247055) (xy 234.992617 -117.269701) (xy 235.038468 -117.299172) (xy 235.079659 -117.334868)
			(xy 235.115351 -117.376062) (xy 235.144817 -117.421917) (xy 235.167459 -117.471498) (xy 235.182814 -117.523796)
			(xy 235.19057 -117.577747) (xy 235.19057 -117.632251) (xy 238.898903 -117.632251) (xy 238.898903 -117.577749)
			(xy 238.90666 -117.523801) (xy 238.922016 -117.471507) (xy 238.944659 -117.421931) (xy 238.974127 -117.376081)
			(xy 239.00982 -117.334893) (xy 239.051012 -117.299204) (xy 239.096864 -117.269741) (xy 239.146443 -117.247103)
			(xy 239.198739 -117.231752) (xy 239.252687 -117.224001) (xy 239.279938 -117.22354) (xy 240.143538 -117.22354)
			(xy 240.170791 -117.223932) (xy 240.224741 -117.231694) (xy 240.277038 -117.247055) (xy 240.326617 -117.269701)
			(xy 240.372468 -117.299172) (xy 240.413659 -117.334868) (xy 240.449351 -117.376062) (xy 240.478817 -117.421917)
			(xy 240.501459 -117.471498) (xy 240.516814 -117.523796) (xy 240.52457 -117.577747) (xy 240.52457 -117.632253)
			(xy 240.516814 -117.686204) (xy 240.501459 -117.738502) (xy 240.478817 -117.788083) (xy 240.449351 -117.833938)
			(xy 240.413659 -117.875132) (xy 240.372468 -117.910828) (xy 240.326617 -117.940299) (xy 240.277038 -117.962945)
			(xy 240.224741 -117.978306) (xy 240.170791 -117.986068) (xy 240.143538 -117.986556) (xy 239.279938 -117.986556)
			(xy 239.252687 -117.985999) (xy 239.198739 -117.978248) (xy 239.146443 -117.962897) (xy 239.096864 -117.940259)
			(xy 239.051012 -117.910796) (xy 239.00982 -117.875107) (xy 238.974127 -117.833919) (xy 238.944659 -117.788069)
			(xy 238.922016 -117.738493) (xy 238.90666 -117.686199) (xy 238.898903 -117.632251) (xy 235.19057 -117.632251)
			(xy 235.19057 -117.632253) (xy 235.182814 -117.686204) (xy 235.167459 -117.738502) (xy 235.144817 -117.788083)
			(xy 235.115351 -117.833938) (xy 235.079659 -117.875132) (xy 235.038468 -117.910828) (xy 234.992617 -117.940299)
			(xy 234.943038 -117.962945) (xy 234.890741 -117.978306) (xy 234.836791 -117.986068) (xy 234.809538 -117.986556)
			(xy 233.945938 -117.986556) (xy 233.918687 -117.985999) (xy 233.864739 -117.978248) (xy 233.812443 -117.962897)
			(xy 233.762864 -117.940259) (xy 233.717012 -117.910796) (xy 233.67582 -117.875107) (xy 233.640127 -117.833919)
			(xy 233.610659 -117.788069) (xy 233.588016 -117.738493) (xy 233.57266 -117.686199) (xy 233.564903 -117.632251)
			(xy 2.509012 -117.632251) (xy 2.509012 -123.093988) (xy 227.217732 -123.093988) (xy 227.217732 -122.230388)
			(xy 227.218218 -122.203137) (xy 227.225974 -122.149189) (xy 227.241329 -122.096894) (xy 227.263971 -122.047317)
			(xy 227.293437 -122.001467) (xy 227.329128 -121.960276) (xy 227.370319 -121.924585) (xy 227.416169 -121.895119)
			(xy 227.465746 -121.872477) (xy 227.518041 -121.857122) (xy 227.571989 -121.849366) (xy 227.626491 -121.849366)
			(xy 227.680439 -121.857122) (xy 227.732734 -121.872477) (xy 227.782311 -121.895119) (xy 227.828161 -121.924585)
			(xy 227.869352 -121.960276) (xy 227.905043 -122.001467) (xy 227.934509 -122.047317) (xy 227.957151 -122.096894)
			(xy 227.972506 -122.149189) (xy 227.980262 -122.203137) (xy 227.980748 -122.230388) (xy 227.980748 -122.921014)
			(xy 245.563136 -122.921014) (xy 245.563136 -122.057414) (xy 245.563622 -122.030163) (xy 245.571378 -121.976215)
			(xy 245.586733 -121.92392) (xy 245.609375 -121.874343) (xy 245.638841 -121.828493) (xy 245.674532 -121.787302)
			(xy 245.715723 -121.751611) (xy 245.761573 -121.722145) (xy 245.81115 -121.699503) (xy 245.863445 -121.684148)
			(xy 245.917393 -121.676392) (xy 245.971895 -121.676392) (xy 246.025843 -121.684148) (xy 246.078138 -121.699503)
			(xy 246.127715 -121.722145) (xy 246.173565 -121.751611) (xy 246.214756 -121.787302) (xy 246.250447 -121.828493)
			(xy 246.279913 -121.874343) (xy 246.302555 -121.92392) (xy 246.31791 -121.976215) (xy 246.325666 -122.030163)
			(xy 246.326152 -122.057414) (xy 246.326152 -122.921014) (xy 246.325666 -122.948265) (xy 246.31791 -123.002213)
			(xy 246.302555 -123.054508) (xy 246.279913 -123.104085) (xy 246.250447 -123.149935) (xy 246.214756 -123.191126)
			(xy 246.173565 -123.226817) (xy 246.127715 -123.256283) (xy 246.078138 -123.278925) (xy 246.025843 -123.29428)
			(xy 245.971895 -123.302036) (xy 245.917393 -123.302036) (xy 245.863445 -123.29428) (xy 245.81115 -123.278925)
			(xy 245.761573 -123.256283) (xy 245.715723 -123.226817) (xy 245.674532 -123.191126) (xy 245.638841 -123.149935)
			(xy 245.609375 -123.104085) (xy 245.586733 -123.054508) (xy 245.571378 -123.002213) (xy 245.563622 -122.948265)
			(xy 245.563136 -122.921014) (xy 227.980748 -122.921014) (xy 227.980748 -123.093988) (xy 227.980262 -123.121239)
			(xy 227.972506 -123.175187) (xy 227.957151 -123.227482) (xy 227.934509 -123.277059) (xy 227.905043 -123.322909)
			(xy 227.869352 -123.3641) (xy 227.828161 -123.399791) (xy 227.782311 -123.429257) (xy 227.732734 -123.451899)
			(xy 227.680439 -123.467254) (xy 227.626491 -123.47501) (xy 227.571989 -123.47501) (xy 227.518041 -123.467254)
			(xy 227.465746 -123.451899) (xy 227.416169 -123.429257) (xy 227.370319 -123.399791) (xy 227.329128 -123.3641)
			(xy 227.293437 -123.322909) (xy 227.263971 -123.277059) (xy 227.241329 -123.227482) (xy 227.225974 -123.175187)
			(xy 227.218218 -123.121239) (xy 227.217732 -123.093988) (xy 2.509012 -123.093988) (xy 2.509012 -125.221746)
			(xy 225.535744 -125.221746) (xy 225.535744 -124.358146) (xy 225.53623 -124.330877) (xy 225.543992 -124.276893)
			(xy 225.559357 -124.224563) (xy 225.582014 -124.174953) (xy 225.6115 -124.129072) (xy 225.647215 -124.087855)
			(xy 225.688432 -124.05214) (xy 225.734313 -124.022654) (xy 225.783923 -123.999997) (xy 225.836253 -123.984632)
			(xy 225.890237 -123.97687) (xy 225.944775 -123.97687) (xy 225.998759 -123.984632) (xy 226.051089 -123.999997)
			(xy 226.100699 -124.022654) (xy 226.14658 -124.05214) (xy 226.187797 -124.087855) (xy 226.223512 -124.129072)
			(xy 226.252998 -124.174953) (xy 226.275655 -124.224563) (xy 226.29102 -124.276893) (xy 226.298782 -124.330877)
			(xy 226.299268 -124.358146) (xy 226.299268 -125.221746) (xy 226.298782 -125.249015) (xy 226.29102 -125.302999)
			(xy 226.275655 -125.355329) (xy 226.252998 -125.404939) (xy 226.223512 -125.45082) (xy 226.187797 -125.492037)
			(xy 226.14658 -125.527752) (xy 226.100699 -125.557238) (xy 226.051089 -125.579895) (xy 225.998759 -125.59526)
			(xy 225.944775 -125.603022) (xy 225.890237 -125.603022) (xy 225.836253 -125.59526) (xy 225.783923 -125.579895)
			(xy 225.734313 -125.557238) (xy 225.688432 -125.527752) (xy 225.647215 -125.492037) (xy 225.6115 -125.45082)
			(xy 225.582014 -125.404939) (xy 225.559357 -125.355329) (xy 225.543992 -125.302999) (xy 225.53623 -125.249015)
			(xy 225.535744 -125.221746) (xy 2.509012 -125.221746) (xy 2.509012 -127.325628) (xy 227.034852 -127.325628)
			(xy 227.034852 -126.462028) (xy 227.035338 -126.434777) (xy 227.043094 -126.380829) (xy 227.058449 -126.328534)
			(xy 227.081091 -126.278957) (xy 227.110557 -126.233107) (xy 227.146248 -126.191916) (xy 227.187439 -126.156225)
			(xy 227.233289 -126.126759) (xy 227.282866 -126.104117) (xy 227.335161 -126.088762) (xy 227.389109 -126.081006)
			(xy 227.443611 -126.081006) (xy 227.497559 -126.088762) (xy 227.549854 -126.104117) (xy 227.599431 -126.126759)
			(xy 227.645281 -126.156225) (xy 227.686472 -126.191916) (xy 227.722163 -126.233107) (xy 227.751629 -126.278957)
			(xy 227.774271 -126.328534) (xy 227.789626 -126.380829) (xy 227.797382 -126.434777) (xy 227.797868 -126.462028)
			(xy 227.797868 -127.140208) (xy 242.041172 -127.140208) (xy 242.041172 -126.276608) (xy 242.041658 -126.249357)
			(xy 242.049414 -126.195409) (xy 242.064769 -126.143114) (xy 242.087411 -126.093537) (xy 242.116877 -126.047687)
			(xy 242.152568 -126.006496) (xy 242.193759 -125.970805) (xy 242.239609 -125.941339) (xy 242.289186 -125.918697)
			(xy 242.341481 -125.903342) (xy 242.395429 -125.895586) (xy 242.449931 -125.895586) (xy 242.503879 -125.903342)
			(xy 242.556174 -125.918697) (xy 242.605751 -125.941339) (xy 242.651601 -125.970805) (xy 242.692792 -126.006496)
			(xy 242.728483 -126.047687) (xy 242.757949 -126.093537) (xy 242.780591 -126.143114) (xy 242.795946 -126.195409)
			(xy 242.803702 -126.249357) (xy 242.804188 -126.276608) (xy 242.804188 -127.140208) (xy 242.803702 -127.167459)
			(xy 242.795946 -127.221407) (xy 242.780591 -127.273702) (xy 242.757949 -127.323279) (xy 242.728483 -127.369129)
			(xy 242.692792 -127.41032) (xy 242.651601 -127.446011) (xy 242.605751 -127.475477) (xy 242.556174 -127.498119)
			(xy 242.503879 -127.513474) (xy 242.449931 -127.52123) (xy 242.395429 -127.52123) (xy 242.341481 -127.513474)
			(xy 242.289186 -127.498119) (xy 242.239609 -127.475477) (xy 242.193759 -127.446011) (xy 242.152568 -127.41032)
			(xy 242.116877 -127.369129) (xy 242.087411 -127.323279) (xy 242.064769 -127.273702) (xy 242.049414 -127.221407)
			(xy 242.041658 -127.167459) (xy 242.041172 -127.140208) (xy 227.797868 -127.140208) (xy 227.797868 -127.325628)
			(xy 227.797382 -127.352879) (xy 227.789626 -127.406827) (xy 227.774271 -127.459122) (xy 227.751629 -127.508699)
			(xy 227.722163 -127.554549) (xy 227.686472 -127.59574) (xy 227.645281 -127.631431) (xy 227.599431 -127.660897)
			(xy 227.549854 -127.683539) (xy 227.519478 -127.692458) (xy 458.401155 -127.692458) (xy 458.401155 -127.563318)
			(xy 458.409105 -127.434423) (xy 458.424975 -127.306263) (xy 458.448704 -127.179322) (xy 458.480203 -127.054083)
			(xy 458.519352 -126.93102) (xy 458.566003 -126.810601) (xy 458.619978 -126.693282) (xy 458.681073 -126.579508)
			(xy 458.749056 -126.469711) (xy 458.82367 -126.364308) (xy 458.904631 -126.263698) (xy 458.991631 -126.168263)
			(xy 459.084342 -126.078364) (xy 459.182412 -125.994343) (xy 459.285467 -125.916519) (xy 459.393118 -125.845187)
			(xy 459.504957 -125.780617) (xy 459.620558 -125.723055) (xy 459.739483 -125.672718) (xy 459.861282 -125.629798)
			(xy 459.985492 -125.594457) (xy 460.111641 -125.56683) (xy 460.239253 -125.547021) (xy 460.367842 -125.535105)
			(xy 460.49692 -125.531129) (xy 460.625998 -125.535105) (xy 460.754587 -125.547021) (xy 460.882199 -125.56683)
			(xy 461.008348 -125.594457) (xy 461.132558 -125.629798) (xy 461.254357 -125.672718) (xy 461.373282 -125.723055)
			(xy 461.488883 -125.780617) (xy 461.600722 -125.845187) (xy 461.708373 -125.916519) (xy 461.811428 -125.994343)
			(xy 461.909498 -126.078364) (xy 462.002209 -126.168263) (xy 462.089209 -126.263698) (xy 462.17017 -126.364308)
			(xy 462.244784 -126.469711) (xy 462.312767 -126.579508) (xy 462.373862 -126.693282) (xy 462.427837 -126.810601)
			(xy 462.474488 -126.93102) (xy 462.513637 -127.054083) (xy 462.545136 -127.179322) (xy 462.568865 -127.306263)
			(xy 462.584735 -127.434423) (xy 462.592685 -127.563318) (xy 462.593182 -127.627888) (xy 462.592685 -127.692458)
			(xy 462.584735 -127.821353) (xy 462.568865 -127.949513) (xy 462.545136 -128.076454) (xy 462.513637 -128.201693)
			(xy 462.474488 -128.324756) (xy 462.427837 -128.445175) (xy 462.373862 -128.562494) (xy 462.312767 -128.676268)
			(xy 462.244784 -128.786065) (xy 462.17017 -128.891468) (xy 462.089209 -128.992078) (xy 462.002209 -129.087513)
			(xy 461.909498 -129.177412) (xy 461.811428 -129.261433) (xy 461.708373 -129.339257) (xy 461.600722 -129.410589)
			(xy 461.488883 -129.475159) (xy 461.373282 -129.532721) (xy 461.254357 -129.583058) (xy 461.132558 -129.625978)
			(xy 461.008348 -129.661319) (xy 460.882199 -129.688946) (xy 460.754587 -129.708755) (xy 460.625998 -129.720671)
			(xy 460.49692 -129.724648) (xy 460.367842 -129.720671) (xy 460.239253 -129.708755) (xy 460.111641 -129.688946)
			(xy 459.985492 -129.661319) (xy 459.861282 -129.625978) (xy 459.739483 -129.583058) (xy 459.620558 -129.532721)
			(xy 459.504957 -129.475159) (xy 459.393118 -129.410589) (xy 459.285467 -129.339257) (xy 459.182412 -129.261433)
			(xy 459.084342 -129.177412) (xy 458.991631 -129.087513) (xy 458.904631 -128.992078) (xy 458.82367 -128.891468)
			(xy 458.749056 -128.786065) (xy 458.681073 -128.676268) (xy 458.619978 -128.562494) (xy 458.566003 -128.445175)
			(xy 458.519352 -128.324756) (xy 458.480203 -128.201693) (xy 458.448704 -128.076454) (xy 458.424975 -127.949513)
			(xy 458.409105 -127.821353) (xy 458.401155 -127.692458) (xy 227.519478 -127.692458) (xy 227.497559 -127.698894)
			(xy 227.443611 -127.70665) (xy 227.389109 -127.70665) (xy 227.335161 -127.698894) (xy 227.282866 -127.683539)
			(xy 227.233289 -127.660897) (xy 227.187439 -127.631431) (xy 227.146248 -127.59574) (xy 227.110557 -127.554549)
			(xy 227.081091 -127.508699) (xy 227.058449 -127.459122) (xy 227.043094 -127.406827) (xy 227.035338 -127.352879)
			(xy 227.034852 -127.325628) (xy 2.509012 -127.325628) (xy 2.509012 -129.073148) (xy 223.562672 -129.073148)
			(xy 223.562672 -128.209548) (xy 223.563115 -128.182788) (xy 223.570596 -128.129795) (xy 223.585403 -128.078365)
			(xy 223.607247 -128.029506) (xy 223.621092 -128.006602) (xy 223.636032 -127.983032) (xy 223.671662 -127.940084)
			(xy 223.713174 -127.902792) (xy 223.759681 -127.871951) (xy 223.810187 -127.848221) (xy 223.863614 -127.832109)
			(xy 223.918819 -127.823961) (xy 223.94672 -127.823468) (xy 223.973934 -127.823967) (xy 224.027808 -127.831715)
			(xy 224.080031 -127.84705) (xy 224.12954 -127.869661) (xy 224.175327 -127.899088) (xy 224.216462 -127.93473)
			(xy 224.252105 -127.975863) (xy 224.281533 -128.02165) (xy 224.304145 -128.071158) (xy 224.319483 -128.123381)
			(xy 224.327232 -128.177254) (xy 224.32772 -128.204468) (xy 224.32772 -128.204722) (xy 224.325942 -128.241552)
			(xy 224.325688 -128.243838) (xy 224.325688 -129.019808) (xy 240.086896 -129.019808) (xy 240.086896 -128.156208)
			(xy 240.087382 -128.128939) (xy 240.095144 -128.074955) (xy 240.110509 -128.022625) (xy 240.133166 -127.973015)
			(xy 240.162652 -127.927134) (xy 240.198367 -127.885917) (xy 240.239584 -127.850202) (xy 240.285465 -127.820716)
			(xy 240.335075 -127.798059) (xy 240.387405 -127.782694) (xy 240.441389 -127.774932) (xy 240.495927 -127.774932)
			(xy 240.549911 -127.782694) (xy 240.602241 -127.798059) (xy 240.651851 -127.820716) (xy 240.697732 -127.850202)
			(xy 240.738949 -127.885917) (xy 240.774664 -127.927134) (xy 240.80415 -127.973015) (xy 240.826807 -128.022625)
			(xy 240.842172 -128.074955) (xy 240.849934 -128.128939) (xy 240.85042 -128.156208) (xy 240.85042 -129.019808)
			(xy 240.849934 -129.047077) (xy 240.842172 -129.101061) (xy 240.826807 -129.153391) (xy 240.80415 -129.203001)
			(xy 240.774664 -129.248882) (xy 240.738949 -129.290099) (xy 240.697732 -129.325814) (xy 240.651851 -129.3553)
			(xy 240.602241 -129.377957) (xy 240.549911 -129.393322) (xy 240.495927 -129.401084) (xy 240.441389 -129.401084)
			(xy 240.387405 -129.393322) (xy 240.335075 -129.377957) (xy 240.285465 -129.3553) (xy 240.239584 -129.325814)
			(xy 240.198367 -129.290099) (xy 240.162652 -129.248882) (xy 240.133166 -129.203001) (xy 240.110509 -129.153391)
			(xy 240.095144 -129.101061) (xy 240.087382 -129.047077) (xy 240.086896 -129.019808) (xy 224.325688 -129.019808)
			(xy 224.325942 -129.022602) (xy 224.327226 -129.033861) (xy 224.328622 -129.056482) (xy 224.328736 -129.067814)
			(xy 224.328736 -129.068068) (xy 224.328226 -129.095352) (xy 224.320425 -129.14936) (xy 224.305035 -129.201713)
			(xy 224.282367 -129.251351) (xy 224.26803 -129.27457) (xy 224.253042 -129.297814) (xy 224.217376 -129.340083)
			(xy 224.175977 -129.376756) (xy 224.129714 -129.407061) (xy 224.079557 -129.430365) (xy 224.026559 -129.446176)
			(xy 223.971833 -129.454165) (xy 223.94418 -129.454656) (xy 223.91693 -129.454141) (xy 223.862986 -129.446383)
			(xy 223.810695 -129.431028) (xy 223.761121 -129.408388) (xy 223.715273 -129.378924) (xy 223.674084 -129.343236)
			(xy 223.638393 -129.30205) (xy 223.608926 -129.256204) (xy 223.586282 -129.206631) (xy 223.570923 -129.154341)
			(xy 223.563161 -129.100398) (xy 223.562672 -129.073148) (xy 2.509012 -129.073148) (xy 2.509012 -131.09702)
			(xy 228.682804 -131.09702) (xy 228.682804 -130.23342) (xy 228.68329 -130.206151) (xy 228.691052 -130.152167)
			(xy 228.706417 -130.099837) (xy 228.729074 -130.050227) (xy 228.75856 -130.004346) (xy 228.794275 -129.963129)
			(xy 228.835492 -129.927414) (xy 228.881373 -129.897928) (xy 228.930983 -129.875271) (xy 228.983313 -129.859906)
			(xy 229.037297 -129.852144) (xy 229.091835 -129.852144) (xy 229.145819 -129.859906) (xy 229.198149 -129.875271)
			(xy 229.247759 -129.897928) (xy 229.29364 -129.927414) (xy 229.334857 -129.963129) (xy 229.370572 -130.004346)
			(xy 229.400058 -130.050227) (xy 229.422715 -130.099837) (xy 229.43808 -130.152167) (xy 229.445842 -130.206151)
			(xy 229.446328 -130.23342) (xy 229.446328 -130.721608) (xy 242.041172 -130.721608) (xy 242.041172 -129.858008)
			(xy 242.041658 -129.830757) (xy 242.049414 -129.776809) (xy 242.064769 -129.724514) (xy 242.087411 -129.674937)
			(xy 242.116877 -129.629087) (xy 242.152568 -129.587896) (xy 242.193759 -129.552205) (xy 242.239609 -129.522739)
			(xy 242.289186 -129.500097) (xy 242.341481 -129.484742) (xy 242.395429 -129.476986) (xy 242.449931 -129.476986)
			(xy 242.503879 -129.484742) (xy 242.556174 -129.500097) (xy 242.605751 -129.522739) (xy 242.651601 -129.552205)
			(xy 242.692792 -129.587896) (xy 242.728483 -129.629087) (xy 242.757949 -129.674937) (xy 242.780591 -129.724514)
			(xy 242.795946 -129.776809) (xy 242.803702 -129.830757) (xy 242.804188 -129.858008) (xy 242.804188 -130.721608)
			(xy 242.803702 -130.748859) (xy 242.795946 -130.802807) (xy 242.780591 -130.855102) (xy 242.757949 -130.904679)
			(xy 242.728483 -130.950529) (xy 242.692792 -130.99172) (xy 242.651601 -131.027411) (xy 242.605751 -131.056877)
			(xy 242.556174 -131.079519) (xy 242.503879 -131.094874) (xy 242.449931 -131.10263) (xy 242.395429 -131.10263)
			(xy 242.341481 -131.094874) (xy 242.289186 -131.079519) (xy 242.239609 -131.056877) (xy 242.193759 -131.027411)
			(xy 242.152568 -130.99172) (xy 242.116877 -130.950529) (xy 242.087411 -130.904679) (xy 242.064769 -130.855102)
			(xy 242.049414 -130.802807) (xy 242.041658 -130.748859) (xy 242.041172 -130.721608) (xy 229.446328 -130.721608)
			(xy 229.446328 -131.09702) (xy 229.445842 -131.124289) (xy 229.43808 -131.178273) (xy 229.422715 -131.230603)
			(xy 229.400058 -131.280213) (xy 229.370572 -131.326094) (xy 229.334857 -131.367311) (xy 229.29364 -131.403026)
			(xy 229.247759 -131.432512) (xy 229.198149 -131.455169) (xy 229.145819 -131.470534) (xy 229.091835 -131.478296)
			(xy 229.037297 -131.478296) (xy 228.983313 -131.470534) (xy 228.930983 -131.455169) (xy 228.881373 -131.432512)
			(xy 228.835492 -131.403026) (xy 228.794275 -131.367311) (xy 228.75856 -131.326094) (xy 228.729074 -131.280213)
			(xy 228.706417 -131.230603) (xy 228.691052 -131.178273) (xy 228.68329 -131.124289) (xy 228.682804 -131.09702)
			(xy 2.509012 -131.09702) (xy 2.509012 -132.529347) (xy 231.621126 -132.529347) (xy 231.621126 -132.474853)
			(xy 231.628881 -132.420915) (xy 231.644233 -132.368628) (xy 231.666869 -132.319059) (xy 231.69633 -132.273216)
			(xy 231.732014 -132.232031) (xy 231.773196 -132.196344) (xy 231.819038 -132.166881) (xy 231.868606 -132.144241)
			(xy 231.920891 -132.128886) (xy 231.974829 -132.121128) (xy 232.002076 -132.12064) (xy 232.865676 -132.12064)
			(xy 232.892933 -132.121005) (xy 232.946894 -132.128761) (xy 232.999201 -132.144116) (xy 233.048791 -132.16676)
			(xy 233.094653 -132.196231) (xy 233.135853 -132.23193) (xy 233.171554 -132.273128) (xy 233.201028 -132.318988)
			(xy 233.223675 -132.368576) (xy 233.239034 -132.420883) (xy 233.246793 -132.474843) (xy 233.246793 -132.529357)
			(xy 233.239034 -132.583317) (xy 233.223675 -132.635624) (xy 233.201028 -132.685212) (xy 233.171554 -132.731072)
			(xy 233.135853 -132.77227) (xy 233.094653 -132.807968) (xy 233.048791 -132.83744) (xy 232.999201 -132.860084)
			(xy 232.946894 -132.875439) (xy 232.892933 -132.883195) (xy 232.865676 -132.883656) (xy 232.002076 -132.883656)
			(xy 231.974829 -132.883072) (xy 231.920891 -132.875314) (xy 231.868606 -132.859959) (xy 231.819038 -132.837319)
			(xy 231.773196 -132.807856) (xy 231.732014 -132.772169) (xy 231.69633 -132.730984) (xy 231.666869 -132.685141)
			(xy 231.644233 -132.635572) (xy 231.628881 -132.583285) (xy 231.621126 -132.529347) (xy 2.509012 -132.529347)
			(xy 2.509012 -135.31065) (xy 225.204003 -135.31065) (xy 225.204003 -135.25615) (xy 225.21176 -135.202204)
			(xy 225.227115 -135.149911) (xy 225.249756 -135.100336) (xy 225.279222 -135.054487) (xy 225.314914 -135.013299)
			(xy 225.356103 -134.97761) (xy 225.401953 -134.948146) (xy 225.45153 -134.925508) (xy 225.503823 -134.910156)
			(xy 225.55777 -134.902402) (xy 225.58502 -134.90194) (xy 226.44862 -134.90194) (xy 226.475874 -134.902331)
			(xy 226.529826 -134.910091) (xy 226.582125 -134.92545) (xy 226.631706 -134.948095) (xy 226.67756 -134.977566)
			(xy 226.718753 -135.013262) (xy 226.754446 -135.054456) (xy 226.755856 -135.05665) (xy 228.531403 -135.05665)
			(xy 228.531403 -135.00215) (xy 228.53916 -134.948204) (xy 228.554515 -134.895911) (xy 228.577156 -134.846336)
			(xy 228.606622 -134.800487) (xy 228.642314 -134.759299) (xy 228.683503 -134.72361) (xy 228.729353 -134.694146)
			(xy 228.77893 -134.671508) (xy 228.831223 -134.656156) (xy 228.88517 -134.648402) (xy 228.91242 -134.64794)
			(xy 229.77602 -134.64794) (xy 229.803274 -134.648331) (xy 229.857226 -134.656091) (xy 229.909525 -134.67145)
			(xy 229.959106 -134.694095) (xy 230.00496 -134.723566) (xy 230.046153 -134.759262) (xy 230.081846 -134.800456)
			(xy 230.111315 -134.846312) (xy 230.133957 -134.895894) (xy 230.149313 -134.948193) (xy 230.15707 -135.002146)
			(xy 230.15707 -135.056654) (xy 230.149313 -135.110607) (xy 230.145996 -135.121904) (xy 234.029504 -135.121904)
			(xy 234.029504 -134.258304) (xy 234.02999 -134.231035) (xy 234.037752 -134.177051) (xy 234.053117 -134.124721)
			(xy 234.075774 -134.075111) (xy 234.10526 -134.02923) (xy 234.140975 -133.988013) (xy 234.182192 -133.952298)
			(xy 234.228073 -133.922812) (xy 234.277683 -133.900155) (xy 234.330013 -133.88479) (xy 234.383997 -133.877028)
			(xy 234.438535 -133.877028) (xy 234.492519 -133.88479) (xy 234.544849 -133.900155) (xy 234.594459 -133.922812)
			(xy 234.64034 -133.952298) (xy 234.681557 -133.988013) (xy 234.717272 -134.02923) (xy 234.746758 -134.075111)
			(xy 234.769415 -134.124721) (xy 234.78478 -134.177051) (xy 234.792542 -134.231035) (xy 234.793028 -134.258304)
			(xy 234.793028 -134.768971) (xy 236.02439 -134.768971) (xy 236.02439 -134.714429) (xy 236.032152 -134.660443)
			(xy 236.047518 -134.608111) (xy 236.070174 -134.558498) (xy 236.09966 -134.512615) (xy 236.135376 -134.471394)
			(xy 236.176594 -134.435676) (xy 236.222475 -134.406186) (xy 236.272087 -134.383527) (xy 236.324418 -134.368158)
			(xy 236.378403 -134.360392) (xy 236.405674 -134.359904) (xy 237.178342 -134.359904) (xy 237.205607 -134.360461)
			(xy 237.259581 -134.368227) (xy 237.311901 -134.383595) (xy 237.361502 -134.406251) (xy 237.407373 -134.435736)
			(xy 237.448582 -134.471448) (xy 237.48429 -134.512661) (xy 237.513769 -134.558535) (xy 237.53642 -134.608138)
			(xy 237.551782 -134.66046) (xy 237.559542 -134.714435) (xy 237.559542 -134.768965) (xy 237.551782 -134.82294)
			(xy 237.53642 -134.875262) (xy 237.513769 -134.924865) (xy 237.48429 -134.970739) (xy 237.448582 -135.011952)
			(xy 237.407373 -135.047664) (xy 237.361502 -135.077149) (xy 237.311901 -135.099805) (xy 237.259581 -135.115173)
			(xy 237.205607 -135.122939) (xy 237.178342 -135.123428) (xy 236.405674 -135.123428) (xy 236.378403 -135.123008)
			(xy 236.324418 -135.115242) (xy 236.272087 -135.099873) (xy 236.222475 -135.077214) (xy 236.176594 -135.047724)
			(xy 236.135376 -135.012006) (xy 236.09966 -134.970785) (xy 236.070174 -134.924902) (xy 236.047518 -134.875289)
			(xy 236.032152 -134.822957) (xy 236.02439 -134.768971) (xy 234.793028 -134.768971) (xy 234.793028 -135.121904)
			(xy 234.792542 -135.149173) (xy 234.786383 -135.192008) (xy 238.645192 -135.192008) (xy 238.645192 -134.328408)
			(xy 238.645678 -134.301157) (xy 238.653434 -134.247209) (xy 238.668789 -134.194914) (xy 238.691431 -134.145337)
			(xy 238.720897 -134.099487) (xy 238.756588 -134.058296) (xy 238.797779 -134.022605) (xy 238.843629 -133.993139)
			(xy 238.893206 -133.970497) (xy 238.945501 -133.955142) (xy 238.999449 -133.947386) (xy 239.053951 -133.947386)
			(xy 239.107899 -133.955142) (xy 239.160194 -133.970497) (xy 239.209771 -133.993139) (xy 239.255621 -134.022605)
			(xy 239.271831 -134.036651) (xy 242.034062 -134.036651) (xy 242.034062 -133.982149) (xy 242.041817 -133.928203)
			(xy 242.057171 -133.875909) (xy 242.07981 -133.826333) (xy 242.109274 -133.780482) (xy 242.144963 -133.739291)
			(xy 242.18615 -133.703598) (xy 242.231997 -133.67413) (xy 242.281572 -133.651485) (xy 242.333864 -133.636126)
			(xy 242.387809 -133.628365) (xy 242.41506 -133.627876) (xy 243.27866 -133.627876) (xy 243.305914 -133.628369)
			(xy 243.359867 -133.636121) (xy 243.412167 -133.651473) (xy 243.46175 -133.674112) (xy 243.507606 -133.703577)
			(xy 243.548802 -133.73927) (xy 243.584499 -133.780462) (xy 243.613969 -133.826315) (xy 243.636613 -133.875895)
			(xy 243.651971 -133.928194) (xy 243.659729 -133.982146) (xy 243.659729 -134.036654) (xy 243.651971 -134.090606)
			(xy 243.636613 -134.142905) (xy 243.613969 -134.192485) (xy 243.584499 -134.238338) (xy 243.548802 -134.27953)
			(xy 243.507606 -134.315223) (xy 243.46175 -134.344688) (xy 243.412167 -134.367327) (xy 243.359867 -134.382679)
			(xy 243.305914 -134.390431) (xy 243.27866 -134.390892) (xy 242.41506 -134.390892) (xy 242.387809 -134.390435)
			(xy 242.333864 -134.382674) (xy 242.281572 -134.367315) (xy 242.231997 -134.34467) (xy 242.18615 -134.315202)
			(xy 242.144963 -134.279509) (xy 242.109274 -134.238318) (xy 242.07981 -134.192467) (xy 242.057171 -134.142891)
			(xy 242.041817 -134.090597) (xy 242.034062 -134.036651) (xy 239.271831 -134.036651) (xy 239.296812 -134.058296)
			(xy 239.332503 -134.099487) (xy 239.361969 -134.145337) (xy 239.384611 -134.194914) (xy 239.399966 -134.247209)
			(xy 239.407722 -134.301157) (xy 239.408208 -134.328408) (xy 239.408208 -135.192008) (xy 239.407722 -135.219259)
			(xy 239.399966 -135.273207) (xy 239.384611 -135.325502) (xy 239.361969 -135.375079) (xy 239.332503 -135.420929)
			(xy 239.296812 -135.46212) (xy 239.255621 -135.497811) (xy 239.250425 -135.50115) (xy 244.457203 -135.50115)
			(xy 244.457203 -135.44665) (xy 244.46496 -135.392704) (xy 244.480315 -135.340411) (xy 244.502956 -135.290836)
			(xy 244.532422 -135.244987) (xy 244.568114 -135.203799) (xy 244.609303 -135.16811) (xy 244.655153 -135.138646)
			(xy 244.70473 -135.116008) (xy 244.757023 -135.100656) (xy 244.81097 -135.092902) (xy 244.83822 -135.09244)
			(xy 245.70182 -135.09244) (xy 245.729074 -135.092831) (xy 245.783026 -135.100591) (xy 245.835325 -135.11595)
			(xy 245.884906 -135.138595) (xy 245.93076 -135.168066) (xy 245.971953 -135.203762) (xy 246.007646 -135.244956)
			(xy 246.037115 -135.290812) (xy 246.059757 -135.340394) (xy 246.075113 -135.392693) (xy 246.08287 -135.446646)
			(xy 246.08287 -135.501154) (xy 246.075113 -135.555107) (xy 246.059757 -135.607406) (xy 246.037115 -135.656988)
			(xy 246.007646 -135.702844) (xy 245.971953 -135.744038) (xy 245.93076 -135.779734) (xy 245.884906 -135.809205)
			(xy 245.835325 -135.83185) (xy 245.783026 -135.847209) (xy 245.729074 -135.854969) (xy 245.70182 -135.855456)
			(xy 244.83822 -135.855456) (xy 244.81097 -135.854898) (xy 244.757023 -135.847144) (xy 244.70473 -135.831792)
			(xy 244.655153 -135.809154) (xy 244.609303 -135.77969) (xy 244.568114 -135.744001) (xy 244.532422 -135.702813)
			(xy 244.502956 -135.656964) (xy 244.480315 -135.607389) (xy 244.46496 -135.555096) (xy 244.457203 -135.50115)
			(xy 239.250425 -135.50115) (xy 239.209771 -135.527277) (xy 239.160194 -135.549919) (xy 239.107899 -135.565274)
			(xy 239.053951 -135.57303) (xy 238.999449 -135.57303) (xy 238.945501 -135.565274) (xy 238.893206 -135.549919)
			(xy 238.843629 -135.527277) (xy 238.797779 -135.497811) (xy 238.756588 -135.46212) (xy 238.720897 -135.420929)
			(xy 238.691431 -135.375079) (xy 238.668789 -135.325502) (xy 238.653434 -135.273207) (xy 238.645678 -135.219259)
			(xy 238.645192 -135.192008) (xy 234.786383 -135.192008) (xy 234.78478 -135.203157) (xy 234.769415 -135.255487)
			(xy 234.746758 -135.305097) (xy 234.717272 -135.350978) (xy 234.681557 -135.392195) (xy 234.64034 -135.42791)
			(xy 234.594459 -135.457396) (xy 234.544849 -135.480053) (xy 234.492519 -135.495418) (xy 234.438535 -135.50318)
			(xy 234.383997 -135.50318) (xy 234.330013 -135.495418) (xy 234.277683 -135.480053) (xy 234.228073 -135.457396)
			(xy 234.182192 -135.42791) (xy 234.140975 -135.392195) (xy 234.10526 -135.350978) (xy 234.075774 -135.305097)
			(xy 234.053117 -135.255487) (xy 234.037752 -135.203157) (xy 234.02999 -135.149173) (xy 234.029504 -135.121904)
			(xy 230.145996 -135.121904) (xy 230.133957 -135.162906) (xy 230.111315 -135.212488) (xy 230.081846 -135.258344)
			(xy 230.046153 -135.299538) (xy 230.00496 -135.335234) (xy 229.959106 -135.364705) (xy 229.909525 -135.38735)
			(xy 229.857226 -135.402709) (xy 229.803274 -135.410469) (xy 229.77602 -135.410956) (xy 228.91242 -135.410956)
			(xy 228.88517 -135.410398) (xy 228.831223 -135.402644) (xy 228.77893 -135.387292) (xy 228.729353 -135.364654)
			(xy 228.683503 -135.33519) (xy 228.642314 -135.299501) (xy 228.606622 -135.258313) (xy 228.577156 -135.212464)
			(xy 228.554515 -135.162889) (xy 228.53916 -135.110596) (xy 228.531403 -135.05665) (xy 226.755856 -135.05665)
			(xy 226.783915 -135.100312) (xy 226.806557 -135.149894) (xy 226.821913 -135.202193) (xy 226.82967 -135.256146)
			(xy 226.82967 -135.310654) (xy 226.821913 -135.364607) (xy 226.806557 -135.416906) (xy 226.783915 -135.466488)
			(xy 226.754446 -135.512344) (xy 226.718753 -135.553538) (xy 226.67756 -135.589234) (xy 226.631706 -135.618705)
			(xy 226.582125 -135.64135) (xy 226.529826 -135.656709) (xy 226.475874 -135.664469) (xy 226.44862 -135.664956)
			(xy 225.58502 -135.664956) (xy 225.55777 -135.664398) (xy 225.503823 -135.656644) (xy 225.45153 -135.641292)
			(xy 225.401953 -135.618654) (xy 225.356103 -135.58919) (xy 225.314914 -135.553501) (xy 225.279222 -135.512313)
			(xy 225.249756 -135.466464) (xy 225.227115 -135.416889) (xy 225.21176 -135.364596) (xy 225.204003 -135.31065)
			(xy 2.509012 -135.31065) (xy 2.509012 -137.199664) (xy 337.46447 -137.199664) (xy 337.46447 -137.145136)
			(xy 337.47223 -137.091163) (xy 337.487591 -137.038843) (xy 337.510241 -136.989242) (xy 337.539719 -136.943369)
			(xy 337.575425 -136.902158) (xy 337.616632 -136.866447) (xy 337.662502 -136.836963) (xy 337.7121 -136.814307)
			(xy 337.764418 -136.79894) (xy 337.81839 -136.791173) (xy 337.845654 -136.790684) (xy 338.618322 -136.790684)
			(xy 338.645594 -136.79108) (xy 338.699581 -136.798845) (xy 338.751915 -136.814214) (xy 338.801528 -136.836874)
			(xy 338.847412 -136.866364) (xy 338.888632 -136.902084) (xy 338.924349 -136.943306) (xy 338.953836 -136.989191)
			(xy 338.976493 -137.038806) (xy 338.991859 -137.09114) (xy 338.999622 -137.145128) (xy 338.999622 -137.199672)
			(xy 338.991859 -137.25366) (xy 338.976493 -137.305994) (xy 338.953836 -137.355609) (xy 338.924349 -137.401494)
			(xy 338.888632 -137.442716) (xy 338.847412 -137.478436) (xy 338.801528 -137.507926) (xy 338.751915 -137.530586)
			(xy 338.699581 -137.545955) (xy 338.645594 -137.55372) (xy 338.618322 -137.554208) (xy 337.845654 -137.554208)
			(xy 337.81839 -137.553627) (xy 337.764418 -137.54586) (xy 337.7121 -137.530493) (xy 337.662502 -137.507837)
			(xy 337.616632 -137.478353) (xy 337.575425 -137.442642) (xy 337.539719 -137.401431) (xy 337.510241 -137.355558)
			(xy 337.487591 -137.305957) (xy 337.47223 -137.253637) (xy 337.46447 -137.199664) (xy 2.509012 -137.199664)
			(xy 2.509012 -137.622788) (xy 340.085172 -137.622788) (xy 340.085172 -136.759188) (xy 340.085658 -136.731937)
			(xy 340.093414 -136.677989) (xy 340.108769 -136.625694) (xy 340.131411 -136.576117) (xy 340.160877 -136.530267)
			(xy 340.196568 -136.489076) (xy 340.237759 -136.453385) (xy 340.283609 -136.423919) (xy 340.333186 -136.401277)
			(xy 340.385481 -136.385922) (xy 340.439429 -136.378166) (xy 340.493931 -136.378166) (xy 340.547879 -136.385922)
			(xy 340.600174 -136.401277) (xy 340.649751 -136.423919) (xy 340.695601 -136.453385) (xy 340.736792 -136.489076)
			(xy 340.772483 -136.530267) (xy 340.801949 -136.576117) (xy 340.824591 -136.625694) (xy 340.839946 -136.677989)
			(xy 340.847702 -136.731937) (xy 340.848188 -136.759188) (xy 340.848188 -137.622788) (xy 340.847702 -137.650039)
			(xy 340.839946 -137.703987) (xy 340.824591 -137.756282) (xy 340.801949 -137.805859) (xy 340.772483 -137.851709)
			(xy 340.736792 -137.8929) (xy 340.695601 -137.928591) (xy 340.649751 -137.958057) (xy 340.600174 -137.980699)
			(xy 340.547879 -137.996054) (xy 340.493931 -138.00381) (xy 340.439429 -138.00381) (xy 340.385481 -137.996054)
			(xy 340.333186 -137.980699) (xy 340.283609 -137.958057) (xy 340.237759 -137.928591) (xy 340.196568 -137.8929)
			(xy 340.160877 -137.851709) (xy 340.131411 -137.805859) (xy 340.108769 -137.756282) (xy 340.093414 -137.703987)
			(xy 340.085658 -137.650039) (xy 340.085172 -137.622788) (xy 2.509012 -137.622788) (xy 2.509012 -153.766012)
			(xy 24.445731 -153.766012) (xy 24.449724 -153.556271) (xy 24.4617 -153.346834) (xy 24.481641 -153.138005)
			(xy 24.509518 -152.930086) (xy 24.54529 -152.723379) (xy 24.588905 -152.518184) (xy 24.640301 -152.314799)
			(xy 24.699403 -152.113517) (xy 24.766125 -151.914631) (xy 24.84037 -151.71843) (xy 24.92203 -151.525198)
			(xy 25.010988 -151.335214) (xy 25.107115 -151.148755) (xy 25.21027 -150.966091) (xy 25.320305 -150.787486)
			(xy 25.437059 -150.6132) (xy 25.560364 -150.443485) (xy 25.690041 -150.278587) (xy 25.825902 -150.118746)
			(xy 25.967749 -149.964193) (xy 26.115378 -149.815153) (xy 26.268573 -149.67184) (xy 26.427114 -149.534464)
			(xy 26.590769 -149.403223) (xy 26.759303 -149.278308) (xy 26.932469 -149.1599) (xy 27.110019 -149.04817)
			(xy 27.291693 -148.94328) (xy 27.477228 -148.845383) (xy 27.666356 -148.754621) (xy 27.858803 -148.671124)
			(xy 28.054288 -148.595014) (xy 28.25253 -148.526402) (xy 28.45324 -148.465387) (xy 28.656127 -148.412058)
			(xy 28.860897 -148.366491) (xy 29.067254 -148.328752) (xy 29.274898 -148.298898) (xy 29.483528 -148.27697)
			(xy 29.692841 -148.263001) (xy 29.902535 -148.25701) (xy 30.112304 -148.259007) (xy 30.321846 -148.268989)
			(xy 30.530856 -148.286941) (xy 30.73903 -148.312837) (xy 30.946068 -148.346639) (xy 31.151669 -148.388299)
			(xy 31.355535 -148.437757) (xy 31.55737 -148.49494) (xy 31.756882 -148.559765) (xy 31.953781 -148.632139)
			(xy 32.147782 -148.711956) (xy 32.338604 -148.799102) (xy 32.52597 -148.893449) (xy 32.709608 -148.99486)
			(xy 32.889252 -149.10319) (xy 33.064642 -149.21828) (xy 33.235523 -149.339964) (xy 33.401647 -149.468065)
			(xy 33.562774 -149.602398) (xy 33.718671 -149.742767) (xy 33.86911 -149.88897) (xy 34.013874 -150.040794)
			(xy 34.152753 -150.19802) (xy 34.285546 -150.360419) (xy 34.41206 -150.527755) (xy 34.532112 -150.699787)
			(xy 34.645527 -150.876264) (xy 34.752141 -151.056932) (xy 34.8518 -151.241527) (xy 34.944359 -151.429782)
			(xy 35.029684 -151.621425) (xy 35.107651 -151.816177) (xy 35.178147 -152.013757) (xy 35.24107 -152.213876)
			(xy 35.296329 -152.416247) (xy 35.343843 -152.620574) (xy 35.383544 -152.826562) (xy 35.415374 -153.033913)
			(xy 35.439287 -153.242324) (xy 35.455248 -153.451495) (xy 35.463235 -153.661122) (xy 35.463734 -153.766012)
			(xy 35.463235 -153.870902) (xy 35.455248 -154.080529) (xy 35.44312 -154.239468) (xy 186.742832 -154.239468)
			(xy 186.742832 -153.375868) (xy 186.743318 -153.348617) (xy 186.751074 -153.294669) (xy 186.766429 -153.242374)
			(xy 186.789071 -153.192797) (xy 186.818537 -153.146947) (xy 186.854228 -153.105756) (xy 186.895419 -153.070065)
			(xy 186.941269 -153.040599) (xy 186.990846 -153.017957) (xy 187.043141 -153.002602) (xy 187.097089 -152.994846)
			(xy 187.151591 -152.994846) (xy 187.205539 -153.002602) (xy 187.257834 -153.017957) (xy 187.307411 -153.040599)
			(xy 187.353261 -153.070065) (xy 187.394452 -153.105756) (xy 187.430143 -153.146947) (xy 187.459609 -153.192797)
			(xy 187.482251 -153.242374) (xy 187.497606 -153.294669) (xy 187.505362 -153.348617) (xy 187.505848 -153.375868)
			(xy 187.505848 -153.774902) (xy 188.445657 -153.774902) (xy 188.44965 -153.565161) (xy 188.461626 -153.355724)
			(xy 188.481567 -153.146895) (xy 188.509444 -152.938976) (xy 188.545216 -152.732269) (xy 188.588831 -152.527074)
			(xy 188.640227 -152.323689) (xy 188.699329 -152.122407) (xy 188.766051 -151.923521) (xy 188.840296 -151.72732)
			(xy 188.921956 -151.534088) (xy 189.010914 -151.344104) (xy 189.107041 -151.157645) (xy 189.210196 -150.974981)
			(xy 189.320231 -150.796376) (xy 189.436985 -150.62209) (xy 189.56029 -150.452375) (xy 189.689967 -150.287477)
			(xy 189.825828 -150.127636) (xy 189.967675 -149.973083) (xy 190.115304 -149.824043) (xy 190.268499 -149.68073)
			(xy 190.42704 -149.543354) (xy 190.590695 -149.412113) (xy 190.759229 -149.287198) (xy 190.932395 -149.16879)
			(xy 191.109945 -149.05706) (xy 191.291619 -148.95217) (xy 191.477154 -148.854273) (xy 191.666282 -148.763511)
			(xy 191.858729 -148.680014) (xy 192.054214 -148.603904) (xy 192.252456 -148.535292) (xy 192.453166 -148.474277)
			(xy 192.656053 -148.420948) (xy 192.860823 -148.375381) (xy 193.06718 -148.337642) (xy 193.274824 -148.307788)
			(xy 193.483454 -148.28586) (xy 193.692767 -148.271891) (xy 193.902461 -148.2659) (xy 194.11223 -148.267897)
			(xy 194.321772 -148.277879) (xy 194.530782 -148.295831) (xy 194.738956 -148.321727) (xy 194.945994 -148.355529)
			(xy 195.151595 -148.397189) (xy 195.355461 -148.446647) (xy 195.557296 -148.50383) (xy 195.756808 -148.568655)
			(xy 195.953707 -148.641029) (xy 196.147708 -148.720846) (xy 196.33853 -148.807992) (xy 196.525896 -148.902339)
			(xy 196.709534 -149.00375) (xy 196.889178 -149.11208) (xy 197.064568 -149.22717) (xy 197.235449 -149.348854)
			(xy 197.401573 -149.476955) (xy 197.5627 -149.611288) (xy 197.718597 -149.751657) (xy 197.869036 -149.89786)
			(xy 198.0138 -150.049684) (xy 198.152679 -150.20691) (xy 198.285472 -150.369309) (xy 198.411986 -150.536645)
			(xy 198.532038 -150.708677) (xy 198.645453 -150.885154) (xy 198.752067 -151.065822) (xy 198.851726 -151.250417)
			(xy 198.944285 -151.438672) (xy 199.02961 -151.630315) (xy 199.107577 -151.825067) (xy 199.178073 -152.022647)
			(xy 199.240996 -152.222766) (xy 199.296255 -152.425137) (xy 199.343769 -152.629464) (xy 199.38347 -152.835452)
			(xy 199.4153 -153.042803) (xy 199.439213 -153.251214) (xy 199.455174 -153.460385) (xy 199.463161 -153.670012)
			(xy 199.463618 -153.766012) (xy 272.385799 -153.766012) (xy 272.389792 -153.556271) (xy 272.401768 -153.346834)
			(xy 272.421709 -153.138005) (xy 272.449586 -152.930086) (xy 272.485358 -152.723379) (xy 272.528973 -152.518184)
			(xy 272.580369 -152.314799) (xy 272.639471 -152.113517) (xy 272.706193 -151.914631) (xy 272.780438 -151.71843)
			(xy 272.862098 -151.525198) (xy 272.951056 -151.335214) (xy 273.047183 -151.148755) (xy 273.150338 -150.966091)
			(xy 273.260373 -150.787486) (xy 273.377127 -150.6132) (xy 273.500432 -150.443485) (xy 273.630109 -150.278587)
			(xy 273.76597 -150.118746) (xy 273.907817 -149.964193) (xy 274.055446 -149.815153) (xy 274.208641 -149.67184)
			(xy 274.367182 -149.534464) (xy 274.530837 -149.403223) (xy 274.699371 -149.278308) (xy 274.872537 -149.1599)
			(xy 275.050087 -149.04817) (xy 275.231761 -148.94328) (xy 275.417296 -148.845383) (xy 275.606424 -148.754621)
			(xy 275.798871 -148.671124) (xy 275.994356 -148.595014) (xy 276.192598 -148.526402) (xy 276.393308 -148.465387)
			(xy 276.596195 -148.412058) (xy 276.800965 -148.366491) (xy 277.007322 -148.328752) (xy 277.214966 -148.298898)
			(xy 277.423596 -148.27697) (xy 277.632909 -148.263001) (xy 277.842603 -148.25701) (xy 278.052372 -148.259007)
			(xy 278.261914 -148.268989) (xy 278.470924 -148.286941) (xy 278.679098 -148.312837) (xy 278.886136 -148.346639)
			(xy 279.091737 -148.388299) (xy 279.295603 -148.437757) (xy 279.497438 -148.49494) (xy 279.69695 -148.559765)
			(xy 279.893849 -148.632139) (xy 280.08785 -148.711956) (xy 280.278672 -148.799102) (xy 280.466038 -148.893449)
			(xy 280.649676 -148.99486) (xy 280.82932 -149.10319) (xy 281.00471 -149.21828) (xy 281.175591 -149.339964)
			(xy 281.341715 -149.468065) (xy 281.502842 -149.602398) (xy 281.658739 -149.742767) (xy 281.809178 -149.88897)
			(xy 281.953942 -150.040794) (xy 282.092821 -150.19802) (xy 282.225614 -150.360419) (xy 282.352128 -150.527755)
			(xy 282.47218 -150.699787) (xy 282.585595 -150.876264) (xy 282.692209 -151.056932) (xy 282.791868 -151.241527)
			(xy 282.884427 -151.429782) (xy 282.969752 -151.621425) (xy 283.047719 -151.816177) (xy 283.118215 -152.013757)
			(xy 283.181138 -152.213876) (xy 283.236397 -152.416247) (xy 283.283911 -152.620574) (xy 283.323612 -152.826562)
			(xy 283.355442 -153.033913) (xy 283.379355 -153.242324) (xy 283.395316 -153.451495) (xy 283.403303 -153.661122)
			(xy 283.403802 -153.766012) (xy 283.40376 -153.774902) (xy 436.385725 -153.774902) (xy 436.389718 -153.565161)
			(xy 436.401694 -153.355724) (xy 436.421635 -153.146895) (xy 436.449512 -152.938976) (xy 436.485284 -152.732269)
			(xy 436.528899 -152.527074) (xy 436.580295 -152.323689) (xy 436.639397 -152.122407) (xy 436.706119 -151.923521)
			(xy 436.780364 -151.72732) (xy 436.862024 -151.534088) (xy 436.950982 -151.344104) (xy 437.047109 -151.157645)
			(xy 437.150264 -150.974981) (xy 437.260299 -150.796376) (xy 437.377053 -150.62209) (xy 437.500358 -150.452375)
			(xy 437.630035 -150.287477) (xy 437.765896 -150.127636) (xy 437.907743 -149.973083) (xy 438.055372 -149.824043)
			(xy 438.208567 -149.68073) (xy 438.367108 -149.543354) (xy 438.530763 -149.412113) (xy 438.699297 -149.287198)
			(xy 438.872463 -149.16879) (xy 439.050013 -149.05706) (xy 439.231687 -148.95217) (xy 439.417222 -148.854273)
			(xy 439.60635 -148.763511) (xy 439.798797 -148.680014) (xy 439.994282 -148.603904) (xy 440.192524 -148.535292)
			(xy 440.393234 -148.474277) (xy 440.596121 -148.420948) (xy 440.800891 -148.375381) (xy 441.007248 -148.337642)
			(xy 441.214892 -148.307788) (xy 441.423522 -148.28586) (xy 441.632835 -148.271891) (xy 441.842529 -148.2659)
			(xy 442.052298 -148.267897) (xy 442.26184 -148.277879) (xy 442.47085 -148.295831) (xy 442.679024 -148.321727)
			(xy 442.886062 -148.355529) (xy 443.091663 -148.397189) (xy 443.295529 -148.446647) (xy 443.497364 -148.50383)
			(xy 443.696876 -148.568655) (xy 443.893775 -148.641029) (xy 444.087776 -148.720846) (xy 444.278598 -148.807992)
			(xy 444.465964 -148.902339) (xy 444.649602 -149.00375) (xy 444.829246 -149.11208) (xy 445.004636 -149.22717)
			(xy 445.175517 -149.348854) (xy 445.341641 -149.476955) (xy 445.502768 -149.611288) (xy 445.658665 -149.751657)
			(xy 445.809104 -149.89786) (xy 445.953868 -150.049684) (xy 446.092747 -150.20691) (xy 446.22554 -150.369309)
			(xy 446.352054 -150.536645) (xy 446.472106 -150.708677) (xy 446.585521 -150.885154) (xy 446.692135 -151.065822)
			(xy 446.791794 -151.250417) (xy 446.884353 -151.438672) (xy 446.969678 -151.630315) (xy 447.047645 -151.825067)
			(xy 447.118141 -152.022647) (xy 447.181064 -152.222766) (xy 447.236323 -152.425137) (xy 447.283837 -152.629464)
			(xy 447.323538 -152.835452) (xy 447.355368 -153.042803) (xy 447.379281 -153.251214) (xy 447.395242 -153.460385)
			(xy 447.403229 -153.670012) (xy 447.403728 -153.774902) (xy 447.403229 -153.879792) (xy 447.395242 -154.089419)
			(xy 447.379281 -154.29859) (xy 447.355368 -154.507001) (xy 447.323538 -154.714352) (xy 447.283837 -154.92034)
			(xy 447.236323 -155.124667) (xy 447.181064 -155.327038) (xy 447.118141 -155.527157) (xy 447.047645 -155.724737)
			(xy 446.969678 -155.919489) (xy 446.884353 -156.111132) (xy 446.791794 -156.299387) (xy 446.692135 -156.483982)
			(xy 446.585521 -156.66465) (xy 446.472106 -156.841127) (xy 446.352054 -157.013159) (xy 446.22554 -157.180495)
			(xy 446.092747 -157.342894) (xy 445.953868 -157.50012) (xy 445.809104 -157.651944) (xy 445.658665 -157.798147)
			(xy 445.502768 -157.938516) (xy 445.341641 -158.072849) (xy 445.175517 -158.20095) (xy 445.004636 -158.322634)
			(xy 444.829246 -158.437724) (xy 444.649602 -158.546054) (xy 444.465964 -158.647465) (xy 444.278598 -158.741812)
			(xy 444.087776 -158.828958) (xy 443.893775 -158.908775) (xy 443.696876 -158.981149) (xy 443.497364 -159.045974)
			(xy 443.295529 -159.103157) (xy 443.091663 -159.152615) (xy 442.886062 -159.194275) (xy 442.679024 -159.228077)
			(xy 442.47085 -159.253973) (xy 442.26184 -159.271925) (xy 442.052298 -159.281907) (xy 441.842529 -159.283904)
			(xy 441.632835 -159.277913) (xy 441.423522 -159.263944) (xy 441.214892 -159.242016) (xy 441.007248 -159.212162)
			(xy 440.800891 -159.174423) (xy 440.596121 -159.128856) (xy 440.393234 -159.075527) (xy 440.192524 -159.014512)
			(xy 439.994282 -158.9459) (xy 439.798797 -158.86979) (xy 439.60635 -158.786293) (xy 439.417222 -158.695531)
			(xy 439.231687 -158.597634) (xy 439.050013 -158.492744) (xy 438.872463 -158.381014) (xy 438.699297 -158.262606)
			(xy 438.530763 -158.137691) (xy 438.367108 -158.00645) (xy 438.208567 -157.869074) (xy 438.055372 -157.725761)
			(xy 437.907743 -157.576721) (xy 437.765896 -157.422168) (xy 437.630035 -157.262327) (xy 437.500358 -157.097429)
			(xy 437.377053 -156.927714) (xy 437.260299 -156.753428) (xy 437.150264 -156.574823) (xy 437.047109 -156.392159)
			(xy 436.950982 -156.2057) (xy 436.862024 -156.015716) (xy 436.780364 -155.822484) (xy 436.706119 -155.626283)
			(xy 436.639397 -155.427397) (xy 436.580295 -155.226115) (xy 436.528899 -155.02273) (xy 436.485284 -154.817535)
			(xy 436.449512 -154.610828) (xy 436.421635 -154.402909) (xy 436.401694 -154.19408) (xy 436.389718 -153.984643)
			(xy 436.385725 -153.774902) (xy 283.40376 -153.774902) (xy 283.403303 -153.870902) (xy 283.395316 -154.080529)
			(xy 283.379355 -154.2897) (xy 283.355442 -154.498111) (xy 283.323612 -154.705462) (xy 283.283911 -154.91145)
			(xy 283.236397 -155.115777) (xy 283.181138 -155.318148) (xy 283.118215 -155.518267) (xy 283.047719 -155.715847)
			(xy 282.969752 -155.910599) (xy 282.884427 -156.102242) (xy 282.791868 -156.290497) (xy 282.692209 -156.475092)
			(xy 282.585595 -156.65576) (xy 282.47218 -156.832237) (xy 282.352128 -157.004269) (xy 282.225614 -157.171605)
			(xy 282.092821 -157.334004) (xy 281.953942 -157.49123) (xy 281.809178 -157.643054) (xy 281.658739 -157.789257)
			(xy 281.502842 -157.929626) (xy 281.341715 -158.063959) (xy 281.175591 -158.19206) (xy 281.00471 -158.313744)
			(xy 280.82932 -158.428834) (xy 280.649676 -158.537164) (xy 280.466038 -158.638575) (xy 280.278672 -158.732922)
			(xy 280.08785 -158.820068) (xy 279.893849 -158.899885) (xy 279.69695 -158.972259) (xy 279.497438 -159.037084)
			(xy 279.295603 -159.094267) (xy 279.091737 -159.143725) (xy 278.886136 -159.185385) (xy 278.679098 -159.219187)
			(xy 278.470924 -159.245083) (xy 278.261914 -159.263035) (xy 278.052372 -159.273017) (xy 277.842603 -159.275014)
			(xy 277.632909 -159.269023) (xy 277.423596 -159.255054) (xy 277.214966 -159.233126) (xy 277.007322 -159.203272)
			(xy 276.800965 -159.165533) (xy 276.596195 -159.119966) (xy 276.393308 -159.066637) (xy 276.192598 -159.005622)
			(xy 275.994356 -158.93701) (xy 275.798871 -158.8609) (xy 275.606424 -158.777403) (xy 275.417296 -158.686641)
			(xy 275.231761 -158.588744) (xy 275.050087 -158.483854) (xy 274.872537 -158.372124) (xy 274.699371 -158.253716)
			(xy 274.530837 -158.128801) (xy 274.367182 -157.99756) (xy 274.208641 -157.860184) (xy 274.055446 -157.716871)
			(xy 273.907817 -157.567831) (xy 273.76597 -157.413278) (xy 273.630109 -157.253437) (xy 273.500432 -157.088539)
			(xy 273.377127 -156.918824) (xy 273.260373 -156.744538) (xy 273.150338 -156.565933) (xy 273.047183 -156.383269)
			(xy 272.951056 -156.19681) (xy 272.862098 -156.006826) (xy 272.780438 -155.813594) (xy 272.706193 -155.617393)
			(xy 272.639471 -155.418507) (xy 272.580369 -155.217225) (xy 272.528973 -155.01384) (xy 272.485358 -154.808645)
			(xy 272.449586 -154.601938) (xy 272.421709 -154.394019) (xy 272.401768 -154.18519) (xy 272.389792 -153.975753)
			(xy 272.385799 -153.766012) (xy 199.463618 -153.766012) (xy 199.46366 -153.774902) (xy 199.463161 -153.879792)
			(xy 199.455174 -154.089419) (xy 199.439213 -154.29859) (xy 199.4153 -154.507001) (xy 199.38347 -154.714352)
			(xy 199.343769 -154.92034) (xy 199.296255 -155.124667) (xy 199.240996 -155.327038) (xy 199.178073 -155.527157)
			(xy 199.107577 -155.724737) (xy 199.02961 -155.919489) (xy 198.944285 -156.111132) (xy 198.851726 -156.299387)
			(xy 198.752067 -156.483982) (xy 198.645453 -156.66465) (xy 198.532038 -156.841127) (xy 198.411986 -157.013159)
			(xy 198.285472 -157.180495) (xy 198.152679 -157.342894) (xy 198.0138 -157.50012) (xy 197.869036 -157.651944)
			(xy 197.718597 -157.798147) (xy 197.5627 -157.938516) (xy 197.401573 -158.072849) (xy 197.235449 -158.20095)
			(xy 197.064568 -158.322634) (xy 196.889178 -158.437724) (xy 196.709534 -158.546054) (xy 196.525896 -158.647465)
			(xy 196.33853 -158.741812) (xy 196.147708 -158.828958) (xy 195.953707 -158.908775) (xy 195.756808 -158.981149)
			(xy 195.557296 -159.045974) (xy 195.355461 -159.103157) (xy 195.151595 -159.152615) (xy 194.945994 -159.194275)
			(xy 194.738956 -159.228077) (xy 194.530782 -159.253973) (xy 194.321772 -159.271925) (xy 194.11223 -159.281907)
			(xy 193.902461 -159.283904) (xy 193.692767 -159.277913) (xy 193.483454 -159.263944) (xy 193.274824 -159.242016)
			(xy 193.06718 -159.212162) (xy 192.860823 -159.174423) (xy 192.656053 -159.128856) (xy 192.453166 -159.075527)
			(xy 192.252456 -159.014512) (xy 192.054214 -158.9459) (xy 191.858729 -158.86979) (xy 191.666282 -158.786293)
			(xy 191.477154 -158.695531) (xy 191.291619 -158.597634) (xy 191.109945 -158.492744) (xy 190.932395 -158.381014)
			(xy 190.759229 -158.262606) (xy 190.590695 -158.137691) (xy 190.42704 -158.00645) (xy 190.268499 -157.869074)
			(xy 190.115304 -157.725761) (xy 189.967675 -157.576721) (xy 189.825828 -157.422168) (xy 189.689967 -157.262327)
			(xy 189.56029 -157.097429) (xy 189.436985 -156.927714) (xy 189.320231 -156.753428) (xy 189.210196 -156.574823)
			(xy 189.107041 -156.392159) (xy 189.010914 -156.2057) (xy 188.921956 -156.015716) (xy 188.840296 -155.822484)
			(xy 188.766051 -155.626283) (xy 188.699329 -155.427397) (xy 188.640227 -155.226115) (xy 188.588831 -155.02273)
			(xy 188.545216 -154.817535) (xy 188.509444 -154.610828) (xy 188.481567 -154.402909) (xy 188.461626 -154.19408)
			(xy 188.44965 -153.984643) (xy 188.445657 -153.774902) (xy 187.505848 -153.774902) (xy 187.505848 -154.239468)
			(xy 187.505362 -154.266719) (xy 187.497606 -154.320667) (xy 187.482251 -154.372962) (xy 187.459609 -154.422539)
			(xy 187.430143 -154.468389) (xy 187.394452 -154.50958) (xy 187.353261 -154.545271) (xy 187.307411 -154.574737)
			(xy 187.257834 -154.597379) (xy 187.205539 -154.612734) (xy 187.151591 -154.62049) (xy 187.097089 -154.62049)
			(xy 187.043141 -154.612734) (xy 186.990846 -154.597379) (xy 186.941269 -154.574737) (xy 186.895419 -154.545271)
			(xy 186.854228 -154.50958) (xy 186.818537 -154.468389) (xy 186.789071 -154.422539) (xy 186.766429 -154.372962)
			(xy 186.751074 -154.320667) (xy 186.743318 -154.266719) (xy 186.742832 -154.239468) (xy 35.44312 -154.239468)
			(xy 35.439287 -154.2897) (xy 35.415374 -154.498111) (xy 35.383544 -154.705462) (xy 35.343843 -154.91145)
			(xy 35.296329 -155.115777) (xy 35.24107 -155.318148) (xy 35.178147 -155.518267) (xy 35.107651 -155.715847)
			(xy 35.029684 -155.910599) (xy 34.944359 -156.102242) (xy 34.8518 -156.290497) (xy 34.752141 -156.475092)
			(xy 34.645527 -156.65576) (xy 34.532112 -156.832237) (xy 34.41206 -157.004269) (xy 34.285546 -157.171605)
			(xy 34.152753 -157.334004) (xy 34.013874 -157.49123) (xy 33.86911 -157.643054) (xy 33.718671 -157.789257)
			(xy 33.562774 -157.929626) (xy 33.401647 -158.063959) (xy 33.235523 -158.19206) (xy 33.064642 -158.313744)
			(xy 32.889252 -158.428834) (xy 32.709608 -158.537164) (xy 32.52597 -158.638575) (xy 32.338604 -158.732922)
			(xy 32.147782 -158.820068) (xy 31.953781 -158.899885) (xy 31.756882 -158.972259) (xy 31.55737 -159.037084)
			(xy 31.355535 -159.094267) (xy 31.151669 -159.143725) (xy 30.946068 -159.185385) (xy 30.73903 -159.219187)
			(xy 30.530856 -159.245083) (xy 30.321846 -159.263035) (xy 30.112304 -159.273017) (xy 29.902535 -159.275014)
			(xy 29.692841 -159.269023) (xy 29.483528 -159.255054) (xy 29.274898 -159.233126) (xy 29.067254 -159.203272)
			(xy 28.860897 -159.165533) (xy 28.656127 -159.119966) (xy 28.45324 -159.066637) (xy 28.25253 -159.005622)
			(xy 28.054288 -158.93701) (xy 27.858803 -158.8609) (xy 27.666356 -158.777403) (xy 27.477228 -158.686641)
			(xy 27.291693 -158.588744) (xy 27.110019 -158.483854) (xy 26.932469 -158.372124) (xy 26.759303 -158.253716)
			(xy 26.590769 -158.128801) (xy 26.427114 -157.99756) (xy 26.268573 -157.860184) (xy 26.115378 -157.716871)
			(xy 25.967749 -157.567831) (xy 25.825902 -157.413278) (xy 25.690041 -157.253437) (xy 25.560364 -157.088539)
			(xy 25.437059 -156.918824) (xy 25.320305 -156.744538) (xy 25.21027 -156.565933) (xy 25.107115 -156.383269)
			(xy 25.010988 -156.19681) (xy 24.92203 -156.006826) (xy 24.84037 -155.813594) (xy 24.766125 -155.617393)
			(xy 24.699403 -155.418507) (xy 24.640301 -155.217225) (xy 24.588905 -155.01384) (xy 24.54529 -154.808645)
			(xy 24.509518 -154.601938) (xy 24.481641 -154.394019) (xy 24.4617 -154.18519) (xy 24.449724 -153.975753)
			(xy 24.445731 -153.766012) (xy 2.509012 -153.766012) (xy 2.509012 -160.911354) (xy 372.506163 -160.911354)
			(xy 372.506163 -160.856846) (xy 372.513921 -160.802893) (xy 372.529279 -160.750593) (xy 372.551924 -160.701011)
			(xy 372.581395 -160.655157) (xy 372.617092 -160.613964) (xy 372.658289 -160.578271) (xy 372.704146 -160.548805)
			(xy 372.75373 -160.526165) (xy 372.806032 -160.510813) (xy 372.859986 -160.503061) (xy 372.88724 -160.5026)
			(xy 373.75084 -160.5026) (xy 373.77809 -160.503073) (xy 373.832034 -160.510834) (xy 373.884326 -160.526193)
			(xy 373.933899 -160.548837) (xy 373.979745 -160.578305) (xy 374.020931 -160.613997) (xy 374.056619 -160.655187)
			(xy 374.086083 -160.701036) (xy 374.108721 -160.750612) (xy 374.124075 -160.802905) (xy 374.13183 -160.85685)
			(xy 374.13183 -160.91135) (xy 374.124075 -160.965295) (xy 374.108721 -161.017588) (xy 374.086083 -161.067164)
			(xy 374.056619 -161.113013) (xy 374.020931 -161.154203) (xy 373.979745 -161.189895) (xy 373.933899 -161.219363)
			(xy 373.884326 -161.242007) (xy 373.832034 -161.257366) (xy 373.77809 -161.265127) (xy 373.75084 -161.265616)
			(xy 372.88724 -161.265616) (xy 372.859986 -161.265139) (xy 372.806032 -161.257387) (xy 372.75373 -161.242035)
			(xy 372.704146 -161.219395) (xy 372.658289 -161.189929) (xy 372.617092 -161.154236) (xy 372.581395 -161.113043)
			(xy 372.551924 -161.067189) (xy 372.529279 -161.017607) (xy 372.513921 -160.965307) (xy 372.506163 -160.911354)
			(xy 2.509012 -160.911354) (xy 2.509012 -161.58445) (xy 296.753286 -161.58445) (xy 296.753286 -161.52995)
			(xy 296.761042 -161.476005) (xy 296.776395 -161.423713) (xy 296.799035 -161.374138) (xy 296.828498 -161.32829)
			(xy 296.864187 -161.287101) (xy 296.905374 -161.25141) (xy 296.951221 -161.221944) (xy 297.000795 -161.199302)
			(xy 297.053086 -161.183946) (xy 297.10703 -161.176187) (xy 297.13428 -161.1757) (xy 297.99788 -161.1757)
			(xy 298.025134 -161.176146) (xy 298.079089 -161.183901) (xy 298.13139 -161.199255) (xy 298.180974 -161.221897)
			(xy 298.22683 -161.251365) (xy 298.268026 -161.28706) (xy 298.303723 -161.328254) (xy 298.333193 -161.374109)
			(xy 298.355838 -161.423691) (xy 298.371195 -161.475992) (xy 298.378953 -161.529946) (xy 298.378953 -161.584454)
			(xy 298.371195 -161.638408) (xy 298.355838 -161.690709) (xy 298.333193 -161.740291) (xy 298.303723 -161.786146)
			(xy 298.268026 -161.82734) (xy 298.22683 -161.863035) (xy 298.180974 -161.892503) (xy 298.13139 -161.915145)
			(xy 298.079089 -161.930499) (xy 298.025134 -161.938254) (xy 297.99788 -161.938716) (xy 297.13428 -161.938716)
			(xy 297.10703 -161.938213) (xy 297.053086 -161.930454) (xy 297.000795 -161.915098) (xy 296.951221 -161.892456)
			(xy 296.905374 -161.86299) (xy 296.864187 -161.827299) (xy 296.828498 -161.78611) (xy 296.799035 -161.740262)
			(xy 296.776395 -161.690687) (xy 296.761042 -161.638395) (xy 296.753286 -161.58445) (xy 2.509012 -161.58445)
			(xy 2.509012 -162.128053) (xy 292.574946 -162.128053) (xy 292.574946 -162.073547) (xy 292.582702 -162.019597)
			(xy 292.598058 -161.967299) (xy 292.620699 -161.917719) (xy 292.650166 -161.871866) (xy 292.685859 -161.830673)
			(xy 292.72705 -161.794978) (xy 292.772902 -161.765509) (xy 292.822481 -161.742865) (xy 292.874777 -161.727507)
			(xy 292.928727 -161.719747) (xy 292.95598 -161.71926) (xy 293.81958 -161.71926) (xy 293.846832 -161.719786)
			(xy 293.90078 -161.72754) (xy 293.953076 -161.742893) (xy 294.002654 -161.765532) (xy 294.048506 -161.794997)
			(xy 294.089698 -161.830688) (xy 294.125391 -161.871878) (xy 294.154858 -161.917728) (xy 294.1775 -161.967305)
			(xy 294.192856 -162.0196) (xy 294.200613 -162.073549) (xy 294.200613 -162.128051) (xy 294.192856 -162.182)
			(xy 294.1775 -162.234295) (xy 294.154858 -162.283872) (xy 294.125391 -162.329722) (xy 294.089698 -162.370912)
			(xy 294.048506 -162.406603) (xy 294.002654 -162.436068) (xy 293.953076 -162.458707) (xy 293.90078 -162.47406)
			(xy 293.846832 -162.481814) (xy 293.81958 -162.482276) (xy 292.95598 -162.482276) (xy 292.928727 -162.481853)
			(xy 292.874777 -162.474093) (xy 292.822481 -162.458735) (xy 292.772902 -162.436091) (xy 292.72705 -162.406622)
			(xy 292.685859 -162.370927) (xy 292.650166 -162.329734) (xy 292.620699 -162.283881) (xy 292.598058 -162.234301)
			(xy 292.582702 -162.182003) (xy 292.574946 -162.128053) (xy 2.509012 -162.128053) (xy 2.509012 -163.123651)
			(xy 294.731403 -163.123651) (xy 294.731403 -163.069149) (xy 294.73916 -163.015201) (xy 294.754516 -162.962907)
			(xy 294.777159 -162.91333) (xy 294.806627 -162.867481) (xy 294.842321 -162.826292) (xy 294.883513 -162.790603)
			(xy 294.929365 -162.76114) (xy 294.978944 -162.738502) (xy 295.03124 -162.723152) (xy 295.085189 -162.7154)
			(xy 295.11244 -162.71494) (xy 295.97604 -162.71494) (xy 296.003293 -162.715333) (xy 296.057243 -162.723095)
			(xy 296.10954 -162.738455) (xy 296.159118 -162.761102) (xy 296.204969 -162.790573) (xy 296.24616 -162.826269)
			(xy 296.281851 -162.867463) (xy 296.311318 -162.913317) (xy 296.333959 -162.962898) (xy 296.349314 -163.015196)
			(xy 296.35707 -163.069147) (xy 296.35707 -163.110951) (xy 300.192403 -163.110951) (xy 300.192403 -163.056449)
			(xy 300.20016 -163.002501) (xy 300.215516 -162.950207) (xy 300.238159 -162.90063) (xy 300.267627 -162.854781)
			(xy 300.303321 -162.813592) (xy 300.344513 -162.777903) (xy 300.390365 -162.74844) (xy 300.439944 -162.725802)
			(xy 300.49224 -162.710452) (xy 300.546189 -162.7027) (xy 300.57344 -162.70224) (xy 301.43704 -162.70224)
			(xy 301.464293 -162.702633) (xy 301.518243 -162.710395) (xy 301.57054 -162.725755) (xy 301.620118 -162.748402)
			(xy 301.665969 -162.777873) (xy 301.70716 -162.813569) (xy 301.742851 -162.854763) (xy 301.772318 -162.900617)
			(xy 301.794959 -162.950198) (xy 301.810314 -163.002496) (xy 301.81807 -163.056447) (xy 301.81807 -163.110953)
			(xy 301.810314 -163.164904) (xy 301.794959 -163.217202) (xy 301.772318 -163.266783) (xy 301.742851 -163.312637)
			(xy 301.70716 -163.353831) (xy 301.665969 -163.389527) (xy 301.620118 -163.418998) (xy 301.57054 -163.441645)
			(xy 301.518243 -163.457005) (xy 301.464293 -163.464767) (xy 301.43704 -163.465256) (xy 300.57344 -163.465256)
			(xy 300.546189 -163.4647) (xy 300.49224 -163.456948) (xy 300.439944 -163.441598) (xy 300.390365 -163.41896)
			(xy 300.344513 -163.389497) (xy 300.303321 -163.353808) (xy 300.267627 -163.312619) (xy 300.238159 -163.26677)
			(xy 300.215516 -163.217193) (xy 300.20016 -163.164899) (xy 300.192403 -163.110951) (xy 296.35707 -163.110951)
			(xy 296.35707 -163.123653) (xy 296.349314 -163.177604) (xy 296.333959 -163.229902) (xy 296.311318 -163.279483)
			(xy 296.281851 -163.325337) (xy 296.24616 -163.366531) (xy 296.204969 -163.402227) (xy 296.159118 -163.431698)
			(xy 296.10954 -163.454345) (xy 296.057243 -163.469705) (xy 296.003293 -163.477467) (xy 295.97604 -163.477956)
			(xy 295.11244 -163.477956) (xy 295.085189 -163.4774) (xy 295.03124 -163.469648) (xy 294.978944 -163.454298)
			(xy 294.929365 -163.43166) (xy 294.883513 -163.402197) (xy 294.842321 -163.366508) (xy 294.806627 -163.325319)
			(xy 294.777159 -163.27947) (xy 294.754516 -163.229893) (xy 294.73916 -163.177599) (xy 294.731403 -163.123651)
			(xy 2.509012 -163.123651) (xy 2.509012 -167.565832) (xy 348.657164 -167.565832) (xy 348.657658 -167.532531)
			(xy 348.666337 -167.466499) (xy 348.683566 -167.402165) (xy 348.709048 -167.340632) (xy 348.742347 -167.282953)
			(xy 348.782893 -167.230117) (xy 348.829992 -167.183027) (xy 348.882836 -167.142492) (xy 348.911418 -167.125396)
			(xy 349.83547 -166.591742) (xy 349.864533 -166.575642) (xy 349.925937 -166.550271) (xy 349.990123 -166.533114)
			(xy 350.055996 -166.524463) (xy 350.089216 -166.523924) (xy 350.089724 -166.523924) (xy 350.120458 -166.524315)
			(xy 350.181477 -166.531727) (xy 350.241158 -166.54644) (xy 350.29863 -166.56824) (xy 350.353056 -166.596808)
			(xy 350.403641 -166.631729) (xy 350.449648 -166.672492) (xy 350.490406 -166.718503) (xy 350.525321 -166.769092)
			(xy 350.553883 -166.823521) (xy 350.57377 -166.875968) (xy 369.614196 -166.875968) (xy 369.614752 -166.84267)
			(xy 369.623426 -166.776641) (xy 369.640648 -166.71231) (xy 369.666122 -166.650779) (xy 369.699412 -166.593101)
			(xy 369.739949 -166.540263) (xy 369.787038 -166.493171) (xy 369.839873 -166.452631) (xy 369.86845 -166.435532)
			(xy 370.792502 -165.901878) (xy 370.82156 -165.885769) (xy 370.882966 -165.8604) (xy 370.947153 -165.843245)
			(xy 371.013028 -165.834597) (xy 371.046248 -165.83406) (xy 371.046756 -165.83406) (xy 371.077486 -165.834579)
			(xy 371.138498 -165.841982) (xy 371.198173 -165.856685) (xy 371.255641 -165.878475) (xy 371.310063 -165.907032)
			(xy 371.360647 -165.941941) (xy 371.406653 -165.982693) (xy 371.447412 -166.028694) (xy 371.482329 -166.079272)
			(xy 371.510894 -166.133689) (xy 371.532692 -166.191154) (xy 371.547404 -166.250827) (xy 371.554816 -166.311838)
			(xy 371.555264 -166.342568) (xy 371.554757 -166.375868) (xy 371.546077 -166.4419) (xy 371.52885 -166.506232)
			(xy 371.503369 -166.567765) (xy 371.470072 -166.625443) (xy 371.429528 -166.67828) (xy 371.382432 -166.72537)
			(xy 371.329591 -166.765907) (xy 371.30101 -166.783004) (xy 370.964111 -166.977568) (xy 373.398796 -166.977568)
			(xy 373.399226 -166.946836) (xy 373.406638 -166.885821) (xy 373.421351 -166.826144) (xy 373.443149 -166.768676)
			(xy 373.471715 -166.714254) (xy 373.506633 -166.663671) (xy 373.547392 -166.617667) (xy 373.5934 -166.57691)
			(xy 373.643984 -166.541996) (xy 373.698409 -166.513434) (xy 373.755879 -166.49164) (xy 373.815556 -166.476932)
			(xy 373.876572 -166.469524) (xy 373.907304 -166.46906) (xy 373.907812 -166.46906) (xy 373.941031 -166.469606)
			(xy 374.006903 -166.478264) (xy 374.071088 -166.495419) (xy 374.132496 -166.520778) (xy 374.161558 -166.536878)
			(xy 375.08561 -167.070532) (xy 375.114171 -167.087654) (xy 375.166997 -167.128201) (xy 375.214079 -167.175295)
			(xy 375.254613 -167.22813) (xy 375.287906 -167.285802) (xy 375.313388 -167.347326) (xy 375.330623 -167.411649)
			(xy 375.339318 -167.477672) (xy 375.339864 -167.510968) (xy 375.339432 -167.541701) (xy 375.332026 -167.60272)
			(xy 375.317319 -167.6624) (xy 375.295524 -167.719873) (xy 375.266961 -167.774299) (xy 375.232044 -167.824885)
			(xy 375.191284 -167.870893) (xy 375.145275 -167.911651) (xy 375.094689 -167.946567) (xy 375.040262 -167.975129)
			(xy 374.982789 -167.996923) (xy 374.923108 -168.011629) (xy 374.862089 -168.019033) (xy 374.831356 -168.019476)
			(xy 374.830848 -168.019476) (xy 374.797629 -168.018942) (xy 374.731757 -168.01028) (xy 374.667571 -167.993122)
			(xy 374.606164 -167.967759) (xy 374.577102 -167.951658) (xy 373.65305 -167.418004) (xy 373.624495 -167.400872)
			(xy 373.571672 -167.360325) (xy 373.524591 -167.313232) (xy 373.484057 -167.260398) (xy 373.450764 -167.202727)
			(xy 373.42528 -167.141205) (xy 373.408042 -167.076884) (xy 373.399344 -167.010863) (xy 373.398796 -166.977568)
			(xy 370.964111 -166.977568) (xy 370.376958 -167.316658) (xy 370.34791 -167.332786) (xy 370.2865 -167.35815)
			(xy 370.22231 -167.375299) (xy 370.156433 -167.383942) (xy 370.123212 -167.384476) (xy 370.122704 -167.384476)
			(xy 370.091971 -167.384059) (xy 370.030952 -167.37665) (xy 369.971272 -167.36194) (xy 369.9138 -167.340143)
			(xy 369.859375 -167.311577) (xy 369.808789 -167.276659) (xy 369.762782 -167.235898) (xy 369.722023 -167.189889)
			(xy 369.687108 -167.139301) (xy 369.658546 -167.084874) (xy 369.636752 -167.027401) (xy 369.622045 -166.96772)
			(xy 369.61464 -166.906701) (xy 369.614196 -166.875968) (xy 350.57377 -166.875968) (xy 350.575676 -166.880996)
			(xy 350.590383 -166.940678) (xy 350.597788 -167.001698) (xy 350.598232 -167.032432) (xy 350.597712 -167.065732)
			(xy 350.589036 -167.131763) (xy 350.571812 -167.196097) (xy 350.546334 -167.25763) (xy 350.513038 -167.315309)
			(xy 350.472496 -167.368145) (xy 350.4254 -167.415235) (xy 350.372559 -167.455772) (xy 350.343978 -167.472868)
			(xy 349.419926 -168.006522) (xy 349.390862 -168.02262) (xy 349.329459 -168.047992) (xy 349.265273 -168.06515)
			(xy 349.1994 -168.073802) (xy 349.16618 -168.07434) (xy 349.165672 -168.07434) (xy 349.134942 -168.07387)
			(xy 349.073929 -168.066459) (xy 349.014255 -168.051748) (xy 348.956789 -168.029953) (xy 348.902369 -168.001389)
			(xy 348.851788 -167.966475) (xy 348.805784 -167.925719) (xy 348.765027 -167.879715) (xy 348.730113 -167.829135)
			(xy 348.701549 -167.774715) (xy 348.679753 -167.717249) (xy 348.665041 -167.657575) (xy 348.65763 -167.596562)
			(xy 348.657164 -167.565832) (xy 2.509012 -167.565832) (xy 2.509012 -168.302432) (xy 352.441764 -168.302432)
			(xy 352.442268 -168.271702) (xy 352.449672 -168.210689) (xy 352.464377 -168.151013) (xy 352.486168 -168.093545)
			(xy 352.514727 -168.039122) (xy 352.549637 -167.988539) (xy 352.59039 -167.942533) (xy 352.636392 -167.901774)
			(xy 352.686971 -167.866858) (xy 352.74139 -167.838292) (xy 352.798856 -167.816495) (xy 352.85853 -167.801783)
			(xy 352.919542 -167.794371) (xy 352.950272 -167.793924) (xy 352.95078 -167.793924) (xy 352.983998 -167.794489)
			(xy 353.049869 -167.803142) (xy 353.114055 -167.820291) (xy 353.175463 -167.845645) (xy 353.204526 -167.861742)
			(xy 354.128578 -168.395396) (xy 354.157139 -168.412518) (xy 354.209962 -168.453067) (xy 354.257042 -168.500162)
			(xy 354.297574 -168.552998) (xy 354.330866 -168.61067) (xy 354.356349 -168.672193) (xy 354.373586 -168.736515)
			(xy 354.382284 -168.802536) (xy 354.382832 -168.835832) (xy 354.382374 -168.866563) (xy 354.374962 -168.927576)
			(xy 354.360251 -168.987251) (xy 354.338454 -169.044717) (xy 354.30989 -169.099138) (xy 354.274975 -169.149719)
			(xy 354.234218 -169.195723) (xy 354.188213 -169.23648) (xy 354.137631 -169.271394) (xy 354.08321 -169.299957)
			(xy 354.025743 -169.321753) (xy 353.966068 -169.336464) (xy 353.905055 -169.343875) (xy 353.874324 -169.34434)
			(xy 353.873816 -169.34434) (xy 353.840597 -169.343782) (xy 353.774726 -169.335127) (xy 353.710541 -169.317976)
			(xy 353.649132 -169.292621) (xy 353.62007 -169.276522) (xy 352.696018 -168.742868) (xy 352.667463 -168.725735)
			(xy 352.614637 -168.685191) (xy 352.567553 -168.638099) (xy 352.527018 -168.585266) (xy 352.493724 -168.527595)
			(xy 352.468241 -168.466072) (xy 352.451005 -168.40175) (xy 352.44231 -168.335728) (xy 352.441764 -168.302432)
			(xy 2.509012 -168.302432) (xy 2.509012 -170.613832) (xy 348.657164 -170.613832) (xy 348.657658 -170.580531)
			(xy 348.666337 -170.514499) (xy 348.683566 -170.450165) (xy 348.709048 -170.388632) (xy 348.742347 -170.330953)
			(xy 348.782893 -170.278117) (xy 348.829992 -170.231027) (xy 348.882836 -170.190492) (xy 348.911418 -170.173396)
			(xy 349.83547 -169.639742) (xy 349.864533 -169.623642) (xy 349.925937 -169.598271) (xy 349.990123 -169.581114)
			(xy 350.055996 -169.572463) (xy 350.089216 -169.571924) (xy 350.089724 -169.571924) (xy 350.120458 -169.572315)
			(xy 350.181477 -169.579727) (xy 350.241158 -169.59444) (xy 350.29863 -169.61624) (xy 350.353056 -169.644808)
			(xy 350.403641 -169.679729) (xy 350.449648 -169.720492) (xy 350.490406 -169.766503) (xy 350.525321 -169.817092)
			(xy 350.553883 -169.871521) (xy 350.57377 -169.923968) (xy 369.614196 -169.923968) (xy 369.614752 -169.89067)
			(xy 369.623426 -169.824641) (xy 369.640648 -169.76031) (xy 369.666122 -169.698779) (xy 369.699412 -169.641101)
			(xy 369.739949 -169.588263) (xy 369.787038 -169.541171) (xy 369.839873 -169.500631) (xy 369.86845 -169.483532)
			(xy 370.792502 -168.949878) (xy 370.82156 -168.933769) (xy 370.882966 -168.9084) (xy 370.947153 -168.891245)
			(xy 371.013028 -168.882597) (xy 371.046248 -168.88206) (xy 371.046756 -168.88206) (xy 371.077486 -168.882579)
			(xy 371.138498 -168.889982) (xy 371.198173 -168.904685) (xy 371.255641 -168.926475) (xy 371.310063 -168.955032)
			(xy 371.360647 -168.989941) (xy 371.406653 -169.030693) (xy 371.447412 -169.076694) (xy 371.482329 -169.127272)
			(xy 371.510894 -169.181689) (xy 371.532692 -169.239154) (xy 371.547404 -169.298827) (xy 371.554816 -169.359838)
			(xy 371.555264 -169.390568) (xy 371.554757 -169.423868) (xy 371.546077 -169.4899) (xy 371.52885 -169.554232)
			(xy 371.503369 -169.615765) (xy 371.470072 -169.673443) (xy 371.429528 -169.72628) (xy 371.382432 -169.77337)
			(xy 371.329591 -169.813907) (xy 371.30101 -169.831004) (xy 370.376958 -170.364658) (xy 370.34791 -170.380786)
			(xy 370.2865 -170.40615) (xy 370.22231 -170.423299) (xy 370.156433 -170.431942) (xy 370.123212 -170.432476)
			(xy 370.122704 -170.432476) (xy 370.091971 -170.432059) (xy 370.030952 -170.42465) (xy 369.971272 -170.40994)
			(xy 369.9138 -170.388143) (xy 369.859375 -170.359577) (xy 369.808789 -170.324659) (xy 369.762782 -170.283898)
			(xy 369.722023 -170.237889) (xy 369.687108 -170.187301) (xy 369.658546 -170.132874) (xy 369.636752 -170.075401)
			(xy 369.622045 -170.01572) (xy 369.61464 -169.954701) (xy 369.614196 -169.923968) (xy 350.57377 -169.923968)
			(xy 350.575676 -169.928996) (xy 350.590383 -169.988678) (xy 350.597788 -170.049698) (xy 350.598232 -170.080432)
			(xy 350.597712 -170.113732) (xy 350.589036 -170.179763) (xy 350.571812 -170.244097) (xy 350.546334 -170.30563)
			(xy 350.513038 -170.363309) (xy 350.472496 -170.416145) (xy 350.4254 -170.463235) (xy 350.372559 -170.503772)
			(xy 350.343978 -170.520868) (xy 350.10208 -170.660568) (xy 373.398796 -170.660568) (xy 373.399226 -170.629836)
			(xy 373.406638 -170.568821) (xy 373.421351 -170.509144) (xy 373.443149 -170.451676) (xy 373.471715 -170.397254)
			(xy 373.506633 -170.346671) (xy 373.547392 -170.300667) (xy 373.5934 -170.25991) (xy 373.643984 -170.224996)
			(xy 373.698409 -170.196434) (xy 373.755879 -170.17464) (xy 373.815556 -170.159932) (xy 373.876572 -170.152524)
			(xy 373.907304 -170.15206) (xy 373.907812 -170.15206) (xy 373.941031 -170.152606) (xy 374.006903 -170.161264)
			(xy 374.071088 -170.178419) (xy 374.132496 -170.203778) (xy 374.161558 -170.219878) (xy 375.08561 -170.753532)
			(xy 375.114171 -170.770654) (xy 375.166997 -170.811201) (xy 375.214079 -170.858295) (xy 375.254613 -170.91113)
			(xy 375.287906 -170.968802) (xy 375.313388 -171.030326) (xy 375.330623 -171.094649) (xy 375.339318 -171.160672)
			(xy 375.339864 -171.193968) (xy 375.339432 -171.224701) (xy 375.332026 -171.28572) (xy 375.317319 -171.3454)
			(xy 375.295524 -171.402873) (xy 375.266961 -171.457299) (xy 375.232044 -171.507885) (xy 375.191284 -171.553893)
			(xy 375.145275 -171.594651) (xy 375.094689 -171.629567) (xy 375.040262 -171.658129) (xy 374.982789 -171.679923)
			(xy 374.923108 -171.694629) (xy 374.862089 -171.702033) (xy 374.831356 -171.702476) (xy 374.830848 -171.702476)
			(xy 374.797629 -171.701942) (xy 374.731757 -171.69328) (xy 374.667571 -171.676122) (xy 374.606164 -171.650759)
			(xy 374.577102 -171.634658) (xy 373.65305 -171.101004) (xy 373.624495 -171.083872) (xy 373.571672 -171.043325)
			(xy 373.524591 -170.996232) (xy 373.484057 -170.943398) (xy 373.450764 -170.885727) (xy 373.42528 -170.824205)
			(xy 373.408042 -170.759884) (xy 373.399344 -170.693863) (xy 373.398796 -170.660568) (xy 350.10208 -170.660568)
			(xy 349.419926 -171.054522) (xy 349.390862 -171.07062) (xy 349.329459 -171.095992) (xy 349.265273 -171.11315)
			(xy 349.1994 -171.121802) (xy 349.16618 -171.12234) (xy 349.165672 -171.12234) (xy 349.134942 -171.12187)
			(xy 349.073929 -171.114459) (xy 349.014255 -171.099748) (xy 348.956789 -171.077953) (xy 348.902369 -171.049389)
			(xy 348.851788 -171.014475) (xy 348.805784 -170.973719) (xy 348.765027 -170.927715) (xy 348.730113 -170.877135)
			(xy 348.701549 -170.822715) (xy 348.679753 -170.765249) (xy 348.665041 -170.705575) (xy 348.65763 -170.644562)
			(xy 348.657164 -170.613832) (xy 2.509012 -170.613832) (xy 2.509012 -171.985432) (xy 352.441764 -171.985432)
			(xy 352.442268 -171.954702) (xy 352.449672 -171.893689) (xy 352.464377 -171.834013) (xy 352.486168 -171.776545)
			(xy 352.514727 -171.722122) (xy 352.549637 -171.671539) (xy 352.59039 -171.625533) (xy 352.636392 -171.584774)
			(xy 352.686971 -171.549858) (xy 352.74139 -171.521292) (xy 352.798856 -171.499495) (xy 352.85853 -171.484783)
			(xy 352.919542 -171.477371) (xy 352.950272 -171.476924) (xy 352.95078 -171.476924) (xy 352.983998 -171.477489)
			(xy 353.049869 -171.486142) (xy 353.114055 -171.503291) (xy 353.175463 -171.528645) (xy 353.204526 -171.544742)
			(xy 354.128578 -172.078396) (xy 354.157139 -172.095518) (xy 354.209962 -172.136067) (xy 354.257042 -172.183162)
			(xy 354.297574 -172.235998) (xy 354.330866 -172.29367) (xy 354.356349 -172.355193) (xy 354.373586 -172.419515)
			(xy 354.382284 -172.485536) (xy 354.382832 -172.518832) (xy 354.382374 -172.549563) (xy 354.374962 -172.610576)
			(xy 354.360251 -172.670251) (xy 354.338454 -172.727717) (xy 354.30989 -172.782138) (xy 354.274975 -172.832719)
			(xy 354.234218 -172.878723) (xy 354.188213 -172.91948) (xy 354.137631 -172.954394) (xy 354.104147 -172.971968)
			(xy 369.614196 -172.971968) (xy 369.614752 -172.93867) (xy 369.623426 -172.872641) (xy 369.640648 -172.80831)
			(xy 369.666122 -172.746779) (xy 369.699412 -172.689101) (xy 369.739949 -172.636263) (xy 369.787038 -172.589171)
			(xy 369.839873 -172.548631) (xy 369.86845 -172.531532) (xy 370.792502 -171.997878) (xy 370.82156 -171.981769)
			(xy 370.882966 -171.9564) (xy 370.947153 -171.939245) (xy 371.013028 -171.930597) (xy 371.046248 -171.93006)
			(xy 371.046756 -171.93006) (xy 371.077486 -171.930579) (xy 371.138498 -171.937982) (xy 371.198173 -171.952685)
			(xy 371.255641 -171.974475) (xy 371.310063 -172.003032) (xy 371.360647 -172.037941) (xy 371.406653 -172.078693)
			(xy 371.447412 -172.124694) (xy 371.482329 -172.175272) (xy 371.510894 -172.229689) (xy 371.532692 -172.287154)
			(xy 371.547404 -172.346827) (xy 371.554816 -172.407838) (xy 371.555264 -172.438568) (xy 371.554757 -172.471868)
			(xy 371.546077 -172.5379) (xy 371.52885 -172.602232) (xy 371.503369 -172.663765) (xy 371.470072 -172.721443)
			(xy 371.429528 -172.77428) (xy 371.382432 -172.82137) (xy 371.329591 -172.861907) (xy 371.30101 -172.879004)
			(xy 370.376958 -173.412658) (xy 370.34791 -173.428786) (xy 370.2865 -173.45415) (xy 370.22231 -173.471299)
			(xy 370.156433 -173.479942) (xy 370.123212 -173.480476) (xy 370.122704 -173.480476) (xy 370.091971 -173.480059)
			(xy 370.030952 -173.47265) (xy 369.971272 -173.45794) (xy 369.9138 -173.436143) (xy 369.859375 -173.407577)
			(xy 369.808789 -173.372659) (xy 369.762782 -173.331898) (xy 369.722023 -173.285889) (xy 369.687108 -173.235301)
			(xy 369.658546 -173.180874) (xy 369.636752 -173.123401) (xy 369.622045 -173.06372) (xy 369.61464 -173.002701)
			(xy 369.614196 -172.971968) (xy 354.104147 -172.971968) (xy 354.08321 -172.982957) (xy 354.025743 -173.004753)
			(xy 353.966068 -173.019464) (xy 353.905055 -173.026875) (xy 353.874324 -173.02734) (xy 353.873816 -173.02734)
			(xy 353.840597 -173.026782) (xy 353.774726 -173.018127) (xy 353.710541 -173.000976) (xy 353.649132 -172.975621)
			(xy 353.62007 -172.959522) (xy 352.696018 -172.425868) (xy 352.667463 -172.408735) (xy 352.614637 -172.368191)
			(xy 352.567553 -172.321099) (xy 352.527018 -172.268266) (xy 352.493724 -172.210595) (xy 352.468241 -172.149072)
			(xy 352.451005 -172.08475) (xy 352.44231 -172.018728) (xy 352.441764 -171.985432) (xy 2.509012 -171.985432)
			(xy 2.509012 -173.661832) (xy 348.657164 -173.661832) (xy 348.657658 -173.628531) (xy 348.666337 -173.562499)
			(xy 348.683566 -173.498165) (xy 348.709048 -173.436632) (xy 348.742347 -173.378953) (xy 348.782893 -173.326117)
			(xy 348.829992 -173.279027) (xy 348.882836 -173.238492) (xy 348.911418 -173.221396) (xy 349.83547 -172.687742)
			(xy 349.864533 -172.671642) (xy 349.925937 -172.646271) (xy 349.990123 -172.629114) (xy 350.055996 -172.620463)
			(xy 350.089216 -172.619924) (xy 350.089724 -172.619924) (xy 350.120458 -172.620315) (xy 350.181477 -172.627727)
			(xy 350.241158 -172.64244) (xy 350.29863 -172.66424) (xy 350.353056 -172.692808) (xy 350.403641 -172.727729)
			(xy 350.449648 -172.768492) (xy 350.490406 -172.814503) (xy 350.525321 -172.865092) (xy 350.553883 -172.919521)
			(xy 350.575676 -172.976996) (xy 350.590383 -173.036678) (xy 350.597788 -173.097698) (xy 350.598232 -173.128432)
			(xy 350.597712 -173.161732) (xy 350.589036 -173.227763) (xy 350.571812 -173.292097) (xy 350.546334 -173.35363)
			(xy 350.513038 -173.411309) (xy 350.472496 -173.464145) (xy 350.4254 -173.511235) (xy 350.372559 -173.551772)
			(xy 350.343978 -173.568868) (xy 349.419926 -174.102522) (xy 349.390862 -174.11862) (xy 349.329459 -174.143992)
			(xy 349.265273 -174.16115) (xy 349.1994 -174.169802) (xy 349.16618 -174.17034) (xy 349.165672 -174.17034)
			(xy 349.134942 -174.16987) (xy 349.073929 -174.162459) (xy 349.014255 -174.147748) (xy 348.956789 -174.125953)
			(xy 348.902369 -174.097389) (xy 348.851788 -174.062475) (xy 348.805784 -174.021719) (xy 348.765027 -173.975715)
			(xy 348.730113 -173.925135) (xy 348.701549 -173.870715) (xy 348.679753 -173.813249) (xy 348.665041 -173.753575)
			(xy 348.65763 -173.692562) (xy 348.657164 -173.661832) (xy 2.509012 -173.661832) (xy 2.509012 -174.343568)
			(xy 373.398796 -174.343568) (xy 373.399226 -174.312836) (xy 373.406638 -174.251821) (xy 373.421351 -174.192144)
			(xy 373.443149 -174.134676) (xy 373.471715 -174.080254) (xy 373.506633 -174.029671) (xy 373.547392 -173.983667)
			(xy 373.5934 -173.94291) (xy 373.643984 -173.907996) (xy 373.698409 -173.879434) (xy 373.755879 -173.85764)
			(xy 373.815556 -173.842932) (xy 373.876572 -173.835524) (xy 373.907304 -173.83506) (xy 373.907812 -173.83506)
			(xy 373.941031 -173.835606) (xy 374.006903 -173.844264) (xy 374.071088 -173.861419) (xy 374.132496 -173.886778)
			(xy 374.161558 -173.902878) (xy 375.08561 -174.436532) (xy 375.114171 -174.453654) (xy 375.166997 -174.494201)
			(xy 375.214079 -174.541295) (xy 375.254613 -174.59413) (xy 375.287906 -174.651802) (xy 375.313388 -174.713326)
			(xy 375.330623 -174.777649) (xy 375.339318 -174.843672) (xy 375.339864 -174.876968) (xy 375.339432 -174.907701)
			(xy 375.332026 -174.96872) (xy 375.317319 -175.0284) (xy 375.295524 -175.085873) (xy 375.266961 -175.140299)
			(xy 375.232044 -175.190885) (xy 375.191284 -175.236893) (xy 375.145275 -175.277651) (xy 375.094689 -175.312567)
			(xy 375.040262 -175.341129) (xy 374.982789 -175.362923) (xy 374.923108 -175.377629) (xy 374.862089 -175.385033)
			(xy 374.831356 -175.385476) (xy 374.830848 -175.385476) (xy 374.797629 -175.384942) (xy 374.731757 -175.37628)
			(xy 374.667571 -175.359122) (xy 374.606164 -175.333759) (xy 374.577102 -175.317658) (xy 373.65305 -174.784004)
			(xy 373.624495 -174.766872) (xy 373.571672 -174.726325) (xy 373.524591 -174.679232) (xy 373.484057 -174.626398)
			(xy 373.450764 -174.568727) (xy 373.42528 -174.507205) (xy 373.408042 -174.442884) (xy 373.399344 -174.376863)
			(xy 373.398796 -174.343568) (xy 2.509012 -174.343568) (xy 2.509012 -175.83404) (xy 23.37714 -175.83404)
			(xy 23.381229 -175.778158) (xy 23.393412 -175.723468) (xy 23.413428 -175.671134) (xy 23.440851 -175.622272)
			(xy 23.475096 -175.577924) (xy 23.515432 -175.539034) (xy 23.561002 -175.506432) (xy 23.610833 -175.480813)
			(xy 23.663863 -175.462721) (xy 23.718961 -175.452544) (xy 23.774955 -175.450498) (xy 23.83065 -175.456626)
			(xy 23.884859 -175.470798) (xy 23.936427 -175.492712) (xy 23.984255 -175.521901) (xy 24.027323 -175.557742)
			(xy 24.064713 -175.599472) (xy 24.095629 -175.646202) (xy 24.119412 -175.696935) (xy 24.135554 -175.750591)
			(xy 24.143713 -175.806025) (xy 24.144224 -175.83404) (xy 24.143713 -175.862055) (xy 24.135554 -175.917489)
			(xy 24.119412 -175.971145) (xy 24.095629 -176.021878) (xy 24.064713 -176.068608) (xy 24.027323 -176.110338)
			(xy 23.984255 -176.146179) (xy 23.936427 -176.175368) (xy 23.884859 -176.197282) (xy 23.83065 -176.211454)
			(xy 23.774955 -176.217582) (xy 23.718961 -176.215536) (xy 23.663863 -176.205359) (xy 23.610833 -176.187267)
			(xy 23.561002 -176.161648) (xy 23.515432 -176.129046) (xy 23.475096 -176.090156) (xy 23.440851 -176.045808)
			(xy 23.413428 -175.996946) (xy 23.393412 -175.944612) (xy 23.381229 -175.889922) (xy 23.37714 -175.83404)
			(xy 2.509012 -175.83404) (xy 2.509012 -176.709832) (xy 348.657164 -176.709832) (xy 348.657658 -176.676531)
			(xy 348.666337 -176.610499) (xy 348.683566 -176.546165) (xy 348.709048 -176.484632) (xy 348.742347 -176.426953)
			(xy 348.782893 -176.374117) (xy 348.829992 -176.327027) (xy 348.882836 -176.286492) (xy 348.911418 -176.269396)
			(xy 349.83547 -175.735742) (xy 349.864533 -175.719642) (xy 349.925937 -175.694271) (xy 349.990123 -175.677114)
			(xy 350.055996 -175.668463) (xy 350.089216 -175.667924) (xy 350.089724 -175.667924) (xy 350.120458 -175.668315)
			(xy 350.121421 -175.668432) (xy 352.441764 -175.668432) (xy 352.442268 -175.637702) (xy 352.449672 -175.576689)
			(xy 352.464377 -175.517013) (xy 352.486168 -175.459545) (xy 352.514727 -175.405122) (xy 352.549637 -175.354539)
			(xy 352.59039 -175.308533) (xy 352.636392 -175.267774) (xy 352.686971 -175.232858) (xy 352.74139 -175.204292)
			(xy 352.798856 -175.182495) (xy 352.85853 -175.167783) (xy 352.919542 -175.160371) (xy 352.950272 -175.159924)
			(xy 352.95078 -175.159924) (xy 352.983998 -175.160489) (xy 353.049869 -175.169142) (xy 353.114055 -175.186291)
			(xy 353.175463 -175.211645) (xy 353.204526 -175.227742) (xy 354.128578 -175.761396) (xy 354.157139 -175.778518)
			(xy 354.209962 -175.819067) (xy 354.257042 -175.866162) (xy 354.297574 -175.918998) (xy 354.330866 -175.97667)
			(xy 354.3488 -176.019968) (xy 369.614196 -176.019968) (xy 369.614752 -175.98667) (xy 369.623426 -175.920641)
			(xy 369.640648 -175.85631) (xy 369.666122 -175.794779) (xy 369.699412 -175.737101) (xy 369.739949 -175.684263)
			(xy 369.787038 -175.637171) (xy 369.839873 -175.596631) (xy 369.86845 -175.579532) (xy 370.792502 -175.045878)
			(xy 370.82156 -175.029769) (xy 370.882966 -175.0044) (xy 370.947153 -174.987245) (xy 371.013028 -174.978597)
			(xy 371.046248 -174.97806) (xy 371.046756 -174.97806) (xy 371.077486 -174.978579) (xy 371.138498 -174.985982)
			(xy 371.198173 -175.000685) (xy 371.255641 -175.022475) (xy 371.310063 -175.051032) (xy 371.360647 -175.085941)
			(xy 371.406653 -175.126693) (xy 371.447412 -175.172694) (xy 371.482329 -175.223272) (xy 371.510894 -175.277689)
			(xy 371.532692 -175.335154) (xy 371.547404 -175.394827) (xy 371.554816 -175.455838) (xy 371.555264 -175.486568)
			(xy 371.554757 -175.519868) (xy 371.546077 -175.5859) (xy 371.543089 -175.597058) (xy 434.095902 -175.597058)
			(xy 434.099991 -175.541176) (xy 434.112174 -175.486486) (xy 434.13219 -175.434152) (xy 434.159613 -175.38529)
			(xy 434.193858 -175.340942) (xy 434.234194 -175.302052) (xy 434.279764 -175.26945) (xy 434.329595 -175.243831)
			(xy 434.382625 -175.225739) (xy 434.437723 -175.215562) (xy 434.493717 -175.213516) (xy 434.549412 -175.219644)
			(xy 434.603621 -175.233816) (xy 434.655189 -175.25573) (xy 434.703017 -175.284919) (xy 434.746085 -175.32076)
			(xy 434.783475 -175.36249) (xy 434.814391 -175.40922) (xy 434.838174 -175.459953) (xy 434.854316 -175.513609)
			(xy 434.862475 -175.569043) (xy 434.862986 -175.597058) (xy 434.862475 -175.625073) (xy 434.854316 -175.680507)
			(xy 434.838174 -175.734163) (xy 434.814391 -175.784896) (xy 434.783475 -175.831626) (xy 434.746085 -175.873356)
			(xy 434.703017 -175.909197) (xy 434.655189 -175.938386) (xy 434.603621 -175.9603) (xy 434.549412 -175.974472)
			(xy 434.493717 -175.9806) (xy 434.437723 -175.978554) (xy 434.382625 -175.968377) (xy 434.329595 -175.950285)
			(xy 434.279764 -175.924666) (xy 434.234194 -175.892064) (xy 434.193858 -175.853174) (xy 434.159613 -175.808826)
			(xy 434.13219 -175.759964) (xy 434.112174 -175.70763) (xy 434.099991 -175.65294) (xy 434.095902 -175.597058)
			(xy 371.543089 -175.597058) (xy 371.52885 -175.650232) (xy 371.503369 -175.711765) (xy 371.470072 -175.769443)
			(xy 371.429528 -175.82228) (xy 371.382432 -175.86937) (xy 371.329591 -175.909907) (xy 371.30101 -175.927004)
			(xy 370.376958 -176.460658) (xy 370.34791 -176.476786) (xy 370.2865 -176.50215) (xy 370.22231 -176.519299)
			(xy 370.156433 -176.527942) (xy 370.123212 -176.528476) (xy 370.122704 -176.528476) (xy 370.091971 -176.528059)
			(xy 370.030952 -176.52065) (xy 369.971272 -176.50594) (xy 369.9138 -176.484143) (xy 369.859375 -176.455577)
			(xy 369.808789 -176.420659) (xy 369.762782 -176.379898) (xy 369.722023 -176.333889) (xy 369.687108 -176.283301)
			(xy 369.658546 -176.228874) (xy 369.636752 -176.171401) (xy 369.622045 -176.11172) (xy 369.61464 -176.050701)
			(xy 369.614196 -176.019968) (xy 354.3488 -176.019968) (xy 354.356349 -176.038193) (xy 354.373586 -176.102515)
			(xy 354.382284 -176.168536) (xy 354.382832 -176.201832) (xy 354.382374 -176.232563) (xy 354.374962 -176.293576)
			(xy 354.360251 -176.353251) (xy 354.338454 -176.410717) (xy 354.30989 -176.465138) (xy 354.274975 -176.515719)
			(xy 354.234218 -176.561723) (xy 354.188213 -176.60248) (xy 354.137631 -176.637394) (xy 354.08321 -176.665957)
			(xy 354.025743 -176.687753) (xy 353.966068 -176.702464) (xy 353.905055 -176.709875) (xy 353.874324 -176.71034)
			(xy 353.873816 -176.71034) (xy 353.840597 -176.709782) (xy 353.774726 -176.701127) (xy 353.710541 -176.683976)
			(xy 353.649132 -176.658621) (xy 353.62007 -176.642522) (xy 352.696018 -176.108868) (xy 352.667463 -176.091735)
			(xy 352.614637 -176.051191) (xy 352.567553 -176.004099) (xy 352.527018 -175.951266) (xy 352.493724 -175.893595)
			(xy 352.468241 -175.832072) (xy 352.451005 -175.76775) (xy 352.44231 -175.701728) (xy 352.441764 -175.668432)
			(xy 350.121421 -175.668432) (xy 350.181477 -175.675727) (xy 350.241158 -175.69044) (xy 350.29863 -175.71224)
			(xy 350.353056 -175.740808) (xy 350.403641 -175.775729) (xy 350.449648 -175.816492) (xy 350.490406 -175.862503)
			(xy 350.525321 -175.913092) (xy 350.553883 -175.967521) (xy 350.575676 -176.024996) (xy 350.590383 -176.084678)
			(xy 350.597788 -176.145698) (xy 350.598232 -176.176432) (xy 350.597712 -176.209732) (xy 350.589036 -176.275763)
			(xy 350.571812 -176.340097) (xy 350.546334 -176.40163) (xy 350.513038 -176.459309) (xy 350.472496 -176.512145)
			(xy 350.4254 -176.559235) (xy 350.372559 -176.599772) (xy 350.343978 -176.616868) (xy 349.419926 -177.150522)
			(xy 349.390862 -177.16662) (xy 349.329459 -177.191992) (xy 349.265273 -177.20915) (xy 349.1994 -177.217802)
			(xy 349.16618 -177.21834) (xy 349.165672 -177.21834) (xy 349.134942 -177.21787) (xy 349.073929 -177.210459)
			(xy 349.014255 -177.195748) (xy 348.956789 -177.173953) (xy 348.902369 -177.145389) (xy 348.851788 -177.110475)
			(xy 348.805784 -177.069719) (xy 348.765027 -177.023715) (xy 348.730113 -176.973135) (xy 348.701549 -176.918715)
			(xy 348.679753 -176.861249) (xy 348.665041 -176.801575) (xy 348.65763 -176.740562) (xy 348.657164 -176.709832)
			(xy 2.509012 -176.709832) (xy 2.509012 -179.757832) (xy 348.657164 -179.757832) (xy 348.657658 -179.724531)
			(xy 348.666337 -179.658499) (xy 348.683566 -179.594165) (xy 348.709048 -179.532632) (xy 348.742347 -179.474953)
			(xy 348.782893 -179.422117) (xy 348.829992 -179.375027) (xy 348.882836 -179.334492) (xy 348.911418 -179.317396)
			(xy 349.83547 -178.783742) (xy 349.864533 -178.767642) (xy 349.925937 -178.742271) (xy 349.990123 -178.725114)
			(xy 350.055996 -178.716463) (xy 350.089216 -178.715924) (xy 350.089724 -178.715924) (xy 350.120458 -178.716315)
			(xy 350.181477 -178.723727) (xy 350.241158 -178.73844) (xy 350.29863 -178.76024) (xy 350.353056 -178.788808)
			(xy 350.403641 -178.823729) (xy 350.449648 -178.864492) (xy 350.490406 -178.910503) (xy 350.525321 -178.961092)
			(xy 350.553883 -179.015521) (xy 350.575676 -179.072996) (xy 350.590383 -179.132678) (xy 350.597788 -179.193698)
			(xy 350.598232 -179.224432) (xy 350.597712 -179.257732) (xy 350.589036 -179.323763) (xy 350.581628 -179.351432)
			(xy 352.441764 -179.351432) (xy 352.442268 -179.320702) (xy 352.449672 -179.259689) (xy 352.464377 -179.200013)
			(xy 352.486168 -179.142545) (xy 352.514727 -179.088122) (xy 352.549637 -179.037539) (xy 352.59039 -178.991533)
			(xy 352.636392 -178.950774) (xy 352.686971 -178.915858) (xy 352.74139 -178.887292) (xy 352.798856 -178.865495)
			(xy 352.85853 -178.850783) (xy 352.919542 -178.843371) (xy 352.950272 -178.842924) (xy 352.95078 -178.842924)
			(xy 352.983998 -178.843489) (xy 353.049869 -178.852142) (xy 353.114055 -178.869291) (xy 353.175463 -178.894645)
			(xy 353.204526 -178.910742) (xy 353.476772 -179.067968) (xy 369.614196 -179.067968) (xy 369.614752 -179.03467)
			(xy 369.623426 -178.968641) (xy 369.640648 -178.90431) (xy 369.666122 -178.842779) (xy 369.699412 -178.785101)
			(xy 369.739949 -178.732263) (xy 369.787038 -178.685171) (xy 369.839873 -178.644631) (xy 369.86845 -178.627532)
			(xy 370.792502 -178.093878) (xy 370.82156 -178.077769) (xy 370.882966 -178.0524) (xy 370.947153 -178.035245)
			(xy 371.013028 -178.026597) (xy 371.046248 -178.02606) (xy 371.046756 -178.02606) (xy 371.076835 -178.026568)
			(xy 373.398796 -178.026568) (xy 373.399226 -177.995836) (xy 373.406638 -177.934821) (xy 373.421351 -177.875144)
			(xy 373.443149 -177.817676) (xy 373.471715 -177.763254) (xy 373.506633 -177.712671) (xy 373.547392 -177.666667)
			(xy 373.5934 -177.62591) (xy 373.643984 -177.590996) (xy 373.698409 -177.562434) (xy 373.755879 -177.54064)
			(xy 373.815556 -177.525932) (xy 373.876572 -177.518524) (xy 373.907304 -177.51806) (xy 373.907812 -177.51806)
			(xy 373.941031 -177.518606) (xy 374.006903 -177.527264) (xy 374.071088 -177.544419) (xy 374.132496 -177.569778)
			(xy 374.161558 -177.585878) (xy 375.08561 -178.119532) (xy 375.114171 -178.136654) (xy 375.166997 -178.177201)
			(xy 375.214079 -178.224295) (xy 375.254613 -178.27713) (xy 375.287906 -178.334802) (xy 375.313388 -178.396326)
			(xy 375.330623 -178.460649) (xy 375.339318 -178.526672) (xy 375.339864 -178.559968) (xy 375.339432 -178.590701)
			(xy 375.332026 -178.65172) (xy 375.317319 -178.7114) (xy 375.295524 -178.768873) (xy 375.266961 -178.823299)
			(xy 375.232044 -178.873885) (xy 375.191284 -178.919893) (xy 375.145275 -178.960651) (xy 375.094689 -178.995567)
			(xy 375.040262 -179.024129) (xy 374.982789 -179.045923) (xy 374.923108 -179.060629) (xy 374.862089 -179.068033)
			(xy 374.831356 -179.068476) (xy 374.830848 -179.068476) (xy 374.797629 -179.067942) (xy 374.731757 -179.05928)
			(xy 374.667571 -179.042122) (xy 374.606164 -179.016759) (xy 374.577102 -179.000658) (xy 373.65305 -178.467004)
			(xy 373.624495 -178.449872) (xy 373.571672 -178.409325) (xy 373.524591 -178.362232) (xy 373.484057 -178.309398)
			(xy 373.450764 -178.251727) (xy 373.42528 -178.190205) (xy 373.408042 -178.125884) (xy 373.399344 -178.059863)
			(xy 373.398796 -178.026568) (xy 371.076835 -178.026568) (xy 371.077486 -178.026579) (xy 371.138498 -178.033982)
			(xy 371.198173 -178.048685) (xy 371.255641 -178.070475) (xy 371.310063 -178.099032) (xy 371.360647 -178.133941)
			(xy 371.406653 -178.174693) (xy 371.447412 -178.220694) (xy 371.482329 -178.271272) (xy 371.510894 -178.325689)
			(xy 371.532692 -178.383154) (xy 371.547404 -178.442827) (xy 371.554816 -178.503838) (xy 371.555264 -178.534568)
			(xy 371.554757 -178.567868) (xy 371.546077 -178.6339) (xy 371.52885 -178.698232) (xy 371.503369 -178.759765)
			(xy 371.470072 -178.817443) (xy 371.429528 -178.87028) (xy 371.382432 -178.91737) (xy 371.329591 -178.957907)
			(xy 371.30101 -178.975004) (xy 370.376958 -179.508658) (xy 370.34791 -179.524786) (xy 370.2865 -179.55015)
			(xy 370.22231 -179.567299) (xy 370.156433 -179.575942) (xy 370.123212 -179.576476) (xy 370.122704 -179.576476)
			(xy 370.091971 -179.576059) (xy 370.030952 -179.56865) (xy 369.971272 -179.55394) (xy 369.9138 -179.532143)
			(xy 369.859375 -179.503577) (xy 369.808789 -179.468659) (xy 369.762782 -179.427898) (xy 369.722023 -179.381889)
			(xy 369.687108 -179.331301) (xy 369.658546 -179.276874) (xy 369.636752 -179.219401) (xy 369.622045 -179.15972)
			(xy 369.61464 -179.098701) (xy 369.614196 -179.067968) (xy 353.476772 -179.067968) (xy 354.128578 -179.444396)
			(xy 354.157139 -179.461518) (xy 354.209962 -179.502067) (xy 354.257042 -179.549162) (xy 354.297574 -179.601998)
			(xy 354.330866 -179.65967) (xy 354.356349 -179.721193) (xy 354.373586 -179.785515) (xy 354.382284 -179.851536)
			(xy 354.382832 -179.884832) (xy 354.382374 -179.915563) (xy 354.374962 -179.976576) (xy 354.360251 -180.036251)
			(xy 354.338454 -180.093717) (xy 354.30989 -180.148138) (xy 354.274975 -180.198719) (xy 354.234218 -180.244723)
			(xy 354.188213 -180.28548) (xy 354.137631 -180.320394) (xy 354.08321 -180.348957) (xy 354.025743 -180.370753)
			(xy 353.966068 -180.385464) (xy 353.905055 -180.392875) (xy 353.874324 -180.39334) (xy 353.873816 -180.39334)
			(xy 353.840597 -180.392782) (xy 353.774726 -180.384127) (xy 353.710541 -180.366976) (xy 353.649132 -180.341621)
			(xy 353.62007 -180.325522) (xy 352.696018 -179.791868) (xy 352.667463 -179.774735) (xy 352.614637 -179.734191)
			(xy 352.567553 -179.687099) (xy 352.527018 -179.634266) (xy 352.493724 -179.576595) (xy 352.468241 -179.515072)
			(xy 352.451005 -179.45075) (xy 352.44231 -179.384728) (xy 352.441764 -179.351432) (xy 350.581628 -179.351432)
			(xy 350.571812 -179.388097) (xy 350.546334 -179.44963) (xy 350.513038 -179.507309) (xy 350.472496 -179.560145)
			(xy 350.4254 -179.607235) (xy 350.372559 -179.647772) (xy 350.343978 -179.664868) (xy 349.419926 -180.198522)
			(xy 349.390862 -180.21462) (xy 349.329459 -180.239992) (xy 349.265273 -180.25715) (xy 349.1994 -180.265802)
			(xy 349.16618 -180.26634) (xy 349.165672 -180.26634) (xy 349.134942 -180.26587) (xy 349.073929 -180.258459)
			(xy 349.014255 -180.243748) (xy 348.956789 -180.221953) (xy 348.902369 -180.193389) (xy 348.851788 -180.158475)
			(xy 348.805784 -180.117719) (xy 348.765027 -180.071715) (xy 348.730113 -180.021135) (xy 348.701549 -179.966715)
			(xy 348.679753 -179.909249) (xy 348.665041 -179.849575) (xy 348.65763 -179.788562) (xy 348.657164 -179.757832)
			(xy 2.509012 -179.757832) (xy 2.509012 -182.805832) (xy 348.657164 -182.805832) (xy 348.657658 -182.772531)
			(xy 348.666337 -182.706499) (xy 348.683566 -182.642165) (xy 348.709048 -182.580632) (xy 348.742347 -182.522953)
			(xy 348.782893 -182.470117) (xy 348.829992 -182.423027) (xy 348.882836 -182.382492) (xy 348.911418 -182.365396)
			(xy 349.83547 -181.831742) (xy 349.864533 -181.815642) (xy 349.925937 -181.790271) (xy 349.990123 -181.773114)
			(xy 350.055996 -181.764463) (xy 350.089216 -181.763924) (xy 350.089724 -181.763924) (xy 350.120458 -181.764315)
			(xy 350.181477 -181.771727) (xy 350.241158 -181.78644) (xy 350.29863 -181.80824) (xy 350.353056 -181.836808)
			(xy 350.403641 -181.871729) (xy 350.449648 -181.912492) (xy 350.490406 -181.958503) (xy 350.525321 -182.009092)
			(xy 350.553883 -182.063521) (xy 350.57377 -182.115968) (xy 369.614196 -182.115968) (xy 369.614752 -182.08267)
			(xy 369.623426 -182.016641) (xy 369.640648 -181.95231) (xy 369.666122 -181.890779) (xy 369.699412 -181.833101)
			(xy 369.739949 -181.780263) (xy 369.787038 -181.733171) (xy 369.839873 -181.692631) (xy 369.86845 -181.675532)
			(xy 370.792502 -181.141878) (xy 370.82156 -181.125769) (xy 370.882966 -181.1004) (xy 370.947153 -181.083245)
			(xy 371.013028 -181.074597) (xy 371.046248 -181.07406) (xy 371.046756 -181.07406) (xy 371.077486 -181.074579)
			(xy 371.138498 -181.081982) (xy 371.198173 -181.096685) (xy 371.255641 -181.118475) (xy 371.310063 -181.147032)
			(xy 371.360647 -181.181941) (xy 371.406653 -181.222693) (xy 371.447412 -181.268694) (xy 371.482329 -181.319272)
			(xy 371.510894 -181.373689) (xy 371.532692 -181.431154) (xy 371.547404 -181.490827) (xy 371.554816 -181.551838)
			(xy 371.555264 -181.582568) (xy 371.554757 -181.615868) (xy 371.546077 -181.6819) (xy 371.538668 -181.709568)
			(xy 373.398796 -181.709568) (xy 373.399226 -181.678836) (xy 373.406638 -181.617821) (xy 373.421351 -181.558144)
			(xy 373.443149 -181.500676) (xy 373.471715 -181.446254) (xy 373.506633 -181.395671) (xy 373.547392 -181.349667)
			(xy 373.5934 -181.30891) (xy 373.643984 -181.273996) (xy 373.698409 -181.245434) (xy 373.755879 -181.22364)
			(xy 373.815556 -181.208932) (xy 373.876572 -181.201524) (xy 373.907304 -181.20106) (xy 373.907812 -181.20106)
			(xy 373.941031 -181.201606) (xy 374.006903 -181.210264) (xy 374.071088 -181.227419) (xy 374.132496 -181.252778)
			(xy 374.161558 -181.268878) (xy 375.08561 -181.802532) (xy 375.114171 -181.819654) (xy 375.166997 -181.860201)
			(xy 375.214079 -181.907295) (xy 375.254613 -181.96013) (xy 375.287906 -182.017802) (xy 375.313388 -182.079326)
			(xy 375.330623 -182.143649) (xy 375.339318 -182.209672) (xy 375.339864 -182.242968) (xy 375.339432 -182.273701)
			(xy 375.332026 -182.33472) (xy 375.317319 -182.3944) (xy 375.295524 -182.451873) (xy 375.266961 -182.506299)
			(xy 375.232044 -182.556885) (xy 375.191284 -182.602893) (xy 375.145275 -182.643651) (xy 375.094689 -182.678567)
			(xy 375.040262 -182.707129) (xy 374.982789 -182.728923) (xy 374.923108 -182.743629) (xy 374.862089 -182.751033)
			(xy 374.831356 -182.751476) (xy 374.830848 -182.751476) (xy 374.797629 -182.750942) (xy 374.731757 -182.74228)
			(xy 374.667571 -182.725122) (xy 374.606164 -182.699759) (xy 374.577102 -182.683658) (xy 373.65305 -182.150004)
			(xy 373.624495 -182.132872) (xy 373.571672 -182.092325) (xy 373.524591 -182.045232) (xy 373.484057 -181.992398)
			(xy 373.450764 -181.934727) (xy 373.42528 -181.873205) (xy 373.408042 -181.808884) (xy 373.399344 -181.742863)
			(xy 373.398796 -181.709568) (xy 371.538668 -181.709568) (xy 371.52885 -181.746232) (xy 371.503369 -181.807765)
			(xy 371.470072 -181.865443) (xy 371.429528 -181.91828) (xy 371.382432 -181.96537) (xy 371.329591 -182.005907)
			(xy 371.30101 -182.023004) (xy 370.376958 -182.556658) (xy 370.34791 -182.572786) (xy 370.2865 -182.59815)
			(xy 370.22231 -182.615299) (xy 370.156433 -182.623942) (xy 370.123212 -182.624476) (xy 370.122704 -182.624476)
			(xy 370.091971 -182.624059) (xy 370.030952 -182.61665) (xy 369.971272 -182.60194) (xy 369.9138 -182.580143)
			(xy 369.859375 -182.551577) (xy 369.808789 -182.516659) (xy 369.762782 -182.475898) (xy 369.722023 -182.429889)
			(xy 369.687108 -182.379301) (xy 369.658546 -182.324874) (xy 369.636752 -182.267401) (xy 369.622045 -182.20772)
			(xy 369.61464 -182.146701) (xy 369.614196 -182.115968) (xy 350.57377 -182.115968) (xy 350.575676 -182.120996)
			(xy 350.590383 -182.180678) (xy 350.597788 -182.241698) (xy 350.598232 -182.272432) (xy 350.597712 -182.305732)
			(xy 350.589036 -182.371763) (xy 350.571812 -182.436097) (xy 350.546334 -182.49763) (xy 350.513038 -182.555309)
			(xy 350.472496 -182.608145) (xy 350.4254 -182.655235) (xy 350.372559 -182.695772) (xy 350.343978 -182.712868)
			(xy 349.775297 -183.04129) (xy 352.441764 -183.04129) (xy 352.442192 -183.010552) (xy 352.449601 -182.949525)
			(xy 352.46431 -182.889835) (xy 352.486105 -182.832352) (xy 352.514667 -182.777914) (xy 352.549581 -182.727315)
			(xy 352.590338 -182.681292) (xy 352.636344 -182.640516) (xy 352.686928 -182.60558) (xy 352.741353 -182.576994)
			(xy 352.798826 -182.555175) (xy 352.85851 -182.540441) (xy 352.919534 -182.533005) (xy 352.950272 -182.532528)
			(xy 352.95078 -182.532528) (xy 352.984007 -182.533118) (xy 353.049889 -182.541823) (xy 353.114077 -182.559036)
			(xy 353.175475 -182.584464) (xy 353.204526 -182.6006) (xy 354.128578 -183.134254) (xy 354.157165 -183.151335)
			(xy 354.209988 -183.19189) (xy 354.257067 -183.238991) (xy 354.297597 -183.291832) (xy 354.330886 -183.34951)
			(xy 354.356365 -183.411039) (xy 354.373597 -183.475367) (xy 354.382288 -183.541392) (xy 354.382832 -183.57469)
			(xy 354.382389 -183.605428) (xy 354.374982 -183.666455) (xy 354.360275 -183.726145) (xy 354.338483 -183.783627)
			(xy 354.309922 -183.838065) (xy 354.275009 -183.888665) (xy 354.234254 -183.934688) (xy 354.188249 -183.975465)
			(xy 354.137666 -184.010401) (xy 354.083241 -184.038987) (xy 354.025768 -184.060806) (xy 353.966085 -184.07554)
			(xy 353.905061 -184.082975) (xy 353.874324 -184.083452) (xy 353.873816 -184.083452) (xy 353.840589 -184.082867)
			(xy 353.774706 -184.07416) (xy 353.710519 -184.056946) (xy 353.649121 -184.031517) (xy 353.62007 -184.01538)
			(xy 352.696018 -183.481726) (xy 352.667489 -183.464552) (xy 352.614663 -183.424014) (xy 352.567578 -183.376928)
			(xy 352.527041 -183.324101) (xy 352.493744 -183.266436) (xy 352.468257 -183.204918) (xy 352.451015 -183.140601)
			(xy 352.442314 -183.074584) (xy 352.441764 -183.04129) (xy 349.775297 -183.04129) (xy 349.419926 -183.246522)
			(xy 349.390862 -183.26262) (xy 349.329459 -183.287992) (xy 349.265273 -183.30515) (xy 349.1994 -183.313802)
			(xy 349.16618 -183.31434) (xy 349.165672 -183.31434) (xy 349.134942 -183.31387) (xy 349.073929 -183.306459)
			(xy 349.014255 -183.291748) (xy 348.956789 -183.269953) (xy 348.902369 -183.241389) (xy 348.851788 -183.206475)
			(xy 348.805784 -183.165719) (xy 348.765027 -183.119715) (xy 348.730113 -183.069135) (xy 348.701549 -183.014715)
			(xy 348.679753 -182.957249) (xy 348.665041 -182.897575) (xy 348.65763 -182.836562) (xy 348.657164 -182.805832)
			(xy 2.509012 -182.805832) (xy 2.509012 -185.011568) (xy 372.585996 -185.011568) (xy 372.586426 -184.980836)
			(xy 372.593838 -184.919821) (xy 372.608551 -184.860144) (xy 372.630349 -184.802676) (xy 372.658915 -184.748254)
			(xy 372.693833 -184.697671) (xy 372.734592 -184.651667) (xy 372.7806 -184.61091) (xy 372.831184 -184.575996)
			(xy 372.885609 -184.547434) (xy 372.943079 -184.52564) (xy 373.002756 -184.510932) (xy 373.063772 -184.503524)
			(xy 373.094504 -184.50306) (xy 373.095012 -184.50306) (xy 373.128231 -184.503606) (xy 373.194103 -184.512264)
			(xy 373.258288 -184.529419) (xy 373.319696 -184.554778) (xy 373.348758 -184.570878) (xy 374.27281 -185.104532)
			(xy 374.301371 -185.121654) (xy 374.354197 -185.162201) (xy 374.401279 -185.209295) (xy 374.441813 -185.26213)
			(xy 374.475106 -185.319802) (xy 374.500588 -185.381326) (xy 374.517823 -185.445649) (xy 374.526518 -185.511672)
			(xy 374.527064 -185.544968) (xy 374.526632 -185.575701) (xy 374.519226 -185.63672) (xy 374.504519 -185.6964)
			(xy 374.482724 -185.753873) (xy 374.454161 -185.808299) (xy 374.419244 -185.858885) (xy 374.378484 -185.904893)
			(xy 374.332475 -185.945651) (xy 374.281889 -185.980567) (xy 374.227462 -186.009129) (xy 374.169989 -186.030923)
			(xy 374.110308 -186.045629) (xy 374.049289 -186.053033) (xy 374.018556 -186.053476) (xy 374.018048 -186.053476)
			(xy 373.984829 -186.052942) (xy 373.918957 -186.04428) (xy 373.854771 -186.027122) (xy 373.793364 -186.001759)
			(xy 373.764302 -185.985658) (xy 372.84025 -185.452004) (xy 372.811695 -185.434872) (xy 372.758872 -185.394325)
			(xy 372.711791 -185.347232) (xy 372.671257 -185.294398) (xy 372.637964 -185.236727) (xy 372.61248 -185.175205)
			(xy 372.595242 -185.110884) (xy 372.586544 -185.044863) (xy 372.585996 -185.011568) (xy 2.509012 -185.011568)
			(xy 2.509012 -186.714892) (xy 351.367344 -186.714892) (xy 351.367848 -186.684163) (xy 351.375257 -186.623152)
			(xy 351.389965 -186.563479) (xy 351.411758 -186.506014) (xy 351.440318 -186.451595) (xy 351.475229 -186.401014)
			(xy 351.515982 -186.355011) (xy 351.561983 -186.314254) (xy 351.612561 -186.279339) (xy 351.666978 -186.250774)
			(xy 351.724441 -186.228977) (xy 351.784113 -186.214264) (xy 351.845123 -186.206851) (xy 351.875852 -186.206384)
			(xy 351.87636 -186.206384) (xy 351.90958 -186.206906) (xy 351.975453 -186.215571) (xy 352.039638 -186.232732)
			(xy 352.101045 -186.258098) (xy 352.130106 -186.274202) (xy 353.054158 -186.807856) (xy 353.082741 -186.824943)
			(xy 353.135565 -186.865496) (xy 353.182645 -186.912596) (xy 353.223176 -186.965436) (xy 353.256466 -187.023114)
			(xy 353.281945 -187.084642) (xy 353.299177 -187.148969) (xy 353.307868 -187.214995) (xy 353.308412 -187.248292)
			(xy 353.307955 -187.279024) (xy 353.300547 -187.340039) (xy 353.285839 -187.399717) (xy 353.264044 -187.457187)
			(xy 353.235482 -187.51161) (xy 353.200567 -187.562194) (xy 353.15981 -187.608201) (xy 353.113804 -187.648959)
			(xy 353.063221 -187.683875) (xy 353.008798 -187.712439) (xy 352.951329 -187.734235) (xy 352.891651 -187.748945)
			(xy 352.830636 -187.756354) (xy 352.799904 -187.7568) (xy 352.799396 -187.7568) (xy 352.766177 -187.756256)
			(xy 352.700305 -187.747598) (xy 352.636119 -187.730443) (xy 352.574711 -187.705083) (xy 352.54565 -187.688982)
			(xy 351.621598 -187.155328) (xy 351.593065 -187.13816) (xy 351.54024 -187.09762) (xy 351.493156 -187.050533)
			(xy 351.45262 -186.997705) (xy 351.419323 -186.940039) (xy 351.393837 -186.878521) (xy 351.376595 -186.814204)
			(xy 351.367894 -186.748186) (xy 351.367344 -186.714892) (xy 2.509012 -186.714892) (xy 2.509012 -206.024988)
			(xy 86.700624 -206.024988) (xy 86.704605 -205.891968) (xy 86.716534 -205.759423) (xy 86.736369 -205.62783)
			(xy 86.764038 -205.497658) (xy 86.799442 -205.369373) (xy 86.842455 -205.243436) (xy 86.892922 -205.120297)
			(xy 86.950663 -205.000396) (xy 87.015472 -204.884163) (xy 87.087116 -204.772013) (xy 87.165338 -204.664349)
			(xy 87.249859 -204.561556) (xy 87.340377 -204.464001) (xy 87.436566 -204.372035) (xy 87.538084 -204.285985)
			(xy 87.644565 -204.206161) (xy 87.75563 -204.132848) (xy 87.870881 -204.066308) (xy 87.989905 -204.006779)
			(xy 88.112276 -203.954475) (xy 88.237555 -203.909583) (xy 88.365296 -203.872264) (xy 88.495039 -203.842651)
			(xy 88.626321 -203.82085) (xy 88.758672 -203.80694) (xy 88.891618 -203.800969) (xy 89.024683 -203.80296)
			(xy 89.157391 -203.812905) (xy 89.289267 -203.830769) (xy 89.419838 -203.856487) (xy 89.548638 -203.889968)
			(xy 89.675204 -203.931092) (xy 89.799085 -203.979712) (xy 89.919836 -204.035653) (xy 90.037026 -204.098715)
			(xy 90.150235 -204.168673) (xy 90.259057 -204.245277) (xy 90.363103 -204.328251) (xy 90.462001 -204.417299)
			(xy 90.555396 -204.512102) (xy 90.642954 -204.61232) (xy 90.724363 -204.717596) (xy 90.799329 -204.827552)
			(xy 90.867586 -204.941794) (xy 90.928888 -205.059914) (xy 90.983017 -205.181489) (xy 91.029778 -205.306083)
			(xy 91.069004 -205.433251) (xy 91.100554 -205.562537) (xy 91.124317 -205.693478) (xy 91.140206 -205.825606)
			(xy 91.148164 -205.958448) (xy 91.148662 -206.024988) (xy 132.710692 -206.024988) (xy 132.714673 -205.891968)
			(xy 132.726602 -205.759423) (xy 132.746437 -205.62783) (xy 132.774106 -205.497658) (xy 132.80951 -205.369373)
			(xy 132.852523 -205.243436) (xy 132.90299 -205.120297) (xy 132.960731 -205.000396) (xy 133.02554 -204.884163)
			(xy 133.097184 -204.772013) (xy 133.175406 -204.664349) (xy 133.259927 -204.561556) (xy 133.350445 -204.464001)
			(xy 133.446634 -204.372035) (xy 133.548152 -204.285985) (xy 133.654633 -204.206161) (xy 133.765698 -204.132848)
			(xy 133.880949 -204.066308) (xy 133.999973 -204.006779) (xy 134.122344 -203.954475) (xy 134.247623 -203.909583)
			(xy 134.375364 -203.872264) (xy 134.505107 -203.842651) (xy 134.636389 -203.82085) (xy 134.76874 -203.80694)
			(xy 134.901686 -203.800969) (xy 135.034751 -203.80296) (xy 135.167459 -203.812905) (xy 135.299335 -203.830769)
			(xy 135.429906 -203.856487) (xy 135.558706 -203.889968) (xy 135.685272 -203.931092) (xy 135.809153 -203.979712)
			(xy 135.929904 -204.035653) (xy 136.047094 -204.098715) (xy 136.160303 -204.168673) (xy 136.269125 -204.245277)
			(xy 136.373171 -204.328251) (xy 136.472069 -204.417299) (xy 136.565464 -204.512102) (xy 136.653022 -204.61232)
			(xy 136.734431 -204.717596) (xy 136.809397 -204.827552) (xy 136.877654 -204.941794) (xy 136.938956 -205.059914)
			(xy 136.993085 -205.181489) (xy 137.039846 -205.306083) (xy 137.079072 -205.433251) (xy 137.110622 -205.562537)
			(xy 137.134385 -205.693478) (xy 137.150274 -205.825606) (xy 137.158232 -205.958448) (xy 137.15873 -206.024988)
			(xy 334.640692 -206.024988) (xy 334.644673 -205.891968) (xy 334.656602 -205.759423) (xy 334.676437 -205.62783)
			(xy 334.704106 -205.497658) (xy 334.73951 -205.369373) (xy 334.782523 -205.243436) (xy 334.83299 -205.120297)
			(xy 334.890731 -205.000396) (xy 334.95554 -204.884163) (xy 335.027184 -204.772013) (xy 335.105406 -204.664349)
			(xy 335.189927 -204.561556) (xy 335.280445 -204.464001) (xy 335.376634 -204.372035) (xy 335.478152 -204.285985)
			(xy 335.584633 -204.206161) (xy 335.695698 -204.132848) (xy 335.810949 -204.066308) (xy 335.929973 -204.006779)
			(xy 336.052344 -203.954475) (xy 336.177623 -203.909583) (xy 336.305364 -203.872264) (xy 336.435107 -203.842651)
			(xy 336.566389 -203.82085) (xy 336.69874 -203.80694) (xy 336.831686 -203.800969) (xy 336.964751 -203.80296)
			(xy 337.097459 -203.812905) (xy 337.229335 -203.830769) (xy 337.359906 -203.856487) (xy 337.488706 -203.889968)
			(xy 337.615272 -203.931092) (xy 337.739153 -203.979712) (xy 337.859904 -204.035653) (xy 337.977094 -204.098715)
			(xy 338.090303 -204.168673) (xy 338.199125 -204.245277) (xy 338.303171 -204.328251) (xy 338.402069 -204.417299)
			(xy 338.495464 -204.512102) (xy 338.583022 -204.61232) (xy 338.664431 -204.717596) (xy 338.739397 -204.827552)
			(xy 338.807654 -204.941794) (xy 338.868956 -205.059914) (xy 338.923085 -205.181489) (xy 338.969846 -205.306083)
			(xy 339.009072 -205.433251) (xy 339.040622 -205.562537) (xy 339.064385 -205.693478) (xy 339.080274 -205.825606)
			(xy 339.088232 -205.958448) (xy 339.08873 -206.024988) (xy 380.650506 -206.024988) (xy 380.654487 -205.891968)
			(xy 380.666416 -205.759423) (xy 380.686251 -205.62783) (xy 380.71392 -205.497658) (xy 380.749324 -205.369373)
			(xy 380.792337 -205.243436) (xy 380.842804 -205.120297) (xy 380.900545 -205.000396) (xy 380.965354 -204.884163)
			(xy 381.036998 -204.772013) (xy 381.11522 -204.664349) (xy 381.199741 -204.561556) (xy 381.290259 -204.464001)
			(xy 381.386448 -204.372035) (xy 381.487966 -204.285985) (xy 381.594447 -204.206161) (xy 381.705512 -204.132848)
			(xy 381.820763 -204.066308) (xy 381.939787 -204.006779) (xy 382.062158 -203.954475) (xy 382.187437 -203.909583)
			(xy 382.315178 -203.872264) (xy 382.444921 -203.842651) (xy 382.576203 -203.82085) (xy 382.708554 -203.80694)
			(xy 382.8415 -203.800969) (xy 382.974565 -203.80296) (xy 383.107273 -203.812905) (xy 383.239149 -203.830769)
			(xy 383.36972 -203.856487) (xy 383.49852 -203.889968) (xy 383.625086 -203.931092) (xy 383.748967 -203.979712)
			(xy 383.869718 -204.035653) (xy 383.986908 -204.098715) (xy 384.100117 -204.168673) (xy 384.208939 -204.245277)
			(xy 384.312985 -204.328251) (xy 384.411883 -204.417299) (xy 384.505278 -204.512102) (xy 384.592836 -204.61232)
			(xy 384.674245 -204.717596) (xy 384.749211 -204.827552) (xy 384.817468 -204.941794) (xy 384.87877 -205.059914)
			(xy 384.932899 -205.181489) (xy 384.97966 -205.306083) (xy 385.018886 -205.433251) (xy 385.050436 -205.562537)
			(xy 385.074199 -205.693478) (xy 385.090088 -205.825606) (xy 385.098046 -205.958448) (xy 385.098544 -206.024988)
			(xy 385.098046 -206.091528) (xy 385.090088 -206.22437) (xy 385.074199 -206.356498) (xy 385.050436 -206.487439)
			(xy 385.018886 -206.616725) (xy 384.97966 -206.743893) (xy 384.932899 -206.868487) (xy 384.87877 -206.990062)
			(xy 384.817468 -207.108182) (xy 384.749211 -207.222424) (xy 384.674245 -207.33238) (xy 384.592836 -207.437656)
			(xy 384.505278 -207.537874) (xy 384.411883 -207.632677) (xy 384.312985 -207.721725) (xy 384.208939 -207.804699)
			(xy 384.100117 -207.881303) (xy 383.986908 -207.951261) (xy 383.869718 -208.014323) (xy 383.748967 -208.070264)
			(xy 383.625086 -208.118884) (xy 383.49852 -208.160008) (xy 383.36972 -208.193489) (xy 383.239149 -208.219207)
			(xy 383.107273 -208.237071) (xy 382.974565 -208.247016) (xy 382.8415 -208.249007) (xy 382.708554 -208.243036)
			(xy 382.576203 -208.229126) (xy 382.444921 -208.207325) (xy 382.315178 -208.177712) (xy 382.187437 -208.140393)
			(xy 382.062158 -208.095501) (xy 381.939787 -208.043197) (xy 381.820763 -207.983668) (xy 381.705512 -207.917128)
			(xy 381.594447 -207.843815) (xy 381.487966 -207.763991) (xy 381.386448 -207.677941) (xy 381.290259 -207.585975)
			(xy 381.199741 -207.48842) (xy 381.11522 -207.385627) (xy 381.036998 -207.277963) (xy 380.965354 -207.165813)
			(xy 380.900545 -207.04958) (xy 380.842804 -206.929679) (xy 380.792337 -206.80654) (xy 380.749324 -206.680603)
			(xy 380.71392 -206.552318) (xy 380.686251 -206.422146) (xy 380.666416 -206.290553) (xy 380.654487 -206.158008)
			(xy 380.650506 -206.024988) (xy 339.08873 -206.024988) (xy 339.088232 -206.091528) (xy 339.080274 -206.22437)
			(xy 339.064385 -206.356498) (xy 339.040622 -206.487439) (xy 339.009072 -206.616725) (xy 338.969846 -206.743893)
			(xy 338.923085 -206.868487) (xy 338.868956 -206.990062) (xy 338.807654 -207.108182) (xy 338.739397 -207.222424)
			(xy 338.664431 -207.33238) (xy 338.583022 -207.437656) (xy 338.495464 -207.537874) (xy 338.402069 -207.632677)
			(xy 338.303171 -207.721725) (xy 338.199125 -207.804699) (xy 338.090303 -207.881303) (xy 337.977094 -207.951261)
			(xy 337.859904 -208.014323) (xy 337.739153 -208.070264) (xy 337.615272 -208.118884) (xy 337.488706 -208.160008)
			(xy 337.359906 -208.193489) (xy 337.229335 -208.219207) (xy 337.097459 -208.237071) (xy 336.964751 -208.247016)
			(xy 336.831686 -208.249007) (xy 336.69874 -208.243036) (xy 336.566389 -208.229126) (xy 336.435107 -208.207325)
			(xy 336.305364 -208.177712) (xy 336.177623 -208.140393) (xy 336.052344 -208.095501) (xy 335.929973 -208.043197)
			(xy 335.810949 -207.983668) (xy 335.695698 -207.917128) (xy 335.584633 -207.843815) (xy 335.478152 -207.763991)
			(xy 335.376634 -207.677941) (xy 335.280445 -207.585975) (xy 335.189927 -207.48842) (xy 335.105406 -207.385627)
			(xy 335.027184 -207.277963) (xy 334.95554 -207.165813) (xy 334.890731 -207.04958) (xy 334.83299 -206.929679)
			(xy 334.782523 -206.80654) (xy 334.73951 -206.680603) (xy 334.704106 -206.552318) (xy 334.676437 -206.422146)
			(xy 334.656602 -206.290553) (xy 334.644673 -206.158008) (xy 334.640692 -206.024988) (xy 137.15873 -206.024988)
			(xy 137.158232 -206.091528) (xy 137.150274 -206.22437) (xy 137.134385 -206.356498) (xy 137.110622 -206.487439)
			(xy 137.079072 -206.616725) (xy 137.039846 -206.743893) (xy 136.993085 -206.868487) (xy 136.938956 -206.990062)
			(xy 136.877654 -207.108182) (xy 136.809397 -207.222424) (xy 136.734431 -207.33238) (xy 136.653022 -207.437656)
			(xy 136.565464 -207.537874) (xy 136.472069 -207.632677) (xy 136.373171 -207.721725) (xy 136.269125 -207.804699)
			(xy 136.160303 -207.881303) (xy 136.047094 -207.951261) (xy 135.929904 -208.014323) (xy 135.809153 -208.070264)
			(xy 135.685272 -208.118884) (xy 135.558706 -208.160008) (xy 135.429906 -208.193489) (xy 135.299335 -208.219207)
			(xy 135.167459 -208.237071) (xy 135.034751 -208.247016) (xy 134.901686 -208.249007) (xy 134.76874 -208.243036)
			(xy 134.636389 -208.229126) (xy 134.505107 -208.207325) (xy 134.375364 -208.177712) (xy 134.247623 -208.140393)
			(xy 134.122344 -208.095501) (xy 133.999973 -208.043197) (xy 133.880949 -207.983668) (xy 133.765698 -207.917128)
			(xy 133.654633 -207.843815) (xy 133.548152 -207.763991) (xy 133.446634 -207.677941) (xy 133.350445 -207.585975)
			(xy 133.259927 -207.48842) (xy 133.175406 -207.385627) (xy 133.097184 -207.277963) (xy 133.02554 -207.165813)
			(xy 132.960731 -207.04958) (xy 132.90299 -206.929679) (xy 132.852523 -206.80654) (xy 132.80951 -206.680603)
			(xy 132.774106 -206.552318) (xy 132.746437 -206.422146) (xy 132.726602 -206.290553) (xy 132.714673 -206.158008)
			(xy 132.710692 -206.024988) (xy 91.148662 -206.024988) (xy 91.148164 -206.091528) (xy 91.140206 -206.22437)
			(xy 91.124317 -206.356498) (xy 91.100554 -206.487439) (xy 91.069004 -206.616725) (xy 91.029778 -206.743893)
			(xy 90.983017 -206.868487) (xy 90.928888 -206.990062) (xy 90.867586 -207.108182) (xy 90.799329 -207.222424)
			(xy 90.724363 -207.33238) (xy 90.642954 -207.437656) (xy 90.555396 -207.537874) (xy 90.462001 -207.632677)
			(xy 90.363103 -207.721725) (xy 90.259057 -207.804699) (xy 90.150235 -207.881303) (xy 90.037026 -207.951261)
			(xy 89.919836 -208.014323) (xy 89.799085 -208.070264) (xy 89.675204 -208.118884) (xy 89.548638 -208.160008)
			(xy 89.419838 -208.193489) (xy 89.289267 -208.219207) (xy 89.157391 -208.237071) (xy 89.024683 -208.247016)
			(xy 88.891618 -208.249007) (xy 88.758672 -208.243036) (xy 88.626321 -208.229126) (xy 88.495039 -208.207325)
			(xy 88.365296 -208.177712) (xy 88.237555 -208.140393) (xy 88.112276 -208.095501) (xy 87.989905 -208.043197)
			(xy 87.870881 -207.983668) (xy 87.75563 -207.917128) (xy 87.644565 -207.843815) (xy 87.538084 -207.763991)
			(xy 87.436566 -207.677941) (xy 87.340377 -207.585975) (xy 87.249859 -207.48842) (xy 87.165338 -207.385627)
			(xy 87.087116 -207.277963) (xy 87.015472 -207.165813) (xy 86.950663 -207.04958) (xy 86.892922 -206.929679)
			(xy 86.842455 -206.80654) (xy 86.799442 -206.680603) (xy 86.764038 -206.552318) (xy 86.736369 -206.422146)
			(xy 86.716534 -206.290553) (xy 86.704605 -206.158008) (xy 86.700624 -206.024988) (xy 2.509012 -206.024988)
			(xy 2.509012 -213.732618) (xy 90.165428 -213.732618) (xy 90.165936 -213.706731) (xy 90.174035 -213.655593)
			(xy 90.190034 -213.606353) (xy 90.21354 -213.560221) (xy 90.243972 -213.518334) (xy 90.280582 -213.481724)
			(xy 90.322469 -213.451292) (xy 90.368601 -213.427786) (xy 90.417841 -213.411787) (xy 90.468979 -213.403688)
			(xy 90.520753 -213.403688) (xy 90.571891 -213.411787) (xy 90.621131 -213.427786) (xy 90.667263 -213.451292)
			(xy 90.70915 -213.481724) (xy 90.74576 -213.518334) (xy 90.776192 -213.560221) (xy 90.799698 -213.606353)
			(xy 90.815697 -213.655593) (xy 90.823796 -213.706731) (xy 90.824304 -213.732618) (xy 92.045028 -213.732618)
			(xy 92.045536 -213.706731) (xy 92.053635 -213.655593) (xy 92.069634 -213.606353) (xy 92.09314 -213.560221)
			(xy 92.123572 -213.518334) (xy 92.160182 -213.481724) (xy 92.202069 -213.451292) (xy 92.248201 -213.427786)
			(xy 92.297441 -213.411787) (xy 92.348579 -213.403688) (xy 92.400353 -213.403688) (xy 92.451491 -213.411787)
			(xy 92.500731 -213.427786) (xy 92.546863 -213.451292) (xy 92.58875 -213.481724) (xy 92.62536 -213.518334)
			(xy 92.655792 -213.560221) (xy 92.679298 -213.606353) (xy 92.695297 -213.655593) (xy 92.703396 -213.706731)
			(xy 92.703904 -213.732618) (xy 93.924628 -213.732618) (xy 93.925136 -213.706731) (xy 93.933235 -213.655593)
			(xy 93.949234 -213.606353) (xy 93.97274 -213.560221) (xy 94.003172 -213.518334) (xy 94.039782 -213.481724)
			(xy 94.081669 -213.451292) (xy 94.127801 -213.427786) (xy 94.177041 -213.411787) (xy 94.228179 -213.403688)
			(xy 94.279953 -213.403688) (xy 94.331091 -213.411787) (xy 94.380331 -213.427786) (xy 94.426463 -213.451292)
			(xy 94.46835 -213.481724) (xy 94.50496 -213.518334) (xy 94.535392 -213.560221) (xy 94.558898 -213.606353)
			(xy 94.574897 -213.655593) (xy 94.582996 -213.706731) (xy 94.583504 -213.732618) (xy 95.804228 -213.732618)
			(xy 95.804736 -213.706731) (xy 95.812835 -213.655593) (xy 95.828834 -213.606353) (xy 95.85234 -213.560221)
			(xy 95.882772 -213.518334) (xy 95.919382 -213.481724) (xy 95.961269 -213.451292) (xy 96.007401 -213.427786)
			(xy 96.056641 -213.411787) (xy 96.107779 -213.403688) (xy 96.159553 -213.403688) (xy 96.210691 -213.411787)
			(xy 96.259931 -213.427786) (xy 96.306063 -213.451292) (xy 96.34795 -213.481724) (xy 96.38456 -213.518334)
			(xy 96.414992 -213.560221) (xy 96.438498 -213.606353) (xy 96.454497 -213.655593) (xy 96.462596 -213.706731)
			(xy 96.463104 -213.732618) (xy 97.683828 -213.732618) (xy 97.684336 -213.706731) (xy 97.692435 -213.655593)
			(xy 97.708434 -213.606353) (xy 97.73194 -213.560221) (xy 97.762372 -213.518334) (xy 97.798982 -213.481724)
			(xy 97.840869 -213.451292) (xy 97.887001 -213.427786) (xy 97.936241 -213.411787) (xy 97.987379 -213.403688)
			(xy 98.039153 -213.403688) (xy 98.090291 -213.411787) (xy 98.139531 -213.427786) (xy 98.185663 -213.451292)
			(xy 98.22755 -213.481724) (xy 98.26416 -213.518334) (xy 98.294592 -213.560221) (xy 98.318098 -213.606353)
			(xy 98.334097 -213.655593) (xy 98.342196 -213.706731) (xy 98.342704 -213.732618) (xy 99.563428 -213.732618)
			(xy 99.563936 -213.706731) (xy 99.572035 -213.655593) (xy 99.588034 -213.606353) (xy 99.61154 -213.560221)
			(xy 99.641972 -213.518334) (xy 99.678582 -213.481724) (xy 99.720469 -213.451292) (xy 99.766601 -213.427786)
			(xy 99.815841 -213.411787) (xy 99.866979 -213.403688) (xy 99.918753 -213.403688) (xy 99.969891 -213.411787)
			(xy 100.019131 -213.427786) (xy 100.065263 -213.451292) (xy 100.10715 -213.481724) (xy 100.14376 -213.518334)
			(xy 100.174192 -213.560221) (xy 100.197698 -213.606353) (xy 100.213697 -213.655593) (xy 100.221796 -213.706731)
			(xy 100.222304 -213.732618) (xy 101.443028 -213.732618) (xy 101.443536 -213.706731) (xy 101.451635 -213.655593)
			(xy 101.467634 -213.606353) (xy 101.49114 -213.560221) (xy 101.521572 -213.518334) (xy 101.558182 -213.481724)
			(xy 101.600069 -213.451292) (xy 101.646201 -213.427786) (xy 101.695441 -213.411787) (xy 101.746579 -213.403688)
			(xy 101.798353 -213.403688) (xy 101.849491 -213.411787) (xy 101.898731 -213.427786) (xy 101.944863 -213.451292)
			(xy 101.98675 -213.481724) (xy 102.02336 -213.518334) (xy 102.053792 -213.560221) (xy 102.077298 -213.606353)
			(xy 102.093297 -213.655593) (xy 102.101396 -213.706731) (xy 102.101904 -213.732618) (xy 103.322628 -213.732618)
			(xy 103.323136 -213.706731) (xy 103.331235 -213.655593) (xy 103.347234 -213.606353) (xy 103.37074 -213.560221)
			(xy 103.401172 -213.518334) (xy 103.437782 -213.481724) (xy 103.479669 -213.451292) (xy 103.525801 -213.427786)
			(xy 103.575041 -213.411787) (xy 103.626179 -213.403688) (xy 103.677953 -213.403688) (xy 103.729091 -213.411787)
			(xy 103.778331 -213.427786) (xy 103.824463 -213.451292) (xy 103.86635 -213.481724) (xy 103.90296 -213.518334)
			(xy 103.933392 -213.560221) (xy 103.956898 -213.606353) (xy 103.972897 -213.655593) (xy 103.980996 -213.706731)
			(xy 103.981504 -213.732618) (xy 105.202228 -213.732618) (xy 105.202736 -213.706731) (xy 105.210835 -213.655593)
			(xy 105.226834 -213.606353) (xy 105.25034 -213.560221) (xy 105.280772 -213.518334) (xy 105.317382 -213.481724)
			(xy 105.359269 -213.451292) (xy 105.405401 -213.427786) (xy 105.454641 -213.411787) (xy 105.505779 -213.403688)
			(xy 105.557553 -213.403688) (xy 105.608691 -213.411787) (xy 105.657931 -213.427786) (xy 105.704063 -213.451292)
			(xy 105.74595 -213.481724) (xy 105.78256 -213.518334) (xy 105.812992 -213.560221) (xy 105.836498 -213.606353)
			(xy 105.852497 -213.655593) (xy 105.860596 -213.706731) (xy 105.861104 -213.732618) (xy 107.081828 -213.732618)
			(xy 107.082336 -213.706731) (xy 107.090435 -213.655593) (xy 107.106434 -213.606353) (xy 107.12994 -213.560221)
			(xy 107.160372 -213.518334) (xy 107.196982 -213.481724) (xy 107.238869 -213.451292) (xy 107.285001 -213.427786)
			(xy 107.334241 -213.411787) (xy 107.385379 -213.403688) (xy 107.437153 -213.403688) (xy 107.488291 -213.411787)
			(xy 107.537531 -213.427786) (xy 107.583663 -213.451292) (xy 107.62555 -213.481724) (xy 107.66216 -213.518334)
			(xy 107.692592 -213.560221) (xy 107.716098 -213.606353) (xy 107.732097 -213.655593) (xy 107.740196 -213.706731)
			(xy 107.740704 -213.732618) (xy 114.600228 -213.732618) (xy 114.600736 -213.706731) (xy 114.608835 -213.655593)
			(xy 114.624834 -213.606353) (xy 114.64834 -213.560221) (xy 114.678772 -213.518334) (xy 114.715382 -213.481724)
			(xy 114.757269 -213.451292) (xy 114.803401 -213.427786) (xy 114.852641 -213.411787) (xy 114.903779 -213.403688)
			(xy 114.955553 -213.403688) (xy 115.006691 -213.411787) (xy 115.055931 -213.427786) (xy 115.102063 -213.451292)
			(xy 115.14395 -213.481724) (xy 115.18056 -213.518334) (xy 115.210992 -213.560221) (xy 115.234498 -213.606353)
			(xy 115.250497 -213.655593) (xy 115.258596 -213.706731) (xy 115.259104 -213.732618) (xy 116.479828 -213.732618)
			(xy 116.480336 -213.706731) (xy 116.488435 -213.655593) (xy 116.504434 -213.606353) (xy 116.52794 -213.560221)
			(xy 116.558372 -213.518334) (xy 116.594982 -213.481724) (xy 116.636869 -213.451292) (xy 116.683001 -213.427786)
			(xy 116.732241 -213.411787) (xy 116.783379 -213.403688) (xy 116.835153 -213.403688) (xy 116.886291 -213.411787)
			(xy 116.935531 -213.427786) (xy 116.981663 -213.451292) (xy 117.02355 -213.481724) (xy 117.06016 -213.518334)
			(xy 117.090592 -213.560221) (xy 117.114098 -213.606353) (xy 117.130097 -213.655593) (xy 117.138196 -213.706731)
			(xy 117.138704 -213.732618) (xy 118.359428 -213.732618) (xy 118.359936 -213.706731) (xy 118.368035 -213.655593)
			(xy 118.384034 -213.606353) (xy 118.40754 -213.560221) (xy 118.437972 -213.518334) (xy 118.474582 -213.481724)
			(xy 118.516469 -213.451292) (xy 118.562601 -213.427786) (xy 118.611841 -213.411787) (xy 118.662979 -213.403688)
			(xy 118.714753 -213.403688) (xy 118.765891 -213.411787) (xy 118.815131 -213.427786) (xy 118.861263 -213.451292)
			(xy 118.90315 -213.481724) (xy 118.93976 -213.518334) (xy 118.970192 -213.560221) (xy 118.993698 -213.606353)
			(xy 119.009697 -213.655593) (xy 119.017796 -213.706731) (xy 119.018304 -213.732618) (xy 120.239028 -213.732618)
			(xy 120.239536 -213.706731) (xy 120.247635 -213.655593) (xy 120.263634 -213.606353) (xy 120.28714 -213.560221)
			(xy 120.317572 -213.518334) (xy 120.354182 -213.481724) (xy 120.396069 -213.451292) (xy 120.442201 -213.427786)
			(xy 120.491441 -213.411787) (xy 120.542579 -213.403688) (xy 120.594353 -213.403688) (xy 120.645491 -213.411787)
			(xy 120.694731 -213.427786) (xy 120.740863 -213.451292) (xy 120.78275 -213.481724) (xy 120.81936 -213.518334)
			(xy 120.849792 -213.560221) (xy 120.873298 -213.606353) (xy 120.889297 -213.655593) (xy 120.897396 -213.706731)
			(xy 120.897904 -213.732618) (xy 122.118628 -213.732618) (xy 122.119136 -213.706731) (xy 122.127235 -213.655593)
			(xy 122.143234 -213.606353) (xy 122.16674 -213.560221) (xy 122.197172 -213.518334) (xy 122.233782 -213.481724)
			(xy 122.275669 -213.451292) (xy 122.321801 -213.427786) (xy 122.371041 -213.411787) (xy 122.422179 -213.403688)
			(xy 122.473953 -213.403688) (xy 122.525091 -213.411787) (xy 122.574331 -213.427786) (xy 122.620463 -213.451292)
			(xy 122.66235 -213.481724) (xy 122.69896 -213.518334) (xy 122.729392 -213.560221) (xy 122.752898 -213.606353)
			(xy 122.768897 -213.655593) (xy 122.776996 -213.706731) (xy 122.777504 -213.732618) (xy 123.99772 -213.732618)
			(xy 123.998228 -213.706711) (xy 124.006334 -213.655534) (xy 124.022346 -213.606255) (xy 124.045869 -213.560088)
			(xy 124.076325 -213.518169) (xy 124.112963 -213.481531) (xy 124.154882 -213.451075) (xy 124.201049 -213.427552)
			(xy 124.250328 -213.41154) (xy 124.301505 -213.403434) (xy 124.353319 -213.403434) (xy 124.404496 -213.41154)
			(xy 124.453775 -213.427552) (xy 124.499942 -213.451075) (xy 124.541861 -213.481531) (xy 124.578499 -213.518169)
			(xy 124.608955 -213.560088) (xy 124.632478 -213.606255) (xy 124.64849 -213.655534) (xy 124.656596 -213.706711)
			(xy 124.657104 -213.732618) (xy 125.87732 -213.732618) (xy 125.877828 -213.706711) (xy 125.885934 -213.655534)
			(xy 125.901946 -213.606255) (xy 125.925469 -213.560088) (xy 125.955925 -213.518169) (xy 125.992563 -213.481531)
			(xy 126.034482 -213.451075) (xy 126.080649 -213.427552) (xy 126.129928 -213.41154) (xy 126.181105 -213.403434)
			(xy 126.232919 -213.403434) (xy 126.284096 -213.41154) (xy 126.333375 -213.427552) (xy 126.379542 -213.451075)
			(xy 126.421461 -213.481531) (xy 126.458099 -213.518169) (xy 126.488555 -213.560088) (xy 126.512078 -213.606255)
			(xy 126.52809 -213.655534) (xy 126.536196 -213.706711) (xy 126.536704 -213.732618) (xy 127.757428 -213.732618)
			(xy 127.757936 -213.706731) (xy 127.766035 -213.655593) (xy 127.782034 -213.606353) (xy 127.80554 -213.560221)
			(xy 127.835972 -213.518334) (xy 127.872582 -213.481724) (xy 127.914469 -213.451292) (xy 127.960601 -213.427786)
			(xy 128.009841 -213.411787) (xy 128.060979 -213.403688) (xy 128.112753 -213.403688) (xy 128.163891 -213.411787)
			(xy 128.213131 -213.427786) (xy 128.259263 -213.451292) (xy 128.30115 -213.481724) (xy 128.33776 -213.518334)
			(xy 128.368192 -213.560221) (xy 128.391698 -213.606353) (xy 128.407697 -213.655593) (xy 128.415796 -213.706731)
			(xy 128.416304 -213.732618) (xy 129.637028 -213.732618) (xy 129.637536 -213.706731) (xy 129.645635 -213.655593)
			(xy 129.661634 -213.606353) (xy 129.68514 -213.560221) (xy 129.715572 -213.518334) (xy 129.752182 -213.481724)
			(xy 129.794069 -213.451292) (xy 129.840201 -213.427786) (xy 129.889441 -213.411787) (xy 129.940579 -213.403688)
			(xy 129.992353 -213.403688) (xy 130.043491 -213.411787) (xy 130.092731 -213.427786) (xy 130.138863 -213.451292)
			(xy 130.18075 -213.481724) (xy 130.21736 -213.518334) (xy 130.247792 -213.560221) (xy 130.271298 -213.606353)
			(xy 130.287297 -213.655593) (xy 130.295396 -213.706731) (xy 130.295904 -213.732618) (xy 131.516628 -213.732618)
			(xy 131.517136 -213.706731) (xy 131.525235 -213.655593) (xy 131.541234 -213.606353) (xy 131.56474 -213.560221)
			(xy 131.595172 -213.518334) (xy 131.631782 -213.481724) (xy 131.673669 -213.451292) (xy 131.719801 -213.427786)
			(xy 131.769041 -213.411787) (xy 131.820179 -213.403688) (xy 131.871953 -213.403688) (xy 131.923091 -213.411787)
			(xy 131.972331 -213.427786) (xy 132.018463 -213.451292) (xy 132.06035 -213.481724) (xy 132.09696 -213.518334)
			(xy 132.127392 -213.560221) (xy 132.150898 -213.606353) (xy 132.166897 -213.655593) (xy 132.174996 -213.706731)
			(xy 132.175504 -213.732618) (xy 338.105496 -213.732618) (xy 338.106004 -213.706731) (xy 338.114103 -213.655593)
			(xy 338.130102 -213.606353) (xy 338.153608 -213.560221) (xy 338.18404 -213.518334) (xy 338.22065 -213.481724)
			(xy 338.262537 -213.451292) (xy 338.308669 -213.427786) (xy 338.357909 -213.411787) (xy 338.409047 -213.403688)
			(xy 338.460821 -213.403688) (xy 338.511959 -213.411787) (xy 338.561199 -213.427786) (xy 338.607331 -213.451292)
			(xy 338.649218 -213.481724) (xy 338.685828 -213.518334) (xy 338.71626 -213.560221) (xy 338.739766 -213.606353)
			(xy 338.755765 -213.655593) (xy 338.763864 -213.706731) (xy 338.764372 -213.732618) (xy 339.985096 -213.732618)
			(xy 339.985604 -213.706731) (xy 339.993703 -213.655593) (xy 340.009702 -213.606353) (xy 340.033208 -213.560221)
			(xy 340.06364 -213.518334) (xy 340.10025 -213.481724) (xy 340.142137 -213.451292) (xy 340.188269 -213.427786)
			(xy 340.237509 -213.411787) (xy 340.288647 -213.403688) (xy 340.340421 -213.403688) (xy 340.391559 -213.411787)
			(xy 340.440799 -213.427786) (xy 340.486931 -213.451292) (xy 340.528818 -213.481724) (xy 340.565428 -213.518334)
			(xy 340.59586 -213.560221) (xy 340.619366 -213.606353) (xy 340.635365 -213.655593) (xy 340.643464 -213.706731)
			(xy 340.643972 -213.732618) (xy 341.864696 -213.732618) (xy 341.865204 -213.706731) (xy 341.873303 -213.655593)
			(xy 341.889302 -213.606353) (xy 341.912808 -213.560221) (xy 341.94324 -213.518334) (xy 341.97985 -213.481724)
			(xy 342.021737 -213.451292) (xy 342.067869 -213.427786) (xy 342.117109 -213.411787) (xy 342.168247 -213.403688)
			(xy 342.220021 -213.403688) (xy 342.271159 -213.411787) (xy 342.320399 -213.427786) (xy 342.366531 -213.451292)
			(xy 342.408418 -213.481724) (xy 342.445028 -213.518334) (xy 342.47546 -213.560221) (xy 342.498966 -213.606353)
			(xy 342.514965 -213.655593) (xy 342.523064 -213.706731) (xy 342.523572 -213.732618) (xy 343.744296 -213.732618)
			(xy 343.744804 -213.706731) (xy 343.752903 -213.655593) (xy 343.768902 -213.606353) (xy 343.792408 -213.560221)
			(xy 343.82284 -213.518334) (xy 343.85945 -213.481724) (xy 343.901337 -213.451292) (xy 343.947469 -213.427786)
			(xy 343.996709 -213.411787) (xy 344.047847 -213.403688) (xy 344.099621 -213.403688) (xy 344.150759 -213.411787)
			(xy 344.199999 -213.427786) (xy 344.246131 -213.451292) (xy 344.288018 -213.481724) (xy 344.324628 -213.518334)
			(xy 344.35506 -213.560221) (xy 344.378566 -213.606353) (xy 344.394565 -213.655593) (xy 344.402664 -213.706731)
			(xy 344.403172 -213.732618) (xy 345.623896 -213.732618) (xy 345.624404 -213.706731) (xy 345.632503 -213.655593)
			(xy 345.648502 -213.606353) (xy 345.672008 -213.560221) (xy 345.70244 -213.518334) (xy 345.73905 -213.481724)
			(xy 345.780937 -213.451292) (xy 345.827069 -213.427786) (xy 345.876309 -213.411787) (xy 345.927447 -213.403688)
			(xy 345.979221 -213.403688) (xy 346.030359 -213.411787) (xy 346.079599 -213.427786) (xy 346.125731 -213.451292)
			(xy 346.167618 -213.481724) (xy 346.204228 -213.518334) (xy 346.23466 -213.560221) (xy 346.258166 -213.606353)
			(xy 346.274165 -213.655593) (xy 346.282264 -213.706731) (xy 346.282772 -213.732618) (xy 347.503496 -213.732618)
			(xy 347.504004 -213.706731) (xy 347.512103 -213.655593) (xy 347.528102 -213.606353) (xy 347.551608 -213.560221)
			(xy 347.58204 -213.518334) (xy 347.61865 -213.481724) (xy 347.660537 -213.451292) (xy 347.706669 -213.427786)
			(xy 347.755909 -213.411787) (xy 347.807047 -213.403688) (xy 347.858821 -213.403688) (xy 347.909959 -213.411787)
			(xy 347.959199 -213.427786) (xy 348.005331 -213.451292) (xy 348.047218 -213.481724) (xy 348.083828 -213.518334)
			(xy 348.11426 -213.560221) (xy 348.137766 -213.606353) (xy 348.153765 -213.655593) (xy 348.161864 -213.706731)
			(xy 348.162372 -213.732618) (xy 349.383096 -213.732618) (xy 349.383604 -213.706731) (xy 349.391703 -213.655593)
			(xy 349.407702 -213.606353) (xy 349.431208 -213.560221) (xy 349.46164 -213.518334) (xy 349.49825 -213.481724)
			(xy 349.540137 -213.451292) (xy 349.586269 -213.427786) (xy 349.635509 -213.411787) (xy 349.686647 -213.403688)
			(xy 349.738421 -213.403688) (xy 349.789559 -213.411787) (xy 349.838799 -213.427786) (xy 349.884931 -213.451292)
			(xy 349.926818 -213.481724) (xy 349.963428 -213.518334) (xy 349.99386 -213.560221) (xy 350.017366 -213.606353)
			(xy 350.033365 -213.655593) (xy 350.041464 -213.706731) (xy 350.041972 -213.732618) (xy 351.262696 -213.732618)
			(xy 351.263204 -213.706731) (xy 351.271303 -213.655593) (xy 351.287302 -213.606353) (xy 351.310808 -213.560221)
			(xy 351.34124 -213.518334) (xy 351.37785 -213.481724) (xy 351.419737 -213.451292) (xy 351.465869 -213.427786)
			(xy 351.515109 -213.411787) (xy 351.566247 -213.403688) (xy 351.618021 -213.403688) (xy 351.669159 -213.411787)
			(xy 351.718399 -213.427786) (xy 351.764531 -213.451292) (xy 351.806418 -213.481724) (xy 351.843028 -213.518334)
			(xy 351.87346 -213.560221) (xy 351.896966 -213.606353) (xy 351.912965 -213.655593) (xy 351.921064 -213.706731)
			(xy 351.921572 -213.732618) (xy 353.142296 -213.732618) (xy 353.142804 -213.706731) (xy 353.150903 -213.655593)
			(xy 353.166902 -213.606353) (xy 353.190408 -213.560221) (xy 353.22084 -213.518334) (xy 353.25745 -213.481724)
			(xy 353.299337 -213.451292) (xy 353.345469 -213.427786) (xy 353.394709 -213.411787) (xy 353.445847 -213.403688)
			(xy 353.497621 -213.403688) (xy 353.548759 -213.411787) (xy 353.597999 -213.427786) (xy 353.644131 -213.451292)
			(xy 353.686018 -213.481724) (xy 353.722628 -213.518334) (xy 353.75306 -213.560221) (xy 353.776566 -213.606353)
			(xy 353.792565 -213.655593) (xy 353.800664 -213.706731) (xy 353.801172 -213.732618) (xy 355.021896 -213.732618)
			(xy 355.022404 -213.706731) (xy 355.030503 -213.655593) (xy 355.046502 -213.606353) (xy 355.070008 -213.560221)
			(xy 355.10044 -213.518334) (xy 355.13705 -213.481724) (xy 355.178937 -213.451292) (xy 355.225069 -213.427786)
			(xy 355.274309 -213.411787) (xy 355.325447 -213.403688) (xy 355.377221 -213.403688) (xy 355.428359 -213.411787)
			(xy 355.477599 -213.427786) (xy 355.523731 -213.451292) (xy 355.565618 -213.481724) (xy 355.602228 -213.518334)
			(xy 355.63266 -213.560221) (xy 355.656166 -213.606353) (xy 355.672165 -213.655593) (xy 355.680264 -213.706731)
			(xy 355.680772 -213.732618) (xy 355.680423 -213.755595) (xy 355.674102 -213.801111) (xy 355.661516 -213.845306)
			(xy 355.652578 -213.866476) (xy 355.642672 -213.888828) (xy 355.856286 -214.293958) (xy 355.880416 -214.29853)
			(xy 355.90533 -214.303664) (xy 355.95334 -214.320459) (xy 355.998199 -214.344434) (xy 356.038841 -214.375017)
			(xy 356.074299 -214.411484) (xy 356.103732 -214.452967) (xy 356.12644 -214.49848) (xy 356.141883 -214.546942)
			(xy 356.149695 -214.597202) (xy 356.150164 -214.622634) (xy 356.149656 -214.648521) (xy 356.141557 -214.699659)
			(xy 356.125558 -214.748899) (xy 356.102052 -214.795031) (xy 356.07162 -214.836918) (xy 356.03501 -214.873528)
			(xy 355.993123 -214.90396) (xy 355.946991 -214.927466) (xy 355.897751 -214.943465) (xy 355.846613 -214.951564)
			(xy 355.794839 -214.951564) (xy 355.743701 -214.943465) (xy 355.694461 -214.927466) (xy 355.648329 -214.90396)
			(xy 355.606442 -214.873528) (xy 355.569832 -214.836918) (xy 355.5394 -214.795031) (xy 355.515894 -214.748899)
			(xy 355.499895 -214.699659) (xy 355.491796 -214.648521) (xy 355.491288 -214.622634) (xy 355.491658 -214.599658)
			(xy 355.49797 -214.554143) (xy 355.510548 -214.509947) (xy 355.519482 -214.488776) (xy 355.529388 -214.466424)
			(xy 355.315774 -214.061294) (xy 355.291644 -214.056722) (xy 355.266713 -214.051663) (xy 355.218699 -214.034858)
			(xy 355.173839 -214.010874) (xy 355.133197 -213.980281) (xy 355.097739 -213.943805) (xy 355.068309 -213.902313)
			(xy 355.045605 -213.856791) (xy 355.030167 -213.80832) (xy 355.022362 -213.758053) (xy 355.021896 -213.732618)
			(xy 353.801172 -213.732618) (xy 353.800823 -213.755595) (xy 353.794502 -213.801111) (xy 353.781916 -213.845306)
			(xy 353.772978 -213.866476) (xy 353.763072 -213.888828) (xy 353.976686 -214.293958) (xy 354.000816 -214.29853)
			(xy 354.02573 -214.303664) (xy 354.07374 -214.320459) (xy 354.118599 -214.344434) (xy 354.159241 -214.375017)
			(xy 354.194699 -214.411484) (xy 354.224132 -214.452967) (xy 354.24684 -214.49848) (xy 354.262283 -214.546942)
			(xy 354.270095 -214.597202) (xy 354.270564 -214.622634) (xy 354.270056 -214.648521) (xy 354.261957 -214.699659)
			(xy 354.245958 -214.748899) (xy 354.222452 -214.795031) (xy 354.19202 -214.836918) (xy 354.15541 -214.873528)
			(xy 354.113523 -214.90396) (xy 354.067391 -214.927466) (xy 354.018151 -214.943465) (xy 353.967013 -214.951564)
			(xy 353.915239 -214.951564) (xy 353.864101 -214.943465) (xy 353.814861 -214.927466) (xy 353.768729 -214.90396)
			(xy 353.726842 -214.873528) (xy 353.690232 -214.836918) (xy 353.6598 -214.795031) (xy 353.636294 -214.748899)
			(xy 353.620295 -214.699659) (xy 353.612196 -214.648521) (xy 353.611688 -214.622634) (xy 353.612058 -214.599658)
			(xy 353.61837 -214.554143) (xy 353.630948 -214.509947) (xy 353.639882 -214.488776) (xy 353.649788 -214.466424)
			(xy 353.436174 -214.061294) (xy 353.412044 -214.056722) (xy 353.387113 -214.051663) (xy 353.339099 -214.034858)
			(xy 353.294239 -214.010874) (xy 353.253597 -213.980281) (xy 353.218139 -213.943805) (xy 353.188709 -213.902313)
			(xy 353.166005 -213.856791) (xy 353.150567 -213.80832) (xy 353.142762 -213.758053) (xy 353.142296 -213.732618)
			(xy 351.921572 -213.732618) (xy 351.921223 -213.755595) (xy 351.914902 -213.801111) (xy 351.902316 -213.845306)
			(xy 351.893378 -213.866476) (xy 351.883472 -213.888828) (xy 352.097086 -214.293958) (xy 352.121216 -214.29853)
			(xy 352.14613 -214.303664) (xy 352.19414 -214.320459) (xy 352.238999 -214.344434) (xy 352.279641 -214.375017)
			(xy 352.315099 -214.411484) (xy 352.344532 -214.452967) (xy 352.36724 -214.49848) (xy 352.382683 -214.546942)
			(xy 352.390495 -214.597202) (xy 352.390964 -214.622634) (xy 352.390456 -214.648521) (xy 352.382357 -214.699659)
			(xy 352.366358 -214.748899) (xy 352.342852 -214.795031) (xy 352.31242 -214.836918) (xy 352.27581 -214.873528)
			(xy 352.233923 -214.90396) (xy 352.187791 -214.927466) (xy 352.138551 -214.943465) (xy 352.087413 -214.951564)
			(xy 352.035639 -214.951564) (xy 351.984501 -214.943465) (xy 351.935261 -214.927466) (xy 351.889129 -214.90396)
			(xy 351.847242 -214.873528) (xy 351.810632 -214.836918) (xy 351.7802 -214.795031) (xy 351.756694 -214.748899)
			(xy 351.740695 -214.699659) (xy 351.732596 -214.648521) (xy 351.732088 -214.622634) (xy 351.732458 -214.599658)
			(xy 351.73877 -214.554143) (xy 351.751348 -214.509947) (xy 351.760282 -214.488776) (xy 351.770188 -214.466424)
			(xy 351.556574 -214.061294) (xy 351.532444 -214.056722) (xy 351.507513 -214.051663) (xy 351.459499 -214.034858)
			(xy 351.414639 -214.010874) (xy 351.373997 -213.980281) (xy 351.338539 -213.943805) (xy 351.309109 -213.902313)
			(xy 351.286405 -213.856791) (xy 351.270967 -213.80832) (xy 351.263162 -213.758053) (xy 351.262696 -213.732618)
			(xy 350.041972 -213.732618) (xy 350.041623 -213.755595) (xy 350.035302 -213.801111) (xy 350.022716 -213.845306)
			(xy 350.013778 -213.866476) (xy 350.003872 -213.888828) (xy 350.217486 -214.293958) (xy 350.241616 -214.29853)
			(xy 350.26653 -214.303664) (xy 350.31454 -214.320459) (xy 350.359399 -214.344434) (xy 350.400041 -214.375017)
			(xy 350.435499 -214.411484) (xy 350.464932 -214.452967) (xy 350.48764 -214.49848) (xy 350.503083 -214.546942)
			(xy 350.510895 -214.597202) (xy 350.511364 -214.622634) (xy 350.510856 -214.648521) (xy 350.502757 -214.699659)
			(xy 350.486758 -214.748899) (xy 350.463252 -214.795031) (xy 350.43282 -214.836918) (xy 350.39621 -214.873528)
			(xy 350.354323 -214.90396) (xy 350.308191 -214.927466) (xy 350.258951 -214.943465) (xy 350.207813 -214.951564)
			(xy 350.156039 -214.951564) (xy 350.104901 -214.943465) (xy 350.055661 -214.927466) (xy 350.009529 -214.90396)
			(xy 349.967642 -214.873528) (xy 349.931032 -214.836918) (xy 349.9006 -214.795031) (xy 349.877094 -214.748899)
			(xy 349.861095 -214.699659) (xy 349.852996 -214.648521) (xy 349.852488 -214.622634) (xy 349.852858 -214.599658)
			(xy 349.85917 -214.554143) (xy 349.871748 -214.509947) (xy 349.880682 -214.488776) (xy 349.890588 -214.466424)
			(xy 349.676974 -214.061294) (xy 349.652844 -214.056722) (xy 349.627913 -214.051663) (xy 349.579899 -214.034858)
			(xy 349.535039 -214.010874) (xy 349.494397 -213.980281) (xy 349.458939 -213.943805) (xy 349.429509 -213.902313)
			(xy 349.406805 -213.856791) (xy 349.391367 -213.80832) (xy 349.383562 -213.758053) (xy 349.383096 -213.732618)
			(xy 348.162372 -213.732618) (xy 348.162023 -213.755595) (xy 348.155702 -213.801111) (xy 348.143116 -213.845306)
			(xy 348.134178 -213.866476) (xy 348.124272 -213.888828) (xy 348.337886 -214.293958) (xy 348.362016 -214.29853)
			(xy 348.38693 -214.303664) (xy 348.43494 -214.320459) (xy 348.479799 -214.344434) (xy 348.520441 -214.375017)
			(xy 348.555899 -214.411484) (xy 348.585332 -214.452967) (xy 348.60804 -214.49848) (xy 348.623483 -214.546942)
			(xy 348.631295 -214.597202) (xy 348.631764 -214.622634) (xy 348.631256 -214.648521) (xy 348.623157 -214.699659)
			(xy 348.607158 -214.748899) (xy 348.583652 -214.795031) (xy 348.55322 -214.836918) (xy 348.51661 -214.873528)
			(xy 348.474723 -214.90396) (xy 348.428591 -214.927466) (xy 348.379351 -214.943465) (xy 348.328213 -214.951564)
			(xy 348.276439 -214.951564) (xy 348.225301 -214.943465) (xy 348.176061 -214.927466) (xy 348.129929 -214.90396)
			(xy 348.088042 -214.873528) (xy 348.051432 -214.836918) (xy 348.021 -214.795031) (xy 347.997494 -214.748899)
			(xy 347.981495 -214.699659) (xy 347.973396 -214.648521) (xy 347.972888 -214.622634) (xy 347.973258 -214.599658)
			(xy 347.97957 -214.554143) (xy 347.992148 -214.509947) (xy 348.001082 -214.488776) (xy 348.010988 -214.466424)
			(xy 347.797374 -214.061294) (xy 347.773244 -214.056722) (xy 347.748313 -214.051663) (xy 347.700299 -214.034858)
			(xy 347.655439 -214.010874) (xy 347.614797 -213.980281) (xy 347.579339 -213.943805) (xy 347.549909 -213.902313)
			(xy 347.527205 -213.856791) (xy 347.511767 -213.80832) (xy 347.503962 -213.758053) (xy 347.503496 -213.732618)
			(xy 346.282772 -213.732618) (xy 346.282423 -213.755595) (xy 346.276102 -213.801111) (xy 346.263516 -213.845306)
			(xy 346.254578 -213.866476) (xy 346.244672 -213.888828) (xy 346.458286 -214.293958) (xy 346.482416 -214.29853)
			(xy 346.50733 -214.303664) (xy 346.55534 -214.320459) (xy 346.600199 -214.344434) (xy 346.640841 -214.375017)
			(xy 346.676299 -214.411484) (xy 346.705732 -214.452967) (xy 346.72844 -214.49848) (xy 346.743883 -214.546942)
			(xy 346.751695 -214.597202) (xy 346.752164 -214.622634) (xy 346.751656 -214.648521) (xy 346.743557 -214.699659)
			(xy 346.727558 -214.748899) (xy 346.704052 -214.795031) (xy 346.67362 -214.836918) (xy 346.63701 -214.873528)
			(xy 346.595123 -214.90396) (xy 346.548991 -214.927466) (xy 346.499751 -214.943465) (xy 346.448613 -214.951564)
			(xy 346.396839 -214.951564) (xy 346.345701 -214.943465) (xy 346.296461 -214.927466) (xy 346.250329 -214.90396)
			(xy 346.208442 -214.873528) (xy 346.171832 -214.836918) (xy 346.1414 -214.795031) (xy 346.117894 -214.748899)
			(xy 346.101895 -214.699659) (xy 346.093796 -214.648521) (xy 346.093288 -214.622634) (xy 346.093658 -214.599658)
			(xy 346.09997 -214.554143) (xy 346.112548 -214.509947) (xy 346.121482 -214.488776) (xy 346.131388 -214.466424)
			(xy 345.917774 -214.061294) (xy 345.893644 -214.056722) (xy 345.868713 -214.051663) (xy 345.820699 -214.034858)
			(xy 345.775839 -214.010874) (xy 345.735197 -213.980281) (xy 345.699739 -213.943805) (xy 345.670309 -213.902313)
			(xy 345.647605 -213.856791) (xy 345.632167 -213.80832) (xy 345.624362 -213.758053) (xy 345.623896 -213.732618)
			(xy 344.403172 -213.732618) (xy 344.402823 -213.755595) (xy 344.396502 -213.801111) (xy 344.383916 -213.845306)
			(xy 344.374978 -213.866476) (xy 344.365072 -213.888828) (xy 344.578686 -214.293958) (xy 344.602816 -214.29853)
			(xy 344.62773 -214.303664) (xy 344.67574 -214.320459) (xy 344.720599 -214.344434) (xy 344.761241 -214.375017)
			(xy 344.796699 -214.411484) (xy 344.826132 -214.452967) (xy 344.84884 -214.49848) (xy 344.864283 -214.546942)
			(xy 344.872095 -214.597202) (xy 344.872564 -214.622634) (xy 344.872056 -214.648521) (xy 344.863957 -214.699659)
			(xy 344.847958 -214.748899) (xy 344.824452 -214.795031) (xy 344.79402 -214.836918) (xy 344.75741 -214.873528)
			(xy 344.715523 -214.90396) (xy 344.669391 -214.927466) (xy 344.620151 -214.943465) (xy 344.569013 -214.951564)
			(xy 344.517239 -214.951564) (xy 344.466101 -214.943465) (xy 344.416861 -214.927466) (xy 344.370729 -214.90396)
			(xy 344.328842 -214.873528) (xy 344.292232 -214.836918) (xy 344.2618 -214.795031) (xy 344.238294 -214.748899)
			(xy 344.222295 -214.699659) (xy 344.214196 -214.648521) (xy 344.213688 -214.622634) (xy 344.214058 -214.599658)
			(xy 344.22037 -214.554143) (xy 344.232948 -214.509947) (xy 344.241882 -214.488776) (xy 344.251788 -214.466424)
			(xy 344.038174 -214.061294) (xy 344.014044 -214.056722) (xy 343.989113 -214.051663) (xy 343.941099 -214.034858)
			(xy 343.896239 -214.010874) (xy 343.855597 -213.980281) (xy 343.820139 -213.943805) (xy 343.790709 -213.902313)
			(xy 343.768005 -213.856791) (xy 343.752567 -213.80832) (xy 343.744762 -213.758053) (xy 343.744296 -213.732618)
			(xy 342.523572 -213.732618) (xy 342.523223 -213.755595) (xy 342.516902 -213.801111) (xy 342.504316 -213.845306)
			(xy 342.495378 -213.866476) (xy 342.485472 -213.888828) (xy 342.699086 -214.293958) (xy 342.723216 -214.29853)
			(xy 342.74813 -214.303664) (xy 342.79614 -214.320459) (xy 342.840999 -214.344434) (xy 342.881641 -214.375017)
			(xy 342.917099 -214.411484) (xy 342.946532 -214.452967) (xy 342.96924 -214.49848) (xy 342.984683 -214.546942)
			(xy 342.992495 -214.597202) (xy 342.992964 -214.622634) (xy 342.992456 -214.648521) (xy 342.984357 -214.699659)
			(xy 342.968358 -214.748899) (xy 342.944852 -214.795031) (xy 342.91442 -214.836918) (xy 342.87781 -214.873528)
			(xy 342.835923 -214.90396) (xy 342.789791 -214.927466) (xy 342.740551 -214.943465) (xy 342.689413 -214.951564)
			(xy 342.637639 -214.951564) (xy 342.586501 -214.943465) (xy 342.537261 -214.927466) (xy 342.491129 -214.90396)
			(xy 342.449242 -214.873528) (xy 342.412632 -214.836918) (xy 342.3822 -214.795031) (xy 342.358694 -214.748899)
			(xy 342.342695 -214.699659) (xy 342.334596 -214.648521) (xy 342.334088 -214.622634) (xy 342.334458 -214.599658)
			(xy 342.34077 -214.554143) (xy 342.353348 -214.509947) (xy 342.362282 -214.488776) (xy 342.372188 -214.466424)
			(xy 342.158574 -214.061294) (xy 342.134444 -214.056722) (xy 342.109513 -214.051663) (xy 342.061499 -214.034858)
			(xy 342.016639 -214.010874) (xy 341.975997 -213.980281) (xy 341.940539 -213.943805) (xy 341.911109 -213.902313)
			(xy 341.888405 -213.856791) (xy 341.872967 -213.80832) (xy 341.865162 -213.758053) (xy 341.864696 -213.732618)
			(xy 340.643972 -213.732618) (xy 340.643623 -213.755595) (xy 340.637302 -213.801111) (xy 340.624716 -213.845306)
			(xy 340.615778 -213.866476) (xy 340.605872 -213.888828) (xy 340.819486 -214.293958) (xy 340.843616 -214.29853)
			(xy 340.86853 -214.303664) (xy 340.91654 -214.320459) (xy 340.961399 -214.344434) (xy 341.002041 -214.375017)
			(xy 341.037499 -214.411484) (xy 341.066932 -214.452967) (xy 341.08964 -214.49848) (xy 341.105083 -214.546942)
			(xy 341.112895 -214.597202) (xy 341.113364 -214.622634) (xy 341.112856 -214.648521) (xy 341.104757 -214.699659)
			(xy 341.088758 -214.748899) (xy 341.065252 -214.795031) (xy 341.03482 -214.836918) (xy 340.99821 -214.873528)
			(xy 340.956323 -214.90396) (xy 340.910191 -214.927466) (xy 340.860951 -214.943465) (xy 340.809813 -214.951564)
			(xy 340.758039 -214.951564) (xy 340.706901 -214.943465) (xy 340.657661 -214.927466) (xy 340.611529 -214.90396)
			(xy 340.569642 -214.873528) (xy 340.533032 -214.836918) (xy 340.5026 -214.795031) (xy 340.479094 -214.748899)
			(xy 340.463095 -214.699659) (xy 340.454996 -214.648521) (xy 340.454488 -214.622634) (xy 340.454858 -214.599658)
			(xy 340.46117 -214.554143) (xy 340.473748 -214.509947) (xy 340.482682 -214.488776) (xy 340.492588 -214.466424)
			(xy 340.278974 -214.061294) (xy 340.254844 -214.056722) (xy 340.229913 -214.051663) (xy 340.181899 -214.034858)
			(xy 340.137039 -214.010874) (xy 340.096397 -213.980281) (xy 340.060939 -213.943805) (xy 340.031509 -213.902313)
			(xy 340.008805 -213.856791) (xy 339.993367 -213.80832) (xy 339.985562 -213.758053) (xy 339.985096 -213.732618)
			(xy 338.764372 -213.732618) (xy 338.764023 -213.755595) (xy 338.757702 -213.801111) (xy 338.745116 -213.845306)
			(xy 338.736178 -213.866476) (xy 338.726272 -213.888828) (xy 338.939886 -214.293958) (xy 338.964016 -214.29853)
			(xy 338.98893 -214.303664) (xy 339.03694 -214.320459) (xy 339.081799 -214.344434) (xy 339.122441 -214.375017)
			(xy 339.157899 -214.411484) (xy 339.187332 -214.452967) (xy 339.21004 -214.49848) (xy 339.225483 -214.546942)
			(xy 339.233295 -214.597202) (xy 339.233764 -214.622634) (xy 339.233256 -214.648521) (xy 339.225157 -214.699659)
			(xy 339.209158 -214.748899) (xy 339.185652 -214.795031) (xy 339.15522 -214.836918) (xy 339.11861 -214.873528)
			(xy 339.076723 -214.90396) (xy 339.030591 -214.927466) (xy 338.981351 -214.943465) (xy 338.930213 -214.951564)
			(xy 338.878439 -214.951564) (xy 338.827301 -214.943465) (xy 338.778061 -214.927466) (xy 338.731929 -214.90396)
			(xy 338.690042 -214.873528) (xy 338.653432 -214.836918) (xy 338.623 -214.795031) (xy 338.599494 -214.748899)
			(xy 338.583495 -214.699659) (xy 338.575396 -214.648521) (xy 338.574888 -214.622634) (xy 338.575258 -214.599658)
			(xy 338.58157 -214.554143) (xy 338.594148 -214.509947) (xy 338.603082 -214.488776) (xy 338.612988 -214.466424)
			(xy 338.399374 -214.061294) (xy 338.375244 -214.056722) (xy 338.350313 -214.051663) (xy 338.302299 -214.034858)
			(xy 338.257439 -214.010874) (xy 338.216797 -213.980281) (xy 338.181339 -213.943805) (xy 338.151909 -213.902313)
			(xy 338.129205 -213.856791) (xy 338.113767 -213.80832) (xy 338.105962 -213.758053) (xy 338.105496 -213.732618)
			(xy 132.175504 -213.732618) (xy 132.175153 -213.755595) (xy 132.168832 -213.80111) (xy 132.156248 -213.845306)
			(xy 132.14731 -213.866476) (xy 132.137404 -213.888828) (xy 132.351018 -214.293958) (xy 132.375148 -214.29853)
			(xy 132.400067 -214.303641) (xy 132.448077 -214.320441) (xy 132.492936 -214.344419) (xy 132.533576 -214.375006)
			(xy 132.569034 -214.411476) (xy 132.598466 -214.452961) (xy 132.621173 -214.498476) (xy 132.636615 -214.54694)
			(xy 132.644427 -214.597201) (xy 132.644896 -214.622634) (xy 132.644388 -214.648521) (xy 132.636289 -214.699659)
			(xy 132.62029 -214.748899) (xy 132.596784 -214.795031) (xy 132.566352 -214.836918) (xy 132.529742 -214.873528)
			(xy 132.487855 -214.90396) (xy 132.441723 -214.927466) (xy 132.392483 -214.943465) (xy 132.341345 -214.951564)
			(xy 132.289571 -214.951564) (xy 132.238433 -214.943465) (xy 132.189193 -214.927466) (xy 132.143061 -214.90396)
			(xy 132.101174 -214.873528) (xy 132.064564 -214.836918) (xy 132.034132 -214.795031) (xy 132.010626 -214.748899)
			(xy 131.994627 -214.699659) (xy 131.986528 -214.648521) (xy 131.98602 -214.622634) (xy 131.986387 -214.599658)
			(xy 131.9927 -214.554143) (xy 132.005279 -214.509947) (xy 132.014214 -214.488776) (xy 132.02412 -214.466424)
			(xy 131.810506 -214.061294) (xy 131.786376 -214.056722) (xy 131.76145 -214.051639) (xy 131.713436 -214.034839)
			(xy 131.668575 -214.010859) (xy 131.627932 -213.980269) (xy 131.592474 -213.943796) (xy 131.563043 -213.902307)
			(xy 131.540338 -213.856787) (xy 131.5249 -213.808318) (xy 131.517094 -213.758052) (xy 131.516628 -213.732618)
			(xy 130.295904 -213.732618) (xy 130.295553 -213.755595) (xy 130.289232 -213.80111) (xy 130.276648 -213.845306)
			(xy 130.26771 -213.866476) (xy 130.257804 -213.888828) (xy 130.471418 -214.293958) (xy 130.495548 -214.29853)
			(xy 130.520467 -214.303641) (xy 130.568477 -214.320441) (xy 130.613336 -214.344419) (xy 130.653976 -214.375006)
			(xy 130.689434 -214.411476) (xy 130.718866 -214.452961) (xy 130.741573 -214.498476) (xy 130.757015 -214.54694)
			(xy 130.764827 -214.597201) (xy 130.765296 -214.622634) (xy 130.764788 -214.648521) (xy 130.756689 -214.699659)
			(xy 130.74069 -214.748899) (xy 130.717184 -214.795031) (xy 130.686752 -214.836918) (xy 130.650142 -214.873528)
			(xy 130.608255 -214.90396) (xy 130.562123 -214.927466) (xy 130.512883 -214.943465) (xy 130.461745 -214.951564)
			(xy 130.409971 -214.951564) (xy 130.358833 -214.943465) (xy 130.309593 -214.927466) (xy 130.263461 -214.90396)
			(xy 130.221574 -214.873528) (xy 130.184964 -214.836918) (xy 130.154532 -214.795031) (xy 130.131026 -214.748899)
			(xy 130.115027 -214.699659) (xy 130.106928 -214.648521) (xy 130.10642 -214.622634) (xy 130.106787 -214.599658)
			(xy 130.1131 -214.554143) (xy 130.125679 -214.509947) (xy 130.134614 -214.488776) (xy 130.14452 -214.466424)
			(xy 129.930906 -214.061294) (xy 129.906776 -214.056722) (xy 129.88185 -214.051639) (xy 129.833836 -214.034839)
			(xy 129.788975 -214.010859) (xy 129.748332 -213.980269) (xy 129.712874 -213.943796) (xy 129.683443 -213.902307)
			(xy 129.660738 -213.856787) (xy 129.6453 -213.808318) (xy 129.637494 -213.758052) (xy 129.637028 -213.732618)
			(xy 128.416304 -213.732618) (xy 128.415953 -213.755595) (xy 128.409632 -213.80111) (xy 128.397048 -213.845306)
			(xy 128.38811 -213.866476) (xy 128.378204 -213.888828) (xy 128.591818 -214.293958) (xy 128.615948 -214.29853)
			(xy 128.640867 -214.303641) (xy 128.688877 -214.320441) (xy 128.733736 -214.344419) (xy 128.774376 -214.375006)
			(xy 128.809834 -214.411476) (xy 128.839266 -214.452961) (xy 128.861973 -214.498476) (xy 128.877415 -214.54694)
			(xy 128.885227 -214.597201) (xy 128.885696 -214.622634) (xy 128.885188 -214.648521) (xy 128.877089 -214.699659)
			(xy 128.86109 -214.748899) (xy 128.837584 -214.795031) (xy 128.807152 -214.836918) (xy 128.770542 -214.873528)
			(xy 128.728655 -214.90396) (xy 128.682523 -214.927466) (xy 128.633283 -214.943465) (xy 128.582145 -214.951564)
			(xy 128.530371 -214.951564) (xy 128.479233 -214.943465) (xy 128.429993 -214.927466) (xy 128.383861 -214.90396)
			(xy 128.341974 -214.873528) (xy 128.305364 -214.836918) (xy 128.274932 -214.795031) (xy 128.251426 -214.748899)
			(xy 128.235427 -214.699659) (xy 128.227328 -214.648521) (xy 128.22682 -214.622634) (xy 128.227187 -214.599658)
			(xy 128.2335 -214.554143) (xy 128.246079 -214.509947) (xy 128.255014 -214.488776) (xy 128.26492 -214.466424)
			(xy 128.051306 -214.061294) (xy 128.027176 -214.056722) (xy 128.00225 -214.051639) (xy 127.954236 -214.034839)
			(xy 127.909375 -214.010859) (xy 127.868732 -213.980269) (xy 127.833274 -213.943796) (xy 127.803843 -213.902307)
			(xy 127.781138 -213.856787) (xy 127.7657 -213.808318) (xy 127.757894 -213.758052) (xy 127.757428 -213.732618)
			(xy 126.536704 -213.732618) (xy 126.536283 -213.755559) (xy 126.529855 -213.80099) (xy 126.517209 -213.845096)
			(xy 126.508256 -213.866222) (xy 126.49835 -213.888574) (xy 126.712218 -214.293958) (xy 126.736348 -214.29853)
			(xy 126.761267 -214.303641) (xy 126.809277 -214.320441) (xy 126.854136 -214.344419) (xy 126.894776 -214.375006)
			(xy 126.930234 -214.411476) (xy 126.959666 -214.452961) (xy 126.982373 -214.498476) (xy 126.997815 -214.54694)
			(xy 127.005627 -214.597201) (xy 127.006096 -214.622634) (xy 127.005588 -214.648521) (xy 126.997489 -214.699659)
			(xy 126.98149 -214.748899) (xy 126.957984 -214.795031) (xy 126.927552 -214.836918) (xy 126.890942 -214.873528)
			(xy 126.849055 -214.90396) (xy 126.802923 -214.927466) (xy 126.753683 -214.943465) (xy 126.702545 -214.951564)
			(xy 126.650771 -214.951564) (xy 126.599633 -214.943465) (xy 126.550393 -214.927466) (xy 126.504261 -214.90396)
			(xy 126.462374 -214.873528) (xy 126.425764 -214.836918) (xy 126.395332 -214.795031) (xy 126.371826 -214.748899)
			(xy 126.355827 -214.699659) (xy 126.347728 -214.648521) (xy 126.34722 -214.622634) (xy 126.347587 -214.599658)
			(xy 126.3539 -214.554143) (xy 126.366479 -214.509947) (xy 126.375414 -214.488776) (xy 126.38532 -214.466424)
			(xy 126.171706 -214.061294) (xy 126.147576 -214.056722) (xy 126.12262 -214.051672) (xy 126.074538 -214.034924)
			(xy 126.029605 -214.010979) (xy 125.98889 -213.980407) (xy 125.953363 -213.943936) (xy 125.92387 -213.902434)
			(xy 125.901111 -213.856888) (xy 125.88563 -213.808384) (xy 125.877795 -213.758075) (xy 125.87732 -213.732618)
			(xy 124.657104 -213.732618) (xy 124.656681 -213.756953) (xy 124.649527 -213.805095) (xy 124.635379 -213.851663)
			(xy 124.625354 -213.873842) (xy 124.614432 -213.896448) (xy 124.820172 -214.292942) (xy 124.845826 -214.296752)
			(xy 124.87151 -214.301109) (xy 124.921167 -214.316849) (xy 124.967731 -214.340204) (xy 125.010041 -214.370592)
			(xy 125.047044 -214.407258) (xy 125.077819 -214.449288) (xy 125.101599 -214.495635) (xy 125.117793 -214.545146)
			(xy 125.125998 -214.596588) (xy 125.126496 -214.622634) (xy 125.125988 -214.648521) (xy 125.117889 -214.699659)
			(xy 125.10189 -214.748899) (xy 125.078384 -214.795031) (xy 125.047952 -214.836918) (xy 125.011342 -214.873528)
			(xy 124.969455 -214.90396) (xy 124.923323 -214.927466) (xy 124.874083 -214.943465) (xy 124.822945 -214.951564)
			(xy 124.771171 -214.951564) (xy 124.720033 -214.943465) (xy 124.670793 -214.927466) (xy 124.624661 -214.90396)
			(xy 124.582774 -214.873528) (xy 124.546164 -214.836918) (xy 124.515732 -214.795031) (xy 124.492226 -214.748899)
			(xy 124.476227 -214.699659) (xy 124.468128 -214.648521) (xy 124.46762 -214.622634) (xy 124.468099 -214.597068)
			(xy 124.476002 -214.546552) (xy 124.491623 -214.497866) (xy 124.502672 -214.474806) (xy 124.514102 -214.451438)
			(xy 124.31268 -214.062818) (xy 124.28601 -214.059516) (xy 124.259814 -214.055663) (xy 124.20902 -214.04073)
			(xy 124.161267 -214.017866) (xy 124.117785 -213.987661) (xy 124.079693 -213.950891) (xy 124.047971 -213.908503)
			(xy 124.023436 -213.861587) (xy 124.006718 -213.811352) (xy 123.998249 -213.75909) (xy 123.99772 -213.732618)
			(xy 122.777504 -213.732618) (xy 122.777153 -213.755595) (xy 122.770832 -213.80111) (xy 122.758248 -213.845306)
			(xy 122.74931 -213.866476) (xy 122.739404 -213.888828) (xy 122.953018 -214.293958) (xy 122.977148 -214.29853)
			(xy 123.002067 -214.303641) (xy 123.050077 -214.320441) (xy 123.094936 -214.344419) (xy 123.135576 -214.375006)
			(xy 123.171034 -214.411476) (xy 123.200466 -214.452961) (xy 123.223173 -214.498476) (xy 123.238615 -214.54694)
			(xy 123.246427 -214.597201) (xy 123.246896 -214.622634) (xy 123.246388 -214.648521) (xy 123.238289 -214.699659)
			(xy 123.22229 -214.748899) (xy 123.198784 -214.795031) (xy 123.168352 -214.836918) (xy 123.131742 -214.873528)
			(xy 123.089855 -214.90396) (xy 123.043723 -214.927466) (xy 122.994483 -214.943465) (xy 122.943345 -214.951564)
			(xy 122.891571 -214.951564) (xy 122.840433 -214.943465) (xy 122.791193 -214.927466) (xy 122.745061 -214.90396)
			(xy 122.703174 -214.873528) (xy 122.666564 -214.836918) (xy 122.636132 -214.795031) (xy 122.612626 -214.748899)
			(xy 122.596627 -214.699659) (xy 122.588528 -214.648521) (xy 122.58802 -214.622634) (xy 122.588387 -214.599658)
			(xy 122.5947 -214.554143) (xy 122.607279 -214.509947) (xy 122.616214 -214.488776) (xy 122.62612 -214.466424)
			(xy 122.412506 -214.061294) (xy 122.388376 -214.056722) (xy 122.36345 -214.051639) (xy 122.315436 -214.034839)
			(xy 122.270575 -214.010859) (xy 122.229932 -213.980269) (xy 122.194474 -213.943796) (xy 122.165043 -213.902307)
			(xy 122.142338 -213.856787) (xy 122.1269 -213.808318) (xy 122.119094 -213.758052) (xy 122.118628 -213.732618)
			(xy 120.897904 -213.732618) (xy 120.897553 -213.755595) (xy 120.891232 -213.80111) (xy 120.878648 -213.845306)
			(xy 120.86971 -213.866476) (xy 120.859804 -213.888828) (xy 121.073418 -214.293958) (xy 121.097548 -214.29853)
			(xy 121.122467 -214.303641) (xy 121.170477 -214.320441) (xy 121.215336 -214.344419) (xy 121.255976 -214.375006)
			(xy 121.291434 -214.411476) (xy 121.320866 -214.452961) (xy 121.343573 -214.498476) (xy 121.359015 -214.54694)
			(xy 121.366827 -214.597201) (xy 121.367296 -214.622634) (xy 121.366788 -214.648521) (xy 121.358689 -214.699659)
			(xy 121.34269 -214.748899) (xy 121.319184 -214.795031) (xy 121.288752 -214.836918) (xy 121.252142 -214.873528)
			(xy 121.210255 -214.90396) (xy 121.164123 -214.927466) (xy 121.114883 -214.943465) (xy 121.063745 -214.951564)
			(xy 121.011971 -214.951564) (xy 120.960833 -214.943465) (xy 120.911593 -214.927466) (xy 120.865461 -214.90396)
			(xy 120.823574 -214.873528) (xy 120.786964 -214.836918) (xy 120.756532 -214.795031) (xy 120.733026 -214.748899)
			(xy 120.717027 -214.699659) (xy 120.708928 -214.648521) (xy 120.70842 -214.622634) (xy 120.708787 -214.599658)
			(xy 120.7151 -214.554143) (xy 120.727679 -214.509947) (xy 120.736614 -214.488776) (xy 120.74652 -214.466424)
			(xy 120.532906 -214.061294) (xy 120.508776 -214.056722) (xy 120.48385 -214.051639) (xy 120.435836 -214.034839)
			(xy 120.390975 -214.010859) (xy 120.350332 -213.980269) (xy 120.314874 -213.943796) (xy 120.285443 -213.902307)
			(xy 120.262738 -213.856787) (xy 120.2473 -213.808318) (xy 120.239494 -213.758052) (xy 120.239028 -213.732618)
			(xy 119.018304 -213.732618) (xy 119.017953 -213.755595) (xy 119.011632 -213.80111) (xy 118.999048 -213.845306)
			(xy 118.99011 -213.866476) (xy 118.980204 -213.888828) (xy 119.193818 -214.293958) (xy 119.217948 -214.29853)
			(xy 119.242867 -214.303641) (xy 119.290877 -214.320441) (xy 119.335736 -214.344419) (xy 119.376376 -214.375006)
			(xy 119.411834 -214.411476) (xy 119.441266 -214.452961) (xy 119.463973 -214.498476) (xy 119.479415 -214.54694)
			(xy 119.487227 -214.597201) (xy 119.487696 -214.622634) (xy 119.487188 -214.648521) (xy 119.479089 -214.699659)
			(xy 119.46309 -214.748899) (xy 119.439584 -214.795031) (xy 119.409152 -214.836918) (xy 119.372542 -214.873528)
			(xy 119.330655 -214.90396) (xy 119.284523 -214.927466) (xy 119.235283 -214.943465) (xy 119.184145 -214.951564)
			(xy 119.132371 -214.951564) (xy 119.081233 -214.943465) (xy 119.031993 -214.927466) (xy 118.985861 -214.90396)
			(xy 118.943974 -214.873528) (xy 118.907364 -214.836918) (xy 118.876932 -214.795031) (xy 118.853426 -214.748899)
			(xy 118.837427 -214.699659) (xy 118.829328 -214.648521) (xy 118.82882 -214.622634) (xy 118.829187 -214.599658)
			(xy 118.8355 -214.554143) (xy 118.848079 -214.509947) (xy 118.857014 -214.488776) (xy 118.86692 -214.466424)
			(xy 118.653306 -214.061294) (xy 118.629176 -214.056722) (xy 118.60425 -214.051639) (xy 118.556236 -214.034839)
			(xy 118.511375 -214.010859) (xy 118.470732 -213.980269) (xy 118.435274 -213.943796) (xy 118.405843 -213.902307)
			(xy 118.383138 -213.856787) (xy 118.3677 -213.808318) (xy 118.359894 -213.758052) (xy 118.359428 -213.732618)
			(xy 117.138704 -213.732618) (xy 117.138353 -213.755595) (xy 117.132032 -213.80111) (xy 117.119448 -213.845306)
			(xy 117.11051 -213.866476) (xy 117.100604 -213.888828) (xy 117.314218 -214.293958) (xy 117.338348 -214.29853)
			(xy 117.363267 -214.303641) (xy 117.411277 -214.320441) (xy 117.456136 -214.344419) (xy 117.496776 -214.375006)
			(xy 117.532234 -214.411476) (xy 117.561666 -214.452961) (xy 117.584373 -214.498476) (xy 117.599815 -214.54694)
			(xy 117.607627 -214.597201) (xy 117.608096 -214.622634) (xy 117.607588 -214.648521) (xy 117.599489 -214.699659)
			(xy 117.58349 -214.748899) (xy 117.559984 -214.795031) (xy 117.529552 -214.836918) (xy 117.492942 -214.873528)
			(xy 117.451055 -214.90396) (xy 117.404923 -214.927466) (xy 117.355683 -214.943465) (xy 117.304545 -214.951564)
			(xy 117.252771 -214.951564) (xy 117.201633 -214.943465) (xy 117.152393 -214.927466) (xy 117.106261 -214.90396)
			(xy 117.064374 -214.873528) (xy 117.027764 -214.836918) (xy 116.997332 -214.795031) (xy 116.973826 -214.748899)
			(xy 116.957827 -214.699659) (xy 116.949728 -214.648521) (xy 116.94922 -214.622634) (xy 116.949587 -214.599658)
			(xy 116.9559 -214.554143) (xy 116.968479 -214.509947) (xy 116.977414 -214.488776) (xy 116.98732 -214.466424)
			(xy 116.773706 -214.061294) (xy 116.749576 -214.056722) (xy 116.72465 -214.051639) (xy 116.676636 -214.034839)
			(xy 116.631775 -214.010859) (xy 116.591132 -213.980269) (xy 116.555674 -213.943796) (xy 116.526243 -213.902307)
			(xy 116.503538 -213.856787) (xy 116.4881 -213.808318) (xy 116.480294 -213.758052) (xy 116.479828 -213.732618)
			(xy 115.259104 -213.732618) (xy 115.258753 -213.755595) (xy 115.252432 -213.80111) (xy 115.239848 -213.845306)
			(xy 115.23091 -213.866476) (xy 115.221004 -213.888828) (xy 115.434618 -214.293958) (xy 115.458748 -214.29853)
			(xy 115.483667 -214.303641) (xy 115.531677 -214.320441) (xy 115.576536 -214.344419) (xy 115.617176 -214.375006)
			(xy 115.652634 -214.411476) (xy 115.682066 -214.452961) (xy 115.704773 -214.498476) (xy 115.720215 -214.54694)
			(xy 115.728027 -214.597201) (xy 115.728496 -214.622634) (xy 115.727988 -214.648521) (xy 115.719889 -214.699659)
			(xy 115.70389 -214.748899) (xy 115.680384 -214.795031) (xy 115.649952 -214.836918) (xy 115.613342 -214.873528)
			(xy 115.571455 -214.90396) (xy 115.525323 -214.927466) (xy 115.476083 -214.943465) (xy 115.424945 -214.951564)
			(xy 115.373171 -214.951564) (xy 115.322033 -214.943465) (xy 115.272793 -214.927466) (xy 115.226661 -214.90396)
			(xy 115.184774 -214.873528) (xy 115.148164 -214.836918) (xy 115.117732 -214.795031) (xy 115.094226 -214.748899)
			(xy 115.078227 -214.699659) (xy 115.070128 -214.648521) (xy 115.06962 -214.622634) (xy 115.069987 -214.599658)
			(xy 115.0763 -214.554143) (xy 115.088879 -214.509947) (xy 115.097814 -214.488776) (xy 115.10772 -214.466424)
			(xy 114.894106 -214.061294) (xy 114.869976 -214.056722) (xy 114.84505 -214.051639) (xy 114.797036 -214.034839)
			(xy 114.752175 -214.010859) (xy 114.711532 -213.980269) (xy 114.676074 -213.943796) (xy 114.646643 -213.902307)
			(xy 114.623938 -213.856787) (xy 114.6085 -213.808318) (xy 114.600694 -213.758052) (xy 114.600228 -213.732618)
			(xy 107.740704 -213.732618) (xy 107.740353 -213.755595) (xy 107.734032 -213.80111) (xy 107.721448 -213.845306)
			(xy 107.71251 -213.866476) (xy 107.702604 -213.888828) (xy 107.916218 -214.293958) (xy 107.940348 -214.29853)
			(xy 107.965267 -214.303641) (xy 108.013277 -214.320441) (xy 108.058136 -214.344419) (xy 108.098776 -214.375006)
			(xy 108.134234 -214.411476) (xy 108.163666 -214.452961) (xy 108.186373 -214.498476) (xy 108.201815 -214.54694)
			(xy 108.209627 -214.597201) (xy 108.210096 -214.622634) (xy 108.209588 -214.648521) (xy 108.201489 -214.699659)
			(xy 108.18549 -214.748899) (xy 108.161984 -214.795031) (xy 108.131552 -214.836918) (xy 108.094942 -214.873528)
			(xy 108.053055 -214.90396) (xy 108.006923 -214.927466) (xy 107.957683 -214.943465) (xy 107.906545 -214.951564)
			(xy 107.854771 -214.951564) (xy 107.803633 -214.943465) (xy 107.754393 -214.927466) (xy 107.708261 -214.90396)
			(xy 107.666374 -214.873528) (xy 107.629764 -214.836918) (xy 107.599332 -214.795031) (xy 107.575826 -214.748899)
			(xy 107.559827 -214.699659) (xy 107.551728 -214.648521) (xy 107.55122 -214.622634) (xy 107.551587 -214.599658)
			(xy 107.5579 -214.554143) (xy 107.570479 -214.509947) (xy 107.579414 -214.488776) (xy 107.58932 -214.466424)
			(xy 107.375706 -214.061294) (xy 107.351576 -214.056722) (xy 107.32665 -214.051639) (xy 107.278636 -214.034839)
			(xy 107.233775 -214.010859) (xy 107.193132 -213.980269) (xy 107.157674 -213.943796) (xy 107.128243 -213.902307)
			(xy 107.105538 -213.856787) (xy 107.0901 -213.808318) (xy 107.082294 -213.758052) (xy 107.081828 -213.732618)
			(xy 105.861104 -213.732618) (xy 105.860753 -213.755595) (xy 105.854432 -213.80111) (xy 105.841848 -213.845306)
			(xy 105.83291 -213.866476) (xy 105.823004 -213.888828) (xy 106.036618 -214.293958) (xy 106.060748 -214.29853)
			(xy 106.085667 -214.303641) (xy 106.133677 -214.320441) (xy 106.178536 -214.344419) (xy 106.219176 -214.375006)
			(xy 106.254634 -214.411476) (xy 106.284066 -214.452961) (xy 106.306773 -214.498476) (xy 106.322215 -214.54694)
			(xy 106.330027 -214.597201) (xy 106.330496 -214.622634) (xy 106.329988 -214.648521) (xy 106.321889 -214.699659)
			(xy 106.30589 -214.748899) (xy 106.282384 -214.795031) (xy 106.251952 -214.836918) (xy 106.215342 -214.873528)
			(xy 106.173455 -214.90396) (xy 106.127323 -214.927466) (xy 106.078083 -214.943465) (xy 106.026945 -214.951564)
			(xy 105.975171 -214.951564) (xy 105.924033 -214.943465) (xy 105.874793 -214.927466) (xy 105.828661 -214.90396)
			(xy 105.786774 -214.873528) (xy 105.750164 -214.836918) (xy 105.719732 -214.795031) (xy 105.696226 -214.748899)
			(xy 105.680227 -214.699659) (xy 105.672128 -214.648521) (xy 105.67162 -214.622634) (xy 105.671987 -214.599658)
			(xy 105.6783 -214.554143) (xy 105.690879 -214.509947) (xy 105.699814 -214.488776) (xy 105.70972 -214.466424)
			(xy 105.496106 -214.061294) (xy 105.471976 -214.056722) (xy 105.44705 -214.051639) (xy 105.399036 -214.034839)
			(xy 105.354175 -214.010859) (xy 105.313532 -213.980269) (xy 105.278074 -213.943796) (xy 105.248643 -213.902307)
			(xy 105.225938 -213.856787) (xy 105.2105 -213.808318) (xy 105.202694 -213.758052) (xy 105.202228 -213.732618)
			(xy 103.981504 -213.732618) (xy 103.981153 -213.755595) (xy 103.974832 -213.80111) (xy 103.962248 -213.845306)
			(xy 103.95331 -213.866476) (xy 103.943404 -213.888828) (xy 104.157018 -214.293958) (xy 104.181148 -214.29853)
			(xy 104.206067 -214.303641) (xy 104.254077 -214.320441) (xy 104.298936 -214.344419) (xy 104.339576 -214.375006)
			(xy 104.375034 -214.411476) (xy 104.404466 -214.452961) (xy 104.427173 -214.498476) (xy 104.442615 -214.54694)
			(xy 104.450427 -214.597201) (xy 104.450896 -214.622634) (xy 104.450388 -214.648521) (xy 104.442289 -214.699659)
			(xy 104.42629 -214.748899) (xy 104.402784 -214.795031) (xy 104.372352 -214.836918) (xy 104.335742 -214.873528)
			(xy 104.293855 -214.90396) (xy 104.247723 -214.927466) (xy 104.198483 -214.943465) (xy 104.147345 -214.951564)
			(xy 104.095571 -214.951564) (xy 104.044433 -214.943465) (xy 103.995193 -214.927466) (xy 103.949061 -214.90396)
			(xy 103.907174 -214.873528) (xy 103.870564 -214.836918) (xy 103.840132 -214.795031) (xy 103.816626 -214.748899)
			(xy 103.800627 -214.699659) (xy 103.792528 -214.648521) (xy 103.79202 -214.622634) (xy 103.792387 -214.599658)
			(xy 103.7987 -214.554143) (xy 103.811279 -214.509947) (xy 103.820214 -214.488776) (xy 103.83012 -214.466424)
			(xy 103.616506 -214.061294) (xy 103.592376 -214.056722) (xy 103.56745 -214.051639) (xy 103.519436 -214.034839)
			(xy 103.474575 -214.010859) (xy 103.433932 -213.980269) (xy 103.398474 -213.943796) (xy 103.369043 -213.902307)
			(xy 103.346338 -213.856787) (xy 103.3309 -213.808318) (xy 103.323094 -213.758052) (xy 103.322628 -213.732618)
			(xy 102.101904 -213.732618) (xy 102.101553 -213.755595) (xy 102.095232 -213.80111) (xy 102.082648 -213.845306)
			(xy 102.07371 -213.866476) (xy 102.063804 -213.888828) (xy 102.277418 -214.293958) (xy 102.301548 -214.29853)
			(xy 102.326467 -214.303641) (xy 102.374477 -214.320441) (xy 102.419336 -214.344419) (xy 102.459976 -214.375006)
			(xy 102.495434 -214.411476) (xy 102.524866 -214.452961) (xy 102.547573 -214.498476) (xy 102.563015 -214.54694)
			(xy 102.570827 -214.597201) (xy 102.571296 -214.622634) (xy 102.570788 -214.648521) (xy 102.562689 -214.699659)
			(xy 102.54669 -214.748899) (xy 102.523184 -214.795031) (xy 102.492752 -214.836918) (xy 102.456142 -214.873528)
			(xy 102.414255 -214.90396) (xy 102.368123 -214.927466) (xy 102.318883 -214.943465) (xy 102.267745 -214.951564)
			(xy 102.215971 -214.951564) (xy 102.164833 -214.943465) (xy 102.115593 -214.927466) (xy 102.069461 -214.90396)
			(xy 102.027574 -214.873528) (xy 101.990964 -214.836918) (xy 101.960532 -214.795031) (xy 101.937026 -214.748899)
			(xy 101.921027 -214.699659) (xy 101.912928 -214.648521) (xy 101.91242 -214.622634) (xy 101.912787 -214.599658)
			(xy 101.9191 -214.554143) (xy 101.931679 -214.509947) (xy 101.940614 -214.488776) (xy 101.95052 -214.466424)
			(xy 101.736906 -214.061294) (xy 101.712776 -214.056722) (xy 101.68785 -214.051639) (xy 101.639836 -214.034839)
			(xy 101.594975 -214.010859) (xy 101.554332 -213.980269) (xy 101.518874 -213.943796) (xy 101.489443 -213.902307)
			(xy 101.466738 -213.856787) (xy 101.4513 -213.808318) (xy 101.443494 -213.758052) (xy 101.443028 -213.732618)
			(xy 100.222304 -213.732618) (xy 100.221953 -213.755595) (xy 100.215632 -213.80111) (xy 100.203048 -213.845306)
			(xy 100.19411 -213.866476) (xy 100.184204 -213.888828) (xy 100.397818 -214.293958) (xy 100.421948 -214.29853)
			(xy 100.446867 -214.303641) (xy 100.494877 -214.320441) (xy 100.539736 -214.344419) (xy 100.580376 -214.375006)
			(xy 100.615834 -214.411476) (xy 100.645266 -214.452961) (xy 100.667973 -214.498476) (xy 100.683415 -214.54694)
			(xy 100.691227 -214.597201) (xy 100.691696 -214.622634) (xy 100.691188 -214.648521) (xy 100.683089 -214.699659)
			(xy 100.66709 -214.748899) (xy 100.643584 -214.795031) (xy 100.613152 -214.836918) (xy 100.576542 -214.873528)
			(xy 100.534655 -214.90396) (xy 100.488523 -214.927466) (xy 100.439283 -214.943465) (xy 100.388145 -214.951564)
			(xy 100.336371 -214.951564) (xy 100.285233 -214.943465) (xy 100.235993 -214.927466) (xy 100.189861 -214.90396)
			(xy 100.147974 -214.873528) (xy 100.111364 -214.836918) (xy 100.080932 -214.795031) (xy 100.057426 -214.748899)
			(xy 100.041427 -214.699659) (xy 100.033328 -214.648521) (xy 100.03282 -214.622634) (xy 100.033187 -214.599658)
			(xy 100.0395 -214.554143) (xy 100.052079 -214.509947) (xy 100.061014 -214.488776) (xy 100.07092 -214.466424)
			(xy 99.857306 -214.061294) (xy 99.833176 -214.056722) (xy 99.80825 -214.051639) (xy 99.760236 -214.034839)
			(xy 99.715375 -214.010859) (xy 99.674732 -213.980269) (xy 99.639274 -213.943796) (xy 99.609843 -213.902307)
			(xy 99.587138 -213.856787) (xy 99.5717 -213.808318) (xy 99.563894 -213.758052) (xy 99.563428 -213.732618)
			(xy 98.342704 -213.732618) (xy 98.342353 -213.755595) (xy 98.336032 -213.80111) (xy 98.323448 -213.845306)
			(xy 98.31451 -213.866476) (xy 98.304604 -213.888828) (xy 98.518218 -214.293958) (xy 98.542348 -214.29853)
			(xy 98.567267 -214.303641) (xy 98.615277 -214.320441) (xy 98.660136 -214.344419) (xy 98.700776 -214.375006)
			(xy 98.736234 -214.411476) (xy 98.765666 -214.452961) (xy 98.788373 -214.498476) (xy 98.803815 -214.54694)
			(xy 98.811627 -214.597201) (xy 98.812096 -214.622634) (xy 98.811588 -214.648521) (xy 98.803489 -214.699659)
			(xy 98.78749 -214.748899) (xy 98.763984 -214.795031) (xy 98.733552 -214.836918) (xy 98.696942 -214.873528)
			(xy 98.655055 -214.90396) (xy 98.608923 -214.927466) (xy 98.559683 -214.943465) (xy 98.508545 -214.951564)
			(xy 98.456771 -214.951564) (xy 98.405633 -214.943465) (xy 98.356393 -214.927466) (xy 98.310261 -214.90396)
			(xy 98.268374 -214.873528) (xy 98.231764 -214.836918) (xy 98.201332 -214.795031) (xy 98.177826 -214.748899)
			(xy 98.161827 -214.699659) (xy 98.153728 -214.648521) (xy 98.15322 -214.622634) (xy 98.153587 -214.599658)
			(xy 98.1599 -214.554143) (xy 98.172479 -214.509947) (xy 98.181414 -214.488776) (xy 98.19132 -214.466424)
			(xy 97.977706 -214.061294) (xy 97.953576 -214.056722) (xy 97.92865 -214.051639) (xy 97.880636 -214.034839)
			(xy 97.835775 -214.010859) (xy 97.795132 -213.980269) (xy 97.759674 -213.943796) (xy 97.730243 -213.902307)
			(xy 97.707538 -213.856787) (xy 97.6921 -213.808318) (xy 97.684294 -213.758052) (xy 97.683828 -213.732618)
			(xy 96.463104 -213.732618) (xy 96.462753 -213.755595) (xy 96.456432 -213.80111) (xy 96.443848 -213.845306)
			(xy 96.43491 -213.866476) (xy 96.425004 -213.888828) (xy 96.638618 -214.293958) (xy 96.662748 -214.29853)
			(xy 96.687667 -214.303641) (xy 96.735677 -214.320441) (xy 96.780536 -214.344419) (xy 96.821176 -214.375006)
			(xy 96.856634 -214.411476) (xy 96.886066 -214.452961) (xy 96.908773 -214.498476) (xy 96.924215 -214.54694)
			(xy 96.932027 -214.597201) (xy 96.932496 -214.622634) (xy 96.931988 -214.648521) (xy 96.923889 -214.699659)
			(xy 96.90789 -214.748899) (xy 96.884384 -214.795031) (xy 96.853952 -214.836918) (xy 96.817342 -214.873528)
			(xy 96.775455 -214.90396) (xy 96.729323 -214.927466) (xy 96.680083 -214.943465) (xy 96.628945 -214.951564)
			(xy 96.577171 -214.951564) (xy 96.526033 -214.943465) (xy 96.476793 -214.927466) (xy 96.430661 -214.90396)
			(xy 96.388774 -214.873528) (xy 96.352164 -214.836918) (xy 96.321732 -214.795031) (xy 96.298226 -214.748899)
			(xy 96.282227 -214.699659) (xy 96.274128 -214.648521) (xy 96.27362 -214.622634) (xy 96.273987 -214.599658)
			(xy 96.2803 -214.554143) (xy 96.292879 -214.509947) (xy 96.301814 -214.488776) (xy 96.31172 -214.466424)
			(xy 96.098106 -214.061294) (xy 96.073976 -214.056722) (xy 96.04905 -214.051639) (xy 96.001036 -214.034839)
			(xy 95.956175 -214.010859) (xy 95.915532 -213.980269) (xy 95.880074 -213.943796) (xy 95.850643 -213.902307)
			(xy 95.827938 -213.856787) (xy 95.8125 -213.808318) (xy 95.804694 -213.758052) (xy 95.804228 -213.732618)
			(xy 94.583504 -213.732618) (xy 94.583153 -213.755595) (xy 94.576832 -213.80111) (xy 94.564248 -213.845306)
			(xy 94.55531 -213.866476) (xy 94.545404 -213.888828) (xy 94.759018 -214.293958) (xy 94.783148 -214.29853)
			(xy 94.808067 -214.303641) (xy 94.856077 -214.320441) (xy 94.900936 -214.344419) (xy 94.941576 -214.375006)
			(xy 94.977034 -214.411476) (xy 95.006466 -214.452961) (xy 95.029173 -214.498476) (xy 95.044615 -214.54694)
			(xy 95.052427 -214.597201) (xy 95.052896 -214.622634) (xy 95.052388 -214.648521) (xy 95.044289 -214.699659)
			(xy 95.02829 -214.748899) (xy 95.004784 -214.795031) (xy 94.974352 -214.836918) (xy 94.937742 -214.873528)
			(xy 94.895855 -214.90396) (xy 94.849723 -214.927466) (xy 94.800483 -214.943465) (xy 94.749345 -214.951564)
			(xy 94.697571 -214.951564) (xy 94.646433 -214.943465) (xy 94.597193 -214.927466) (xy 94.551061 -214.90396)
			(xy 94.509174 -214.873528) (xy 94.472564 -214.836918) (xy 94.442132 -214.795031) (xy 94.418626 -214.748899)
			(xy 94.402627 -214.699659) (xy 94.394528 -214.648521) (xy 94.39402 -214.622634) (xy 94.394387 -214.599658)
			(xy 94.4007 -214.554143) (xy 94.413279 -214.509947) (xy 94.422214 -214.488776) (xy 94.43212 -214.466424)
			(xy 94.218506 -214.061294) (xy 94.194376 -214.056722) (xy 94.16945 -214.051639) (xy 94.121436 -214.034839)
			(xy 94.076575 -214.010859) (xy 94.035932 -213.980269) (xy 94.000474 -213.943796) (xy 93.971043 -213.902307)
			(xy 93.948338 -213.856787) (xy 93.9329 -213.808318) (xy 93.925094 -213.758052) (xy 93.924628 -213.732618)
			(xy 92.703904 -213.732618) (xy 92.703553 -213.755595) (xy 92.697232 -213.80111) (xy 92.684648 -213.845306)
			(xy 92.67571 -213.866476) (xy 92.665804 -213.888828) (xy 92.879418 -214.293958) (xy 92.903548 -214.29853)
			(xy 92.928467 -214.303641) (xy 92.976477 -214.320441) (xy 93.021336 -214.344419) (xy 93.061976 -214.375006)
			(xy 93.097434 -214.411476) (xy 93.126866 -214.452961) (xy 93.149573 -214.498476) (xy 93.165015 -214.54694)
			(xy 93.172827 -214.597201) (xy 93.173296 -214.622634) (xy 93.172788 -214.648521) (xy 93.164689 -214.699659)
			(xy 93.14869 -214.748899) (xy 93.125184 -214.795031) (xy 93.094752 -214.836918) (xy 93.058142 -214.873528)
			(xy 93.016255 -214.90396) (xy 92.970123 -214.927466) (xy 92.920883 -214.943465) (xy 92.869745 -214.951564)
			(xy 92.817971 -214.951564) (xy 92.766833 -214.943465) (xy 92.717593 -214.927466) (xy 92.671461 -214.90396)
			(xy 92.629574 -214.873528) (xy 92.592964 -214.836918) (xy 92.562532 -214.795031) (xy 92.539026 -214.748899)
			(xy 92.523027 -214.699659) (xy 92.514928 -214.648521) (xy 92.51442 -214.622634) (xy 92.514787 -214.599658)
			(xy 92.5211 -214.554143) (xy 92.533679 -214.509947) (xy 92.542614 -214.488776) (xy 92.55252 -214.466424)
			(xy 92.338906 -214.061294) (xy 92.314776 -214.056722) (xy 92.28985 -214.051639) (xy 92.241836 -214.034839)
			(xy 92.196975 -214.010859) (xy 92.156332 -213.980269) (xy 92.120874 -213.943796) (xy 92.091443 -213.902307)
			(xy 92.068738 -213.856787) (xy 92.0533 -213.808318) (xy 92.045494 -213.758052) (xy 92.045028 -213.732618)
			(xy 90.824304 -213.732618) (xy 90.823953 -213.755595) (xy 90.817632 -213.80111) (xy 90.805048 -213.845306)
			(xy 90.79611 -213.866476) (xy 90.786204 -213.888828) (xy 90.999818 -214.293958) (xy 91.023948 -214.29853)
			(xy 91.048867 -214.303641) (xy 91.096877 -214.320441) (xy 91.141736 -214.344419) (xy 91.182376 -214.375006)
			(xy 91.217834 -214.411476) (xy 91.247266 -214.452961) (xy 91.269973 -214.498476) (xy 91.285415 -214.54694)
			(xy 91.293227 -214.597201) (xy 91.293696 -214.622634) (xy 91.293188 -214.648521) (xy 91.285089 -214.699659)
			(xy 91.26909 -214.748899) (xy 91.245584 -214.795031) (xy 91.215152 -214.836918) (xy 91.178542 -214.873528)
			(xy 91.136655 -214.90396) (xy 91.090523 -214.927466) (xy 91.041283 -214.943465) (xy 90.990145 -214.951564)
			(xy 90.938371 -214.951564) (xy 90.887233 -214.943465) (xy 90.837993 -214.927466) (xy 90.791861 -214.90396)
			(xy 90.749974 -214.873528) (xy 90.713364 -214.836918) (xy 90.682932 -214.795031) (xy 90.659426 -214.748899)
			(xy 90.643427 -214.699659) (xy 90.635328 -214.648521) (xy 90.63482 -214.622634) (xy 90.635187 -214.599658)
			(xy 90.6415 -214.554143) (xy 90.654079 -214.509947) (xy 90.663014 -214.488776) (xy 90.67292 -214.466424)
			(xy 90.459306 -214.061294) (xy 90.435176 -214.056722) (xy 90.41025 -214.051639) (xy 90.362236 -214.034839)
			(xy 90.317375 -214.010859) (xy 90.276732 -213.980269) (xy 90.241274 -213.943796) (xy 90.211843 -213.902307)
			(xy 90.189138 -213.856787) (xy 90.1737 -213.808318) (xy 90.165894 -213.758052) (xy 90.165428 -213.732618)
			(xy 2.509012 -213.732618) (xy 2.509012 -215.436704) (xy 88.28532 -215.436704) (xy 88.285828 -215.410797)
			(xy 88.293934 -215.35962) (xy 88.309946 -215.310341) (xy 88.333469 -215.264174) (xy 88.363925 -215.222255)
			(xy 88.400563 -215.185617) (xy 88.442482 -215.155161) (xy 88.488649 -215.131638) (xy 88.537928 -215.115626)
			(xy 88.589105 -215.10752) (xy 88.640919 -215.10752) (xy 88.692096 -215.115626) (xy 88.741375 -215.131638)
			(xy 88.787542 -215.155161) (xy 88.829461 -215.185617) (xy 88.866099 -215.222255) (xy 88.896555 -215.264174)
			(xy 88.920078 -215.310341) (xy 88.93609 -215.35962) (xy 88.944196 -215.410797) (xy 88.944704 -215.436704)
			(xy 89.22512 -215.436704) (xy 89.225629 -215.41136) (xy 89.2334 -215.36127) (xy 89.248746 -215.31296)
			(xy 89.271303 -215.267567) (xy 89.300542 -215.226161) (xy 89.335773 -215.189717) (xy 89.376165 -215.159094)
			(xy 89.420769 -215.135013) (xy 89.468532 -215.118041) (xy 89.493344 -215.112854) (xy 89.516204 -215.108536)
			(xy 89.721182 -214.753444) (xy 89.713308 -214.7316) (xy 89.704729 -214.705181) (xy 89.695532 -214.650406)
			(xy 89.69502 -214.622634) (xy 89.695528 -214.596747) (xy 89.703627 -214.545609) (xy 89.719626 -214.496369)
			(xy 89.743132 -214.450237) (xy 89.773564 -214.40835) (xy 89.810174 -214.37174) (xy 89.852061 -214.341308)
			(xy 89.898193 -214.317802) (xy 89.947433 -214.301803) (xy 89.998571 -214.293704) (xy 90.050345 -214.293704)
			(xy 90.101483 -214.301803) (xy 90.150723 -214.317802) (xy 90.196855 -214.341308) (xy 90.238742 -214.37174)
			(xy 90.275352 -214.40835) (xy 90.305784 -214.450237) (xy 90.32929 -214.496369) (xy 90.345289 -214.545609)
			(xy 90.353388 -214.596747) (xy 90.353896 -214.622634) (xy 90.353447 -214.64797) (xy 90.34569 -214.698044)
			(xy 90.330363 -214.746341) (xy 90.307827 -214.791726) (xy 90.278612 -214.833128) (xy 90.243408 -214.869572)
			(xy 90.203042 -214.900202) (xy 90.158465 -214.924296) (xy 90.110727 -214.941286) (xy 90.085926 -214.946484)
			(xy 90.063066 -214.950802) (xy 89.858088 -215.305894) (xy 89.865962 -215.327738) (xy 89.87461 -215.354146)
			(xy 89.883929 -215.408922) (xy 89.884504 -215.436704) (xy 91.10472 -215.436704) (xy 91.105229 -215.41136)
			(xy 91.113 -215.36127) (xy 91.128346 -215.31296) (xy 91.150903 -215.267567) (xy 91.180142 -215.226161)
			(xy 91.215373 -215.189717) (xy 91.255765 -215.159094) (xy 91.300369 -215.135013) (xy 91.348132 -215.118041)
			(xy 91.372944 -215.112854) (xy 91.395804 -215.108536) (xy 91.600782 -214.753444) (xy 91.592908 -214.7316)
			(xy 91.584329 -214.705181) (xy 91.575132 -214.650406) (xy 91.57462 -214.622634) (xy 91.575128 -214.596747)
			(xy 91.583227 -214.545609) (xy 91.599226 -214.496369) (xy 91.622732 -214.450237) (xy 91.653164 -214.40835)
			(xy 91.689774 -214.37174) (xy 91.731661 -214.341308) (xy 91.777793 -214.317802) (xy 91.827033 -214.301803)
			(xy 91.878171 -214.293704) (xy 91.929945 -214.293704) (xy 91.981083 -214.301803) (xy 92.030323 -214.317802)
			(xy 92.076455 -214.341308) (xy 92.118342 -214.37174) (xy 92.154952 -214.40835) (xy 92.185384 -214.450237)
			(xy 92.20889 -214.496369) (xy 92.224889 -214.545609) (xy 92.232988 -214.596747) (xy 92.233496 -214.622634)
			(xy 92.233047 -214.64797) (xy 92.22529 -214.698044) (xy 92.209963 -214.746341) (xy 92.187427 -214.791726)
			(xy 92.158212 -214.833128) (xy 92.123008 -214.869572) (xy 92.082642 -214.900202) (xy 92.038065 -214.924296)
			(xy 91.990327 -214.941286) (xy 91.965526 -214.946484) (xy 91.942666 -214.950802) (xy 91.737688 -215.305894)
			(xy 91.745562 -215.327738) (xy 91.75421 -215.354146) (xy 91.763529 -215.408922) (xy 91.764104 -215.436704)
			(xy 92.98432 -215.436704) (xy 92.984829 -215.41136) (xy 92.9926 -215.36127) (xy 93.007946 -215.31296)
			(xy 93.030503 -215.267567) (xy 93.059742 -215.226161) (xy 93.094973 -215.189717) (xy 93.135365 -215.159094)
			(xy 93.179969 -215.135013) (xy 93.227732 -215.118041) (xy 93.252544 -215.112854) (xy 93.275404 -215.108536)
			(xy 93.480382 -214.753444) (xy 93.472508 -214.7316) (xy 93.463929 -214.705181) (xy 93.454732 -214.650406)
			(xy 93.45422 -214.622634) (xy 93.454728 -214.596747) (xy 93.462827 -214.545609) (xy 93.478826 -214.496369)
			(xy 93.502332 -214.450237) (xy 93.532764 -214.40835) (xy 93.569374 -214.37174) (xy 93.611261 -214.341308)
			(xy 93.657393 -214.317802) (xy 93.706633 -214.301803) (xy 93.757771 -214.293704) (xy 93.809545 -214.293704)
			(xy 93.860683 -214.301803) (xy 93.909923 -214.317802) (xy 93.956055 -214.341308) (xy 93.997942 -214.37174)
			(xy 94.034552 -214.40835) (xy 94.064984 -214.450237) (xy 94.08849 -214.496369) (xy 94.104489 -214.545609)
			(xy 94.112588 -214.596747) (xy 94.113096 -214.622634) (xy 94.112647 -214.64797) (xy 94.10489 -214.698044)
			(xy 94.089563 -214.746341) (xy 94.067027 -214.791726) (xy 94.037812 -214.833128) (xy 94.002608 -214.869572)
			(xy 93.962242 -214.900202) (xy 93.917665 -214.924296) (xy 93.869927 -214.941286) (xy 93.845126 -214.946484)
			(xy 93.822266 -214.950802) (xy 93.617288 -215.305894) (xy 93.625162 -215.327738) (xy 93.63381 -215.354146)
			(xy 93.643129 -215.408922) (xy 93.643704 -215.436704) (xy 94.86392 -215.436704) (xy 94.864429 -215.41136)
			(xy 94.8722 -215.36127) (xy 94.887546 -215.31296) (xy 94.910103 -215.267567) (xy 94.939342 -215.226161)
			(xy 94.974573 -215.189717) (xy 95.014965 -215.159094) (xy 95.059569 -215.135013) (xy 95.107332 -215.118041)
			(xy 95.132144 -215.112854) (xy 95.155004 -215.108536) (xy 95.359982 -214.753444) (xy 95.352108 -214.7316)
			(xy 95.343529 -214.705181) (xy 95.334332 -214.650406) (xy 95.33382 -214.622634) (xy 95.334328 -214.596747)
			(xy 95.342427 -214.545609) (xy 95.358426 -214.496369) (xy 95.381932 -214.450237) (xy 95.412364 -214.40835)
			(xy 95.448974 -214.37174) (xy 95.490861 -214.341308) (xy 95.536993 -214.317802) (xy 95.586233 -214.301803)
			(xy 95.637371 -214.293704) (xy 95.689145 -214.293704) (xy 95.740283 -214.301803) (xy 95.789523 -214.317802)
			(xy 95.835655 -214.341308) (xy 95.877542 -214.37174) (xy 95.914152 -214.40835) (xy 95.944584 -214.450237)
			(xy 95.96809 -214.496369) (xy 95.984089 -214.545609) (xy 95.992188 -214.596747) (xy 95.992696 -214.622634)
			(xy 95.992247 -214.64797) (xy 95.98449 -214.698044) (xy 95.969163 -214.746341) (xy 95.946627 -214.791726)
			(xy 95.917412 -214.833128) (xy 95.882208 -214.869572) (xy 95.841842 -214.900202) (xy 95.797265 -214.924296)
			(xy 95.749527 -214.941286) (xy 95.724726 -214.946484) (xy 95.701866 -214.950802) (xy 95.496888 -215.305894)
			(xy 95.504762 -215.327738) (xy 95.51341 -215.354146) (xy 95.522729 -215.408922) (xy 95.523304 -215.436704)
			(xy 96.74352 -215.436704) (xy 96.744029 -215.41136) (xy 96.7518 -215.36127) (xy 96.767146 -215.31296)
			(xy 96.789703 -215.267567) (xy 96.818942 -215.226161) (xy 96.854173 -215.189717) (xy 96.894565 -215.159094)
			(xy 96.939169 -215.135013) (xy 96.986932 -215.118041) (xy 97.011744 -215.112854) (xy 97.034604 -215.108536)
			(xy 97.239582 -214.753444) (xy 97.231708 -214.7316) (xy 97.223129 -214.705181) (xy 97.213932 -214.650406)
			(xy 97.21342 -214.622634) (xy 97.213928 -214.596747) (xy 97.222027 -214.545609) (xy 97.238026 -214.496369)
			(xy 97.261532 -214.450237) (xy 97.291964 -214.40835) (xy 97.328574 -214.37174) (xy 97.370461 -214.341308)
			(xy 97.416593 -214.317802) (xy 97.465833 -214.301803) (xy 97.516971 -214.293704) (xy 97.568745 -214.293704)
			(xy 97.619883 -214.301803) (xy 97.669123 -214.317802) (xy 97.715255 -214.341308) (xy 97.757142 -214.37174)
			(xy 97.793752 -214.40835) (xy 97.824184 -214.450237) (xy 97.84769 -214.496369) (xy 97.863689 -214.545609)
			(xy 97.871788 -214.596747) (xy 97.872296 -214.622634) (xy 97.871847 -214.64797) (xy 97.86409 -214.698044)
			(xy 97.848763 -214.746341) (xy 97.826227 -214.791726) (xy 97.797012 -214.833128) (xy 97.761808 -214.869572)
			(xy 97.721442 -214.900202) (xy 97.676865 -214.924296) (xy 97.629127 -214.941286) (xy 97.604326 -214.946484)
			(xy 97.581466 -214.950802) (xy 97.376488 -215.305894) (xy 97.384362 -215.327738) (xy 97.39301 -215.354146)
			(xy 97.402329 -215.408922) (xy 97.402904 -215.436704) (xy 98.62312 -215.436704) (xy 98.623629 -215.41136)
			(xy 98.6314 -215.36127) (xy 98.646746 -215.31296) (xy 98.669303 -215.267567) (xy 98.698542 -215.226161)
			(xy 98.733773 -215.189717) (xy 98.774165 -215.159094) (xy 98.818769 -215.135013) (xy 98.866532 -215.118041)
			(xy 98.891344 -215.112854) (xy 98.914204 -215.108536) (xy 99.119182 -214.753444) (xy 99.111308 -214.7316)
			(xy 99.102729 -214.705181) (xy 99.093532 -214.650406) (xy 99.09302 -214.622634) (xy 99.093528 -214.596747)
			(xy 99.101627 -214.545609) (xy 99.117626 -214.496369) (xy 99.141132 -214.450237) (xy 99.171564 -214.40835)
			(xy 99.208174 -214.37174) (xy 99.250061 -214.341308) (xy 99.296193 -214.317802) (xy 99.345433 -214.301803)
			(xy 99.396571 -214.293704) (xy 99.448345 -214.293704) (xy 99.499483 -214.301803) (xy 99.548723 -214.317802)
			(xy 99.594855 -214.341308) (xy 99.636742 -214.37174) (xy 99.673352 -214.40835) (xy 99.703784 -214.450237)
			(xy 99.72729 -214.496369) (xy 99.743289 -214.545609) (xy 99.751388 -214.596747) (xy 99.751896 -214.622634)
			(xy 99.751447 -214.64797) (xy 99.74369 -214.698044) (xy 99.728363 -214.746341) (xy 99.705827 -214.791726)
			(xy 99.676612 -214.833128) (xy 99.641408 -214.869572) (xy 99.601042 -214.900202) (xy 99.556465 -214.924296)
			(xy 99.508727 -214.941286) (xy 99.483926 -214.946484) (xy 99.461066 -214.950802) (xy 99.256088 -215.305894)
			(xy 99.263962 -215.327738) (xy 99.27261 -215.354146) (xy 99.281929 -215.408922) (xy 99.282504 -215.436704)
			(xy 100.50272 -215.436704) (xy 100.503229 -215.41136) (xy 100.511 -215.36127) (xy 100.526346 -215.31296)
			(xy 100.548903 -215.267567) (xy 100.578142 -215.226161) (xy 100.613373 -215.189717) (xy 100.653765 -215.159094)
			(xy 100.698369 -215.135013) (xy 100.746132 -215.118041) (xy 100.770944 -215.112854) (xy 100.793804 -215.108536)
			(xy 100.998782 -214.753444) (xy 100.990908 -214.7316) (xy 100.982329 -214.705181) (xy 100.973132 -214.650406)
			(xy 100.97262 -214.622634) (xy 100.973128 -214.596747) (xy 100.981227 -214.545609) (xy 100.997226 -214.496369)
			(xy 101.020732 -214.450237) (xy 101.051164 -214.40835) (xy 101.087774 -214.37174) (xy 101.129661 -214.341308)
			(xy 101.175793 -214.317802) (xy 101.225033 -214.301803) (xy 101.276171 -214.293704) (xy 101.327945 -214.293704)
			(xy 101.379083 -214.301803) (xy 101.428323 -214.317802) (xy 101.474455 -214.341308) (xy 101.516342 -214.37174)
			(xy 101.552952 -214.40835) (xy 101.583384 -214.450237) (xy 101.60689 -214.496369) (xy 101.622889 -214.545609)
			(xy 101.630988 -214.596747) (xy 101.631496 -214.622634) (xy 101.631047 -214.64797) (xy 101.62329 -214.698044)
			(xy 101.607963 -214.746341) (xy 101.585427 -214.791726) (xy 101.556212 -214.833128) (xy 101.521008 -214.869572)
			(xy 101.480642 -214.900202) (xy 101.436065 -214.924296) (xy 101.388327 -214.941286) (xy 101.363526 -214.946484)
			(xy 101.340666 -214.950802) (xy 101.135688 -215.305894) (xy 101.143562 -215.327738) (xy 101.15221 -215.354146)
			(xy 101.161529 -215.408922) (xy 101.162104 -215.436704) (xy 102.38232 -215.436704) (xy 102.382829 -215.41136)
			(xy 102.3906 -215.36127) (xy 102.405946 -215.31296) (xy 102.428503 -215.267567) (xy 102.457742 -215.226161)
			(xy 102.492973 -215.189717) (xy 102.533365 -215.159094) (xy 102.577969 -215.135013) (xy 102.625732 -215.118041)
			(xy 102.650544 -215.112854) (xy 102.673404 -215.108536) (xy 102.878382 -214.753444) (xy 102.870508 -214.7316)
			(xy 102.861929 -214.705181) (xy 102.852732 -214.650406) (xy 102.85222 -214.622634) (xy 102.852728 -214.596747)
			(xy 102.860827 -214.545609) (xy 102.876826 -214.496369) (xy 102.900332 -214.450237) (xy 102.930764 -214.40835)
			(xy 102.967374 -214.37174) (xy 103.009261 -214.341308) (xy 103.055393 -214.317802) (xy 103.104633 -214.301803)
			(xy 103.155771 -214.293704) (xy 103.207545 -214.293704) (xy 103.258683 -214.301803) (xy 103.307923 -214.317802)
			(xy 103.354055 -214.341308) (xy 103.395942 -214.37174) (xy 103.432552 -214.40835) (xy 103.462984 -214.450237)
			(xy 103.48649 -214.496369) (xy 103.502489 -214.545609) (xy 103.510588 -214.596747) (xy 103.511096 -214.622634)
			(xy 103.510647 -214.64797) (xy 103.50289 -214.698044) (xy 103.487563 -214.746341) (xy 103.465027 -214.791726)
			(xy 103.435812 -214.833128) (xy 103.400608 -214.869572) (xy 103.360242 -214.900202) (xy 103.315665 -214.924296)
			(xy 103.267927 -214.941286) (xy 103.243126 -214.946484) (xy 103.220266 -214.950802) (xy 103.015288 -215.305894)
			(xy 103.023162 -215.327738) (xy 103.03181 -215.354146) (xy 103.041129 -215.408922) (xy 103.041704 -215.436704)
			(xy 104.26192 -215.436704) (xy 104.262429 -215.41136) (xy 104.2702 -215.36127) (xy 104.285546 -215.31296)
			(xy 104.308103 -215.267567) (xy 104.337342 -215.226161) (xy 104.372573 -215.189717) (xy 104.412965 -215.159094)
			(xy 104.457569 -215.135013) (xy 104.505332 -215.118041) (xy 104.530144 -215.112854) (xy 104.553004 -215.108536)
			(xy 104.757982 -214.753444) (xy 104.750108 -214.7316) (xy 104.741529 -214.705181) (xy 104.732332 -214.650406)
			(xy 104.73182 -214.622634) (xy 104.732328 -214.596747) (xy 104.740427 -214.545609) (xy 104.756426 -214.496369)
			(xy 104.779932 -214.450237) (xy 104.810364 -214.40835) (xy 104.846974 -214.37174) (xy 104.888861 -214.341308)
			(xy 104.934993 -214.317802) (xy 104.984233 -214.301803) (xy 105.035371 -214.293704) (xy 105.087145 -214.293704)
			(xy 105.138283 -214.301803) (xy 105.187523 -214.317802) (xy 105.233655 -214.341308) (xy 105.275542 -214.37174)
			(xy 105.312152 -214.40835) (xy 105.342584 -214.450237) (xy 105.36609 -214.496369) (xy 105.382089 -214.545609)
			(xy 105.390188 -214.596747) (xy 105.390696 -214.622634) (xy 105.390247 -214.64797) (xy 105.38249 -214.698044)
			(xy 105.367163 -214.746341) (xy 105.344627 -214.791726) (xy 105.315412 -214.833128) (xy 105.280208 -214.869572)
			(xy 105.239842 -214.900202) (xy 105.195265 -214.924296) (xy 105.147527 -214.941286) (xy 105.122726 -214.946484)
			(xy 105.099866 -214.950802) (xy 104.894888 -215.305894) (xy 104.902762 -215.327738) (xy 104.91141 -215.354146)
			(xy 104.920729 -215.408922) (xy 104.921304 -215.436704) (xy 106.14152 -215.436704) (xy 106.142029 -215.41136)
			(xy 106.1498 -215.36127) (xy 106.165146 -215.31296) (xy 106.187703 -215.267567) (xy 106.216942 -215.226161)
			(xy 106.252173 -215.189717) (xy 106.292565 -215.159094) (xy 106.337169 -215.135013) (xy 106.384932 -215.118041)
			(xy 106.409744 -215.112854) (xy 106.432604 -215.108536) (xy 106.637582 -214.753444) (xy 106.629708 -214.7316)
			(xy 106.621129 -214.705181) (xy 106.611932 -214.650406) (xy 106.61142 -214.622634) (xy 106.611928 -214.596747)
			(xy 106.620027 -214.545609) (xy 106.636026 -214.496369) (xy 106.659532 -214.450237) (xy 106.689964 -214.40835)
			(xy 106.726574 -214.37174) (xy 106.768461 -214.341308) (xy 106.814593 -214.317802) (xy 106.863833 -214.301803)
			(xy 106.914971 -214.293704) (xy 106.966745 -214.293704) (xy 107.017883 -214.301803) (xy 107.067123 -214.317802)
			(xy 107.113255 -214.341308) (xy 107.155142 -214.37174) (xy 107.191752 -214.40835) (xy 107.222184 -214.450237)
			(xy 107.24569 -214.496369) (xy 107.261689 -214.545609) (xy 107.269788 -214.596747) (xy 107.270296 -214.622634)
			(xy 107.269847 -214.64797) (xy 107.26209 -214.698044) (xy 107.246763 -214.746341) (xy 107.224227 -214.791726)
			(xy 107.195012 -214.833128) (xy 107.159808 -214.869572) (xy 107.119442 -214.900202) (xy 107.074865 -214.924296)
			(xy 107.027127 -214.941286) (xy 107.002326 -214.946484) (xy 106.979466 -214.950802) (xy 106.774488 -215.305894)
			(xy 106.782362 -215.327738) (xy 106.79101 -215.354146) (xy 106.800329 -215.408922) (xy 106.800904 -215.436704)
			(xy 108.02112 -215.436704) (xy 108.021629 -215.41136) (xy 108.0294 -215.36127) (xy 108.044746 -215.31296)
			(xy 108.067303 -215.267567) (xy 108.096542 -215.226161) (xy 108.131773 -215.189717) (xy 108.172165 -215.159094)
			(xy 108.216769 -215.135013) (xy 108.264532 -215.118041) (xy 108.289344 -215.112854) (xy 108.312204 -215.108536)
			(xy 108.517182 -214.753444) (xy 108.509308 -214.7316) (xy 108.500729 -214.705181) (xy 108.491532 -214.650406)
			(xy 108.49102 -214.622634) (xy 108.491528 -214.596747) (xy 108.499627 -214.545609) (xy 108.515626 -214.496369)
			(xy 108.539132 -214.450237) (xy 108.569564 -214.40835) (xy 108.606174 -214.37174) (xy 108.648061 -214.341308)
			(xy 108.694193 -214.317802) (xy 108.743433 -214.301803) (xy 108.794571 -214.293704) (xy 108.846345 -214.293704)
			(xy 108.897483 -214.301803) (xy 108.946723 -214.317802) (xy 108.992855 -214.341308) (xy 109.034742 -214.37174)
			(xy 109.071352 -214.40835) (xy 109.101784 -214.450237) (xy 109.12529 -214.496369) (xy 109.141289 -214.545609)
			(xy 109.14142 -214.546434) (xy 110.371128 -214.546434) (xy 110.371636 -214.520547) (xy 110.379735 -214.469409)
			(xy 110.395734 -214.420169) (xy 110.41924 -214.374037) (xy 110.449672 -214.33215) (xy 110.486282 -214.29554)
			(xy 110.528169 -214.265108) (xy 110.574301 -214.241602) (xy 110.623541 -214.225603) (xy 110.674679 -214.217504)
			(xy 110.726453 -214.217504) (xy 110.777591 -214.225603) (xy 110.826831 -214.241602) (xy 110.872963 -214.265108)
			(xy 110.91485 -214.29554) (xy 110.95146 -214.33215) (xy 110.981892 -214.374037) (xy 111.005398 -214.420169)
			(xy 111.021397 -214.469409) (xy 111.029496 -214.520547) (xy 111.030004 -214.546434) (xy 111.030004 -214.546942)
			(xy 111.029596 -214.56979) (xy 111.029246 -214.572283) (xy 112.250803 -214.572283) (xy 112.250803 -214.520517)
			(xy 112.258901 -214.469389) (xy 112.274896 -214.420157) (xy 112.298395 -214.374033) (xy 112.32882 -214.332153)
			(xy 112.365421 -214.295547) (xy 112.407297 -214.265117) (xy 112.453418 -214.241612) (xy 112.502648 -214.22561)
			(xy 112.553775 -214.217507) (xy 112.579658 -214.216996) (xy 112.605169 -214.217509) (xy 112.655581 -214.225363)
			(xy 112.704182 -214.24089) (xy 112.749811 -214.263719) (xy 112.791377 -214.293306) (xy 112.827889 -214.328944)
			(xy 112.843564 -214.349076) (xy 113.255552 -214.349076) (xy 113.271247 -214.328958) (xy 113.307753 -214.293314)
			(xy 113.349314 -214.263719) (xy 113.394938 -214.24088) (xy 113.443536 -214.225342) (xy 113.493947 -214.217476)
			(xy 113.519458 -214.216996) (xy 113.545352 -214.217406) (xy 113.596504 -214.225502) (xy 113.645759 -214.2415)
			(xy 113.691905 -214.265008) (xy 113.733805 -214.295445) (xy 113.770428 -214.332063) (xy 113.80087 -214.373959)
			(xy 113.824384 -214.420102) (xy 113.840388 -214.469355) (xy 113.848491 -214.520506) (xy 113.848491 -214.572294)
			(xy 113.840388 -214.623445) (xy 113.824384 -214.672698) (xy 113.80087 -214.718841) (xy 113.770428 -214.760737)
			(xy 113.733805 -214.797355) (xy 113.691905 -214.827792) (xy 113.645759 -214.8513) (xy 113.596504 -214.867298)
			(xy 113.545352 -214.875394) (xy 113.519458 -214.875872) (xy 113.493944 -214.875433) (xy 113.443527 -214.867566)
			(xy 113.394925 -214.852025) (xy 113.349296 -214.829181) (xy 113.307732 -214.799581) (xy 113.271224 -214.763931)
			(xy 113.255552 -214.743792) (xy 112.843564 -214.743792) (xy 112.827909 -214.763943) (xy 112.791396 -214.799586)
			(xy 112.749827 -214.829178) (xy 112.704195 -214.852012) (xy 112.655589 -214.867542) (xy 112.605171 -214.875398)
			(xy 112.579658 -214.875872) (xy 112.553775 -214.875293) (xy 112.502648 -214.86719) (xy 112.453418 -214.851188)
			(xy 112.407297 -214.827683) (xy 112.365421 -214.797253) (xy 112.32882 -214.760647) (xy 112.298395 -214.718767)
			(xy 112.274896 -214.672643) (xy 112.258901 -214.623411) (xy 112.250803 -214.572283) (xy 111.029246 -214.572283)
			(xy 111.023246 -214.615045) (xy 111.010702 -214.658987) (xy 111.00181 -214.680038) (xy 110.991904 -214.702644)
			(xy 111.205772 -215.108028) (xy 111.229902 -215.1126) (xy 111.254835 -215.117694) (xy 111.302873 -215.134477)
			(xy 111.347761 -215.158443) (xy 111.388433 -215.189024) (xy 111.423922 -215.225492) (xy 111.453384 -215.266981)
			(xy 111.47612 -215.312505) (xy 111.491589 -215.360982) (xy 111.499424 -215.411261) (xy 111.499904 -215.436704)
			(xy 113.65992 -215.436704) (xy 113.660429 -215.41136) (xy 113.6682 -215.36127) (xy 113.683546 -215.31296)
			(xy 113.706103 -215.267567) (xy 113.735342 -215.226161) (xy 113.770573 -215.189717) (xy 113.810965 -215.159094)
			(xy 113.855569 -215.135013) (xy 113.903332 -215.118041) (xy 113.928144 -215.112854) (xy 113.951004 -215.108536)
			(xy 114.156236 -214.753444) (xy 114.148362 -214.731346) (xy 114.139733 -214.704999) (xy 114.130411 -214.650352)
			(xy 114.12982 -214.622634) (xy 114.130328 -214.596727) (xy 114.138434 -214.54555) (xy 114.154446 -214.496271)
			(xy 114.177969 -214.450104) (xy 114.208425 -214.408185) (xy 114.245063 -214.371547) (xy 114.286982 -214.341091)
			(xy 114.333149 -214.317568) (xy 114.382428 -214.301556) (xy 114.433605 -214.29345) (xy 114.485419 -214.29345)
			(xy 114.536596 -214.301556) (xy 114.585875 -214.317568) (xy 114.632042 -214.341091) (xy 114.673961 -214.371547)
			(xy 114.710599 -214.408185) (xy 114.741055 -214.450104) (xy 114.764578 -214.496271) (xy 114.78059 -214.54555)
			(xy 114.788696 -214.596727) (xy 114.789204 -214.622634) (xy 114.78871 -214.647978) (xy 114.780934 -214.698068)
			(xy 114.765584 -214.746377) (xy 114.743024 -214.791769) (xy 114.713783 -214.833174) (xy 114.678552 -214.869617)
			(xy 114.638158 -214.90024) (xy 114.593555 -214.924322) (xy 114.545792 -214.941296) (xy 114.52098 -214.946484)
			(xy 114.49812 -214.950802) (xy 114.292888 -215.305894) (xy 114.300762 -215.327992) (xy 114.309397 -215.354337)
			(xy 114.318716 -215.408986) (xy 114.319304 -215.436704) (xy 115.53952 -215.436704) (xy 115.540029 -215.41136)
			(xy 115.5478 -215.36127) (xy 115.563146 -215.31296) (xy 115.585703 -215.267567) (xy 115.614942 -215.226161)
			(xy 115.650173 -215.189717) (xy 115.690565 -215.159094) (xy 115.735169 -215.135013) (xy 115.782932 -215.118041)
			(xy 115.807744 -215.112854) (xy 115.830604 -215.108536) (xy 116.035582 -214.753444) (xy 116.027708 -214.7316)
			(xy 116.019129 -214.705181) (xy 116.009932 -214.650406) (xy 116.00942 -214.622634) (xy 116.009928 -214.596747)
			(xy 116.018027 -214.545609) (xy 116.034026 -214.496369) (xy 116.057532 -214.450237) (xy 116.087964 -214.40835)
			(xy 116.124574 -214.37174) (xy 116.166461 -214.341308) (xy 116.212593 -214.317802) (xy 116.261833 -214.301803)
			(xy 116.312971 -214.293704) (xy 116.364745 -214.293704) (xy 116.415883 -214.301803) (xy 116.465123 -214.317802)
			(xy 116.511255 -214.341308) (xy 116.553142 -214.37174) (xy 116.589752 -214.40835) (xy 116.620184 -214.450237)
			(xy 116.64369 -214.496369) (xy 116.659689 -214.545609) (xy 116.667788 -214.596747) (xy 116.668296 -214.622634)
			(xy 116.667847 -214.64797) (xy 116.66009 -214.698044) (xy 116.644763 -214.746341) (xy 116.622227 -214.791726)
			(xy 116.593012 -214.833128) (xy 116.557808 -214.869572) (xy 116.517442 -214.900202) (xy 116.472865 -214.924296)
			(xy 116.425127 -214.941286) (xy 116.400326 -214.946484) (xy 116.377466 -214.950802) (xy 116.172488 -215.305894)
			(xy 116.180362 -215.327738) (xy 116.18901 -215.354146) (xy 116.198329 -215.408922) (xy 116.198904 -215.436704)
			(xy 117.41912 -215.436704) (xy 117.419629 -215.41136) (xy 117.4274 -215.36127) (xy 117.442746 -215.31296)
			(xy 117.465303 -215.267567) (xy 117.494542 -215.226161) (xy 117.529773 -215.189717) (xy 117.570165 -215.159094)
			(xy 117.614769 -215.135013) (xy 117.662532 -215.118041) (xy 117.687344 -215.112854) (xy 117.710204 -215.108536)
			(xy 117.915182 -214.753444) (xy 117.907308 -214.7316) (xy 117.898729 -214.705181) (xy 117.889532 -214.650406)
			(xy 117.88902 -214.622634) (xy 117.889528 -214.596747) (xy 117.897627 -214.545609) (xy 117.913626 -214.496369)
			(xy 117.937132 -214.450237) (xy 117.967564 -214.40835) (xy 118.004174 -214.37174) (xy 118.046061 -214.341308)
			(xy 118.092193 -214.317802) (xy 118.141433 -214.301803) (xy 118.192571 -214.293704) (xy 118.244345 -214.293704)
			(xy 118.295483 -214.301803) (xy 118.344723 -214.317802) (xy 118.390855 -214.341308) (xy 118.432742 -214.37174)
			(xy 118.469352 -214.40835) (xy 118.499784 -214.450237) (xy 118.52329 -214.496369) (xy 118.539289 -214.545609)
			(xy 118.547388 -214.596747) (xy 118.547896 -214.622634) (xy 118.547447 -214.64797) (xy 118.53969 -214.698044)
			(xy 118.524363 -214.746341) (xy 118.501827 -214.791726) (xy 118.472612 -214.833128) (xy 118.437408 -214.869572)
			(xy 118.397042 -214.900202) (xy 118.352465 -214.924296) (xy 118.304727 -214.941286) (xy 118.279926 -214.946484)
			(xy 118.257066 -214.950802) (xy 118.052088 -215.305894) (xy 118.059962 -215.327738) (xy 118.06861 -215.354146)
			(xy 118.077929 -215.408922) (xy 118.078504 -215.436704) (xy 119.29872 -215.436704) (xy 119.299229 -215.41136)
			(xy 119.307 -215.36127) (xy 119.322346 -215.31296) (xy 119.344903 -215.267567) (xy 119.374142 -215.226161)
			(xy 119.409373 -215.189717) (xy 119.449765 -215.159094) (xy 119.494369 -215.135013) (xy 119.542132 -215.118041)
			(xy 119.566944 -215.112854) (xy 119.589804 -215.108536) (xy 119.794782 -214.753444) (xy 119.786908 -214.7316)
			(xy 119.778329 -214.705181) (xy 119.769132 -214.650406) (xy 119.76862 -214.622634) (xy 119.769128 -214.596747)
			(xy 119.777227 -214.545609) (xy 119.793226 -214.496369) (xy 119.816732 -214.450237) (xy 119.847164 -214.40835)
			(xy 119.883774 -214.37174) (xy 119.925661 -214.341308) (xy 119.971793 -214.317802) (xy 120.021033 -214.301803)
			(xy 120.072171 -214.293704) (xy 120.123945 -214.293704) (xy 120.175083 -214.301803) (xy 120.224323 -214.317802)
			(xy 120.270455 -214.341308) (xy 120.312342 -214.37174) (xy 120.348952 -214.40835) (xy 120.379384 -214.450237)
			(xy 120.40289 -214.496369) (xy 120.418889 -214.545609) (xy 120.426988 -214.596747) (xy 120.427496 -214.622634)
			(xy 120.427047 -214.64797) (xy 120.41929 -214.698044) (xy 120.403963 -214.746341) (xy 120.381427 -214.791726)
			(xy 120.352212 -214.833128) (xy 120.317008 -214.869572) (xy 120.276642 -214.900202) (xy 120.232065 -214.924296)
			(xy 120.184327 -214.941286) (xy 120.159526 -214.946484) (xy 120.136666 -214.950802) (xy 119.931688 -215.305894)
			(xy 119.939562 -215.327738) (xy 119.94821 -215.354146) (xy 119.957529 -215.408922) (xy 119.958104 -215.436704)
			(xy 121.17832 -215.436704) (xy 121.178829 -215.41136) (xy 121.1866 -215.36127) (xy 121.201946 -215.31296)
			(xy 121.224503 -215.267567) (xy 121.253742 -215.226161) (xy 121.288973 -215.189717) (xy 121.329365 -215.159094)
			(xy 121.373969 -215.135013) (xy 121.421732 -215.118041) (xy 121.446544 -215.112854) (xy 121.469404 -215.108536)
			(xy 121.674382 -214.753444) (xy 121.666508 -214.7316) (xy 121.657929 -214.705181) (xy 121.648732 -214.650406)
			(xy 121.64822 -214.622634) (xy 121.648728 -214.596747) (xy 121.656827 -214.545609) (xy 121.672826 -214.496369)
			(xy 121.696332 -214.450237) (xy 121.726764 -214.40835) (xy 121.763374 -214.37174) (xy 121.805261 -214.341308)
			(xy 121.851393 -214.317802) (xy 121.900633 -214.301803) (xy 121.951771 -214.293704) (xy 122.003545 -214.293704)
			(xy 122.054683 -214.301803) (xy 122.103923 -214.317802) (xy 122.150055 -214.341308) (xy 122.191942 -214.37174)
			(xy 122.228552 -214.40835) (xy 122.258984 -214.450237) (xy 122.28249 -214.496369) (xy 122.298489 -214.545609)
			(xy 122.306588 -214.596747) (xy 122.307096 -214.622634) (xy 122.306647 -214.64797) (xy 122.29889 -214.698044)
			(xy 122.283563 -214.746341) (xy 122.261027 -214.791726) (xy 122.231812 -214.833128) (xy 122.196608 -214.869572)
			(xy 122.156242 -214.900202) (xy 122.111665 -214.924296) (xy 122.063927 -214.941286) (xy 122.039126 -214.946484)
			(xy 122.016266 -214.950802) (xy 121.811288 -215.305894) (xy 121.819162 -215.327738) (xy 121.82781 -215.354146)
			(xy 121.837129 -215.408922) (xy 121.837704 -215.436704) (xy 123.05792 -215.436704) (xy 123.058429 -215.41136)
			(xy 123.0662 -215.36127) (xy 123.081546 -215.31296) (xy 123.104103 -215.267567) (xy 123.133342 -215.226161)
			(xy 123.168573 -215.189717) (xy 123.208965 -215.159094) (xy 123.253569 -215.135013) (xy 123.301332 -215.118041)
			(xy 123.326144 -215.112854) (xy 123.349004 -215.108536) (xy 123.553982 -214.753444) (xy 123.546108 -214.7316)
			(xy 123.537529 -214.705181) (xy 123.528332 -214.650406) (xy 123.52782 -214.622634) (xy 123.528328 -214.596747)
			(xy 123.536427 -214.545609) (xy 123.552426 -214.496369) (xy 123.575932 -214.450237) (xy 123.606364 -214.40835)
			(xy 123.642974 -214.37174) (xy 123.684861 -214.341308) (xy 123.730993 -214.317802) (xy 123.780233 -214.301803)
			(xy 123.831371 -214.293704) (xy 123.883145 -214.293704) (xy 123.934283 -214.301803) (xy 123.983523 -214.317802)
			(xy 124.029655 -214.341308) (xy 124.071542 -214.37174) (xy 124.108152 -214.40835) (xy 124.138584 -214.450237)
			(xy 124.16209 -214.496369) (xy 124.178089 -214.545609) (xy 124.186188 -214.596747) (xy 124.186696 -214.622634)
			(xy 124.186247 -214.64797) (xy 124.17849 -214.698044) (xy 124.163163 -214.746341) (xy 124.140627 -214.791726)
			(xy 124.111412 -214.833128) (xy 124.076208 -214.869572) (xy 124.035842 -214.900202) (xy 123.991265 -214.924296)
			(xy 123.943527 -214.941286) (xy 123.918726 -214.946484) (xy 123.895866 -214.950802) (xy 123.690888 -215.305894)
			(xy 123.698762 -215.327738) (xy 123.70741 -215.354146) (xy 123.716729 -215.408922) (xy 123.717304 -215.436704)
			(xy 124.93752 -215.436704) (xy 124.938029 -215.41136) (xy 124.9458 -215.36127) (xy 124.961146 -215.31296)
			(xy 124.983703 -215.267567) (xy 125.012942 -215.226161) (xy 125.048173 -215.189717) (xy 125.088565 -215.159094)
			(xy 125.133169 -215.135013) (xy 125.180932 -215.118041) (xy 125.205744 -215.112854) (xy 125.228604 -215.108536)
			(xy 125.433582 -214.753444) (xy 125.425708 -214.7316) (xy 125.417129 -214.705181) (xy 125.407932 -214.650406)
			(xy 125.40742 -214.622634) (xy 125.407928 -214.596747) (xy 125.416027 -214.545609) (xy 125.432026 -214.496369)
			(xy 125.455532 -214.450237) (xy 125.485964 -214.40835) (xy 125.522574 -214.37174) (xy 125.564461 -214.341308)
			(xy 125.610593 -214.317802) (xy 125.659833 -214.301803) (xy 125.710971 -214.293704) (xy 125.762745 -214.293704)
			(xy 125.813883 -214.301803) (xy 125.863123 -214.317802) (xy 125.909255 -214.341308) (xy 125.951142 -214.37174)
			(xy 125.987752 -214.40835) (xy 126.018184 -214.450237) (xy 126.04169 -214.496369) (xy 126.057689 -214.545609)
			(xy 126.065788 -214.596747) (xy 126.066296 -214.622634) (xy 126.065847 -214.64797) (xy 126.05809 -214.698044)
			(xy 126.042763 -214.746341) (xy 126.020227 -214.791726) (xy 125.991012 -214.833128) (xy 125.955808 -214.869572)
			(xy 125.915442 -214.900202) (xy 125.870865 -214.924296) (xy 125.823127 -214.941286) (xy 125.798326 -214.946484)
			(xy 125.775466 -214.950802) (xy 125.570488 -215.305894) (xy 125.578362 -215.327738) (xy 125.58701 -215.354146)
			(xy 125.596329 -215.408922) (xy 125.596904 -215.436704) (xy 126.81712 -215.436704) (xy 126.817629 -215.41136)
			(xy 126.8254 -215.36127) (xy 126.840746 -215.31296) (xy 126.863303 -215.267567) (xy 126.892542 -215.226161)
			(xy 126.927773 -215.189717) (xy 126.968165 -215.159094) (xy 127.012769 -215.135013) (xy 127.060532 -215.118041)
			(xy 127.085344 -215.112854) (xy 127.108204 -215.108536) (xy 127.313182 -214.753444) (xy 127.305308 -214.7316)
			(xy 127.296729 -214.705181) (xy 127.287532 -214.650406) (xy 127.28702 -214.622634) (xy 127.287528 -214.596747)
			(xy 127.295627 -214.545609) (xy 127.311626 -214.496369) (xy 127.335132 -214.450237) (xy 127.365564 -214.40835)
			(xy 127.402174 -214.37174) (xy 127.444061 -214.341308) (xy 127.490193 -214.317802) (xy 127.539433 -214.301803)
			(xy 127.590571 -214.293704) (xy 127.642345 -214.293704) (xy 127.693483 -214.301803) (xy 127.742723 -214.317802)
			(xy 127.788855 -214.341308) (xy 127.830742 -214.37174) (xy 127.867352 -214.40835) (xy 127.897784 -214.450237)
			(xy 127.92129 -214.496369) (xy 127.937289 -214.545609) (xy 127.945388 -214.596747) (xy 127.945896 -214.622634)
			(xy 127.945447 -214.64797) (xy 127.93769 -214.698044) (xy 127.922363 -214.746341) (xy 127.899827 -214.791726)
			(xy 127.870612 -214.833128) (xy 127.835408 -214.869572) (xy 127.795042 -214.900202) (xy 127.750465 -214.924296)
			(xy 127.702727 -214.941286) (xy 127.677926 -214.946484) (xy 127.655066 -214.950802) (xy 127.450088 -215.305894)
			(xy 127.457962 -215.327738) (xy 127.46661 -215.354146) (xy 127.475929 -215.408922) (xy 127.476504 -215.436704)
			(xy 128.69672 -215.436704) (xy 128.697229 -215.41136) (xy 128.705 -215.36127) (xy 128.720346 -215.31296)
			(xy 128.742903 -215.267567) (xy 128.772142 -215.226161) (xy 128.807373 -215.189717) (xy 128.847765 -215.159094)
			(xy 128.892369 -215.135013) (xy 128.940132 -215.118041) (xy 128.964944 -215.112854) (xy 128.987804 -215.108536)
			(xy 129.192782 -214.753444) (xy 129.184908 -214.7316) (xy 129.176329 -214.705181) (xy 129.167132 -214.650406)
			(xy 129.16662 -214.622634) (xy 129.167128 -214.596747) (xy 129.175227 -214.545609) (xy 129.191226 -214.496369)
			(xy 129.214732 -214.450237) (xy 129.245164 -214.40835) (xy 129.281774 -214.37174) (xy 129.323661 -214.341308)
			(xy 129.369793 -214.317802) (xy 129.419033 -214.301803) (xy 129.470171 -214.293704) (xy 129.521945 -214.293704)
			(xy 129.573083 -214.301803) (xy 129.622323 -214.317802) (xy 129.668455 -214.341308) (xy 129.710342 -214.37174)
			(xy 129.746952 -214.40835) (xy 129.777384 -214.450237) (xy 129.80089 -214.496369) (xy 129.816889 -214.545609)
			(xy 129.824988 -214.596747) (xy 129.825496 -214.622634) (xy 129.825047 -214.64797) (xy 129.81729 -214.698044)
			(xy 129.801963 -214.746341) (xy 129.779427 -214.791726) (xy 129.750212 -214.833128) (xy 129.715008 -214.869572)
			(xy 129.674642 -214.900202) (xy 129.630065 -214.924296) (xy 129.582327 -214.941286) (xy 129.557526 -214.946484)
			(xy 129.534666 -214.950802) (xy 129.329688 -215.305894) (xy 129.337562 -215.327738) (xy 129.34621 -215.354146)
			(xy 129.355529 -215.408922) (xy 129.356104 -215.436704) (xy 130.57632 -215.436704) (xy 130.576829 -215.41136)
			(xy 130.5846 -215.36127) (xy 130.599946 -215.31296) (xy 130.622503 -215.267567) (xy 130.651742 -215.226161)
			(xy 130.686973 -215.189717) (xy 130.727365 -215.159094) (xy 130.771969 -215.135013) (xy 130.819732 -215.118041)
			(xy 130.844544 -215.112854) (xy 130.867404 -215.108536) (xy 131.072382 -214.753444) (xy 131.064508 -214.7316)
			(xy 131.055929 -214.705181) (xy 131.046732 -214.650406) (xy 131.04622 -214.622634) (xy 131.046728 -214.596747)
			(xy 131.054827 -214.545609) (xy 131.070826 -214.496369) (xy 131.094332 -214.450237) (xy 131.124764 -214.40835)
			(xy 131.161374 -214.37174) (xy 131.203261 -214.341308) (xy 131.249393 -214.317802) (xy 131.298633 -214.301803)
			(xy 131.349771 -214.293704) (xy 131.401545 -214.293704) (xy 131.452683 -214.301803) (xy 131.501923 -214.317802)
			(xy 131.548055 -214.341308) (xy 131.589942 -214.37174) (xy 131.626552 -214.40835) (xy 131.656984 -214.450237)
			(xy 131.68049 -214.496369) (xy 131.696489 -214.545609) (xy 131.704588 -214.596747) (xy 131.705096 -214.622634)
			(xy 131.704647 -214.64797) (xy 131.69689 -214.698044) (xy 131.681563 -214.746341) (xy 131.659027 -214.791726)
			(xy 131.629812 -214.833128) (xy 131.594608 -214.869572) (xy 131.554242 -214.900202) (xy 131.509665 -214.924296)
			(xy 131.461927 -214.941286) (xy 131.437126 -214.946484) (xy 131.414266 -214.950802) (xy 131.209288 -215.305894)
			(xy 131.217162 -215.327738) (xy 131.22581 -215.354146) (xy 131.235129 -215.408922) (xy 131.235704 -215.436704)
			(xy 132.45592 -215.436704) (xy 132.456429 -215.41136) (xy 132.4642 -215.36127) (xy 132.479546 -215.31296)
			(xy 132.502103 -215.267567) (xy 132.531342 -215.226161) (xy 132.566573 -215.189717) (xy 132.606965 -215.159094)
			(xy 132.651569 -215.135013) (xy 132.699332 -215.118041) (xy 132.724144 -215.112854) (xy 132.747004 -215.108536)
			(xy 132.951982 -214.753444) (xy 132.944108 -214.7316) (xy 132.935529 -214.705181) (xy 132.926332 -214.650406)
			(xy 132.92582 -214.622634) (xy 132.926328 -214.596747) (xy 132.934427 -214.545609) (xy 132.950426 -214.496369)
			(xy 132.973932 -214.450237) (xy 133.004364 -214.40835) (xy 133.040974 -214.37174) (xy 133.082861 -214.341308)
			(xy 133.128993 -214.317802) (xy 133.178233 -214.301803) (xy 133.229371 -214.293704) (xy 133.281145 -214.293704)
			(xy 133.332283 -214.301803) (xy 133.381523 -214.317802) (xy 133.427655 -214.341308) (xy 133.469542 -214.37174)
			(xy 133.506152 -214.40835) (xy 133.536584 -214.450237) (xy 133.56009 -214.496369) (xy 133.576089 -214.545609)
			(xy 133.57622 -214.546434) (xy 134.80542 -214.546434) (xy 134.805928 -214.520527) (xy 134.814034 -214.46935)
			(xy 134.830046 -214.420071) (xy 134.853569 -214.373904) (xy 134.884025 -214.331985) (xy 134.920663 -214.295347)
			(xy 134.962582 -214.264891) (xy 135.008749 -214.241368) (xy 135.058028 -214.225356) (xy 135.109205 -214.21725)
			(xy 135.161019 -214.21725) (xy 135.212196 -214.225356) (xy 135.261475 -214.241368) (xy 135.307642 -214.264891)
			(xy 135.349561 -214.295347) (xy 135.386199 -214.331985) (xy 135.416655 -214.373904) (xy 135.440178 -214.420071)
			(xy 135.45619 -214.46935) (xy 135.464296 -214.520527) (xy 135.464804 -214.546434) (xy 135.464102 -214.577275)
			(xy 135.452589 -214.637875) (xy 135.441944 -214.66683) (xy 135.433308 -214.688674) (xy 135.656066 -215.110314)
			(xy 135.678672 -215.115394) (xy 135.702597 -215.121362) (xy 135.748484 -215.139404) (xy 135.791171 -215.164081)
			(xy 135.829706 -215.194841) (xy 135.863229 -215.230999) (xy 135.890992 -215.271747) (xy 135.912374 -215.316176)
			(xy 135.9269 -215.363294) (xy 135.934244 -215.412051) (xy 135.934704 -215.436704) (xy 336.225388 -215.436704)
			(xy 336.225896 -215.410797) (xy 336.234002 -215.35962) (xy 336.250014 -215.310341) (xy 336.273537 -215.264174)
			(xy 336.303993 -215.222255) (xy 336.340631 -215.185617) (xy 336.38255 -215.155161) (xy 336.428717 -215.131638)
			(xy 336.477996 -215.115626) (xy 336.529173 -215.10752) (xy 336.580987 -215.10752) (xy 336.632164 -215.115626)
			(xy 336.681443 -215.131638) (xy 336.72761 -215.155161) (xy 336.769529 -215.185617) (xy 336.806167 -215.222255)
			(xy 336.836623 -215.264174) (xy 336.860146 -215.310341) (xy 336.876158 -215.35962) (xy 336.884264 -215.410797)
			(xy 336.884772 -215.436704) (xy 337.165188 -215.436704) (xy 337.165723 -215.411361) (xy 337.173493 -215.361274)
			(xy 337.188837 -215.312966) (xy 337.211392 -215.267575) (xy 337.240627 -215.226169) (xy 337.275854 -215.189725)
			(xy 337.316243 -215.159101) (xy 337.360842 -215.135018) (xy 337.408601 -215.118043) (xy 337.433412 -215.112854)
			(xy 337.456272 -215.108536) (xy 337.66125 -214.753444) (xy 337.653376 -214.7316) (xy 337.644799 -214.705181)
			(xy 337.6356 -214.650406) (xy 337.635088 -214.622634) (xy 337.635596 -214.596747) (xy 337.643695 -214.545609)
			(xy 337.659694 -214.496369) (xy 337.6832 -214.450237) (xy 337.713632 -214.40835) (xy 337.750242 -214.37174)
			(xy 337.792129 -214.341308) (xy 337.838261 -214.317802) (xy 337.887501 -214.301803) (xy 337.938639 -214.293704)
			(xy 337.990413 -214.293704) (xy 338.041551 -214.301803) (xy 338.090791 -214.317802) (xy 338.136923 -214.341308)
			(xy 338.17881 -214.37174) (xy 338.21542 -214.40835) (xy 338.245852 -214.450237) (xy 338.269358 -214.496369)
			(xy 338.285357 -214.545609) (xy 338.293456 -214.596747) (xy 338.293964 -214.622634) (xy 338.293541 -214.647971)
			(xy 338.285783 -214.698047) (xy 338.270454 -214.746347) (xy 338.247915 -214.791733) (xy 338.218698 -214.833136)
			(xy 338.18349 -214.869581) (xy 338.14312 -214.90021) (xy 338.098539 -214.924301) (xy 338.050797 -214.941288)
			(xy 338.025994 -214.946484) (xy 338.003134 -214.950802) (xy 337.798156 -215.305894) (xy 337.80603 -215.327738)
			(xy 337.814677 -215.354146) (xy 337.823997 -215.408922) (xy 337.824572 -215.436704) (xy 339.044788 -215.436704)
			(xy 339.045323 -215.411361) (xy 339.053093 -215.361274) (xy 339.068437 -215.312966) (xy 339.090992 -215.267575)
			(xy 339.120227 -215.226169) (xy 339.155454 -215.189725) (xy 339.195843 -215.159101) (xy 339.240442 -215.135018)
			(xy 339.288201 -215.118043) (xy 339.313012 -215.112854) (xy 339.335872 -215.108536) (xy 339.54085 -214.753444)
			(xy 339.532976 -214.7316) (xy 339.524399 -214.705181) (xy 339.5152 -214.650406) (xy 339.514688 -214.622634)
			(xy 339.515196 -214.596747) (xy 339.523295 -214.545609) (xy 339.539294 -214.496369) (xy 339.5628 -214.450237)
			(xy 339.593232 -214.40835) (xy 339.629842 -214.37174) (xy 339.671729 -214.341308) (xy 339.717861 -214.317802)
			(xy 339.767101 -214.301803) (xy 339.818239 -214.293704) (xy 339.870013 -214.293704) (xy 339.921151 -214.301803)
			(xy 339.970391 -214.317802) (xy 340.016523 -214.341308) (xy 340.05841 -214.37174) (xy 340.09502 -214.40835)
			(xy 340.125452 -214.450237) (xy 340.148958 -214.496369) (xy 340.164957 -214.545609) (xy 340.173056 -214.596747)
			(xy 340.173564 -214.622634) (xy 340.173141 -214.647971) (xy 340.165383 -214.698047) (xy 340.150054 -214.746347)
			(xy 340.127515 -214.791733) (xy 340.098298 -214.833136) (xy 340.06309 -214.869581) (xy 340.02272 -214.90021)
			(xy 339.978139 -214.924301) (xy 339.930397 -214.941288) (xy 339.905594 -214.946484) (xy 339.882734 -214.950802)
			(xy 339.677756 -215.305894) (xy 339.68563 -215.327738) (xy 339.694277 -215.354146) (xy 339.703597 -215.408922)
			(xy 339.704172 -215.436704) (xy 340.924388 -215.436704) (xy 340.924923 -215.411361) (xy 340.932693 -215.361274)
			(xy 340.948037 -215.312966) (xy 340.970592 -215.267575) (xy 340.999827 -215.226169) (xy 341.035054 -215.189725)
			(xy 341.075443 -215.159101) (xy 341.120042 -215.135018) (xy 341.167801 -215.118043) (xy 341.192612 -215.112854)
			(xy 341.215472 -215.108536) (xy 341.42045 -214.753444) (xy 341.412576 -214.7316) (xy 341.403999 -214.705181)
			(xy 341.3948 -214.650406) (xy 341.394288 -214.622634) (xy 341.394796 -214.596747) (xy 341.402895 -214.545609)
			(xy 341.418894 -214.496369) (xy 341.4424 -214.450237) (xy 341.472832 -214.40835) (xy 341.509442 -214.37174)
			(xy 341.551329 -214.341308) (xy 341.597461 -214.317802) (xy 341.646701 -214.301803) (xy 341.697839 -214.293704)
			(xy 341.749613 -214.293704) (xy 341.800751 -214.301803) (xy 341.849991 -214.317802) (xy 341.896123 -214.341308)
			(xy 341.93801 -214.37174) (xy 341.97462 -214.40835) (xy 342.005052 -214.450237) (xy 342.028558 -214.496369)
			(xy 342.044557 -214.545609) (xy 342.052656 -214.596747) (xy 342.053164 -214.622634) (xy 342.052741 -214.647971)
			(xy 342.044983 -214.698047) (xy 342.029654 -214.746347) (xy 342.007115 -214.791733) (xy 341.977898 -214.833136)
			(xy 341.94269 -214.869581) (xy 341.90232 -214.90021) (xy 341.857739 -214.924301) (xy 341.809997 -214.941288)
			(xy 341.785194 -214.946484) (xy 341.762334 -214.950802) (xy 341.557356 -215.305894) (xy 341.56523 -215.327738)
			(xy 341.573877 -215.354146) (xy 341.583197 -215.408922) (xy 341.583772 -215.436704) (xy 342.803988 -215.436704)
			(xy 342.804523 -215.411361) (xy 342.812293 -215.361274) (xy 342.827637 -215.312966) (xy 342.850192 -215.267575)
			(xy 342.879427 -215.226169) (xy 342.914654 -215.189725) (xy 342.955043 -215.159101) (xy 342.999642 -215.135018)
			(xy 343.047401 -215.118043) (xy 343.072212 -215.112854) (xy 343.095072 -215.108536) (xy 343.30005 -214.753444)
			(xy 343.292176 -214.7316) (xy 343.283599 -214.705181) (xy 343.2744 -214.650406) (xy 343.273888 -214.622634)
			(xy 343.274396 -214.596747) (xy 343.282495 -214.545609) (xy 343.298494 -214.496369) (xy 343.322 -214.450237)
			(xy 343.352432 -214.40835) (xy 343.389042 -214.37174) (xy 343.430929 -214.341308) (xy 343.477061 -214.317802)
			(xy 343.526301 -214.301803) (xy 343.577439 -214.293704) (xy 343.629213 -214.293704) (xy 343.680351 -214.301803)
			(xy 343.729591 -214.317802) (xy 343.775723 -214.341308) (xy 343.81761 -214.37174) (xy 343.85422 -214.40835)
			(xy 343.884652 -214.450237) (xy 343.908158 -214.496369) (xy 343.924157 -214.545609) (xy 343.932256 -214.596747)
			(xy 343.932764 -214.622634) (xy 343.932341 -214.647971) (xy 343.924583 -214.698047) (xy 343.909254 -214.746347)
			(xy 343.886715 -214.791733) (xy 343.857498 -214.833136) (xy 343.82229 -214.869581) (xy 343.78192 -214.90021)
			(xy 343.737339 -214.924301) (xy 343.689597 -214.941288) (xy 343.664794 -214.946484) (xy 343.641934 -214.950802)
			(xy 343.436956 -215.305894) (xy 343.44483 -215.327738) (xy 343.453477 -215.354146) (xy 343.462797 -215.408922)
			(xy 343.463372 -215.436704) (xy 344.683588 -215.436704) (xy 344.684123 -215.411361) (xy 344.691893 -215.361274)
			(xy 344.707237 -215.312966) (xy 344.729792 -215.267575) (xy 344.759027 -215.226169) (xy 344.794254 -215.189725)
			(xy 344.834643 -215.159101) (xy 344.879242 -215.135018) (xy 344.927001 -215.118043) (xy 344.951812 -215.112854)
			(xy 344.974672 -215.108536) (xy 345.17965 -214.753444) (xy 345.171776 -214.7316) (xy 345.163199 -214.705181)
			(xy 345.154 -214.650406) (xy 345.153488 -214.622634) (xy 345.153996 -214.596747) (xy 345.162095 -214.545609)
			(xy 345.178094 -214.496369) (xy 345.2016 -214.450237) (xy 345.232032 -214.40835) (xy 345.268642 -214.37174)
			(xy 345.310529 -214.341308) (xy 345.356661 -214.317802) (xy 345.405901 -214.301803) (xy 345.457039 -214.293704)
			(xy 345.508813 -214.293704) (xy 345.559951 -214.301803) (xy 345.609191 -214.317802) (xy 345.655323 -214.341308)
			(xy 345.69721 -214.37174) (xy 345.73382 -214.40835) (xy 345.764252 -214.450237) (xy 345.787758 -214.496369)
			(xy 345.803757 -214.545609) (xy 345.811856 -214.596747) (xy 345.812364 -214.622634) (xy 345.811941 -214.647971)
			(xy 345.804183 -214.698047) (xy 345.788854 -214.746347) (xy 345.766315 -214.791733) (xy 345.737098 -214.833136)
			(xy 345.70189 -214.869581) (xy 345.66152 -214.90021) (xy 345.616939 -214.924301) (xy 345.569197 -214.941288)
			(xy 345.544394 -214.946484) (xy 345.521534 -214.950802) (xy 345.316556 -215.305894) (xy 345.32443 -215.327738)
			(xy 345.333077 -215.354146) (xy 345.342397 -215.408922) (xy 345.342972 -215.436704) (xy 346.563188 -215.436704)
			(xy 346.563723 -215.411361) (xy 346.571493 -215.361274) (xy 346.586837 -215.312966) (xy 346.609392 -215.267575)
			(xy 346.638627 -215.226169) (xy 346.673854 -215.189725) (xy 346.714243 -215.159101) (xy 346.758842 -215.135018)
			(xy 346.806601 -215.118043) (xy 346.831412 -215.112854) (xy 346.854272 -215.108536) (xy 347.05925 -214.753444)
			(xy 347.051376 -214.7316) (xy 347.042799 -214.705181) (xy 347.0336 -214.650406) (xy 347.033088 -214.622634)
			(xy 347.033596 -214.596747) (xy 347.041695 -214.545609) (xy 347.057694 -214.496369) (xy 347.0812 -214.450237)
			(xy 347.111632 -214.40835) (xy 347.148242 -214.37174) (xy 347.190129 -214.341308) (xy 347.236261 -214.317802)
			(xy 347.285501 -214.301803) (xy 347.336639 -214.293704) (xy 347.388413 -214.293704) (xy 347.439551 -214.301803)
			(xy 347.488791 -214.317802) (xy 347.534923 -214.341308) (xy 347.57681 -214.37174) (xy 347.61342 -214.40835)
			(xy 347.643852 -214.450237) (xy 347.667358 -214.496369) (xy 347.683357 -214.545609) (xy 347.691456 -214.596747)
			(xy 347.691964 -214.622634) (xy 347.691541 -214.647971) (xy 347.683783 -214.698047) (xy 347.668454 -214.746347)
			(xy 347.645915 -214.791733) (xy 347.616698 -214.833136) (xy 347.58149 -214.869581) (xy 347.54112 -214.90021)
			(xy 347.496539 -214.924301) (xy 347.448797 -214.941288) (xy 347.423994 -214.946484) (xy 347.401134 -214.950802)
			(xy 347.196156 -215.305894) (xy 347.20403 -215.327738) (xy 347.212677 -215.354146) (xy 347.221997 -215.408922)
			(xy 347.222572 -215.436704) (xy 348.442788 -215.436704) (xy 348.443323 -215.411361) (xy 348.451093 -215.361274)
			(xy 348.466437 -215.312966) (xy 348.488992 -215.267575) (xy 348.518227 -215.226169) (xy 348.553454 -215.189725)
			(xy 348.593843 -215.159101) (xy 348.638442 -215.135018) (xy 348.686201 -215.118043) (xy 348.711012 -215.112854)
			(xy 348.733872 -215.108536) (xy 348.93885 -214.753444) (xy 348.930976 -214.7316) (xy 348.922399 -214.705181)
			(xy 348.9132 -214.650406) (xy 348.912688 -214.622634) (xy 348.913196 -214.596747) (xy 348.921295 -214.545609)
			(xy 348.937294 -214.496369) (xy 348.9608 -214.450237) (xy 348.991232 -214.40835) (xy 349.027842 -214.37174)
			(xy 349.069729 -214.341308) (xy 349.115861 -214.317802) (xy 349.165101 -214.301803) (xy 349.216239 -214.293704)
			(xy 349.268013 -214.293704) (xy 349.319151 -214.301803) (xy 349.368391 -214.317802) (xy 349.414523 -214.341308)
			(xy 349.45641 -214.37174) (xy 349.49302 -214.40835) (xy 349.523452 -214.450237) (xy 349.546958 -214.496369)
			(xy 349.562957 -214.545609) (xy 349.571056 -214.596747) (xy 349.571564 -214.622634) (xy 349.571141 -214.647971)
			(xy 349.563383 -214.698047) (xy 349.548054 -214.746347) (xy 349.525515 -214.791733) (xy 349.496298 -214.833136)
			(xy 349.46109 -214.869581) (xy 349.42072 -214.90021) (xy 349.376139 -214.924301) (xy 349.328397 -214.941288)
			(xy 349.303594 -214.946484) (xy 349.280734 -214.950802) (xy 349.075756 -215.305894) (xy 349.08363 -215.327738)
			(xy 349.092277 -215.354146) (xy 349.101597 -215.408922) (xy 349.102172 -215.436704) (xy 350.322388 -215.436704)
			(xy 350.322923 -215.411361) (xy 350.330693 -215.361274) (xy 350.346037 -215.312966) (xy 350.368592 -215.267575)
			(xy 350.397827 -215.226169) (xy 350.433054 -215.189725) (xy 350.473443 -215.159101) (xy 350.518042 -215.135018)
			(xy 350.565801 -215.118043) (xy 350.590612 -215.112854) (xy 350.613472 -215.108536) (xy 350.81845 -214.753444)
			(xy 350.810576 -214.7316) (xy 350.801999 -214.705181) (xy 350.7928 -214.650406) (xy 350.792288 -214.622634)
			(xy 350.792796 -214.596747) (xy 350.800895 -214.545609) (xy 350.816894 -214.496369) (xy 350.8404 -214.450237)
			(xy 350.870832 -214.40835) (xy 350.907442 -214.37174) (xy 350.949329 -214.341308) (xy 350.995461 -214.317802)
			(xy 351.044701 -214.301803) (xy 351.095839 -214.293704) (xy 351.147613 -214.293704) (xy 351.198751 -214.301803)
			(xy 351.247991 -214.317802) (xy 351.294123 -214.341308) (xy 351.33601 -214.37174) (xy 351.37262 -214.40835)
			(xy 351.403052 -214.450237) (xy 351.426558 -214.496369) (xy 351.442557 -214.545609) (xy 351.450656 -214.596747)
			(xy 351.451164 -214.622634) (xy 351.450741 -214.647971) (xy 351.442983 -214.698047) (xy 351.427654 -214.746347)
			(xy 351.405115 -214.791733) (xy 351.375898 -214.833136) (xy 351.34069 -214.869581) (xy 351.30032 -214.90021)
			(xy 351.255739 -214.924301) (xy 351.207997 -214.941288) (xy 351.183194 -214.946484) (xy 351.160334 -214.950802)
			(xy 350.955356 -215.305894) (xy 350.96323 -215.327738) (xy 350.971877 -215.354146) (xy 350.981197 -215.408922)
			(xy 350.981772 -215.436704) (xy 352.201988 -215.436704) (xy 352.202523 -215.411361) (xy 352.210293 -215.361274)
			(xy 352.225637 -215.312966) (xy 352.248192 -215.267575) (xy 352.277427 -215.226169) (xy 352.312654 -215.189725)
			(xy 352.353043 -215.159101) (xy 352.397642 -215.135018) (xy 352.445401 -215.118043) (xy 352.470212 -215.112854)
			(xy 352.493072 -215.108536) (xy 352.69805 -214.753444) (xy 352.690176 -214.7316) (xy 352.681599 -214.705181)
			(xy 352.6724 -214.650406) (xy 352.671888 -214.622634) (xy 352.672396 -214.596747) (xy 352.680495 -214.545609)
			(xy 352.696494 -214.496369) (xy 352.72 -214.450237) (xy 352.750432 -214.40835) (xy 352.787042 -214.37174)
			(xy 352.828929 -214.341308) (xy 352.875061 -214.317802) (xy 352.924301 -214.301803) (xy 352.975439 -214.293704)
			(xy 353.027213 -214.293704) (xy 353.078351 -214.301803) (xy 353.127591 -214.317802) (xy 353.173723 -214.341308)
			(xy 353.21561 -214.37174) (xy 353.25222 -214.40835) (xy 353.282652 -214.450237) (xy 353.306158 -214.496369)
			(xy 353.322157 -214.545609) (xy 353.330256 -214.596747) (xy 353.330764 -214.622634) (xy 353.330341 -214.647971)
			(xy 353.322583 -214.698047) (xy 353.307254 -214.746347) (xy 353.284715 -214.791733) (xy 353.255498 -214.833136)
			(xy 353.22029 -214.869581) (xy 353.17992 -214.90021) (xy 353.135339 -214.924301) (xy 353.087597 -214.941288)
			(xy 353.062794 -214.946484) (xy 353.039934 -214.950802) (xy 352.834956 -215.305894) (xy 352.84283 -215.327738)
			(xy 352.851477 -215.354146) (xy 352.860797 -215.408922) (xy 352.861372 -215.436704) (xy 354.081588 -215.436704)
			(xy 354.082123 -215.411361) (xy 354.089893 -215.361274) (xy 354.105237 -215.312966) (xy 354.127792 -215.267575)
			(xy 354.157027 -215.226169) (xy 354.192254 -215.189725) (xy 354.232643 -215.159101) (xy 354.277242 -215.135018)
			(xy 354.325001 -215.118043) (xy 354.349812 -215.112854) (xy 354.372672 -215.108536) (xy 354.57765 -214.753444)
			(xy 354.569776 -214.7316) (xy 354.561199 -214.705181) (xy 354.552 -214.650406) (xy 354.551488 -214.622634)
			(xy 354.551996 -214.596747) (xy 354.560095 -214.545609) (xy 354.576094 -214.496369) (xy 354.5996 -214.450237)
			(xy 354.630032 -214.40835) (xy 354.666642 -214.37174) (xy 354.708529 -214.341308) (xy 354.754661 -214.317802)
			(xy 354.803901 -214.301803) (xy 354.855039 -214.293704) (xy 354.906813 -214.293704) (xy 354.957951 -214.301803)
			(xy 355.007191 -214.317802) (xy 355.053323 -214.341308) (xy 355.09521 -214.37174) (xy 355.13182 -214.40835)
			(xy 355.162252 -214.450237) (xy 355.185758 -214.496369) (xy 355.201757 -214.545609) (xy 355.209856 -214.596747)
			(xy 355.210364 -214.622634) (xy 355.209941 -214.647971) (xy 355.202183 -214.698047) (xy 355.186854 -214.746347)
			(xy 355.164315 -214.791733) (xy 355.135098 -214.833136) (xy 355.09989 -214.869581) (xy 355.05952 -214.90021)
			(xy 355.014939 -214.924301) (xy 354.967197 -214.941288) (xy 354.942394 -214.946484) (xy 354.919534 -214.950802)
			(xy 354.714556 -215.305894) (xy 354.72243 -215.327738) (xy 354.731077 -215.354146) (xy 354.740397 -215.408922)
			(xy 354.740972 -215.436704) (xy 355.961188 -215.436704) (xy 355.961723 -215.411361) (xy 355.969493 -215.361274)
			(xy 355.984837 -215.312966) (xy 356.007392 -215.267575) (xy 356.036627 -215.226169) (xy 356.071854 -215.189725)
			(xy 356.112243 -215.159101) (xy 356.156842 -215.135018) (xy 356.204601 -215.118043) (xy 356.229412 -215.112854)
			(xy 356.252272 -215.108536) (xy 356.45725 -214.753444) (xy 356.449376 -214.7316) (xy 356.440799 -214.705181)
			(xy 356.4316 -214.650406) (xy 356.431088 -214.622634) (xy 356.431596 -214.596747) (xy 356.439695 -214.545609)
			(xy 356.455694 -214.496369) (xy 356.4792 -214.450237) (xy 356.509632 -214.40835) (xy 356.546242 -214.37174)
			(xy 356.588129 -214.341308) (xy 356.634261 -214.317802) (xy 356.683501 -214.301803) (xy 356.734639 -214.293704)
			(xy 356.786413 -214.293704) (xy 356.837551 -214.301803) (xy 356.886791 -214.317802) (xy 356.932923 -214.341308)
			(xy 356.97481 -214.37174) (xy 357.01142 -214.40835) (xy 357.041852 -214.450237) (xy 357.065358 -214.496369)
			(xy 357.081357 -214.545609) (xy 357.089456 -214.596747) (xy 357.089964 -214.622634) (xy 358.310688 -214.622634)
			(xy 358.311196 -214.596747) (xy 358.319295 -214.545609) (xy 358.335294 -214.496369) (xy 358.3588 -214.450237)
			(xy 358.389232 -214.40835) (xy 358.425842 -214.37174) (xy 358.467729 -214.341308) (xy 358.513861 -214.317802)
			(xy 358.563101 -214.301803) (xy 358.614239 -214.293704) (xy 358.666013 -214.293704) (xy 358.717151 -214.301803)
			(xy 358.766391 -214.317802) (xy 358.812523 -214.341308) (xy 358.85441 -214.37174) (xy 358.89102 -214.40835)
			(xy 358.921452 -214.450237) (xy 358.944958 -214.496369) (xy 358.960957 -214.545609) (xy 358.969056 -214.596747)
			(xy 358.969564 -214.622634) (xy 358.969564 -214.623142) (xy 358.968984 -214.650659) (xy 358.959791 -214.70492)
			(xy 358.951276 -214.731092) (xy 358.943656 -214.75319) (xy 359.148888 -215.108536) (xy 359.171748 -215.112854)
			(xy 359.196559 -215.118062) (xy 359.244336 -215.135013) (xy 359.288953 -215.15908) (xy 359.329358 -215.189696)
			(xy 359.364599 -215.226137) (xy 359.393844 -215.267545) (xy 359.416403 -215.312943) (xy 359.431745 -215.36126)
			(xy 359.439507 -215.411357) (xy 359.439972 -215.436704) (xy 359.439464 -215.462611) (xy 359.431358 -215.513788)
			(xy 359.415346 -215.563067) (xy 359.391823 -215.609234) (xy 359.361367 -215.651153) (xy 359.324729 -215.687791)
			(xy 359.28281 -215.718247) (xy 359.236643 -215.74177) (xy 359.187364 -215.757782) (xy 359.136187 -215.765888)
			(xy 359.084373 -215.765888) (xy 359.033196 -215.757782) (xy 358.983917 -215.74177) (xy 358.93775 -215.718247)
			(xy 358.895831 -215.687791) (xy 358.859193 -215.651153) (xy 358.828737 -215.609234) (xy 358.805214 -215.563067)
			(xy 358.789202 -215.513788) (xy 358.781096 -215.462611) (xy 358.780588 -215.436704) (xy 358.781184 -215.408987)
			(xy 358.790506 -215.35434) (xy 358.79913 -215.327992) (xy 358.80675 -215.306148) (xy 358.601772 -214.950802)
			(xy 358.578912 -214.946484) (xy 358.554096 -214.941291) (xy 358.506315 -214.924344) (xy 358.461694 -214.900279)
			(xy 358.421285 -214.869663) (xy 358.386043 -214.833219) (xy 358.356798 -214.791807) (xy 358.33424 -214.746405)
			(xy 358.318903 -214.698083) (xy 358.311148 -214.647983) (xy 358.310688 -214.622634) (xy 357.089964 -214.622634)
			(xy 357.089541 -214.647971) (xy 357.081783 -214.698047) (xy 357.066454 -214.746347) (xy 357.043915 -214.791733)
			(xy 357.014698 -214.833136) (xy 356.97949 -214.869581) (xy 356.93912 -214.90021) (xy 356.894539 -214.924301)
			(xy 356.846797 -214.941288) (xy 356.821994 -214.946484) (xy 356.799134 -214.950802) (xy 356.594156 -215.305894)
			(xy 356.60203 -215.327738) (xy 356.610677 -215.354146) (xy 356.619997 -215.408922) (xy 356.620572 -215.436704)
			(xy 356.620064 -215.462606) (xy 356.90152 -215.462606) (xy 356.90152 -215.410794) (xy 356.909625 -215.35962)
			(xy 356.925635 -215.310344) (xy 356.949157 -215.264178) (xy 356.97961 -215.222261) (xy 357.016246 -215.185623)
			(xy 357.058161 -215.155167) (xy 357.104325 -215.131643) (xy 357.1536 -215.11563) (xy 357.204774 -215.107522)
			(xy 357.23068 -215.107012) (xy 357.256191 -215.107502) (xy 357.306606 -215.11536) (xy 357.355207 -215.130891)
			(xy 357.400836 -215.153725) (xy 357.442402 -215.183316) (xy 357.478912 -215.218958) (xy 357.494586 -215.239092)
			(xy 357.906574 -215.239092) (xy 357.92226 -215.218967) (xy 357.958768 -215.183323) (xy 358.000331 -215.153729)
			(xy 358.045956 -215.130891) (xy 358.094556 -215.115355) (xy 358.144969 -215.107491) (xy 358.17048 -215.107012)
			(xy 358.196391 -215.107484) (xy 358.247575 -215.115588) (xy 358.296861 -215.131599) (xy 358.343035 -215.155124)
			(xy 358.38496 -215.185582) (xy 358.421605 -215.222224) (xy 358.452066 -215.264148) (xy 358.475593 -215.310321)
			(xy 358.491607 -215.359606) (xy 358.499714 -215.410789) (xy 358.499714 -215.462611) (xy 358.491607 -215.513794)
			(xy 358.475593 -215.563079) (xy 358.452066 -215.609252) (xy 358.421605 -215.651176) (xy 358.38496 -215.687818)
			(xy 358.343035 -215.718276) (xy 358.296861 -215.741801) (xy 358.247575 -215.757812) (xy 358.196391 -215.765916)
			(xy 358.17048 -215.766396) (xy 358.144968 -215.765932) (xy 358.094552 -215.758068) (xy 358.04595 -215.742532)
			(xy 358.000322 -215.719693) (xy 357.958757 -215.690098) (xy 357.922247 -215.654452) (xy 357.906574 -215.634316)
			(xy 357.494586 -215.634316) (xy 357.478925 -215.654461) (xy 357.442412 -215.690104) (xy 357.400844 -215.719696)
			(xy 357.355213 -215.74253) (xy 357.306609 -215.758062) (xy 357.256193 -215.76592) (xy 357.23068 -215.766396)
			(xy 357.204774 -215.765878) (xy 357.1536 -215.75777) (xy 357.104325 -215.741757) (xy 357.058161 -215.718233)
			(xy 357.016246 -215.687777) (xy 356.97961 -215.651139) (xy 356.949157 -215.609222) (xy 356.925635 -215.563056)
			(xy 356.909625 -215.51378) (xy 356.90152 -215.462606) (xy 356.620064 -215.462606) (xy 356.620064 -215.462611)
			(xy 356.611958 -215.513788) (xy 356.595946 -215.563067) (xy 356.572423 -215.609234) (xy 356.541967 -215.651153)
			(xy 356.505329 -215.687791) (xy 356.46341 -215.718247) (xy 356.417243 -215.74177) (xy 356.367964 -215.757782)
			(xy 356.316787 -215.765888) (xy 356.264973 -215.765888) (xy 356.213796 -215.757782) (xy 356.164517 -215.74177)
			(xy 356.11835 -215.718247) (xy 356.076431 -215.687791) (xy 356.039793 -215.651153) (xy 356.009337 -215.609234)
			(xy 355.985814 -215.563067) (xy 355.969802 -215.513788) (xy 355.961696 -215.462611) (xy 355.961188 -215.436704)
			(xy 354.740972 -215.436704) (xy 354.740464 -215.462611) (xy 354.732358 -215.513788) (xy 354.716346 -215.563067)
			(xy 354.692823 -215.609234) (xy 354.662367 -215.651153) (xy 354.625729 -215.687791) (xy 354.58381 -215.718247)
			(xy 354.537643 -215.74177) (xy 354.488364 -215.757782) (xy 354.437187 -215.765888) (xy 354.385373 -215.765888)
			(xy 354.334196 -215.757782) (xy 354.284917 -215.74177) (xy 354.23875 -215.718247) (xy 354.196831 -215.687791)
			(xy 354.160193 -215.651153) (xy 354.129737 -215.609234) (xy 354.106214 -215.563067) (xy 354.090202 -215.513788)
			(xy 354.082096 -215.462611) (xy 354.081588 -215.436704) (xy 352.861372 -215.436704) (xy 352.860864 -215.462611)
			(xy 352.852758 -215.513788) (xy 352.836746 -215.563067) (xy 352.813223 -215.609234) (xy 352.782767 -215.651153)
			(xy 352.746129 -215.687791) (xy 352.70421 -215.718247) (xy 352.658043 -215.74177) (xy 352.608764 -215.757782)
			(xy 352.557587 -215.765888) (xy 352.505773 -215.765888) (xy 352.454596 -215.757782) (xy 352.405317 -215.74177)
			(xy 352.35915 -215.718247) (xy 352.317231 -215.687791) (xy 352.280593 -215.651153) (xy 352.250137 -215.609234)
			(xy 352.226614 -215.563067) (xy 352.210602 -215.513788) (xy 352.202496 -215.462611) (xy 352.201988 -215.436704)
			(xy 350.981772 -215.436704) (xy 350.981264 -215.462611) (xy 350.973158 -215.513788) (xy 350.957146 -215.563067)
			(xy 350.933623 -215.609234) (xy 350.903167 -215.651153) (xy 350.866529 -215.687791) (xy 350.82461 -215.718247)
			(xy 350.778443 -215.74177) (xy 350.729164 -215.757782) (xy 350.677987 -215.765888) (xy 350.626173 -215.765888)
			(xy 350.574996 -215.757782) (xy 350.525717 -215.74177) (xy 350.47955 -215.718247) (xy 350.437631 -215.687791)
			(xy 350.400993 -215.651153) (xy 350.370537 -215.609234) (xy 350.347014 -215.563067) (xy 350.331002 -215.513788)
			(xy 350.322896 -215.462611) (xy 350.322388 -215.436704) (xy 349.102172 -215.436704) (xy 349.101664 -215.462611)
			(xy 349.093558 -215.513788) (xy 349.077546 -215.563067) (xy 349.054023 -215.609234) (xy 349.023567 -215.651153)
			(xy 348.986929 -215.687791) (xy 348.94501 -215.718247) (xy 348.898843 -215.74177) (xy 348.849564 -215.757782)
			(xy 348.798387 -215.765888) (xy 348.746573 -215.765888) (xy 348.695396 -215.757782) (xy 348.646117 -215.74177)
			(xy 348.59995 -215.718247) (xy 348.558031 -215.687791) (xy 348.521393 -215.651153) (xy 348.490937 -215.609234)
			(xy 348.467414 -215.563067) (xy 348.451402 -215.513788) (xy 348.443296 -215.462611) (xy 348.442788 -215.436704)
			(xy 347.222572 -215.436704) (xy 347.222064 -215.462611) (xy 347.213958 -215.513788) (xy 347.197946 -215.563067)
			(xy 347.174423 -215.609234) (xy 347.143967 -215.651153) (xy 347.107329 -215.687791) (xy 347.06541 -215.718247)
			(xy 347.019243 -215.74177) (xy 346.969964 -215.757782) (xy 346.918787 -215.765888) (xy 346.866973 -215.765888)
			(xy 346.815796 -215.757782) (xy 346.766517 -215.74177) (xy 346.72035 -215.718247) (xy 346.678431 -215.687791)
			(xy 346.641793 -215.651153) (xy 346.611337 -215.609234) (xy 346.587814 -215.563067) (xy 346.571802 -215.513788)
			(xy 346.563696 -215.462611) (xy 346.563188 -215.436704) (xy 345.342972 -215.436704) (xy 345.342464 -215.462611)
			(xy 345.334358 -215.513788) (xy 345.318346 -215.563067) (xy 345.294823 -215.609234) (xy 345.264367 -215.651153)
			(xy 345.227729 -215.687791) (xy 345.18581 -215.718247) (xy 345.139643 -215.74177) (xy 345.090364 -215.757782)
			(xy 345.039187 -215.765888) (xy 344.987373 -215.765888) (xy 344.936196 -215.757782) (xy 344.886917 -215.74177)
			(xy 344.84075 -215.718247) (xy 344.798831 -215.687791) (xy 344.762193 -215.651153) (xy 344.731737 -215.609234)
			(xy 344.708214 -215.563067) (xy 344.692202 -215.513788) (xy 344.684096 -215.462611) (xy 344.683588 -215.436704)
			(xy 343.463372 -215.436704) (xy 343.462864 -215.462611) (xy 343.454758 -215.513788) (xy 343.438746 -215.563067)
			(xy 343.415223 -215.609234) (xy 343.384767 -215.651153) (xy 343.348129 -215.687791) (xy 343.30621 -215.718247)
			(xy 343.260043 -215.74177) (xy 343.210764 -215.757782) (xy 343.159587 -215.765888) (xy 343.107773 -215.765888)
			(xy 343.056596 -215.757782) (xy 343.007317 -215.74177) (xy 342.96115 -215.718247) (xy 342.919231 -215.687791)
			(xy 342.882593 -215.651153) (xy 342.852137 -215.609234) (xy 342.828614 -215.563067) (xy 342.812602 -215.513788)
			(xy 342.804496 -215.462611) (xy 342.803988 -215.436704) (xy 341.583772 -215.436704) (xy 341.583264 -215.462611)
			(xy 341.575158 -215.513788) (xy 341.559146 -215.563067) (xy 341.535623 -215.609234) (xy 341.505167 -215.651153)
			(xy 341.468529 -215.687791) (xy 341.42661 -215.718247) (xy 341.380443 -215.74177) (xy 341.331164 -215.757782)
			(xy 341.279987 -215.765888) (xy 341.228173 -215.765888) (xy 341.176996 -215.757782) (xy 341.127717 -215.74177)
			(xy 341.08155 -215.718247) (xy 341.039631 -215.687791) (xy 341.002993 -215.651153) (xy 340.972537 -215.609234)
			(xy 340.949014 -215.563067) (xy 340.933002 -215.513788) (xy 340.924896 -215.462611) (xy 340.924388 -215.436704)
			(xy 339.704172 -215.436704) (xy 339.703664 -215.462611) (xy 339.695558 -215.513788) (xy 339.679546 -215.563067)
			(xy 339.656023 -215.609234) (xy 339.625567 -215.651153) (xy 339.588929 -215.687791) (xy 339.54701 -215.718247)
			(xy 339.500843 -215.74177) (xy 339.451564 -215.757782) (xy 339.400387 -215.765888) (xy 339.348573 -215.765888)
			(xy 339.297396 -215.757782) (xy 339.248117 -215.74177) (xy 339.20195 -215.718247) (xy 339.160031 -215.687791)
			(xy 339.123393 -215.651153) (xy 339.092937 -215.609234) (xy 339.069414 -215.563067) (xy 339.053402 -215.513788)
			(xy 339.045296 -215.462611) (xy 339.044788 -215.436704) (xy 337.824572 -215.436704) (xy 337.824064 -215.462611)
			(xy 337.815958 -215.513788) (xy 337.799946 -215.563067) (xy 337.776423 -215.609234) (xy 337.745967 -215.651153)
			(xy 337.709329 -215.687791) (xy 337.66741 -215.718247) (xy 337.621243 -215.74177) (xy 337.571964 -215.757782)
			(xy 337.520787 -215.765888) (xy 337.468973 -215.765888) (xy 337.417796 -215.757782) (xy 337.368517 -215.74177)
			(xy 337.32235 -215.718247) (xy 337.280431 -215.687791) (xy 337.243793 -215.651153) (xy 337.213337 -215.609234)
			(xy 337.189814 -215.563067) (xy 337.173802 -215.513788) (xy 337.165696 -215.462611) (xy 337.165188 -215.436704)
			(xy 336.884772 -215.436704) (xy 336.884181 -215.464421) (xy 336.874856 -215.519068) (xy 336.86623 -215.545416)
			(xy 336.858356 -215.567514) (xy 337.063334 -215.922352) (xy 337.086194 -215.92667) (xy 337.110997 -215.931858)
			(xy 337.158737 -215.948846) (xy 337.203315 -215.972939) (xy 337.243681 -216.00357) (xy 337.278884 -216.040017)
			(xy 337.308096 -216.081421) (xy 337.330629 -216.126808) (xy 337.345951 -216.175108) (xy 337.353702 -216.225184)
			(xy 337.354164 -216.25052) (xy 337.353656 -216.276407) (xy 337.345557 -216.327545) (xy 337.329558 -216.376785)
			(xy 337.306052 -216.422917) (xy 337.27562 -216.464804) (xy 337.23901 -216.501414) (xy 337.197123 -216.531846)
			(xy 337.150991 -216.555352) (xy 337.101751 -216.571351) (xy 337.050613 -216.57945) (xy 336.998839 -216.57945)
			(xy 336.947701 -216.571351) (xy 336.898461 -216.555352) (xy 336.852329 -216.531846) (xy 336.810442 -216.501414)
			(xy 336.773832 -216.464804) (xy 336.7434 -216.422917) (xy 336.719894 -216.376785) (xy 336.703895 -216.327545)
			(xy 336.695796 -216.276407) (xy 336.695288 -216.25052) (xy 336.695823 -216.222812) (xy 336.705015 -216.168165)
			(xy 336.713576 -216.141808) (xy 336.72145 -216.11971) (xy 336.516472 -215.764872) (xy 336.493612 -215.760554)
			(xy 336.46879 -215.755389) (xy 336.421007 -215.73844) (xy 336.376384 -215.714372) (xy 336.335974 -215.683753)
			(xy 336.300731 -215.647305) (xy 336.271487 -215.60589) (xy 336.248932 -215.560483) (xy 336.233597 -215.512158)
			(xy 336.225846 -215.462054) (xy 336.225388 -215.436704) (xy 135.934704 -215.436704) (xy 135.934196 -215.462611)
			(xy 135.92609 -215.513788) (xy 135.910078 -215.563067) (xy 135.886555 -215.609234) (xy 135.856099 -215.651153)
			(xy 135.819461 -215.687791) (xy 135.777542 -215.718247) (xy 135.731375 -215.74177) (xy 135.682096 -215.757782)
			(xy 135.630919 -215.765888) (xy 135.579105 -215.765888) (xy 135.527928 -215.757782) (xy 135.478649 -215.74177)
			(xy 135.432482 -215.718247) (xy 135.390563 -215.687791) (xy 135.353925 -215.651153) (xy 135.323469 -215.609234)
			(xy 135.299946 -215.563067) (xy 135.283934 -215.513788) (xy 135.275828 -215.462611) (xy 135.27532 -215.436704)
			(xy 135.27603 -215.405863) (xy 135.287538 -215.345263) (xy 135.29818 -215.316308) (xy 135.306816 -215.294464)
			(xy 135.084058 -214.872824) (xy 135.061452 -214.867744) (xy 135.037516 -214.861817) (xy 134.991624 -214.843773)
			(xy 134.948934 -214.819093) (xy 134.910397 -214.788329) (xy 134.876873 -214.752166) (xy 134.849112 -214.711412)
			(xy 134.827733 -214.666976) (xy 134.813212 -214.619852) (xy 134.805875 -214.57109) (xy 134.80542 -214.546434)
			(xy 133.57622 -214.546434) (xy 133.584188 -214.596747) (xy 133.584696 -214.622634) (xy 133.584247 -214.64797)
			(xy 133.57649 -214.698044) (xy 133.561163 -214.746341) (xy 133.538627 -214.791726) (xy 133.509412 -214.833128)
			(xy 133.474208 -214.869572) (xy 133.433842 -214.900202) (xy 133.389265 -214.924296) (xy 133.341527 -214.941286)
			(xy 133.316726 -214.946484) (xy 133.293866 -214.950802) (xy 133.088888 -215.305894) (xy 133.096762 -215.327738)
			(xy 133.10541 -215.354146) (xy 133.114729 -215.408922) (xy 133.115304 -215.436704) (xy 133.114796 -215.46261)
			(xy 133.396194 -215.46261) (xy 133.396194 -215.41079) (xy 133.4043 -215.359609) (xy 133.420313 -215.310326)
			(xy 133.44384 -215.264155) (xy 133.474299 -215.222232) (xy 133.510941 -215.185591) (xy 133.552865 -215.155133)
			(xy 133.599037 -215.131609) (xy 133.648321 -215.115597) (xy 133.699502 -215.107493) (xy 133.725412 -215.107012)
			(xy 133.750924 -215.107479) (xy 133.80134 -215.115342) (xy 133.849942 -215.130878) (xy 133.89557 -215.153716)
			(xy 133.937135 -215.183311) (xy 133.973645 -215.218956) (xy 133.989318 -215.239092) (xy 134.401306 -215.239092)
			(xy 134.416974 -215.218952) (xy 134.453485 -215.183309) (xy 134.495052 -215.153716) (xy 134.540681 -215.130881)
			(xy 134.589284 -215.115348) (xy 134.6397 -215.107489) (xy 134.665212 -215.107012) (xy 134.691119 -215.107513)
			(xy 134.742295 -215.11562) (xy 134.791573 -215.131633) (xy 134.837739 -215.155158) (xy 134.879656 -215.185614)
			(xy 134.916294 -215.222253) (xy 134.946749 -215.264172) (xy 134.970271 -215.310339) (xy 134.986282 -215.359617)
			(xy 134.994388 -215.410793) (xy 134.994388 -215.462607) (xy 134.986282 -215.513783) (xy 134.970271 -215.563061)
			(xy 134.946749 -215.609228) (xy 134.916294 -215.651147) (xy 134.879656 -215.687786) (xy 134.837739 -215.718242)
			(xy 134.791573 -215.741767) (xy 134.742295 -215.75778) (xy 134.691119 -215.765887) (xy 134.665212 -215.766396)
			(xy 134.6397 -215.765908) (xy 134.589286 -215.758049) (xy 134.540685 -215.742517) (xy 134.495056 -215.719683)
			(xy 134.453491 -215.690092) (xy 134.41698 -215.65445) (xy 134.401306 -215.634316) (xy 133.989318 -215.634316)
			(xy 133.973638 -215.654446) (xy 133.937129 -215.69009) (xy 133.895565 -215.719683) (xy 133.849938 -215.74252)
			(xy 133.801337 -215.758055) (xy 133.750924 -215.765918) (xy 133.725412 -215.766396) (xy 133.699502 -215.765907)
			(xy 133.648321 -215.757803) (xy 133.599037 -215.741791) (xy 133.552865 -215.718267) (xy 133.510941 -215.687809)
			(xy 133.474299 -215.651168) (xy 133.44384 -215.609245) (xy 133.420313 -215.563074) (xy 133.4043 -215.513791)
			(xy 133.396194 -215.46261) (xy 133.114796 -215.46261) (xy 133.114796 -215.462611) (xy 133.10669 -215.513788)
			(xy 133.090678 -215.563067) (xy 133.067155 -215.609234) (xy 133.036699 -215.651153) (xy 133.000061 -215.687791)
			(xy 132.958142 -215.718247) (xy 132.911975 -215.74177) (xy 132.862696 -215.757782) (xy 132.811519 -215.765888)
			(xy 132.759705 -215.765888) (xy 132.708528 -215.757782) (xy 132.659249 -215.74177) (xy 132.613082 -215.718247)
			(xy 132.571163 -215.687791) (xy 132.534525 -215.651153) (xy 132.504069 -215.609234) (xy 132.480546 -215.563067)
			(xy 132.464534 -215.513788) (xy 132.456428 -215.462611) (xy 132.45592 -215.436704) (xy 131.235704 -215.436704)
			(xy 131.235196 -215.462611) (xy 131.22709 -215.513788) (xy 131.211078 -215.563067) (xy 131.187555 -215.609234)
			(xy 131.157099 -215.651153) (xy 131.120461 -215.687791) (xy 131.078542 -215.718247) (xy 131.032375 -215.74177)
			(xy 130.983096 -215.757782) (xy 130.931919 -215.765888) (xy 130.880105 -215.765888) (xy 130.828928 -215.757782)
			(xy 130.779649 -215.74177) (xy 130.733482 -215.718247) (xy 130.691563 -215.687791) (xy 130.654925 -215.651153)
			(xy 130.624469 -215.609234) (xy 130.600946 -215.563067) (xy 130.584934 -215.513788) (xy 130.576828 -215.462611)
			(xy 130.57632 -215.436704) (xy 129.356104 -215.436704) (xy 129.355596 -215.462611) (xy 129.34749 -215.513788)
			(xy 129.331478 -215.563067) (xy 129.307955 -215.609234) (xy 129.277499 -215.651153) (xy 129.240861 -215.687791)
			(xy 129.198942 -215.718247) (xy 129.152775 -215.74177) (xy 129.103496 -215.757782) (xy 129.052319 -215.765888)
			(xy 129.000505 -215.765888) (xy 128.949328 -215.757782) (xy 128.900049 -215.74177) (xy 128.853882 -215.718247)
			(xy 128.811963 -215.687791) (xy 128.775325 -215.651153) (xy 128.744869 -215.609234) (xy 128.721346 -215.563067)
			(xy 128.705334 -215.513788) (xy 128.697228 -215.462611) (xy 128.69672 -215.436704) (xy 127.476504 -215.436704)
			(xy 127.475996 -215.462611) (xy 127.46789 -215.513788) (xy 127.451878 -215.563067) (xy 127.428355 -215.609234)
			(xy 127.397899 -215.651153) (xy 127.361261 -215.687791) (xy 127.319342 -215.718247) (xy 127.273175 -215.74177)
			(xy 127.223896 -215.757782) (xy 127.172719 -215.765888) (xy 127.120905 -215.765888) (xy 127.069728 -215.757782)
			(xy 127.020449 -215.74177) (xy 126.974282 -215.718247) (xy 126.932363 -215.687791) (xy 126.895725 -215.651153)
			(xy 126.865269 -215.609234) (xy 126.841746 -215.563067) (xy 126.825734 -215.513788) (xy 126.817628 -215.462611)
			(xy 126.81712 -215.436704) (xy 125.596904 -215.436704) (xy 125.596396 -215.462611) (xy 125.58829 -215.513788)
			(xy 125.572278 -215.563067) (xy 125.548755 -215.609234) (xy 125.518299 -215.651153) (xy 125.481661 -215.687791)
			(xy 125.439742 -215.718247) (xy 125.393575 -215.74177) (xy 125.344296 -215.757782) (xy 125.293119 -215.765888)
			(xy 125.241305 -215.765888) (xy 125.190128 -215.757782) (xy 125.140849 -215.74177) (xy 125.094682 -215.718247)
			(xy 125.052763 -215.687791) (xy 125.016125 -215.651153) (xy 124.985669 -215.609234) (xy 124.962146 -215.563067)
			(xy 124.946134 -215.513788) (xy 124.938028 -215.462611) (xy 124.93752 -215.436704) (xy 123.717304 -215.436704)
			(xy 123.716796 -215.462611) (xy 123.70869 -215.513788) (xy 123.692678 -215.563067) (xy 123.669155 -215.609234)
			(xy 123.638699 -215.651153) (xy 123.602061 -215.687791) (xy 123.560142 -215.718247) (xy 123.513975 -215.74177)
			(xy 123.464696 -215.757782) (xy 123.413519 -215.765888) (xy 123.361705 -215.765888) (xy 123.310528 -215.757782)
			(xy 123.261249 -215.74177) (xy 123.215082 -215.718247) (xy 123.173163 -215.687791) (xy 123.136525 -215.651153)
			(xy 123.106069 -215.609234) (xy 123.082546 -215.563067) (xy 123.066534 -215.513788) (xy 123.058428 -215.462611)
			(xy 123.05792 -215.436704) (xy 121.837704 -215.436704) (xy 121.837196 -215.462611) (xy 121.82909 -215.513788)
			(xy 121.813078 -215.563067) (xy 121.789555 -215.609234) (xy 121.759099 -215.651153) (xy 121.722461 -215.687791)
			(xy 121.680542 -215.718247) (xy 121.634375 -215.74177) (xy 121.585096 -215.757782) (xy 121.533919 -215.765888)
			(xy 121.482105 -215.765888) (xy 121.430928 -215.757782) (xy 121.381649 -215.74177) (xy 121.335482 -215.718247)
			(xy 121.293563 -215.687791) (xy 121.256925 -215.651153) (xy 121.226469 -215.609234) (xy 121.202946 -215.563067)
			(xy 121.186934 -215.513788) (xy 121.178828 -215.462611) (xy 121.17832 -215.436704) (xy 119.958104 -215.436704)
			(xy 119.957596 -215.462611) (xy 119.94949 -215.513788) (xy 119.933478 -215.563067) (xy 119.909955 -215.609234)
			(xy 119.879499 -215.651153) (xy 119.842861 -215.687791) (xy 119.800942 -215.718247) (xy 119.754775 -215.74177)
			(xy 119.705496 -215.757782) (xy 119.654319 -215.765888) (xy 119.602505 -215.765888) (xy 119.551328 -215.757782)
			(xy 119.502049 -215.74177) (xy 119.455882 -215.718247) (xy 119.413963 -215.687791) (xy 119.377325 -215.651153)
			(xy 119.346869 -215.609234) (xy 119.323346 -215.563067) (xy 119.307334 -215.513788) (xy 119.299228 -215.462611)
			(xy 119.29872 -215.436704) (xy 118.078504 -215.436704) (xy 118.077996 -215.462611) (xy 118.06989 -215.513788)
			(xy 118.053878 -215.563067) (xy 118.030355 -215.609234) (xy 117.999899 -215.651153) (xy 117.963261 -215.687791)
			(xy 117.921342 -215.718247) (xy 117.875175 -215.74177) (xy 117.825896 -215.757782) (xy 117.774719 -215.765888)
			(xy 117.722905 -215.765888) (xy 117.671728 -215.757782) (xy 117.622449 -215.74177) (xy 117.576282 -215.718247)
			(xy 117.534363 -215.687791) (xy 117.497725 -215.651153) (xy 117.467269 -215.609234) (xy 117.443746 -215.563067)
			(xy 117.427734 -215.513788) (xy 117.419628 -215.462611) (xy 117.41912 -215.436704) (xy 116.198904 -215.436704)
			(xy 116.198396 -215.462611) (xy 116.19029 -215.513788) (xy 116.174278 -215.563067) (xy 116.150755 -215.609234)
			(xy 116.120299 -215.651153) (xy 116.083661 -215.687791) (xy 116.041742 -215.718247) (xy 115.995575 -215.74177)
			(xy 115.946296 -215.757782) (xy 115.895119 -215.765888) (xy 115.843305 -215.765888) (xy 115.792128 -215.757782)
			(xy 115.742849 -215.74177) (xy 115.696682 -215.718247) (xy 115.654763 -215.687791) (xy 115.618125 -215.651153)
			(xy 115.587669 -215.609234) (xy 115.564146 -215.563067) (xy 115.548134 -215.513788) (xy 115.540028 -215.462611)
			(xy 115.53952 -215.436704) (xy 114.319304 -215.436704) (xy 114.318796 -215.462611) (xy 114.31069 -215.513788)
			(xy 114.294678 -215.563067) (xy 114.271155 -215.609234) (xy 114.240699 -215.651153) (xy 114.204061 -215.687791)
			(xy 114.162142 -215.718247) (xy 114.115975 -215.74177) (xy 114.066696 -215.757782) (xy 114.015519 -215.765888)
			(xy 113.963705 -215.765888) (xy 113.912528 -215.757782) (xy 113.863249 -215.74177) (xy 113.817082 -215.718247)
			(xy 113.775163 -215.687791) (xy 113.738525 -215.651153) (xy 113.708069 -215.609234) (xy 113.684546 -215.563067)
			(xy 113.668534 -215.513788) (xy 113.660428 -215.462611) (xy 113.65992 -215.436704) (xy 111.499904 -215.436704)
			(xy 111.499396 -215.462611) (xy 111.49129 -215.513788) (xy 111.475278 -215.563067) (xy 111.451755 -215.609234)
			(xy 111.421299 -215.651153) (xy 111.384661 -215.687791) (xy 111.342742 -215.718247) (xy 111.296575 -215.74177)
			(xy 111.247296 -215.757782) (xy 111.196119 -215.765888) (xy 111.144305 -215.765888) (xy 111.093128 -215.757782)
			(xy 111.043849 -215.74177) (xy 110.997682 -215.718247) (xy 110.955763 -215.687791) (xy 110.919125 -215.651153)
			(xy 110.888669 -215.609234) (xy 110.865146 -215.563067) (xy 110.849134 -215.513788) (xy 110.841028 -215.462611)
			(xy 110.84052 -215.436704) (xy 110.840955 -215.413764) (xy 110.847378 -215.368334) (xy 110.860018 -215.324227)
			(xy 110.868968 -215.3031) (xy 110.878874 -215.280494) (xy 110.665006 -214.87511) (xy 110.640876 -214.870538)
			(xy 110.615954 -214.86544) (xy 110.567941 -214.848641) (xy 110.523081 -214.824663) (xy 110.482438 -214.794075)
			(xy 110.44698 -214.757604) (xy 110.417549 -214.716116) (xy 110.394843 -214.670598) (xy 110.379403 -214.622131)
			(xy 110.371595 -214.571867) (xy 110.371128 -214.546434) (xy 109.14142 -214.546434) (xy 109.149388 -214.596747)
			(xy 109.149896 -214.622634) (xy 109.149447 -214.64797) (xy 109.14169 -214.698044) (xy 109.126363 -214.746341)
			(xy 109.103827 -214.791726) (xy 109.074612 -214.833128) (xy 109.039408 -214.869572) (xy 108.999042 -214.900202)
			(xy 108.954465 -214.924296) (xy 108.906727 -214.941286) (xy 108.881926 -214.946484) (xy 108.859066 -214.950802)
			(xy 108.654088 -215.305894) (xy 108.661962 -215.327738) (xy 108.67061 -215.354146) (xy 108.679929 -215.408922)
			(xy 108.680504 -215.436704) (xy 108.679996 -215.46261) (xy 108.961394 -215.46261) (xy 108.961394 -215.41079)
			(xy 108.9695 -215.359609) (xy 108.985513 -215.310326) (xy 109.00904 -215.264155) (xy 109.039499 -215.222232)
			(xy 109.076141 -215.185591) (xy 109.118065 -215.155133) (xy 109.164237 -215.131609) (xy 109.213521 -215.115597)
			(xy 109.264702 -215.107493) (xy 109.290612 -215.107012) (xy 109.316124 -215.107479) (xy 109.36654 -215.115342)
			(xy 109.415142 -215.130878) (xy 109.46077 -215.153716) (xy 109.502335 -215.183311) (xy 109.538845 -215.218956)
			(xy 109.554518 -215.239092) (xy 109.966506 -215.239092) (xy 109.982174 -215.218952) (xy 110.018685 -215.183309)
			(xy 110.060252 -215.153716) (xy 110.105881 -215.130881) (xy 110.154484 -215.115348) (xy 110.2049 -215.107489)
			(xy 110.230412 -215.107012) (xy 110.256319 -215.107513) (xy 110.307495 -215.11562) (xy 110.356773 -215.131633)
			(xy 110.402939 -215.155158) (xy 110.444856 -215.185614) (xy 110.481494 -215.222253) (xy 110.511949 -215.264172)
			(xy 110.535471 -215.310339) (xy 110.551482 -215.359617) (xy 110.559588 -215.410793) (xy 110.559588 -215.462607)
			(xy 110.551482 -215.513783) (xy 110.535471 -215.563061) (xy 110.511949 -215.609228) (xy 110.481494 -215.651147)
			(xy 110.444856 -215.687786) (xy 110.402939 -215.718242) (xy 110.356773 -215.741767) (xy 110.307495 -215.75778)
			(xy 110.256319 -215.765887) (xy 110.230412 -215.766396) (xy 110.2049 -215.765908) (xy 110.154486 -215.758049)
			(xy 110.105885 -215.742517) (xy 110.060256 -215.719683) (xy 110.018691 -215.690092) (xy 109.98218 -215.65445)
			(xy 109.966506 -215.634316) (xy 109.554518 -215.634316) (xy 109.538838 -215.654446) (xy 109.502329 -215.69009)
			(xy 109.460765 -215.719683) (xy 109.415138 -215.74252) (xy 109.366537 -215.758055) (xy 109.316124 -215.765918)
			(xy 109.290612 -215.766396) (xy 109.264702 -215.765907) (xy 109.213521 -215.757803) (xy 109.164237 -215.741791)
			(xy 109.118065 -215.718267) (xy 109.076141 -215.687809) (xy 109.039499 -215.651168) (xy 109.00904 -215.609245)
			(xy 108.985513 -215.563074) (xy 108.9695 -215.513791) (xy 108.961394 -215.46261) (xy 108.679996 -215.46261)
			(xy 108.679996 -215.462611) (xy 108.67189 -215.513788) (xy 108.655878 -215.563067) (xy 108.632355 -215.609234)
			(xy 108.601899 -215.651153) (xy 108.565261 -215.687791) (xy 108.523342 -215.718247) (xy 108.477175 -215.74177)
			(xy 108.427896 -215.757782) (xy 108.376719 -215.765888) (xy 108.324905 -215.765888) (xy 108.273728 -215.757782)
			(xy 108.224449 -215.74177) (xy 108.178282 -215.718247) (xy 108.136363 -215.687791) (xy 108.099725 -215.651153)
			(xy 108.069269 -215.609234) (xy 108.045746 -215.563067) (xy 108.029734 -215.513788) (xy 108.021628 -215.462611)
			(xy 108.02112 -215.436704) (xy 106.800904 -215.436704) (xy 106.800396 -215.462611) (xy 106.79229 -215.513788)
			(xy 106.776278 -215.563067) (xy 106.752755 -215.609234) (xy 106.722299 -215.651153) (xy 106.685661 -215.687791)
			(xy 106.643742 -215.718247) (xy 106.597575 -215.74177) (xy 106.548296 -215.757782) (xy 106.497119 -215.765888)
			(xy 106.445305 -215.765888) (xy 106.394128 -215.757782) (xy 106.344849 -215.74177) (xy 106.298682 -215.718247)
			(xy 106.256763 -215.687791) (xy 106.220125 -215.651153) (xy 106.189669 -215.609234) (xy 106.166146 -215.563067)
			(xy 106.150134 -215.513788) (xy 106.142028 -215.462611) (xy 106.14152 -215.436704) (xy 104.921304 -215.436704)
			(xy 104.920796 -215.462611) (xy 104.91269 -215.513788) (xy 104.896678 -215.563067) (xy 104.873155 -215.609234)
			(xy 104.842699 -215.651153) (xy 104.806061 -215.687791) (xy 104.764142 -215.718247) (xy 104.717975 -215.74177)
			(xy 104.668696 -215.757782) (xy 104.617519 -215.765888) (xy 104.565705 -215.765888) (xy 104.514528 -215.757782)
			(xy 104.465249 -215.74177) (xy 104.419082 -215.718247) (xy 104.377163 -215.687791) (xy 104.340525 -215.651153)
			(xy 104.310069 -215.609234) (xy 104.286546 -215.563067) (xy 104.270534 -215.513788) (xy 104.262428 -215.462611)
			(xy 104.26192 -215.436704) (xy 103.041704 -215.436704) (xy 103.041196 -215.462611) (xy 103.03309 -215.513788)
			(xy 103.017078 -215.563067) (xy 102.993555 -215.609234) (xy 102.963099 -215.651153) (xy 102.926461 -215.687791)
			(xy 102.884542 -215.718247) (xy 102.838375 -215.74177) (xy 102.789096 -215.757782) (xy 102.737919 -215.765888)
			(xy 102.686105 -215.765888) (xy 102.634928 -215.757782) (xy 102.585649 -215.74177) (xy 102.539482 -215.718247)
			(xy 102.497563 -215.687791) (xy 102.460925 -215.651153) (xy 102.430469 -215.609234) (xy 102.406946 -215.563067)
			(xy 102.390934 -215.513788) (xy 102.382828 -215.462611) (xy 102.38232 -215.436704) (xy 101.162104 -215.436704)
			(xy 101.161596 -215.462611) (xy 101.15349 -215.513788) (xy 101.137478 -215.563067) (xy 101.113955 -215.609234)
			(xy 101.083499 -215.651153) (xy 101.046861 -215.687791) (xy 101.004942 -215.718247) (xy 100.958775 -215.74177)
			(xy 100.909496 -215.757782) (xy 100.858319 -215.765888) (xy 100.806505 -215.765888) (xy 100.755328 -215.757782)
			(xy 100.706049 -215.74177) (xy 100.659882 -215.718247) (xy 100.617963 -215.687791) (xy 100.581325 -215.651153)
			(xy 100.550869 -215.609234) (xy 100.527346 -215.563067) (xy 100.511334 -215.513788) (xy 100.503228 -215.462611)
			(xy 100.50272 -215.436704) (xy 99.282504 -215.436704) (xy 99.281996 -215.462611) (xy 99.27389 -215.513788)
			(xy 99.257878 -215.563067) (xy 99.234355 -215.609234) (xy 99.203899 -215.651153) (xy 99.167261 -215.687791)
			(xy 99.125342 -215.718247) (xy 99.079175 -215.74177) (xy 99.029896 -215.757782) (xy 98.978719 -215.765888)
			(xy 98.926905 -215.765888) (xy 98.875728 -215.757782) (xy 98.826449 -215.74177) (xy 98.780282 -215.718247)
			(xy 98.738363 -215.687791) (xy 98.701725 -215.651153) (xy 98.671269 -215.609234) (xy 98.647746 -215.563067)
			(xy 98.631734 -215.513788) (xy 98.623628 -215.462611) (xy 98.62312 -215.436704) (xy 97.402904 -215.436704)
			(xy 97.402396 -215.462611) (xy 97.39429 -215.513788) (xy 97.378278 -215.563067) (xy 97.354755 -215.609234)
			(xy 97.324299 -215.651153) (xy 97.287661 -215.687791) (xy 97.245742 -215.718247) (xy 97.199575 -215.74177)
			(xy 97.150296 -215.757782) (xy 97.099119 -215.765888) (xy 97.047305 -215.765888) (xy 96.996128 -215.757782)
			(xy 96.946849 -215.74177) (xy 96.900682 -215.718247) (xy 96.858763 -215.687791) (xy 96.822125 -215.651153)
			(xy 96.791669 -215.609234) (xy 96.768146 -215.563067) (xy 96.752134 -215.513788) (xy 96.744028 -215.462611)
			(xy 96.74352 -215.436704) (xy 95.523304 -215.436704) (xy 95.522796 -215.462611) (xy 95.51469 -215.513788)
			(xy 95.498678 -215.563067) (xy 95.475155 -215.609234) (xy 95.444699 -215.651153) (xy 95.408061 -215.687791)
			(xy 95.366142 -215.718247) (xy 95.319975 -215.74177) (xy 95.270696 -215.757782) (xy 95.219519 -215.765888)
			(xy 95.167705 -215.765888) (xy 95.116528 -215.757782) (xy 95.067249 -215.74177) (xy 95.021082 -215.718247)
			(xy 94.979163 -215.687791) (xy 94.942525 -215.651153) (xy 94.912069 -215.609234) (xy 94.888546 -215.563067)
			(xy 94.872534 -215.513788) (xy 94.864428 -215.462611) (xy 94.86392 -215.436704) (xy 93.643704 -215.436704)
			(xy 93.643196 -215.462611) (xy 93.63509 -215.513788) (xy 93.619078 -215.563067) (xy 93.595555 -215.609234)
			(xy 93.565099 -215.651153) (xy 93.528461 -215.687791) (xy 93.486542 -215.718247) (xy 93.440375 -215.74177)
			(xy 93.391096 -215.757782) (xy 93.339919 -215.765888) (xy 93.288105 -215.765888) (xy 93.236928 -215.757782)
			(xy 93.187649 -215.74177) (xy 93.141482 -215.718247) (xy 93.099563 -215.687791) (xy 93.062925 -215.651153)
			(xy 93.032469 -215.609234) (xy 93.008946 -215.563067) (xy 92.992934 -215.513788) (xy 92.984828 -215.462611)
			(xy 92.98432 -215.436704) (xy 91.764104 -215.436704) (xy 91.763596 -215.462611) (xy 91.75549 -215.513788)
			(xy 91.739478 -215.563067) (xy 91.715955 -215.609234) (xy 91.685499 -215.651153) (xy 91.648861 -215.687791)
			(xy 91.606942 -215.718247) (xy 91.560775 -215.74177) (xy 91.511496 -215.757782) (xy 91.460319 -215.765888)
			(xy 91.408505 -215.765888) (xy 91.357328 -215.757782) (xy 91.308049 -215.74177) (xy 91.261882 -215.718247)
			(xy 91.219963 -215.687791) (xy 91.183325 -215.651153) (xy 91.152869 -215.609234) (xy 91.129346 -215.563067)
			(xy 91.113334 -215.513788) (xy 91.105228 -215.462611) (xy 91.10472 -215.436704) (xy 89.884504 -215.436704)
			(xy 89.883996 -215.462611) (xy 89.87589 -215.513788) (xy 89.859878 -215.563067) (xy 89.836355 -215.609234)
			(xy 89.805899 -215.651153) (xy 89.769261 -215.687791) (xy 89.727342 -215.718247) (xy 89.681175 -215.74177)
			(xy 89.631896 -215.757782) (xy 89.580719 -215.765888) (xy 89.528905 -215.765888) (xy 89.477728 -215.757782)
			(xy 89.428449 -215.74177) (xy 89.382282 -215.718247) (xy 89.340363 -215.687791) (xy 89.303725 -215.651153)
			(xy 89.273269 -215.609234) (xy 89.249746 -215.563067) (xy 89.233734 -215.513788) (xy 89.225628 -215.462611)
			(xy 89.22512 -215.436704) (xy 88.944704 -215.436704) (xy 88.944111 -215.464421) (xy 88.934787 -215.519068)
			(xy 88.926162 -215.545416) (xy 88.918288 -215.567514) (xy 89.123266 -215.922352) (xy 89.146126 -215.92667)
			(xy 89.170934 -215.931835) (xy 89.218674 -215.948828) (xy 89.263251 -215.972925) (xy 89.303616 -216.003559)
			(xy 89.338819 -216.040009) (xy 89.36803 -216.081415) (xy 89.390562 -216.126804) (xy 89.405883 -216.175106)
			(xy 89.413634 -216.225183) (xy 89.414096 -216.25052) (xy 89.413588 -216.276407) (xy 89.405489 -216.327545)
			(xy 89.38949 -216.376785) (xy 89.365984 -216.422917) (xy 89.335552 -216.464804) (xy 89.298942 -216.501414)
			(xy 89.257055 -216.531846) (xy 89.210923 -216.555352) (xy 89.161683 -216.571351) (xy 89.110545 -216.57945)
			(xy 89.058771 -216.57945) (xy 89.007633 -216.571351) (xy 88.958393 -216.555352) (xy 88.912261 -216.531846)
			(xy 88.870374 -216.501414) (xy 88.833764 -216.464804) (xy 88.803332 -216.422917) (xy 88.779826 -216.376785)
			(xy 88.763827 -216.327545) (xy 88.755728 -216.276407) (xy 88.75522 -216.25052) (xy 88.755754 -216.222812)
			(xy 88.764946 -216.168165) (xy 88.773508 -216.141808) (xy 88.781382 -216.11971) (xy 88.576404 -215.764872)
			(xy 88.553544 -215.760554) (xy 88.528711 -215.755439) (xy 88.480928 -215.73848) (xy 88.436306 -215.714403)
			(xy 88.395898 -215.683776) (xy 88.360658 -215.647323) (xy 88.331415 -215.605902) (xy 88.308862 -215.560492)
			(xy 88.293529 -215.512163) (xy 88.285778 -215.462056) (xy 88.28532 -215.436704) (xy 2.509012 -215.436704)
			(xy 2.509012 -217.878406) (xy 88.755728 -217.878406) (xy 88.756236 -217.852519) (xy 88.764335 -217.801381)
			(xy 88.780334 -217.752141) (xy 88.80384 -217.706009) (xy 88.834272 -217.664122) (xy 88.870882 -217.627512)
			(xy 88.912769 -217.59708) (xy 88.958901 -217.573574) (xy 89.008141 -217.557575) (xy 89.059279 -217.549476)
			(xy 89.111053 -217.549476) (xy 89.162191 -217.557575) (xy 89.211431 -217.573574) (xy 89.257563 -217.59708)
			(xy 89.29945 -217.627512) (xy 89.33606 -217.664122) (xy 89.366492 -217.706009) (xy 89.389998 -217.752141)
			(xy 89.405997 -217.801381) (xy 89.414096 -217.852519) (xy 89.414604 -217.878406) (xy 89.695528 -217.878406)
			(xy 89.695994 -217.853071) (xy 89.703746 -217.802996) (xy 89.719069 -217.754698) (xy 89.741602 -217.709313)
			(xy 89.770814 -217.66791) (xy 89.806017 -217.631464) (xy 89.846382 -217.600835) (xy 89.890959 -217.576742)
			(xy 89.938697 -217.559754) (xy 89.963498 -217.554556) (xy 89.986358 -217.550238) (xy 90.191336 -217.195146)
			(xy 90.183462 -217.173302) (xy 90.174824 -217.146891) (xy 90.165499 -217.092117) (xy 90.16492 -217.064336)
			(xy 90.165428 -217.038429) (xy 90.173534 -216.987252) (xy 90.189546 -216.937973) (xy 90.213069 -216.891806)
			(xy 90.243525 -216.849887) (xy 90.280163 -216.813249) (xy 90.322082 -216.782793) (xy 90.368249 -216.75927)
			(xy 90.417528 -216.743258) (xy 90.468705 -216.735152) (xy 90.520519 -216.735152) (xy 90.571696 -216.743258)
			(xy 90.620975 -216.75927) (xy 90.667142 -216.782793) (xy 90.709061 -216.813249) (xy 90.745699 -216.849887)
			(xy 90.776155 -216.891806) (xy 90.799678 -216.937973) (xy 90.81569 -216.987252) (xy 90.823796 -217.038429)
			(xy 90.824304 -217.064336) (xy 90.823812 -217.08968) (xy 90.816035 -217.13977) (xy 90.800686 -217.188079)
			(xy 90.778125 -217.233471) (xy 90.748884 -217.274876) (xy 90.713652 -217.311319) (xy 90.673259 -217.341943)
			(xy 90.628655 -217.366024) (xy 90.580892 -217.382998) (xy 90.55608 -217.388186) (xy 90.53322 -217.392504)
			(xy 90.328242 -217.747596) (xy 90.336116 -217.76944) (xy 90.344706 -217.795856) (xy 90.353895 -217.850633)
			(xy 90.354404 -217.878406) (xy 90.635328 -217.878406) (xy 90.635836 -217.852519) (xy 90.643935 -217.801381)
			(xy 90.659934 -217.752141) (xy 90.68344 -217.706009) (xy 90.713872 -217.664122) (xy 90.750482 -217.627512)
			(xy 90.792369 -217.59708) (xy 90.838501 -217.573574) (xy 90.887741 -217.557575) (xy 90.938879 -217.549476)
			(xy 90.990653 -217.549476) (xy 91.041791 -217.557575) (xy 91.091031 -217.573574) (xy 91.137163 -217.59708)
			(xy 91.17905 -217.627512) (xy 91.21566 -217.664122) (xy 91.246092 -217.706009) (xy 91.269598 -217.752141)
			(xy 91.285597 -217.801381) (xy 91.293696 -217.852519) (xy 91.294204 -217.878406) (xy 91.575128 -217.878406)
			(xy 91.575594 -217.853071) (xy 91.583346 -217.802996) (xy 91.598669 -217.754698) (xy 91.621202 -217.709313)
			(xy 91.650414 -217.66791) (xy 91.685617 -217.631464) (xy 91.725982 -217.600835) (xy 91.770559 -217.576742)
			(xy 91.818297 -217.559754) (xy 91.843098 -217.554556) (xy 91.865958 -217.550238) (xy 92.070936 -217.195146)
			(xy 92.063062 -217.173302) (xy 92.054424 -217.146891) (xy 92.045099 -217.092117) (xy 92.04452 -217.064336)
			(xy 92.045028 -217.038429) (xy 92.053134 -216.987252) (xy 92.069146 -216.937973) (xy 92.092669 -216.891806)
			(xy 92.123125 -216.849887) (xy 92.159763 -216.813249) (xy 92.201682 -216.782793) (xy 92.247849 -216.75927)
			(xy 92.297128 -216.743258) (xy 92.348305 -216.735152) (xy 92.400119 -216.735152) (xy 92.451296 -216.743258)
			(xy 92.500575 -216.75927) (xy 92.546742 -216.782793) (xy 92.588661 -216.813249) (xy 92.625299 -216.849887)
			(xy 92.655755 -216.891806) (xy 92.679278 -216.937973) (xy 92.69529 -216.987252) (xy 92.703396 -217.038429)
			(xy 92.703904 -217.064336) (xy 92.703412 -217.08968) (xy 92.695635 -217.13977) (xy 92.680286 -217.188079)
			(xy 92.657725 -217.233471) (xy 92.628484 -217.274876) (xy 92.593252 -217.311319) (xy 92.552859 -217.341943)
			(xy 92.508255 -217.366024) (xy 92.460492 -217.382998) (xy 92.43568 -217.388186) (xy 92.41282 -217.392504)
			(xy 92.207842 -217.747596) (xy 92.215716 -217.76944) (xy 92.224306 -217.795856) (xy 92.233495 -217.850633)
			(xy 92.234004 -217.878406) (xy 92.514928 -217.878406) (xy 92.515436 -217.852519) (xy 92.523535 -217.801381)
			(xy 92.539534 -217.752141) (xy 92.56304 -217.706009) (xy 92.593472 -217.664122) (xy 92.630082 -217.627512)
			(xy 92.671969 -217.59708) (xy 92.718101 -217.573574) (xy 92.767341 -217.557575) (xy 92.818479 -217.549476)
			(xy 92.870253 -217.549476) (xy 92.921391 -217.557575) (xy 92.970631 -217.573574) (xy 93.016763 -217.59708)
			(xy 93.05865 -217.627512) (xy 93.09526 -217.664122) (xy 93.125692 -217.706009) (xy 93.149198 -217.752141)
			(xy 93.165197 -217.801381) (xy 93.173296 -217.852519) (xy 93.173804 -217.878406) (xy 93.454728 -217.878406)
			(xy 93.455194 -217.853071) (xy 93.462946 -217.802996) (xy 93.478269 -217.754698) (xy 93.500802 -217.709313)
			(xy 93.530014 -217.66791) (xy 93.565217 -217.631464) (xy 93.605582 -217.600835) (xy 93.650159 -217.576742)
			(xy 93.697897 -217.559754) (xy 93.722698 -217.554556) (xy 93.745558 -217.550238) (xy 93.950536 -217.195146)
			(xy 93.942662 -217.173302) (xy 93.934024 -217.146891) (xy 93.924699 -217.092117) (xy 93.92412 -217.064336)
			(xy 93.924628 -217.038429) (xy 93.932734 -216.987252) (xy 93.948746 -216.937973) (xy 93.972269 -216.891806)
			(xy 94.002725 -216.849887) (xy 94.039363 -216.813249) (xy 94.081282 -216.782793) (xy 94.127449 -216.75927)
			(xy 94.176728 -216.743258) (xy 94.227905 -216.735152) (xy 94.279719 -216.735152) (xy 94.330896 -216.743258)
			(xy 94.380175 -216.75927) (xy 94.426342 -216.782793) (xy 94.468261 -216.813249) (xy 94.504899 -216.849887)
			(xy 94.535355 -216.891806) (xy 94.558878 -216.937973) (xy 94.57489 -216.987252) (xy 94.582996 -217.038429)
			(xy 94.583504 -217.064336) (xy 94.583012 -217.08968) (xy 94.575235 -217.13977) (xy 94.559886 -217.188079)
			(xy 94.537325 -217.233471) (xy 94.508084 -217.274876) (xy 94.472852 -217.311319) (xy 94.432459 -217.341943)
			(xy 94.387855 -217.366024) (xy 94.340092 -217.382998) (xy 94.31528 -217.388186) (xy 94.29242 -217.392504)
			(xy 94.087442 -217.747596) (xy 94.095316 -217.76944) (xy 94.103906 -217.795856) (xy 94.113095 -217.850633)
			(xy 94.113604 -217.878406) (xy 94.394528 -217.878406) (xy 94.395036 -217.852519) (xy 94.403135 -217.801381)
			(xy 94.419134 -217.752141) (xy 94.44264 -217.706009) (xy 94.473072 -217.664122) (xy 94.509682 -217.627512)
			(xy 94.551569 -217.59708) (xy 94.597701 -217.573574) (xy 94.646941 -217.557575) (xy 94.698079 -217.549476)
			(xy 94.749853 -217.549476) (xy 94.800991 -217.557575) (xy 94.850231 -217.573574) (xy 94.896363 -217.59708)
			(xy 94.93825 -217.627512) (xy 94.97486 -217.664122) (xy 95.005292 -217.706009) (xy 95.028798 -217.752141)
			(xy 95.044797 -217.801381) (xy 95.052896 -217.852519) (xy 95.053404 -217.878406) (xy 95.334328 -217.878406)
			(xy 95.334794 -217.853071) (xy 95.342546 -217.802996) (xy 95.357869 -217.754698) (xy 95.380402 -217.709313)
			(xy 95.409614 -217.66791) (xy 95.444817 -217.631464) (xy 95.485182 -217.600835) (xy 95.529759 -217.576742)
			(xy 95.577497 -217.559754) (xy 95.602298 -217.554556) (xy 95.625158 -217.550238) (xy 95.830136 -217.195146)
			(xy 95.822262 -217.173302) (xy 95.813624 -217.146891) (xy 95.804299 -217.092117) (xy 95.80372 -217.064336)
			(xy 95.804228 -217.038429) (xy 95.812334 -216.987252) (xy 95.828346 -216.937973) (xy 95.851869 -216.891806)
			(xy 95.882325 -216.849887) (xy 95.918963 -216.813249) (xy 95.960882 -216.782793) (xy 96.007049 -216.75927)
			(xy 96.056328 -216.743258) (xy 96.107505 -216.735152) (xy 96.159319 -216.735152) (xy 96.210496 -216.743258)
			(xy 96.259775 -216.75927) (xy 96.305942 -216.782793) (xy 96.347861 -216.813249) (xy 96.384499 -216.849887)
			(xy 96.414955 -216.891806) (xy 96.438478 -216.937973) (xy 96.45449 -216.987252) (xy 96.462596 -217.038429)
			(xy 96.463104 -217.064336) (xy 96.462612 -217.08968) (xy 96.454835 -217.13977) (xy 96.439486 -217.188079)
			(xy 96.416925 -217.233471) (xy 96.387684 -217.274876) (xy 96.352452 -217.311319) (xy 96.312059 -217.341943)
			(xy 96.267455 -217.366024) (xy 96.219692 -217.382998) (xy 96.19488 -217.388186) (xy 96.17202 -217.392504)
			(xy 95.967042 -217.747596) (xy 95.974916 -217.76944) (xy 95.983506 -217.795856) (xy 95.992695 -217.850633)
			(xy 95.993204 -217.878406) (xy 96.274128 -217.878406) (xy 96.274636 -217.852519) (xy 96.282735 -217.801381)
			(xy 96.298734 -217.752141) (xy 96.32224 -217.706009) (xy 96.352672 -217.664122) (xy 96.389282 -217.627512)
			(xy 96.431169 -217.59708) (xy 96.477301 -217.573574) (xy 96.526541 -217.557575) (xy 96.577679 -217.549476)
			(xy 96.629453 -217.549476) (xy 96.680591 -217.557575) (xy 96.729831 -217.573574) (xy 96.775963 -217.59708)
			(xy 96.81785 -217.627512) (xy 96.85446 -217.664122) (xy 96.884892 -217.706009) (xy 96.908398 -217.752141)
			(xy 96.924397 -217.801381) (xy 96.932496 -217.852519) (xy 96.933004 -217.878406) (xy 97.213928 -217.878406)
			(xy 97.214394 -217.853071) (xy 97.222146 -217.802996) (xy 97.237469 -217.754698) (xy 97.260002 -217.709313)
			(xy 97.289214 -217.66791) (xy 97.324417 -217.631464) (xy 97.364782 -217.600835) (xy 97.409359 -217.576742)
			(xy 97.457097 -217.559754) (xy 97.481898 -217.554556) (xy 97.504758 -217.550238) (xy 97.709736 -217.195146)
			(xy 97.701862 -217.173302) (xy 97.693224 -217.146891) (xy 97.683899 -217.092117) (xy 97.68332 -217.064336)
			(xy 97.683828 -217.038429) (xy 97.691934 -216.987252) (xy 97.707946 -216.937973) (xy 97.731469 -216.891806)
			(xy 97.761925 -216.849887) (xy 97.798563 -216.813249) (xy 97.840482 -216.782793) (xy 97.886649 -216.75927)
			(xy 97.935928 -216.743258) (xy 97.987105 -216.735152) (xy 98.038919 -216.735152) (xy 98.090096 -216.743258)
			(xy 98.139375 -216.75927) (xy 98.185542 -216.782793) (xy 98.227461 -216.813249) (xy 98.264099 -216.849887)
			(xy 98.294555 -216.891806) (xy 98.318078 -216.937973) (xy 98.33409 -216.987252) (xy 98.342196 -217.038429)
			(xy 98.342704 -217.064336) (xy 98.342212 -217.08968) (xy 98.334435 -217.13977) (xy 98.319086 -217.188079)
			(xy 98.296525 -217.233471) (xy 98.267284 -217.274876) (xy 98.232052 -217.311319) (xy 98.191659 -217.341943)
			(xy 98.147055 -217.366024) (xy 98.099292 -217.382998) (xy 98.07448 -217.388186) (xy 98.05162 -217.392504)
			(xy 97.846642 -217.747596) (xy 97.854516 -217.76944) (xy 97.863106 -217.795856) (xy 97.872295 -217.850633)
			(xy 97.872804 -217.878406) (xy 98.153728 -217.878406) (xy 98.154236 -217.852519) (xy 98.162335 -217.801381)
			(xy 98.178334 -217.752141) (xy 98.20184 -217.706009) (xy 98.232272 -217.664122) (xy 98.268882 -217.627512)
			(xy 98.310769 -217.59708) (xy 98.356901 -217.573574) (xy 98.406141 -217.557575) (xy 98.457279 -217.549476)
			(xy 98.509053 -217.549476) (xy 98.560191 -217.557575) (xy 98.609431 -217.573574) (xy 98.655563 -217.59708)
			(xy 98.69745 -217.627512) (xy 98.73406 -217.664122) (xy 98.764492 -217.706009) (xy 98.787998 -217.752141)
			(xy 98.803997 -217.801381) (xy 98.812096 -217.852519) (xy 98.812604 -217.878406) (xy 99.093528 -217.878406)
			(xy 99.093994 -217.853071) (xy 99.101746 -217.802996) (xy 99.117069 -217.754698) (xy 99.139602 -217.709313)
			(xy 99.168814 -217.66791) (xy 99.204017 -217.631464) (xy 99.244382 -217.600835) (xy 99.288959 -217.576742)
			(xy 99.336697 -217.559754) (xy 99.361498 -217.554556) (xy 99.384358 -217.550238) (xy 99.589336 -217.195146)
			(xy 99.581462 -217.173302) (xy 99.572824 -217.146891) (xy 99.563499 -217.092117) (xy 99.56292 -217.064336)
			(xy 99.563428 -217.038429) (xy 99.571534 -216.987252) (xy 99.587546 -216.937973) (xy 99.611069 -216.891806)
			(xy 99.641525 -216.849887) (xy 99.678163 -216.813249) (xy 99.720082 -216.782793) (xy 99.766249 -216.75927)
			(xy 99.815528 -216.743258) (xy 99.866705 -216.735152) (xy 99.918519 -216.735152) (xy 99.969696 -216.743258)
			(xy 100.018975 -216.75927) (xy 100.065142 -216.782793) (xy 100.107061 -216.813249) (xy 100.143699 -216.849887)
			(xy 100.174155 -216.891806) (xy 100.197678 -216.937973) (xy 100.21369 -216.987252) (xy 100.221796 -217.038429)
			(xy 100.222304 -217.064336) (xy 100.221812 -217.08968) (xy 100.214035 -217.13977) (xy 100.198686 -217.188079)
			(xy 100.176125 -217.233471) (xy 100.146884 -217.274876) (xy 100.111652 -217.311319) (xy 100.071259 -217.341943)
			(xy 100.026655 -217.366024) (xy 99.978892 -217.382998) (xy 99.95408 -217.388186) (xy 99.93122 -217.392504)
			(xy 99.726242 -217.747596) (xy 99.734116 -217.76944) (xy 99.742706 -217.795856) (xy 99.751895 -217.850633)
			(xy 99.752404 -217.878406) (xy 100.033328 -217.878406) (xy 100.033836 -217.852519) (xy 100.041935 -217.801381)
			(xy 100.057934 -217.752141) (xy 100.08144 -217.706009) (xy 100.111872 -217.664122) (xy 100.148482 -217.627512)
			(xy 100.190369 -217.59708) (xy 100.236501 -217.573574) (xy 100.285741 -217.557575) (xy 100.336879 -217.549476)
			(xy 100.388653 -217.549476) (xy 100.439791 -217.557575) (xy 100.489031 -217.573574) (xy 100.535163 -217.59708)
			(xy 100.57705 -217.627512) (xy 100.61366 -217.664122) (xy 100.644092 -217.706009) (xy 100.667598 -217.752141)
			(xy 100.683597 -217.801381) (xy 100.691696 -217.852519) (xy 100.692204 -217.878406) (xy 100.973128 -217.878406)
			(xy 100.973594 -217.853071) (xy 100.981346 -217.802996) (xy 100.996669 -217.754698) (xy 101.019202 -217.709313)
			(xy 101.048414 -217.66791) (xy 101.083617 -217.631464) (xy 101.123982 -217.600835) (xy 101.168559 -217.576742)
			(xy 101.216297 -217.559754) (xy 101.241098 -217.554556) (xy 101.263958 -217.550238) (xy 101.468936 -217.195146)
			(xy 101.461062 -217.173302) (xy 101.452424 -217.146891) (xy 101.443099 -217.092117) (xy 101.44252 -217.064336)
			(xy 101.443028 -217.038429) (xy 101.451134 -216.987252) (xy 101.467146 -216.937973) (xy 101.490669 -216.891806)
			(xy 101.521125 -216.849887) (xy 101.557763 -216.813249) (xy 101.599682 -216.782793) (xy 101.645849 -216.75927)
			(xy 101.695128 -216.743258) (xy 101.746305 -216.735152) (xy 101.798119 -216.735152) (xy 101.849296 -216.743258)
			(xy 101.898575 -216.75927) (xy 101.944742 -216.782793) (xy 101.986661 -216.813249) (xy 102.023299 -216.849887)
			(xy 102.053755 -216.891806) (xy 102.077278 -216.937973) (xy 102.09329 -216.987252) (xy 102.101396 -217.038429)
			(xy 102.101904 -217.064336) (xy 102.101412 -217.08968) (xy 102.093635 -217.13977) (xy 102.078286 -217.188079)
			(xy 102.055725 -217.233471) (xy 102.026484 -217.274876) (xy 101.991252 -217.311319) (xy 101.950859 -217.341943)
			(xy 101.906255 -217.366024) (xy 101.858492 -217.382998) (xy 101.83368 -217.388186) (xy 101.81082 -217.392504)
			(xy 101.605842 -217.747596) (xy 101.613716 -217.76944) (xy 101.622306 -217.795856) (xy 101.631495 -217.850633)
			(xy 101.632004 -217.878406) (xy 101.912928 -217.878406) (xy 101.913436 -217.852519) (xy 101.921535 -217.801381)
			(xy 101.937534 -217.752141) (xy 101.96104 -217.706009) (xy 101.991472 -217.664122) (xy 102.028082 -217.627512)
			(xy 102.069969 -217.59708) (xy 102.116101 -217.573574) (xy 102.165341 -217.557575) (xy 102.216479 -217.549476)
			(xy 102.268253 -217.549476) (xy 102.319391 -217.557575) (xy 102.368631 -217.573574) (xy 102.414763 -217.59708)
			(xy 102.45665 -217.627512) (xy 102.49326 -217.664122) (xy 102.523692 -217.706009) (xy 102.547198 -217.752141)
			(xy 102.563197 -217.801381) (xy 102.571296 -217.852519) (xy 102.571804 -217.878406) (xy 102.852728 -217.878406)
			(xy 102.853194 -217.853071) (xy 102.860946 -217.802996) (xy 102.876269 -217.754698) (xy 102.898802 -217.709313)
			(xy 102.928014 -217.66791) (xy 102.963217 -217.631464) (xy 103.003582 -217.600835) (xy 103.048159 -217.576742)
			(xy 103.095897 -217.559754) (xy 103.120698 -217.554556) (xy 103.143558 -217.550238) (xy 103.348536 -217.195146)
			(xy 103.340662 -217.173302) (xy 103.332024 -217.146891) (xy 103.322699 -217.092117) (xy 103.32212 -217.064336)
			(xy 103.322628 -217.038429) (xy 103.330734 -216.987252) (xy 103.346746 -216.937973) (xy 103.370269 -216.891806)
			(xy 103.400725 -216.849887) (xy 103.437363 -216.813249) (xy 103.479282 -216.782793) (xy 103.525449 -216.75927)
			(xy 103.574728 -216.743258) (xy 103.625905 -216.735152) (xy 103.677719 -216.735152) (xy 103.728896 -216.743258)
			(xy 103.778175 -216.75927) (xy 103.824342 -216.782793) (xy 103.866261 -216.813249) (xy 103.902899 -216.849887)
			(xy 103.933355 -216.891806) (xy 103.956878 -216.937973) (xy 103.97289 -216.987252) (xy 103.980996 -217.038429)
			(xy 103.981504 -217.064336) (xy 103.981012 -217.08968) (xy 103.973235 -217.13977) (xy 103.957886 -217.188079)
			(xy 103.935325 -217.233471) (xy 103.906084 -217.274876) (xy 103.870852 -217.311319) (xy 103.830459 -217.341943)
			(xy 103.785855 -217.366024) (xy 103.738092 -217.382998) (xy 103.71328 -217.388186) (xy 103.69042 -217.392504)
			(xy 103.485442 -217.747596) (xy 103.493316 -217.76944) (xy 103.501906 -217.795856) (xy 103.511095 -217.850633)
			(xy 103.511604 -217.878406) (xy 103.792528 -217.878406) (xy 103.793036 -217.852519) (xy 103.801135 -217.801381)
			(xy 103.817134 -217.752141) (xy 103.84064 -217.706009) (xy 103.871072 -217.664122) (xy 103.907682 -217.627512)
			(xy 103.949569 -217.59708) (xy 103.995701 -217.573574) (xy 104.044941 -217.557575) (xy 104.096079 -217.549476)
			(xy 104.147853 -217.549476) (xy 104.198991 -217.557575) (xy 104.248231 -217.573574) (xy 104.294363 -217.59708)
			(xy 104.33625 -217.627512) (xy 104.37286 -217.664122) (xy 104.403292 -217.706009) (xy 104.426798 -217.752141)
			(xy 104.442797 -217.801381) (xy 104.450896 -217.852519) (xy 104.451404 -217.878406) (xy 104.732328 -217.878406)
			(xy 104.732794 -217.853071) (xy 104.740546 -217.802996) (xy 104.755869 -217.754698) (xy 104.778402 -217.709313)
			(xy 104.807614 -217.66791) (xy 104.842817 -217.631464) (xy 104.883182 -217.600835) (xy 104.927759 -217.576742)
			(xy 104.975497 -217.559754) (xy 105.000298 -217.554556) (xy 105.023158 -217.550238) (xy 105.228136 -217.195146)
			(xy 105.220262 -217.173302) (xy 105.211624 -217.146891) (xy 105.202299 -217.092117) (xy 105.20172 -217.064336)
			(xy 105.202228 -217.038429) (xy 105.210334 -216.987252) (xy 105.226346 -216.937973) (xy 105.249869 -216.891806)
			(xy 105.280325 -216.849887) (xy 105.316963 -216.813249) (xy 105.358882 -216.782793) (xy 105.405049 -216.75927)
			(xy 105.454328 -216.743258) (xy 105.505505 -216.735152) (xy 105.557319 -216.735152) (xy 105.608496 -216.743258)
			(xy 105.657775 -216.75927) (xy 105.703942 -216.782793) (xy 105.745861 -216.813249) (xy 105.782499 -216.849887)
			(xy 105.812955 -216.891806) (xy 105.836478 -216.937973) (xy 105.85249 -216.987252) (xy 105.860596 -217.038429)
			(xy 105.861104 -217.064336) (xy 105.860612 -217.08968) (xy 105.852835 -217.13977) (xy 105.837486 -217.188079)
			(xy 105.814925 -217.233471) (xy 105.785684 -217.274876) (xy 105.750452 -217.311319) (xy 105.710059 -217.341943)
			(xy 105.665455 -217.366024) (xy 105.617692 -217.382998) (xy 105.59288 -217.388186) (xy 105.57002 -217.392504)
			(xy 105.365042 -217.747596) (xy 105.372916 -217.76944) (xy 105.381506 -217.795856) (xy 105.390695 -217.850633)
			(xy 105.391204 -217.878406) (xy 105.672128 -217.878406) (xy 105.672636 -217.852519) (xy 105.680735 -217.801381)
			(xy 105.696734 -217.752141) (xy 105.72024 -217.706009) (xy 105.750672 -217.664122) (xy 105.787282 -217.627512)
			(xy 105.829169 -217.59708) (xy 105.875301 -217.573574) (xy 105.924541 -217.557575) (xy 105.975679 -217.549476)
			(xy 106.027453 -217.549476) (xy 106.078591 -217.557575) (xy 106.127831 -217.573574) (xy 106.173963 -217.59708)
			(xy 106.21585 -217.627512) (xy 106.25246 -217.664122) (xy 106.282892 -217.706009) (xy 106.306398 -217.752141)
			(xy 106.322397 -217.801381) (xy 106.330496 -217.852519) (xy 106.331004 -217.878406) (xy 106.611928 -217.878406)
			(xy 106.612394 -217.853071) (xy 106.620146 -217.802996) (xy 106.635469 -217.754698) (xy 106.658002 -217.709313)
			(xy 106.687214 -217.66791) (xy 106.722417 -217.631464) (xy 106.762782 -217.600835) (xy 106.807359 -217.576742)
			(xy 106.855097 -217.559754) (xy 106.879898 -217.554556) (xy 106.902758 -217.550238) (xy 107.107736 -217.195146)
			(xy 107.099862 -217.173302) (xy 107.091224 -217.146891) (xy 107.081899 -217.092117) (xy 107.08132 -217.064336)
			(xy 107.081828 -217.038429) (xy 107.089934 -216.987252) (xy 107.105946 -216.937973) (xy 107.129469 -216.891806)
			(xy 107.159925 -216.849887) (xy 107.196563 -216.813249) (xy 107.238482 -216.782793) (xy 107.284649 -216.75927)
			(xy 107.333928 -216.743258) (xy 107.385105 -216.735152) (xy 107.436919 -216.735152) (xy 107.488096 -216.743258)
			(xy 107.537375 -216.75927) (xy 107.583542 -216.782793) (xy 107.625461 -216.813249) (xy 107.662099 -216.849887)
			(xy 107.692555 -216.891806) (xy 107.716078 -216.937973) (xy 107.73209 -216.987252) (xy 107.740196 -217.038429)
			(xy 107.740704 -217.064336) (xy 107.740212 -217.08968) (xy 107.732435 -217.13977) (xy 107.717086 -217.188079)
			(xy 107.694525 -217.233471) (xy 107.665284 -217.274876) (xy 107.630052 -217.311319) (xy 107.589659 -217.341943)
			(xy 107.545055 -217.366024) (xy 107.497292 -217.382998) (xy 107.47248 -217.388186) (xy 107.44962 -217.392504)
			(xy 107.244642 -217.747596) (xy 107.252516 -217.76944) (xy 107.261106 -217.795856) (xy 107.270295 -217.850633)
			(xy 107.270804 -217.878406) (xy 107.551728 -217.878406) (xy 107.552236 -217.852519) (xy 107.560335 -217.801381)
			(xy 107.576334 -217.752141) (xy 107.59984 -217.706009) (xy 107.630272 -217.664122) (xy 107.666882 -217.627512)
			(xy 107.708769 -217.59708) (xy 107.754901 -217.573574) (xy 107.804141 -217.557575) (xy 107.855279 -217.549476)
			(xy 107.907053 -217.549476) (xy 107.958191 -217.557575) (xy 108.007431 -217.573574) (xy 108.053563 -217.59708)
			(xy 108.09545 -217.627512) (xy 108.13206 -217.664122) (xy 108.162492 -217.706009) (xy 108.185998 -217.752141)
			(xy 108.201997 -217.801381) (xy 108.210096 -217.852519) (xy 108.210604 -217.878406) (xy 108.491528 -217.878406)
			(xy 108.491994 -217.853071) (xy 108.499746 -217.802996) (xy 108.515069 -217.754698) (xy 108.537602 -217.709313)
			(xy 108.566814 -217.66791) (xy 108.602017 -217.631464) (xy 108.642382 -217.600835) (xy 108.686959 -217.576742)
			(xy 108.734697 -217.559754) (xy 108.759498 -217.554556) (xy 108.782358 -217.550238) (xy 108.987336 -217.195146)
			(xy 108.979462 -217.173302) (xy 108.970824 -217.146891) (xy 108.961499 -217.092117) (xy 108.96092 -217.064336)
			(xy 108.961428 -217.038429) (xy 108.969534 -216.987252) (xy 108.985546 -216.937973) (xy 109.009069 -216.891806)
			(xy 109.039525 -216.849887) (xy 109.076163 -216.813249) (xy 109.118082 -216.782793) (xy 109.164249 -216.75927)
			(xy 109.213528 -216.743258) (xy 109.264705 -216.735152) (xy 109.316519 -216.735152) (xy 109.367696 -216.743258)
			(xy 109.416975 -216.75927) (xy 109.463142 -216.782793) (xy 109.505061 -216.813249) (xy 109.541699 -216.849887)
			(xy 109.572155 -216.891806) (xy 109.595678 -216.937973) (xy 109.61169 -216.987252) (xy 109.619796 -217.038429)
			(xy 109.620304 -217.064336) (xy 109.619812 -217.08968) (xy 109.612035 -217.13977) (xy 109.596686 -217.188079)
			(xy 109.574125 -217.233471) (xy 109.544884 -217.274876) (xy 109.509652 -217.311319) (xy 109.469259 -217.341943)
			(xy 109.424655 -217.366024) (xy 109.376892 -217.382998) (xy 109.35208 -217.388186) (xy 109.32922 -217.392504)
			(xy 109.124242 -217.747596) (xy 109.132116 -217.76944) (xy 109.140706 -217.795856) (xy 109.149895 -217.850633)
			(xy 109.150404 -217.878406) (xy 109.431328 -217.878406) (xy 109.431836 -217.852519) (xy 109.439935 -217.801381)
			(xy 109.455934 -217.752141) (xy 109.47944 -217.706009) (xy 109.509872 -217.664122) (xy 109.546482 -217.627512)
			(xy 109.588369 -217.59708) (xy 109.634501 -217.573574) (xy 109.683741 -217.557575) (xy 109.734879 -217.549476)
			(xy 109.786653 -217.549476) (xy 109.837791 -217.557575) (xy 109.887031 -217.573574) (xy 109.933163 -217.59708)
			(xy 109.97505 -217.627512) (xy 110.01166 -217.664122) (xy 110.042092 -217.706009) (xy 110.065598 -217.752141)
			(xy 110.081597 -217.801381) (xy 110.089696 -217.852519) (xy 110.090204 -217.878406) (xy 110.371128 -217.878406)
			(xy 110.371594 -217.853071) (xy 110.379346 -217.802996) (xy 110.394669 -217.754698) (xy 110.417202 -217.709313)
			(xy 110.446414 -217.66791) (xy 110.481617 -217.631464) (xy 110.521982 -217.600835) (xy 110.566559 -217.576742)
			(xy 110.614297 -217.559754) (xy 110.639098 -217.554556) (xy 110.661958 -217.550238) (xy 110.866936 -217.194892)
			(xy 110.859316 -217.173048) (xy 110.850741 -217.146694) (xy 110.841552 -217.092045) (xy 110.841028 -217.064336)
			(xy 110.841536 -217.038449) (xy 110.849635 -216.987311) (xy 110.865634 -216.938071) (xy 110.88914 -216.891939)
			(xy 110.919572 -216.850052) (xy 110.956182 -216.813442) (xy 110.998069 -216.78301) (xy 111.044201 -216.759504)
			(xy 111.093441 -216.743505) (xy 111.144579 -216.735406) (xy 111.196353 -216.735406) (xy 111.247491 -216.743505)
			(xy 111.296731 -216.759504) (xy 111.342863 -216.78301) (xy 111.38475 -216.813442) (xy 111.42136 -216.850052)
			(xy 111.451792 -216.891939) (xy 111.475298 -216.938071) (xy 111.491297 -216.987311) (xy 111.499396 -217.038449)
			(xy 111.499904 -217.064336) (xy 112.72012 -217.064336) (xy 112.720628 -217.038429) (xy 112.728734 -216.987252)
			(xy 112.744746 -216.937973) (xy 112.768269 -216.891806) (xy 112.798725 -216.849887) (xy 112.835363 -216.813249)
			(xy 112.877282 -216.782793) (xy 112.923449 -216.75927) (xy 112.972728 -216.743258) (xy 113.023905 -216.735152)
			(xy 113.075719 -216.735152) (xy 113.126896 -216.743258) (xy 113.176175 -216.75927) (xy 113.222342 -216.782793)
			(xy 113.264261 -216.813249) (xy 113.300899 -216.849887) (xy 113.331355 -216.891806) (xy 113.354878 -216.937973)
			(xy 113.37089 -216.987252) (xy 113.378996 -217.038429) (xy 113.379504 -217.064336) (xy 114.59972 -217.064336)
			(xy 114.600228 -217.038429) (xy 114.608334 -216.987252) (xy 114.624346 -216.937973) (xy 114.647869 -216.891806)
			(xy 114.678325 -216.849887) (xy 114.714963 -216.813249) (xy 114.756882 -216.782793) (xy 114.803049 -216.75927)
			(xy 114.852328 -216.743258) (xy 114.903505 -216.735152) (xy 114.955319 -216.735152) (xy 115.006496 -216.743258)
			(xy 115.055775 -216.75927) (xy 115.101942 -216.782793) (xy 115.143861 -216.813249) (xy 115.180499 -216.849887)
			(xy 115.210955 -216.891806) (xy 115.234478 -216.937973) (xy 115.25049 -216.987252) (xy 115.258596 -217.038429)
			(xy 115.259104 -217.064336) (xy 116.47932 -217.064336) (xy 116.479828 -217.038429) (xy 116.487934 -216.987252)
			(xy 116.503946 -216.937973) (xy 116.527469 -216.891806) (xy 116.557925 -216.849887) (xy 116.594563 -216.813249)
			(xy 116.636482 -216.782793) (xy 116.682649 -216.75927) (xy 116.731928 -216.743258) (xy 116.783105 -216.735152)
			(xy 116.834919 -216.735152) (xy 116.886096 -216.743258) (xy 116.935375 -216.75927) (xy 116.981542 -216.782793)
			(xy 117.023461 -216.813249) (xy 117.060099 -216.849887) (xy 117.090555 -216.891806) (xy 117.114078 -216.937973)
			(xy 117.13009 -216.987252) (xy 117.138196 -217.038429) (xy 117.138704 -217.064336) (xy 118.35892 -217.064336)
			(xy 118.359428 -217.038429) (xy 118.367534 -216.987252) (xy 118.383546 -216.937973) (xy 118.407069 -216.891806)
			(xy 118.437525 -216.849887) (xy 118.474163 -216.813249) (xy 118.516082 -216.782793) (xy 118.562249 -216.75927)
			(xy 118.611528 -216.743258) (xy 118.662705 -216.735152) (xy 118.714519 -216.735152) (xy 118.765696 -216.743258)
			(xy 118.814975 -216.75927) (xy 118.861142 -216.782793) (xy 118.903061 -216.813249) (xy 118.939699 -216.849887)
			(xy 118.970155 -216.891806) (xy 118.993678 -216.937973) (xy 119.00969 -216.987252) (xy 119.017796 -217.038429)
			(xy 119.018304 -217.064336) (xy 120.23852 -217.064336) (xy 120.239028 -217.038429) (xy 120.247134 -216.987252)
			(xy 120.263146 -216.937973) (xy 120.286669 -216.891806) (xy 120.317125 -216.849887) (xy 120.353763 -216.813249)
			(xy 120.395682 -216.782793) (xy 120.441849 -216.75927) (xy 120.491128 -216.743258) (xy 120.542305 -216.735152)
			(xy 120.594119 -216.735152) (xy 120.645296 -216.743258) (xy 120.694575 -216.75927) (xy 120.740742 -216.782793)
			(xy 120.782661 -216.813249) (xy 120.819299 -216.849887) (xy 120.849755 -216.891806) (xy 120.873278 -216.937973)
			(xy 120.88929 -216.987252) (xy 120.897396 -217.038429) (xy 120.897904 -217.064336) (xy 122.11812 -217.064336)
			(xy 122.118628 -217.038429) (xy 122.126734 -216.987252) (xy 122.142746 -216.937973) (xy 122.166269 -216.891806)
			(xy 122.196725 -216.849887) (xy 122.233363 -216.813249) (xy 122.275282 -216.782793) (xy 122.321449 -216.75927)
			(xy 122.370728 -216.743258) (xy 122.421905 -216.735152) (xy 122.473719 -216.735152) (xy 122.524896 -216.743258)
			(xy 122.574175 -216.75927) (xy 122.620342 -216.782793) (xy 122.662261 -216.813249) (xy 122.698899 -216.849887)
			(xy 122.729355 -216.891806) (xy 122.752878 -216.937973) (xy 122.76889 -216.987252) (xy 122.776996 -217.038429)
			(xy 122.777504 -217.064336) (xy 123.99772 -217.064336) (xy 123.998228 -217.038429) (xy 124.006334 -216.987252)
			(xy 124.022346 -216.937973) (xy 124.045869 -216.891806) (xy 124.076325 -216.849887) (xy 124.112963 -216.813249)
			(xy 124.154882 -216.782793) (xy 124.201049 -216.75927) (xy 124.250328 -216.743258) (xy 124.301505 -216.735152)
			(xy 124.353319 -216.735152) (xy 124.404496 -216.743258) (xy 124.453775 -216.75927) (xy 124.499942 -216.782793)
			(xy 124.541861 -216.813249) (xy 124.578499 -216.849887) (xy 124.608955 -216.891806) (xy 124.632478 -216.937973)
			(xy 124.64849 -216.987252) (xy 124.656596 -217.038429) (xy 124.657104 -217.064336) (xy 125.87732 -217.064336)
			(xy 125.877828 -217.038429) (xy 125.885934 -216.987252) (xy 125.901946 -216.937973) (xy 125.925469 -216.891806)
			(xy 125.955925 -216.849887) (xy 125.992563 -216.813249) (xy 126.034482 -216.782793) (xy 126.080649 -216.75927)
			(xy 126.129928 -216.743258) (xy 126.181105 -216.735152) (xy 126.232919 -216.735152) (xy 126.284096 -216.743258)
			(xy 126.333375 -216.75927) (xy 126.379542 -216.782793) (xy 126.421461 -216.813249) (xy 126.458099 -216.849887)
			(xy 126.488555 -216.891806) (xy 126.512078 -216.937973) (xy 126.52809 -216.987252) (xy 126.536196 -217.038429)
			(xy 126.536704 -217.064336) (xy 127.75692 -217.064336) (xy 127.757428 -217.038429) (xy 127.765534 -216.987252)
			(xy 127.781546 -216.937973) (xy 127.805069 -216.891806) (xy 127.835525 -216.849887) (xy 127.872163 -216.813249)
			(xy 127.914082 -216.782793) (xy 127.960249 -216.75927) (xy 128.009528 -216.743258) (xy 128.060705 -216.735152)
			(xy 128.112519 -216.735152) (xy 128.163696 -216.743258) (xy 128.212975 -216.75927) (xy 128.259142 -216.782793)
			(xy 128.301061 -216.813249) (xy 128.337699 -216.849887) (xy 128.368155 -216.891806) (xy 128.391678 -216.937973)
			(xy 128.40769 -216.987252) (xy 128.415796 -217.038429) (xy 128.416304 -217.064336) (xy 129.63652 -217.064336)
			(xy 129.637028 -217.038429) (xy 129.645134 -216.987252) (xy 129.661146 -216.937973) (xy 129.684669 -216.891806)
			(xy 129.715125 -216.849887) (xy 129.751763 -216.813249) (xy 129.793682 -216.782793) (xy 129.839849 -216.75927)
			(xy 129.889128 -216.743258) (xy 129.940305 -216.735152) (xy 129.992119 -216.735152) (xy 130.043296 -216.743258)
			(xy 130.092575 -216.75927) (xy 130.138742 -216.782793) (xy 130.180661 -216.813249) (xy 130.217299 -216.849887)
			(xy 130.247755 -216.891806) (xy 130.271278 -216.937973) (xy 130.28729 -216.987252) (xy 130.295396 -217.038429)
			(xy 130.295904 -217.064336) (xy 131.51612 -217.064336) (xy 131.516628 -217.038429) (xy 131.524734 -216.987252)
			(xy 131.540746 -216.937973) (xy 131.564269 -216.891806) (xy 131.594725 -216.849887) (xy 131.631363 -216.813249)
			(xy 131.673282 -216.782793) (xy 131.719449 -216.75927) (xy 131.768728 -216.743258) (xy 131.819905 -216.735152)
			(xy 131.871719 -216.735152) (xy 131.922896 -216.743258) (xy 131.972175 -216.75927) (xy 132.018342 -216.782793)
			(xy 132.060261 -216.813249) (xy 132.096899 -216.849887) (xy 132.127355 -216.891806) (xy 132.150878 -216.937973)
			(xy 132.16689 -216.987252) (xy 132.174996 -217.038429) (xy 132.175504 -217.064336) (xy 133.39572 -217.064336)
			(xy 133.396228 -217.038429) (xy 133.404334 -216.987252) (xy 133.420346 -216.937973) (xy 133.443869 -216.891806)
			(xy 133.474325 -216.849887) (xy 133.510963 -216.813249) (xy 133.552882 -216.782793) (xy 133.599049 -216.75927)
			(xy 133.648328 -216.743258) (xy 133.699505 -216.735152) (xy 133.751319 -216.735152) (xy 133.802496 -216.743258)
			(xy 133.851775 -216.75927) (xy 133.897942 -216.782793) (xy 133.939861 -216.813249) (xy 133.976499 -216.849887)
			(xy 134.006955 -216.891806) (xy 134.030478 -216.937973) (xy 134.04649 -216.987252) (xy 134.054596 -217.038429)
			(xy 134.055104 -217.064336) (xy 134.054489 -217.091989) (xy 134.045169 -217.146507) (xy 134.036562 -217.172794)
			(xy 134.028942 -217.194892) (xy 134.234174 -217.550238) (xy 134.257034 -217.554556) (xy 134.281841 -217.559728)
			(xy 134.329579 -217.576721) (xy 134.374156 -217.600818) (xy 134.41452 -217.631451) (xy 134.449723 -217.6679)
			(xy 134.478934 -217.709305) (xy 134.501466 -217.754693) (xy 134.516789 -217.802993) (xy 134.524541 -217.85307)
			(xy 134.525004 -217.878406) (xy 336.695796 -217.878406) (xy 336.696304 -217.852519) (xy 336.704403 -217.801381)
			(xy 336.720402 -217.752141) (xy 336.743908 -217.706009) (xy 336.77434 -217.664122) (xy 336.81095 -217.627512)
			(xy 336.852837 -217.59708) (xy 336.898969 -217.573574) (xy 336.948209 -217.557575) (xy 336.999347 -217.549476)
			(xy 337.051121 -217.549476) (xy 337.102259 -217.557575) (xy 337.151499 -217.573574) (xy 337.197631 -217.59708)
			(xy 337.239518 -217.627512) (xy 337.276128 -217.664122) (xy 337.30656 -217.706009) (xy 337.330066 -217.752141)
			(xy 337.346065 -217.801381) (xy 337.354164 -217.852519) (xy 337.354672 -217.878406) (xy 337.635596 -217.878406)
			(xy 337.636088 -217.853072) (xy 337.643839 -217.803) (xy 337.65916 -217.754704) (xy 337.681691 -217.70932)
			(xy 337.710899 -217.667918) (xy 337.746099 -217.631473) (xy 337.78646 -217.600842) (xy 337.831033 -217.576747)
			(xy 337.878767 -217.559756) (xy 337.903566 -217.554556) (xy 337.926426 -217.550238) (xy 338.131404 -217.195146)
			(xy 338.12353 -217.173302) (xy 338.114891 -217.146892) (xy 338.105567 -217.092117) (xy 338.104988 -217.064336)
			(xy 338.105496 -217.038429) (xy 338.113602 -216.987252) (xy 338.129614 -216.937973) (xy 338.153137 -216.891806)
			(xy 338.183593 -216.849887) (xy 338.220231 -216.813249) (xy 338.26215 -216.782793) (xy 338.308317 -216.75927)
			(xy 338.357596 -216.743258) (xy 338.408773 -216.735152) (xy 338.460587 -216.735152) (xy 338.511764 -216.743258)
			(xy 338.561043 -216.75927) (xy 338.60721 -216.782793) (xy 338.649129 -216.813249) (xy 338.685767 -216.849887)
			(xy 338.716223 -216.891806) (xy 338.739746 -216.937973) (xy 338.755758 -216.987252) (xy 338.763864 -217.038429)
			(xy 338.764372 -217.064336) (xy 338.763906 -217.089682) (xy 338.756128 -217.139773) (xy 338.740777 -217.188085)
			(xy 338.718213 -217.233478) (xy 338.688969 -217.274884) (xy 338.653734 -217.311328) (xy 338.613336 -217.34195)
			(xy 338.568729 -217.36603) (xy 338.520962 -217.383) (xy 338.496148 -217.388186) (xy 338.473288 -217.392504)
			(xy 338.26831 -217.747596) (xy 338.276184 -217.76944) (xy 338.284773 -217.795856) (xy 338.293963 -217.850633)
			(xy 338.294472 -217.878406) (xy 338.575396 -217.878406) (xy 338.575904 -217.852519) (xy 338.584003 -217.801381)
			(xy 338.600002 -217.752141) (xy 338.623508 -217.706009) (xy 338.65394 -217.664122) (xy 338.69055 -217.627512)
			(xy 338.732437 -217.59708) (xy 338.778569 -217.573574) (xy 338.827809 -217.557575) (xy 338.878947 -217.549476)
			(xy 338.930721 -217.549476) (xy 338.981859 -217.557575) (xy 339.031099 -217.573574) (xy 339.077231 -217.59708)
			(xy 339.119118 -217.627512) (xy 339.155728 -217.664122) (xy 339.18616 -217.706009) (xy 339.209666 -217.752141)
			(xy 339.225665 -217.801381) (xy 339.233764 -217.852519) (xy 339.234272 -217.878406) (xy 339.515196 -217.878406)
			(xy 339.515688 -217.853072) (xy 339.523439 -217.803) (xy 339.53876 -217.754704) (xy 339.561291 -217.70932)
			(xy 339.590499 -217.667918) (xy 339.625699 -217.631473) (xy 339.66606 -217.600842) (xy 339.710633 -217.576747)
			(xy 339.758367 -217.559756) (xy 339.783166 -217.554556) (xy 339.806026 -217.550238) (xy 340.011004 -217.195146)
			(xy 340.00313 -217.173302) (xy 339.994491 -217.146892) (xy 339.985167 -217.092117) (xy 339.984588 -217.064336)
			(xy 339.985096 -217.038429) (xy 339.993202 -216.987252) (xy 340.009214 -216.937973) (xy 340.032737 -216.891806)
			(xy 340.063193 -216.849887) (xy 340.099831 -216.813249) (xy 340.14175 -216.782793) (xy 340.187917 -216.75927)
			(xy 340.237196 -216.743258) (xy 340.288373 -216.735152) (xy 340.340187 -216.735152) (xy 340.391364 -216.743258)
			(xy 340.440643 -216.75927) (xy 340.48681 -216.782793) (xy 340.528729 -216.813249) (xy 340.565367 -216.849887)
			(xy 340.595823 -216.891806) (xy 340.619346 -216.937973) (xy 340.635358 -216.987252) (xy 340.643464 -217.038429)
			(xy 340.643972 -217.064336) (xy 340.643506 -217.089682) (xy 340.635728 -217.139773) (xy 340.620377 -217.188085)
			(xy 340.597813 -217.233478) (xy 340.568569 -217.274884) (xy 340.533334 -217.311328) (xy 340.492936 -217.34195)
			(xy 340.448329 -217.36603) (xy 340.400562 -217.383) (xy 340.375748 -217.388186) (xy 340.352888 -217.392504)
			(xy 340.14791 -217.747596) (xy 340.155784 -217.76944) (xy 340.164373 -217.795856) (xy 340.173563 -217.850633)
			(xy 340.174072 -217.878406) (xy 340.454996 -217.878406) (xy 340.455504 -217.852519) (xy 340.463603 -217.801381)
			(xy 340.479602 -217.752141) (xy 340.503108 -217.706009) (xy 340.53354 -217.664122) (xy 340.57015 -217.627512)
			(xy 340.612037 -217.59708) (xy 340.658169 -217.573574) (xy 340.707409 -217.557575) (xy 340.758547 -217.549476)
			(xy 340.810321 -217.549476) (xy 340.861459 -217.557575) (xy 340.910699 -217.573574) (xy 340.956831 -217.59708)
			(xy 340.998718 -217.627512) (xy 341.035328 -217.664122) (xy 341.06576 -217.706009) (xy 341.089266 -217.752141)
			(xy 341.105265 -217.801381) (xy 341.113364 -217.852519) (xy 341.113872 -217.878406) (xy 341.394796 -217.878406)
			(xy 341.395288 -217.853072) (xy 341.403039 -217.803) (xy 341.41836 -217.754704) (xy 341.440891 -217.70932)
			(xy 341.470099 -217.667918) (xy 341.505299 -217.631473) (xy 341.54566 -217.600842) (xy 341.590233 -217.576747)
			(xy 341.637967 -217.559756) (xy 341.662766 -217.554556) (xy 341.685626 -217.550238) (xy 341.890604 -217.195146)
			(xy 341.88273 -217.173302) (xy 341.874091 -217.146892) (xy 341.864767 -217.092117) (xy 341.864188 -217.064336)
			(xy 341.864696 -217.038429) (xy 341.872802 -216.987252) (xy 341.888814 -216.937973) (xy 341.912337 -216.891806)
			(xy 341.942793 -216.849887) (xy 341.979431 -216.813249) (xy 342.02135 -216.782793) (xy 342.067517 -216.75927)
			(xy 342.116796 -216.743258) (xy 342.167973 -216.735152) (xy 342.219787 -216.735152) (xy 342.270964 -216.743258)
			(xy 342.320243 -216.75927) (xy 342.36641 -216.782793) (xy 342.408329 -216.813249) (xy 342.444967 -216.849887)
			(xy 342.475423 -216.891806) (xy 342.498946 -216.937973) (xy 342.514958 -216.987252) (xy 342.523064 -217.038429)
			(xy 342.523572 -217.064336) (xy 342.523106 -217.089682) (xy 342.515328 -217.139773) (xy 342.499977 -217.188085)
			(xy 342.477413 -217.233478) (xy 342.448169 -217.274884) (xy 342.412934 -217.311328) (xy 342.372536 -217.34195)
			(xy 342.327929 -217.36603) (xy 342.280162 -217.383) (xy 342.255348 -217.388186) (xy 342.232488 -217.392504)
			(xy 342.02751 -217.747596) (xy 342.035384 -217.76944) (xy 342.043973 -217.795856) (xy 342.053163 -217.850633)
			(xy 342.053672 -217.878406) (xy 342.334596 -217.878406) (xy 342.335104 -217.852519) (xy 342.343203 -217.801381)
			(xy 342.359202 -217.752141) (xy 342.382708 -217.706009) (xy 342.41314 -217.664122) (xy 342.44975 -217.627512)
			(xy 342.491637 -217.59708) (xy 342.537769 -217.573574) (xy 342.587009 -217.557575) (xy 342.638147 -217.549476)
			(xy 342.689921 -217.549476) (xy 342.741059 -217.557575) (xy 342.790299 -217.573574) (xy 342.836431 -217.59708)
			(xy 342.878318 -217.627512) (xy 342.914928 -217.664122) (xy 342.94536 -217.706009) (xy 342.968866 -217.752141)
			(xy 342.984865 -217.801381) (xy 342.992964 -217.852519) (xy 342.993472 -217.878406) (xy 343.274396 -217.878406)
			(xy 343.274888 -217.853072) (xy 343.282639 -217.803) (xy 343.29796 -217.754704) (xy 343.320491 -217.70932)
			(xy 343.349699 -217.667918) (xy 343.384899 -217.631473) (xy 343.42526 -217.600842) (xy 343.469833 -217.576747)
			(xy 343.517567 -217.559756) (xy 343.542366 -217.554556) (xy 343.565226 -217.550238) (xy 343.770204 -217.195146)
			(xy 343.76233 -217.173302) (xy 343.753691 -217.146892) (xy 343.744367 -217.092117) (xy 343.743788 -217.064336)
			(xy 343.744296 -217.038429) (xy 343.752402 -216.987252) (xy 343.768414 -216.937973) (xy 343.791937 -216.891806)
			(xy 343.822393 -216.849887) (xy 343.859031 -216.813249) (xy 343.90095 -216.782793) (xy 343.947117 -216.75927)
			(xy 343.996396 -216.743258) (xy 344.047573 -216.735152) (xy 344.099387 -216.735152) (xy 344.150564 -216.743258)
			(xy 344.199843 -216.75927) (xy 344.24601 -216.782793) (xy 344.287929 -216.813249) (xy 344.324567 -216.849887)
			(xy 344.355023 -216.891806) (xy 344.378546 -216.937973) (xy 344.394558 -216.987252) (xy 344.402664 -217.038429)
			(xy 344.403172 -217.064336) (xy 344.402706 -217.089682) (xy 344.394928 -217.139773) (xy 344.379577 -217.188085)
			(xy 344.357013 -217.233478) (xy 344.327769 -217.274884) (xy 344.292534 -217.311328) (xy 344.252136 -217.34195)
			(xy 344.207529 -217.36603) (xy 344.159762 -217.383) (xy 344.134948 -217.388186) (xy 344.112088 -217.392504)
			(xy 343.90711 -217.747596) (xy 343.914984 -217.76944) (xy 343.923573 -217.795856) (xy 343.932763 -217.850633)
			(xy 343.933272 -217.878406) (xy 344.214196 -217.878406) (xy 344.214704 -217.852519) (xy 344.222803 -217.801381)
			(xy 344.238802 -217.752141) (xy 344.262308 -217.706009) (xy 344.29274 -217.664122) (xy 344.32935 -217.627512)
			(xy 344.371237 -217.59708) (xy 344.417369 -217.573574) (xy 344.466609 -217.557575) (xy 344.517747 -217.549476)
			(xy 344.569521 -217.549476) (xy 344.620659 -217.557575) (xy 344.669899 -217.573574) (xy 344.716031 -217.59708)
			(xy 344.757918 -217.627512) (xy 344.794528 -217.664122) (xy 344.82496 -217.706009) (xy 344.848466 -217.752141)
			(xy 344.864465 -217.801381) (xy 344.872564 -217.852519) (xy 344.873072 -217.878406) (xy 345.153996 -217.878406)
			(xy 345.154488 -217.853072) (xy 345.162239 -217.803) (xy 345.17756 -217.754704) (xy 345.200091 -217.70932)
			(xy 345.229299 -217.667918) (xy 345.264499 -217.631473) (xy 345.30486 -217.600842) (xy 345.349433 -217.576747)
			(xy 345.397167 -217.559756) (xy 345.421966 -217.554556) (xy 345.444826 -217.550238) (xy 345.649804 -217.195146)
			(xy 345.64193 -217.173302) (xy 345.633291 -217.146892) (xy 345.623967 -217.092117) (xy 345.623388 -217.064336)
			(xy 345.623896 -217.038429) (xy 345.632002 -216.987252) (xy 345.648014 -216.937973) (xy 345.671537 -216.891806)
			(xy 345.701993 -216.849887) (xy 345.738631 -216.813249) (xy 345.78055 -216.782793) (xy 345.826717 -216.75927)
			(xy 345.875996 -216.743258) (xy 345.927173 -216.735152) (xy 345.978987 -216.735152) (xy 346.030164 -216.743258)
			(xy 346.079443 -216.75927) (xy 346.12561 -216.782793) (xy 346.167529 -216.813249) (xy 346.204167 -216.849887)
			(xy 346.234623 -216.891806) (xy 346.258146 -216.937973) (xy 346.274158 -216.987252) (xy 346.282264 -217.038429)
			(xy 346.282772 -217.064336) (xy 346.282306 -217.089682) (xy 346.274528 -217.139773) (xy 346.259177 -217.188085)
			(xy 346.236613 -217.233478) (xy 346.207369 -217.274884) (xy 346.172134 -217.311328) (xy 346.131736 -217.34195)
			(xy 346.087129 -217.36603) (xy 346.039362 -217.383) (xy 346.014548 -217.388186) (xy 345.991688 -217.392504)
			(xy 345.78671 -217.747596) (xy 345.794584 -217.76944) (xy 345.803173 -217.795856) (xy 345.812363 -217.850633)
			(xy 345.812872 -217.878406) (xy 346.093796 -217.878406) (xy 346.094304 -217.852519) (xy 346.102403 -217.801381)
			(xy 346.118402 -217.752141) (xy 346.141908 -217.706009) (xy 346.17234 -217.664122) (xy 346.20895 -217.627512)
			(xy 346.250837 -217.59708) (xy 346.296969 -217.573574) (xy 346.346209 -217.557575) (xy 346.397347 -217.549476)
			(xy 346.449121 -217.549476) (xy 346.500259 -217.557575) (xy 346.549499 -217.573574) (xy 346.595631 -217.59708)
			(xy 346.637518 -217.627512) (xy 346.674128 -217.664122) (xy 346.70456 -217.706009) (xy 346.728066 -217.752141)
			(xy 346.744065 -217.801381) (xy 346.752164 -217.852519) (xy 346.752672 -217.878406) (xy 347.033596 -217.878406)
			(xy 347.034088 -217.853072) (xy 347.041839 -217.803) (xy 347.05716 -217.754704) (xy 347.079691 -217.70932)
			(xy 347.108899 -217.667918) (xy 347.144099 -217.631473) (xy 347.18446 -217.600842) (xy 347.229033 -217.576747)
			(xy 347.276767 -217.559756) (xy 347.301566 -217.554556) (xy 347.324426 -217.550238) (xy 347.529404 -217.195146)
			(xy 347.52153 -217.173302) (xy 347.512891 -217.146892) (xy 347.503567 -217.092117) (xy 347.502988 -217.064336)
			(xy 347.503496 -217.038429) (xy 347.511602 -216.987252) (xy 347.527614 -216.937973) (xy 347.551137 -216.891806)
			(xy 347.581593 -216.849887) (xy 347.618231 -216.813249) (xy 347.66015 -216.782793) (xy 347.706317 -216.75927)
			(xy 347.755596 -216.743258) (xy 347.806773 -216.735152) (xy 347.858587 -216.735152) (xy 347.909764 -216.743258)
			(xy 347.959043 -216.75927) (xy 348.00521 -216.782793) (xy 348.047129 -216.813249) (xy 348.083767 -216.849887)
			(xy 348.114223 -216.891806) (xy 348.137746 -216.937973) (xy 348.153758 -216.987252) (xy 348.161864 -217.038429)
			(xy 348.162372 -217.064336) (xy 348.161906 -217.089682) (xy 348.154128 -217.139773) (xy 348.138777 -217.188085)
			(xy 348.116213 -217.233478) (xy 348.086969 -217.274884) (xy 348.051734 -217.311328) (xy 348.011336 -217.34195)
			(xy 347.966729 -217.36603) (xy 347.918962 -217.383) (xy 347.894148 -217.388186) (xy 347.871288 -217.392504)
			(xy 347.66631 -217.747596) (xy 347.674184 -217.76944) (xy 347.682773 -217.795856) (xy 347.691963 -217.850633)
			(xy 347.692472 -217.878406) (xy 347.973396 -217.878406) (xy 347.973904 -217.852519) (xy 347.982003 -217.801381)
			(xy 347.998002 -217.752141) (xy 348.021508 -217.706009) (xy 348.05194 -217.664122) (xy 348.08855 -217.627512)
			(xy 348.130437 -217.59708) (xy 348.176569 -217.573574) (xy 348.225809 -217.557575) (xy 348.276947 -217.549476)
			(xy 348.328721 -217.549476) (xy 348.379859 -217.557575) (xy 348.429099 -217.573574) (xy 348.475231 -217.59708)
			(xy 348.517118 -217.627512) (xy 348.553728 -217.664122) (xy 348.58416 -217.706009) (xy 348.607666 -217.752141)
			(xy 348.623665 -217.801381) (xy 348.631764 -217.852519) (xy 348.632272 -217.878406) (xy 348.913196 -217.878406)
			(xy 348.913688 -217.853072) (xy 348.921439 -217.803) (xy 348.93676 -217.754704) (xy 348.959291 -217.70932)
			(xy 348.988499 -217.667918) (xy 349.023699 -217.631473) (xy 349.06406 -217.600842) (xy 349.108633 -217.576747)
			(xy 349.156367 -217.559756) (xy 349.181166 -217.554556) (xy 349.204026 -217.550238) (xy 349.409004 -217.195146)
			(xy 349.40113 -217.173302) (xy 349.392491 -217.146892) (xy 349.383167 -217.092117) (xy 349.382588 -217.064336)
			(xy 349.383096 -217.038429) (xy 349.391202 -216.987252) (xy 349.407214 -216.937973) (xy 349.430737 -216.891806)
			(xy 349.461193 -216.849887) (xy 349.497831 -216.813249) (xy 349.53975 -216.782793) (xy 349.585917 -216.75927)
			(xy 349.635196 -216.743258) (xy 349.686373 -216.735152) (xy 349.738187 -216.735152) (xy 349.789364 -216.743258)
			(xy 349.838643 -216.75927) (xy 349.88481 -216.782793) (xy 349.926729 -216.813249) (xy 349.963367 -216.849887)
			(xy 349.993823 -216.891806) (xy 350.017346 -216.937973) (xy 350.033358 -216.987252) (xy 350.041464 -217.038429)
			(xy 350.041972 -217.064336) (xy 350.041506 -217.089682) (xy 350.033728 -217.139773) (xy 350.018377 -217.188085)
			(xy 349.995813 -217.233478) (xy 349.966569 -217.274884) (xy 349.931334 -217.311328) (xy 349.890936 -217.34195)
			(xy 349.846329 -217.36603) (xy 349.798562 -217.383) (xy 349.773748 -217.388186) (xy 349.750888 -217.392504)
			(xy 349.54591 -217.747596) (xy 349.553784 -217.76944) (xy 349.562373 -217.795856) (xy 349.571563 -217.850633)
			(xy 349.572072 -217.878406) (xy 349.852996 -217.878406) (xy 349.853504 -217.852519) (xy 349.861603 -217.801381)
			(xy 349.877602 -217.752141) (xy 349.901108 -217.706009) (xy 349.93154 -217.664122) (xy 349.96815 -217.627512)
			(xy 350.010037 -217.59708) (xy 350.056169 -217.573574) (xy 350.105409 -217.557575) (xy 350.156547 -217.549476)
			(xy 350.208321 -217.549476) (xy 350.259459 -217.557575) (xy 350.308699 -217.573574) (xy 350.354831 -217.59708)
			(xy 350.396718 -217.627512) (xy 350.433328 -217.664122) (xy 350.46376 -217.706009) (xy 350.487266 -217.752141)
			(xy 350.503265 -217.801381) (xy 350.511364 -217.852519) (xy 350.511872 -217.878406) (xy 350.792796 -217.878406)
			(xy 350.793288 -217.853072) (xy 350.801039 -217.803) (xy 350.81636 -217.754704) (xy 350.838891 -217.70932)
			(xy 350.868099 -217.667918) (xy 350.903299 -217.631473) (xy 350.94366 -217.600842) (xy 350.988233 -217.576747)
			(xy 351.035967 -217.559756) (xy 351.060766 -217.554556) (xy 351.083626 -217.550238) (xy 351.288604 -217.195146)
			(xy 351.28073 -217.173302) (xy 351.272091 -217.146892) (xy 351.262767 -217.092117) (xy 351.262188 -217.064336)
			(xy 351.262696 -217.038429) (xy 351.270802 -216.987252) (xy 351.286814 -216.937973) (xy 351.310337 -216.891806)
			(xy 351.340793 -216.849887) (xy 351.377431 -216.813249) (xy 351.41935 -216.782793) (xy 351.465517 -216.75927)
			(xy 351.514796 -216.743258) (xy 351.565973 -216.735152) (xy 351.617787 -216.735152) (xy 351.668964 -216.743258)
			(xy 351.718243 -216.75927) (xy 351.76441 -216.782793) (xy 351.806329 -216.813249) (xy 351.842967 -216.849887)
			(xy 351.873423 -216.891806) (xy 351.896946 -216.937973) (xy 351.912958 -216.987252) (xy 351.921064 -217.038429)
			(xy 351.921572 -217.064336) (xy 351.921106 -217.089682) (xy 351.913328 -217.139773) (xy 351.897977 -217.188085)
			(xy 351.875413 -217.233478) (xy 351.846169 -217.274884) (xy 351.810934 -217.311328) (xy 351.770536 -217.34195)
			(xy 351.725929 -217.36603) (xy 351.678162 -217.383) (xy 351.653348 -217.388186) (xy 351.630488 -217.392504)
			(xy 351.42551 -217.747596) (xy 351.433384 -217.76944) (xy 351.441973 -217.795856) (xy 351.451163 -217.850633)
			(xy 351.451672 -217.878406) (xy 351.732596 -217.878406) (xy 351.733104 -217.852519) (xy 351.741203 -217.801381)
			(xy 351.757202 -217.752141) (xy 351.780708 -217.706009) (xy 351.81114 -217.664122) (xy 351.84775 -217.627512)
			(xy 351.889637 -217.59708) (xy 351.935769 -217.573574) (xy 351.985009 -217.557575) (xy 352.036147 -217.549476)
			(xy 352.087921 -217.549476) (xy 352.139059 -217.557575) (xy 352.188299 -217.573574) (xy 352.234431 -217.59708)
			(xy 352.276318 -217.627512) (xy 352.312928 -217.664122) (xy 352.34336 -217.706009) (xy 352.366866 -217.752141)
			(xy 352.382865 -217.801381) (xy 352.390964 -217.852519) (xy 352.391472 -217.878406) (xy 352.672396 -217.878406)
			(xy 352.672888 -217.853072) (xy 352.680639 -217.803) (xy 352.69596 -217.754704) (xy 352.718491 -217.70932)
			(xy 352.747699 -217.667918) (xy 352.782899 -217.631473) (xy 352.82326 -217.600842) (xy 352.867833 -217.576747)
			(xy 352.915567 -217.559756) (xy 352.940366 -217.554556) (xy 352.963226 -217.550238) (xy 353.168204 -217.195146)
			(xy 353.16033 -217.173302) (xy 353.151691 -217.146892) (xy 353.142367 -217.092117) (xy 353.141788 -217.064336)
			(xy 353.142296 -217.038429) (xy 353.150402 -216.987252) (xy 353.166414 -216.937973) (xy 353.189937 -216.891806)
			(xy 353.220393 -216.849887) (xy 353.257031 -216.813249) (xy 353.29895 -216.782793) (xy 353.345117 -216.75927)
			(xy 353.394396 -216.743258) (xy 353.445573 -216.735152) (xy 353.497387 -216.735152) (xy 353.548564 -216.743258)
			(xy 353.597843 -216.75927) (xy 353.64401 -216.782793) (xy 353.685929 -216.813249) (xy 353.722567 -216.849887)
			(xy 353.753023 -216.891806) (xy 353.776546 -216.937973) (xy 353.792558 -216.987252) (xy 353.800664 -217.038429)
			(xy 353.801172 -217.064336) (xy 353.800706 -217.089682) (xy 353.792928 -217.139773) (xy 353.777577 -217.188085)
			(xy 353.755013 -217.233478) (xy 353.725769 -217.274884) (xy 353.690534 -217.311328) (xy 353.650136 -217.34195)
			(xy 353.605529 -217.36603) (xy 353.557762 -217.383) (xy 353.532948 -217.388186) (xy 353.510088 -217.392504)
			(xy 353.30511 -217.747596) (xy 353.312984 -217.76944) (xy 353.321573 -217.795856) (xy 353.330763 -217.850633)
			(xy 353.331272 -217.878406) (xy 353.612196 -217.878406) (xy 353.612704 -217.852519) (xy 353.620803 -217.801381)
			(xy 353.636802 -217.752141) (xy 353.660308 -217.706009) (xy 353.69074 -217.664122) (xy 353.72735 -217.627512)
			(xy 353.769237 -217.59708) (xy 353.815369 -217.573574) (xy 353.864609 -217.557575) (xy 353.915747 -217.549476)
			(xy 353.967521 -217.549476) (xy 354.018659 -217.557575) (xy 354.067899 -217.573574) (xy 354.114031 -217.59708)
			(xy 354.155918 -217.627512) (xy 354.192528 -217.664122) (xy 354.22296 -217.706009) (xy 354.246466 -217.752141)
			(xy 354.262465 -217.801381) (xy 354.270564 -217.852519) (xy 354.271072 -217.878406) (xy 354.551996 -217.878406)
			(xy 354.552488 -217.853072) (xy 354.560239 -217.803) (xy 354.57556 -217.754704) (xy 354.598091 -217.70932)
			(xy 354.627299 -217.667918) (xy 354.662499 -217.631473) (xy 354.70286 -217.600842) (xy 354.747433 -217.576747)
			(xy 354.795167 -217.559756) (xy 354.819966 -217.554556) (xy 354.842826 -217.550238) (xy 355.047804 -217.195146)
			(xy 355.03993 -217.173302) (xy 355.031291 -217.146892) (xy 355.021967 -217.092117) (xy 355.021388 -217.064336)
			(xy 355.021896 -217.038429) (xy 355.030002 -216.987252) (xy 355.046014 -216.937973) (xy 355.069537 -216.891806)
			(xy 355.099993 -216.849887) (xy 355.136631 -216.813249) (xy 355.17855 -216.782793) (xy 355.224717 -216.75927)
			(xy 355.273996 -216.743258) (xy 355.325173 -216.735152) (xy 355.376987 -216.735152) (xy 355.428164 -216.743258)
			(xy 355.477443 -216.75927) (xy 355.52361 -216.782793) (xy 355.565529 -216.813249) (xy 355.602167 -216.849887)
			(xy 355.632623 -216.891806) (xy 355.656146 -216.937973) (xy 355.672158 -216.987252) (xy 355.680264 -217.038429)
			(xy 355.680772 -217.064336) (xy 355.680306 -217.089682) (xy 355.672528 -217.139773) (xy 355.657177 -217.188085)
			(xy 355.634613 -217.233478) (xy 355.605369 -217.274884) (xy 355.570134 -217.311328) (xy 355.529736 -217.34195)
			(xy 355.485129 -217.36603) (xy 355.437362 -217.383) (xy 355.412548 -217.388186) (xy 355.389688 -217.392504)
			(xy 355.18471 -217.747596) (xy 355.192584 -217.76944) (xy 355.201173 -217.795856) (xy 355.210363 -217.850633)
			(xy 355.210872 -217.878406) (xy 355.491796 -217.878406) (xy 355.492304 -217.852519) (xy 355.500403 -217.801381)
			(xy 355.516402 -217.752141) (xy 355.539908 -217.706009) (xy 355.57034 -217.664122) (xy 355.60695 -217.627512)
			(xy 355.648837 -217.59708) (xy 355.694969 -217.573574) (xy 355.744209 -217.557575) (xy 355.795347 -217.549476)
			(xy 355.847121 -217.549476) (xy 355.898259 -217.557575) (xy 355.947499 -217.573574) (xy 355.993631 -217.59708)
			(xy 356.035518 -217.627512) (xy 356.072128 -217.664122) (xy 356.10256 -217.706009) (xy 356.126066 -217.752141)
			(xy 356.142065 -217.801381) (xy 356.150164 -217.852519) (xy 356.150672 -217.878406) (xy 356.431596 -217.878406)
			(xy 356.432088 -217.853072) (xy 356.439839 -217.803) (xy 356.45516 -217.754704) (xy 356.477691 -217.70932)
			(xy 356.506899 -217.667918) (xy 356.542099 -217.631473) (xy 356.58246 -217.600842) (xy 356.627033 -217.576747)
			(xy 356.674767 -217.559756) (xy 356.699566 -217.554556) (xy 356.722426 -217.550238) (xy 356.927404 -217.195146)
			(xy 356.91953 -217.173302) (xy 356.910891 -217.146892) (xy 356.901567 -217.092117) (xy 356.900988 -217.064336)
			(xy 356.901496 -217.038429) (xy 356.909602 -216.987252) (xy 356.925614 -216.937973) (xy 356.949137 -216.891806)
			(xy 356.979593 -216.849887) (xy 357.016231 -216.813249) (xy 357.05815 -216.782793) (xy 357.104317 -216.75927)
			(xy 357.153596 -216.743258) (xy 357.204773 -216.735152) (xy 357.256587 -216.735152) (xy 357.307764 -216.743258)
			(xy 357.357043 -216.75927) (xy 357.40321 -216.782793) (xy 357.445129 -216.813249) (xy 357.481767 -216.849887)
			(xy 357.512223 -216.891806) (xy 357.535746 -216.937973) (xy 357.551758 -216.987252) (xy 357.559864 -217.038429)
			(xy 357.560372 -217.064336) (xy 357.559906 -217.089682) (xy 357.552128 -217.139773) (xy 357.536777 -217.188085)
			(xy 357.514213 -217.233478) (xy 357.484969 -217.274884) (xy 357.449734 -217.311328) (xy 357.409336 -217.34195)
			(xy 357.364729 -217.36603) (xy 357.316962 -217.383) (xy 357.292148 -217.388186) (xy 357.269288 -217.392504)
			(xy 357.06431 -217.747596) (xy 357.072184 -217.76944) (xy 357.080773 -217.795856) (xy 357.089963 -217.850633)
			(xy 357.090472 -217.878406) (xy 357.371396 -217.878406) (xy 357.371904 -217.852519) (xy 357.380003 -217.801381)
			(xy 357.396002 -217.752141) (xy 357.419508 -217.706009) (xy 357.44994 -217.664122) (xy 357.48655 -217.627512)
			(xy 357.528437 -217.59708) (xy 357.574569 -217.573574) (xy 357.623809 -217.557575) (xy 357.674947 -217.549476)
			(xy 357.726721 -217.549476) (xy 357.777859 -217.557575) (xy 357.827099 -217.573574) (xy 357.873231 -217.59708)
			(xy 357.915118 -217.627512) (xy 357.951728 -217.664122) (xy 357.98216 -217.706009) (xy 358.005666 -217.752141)
			(xy 358.021665 -217.801381) (xy 358.029764 -217.852519) (xy 358.030272 -217.878406) (xy 358.311196 -217.878406)
			(xy 358.311688 -217.853072) (xy 358.319439 -217.803) (xy 358.33476 -217.754704) (xy 358.357291 -217.70932)
			(xy 358.386499 -217.667918) (xy 358.421699 -217.631473) (xy 358.46206 -217.600842) (xy 358.506633 -217.576747)
			(xy 358.554367 -217.559756) (xy 358.579166 -217.554556) (xy 358.602026 -217.550238) (xy 358.807004 -217.194892)
			(xy 358.799384 -217.173048) (xy 358.790811 -217.146694) (xy 358.78162 -217.092045) (xy 358.781096 -217.064336)
			(xy 358.781604 -217.038449) (xy 358.789703 -216.987311) (xy 358.805702 -216.938071) (xy 358.829208 -216.891939)
			(xy 358.85964 -216.850052) (xy 358.89625 -216.813442) (xy 358.938137 -216.78301) (xy 358.984269 -216.759504)
			(xy 359.033509 -216.743505) (xy 359.084647 -216.735406) (xy 359.136421 -216.735406) (xy 359.187559 -216.743505)
			(xy 359.236799 -216.759504) (xy 359.282931 -216.78301) (xy 359.324818 -216.813442) (xy 359.361428 -216.850052)
			(xy 359.39186 -216.891939) (xy 359.415366 -216.938071) (xy 359.431365 -216.987311) (xy 359.439464 -217.038449)
			(xy 359.439972 -217.064336) (xy 360.660188 -217.064336) (xy 360.660696 -217.038429) (xy 360.668802 -216.987252)
			(xy 360.684814 -216.937973) (xy 360.708337 -216.891806) (xy 360.738793 -216.849887) (xy 360.775431 -216.813249)
			(xy 360.81735 -216.782793) (xy 360.863517 -216.75927) (xy 360.912796 -216.743258) (xy 360.963973 -216.735152)
			(xy 361.015787 -216.735152) (xy 361.066964 -216.743258) (xy 361.116243 -216.75927) (xy 361.16241 -216.782793)
			(xy 361.204329 -216.813249) (xy 361.240967 -216.849887) (xy 361.271423 -216.891806) (xy 361.294946 -216.937973)
			(xy 361.310958 -216.987252) (xy 361.319064 -217.038429) (xy 361.319572 -217.064336) (xy 362.539788 -217.064336)
			(xy 362.540296 -217.038429) (xy 362.548402 -216.987252) (xy 362.564414 -216.937973) (xy 362.587937 -216.891806)
			(xy 362.618393 -216.849887) (xy 362.655031 -216.813249) (xy 362.69695 -216.782793) (xy 362.743117 -216.75927)
			(xy 362.792396 -216.743258) (xy 362.843573 -216.735152) (xy 362.895387 -216.735152) (xy 362.946564 -216.743258)
			(xy 362.995843 -216.75927) (xy 363.04201 -216.782793) (xy 363.083929 -216.813249) (xy 363.120567 -216.849887)
			(xy 363.151023 -216.891806) (xy 363.174546 -216.937973) (xy 363.190558 -216.987252) (xy 363.198664 -217.038429)
			(xy 363.199172 -217.064336) (xy 364.419388 -217.064336) (xy 364.419896 -217.038429) (xy 364.428002 -216.987252)
			(xy 364.444014 -216.937973) (xy 364.467537 -216.891806) (xy 364.497993 -216.849887) (xy 364.534631 -216.813249)
			(xy 364.57655 -216.782793) (xy 364.622717 -216.75927) (xy 364.671996 -216.743258) (xy 364.723173 -216.735152)
			(xy 364.774987 -216.735152) (xy 364.826164 -216.743258) (xy 364.875443 -216.75927) (xy 364.92161 -216.782793)
			(xy 364.963529 -216.813249) (xy 365.000167 -216.849887) (xy 365.030623 -216.891806) (xy 365.054146 -216.937973)
			(xy 365.070158 -216.987252) (xy 365.078264 -217.038429) (xy 365.078772 -217.064336) (xy 366.298988 -217.064336)
			(xy 366.299496 -217.038429) (xy 366.307602 -216.987252) (xy 366.323614 -216.937973) (xy 366.347137 -216.891806)
			(xy 366.377593 -216.849887) (xy 366.414231 -216.813249) (xy 366.45615 -216.782793) (xy 366.502317 -216.75927)
			(xy 366.551596 -216.743258) (xy 366.602773 -216.735152) (xy 366.654587 -216.735152) (xy 366.705764 -216.743258)
			(xy 366.755043 -216.75927) (xy 366.80121 -216.782793) (xy 366.843129 -216.813249) (xy 366.879767 -216.849887)
			(xy 366.910223 -216.891806) (xy 366.933746 -216.937973) (xy 366.949758 -216.987252) (xy 366.957864 -217.038429)
			(xy 366.958372 -217.064336) (xy 368.178588 -217.064336) (xy 368.179096 -217.038429) (xy 368.187202 -216.987252)
			(xy 368.203214 -216.937973) (xy 368.226737 -216.891806) (xy 368.257193 -216.849887) (xy 368.293831 -216.813249)
			(xy 368.33575 -216.782793) (xy 368.381917 -216.75927) (xy 368.431196 -216.743258) (xy 368.482373 -216.735152)
			(xy 368.534187 -216.735152) (xy 368.585364 -216.743258) (xy 368.634643 -216.75927) (xy 368.68081 -216.782793)
			(xy 368.722729 -216.813249) (xy 368.759367 -216.849887) (xy 368.789823 -216.891806) (xy 368.813346 -216.937973)
			(xy 368.829358 -216.987252) (xy 368.837464 -217.038429) (xy 368.837972 -217.064336) (xy 370.058188 -217.064336)
			(xy 370.058696 -217.038429) (xy 370.066802 -216.987252) (xy 370.082814 -216.937973) (xy 370.106337 -216.891806)
			(xy 370.136793 -216.849887) (xy 370.173431 -216.813249) (xy 370.21535 -216.782793) (xy 370.261517 -216.75927)
			(xy 370.310796 -216.743258) (xy 370.361973 -216.735152) (xy 370.413787 -216.735152) (xy 370.464964 -216.743258)
			(xy 370.514243 -216.75927) (xy 370.56041 -216.782793) (xy 370.602329 -216.813249) (xy 370.638967 -216.849887)
			(xy 370.669423 -216.891806) (xy 370.692946 -216.937973) (xy 370.708958 -216.987252) (xy 370.717064 -217.038429)
			(xy 370.717572 -217.064336) (xy 371.937788 -217.064336) (xy 371.938296 -217.038429) (xy 371.946402 -216.987252)
			(xy 371.962414 -216.937973) (xy 371.985937 -216.891806) (xy 372.016393 -216.849887) (xy 372.053031 -216.813249)
			(xy 372.09495 -216.782793) (xy 372.141117 -216.75927) (xy 372.190396 -216.743258) (xy 372.241573 -216.735152)
			(xy 372.293387 -216.735152) (xy 372.344564 -216.743258) (xy 372.393843 -216.75927) (xy 372.44001 -216.782793)
			(xy 372.481929 -216.813249) (xy 372.518567 -216.849887) (xy 372.549023 -216.891806) (xy 372.572546 -216.937973)
			(xy 372.588558 -216.987252) (xy 372.596664 -217.038429) (xy 372.597172 -217.064336) (xy 373.817388 -217.064336)
			(xy 373.817896 -217.038429) (xy 373.826002 -216.987252) (xy 373.842014 -216.937973) (xy 373.865537 -216.891806)
			(xy 373.895993 -216.849887) (xy 373.932631 -216.813249) (xy 373.97455 -216.782793) (xy 374.020717 -216.75927)
			(xy 374.069996 -216.743258) (xy 374.121173 -216.735152) (xy 374.172987 -216.735152) (xy 374.224164 -216.743258)
			(xy 374.273443 -216.75927) (xy 374.31961 -216.782793) (xy 374.361529 -216.813249) (xy 374.398167 -216.849887)
			(xy 374.428623 -216.891806) (xy 374.452146 -216.937973) (xy 374.468158 -216.987252) (xy 374.476264 -217.038429)
			(xy 374.476772 -217.064336) (xy 375.696988 -217.064336) (xy 375.697496 -217.038429) (xy 375.705602 -216.987252)
			(xy 375.721614 -216.937973) (xy 375.745137 -216.891806) (xy 375.775593 -216.849887) (xy 375.812231 -216.813249)
			(xy 375.85415 -216.782793) (xy 375.900317 -216.75927) (xy 375.949596 -216.743258) (xy 376.000773 -216.735152)
			(xy 376.052587 -216.735152) (xy 376.103764 -216.743258) (xy 376.153043 -216.75927) (xy 376.19921 -216.782793)
			(xy 376.241129 -216.813249) (xy 376.277767 -216.849887) (xy 376.308223 -216.891806) (xy 376.331746 -216.937973)
			(xy 376.347758 -216.987252) (xy 376.355864 -217.038429) (xy 376.356372 -217.064336) (xy 377.576588 -217.064336)
			(xy 377.577096 -217.038429) (xy 377.585202 -216.987252) (xy 377.601214 -216.937973) (xy 377.624737 -216.891806)
			(xy 377.655193 -216.849887) (xy 377.691831 -216.813249) (xy 377.73375 -216.782793) (xy 377.779917 -216.75927)
			(xy 377.829196 -216.743258) (xy 377.880373 -216.735152) (xy 377.932187 -216.735152) (xy 377.983364 -216.743258)
			(xy 378.032643 -216.75927) (xy 378.07881 -216.782793) (xy 378.120729 -216.813249) (xy 378.157367 -216.849887)
			(xy 378.187823 -216.891806) (xy 378.211346 -216.937973) (xy 378.227358 -216.987252) (xy 378.235464 -217.038429)
			(xy 378.235972 -217.064336) (xy 379.456188 -217.064336) (xy 379.456696 -217.038429) (xy 379.464802 -216.987252)
			(xy 379.480814 -216.937973) (xy 379.504337 -216.891806) (xy 379.534793 -216.849887) (xy 379.571431 -216.813249)
			(xy 379.61335 -216.782793) (xy 379.659517 -216.75927) (xy 379.708796 -216.743258) (xy 379.759973 -216.735152)
			(xy 379.811787 -216.735152) (xy 379.862964 -216.743258) (xy 379.912243 -216.75927) (xy 379.95841 -216.782793)
			(xy 380.000329 -216.813249) (xy 380.036967 -216.849887) (xy 380.067423 -216.891806) (xy 380.090946 -216.937973)
			(xy 380.106958 -216.987252) (xy 380.115064 -217.038429) (xy 380.115572 -217.064336) (xy 381.335788 -217.064336)
			(xy 381.336296 -217.038429) (xy 381.344402 -216.987252) (xy 381.360414 -216.937973) (xy 381.383937 -216.891806)
			(xy 381.414393 -216.849887) (xy 381.451031 -216.813249) (xy 381.49295 -216.782793) (xy 381.539117 -216.75927)
			(xy 381.588396 -216.743258) (xy 381.639573 -216.735152) (xy 381.691387 -216.735152) (xy 381.742564 -216.743258)
			(xy 381.791843 -216.75927) (xy 381.83801 -216.782793) (xy 381.879929 -216.813249) (xy 381.916567 -216.849887)
			(xy 381.947023 -216.891806) (xy 381.970546 -216.937973) (xy 381.986558 -216.987252) (xy 381.994664 -217.038429)
			(xy 381.995172 -217.064336) (xy 381.994559 -217.091989) (xy 381.985238 -217.146507) (xy 381.97663 -217.172794)
			(xy 381.96901 -217.194892) (xy 382.174242 -217.550238) (xy 382.197102 -217.554556) (xy 382.221903 -217.559751)
			(xy 382.269642 -217.57674) (xy 382.314219 -217.600833) (xy 382.354584 -217.631463) (xy 382.389788 -217.667908)
			(xy 382.419 -217.709312) (xy 382.441533 -217.754697) (xy 382.456856 -217.802996) (xy 382.464608 -217.85307)
			(xy 382.465072 -217.878406) (xy 382.464564 -217.904293) (xy 382.456465 -217.955431) (xy 382.440466 -218.004671)
			(xy 382.41696 -218.050803) (xy 382.386528 -218.09269) (xy 382.349918 -218.1293) (xy 382.308031 -218.159732)
			(xy 382.261899 -218.183238) (xy 382.212659 -218.199237) (xy 382.161521 -218.207336) (xy 382.109747 -218.207336)
			(xy 382.058609 -218.199237) (xy 382.009369 -218.183238) (xy 381.963237 -218.159732) (xy 381.92135 -218.1293)
			(xy 381.88474 -218.09269) (xy 381.854308 -218.050803) (xy 381.830802 -218.004671) (xy 381.814803 -217.955431)
			(xy 381.806704 -217.904293) (xy 381.806196 -217.878406) (xy 381.806727 -217.850698) (xy 381.815921 -217.796051)
			(xy 381.824484 -217.769694) (xy 381.832358 -217.747596) (xy 381.62738 -217.392504) (xy 381.60452 -217.388186)
			(xy 381.579675 -217.38302) (xy 381.531826 -217.366126) (xy 381.487133 -217.342096) (xy 381.446653 -217.311499)
			(xy 381.411341 -217.275058) (xy 381.382033 -217.233634) (xy 381.359422 -217.188207) (xy 381.344043 -217.13985)
			(xy 381.336258 -217.089708) (xy 381.335788 -217.064336) (xy 380.115572 -217.064336) (xy 380.114959 -217.091989)
			(xy 380.105638 -217.146507) (xy 380.09703 -217.172794) (xy 380.08941 -217.194892) (xy 380.294642 -217.550238)
			(xy 380.317502 -217.554556) (xy 380.342303 -217.559751) (xy 380.390042 -217.57674) (xy 380.434619 -217.600833)
			(xy 380.474984 -217.631463) (xy 380.510188 -217.667908) (xy 380.5394 -217.709312) (xy 380.561933 -217.754697)
			(xy 380.577256 -217.802996) (xy 380.585008 -217.85307) (xy 380.585472 -217.878406) (xy 380.584964 -217.904293)
			(xy 380.576865 -217.955431) (xy 380.560866 -218.004671) (xy 380.53736 -218.050803) (xy 380.506928 -218.09269)
			(xy 380.470318 -218.1293) (xy 380.428431 -218.159732) (xy 380.382299 -218.183238) (xy 380.333059 -218.199237)
			(xy 380.281921 -218.207336) (xy 380.230147 -218.207336) (xy 380.179009 -218.199237) (xy 380.129769 -218.183238)
			(xy 380.083637 -218.159732) (xy 380.04175 -218.1293) (xy 380.00514 -218.09269) (xy 379.974708 -218.050803)
			(xy 379.951202 -218.004671) (xy 379.935203 -217.955431) (xy 379.927104 -217.904293) (xy 379.926596 -217.878406)
			(xy 379.927127 -217.850698) (xy 379.936321 -217.796051) (xy 379.944884 -217.769694) (xy 379.952758 -217.747596)
			(xy 379.74778 -217.392504) (xy 379.72492 -217.388186) (xy 379.700075 -217.38302) (xy 379.652226 -217.366126)
			(xy 379.607533 -217.342096) (xy 379.567053 -217.311499) (xy 379.531741 -217.275058) (xy 379.502433 -217.233634)
			(xy 379.479822 -217.188207) (xy 379.464443 -217.13985) (xy 379.456658 -217.089708) (xy 379.456188 -217.064336)
			(xy 378.235972 -217.064336) (xy 378.235359 -217.091989) (xy 378.226038 -217.146507) (xy 378.21743 -217.172794)
			(xy 378.20981 -217.194892) (xy 378.415042 -217.550238) (xy 378.437902 -217.554556) (xy 378.462703 -217.559751)
			(xy 378.510442 -217.57674) (xy 378.555019 -217.600833) (xy 378.595384 -217.631463) (xy 378.630588 -217.667908)
			(xy 378.6598 -217.709312) (xy 378.682333 -217.754697) (xy 378.697656 -217.802996) (xy 378.705408 -217.85307)
			(xy 378.705872 -217.878406) (xy 378.705364 -217.904293) (xy 378.697265 -217.955431) (xy 378.681266 -218.004671)
			(xy 378.65776 -218.050803) (xy 378.627328 -218.09269) (xy 378.590718 -218.1293) (xy 378.548831 -218.159732)
			(xy 378.502699 -218.183238) (xy 378.453459 -218.199237) (xy 378.402321 -218.207336) (xy 378.350547 -218.207336)
			(xy 378.299409 -218.199237) (xy 378.250169 -218.183238) (xy 378.204037 -218.159732) (xy 378.16215 -218.1293)
			(xy 378.12554 -218.09269) (xy 378.095108 -218.050803) (xy 378.071602 -218.004671) (xy 378.055603 -217.955431)
			(xy 378.047504 -217.904293) (xy 378.046996 -217.878406) (xy 378.047527 -217.850698) (xy 378.056721 -217.796051)
			(xy 378.065284 -217.769694) (xy 378.073158 -217.747596) (xy 377.86818 -217.392504) (xy 377.84532 -217.388186)
			(xy 377.820475 -217.38302) (xy 377.772626 -217.366126) (xy 377.727933 -217.342096) (xy 377.687453 -217.311499)
			(xy 377.652141 -217.275058) (xy 377.622833 -217.233634) (xy 377.600222 -217.188207) (xy 377.584843 -217.13985)
			(xy 377.577058 -217.089708) (xy 377.576588 -217.064336) (xy 376.356372 -217.064336) (xy 376.355759 -217.091989)
			(xy 376.346438 -217.146507) (xy 376.33783 -217.172794) (xy 376.33021 -217.194892) (xy 376.535442 -217.550238)
			(xy 376.558302 -217.554556) (xy 376.583103 -217.559751) (xy 376.630842 -217.57674) (xy 376.675419 -217.600833)
			(xy 376.715784 -217.631463) (xy 376.750988 -217.667908) (xy 376.7802 -217.709312) (xy 376.802733 -217.754697)
			(xy 376.818056 -217.802996) (xy 376.825808 -217.85307) (xy 376.826272 -217.878406) (xy 376.825764 -217.904293)
			(xy 376.817665 -217.955431) (xy 376.801666 -218.004671) (xy 376.77816 -218.050803) (xy 376.747728 -218.09269)
			(xy 376.711118 -218.1293) (xy 376.669231 -218.159732) (xy 376.623099 -218.183238) (xy 376.573859 -218.199237)
			(xy 376.522721 -218.207336) (xy 376.470947 -218.207336) (xy 376.419809 -218.199237) (xy 376.370569 -218.183238)
			(xy 376.324437 -218.159732) (xy 376.28255 -218.1293) (xy 376.24594 -218.09269) (xy 376.215508 -218.050803)
			(xy 376.192002 -218.004671) (xy 376.176003 -217.955431) (xy 376.167904 -217.904293) (xy 376.167396 -217.878406)
			(xy 376.167927 -217.850698) (xy 376.177121 -217.796051) (xy 376.185684 -217.769694) (xy 376.193558 -217.747596)
			(xy 375.98858 -217.392504) (xy 375.96572 -217.388186) (xy 375.940875 -217.38302) (xy 375.893026 -217.366126)
			(xy 375.848333 -217.342096) (xy 375.807853 -217.311499) (xy 375.772541 -217.275058) (xy 375.743233 -217.233634)
			(xy 375.720622 -217.188207) (xy 375.705243 -217.13985) (xy 375.697458 -217.089708) (xy 375.696988 -217.064336)
			(xy 374.476772 -217.064336) (xy 374.476159 -217.091989) (xy 374.466838 -217.146507) (xy 374.45823 -217.172794)
			(xy 374.45061 -217.194892) (xy 374.655842 -217.550238) (xy 374.678702 -217.554556) (xy 374.703503 -217.559751)
			(xy 374.751242 -217.57674) (xy 374.795819 -217.600833) (xy 374.836184 -217.631463) (xy 374.871388 -217.667908)
			(xy 374.9006 -217.709312) (xy 374.923133 -217.754697) (xy 374.938456 -217.802996) (xy 374.946208 -217.85307)
			(xy 374.946672 -217.878406) (xy 374.946164 -217.904293) (xy 374.938065 -217.955431) (xy 374.922066 -218.004671)
			(xy 374.89856 -218.050803) (xy 374.868128 -218.09269) (xy 374.831518 -218.1293) (xy 374.789631 -218.159732)
			(xy 374.743499 -218.183238) (xy 374.694259 -218.199237) (xy 374.643121 -218.207336) (xy 374.591347 -218.207336)
			(xy 374.540209 -218.199237) (xy 374.490969 -218.183238) (xy 374.444837 -218.159732) (xy 374.40295 -218.1293)
			(xy 374.36634 -218.09269) (xy 374.335908 -218.050803) (xy 374.312402 -218.004671) (xy 374.296403 -217.955431)
			(xy 374.288304 -217.904293) (xy 374.287796 -217.878406) (xy 374.288327 -217.850698) (xy 374.297521 -217.796051)
			(xy 374.306084 -217.769694) (xy 374.313958 -217.747596) (xy 374.10898 -217.392504) (xy 374.08612 -217.388186)
			(xy 374.061275 -217.38302) (xy 374.013426 -217.366126) (xy 373.968733 -217.342096) (xy 373.928253 -217.311499)
			(xy 373.892941 -217.275058) (xy 373.863633 -217.233634) (xy 373.841022 -217.188207) (xy 373.825643 -217.13985)
			(xy 373.817858 -217.089708) (xy 373.817388 -217.064336) (xy 372.597172 -217.064336) (xy 372.596559 -217.091989)
			(xy 372.587238 -217.146507) (xy 372.57863 -217.172794) (xy 372.57101 -217.194892) (xy 372.776242 -217.550238)
			(xy 372.799102 -217.554556) (xy 372.823903 -217.559751) (xy 372.871642 -217.57674) (xy 372.916219 -217.600833)
			(xy 372.956584 -217.631463) (xy 372.991788 -217.667908) (xy 373.021 -217.709312) (xy 373.043533 -217.754697)
			(xy 373.058856 -217.802996) (xy 373.066608 -217.85307) (xy 373.067072 -217.878406) (xy 373.066564 -217.904293)
			(xy 373.058465 -217.955431) (xy 373.042466 -218.004671) (xy 373.01896 -218.050803) (xy 372.988528 -218.09269)
			(xy 372.951918 -218.1293) (xy 372.910031 -218.159732) (xy 372.863899 -218.183238) (xy 372.814659 -218.199237)
			(xy 372.763521 -218.207336) (xy 372.711747 -218.207336) (xy 372.660609 -218.199237) (xy 372.611369 -218.183238)
			(xy 372.565237 -218.159732) (xy 372.52335 -218.1293) (xy 372.48674 -218.09269) (xy 372.456308 -218.050803)
			(xy 372.432802 -218.004671) (xy 372.416803 -217.955431) (xy 372.408704 -217.904293) (xy 372.408196 -217.878406)
			(xy 372.408727 -217.850698) (xy 372.417921 -217.796051) (xy 372.426484 -217.769694) (xy 372.434358 -217.747596)
			(xy 372.22938 -217.392504) (xy 372.20652 -217.388186) (xy 372.181675 -217.38302) (xy 372.133826 -217.366126)
			(xy 372.089133 -217.342096) (xy 372.048653 -217.311499) (xy 372.013341 -217.275058) (xy 371.984033 -217.233634)
			(xy 371.961422 -217.188207) (xy 371.946043 -217.13985) (xy 371.938258 -217.089708) (xy 371.937788 -217.064336)
			(xy 370.717572 -217.064336) (xy 370.716959 -217.091989) (xy 370.707638 -217.146507) (xy 370.69903 -217.172794)
			(xy 370.69141 -217.194892) (xy 370.896642 -217.550238) (xy 370.919502 -217.554556) (xy 370.944303 -217.559751)
			(xy 370.992042 -217.57674) (xy 371.036619 -217.600833) (xy 371.076984 -217.631463) (xy 371.112188 -217.667908)
			(xy 371.1414 -217.709312) (xy 371.163933 -217.754697) (xy 371.179256 -217.802996) (xy 371.187008 -217.85307)
			(xy 371.187472 -217.878406) (xy 371.186964 -217.904293) (xy 371.178865 -217.955431) (xy 371.162866 -218.004671)
			(xy 371.13936 -218.050803) (xy 371.108928 -218.09269) (xy 371.072318 -218.1293) (xy 371.030431 -218.159732)
			(xy 370.984299 -218.183238) (xy 370.935059 -218.199237) (xy 370.883921 -218.207336) (xy 370.832147 -218.207336)
			(xy 370.781009 -218.199237) (xy 370.731769 -218.183238) (xy 370.685637 -218.159732) (xy 370.64375 -218.1293)
			(xy 370.60714 -218.09269) (xy 370.576708 -218.050803) (xy 370.553202 -218.004671) (xy 370.537203 -217.955431)
			(xy 370.529104 -217.904293) (xy 370.528596 -217.878406) (xy 370.529127 -217.850698) (xy 370.538321 -217.796051)
			(xy 370.546884 -217.769694) (xy 370.554758 -217.747596) (xy 370.34978 -217.392504) (xy 370.32692 -217.388186)
			(xy 370.302075 -217.38302) (xy 370.254226 -217.366126) (xy 370.209533 -217.342096) (xy 370.169053 -217.311499)
			(xy 370.133741 -217.275058) (xy 370.104433 -217.233634) (xy 370.081822 -217.188207) (xy 370.066443 -217.13985)
			(xy 370.058658 -217.089708) (xy 370.058188 -217.064336) (xy 368.837972 -217.064336) (xy 368.837359 -217.091989)
			(xy 368.828038 -217.146507) (xy 368.81943 -217.172794) (xy 368.81181 -217.194892) (xy 369.017042 -217.550238)
			(xy 369.039902 -217.554556) (xy 369.064703 -217.559751) (xy 369.112442 -217.57674) (xy 369.157019 -217.600833)
			(xy 369.197384 -217.631463) (xy 369.232588 -217.667908) (xy 369.2618 -217.709312) (xy 369.284333 -217.754697)
			(xy 369.299656 -217.802996) (xy 369.307408 -217.85307) (xy 369.307872 -217.878406) (xy 369.307364 -217.904293)
			(xy 369.299265 -217.955431) (xy 369.283266 -218.004671) (xy 369.25976 -218.050803) (xy 369.229328 -218.09269)
			(xy 369.192718 -218.1293) (xy 369.150831 -218.159732) (xy 369.104699 -218.183238) (xy 369.055459 -218.199237)
			(xy 369.004321 -218.207336) (xy 368.952547 -218.207336) (xy 368.901409 -218.199237) (xy 368.852169 -218.183238)
			(xy 368.806037 -218.159732) (xy 368.76415 -218.1293) (xy 368.72754 -218.09269) (xy 368.697108 -218.050803)
			(xy 368.673602 -218.004671) (xy 368.657603 -217.955431) (xy 368.649504 -217.904293) (xy 368.648996 -217.878406)
			(xy 368.649527 -217.850698) (xy 368.658721 -217.796051) (xy 368.667284 -217.769694) (xy 368.675158 -217.747596)
			(xy 368.47018 -217.392504) (xy 368.44732 -217.388186) (xy 368.422475 -217.38302) (xy 368.374626 -217.366126)
			(xy 368.329933 -217.342096) (xy 368.289453 -217.311499) (xy 368.254141 -217.275058) (xy 368.224833 -217.233634)
			(xy 368.202222 -217.188207) (xy 368.186843 -217.13985) (xy 368.179058 -217.089708) (xy 368.178588 -217.064336)
			(xy 366.958372 -217.064336) (xy 366.957759 -217.091989) (xy 366.948438 -217.146507) (xy 366.93983 -217.172794)
			(xy 366.93221 -217.194892) (xy 367.137442 -217.550238) (xy 367.160302 -217.554556) (xy 367.185103 -217.559751)
			(xy 367.232842 -217.57674) (xy 367.277419 -217.600833) (xy 367.317784 -217.631463) (xy 367.352988 -217.667908)
			(xy 367.3822 -217.709312) (xy 367.404733 -217.754697) (xy 367.420056 -217.802996) (xy 367.427808 -217.85307)
			(xy 367.428272 -217.878406) (xy 367.427764 -217.904293) (xy 367.419665 -217.955431) (xy 367.403666 -218.004671)
			(xy 367.38016 -218.050803) (xy 367.349728 -218.09269) (xy 367.313118 -218.1293) (xy 367.271231 -218.159732)
			(xy 367.225099 -218.183238) (xy 367.175859 -218.199237) (xy 367.124721 -218.207336) (xy 367.072947 -218.207336)
			(xy 367.021809 -218.199237) (xy 366.972569 -218.183238) (xy 366.926437 -218.159732) (xy 366.88455 -218.1293)
			(xy 366.84794 -218.09269) (xy 366.817508 -218.050803) (xy 366.794002 -218.004671) (xy 366.778003 -217.955431)
			(xy 366.769904 -217.904293) (xy 366.769396 -217.878406) (xy 366.769927 -217.850698) (xy 366.779121 -217.796051)
			(xy 366.787684 -217.769694) (xy 366.795558 -217.747596) (xy 366.59058 -217.392504) (xy 366.56772 -217.388186)
			(xy 366.542875 -217.38302) (xy 366.495026 -217.366126) (xy 366.450333 -217.342096) (xy 366.409853 -217.311499)
			(xy 366.374541 -217.275058) (xy 366.345233 -217.233634) (xy 366.322622 -217.188207) (xy 366.307243 -217.13985)
			(xy 366.299458 -217.089708) (xy 366.298988 -217.064336) (xy 365.078772 -217.064336) (xy 365.078159 -217.091989)
			(xy 365.068838 -217.146507) (xy 365.06023 -217.172794) (xy 365.05261 -217.194892) (xy 365.257842 -217.550238)
			(xy 365.280702 -217.554556) (xy 365.305503 -217.559751) (xy 365.353242 -217.57674) (xy 365.397819 -217.600833)
			(xy 365.438184 -217.631463) (xy 365.473388 -217.667908) (xy 365.5026 -217.709312) (xy 365.525133 -217.754697)
			(xy 365.540456 -217.802996) (xy 365.548208 -217.85307) (xy 365.548672 -217.878406) (xy 365.548164 -217.904293)
			(xy 365.540065 -217.955431) (xy 365.524066 -218.004671) (xy 365.50056 -218.050803) (xy 365.470128 -218.09269)
			(xy 365.433518 -218.1293) (xy 365.391631 -218.159732) (xy 365.345499 -218.183238) (xy 365.296259 -218.199237)
			(xy 365.245121 -218.207336) (xy 365.193347 -218.207336) (xy 365.142209 -218.199237) (xy 365.092969 -218.183238)
			(xy 365.046837 -218.159732) (xy 365.00495 -218.1293) (xy 364.96834 -218.09269) (xy 364.937908 -218.050803)
			(xy 364.914402 -218.004671) (xy 364.898403 -217.955431) (xy 364.890304 -217.904293) (xy 364.889796 -217.878406)
			(xy 364.890327 -217.850698) (xy 364.899521 -217.796051) (xy 364.908084 -217.769694) (xy 364.915958 -217.747596)
			(xy 364.71098 -217.392504) (xy 364.68812 -217.388186) (xy 364.663275 -217.38302) (xy 364.615426 -217.366126)
			(xy 364.570733 -217.342096) (xy 364.530253 -217.311499) (xy 364.494941 -217.275058) (xy 364.465633 -217.233634)
			(xy 364.443022 -217.188207) (xy 364.427643 -217.13985) (xy 364.419858 -217.089708) (xy 364.419388 -217.064336)
			(xy 363.199172 -217.064336) (xy 363.198559 -217.091989) (xy 363.189238 -217.146507) (xy 363.18063 -217.172794)
			(xy 363.17301 -217.194892) (xy 363.378242 -217.550238) (xy 363.401102 -217.554556) (xy 363.425903 -217.559751)
			(xy 363.473642 -217.57674) (xy 363.518219 -217.600833) (xy 363.558584 -217.631463) (xy 363.593788 -217.667908)
			(xy 363.623 -217.709312) (xy 363.645533 -217.754697) (xy 363.660856 -217.802996) (xy 363.668608 -217.85307)
			(xy 363.669072 -217.878406) (xy 363.668564 -217.904293) (xy 363.660465 -217.955431) (xy 363.644466 -218.004671)
			(xy 363.62096 -218.050803) (xy 363.590528 -218.09269) (xy 363.553918 -218.1293) (xy 363.512031 -218.159732)
			(xy 363.465899 -218.183238) (xy 363.416659 -218.199237) (xy 363.365521 -218.207336) (xy 363.313747 -218.207336)
			(xy 363.262609 -218.199237) (xy 363.213369 -218.183238) (xy 363.167237 -218.159732) (xy 363.12535 -218.1293)
			(xy 363.08874 -218.09269) (xy 363.058308 -218.050803) (xy 363.034802 -218.004671) (xy 363.018803 -217.955431)
			(xy 363.010704 -217.904293) (xy 363.010196 -217.878406) (xy 363.010727 -217.850698) (xy 363.019921 -217.796051)
			(xy 363.028484 -217.769694) (xy 363.036358 -217.747596) (xy 362.83138 -217.392504) (xy 362.80852 -217.388186)
			(xy 362.783675 -217.38302) (xy 362.735826 -217.366126) (xy 362.691133 -217.342096) (xy 362.650653 -217.311499)
			(xy 362.615341 -217.275058) (xy 362.586033 -217.233634) (xy 362.563422 -217.188207) (xy 362.548043 -217.13985)
			(xy 362.540258 -217.089708) (xy 362.539788 -217.064336) (xy 361.319572 -217.064336) (xy 361.318959 -217.091989)
			(xy 361.309638 -217.146507) (xy 361.30103 -217.172794) (xy 361.29341 -217.194892) (xy 361.498642 -217.550238)
			(xy 361.521502 -217.554556) (xy 361.546303 -217.559751) (xy 361.594042 -217.57674) (xy 361.638619 -217.600833)
			(xy 361.678984 -217.631463) (xy 361.714188 -217.667908) (xy 361.7434 -217.709312) (xy 361.765933 -217.754697)
			(xy 361.781256 -217.802996) (xy 361.789008 -217.85307) (xy 361.789472 -217.878406) (xy 361.788964 -217.904293)
			(xy 361.780865 -217.955431) (xy 361.764866 -218.004671) (xy 361.74136 -218.050803) (xy 361.710928 -218.09269)
			(xy 361.674318 -218.1293) (xy 361.632431 -218.159732) (xy 361.586299 -218.183238) (xy 361.537059 -218.199237)
			(xy 361.485921 -218.207336) (xy 361.434147 -218.207336) (xy 361.383009 -218.199237) (xy 361.333769 -218.183238)
			(xy 361.287637 -218.159732) (xy 361.24575 -218.1293) (xy 361.20914 -218.09269) (xy 361.178708 -218.050803)
			(xy 361.155202 -218.004671) (xy 361.139203 -217.955431) (xy 361.131104 -217.904293) (xy 361.130596 -217.878406)
			(xy 361.131127 -217.850698) (xy 361.140321 -217.796051) (xy 361.148884 -217.769694) (xy 361.156758 -217.747596)
			(xy 360.95178 -217.392504) (xy 360.92892 -217.388186) (xy 360.904075 -217.38302) (xy 360.856226 -217.366126)
			(xy 360.811533 -217.342096) (xy 360.771053 -217.311499) (xy 360.735741 -217.275058) (xy 360.706433 -217.233634)
			(xy 360.683822 -217.188207) (xy 360.668443 -217.13985) (xy 360.660658 -217.089708) (xy 360.660188 -217.064336)
			(xy 359.439972 -217.064336) (xy 359.439506 -217.089682) (xy 359.431728 -217.139773) (xy 359.416377 -217.188085)
			(xy 359.393813 -217.233478) (xy 359.364569 -217.274884) (xy 359.329334 -217.311328) (xy 359.288936 -217.34195)
			(xy 359.244329 -217.36603) (xy 359.196562 -217.383) (xy 359.171748 -217.388186) (xy 359.148888 -217.392504)
			(xy 358.94391 -217.747596) (xy 358.951784 -217.76944) (xy 358.960373 -217.795856) (xy 358.969563 -217.850633)
			(xy 358.970072 -217.878406) (xy 358.969564 -217.904293) (xy 358.961465 -217.955431) (xy 358.945466 -218.004671)
			(xy 358.92196 -218.050803) (xy 358.891528 -218.09269) (xy 358.854918 -218.1293) (xy 358.813031 -218.159732)
			(xy 358.766899 -218.183238) (xy 358.717659 -218.199237) (xy 358.666521 -218.207336) (xy 358.614747 -218.207336)
			(xy 358.563609 -218.199237) (xy 358.514369 -218.183238) (xy 358.468237 -218.159732) (xy 358.42635 -218.1293)
			(xy 358.38974 -218.09269) (xy 358.359308 -218.050803) (xy 358.335802 -218.004671) (xy 358.319803 -217.955431)
			(xy 358.311704 -217.904293) (xy 358.311196 -217.878406) (xy 358.030272 -217.878406) (xy 358.029741 -217.906114)
			(xy 358.020546 -217.960761) (xy 358.011984 -217.987118) (xy 358.004364 -218.008962) (xy 358.209342 -218.364054)
			(xy 358.232202 -218.368372) (xy 358.257007 -218.373552) (xy 358.304747 -218.390542) (xy 358.349324 -218.414636)
			(xy 358.38969 -218.445268) (xy 358.424894 -218.481716) (xy 358.454106 -218.523121) (xy 358.476638 -218.568508)
			(xy 358.491959 -218.616809) (xy 358.49971 -218.666886) (xy 358.500172 -218.692222) (xy 359.720388 -218.692222)
			(xy 359.720939 -218.66688) (xy 359.728707 -218.616793) (xy 359.744048 -218.568485) (xy 359.766601 -218.523094)
			(xy 359.795834 -218.481689) (xy 359.831059 -218.445245) (xy 359.871446 -218.41462) (xy 359.916044 -218.390537)
			(xy 359.963802 -218.373561) (xy 359.988612 -218.368372) (xy 360.011472 -218.364054) (xy 360.216704 -218.008708)
			(xy 360.20883 -217.98661) (xy 360.200361 -217.960367) (xy 360.191292 -217.905977) (xy 360.190796 -217.878406)
			(xy 360.191304 -217.852519) (xy 360.199403 -217.801381) (xy 360.215402 -217.752141) (xy 360.238908 -217.706009)
			(xy 360.26934 -217.664122) (xy 360.30595 -217.627512) (xy 360.347837 -217.59708) (xy 360.393969 -217.573574)
			(xy 360.443209 -217.557575) (xy 360.494347 -217.549476) (xy 360.546121 -217.549476) (xy 360.597259 -217.557575)
			(xy 360.646499 -217.573574) (xy 360.692631 -217.59708) (xy 360.734518 -217.627512) (xy 360.771128 -217.664122)
			(xy 360.80156 -217.706009) (xy 360.825066 -217.752141) (xy 360.841065 -217.801381) (xy 360.849164 -217.852519)
			(xy 360.849672 -217.878406) (xy 360.849225 -217.903782) (xy 360.841455 -217.953934) (xy 360.826085 -218.002302)
			(xy 360.803477 -218.047739) (xy 360.774167 -218.089171) (xy 360.73885 -218.125617) (xy 360.69836 -218.156215)
			(xy 360.653656 -218.18024) (xy 360.605796 -218.197124) (xy 360.58094 -218.202256) (xy 360.55808 -218.206574)
			(xy 360.353356 -218.561412) (xy 360.36123 -218.583256) (xy 360.369881 -218.609663) (xy 360.379198 -218.66444)
			(xy 360.379772 -218.692222) (xy 361.600496 -218.692222) (xy 361.601002 -218.666888) (xy 361.608751 -218.616817)
			(xy 361.62407 -218.568521) (xy 361.646599 -218.523138) (xy 361.675805 -218.481736) (xy 361.711003 -218.44529)
			(xy 361.751363 -218.414659) (xy 361.795934 -218.390564) (xy 361.843667 -218.373572) (xy 361.868466 -218.368372)
			(xy 361.891326 -218.364054) (xy 362.096304 -218.008962) (xy 362.088684 -217.986864) (xy 362.080159 -217.960694)
			(xy 362.070969 -217.906431) (xy 362.070396 -217.878914) (xy 362.070396 -217.878406) (xy 362.070904 -217.852519)
			(xy 362.079003 -217.801381) (xy 362.095002 -217.752141) (xy 362.118508 -217.706009) (xy 362.14894 -217.664122)
			(xy 362.18555 -217.627512) (xy 362.227437 -217.59708) (xy 362.273569 -217.573574) (xy 362.322809 -217.557575)
			(xy 362.373947 -217.549476) (xy 362.425721 -217.549476) (xy 362.476859 -217.557575) (xy 362.526099 -217.573574)
			(xy 362.572231 -217.59708) (xy 362.614118 -217.627512) (xy 362.650728 -217.664122) (xy 362.68116 -217.706009)
			(xy 362.704666 -217.752141) (xy 362.720665 -217.801381) (xy 362.728764 -217.852519) (xy 362.729272 -217.878406)
			(xy 362.728863 -217.903772) (xy 362.721112 -217.953909) (xy 362.705764 -218.002264) (xy 362.683182 -218.047694)
			(xy 362.6539 -218.089122) (xy 362.61861 -218.12557) (xy 362.578149 -218.156175) (xy 362.533472 -218.180212)
			(xy 362.485638 -218.197113) (xy 362.460794 -218.202256) (xy 362.437934 -218.206574) (xy 362.23321 -218.561412)
			(xy 362.241084 -218.583256) (xy 362.249677 -218.609671) (xy 362.258865 -218.664449) (xy 362.259372 -218.692222)
			(xy 363.479588 -218.692222) (xy 363.480139 -218.66688) (xy 363.487907 -218.616793) (xy 363.503248 -218.568485)
			(xy 363.525801 -218.523094) (xy 363.555034 -218.481689) (xy 363.590259 -218.445245) (xy 363.630646 -218.41462)
			(xy 363.675244 -218.390537) (xy 363.723002 -218.373561) (xy 363.747812 -218.368372) (xy 363.770672 -218.364054)
			(xy 363.975904 -218.008708) (xy 363.96803 -217.98661) (xy 363.959561 -217.960367) (xy 363.950492 -217.905977)
			(xy 363.949996 -217.878406) (xy 363.950504 -217.852519) (xy 363.958603 -217.801381) (xy 363.974602 -217.752141)
			(xy 363.998108 -217.706009) (xy 364.02854 -217.664122) (xy 364.06515 -217.627512) (xy 364.107037 -217.59708)
			(xy 364.153169 -217.573574) (xy 364.202409 -217.557575) (xy 364.253547 -217.549476) (xy 364.305321 -217.549476)
			(xy 364.356459 -217.557575) (xy 364.405699 -217.573574) (xy 364.451831 -217.59708) (xy 364.493718 -217.627512)
			(xy 364.530328 -217.664122) (xy 364.56076 -217.706009) (xy 364.584266 -217.752141) (xy 364.600265 -217.801381)
			(xy 364.608364 -217.852519) (xy 364.608872 -217.878406) (xy 364.608425 -217.903782) (xy 364.600655 -217.953934)
			(xy 364.585285 -218.002302) (xy 364.562677 -218.047739) (xy 364.533367 -218.089171) (xy 364.49805 -218.125617)
			(xy 364.45756 -218.156215) (xy 364.412856 -218.18024) (xy 364.364996 -218.197124) (xy 364.34014 -218.202256)
			(xy 364.31728 -218.206574) (xy 364.112556 -218.561412) (xy 364.12043 -218.583256) (xy 364.129081 -218.609663)
			(xy 364.138398 -218.66444) (xy 364.138972 -218.692222) (xy 365.359188 -218.692222) (xy 365.359739 -218.66688)
			(xy 365.367507 -218.616793) (xy 365.382848 -218.568485) (xy 365.405401 -218.523094) (xy 365.434634 -218.481689)
			(xy 365.469859 -218.445245) (xy 365.510246 -218.41462) (xy 365.554844 -218.390537) (xy 365.602602 -218.373561)
			(xy 365.627412 -218.368372) (xy 365.650272 -218.364054) (xy 365.855504 -218.008708) (xy 365.84763 -217.98661)
			(xy 365.839161 -217.960367) (xy 365.830092 -217.905977) (xy 365.829596 -217.878406) (xy 365.830104 -217.852519)
			(xy 365.838203 -217.801381) (xy 365.854202 -217.752141) (xy 365.877708 -217.706009) (xy 365.90814 -217.664122)
			(xy 365.94475 -217.627512) (xy 365.986637 -217.59708) (xy 366.032769 -217.573574) (xy 366.082009 -217.557575)
			(xy 366.133147 -217.549476) (xy 366.184921 -217.549476) (xy 366.236059 -217.557575) (xy 366.285299 -217.573574)
			(xy 366.331431 -217.59708) (xy 366.373318 -217.627512) (xy 366.409928 -217.664122) (xy 366.44036 -217.706009)
			(xy 366.463866 -217.752141) (xy 366.479865 -217.801381) (xy 366.487964 -217.852519) (xy 366.488472 -217.878406)
			(xy 366.488025 -217.903782) (xy 366.480255 -217.953934) (xy 366.464885 -218.002302) (xy 366.442277 -218.047739)
			(xy 366.412967 -218.089171) (xy 366.37765 -218.125617) (xy 366.33716 -218.156215) (xy 366.292456 -218.18024)
			(xy 366.244596 -218.197124) (xy 366.21974 -218.202256) (xy 366.19688 -218.206574) (xy 365.992156 -218.561412)
			(xy 366.00003 -218.583256) (xy 366.008681 -218.609663) (xy 366.017998 -218.66444) (xy 366.018572 -218.692222)
			(xy 367.238788 -218.692222) (xy 367.239339 -218.66688) (xy 367.247107 -218.616793) (xy 367.262448 -218.568485)
			(xy 367.285001 -218.523094) (xy 367.314234 -218.481689) (xy 367.349459 -218.445245) (xy 367.389846 -218.41462)
			(xy 367.434444 -218.390537) (xy 367.482202 -218.373561) (xy 367.507012 -218.368372) (xy 367.529872 -218.364054)
			(xy 367.735104 -218.008708) (xy 367.72723 -217.98661) (xy 367.718761 -217.960367) (xy 367.709692 -217.905977)
			(xy 367.709196 -217.878406) (xy 367.709704 -217.852519) (xy 367.717803 -217.801381) (xy 367.733802 -217.752141)
			(xy 367.757308 -217.706009) (xy 367.78774 -217.664122) (xy 367.82435 -217.627512) (xy 367.866237 -217.59708)
			(xy 367.912369 -217.573574) (xy 367.961609 -217.557575) (xy 368.012747 -217.549476) (xy 368.064521 -217.549476)
			(xy 368.115659 -217.557575) (xy 368.164899 -217.573574) (xy 368.211031 -217.59708) (xy 368.252918 -217.627512)
			(xy 368.289528 -217.664122) (xy 368.31996 -217.706009) (xy 368.343466 -217.752141) (xy 368.359465 -217.801381)
			(xy 368.367564 -217.852519) (xy 368.368072 -217.878406) (xy 368.367625 -217.903782) (xy 368.359855 -217.953934)
			(xy 368.344485 -218.002302) (xy 368.321877 -218.047739) (xy 368.292567 -218.089171) (xy 368.25725 -218.125617)
			(xy 368.21676 -218.156215) (xy 368.172056 -218.18024) (xy 368.124196 -218.197124) (xy 368.09934 -218.202256)
			(xy 368.07648 -218.206574) (xy 367.871756 -218.561412) (xy 367.87963 -218.583256) (xy 367.888281 -218.609663)
			(xy 367.897598 -218.66444) (xy 367.898172 -218.692222) (xy 369.118388 -218.692222) (xy 369.118939 -218.66688)
			(xy 369.126707 -218.616793) (xy 369.142048 -218.568485) (xy 369.164601 -218.523094) (xy 369.193834 -218.481689)
			(xy 369.229059 -218.445245) (xy 369.269446 -218.41462) (xy 369.314044 -218.390537) (xy 369.361802 -218.373561)
			(xy 369.386612 -218.368372) (xy 369.409472 -218.364054) (xy 369.614704 -218.008708) (xy 369.60683 -217.98661)
			(xy 369.598361 -217.960367) (xy 369.589292 -217.905977) (xy 369.588796 -217.878406) (xy 369.589304 -217.852519)
			(xy 369.597403 -217.801381) (xy 369.613402 -217.752141) (xy 369.636908 -217.706009) (xy 369.66734 -217.664122)
			(xy 369.70395 -217.627512) (xy 369.745837 -217.59708) (xy 369.791969 -217.573574) (xy 369.841209 -217.557575)
			(xy 369.892347 -217.549476) (xy 369.944121 -217.549476) (xy 369.995259 -217.557575) (xy 370.044499 -217.573574)
			(xy 370.090631 -217.59708) (xy 370.132518 -217.627512) (xy 370.169128 -217.664122) (xy 370.19956 -217.706009)
			(xy 370.223066 -217.752141) (xy 370.239065 -217.801381) (xy 370.247164 -217.852519) (xy 370.247672 -217.878406)
			(xy 370.247225 -217.903782) (xy 370.239455 -217.953934) (xy 370.224085 -218.002302) (xy 370.201477 -218.047739)
			(xy 370.172167 -218.089171) (xy 370.13685 -218.125617) (xy 370.09636 -218.156215) (xy 370.051656 -218.18024)
			(xy 370.003796 -218.197124) (xy 369.97894 -218.202256) (xy 369.95608 -218.206574) (xy 369.751356 -218.561412)
			(xy 369.75923 -218.583256) (xy 369.767881 -218.609663) (xy 369.777198 -218.66444) (xy 369.777772 -218.692222)
			(xy 370.997988 -218.692222) (xy 370.998539 -218.66688) (xy 371.006307 -218.616793) (xy 371.021648 -218.568485)
			(xy 371.044201 -218.523094) (xy 371.073434 -218.481689) (xy 371.108659 -218.445245) (xy 371.149046 -218.41462)
			(xy 371.193644 -218.390537) (xy 371.241402 -218.373561) (xy 371.266212 -218.368372) (xy 371.289072 -218.364054)
			(xy 371.494304 -218.008708) (xy 371.48643 -217.98661) (xy 371.477961 -217.960367) (xy 371.468892 -217.905977)
			(xy 371.468396 -217.878406) (xy 371.468904 -217.852519) (xy 371.477003 -217.801381) (xy 371.493002 -217.752141)
			(xy 371.516508 -217.706009) (xy 371.54694 -217.664122) (xy 371.58355 -217.627512) (xy 371.625437 -217.59708)
			(xy 371.671569 -217.573574) (xy 371.720809 -217.557575) (xy 371.771947 -217.549476) (xy 371.823721 -217.549476)
			(xy 371.874859 -217.557575) (xy 371.924099 -217.573574) (xy 371.970231 -217.59708) (xy 372.012118 -217.627512)
			(xy 372.048728 -217.664122) (xy 372.07916 -217.706009) (xy 372.102666 -217.752141) (xy 372.118665 -217.801381)
			(xy 372.126764 -217.852519) (xy 372.127272 -217.878406) (xy 372.126825 -217.903782) (xy 372.119055 -217.953934)
			(xy 372.103685 -218.002302) (xy 372.081077 -218.047739) (xy 372.051767 -218.089171) (xy 372.01645 -218.125617)
			(xy 371.97596 -218.156215) (xy 371.931256 -218.18024) (xy 371.883396 -218.197124) (xy 371.85854 -218.202256)
			(xy 371.83568 -218.206574) (xy 371.630956 -218.561412) (xy 371.63883 -218.583256) (xy 371.647481 -218.609663)
			(xy 371.656798 -218.66444) (xy 371.657372 -218.692222) (xy 372.877588 -218.692222) (xy 372.878139 -218.66688)
			(xy 372.885907 -218.616793) (xy 372.901248 -218.568485) (xy 372.923801 -218.523094) (xy 372.953034 -218.481689)
			(xy 372.988259 -218.445245) (xy 373.028646 -218.41462) (xy 373.073244 -218.390537) (xy 373.121002 -218.373561)
			(xy 373.145812 -218.368372) (xy 373.168672 -218.364054) (xy 373.373904 -218.008708) (xy 373.36603 -217.98661)
			(xy 373.357561 -217.960367) (xy 373.348492 -217.905977) (xy 373.347996 -217.878406) (xy 373.348504 -217.852519)
			(xy 373.356603 -217.801381) (xy 373.372602 -217.752141) (xy 373.396108 -217.706009) (xy 373.42654 -217.664122)
			(xy 373.46315 -217.627512) (xy 373.505037 -217.59708) (xy 373.551169 -217.573574) (xy 373.600409 -217.557575)
			(xy 373.651547 -217.549476) (xy 373.703321 -217.549476) (xy 373.754459 -217.557575) (xy 373.803699 -217.573574)
			(xy 373.849831 -217.59708) (xy 373.891718 -217.627512) (xy 373.928328 -217.664122) (xy 373.95876 -217.706009)
			(xy 373.982266 -217.752141) (xy 373.998265 -217.801381) (xy 374.006364 -217.852519) (xy 374.006872 -217.878406)
			(xy 374.006425 -217.903782) (xy 373.998655 -217.953934) (xy 373.983285 -218.002302) (xy 373.960677 -218.047739)
			(xy 373.931367 -218.089171) (xy 373.89605 -218.125617) (xy 373.85556 -218.156215) (xy 373.810856 -218.18024)
			(xy 373.762996 -218.197124) (xy 373.73814 -218.202256) (xy 373.71528 -218.206574) (xy 373.510556 -218.561412)
			(xy 373.51843 -218.583256) (xy 373.527081 -218.609663) (xy 373.536398 -218.66444) (xy 373.536972 -218.692222)
			(xy 374.757188 -218.692222) (xy 374.757739 -218.66688) (xy 374.765507 -218.616793) (xy 374.780848 -218.568485)
			(xy 374.803401 -218.523094) (xy 374.832634 -218.481689) (xy 374.867859 -218.445245) (xy 374.908246 -218.41462)
			(xy 374.952844 -218.390537) (xy 375.000602 -218.373561) (xy 375.025412 -218.368372) (xy 375.048272 -218.364054)
			(xy 375.253504 -218.008708) (xy 375.24563 -217.98661) (xy 375.237161 -217.960367) (xy 375.228092 -217.905977)
			(xy 375.227596 -217.878406) (xy 375.228104 -217.852519) (xy 375.236203 -217.801381) (xy 375.252202 -217.752141)
			(xy 375.275708 -217.706009) (xy 375.30614 -217.664122) (xy 375.34275 -217.627512) (xy 375.384637 -217.59708)
			(xy 375.430769 -217.573574) (xy 375.480009 -217.557575) (xy 375.531147 -217.549476) (xy 375.582921 -217.549476)
			(xy 375.634059 -217.557575) (xy 375.683299 -217.573574) (xy 375.729431 -217.59708) (xy 375.771318 -217.627512)
			(xy 375.807928 -217.664122) (xy 375.83836 -217.706009) (xy 375.861866 -217.752141) (xy 375.877865 -217.801381)
			(xy 375.885964 -217.852519) (xy 375.886472 -217.878406) (xy 375.886025 -217.903782) (xy 375.878255 -217.953934)
			(xy 375.862885 -218.002302) (xy 375.840277 -218.047739) (xy 375.810967 -218.089171) (xy 375.77565 -218.125617)
			(xy 375.73516 -218.156215) (xy 375.690456 -218.18024) (xy 375.642596 -218.197124) (xy 375.61774 -218.202256)
			(xy 375.59488 -218.206574) (xy 375.390156 -218.561412) (xy 375.39803 -218.583256) (xy 375.406681 -218.609663)
			(xy 375.415998 -218.66444) (xy 375.416572 -218.692222) (xy 376.636788 -218.692222) (xy 376.637339 -218.66688)
			(xy 376.645107 -218.616793) (xy 376.660448 -218.568485) (xy 376.683001 -218.523094) (xy 376.712234 -218.481689)
			(xy 376.747459 -218.445245) (xy 376.787846 -218.41462) (xy 376.832444 -218.390537) (xy 376.880202 -218.373561)
			(xy 376.905012 -218.368372) (xy 376.927872 -218.364054) (xy 377.133104 -218.008708) (xy 377.12523 -217.98661)
			(xy 377.116761 -217.960367) (xy 377.107692 -217.905977) (xy 377.107196 -217.878406) (xy 377.107704 -217.852519)
			(xy 377.115803 -217.801381) (xy 377.131802 -217.752141) (xy 377.155308 -217.706009) (xy 377.18574 -217.664122)
			(xy 377.22235 -217.627512) (xy 377.264237 -217.59708) (xy 377.310369 -217.573574) (xy 377.359609 -217.557575)
			(xy 377.410747 -217.549476) (xy 377.462521 -217.549476) (xy 377.513659 -217.557575) (xy 377.562899 -217.573574)
			(xy 377.609031 -217.59708) (xy 377.650918 -217.627512) (xy 377.687528 -217.664122) (xy 377.71796 -217.706009)
			(xy 377.741466 -217.752141) (xy 377.757465 -217.801381) (xy 377.765564 -217.852519) (xy 377.766072 -217.878406)
			(xy 377.765625 -217.903782) (xy 377.757855 -217.953934) (xy 377.742485 -218.002302) (xy 377.719877 -218.047739)
			(xy 377.690567 -218.089171) (xy 377.65525 -218.125617) (xy 377.61476 -218.156215) (xy 377.570056 -218.18024)
			(xy 377.522196 -218.197124) (xy 377.49734 -218.202256) (xy 377.47448 -218.206574) (xy 377.269756 -218.561412)
			(xy 377.27763 -218.583256) (xy 377.286281 -218.609663) (xy 377.295598 -218.66444) (xy 377.296172 -218.692222)
			(xy 378.516388 -218.692222) (xy 378.516939 -218.66688) (xy 378.524707 -218.616793) (xy 378.540048 -218.568485)
			(xy 378.562601 -218.523094) (xy 378.591834 -218.481689) (xy 378.627059 -218.445245) (xy 378.667446 -218.41462)
			(xy 378.712044 -218.390537) (xy 378.759802 -218.373561) (xy 378.784612 -218.368372) (xy 378.807472 -218.364054)
			(xy 379.012704 -218.008708) (xy 379.00483 -217.98661) (xy 378.996361 -217.960367) (xy 378.987292 -217.905977)
			(xy 378.986796 -217.878406) (xy 378.987304 -217.852519) (xy 378.995403 -217.801381) (xy 379.011402 -217.752141)
			(xy 379.034908 -217.706009) (xy 379.06534 -217.664122) (xy 379.10195 -217.627512) (xy 379.143837 -217.59708)
			(xy 379.189969 -217.573574) (xy 379.239209 -217.557575) (xy 379.290347 -217.549476) (xy 379.342121 -217.549476)
			(xy 379.393259 -217.557575) (xy 379.442499 -217.573574) (xy 379.488631 -217.59708) (xy 379.530518 -217.627512)
			(xy 379.567128 -217.664122) (xy 379.59756 -217.706009) (xy 379.621066 -217.752141) (xy 379.637065 -217.801381)
			(xy 379.645164 -217.852519) (xy 379.645672 -217.878406) (xy 379.645225 -217.903782) (xy 379.637455 -217.953934)
			(xy 379.622085 -218.002302) (xy 379.599477 -218.047739) (xy 379.570167 -218.089171) (xy 379.53485 -218.125617)
			(xy 379.49436 -218.156215) (xy 379.449656 -218.18024) (xy 379.401796 -218.197124) (xy 379.37694 -218.202256)
			(xy 379.35408 -218.206574) (xy 379.149356 -218.561412) (xy 379.15723 -218.583256) (xy 379.165881 -218.609663)
			(xy 379.175198 -218.66444) (xy 379.175772 -218.692222) (xy 380.395988 -218.692222) (xy 380.396539 -218.66688)
			(xy 380.404307 -218.616793) (xy 380.419648 -218.568485) (xy 380.442201 -218.523094) (xy 380.471434 -218.481689)
			(xy 380.506659 -218.445245) (xy 380.547046 -218.41462) (xy 380.591644 -218.390537) (xy 380.639402 -218.373561)
			(xy 380.664212 -218.368372) (xy 380.687072 -218.364054) (xy 380.892304 -218.008708) (xy 380.88443 -217.98661)
			(xy 380.875961 -217.960367) (xy 380.866892 -217.905977) (xy 380.866396 -217.878406) (xy 380.866904 -217.852519)
			(xy 380.875003 -217.801381) (xy 380.891002 -217.752141) (xy 380.914508 -217.706009) (xy 380.94494 -217.664122)
			(xy 380.98155 -217.627512) (xy 381.023437 -217.59708) (xy 381.069569 -217.573574) (xy 381.118809 -217.557575)
			(xy 381.169947 -217.549476) (xy 381.221721 -217.549476) (xy 381.272859 -217.557575) (xy 381.322099 -217.573574)
			(xy 381.368231 -217.59708) (xy 381.410118 -217.627512) (xy 381.446728 -217.664122) (xy 381.47716 -217.706009)
			(xy 381.500666 -217.752141) (xy 381.516665 -217.801381) (xy 381.524764 -217.852519) (xy 381.525272 -217.878406)
			(xy 381.524825 -217.903782) (xy 381.517055 -217.953934) (xy 381.501685 -218.002302) (xy 381.479077 -218.047739)
			(xy 381.449767 -218.089171) (xy 381.41445 -218.125617) (xy 381.37396 -218.156215) (xy 381.329256 -218.18024)
			(xy 381.281396 -218.197124) (xy 381.25654 -218.202256) (xy 381.23368 -218.206574) (xy 381.028956 -218.561412)
			(xy 381.03683 -218.583256) (xy 381.045481 -218.609663) (xy 381.054798 -218.66444) (xy 381.055372 -218.692222)
			(xy 381.054864 -218.718129) (xy 381.046758 -218.769306) (xy 381.030746 -218.818585) (xy 381.007223 -218.864752)
			(xy 380.976767 -218.906671) (xy 380.940129 -218.943309) (xy 380.89821 -218.973765) (xy 380.852043 -218.997288)
			(xy 380.802764 -219.0133) (xy 380.751587 -219.021406) (xy 380.699773 -219.021406) (xy 380.648596 -219.0133)
			(xy 380.599317 -218.997288) (xy 380.55315 -218.973765) (xy 380.511231 -218.943309) (xy 380.474593 -218.906671)
			(xy 380.444137 -218.864752) (xy 380.420614 -218.818585) (xy 380.404602 -218.769306) (xy 380.396496 -218.718129)
			(xy 380.395988 -218.692222) (xy 379.175772 -218.692222) (xy 379.175264 -218.718129) (xy 379.167158 -218.769306)
			(xy 379.151146 -218.818585) (xy 379.127623 -218.864752) (xy 379.097167 -218.906671) (xy 379.060529 -218.943309)
			(xy 379.01861 -218.973765) (xy 378.972443 -218.997288) (xy 378.923164 -219.0133) (xy 378.871987 -219.021406)
			(xy 378.820173 -219.021406) (xy 378.768996 -219.0133) (xy 378.719717 -218.997288) (xy 378.67355 -218.973765)
			(xy 378.631631 -218.943309) (xy 378.594993 -218.906671) (xy 378.564537 -218.864752) (xy 378.541014 -218.818585)
			(xy 378.525002 -218.769306) (xy 378.516896 -218.718129) (xy 378.516388 -218.692222) (xy 377.296172 -218.692222)
			(xy 377.295664 -218.718129) (xy 377.287558 -218.769306) (xy 377.271546 -218.818585) (xy 377.248023 -218.864752)
			(xy 377.217567 -218.906671) (xy 377.180929 -218.943309) (xy 377.13901 -218.973765) (xy 377.092843 -218.997288)
			(xy 377.043564 -219.0133) (xy 376.992387 -219.021406) (xy 376.940573 -219.021406) (xy 376.889396 -219.0133)
			(xy 376.840117 -218.997288) (xy 376.79395 -218.973765) (xy 376.752031 -218.943309) (xy 376.715393 -218.906671)
			(xy 376.684937 -218.864752) (xy 376.661414 -218.818585) (xy 376.645402 -218.769306) (xy 376.637296 -218.718129)
			(xy 376.636788 -218.692222) (xy 375.416572 -218.692222) (xy 375.416064 -218.718129) (xy 375.407958 -218.769306)
			(xy 375.391946 -218.818585) (xy 375.368423 -218.864752) (xy 375.337967 -218.906671) (xy 375.301329 -218.943309)
			(xy 375.25941 -218.973765) (xy 375.213243 -218.997288) (xy 375.163964 -219.0133) (xy 375.112787 -219.021406)
			(xy 375.060973 -219.021406) (xy 375.009796 -219.0133) (xy 374.960517 -218.997288) (xy 374.91435 -218.973765)
			(xy 374.872431 -218.943309) (xy 374.835793 -218.906671) (xy 374.805337 -218.864752) (xy 374.781814 -218.818585)
			(xy 374.765802 -218.769306) (xy 374.757696 -218.718129) (xy 374.757188 -218.692222) (xy 373.536972 -218.692222)
			(xy 373.536464 -218.718129) (xy 373.528358 -218.769306) (xy 373.512346 -218.818585) (xy 373.488823 -218.864752)
			(xy 373.458367 -218.906671) (xy 373.421729 -218.943309) (xy 373.37981 -218.973765) (xy 373.333643 -218.997288)
			(xy 373.284364 -219.0133) (xy 373.233187 -219.021406) (xy 373.181373 -219.021406) (xy 373.130196 -219.0133)
			(xy 373.080917 -218.997288) (xy 373.03475 -218.973765) (xy 372.992831 -218.943309) (xy 372.956193 -218.906671)
			(xy 372.925737 -218.864752) (xy 372.902214 -218.818585) (xy 372.886202 -218.769306) (xy 372.878096 -218.718129)
			(xy 372.877588 -218.692222) (xy 371.657372 -218.692222) (xy 371.656864 -218.718129) (xy 371.648758 -218.769306)
			(xy 371.632746 -218.818585) (xy 371.609223 -218.864752) (xy 371.578767 -218.906671) (xy 371.542129 -218.943309)
			(xy 371.50021 -218.973765) (xy 371.454043 -218.997288) (xy 371.404764 -219.0133) (xy 371.353587 -219.021406)
			(xy 371.301773 -219.021406) (xy 371.250596 -219.0133) (xy 371.201317 -218.997288) (xy 371.15515 -218.973765)
			(xy 371.113231 -218.943309) (xy 371.076593 -218.906671) (xy 371.046137 -218.864752) (xy 371.022614 -218.818585)
			(xy 371.006602 -218.769306) (xy 370.998496 -218.718129) (xy 370.997988 -218.692222) (xy 369.777772 -218.692222)
			(xy 369.777264 -218.718129) (xy 369.769158 -218.769306) (xy 369.753146 -218.818585) (xy 369.729623 -218.864752)
			(xy 369.699167 -218.906671) (xy 369.662529 -218.943309) (xy 369.62061 -218.973765) (xy 369.574443 -218.997288)
			(xy 369.525164 -219.0133) (xy 369.473987 -219.021406) (xy 369.422173 -219.021406) (xy 369.370996 -219.0133)
			(xy 369.321717 -218.997288) (xy 369.27555 -218.973765) (xy 369.233631 -218.943309) (xy 369.196993 -218.906671)
			(xy 369.166537 -218.864752) (xy 369.143014 -218.818585) (xy 369.127002 -218.769306) (xy 369.118896 -218.718129)
			(xy 369.118388 -218.692222) (xy 367.898172 -218.692222) (xy 367.897664 -218.718129) (xy 367.889558 -218.769306)
			(xy 367.873546 -218.818585) (xy 367.850023 -218.864752) (xy 367.819567 -218.906671) (xy 367.782929 -218.943309)
			(xy 367.74101 -218.973765) (xy 367.694843 -218.997288) (xy 367.645564 -219.0133) (xy 367.594387 -219.021406)
			(xy 367.542573 -219.021406) (xy 367.491396 -219.0133) (xy 367.442117 -218.997288) (xy 367.39595 -218.973765)
			(xy 367.354031 -218.943309) (xy 367.317393 -218.906671) (xy 367.286937 -218.864752) (xy 367.263414 -218.818585)
			(xy 367.247402 -218.769306) (xy 367.239296 -218.718129) (xy 367.238788 -218.692222) (xy 366.018572 -218.692222)
			(xy 366.018064 -218.718129) (xy 366.009958 -218.769306) (xy 365.993946 -218.818585) (xy 365.970423 -218.864752)
			(xy 365.939967 -218.906671) (xy 365.903329 -218.943309) (xy 365.86141 -218.973765) (xy 365.815243 -218.997288)
			(xy 365.765964 -219.0133) (xy 365.714787 -219.021406) (xy 365.662973 -219.021406) (xy 365.611796 -219.0133)
			(xy 365.562517 -218.997288) (xy 365.51635 -218.973765) (xy 365.474431 -218.943309) (xy 365.437793 -218.906671)
			(xy 365.407337 -218.864752) (xy 365.383814 -218.818585) (xy 365.367802 -218.769306) (xy 365.359696 -218.718129)
			(xy 365.359188 -218.692222) (xy 364.138972 -218.692222) (xy 364.138464 -218.718129) (xy 364.130358 -218.769306)
			(xy 364.114346 -218.818585) (xy 364.090823 -218.864752) (xy 364.060367 -218.906671) (xy 364.023729 -218.943309)
			(xy 363.98181 -218.973765) (xy 363.935643 -218.997288) (xy 363.886364 -219.0133) (xy 363.835187 -219.021406)
			(xy 363.783373 -219.021406) (xy 363.732196 -219.0133) (xy 363.682917 -218.997288) (xy 363.63675 -218.973765)
			(xy 363.594831 -218.943309) (xy 363.558193 -218.906671) (xy 363.527737 -218.864752) (xy 363.504214 -218.818585)
			(xy 363.488202 -218.769306) (xy 363.480096 -218.718129) (xy 363.479588 -218.692222) (xy 362.259372 -218.692222)
			(xy 362.258864 -218.718109) (xy 362.250765 -218.769247) (xy 362.234766 -218.818487) (xy 362.21126 -218.864619)
			(xy 362.180828 -218.906506) (xy 362.144218 -218.943116) (xy 362.102331 -218.973548) (xy 362.056199 -218.997054)
			(xy 362.006959 -219.013053) (xy 361.955821 -219.021152) (xy 361.904047 -219.021152) (xy 361.852909 -219.013053)
			(xy 361.803669 -218.997054) (xy 361.757537 -218.973548) (xy 361.71565 -218.943116) (xy 361.67904 -218.906506)
			(xy 361.648608 -218.864619) (xy 361.625102 -218.818487) (xy 361.609103 -218.769247) (xy 361.601004 -218.718109)
			(xy 361.600496 -218.692222) (xy 360.379772 -218.692222) (xy 360.379264 -218.718129) (xy 360.371158 -218.769306)
			(xy 360.355146 -218.818585) (xy 360.331623 -218.864752) (xy 360.301167 -218.906671) (xy 360.264529 -218.943309)
			(xy 360.22261 -218.973765) (xy 360.176443 -218.997288) (xy 360.127164 -219.0133) (xy 360.075987 -219.021406)
			(xy 360.024173 -219.021406) (xy 359.972996 -219.0133) (xy 359.923717 -218.997288) (xy 359.87755 -218.973765)
			(xy 359.835631 -218.943309) (xy 359.798993 -218.906671) (xy 359.768537 -218.864752) (xy 359.745014 -218.818585)
			(xy 359.729002 -218.769306) (xy 359.720896 -218.718129) (xy 359.720388 -218.692222) (xy 358.500172 -218.692222)
			(xy 358.499664 -218.718109) (xy 358.491565 -218.769247) (xy 358.475566 -218.818487) (xy 358.45206 -218.864619)
			(xy 358.421628 -218.906506) (xy 358.385018 -218.943116) (xy 358.343131 -218.973548) (xy 358.296999 -218.997054)
			(xy 358.247759 -219.013053) (xy 358.196621 -219.021152) (xy 358.144847 -219.021152) (xy 358.093709 -219.013053)
			(xy 358.044469 -218.997054) (xy 357.998337 -218.973548) (xy 357.95645 -218.943116) (xy 357.91984 -218.906506)
			(xy 357.889408 -218.864619) (xy 357.865902 -218.818487) (xy 357.849903 -218.769247) (xy 357.841804 -218.718109)
			(xy 357.841296 -218.692222) (xy 357.841831 -218.664514) (xy 357.851023 -218.609867) (xy 357.859584 -218.58351)
			(xy 357.867458 -218.561412) (xy 357.66248 -218.206574) (xy 357.63962 -218.202256) (xy 357.614783 -218.197156)
			(xy 357.567001 -218.180194) (xy 357.52238 -218.156114) (xy 357.481972 -218.125486) (xy 357.446732 -218.08903)
			(xy 357.417491 -218.047608) (xy 357.394937 -218.002196) (xy 357.379605 -217.953866) (xy 357.371854 -217.903758)
			(xy 357.371396 -217.878406) (xy 357.090472 -217.878406) (xy 357.089964 -217.904293) (xy 357.081865 -217.955431)
			(xy 357.065866 -218.004671) (xy 357.04236 -218.050803) (xy 357.011928 -218.09269) (xy 356.975318 -218.1293)
			(xy 356.933431 -218.159732) (xy 356.887299 -218.183238) (xy 356.838059 -218.199237) (xy 356.786921 -218.207336)
			(xy 356.735147 -218.207336) (xy 356.684009 -218.199237) (xy 356.634769 -218.183238) (xy 356.588637 -218.159732)
			(xy 356.54675 -218.1293) (xy 356.51014 -218.09269) (xy 356.479708 -218.050803) (xy 356.456202 -218.004671)
			(xy 356.440203 -217.955431) (xy 356.432104 -217.904293) (xy 356.431596 -217.878406) (xy 356.150672 -217.878406)
			(xy 356.150141 -217.906114) (xy 356.140946 -217.960761) (xy 356.132384 -217.987118) (xy 356.12451 -218.009216)
			(xy 356.329488 -218.364054) (xy 356.352348 -218.368372) (xy 356.377163 -218.373563) (xy 356.424941 -218.390515)
			(xy 356.469559 -218.414584) (xy 356.509965 -218.445202) (xy 356.545206 -218.481645) (xy 356.57445 -218.523056)
			(xy 356.597009 -218.568456) (xy 356.612349 -218.616776) (xy 356.620108 -218.666874) (xy 356.620572 -218.692222)
			(xy 356.620064 -218.718129) (xy 356.611958 -218.769306) (xy 356.595946 -218.818585) (xy 356.572423 -218.864752)
			(xy 356.541967 -218.906671) (xy 356.505329 -218.943309) (xy 356.46341 -218.973765) (xy 356.417243 -218.997288)
			(xy 356.367964 -219.0133) (xy 356.316787 -219.021406) (xy 356.264973 -219.021406) (xy 356.213796 -219.0133)
			(xy 356.164517 -218.997288) (xy 356.11835 -218.973765) (xy 356.076431 -218.943309) (xy 356.039793 -218.906671)
			(xy 356.009337 -218.864752) (xy 355.985814 -218.818585) (xy 355.969802 -218.769306) (xy 355.961696 -218.718129)
			(xy 355.961188 -218.692222) (xy 355.961788 -218.664505) (xy 355.971107 -218.609859) (xy 355.97973 -218.58351)
			(xy 355.987604 -218.561412) (xy 355.782626 -218.206574) (xy 355.759766 -218.202256) (xy 355.734962 -218.197073)
			(xy 355.687224 -218.180081) (xy 355.642649 -218.155985) (xy 355.602284 -218.125353) (xy 355.567082 -218.088906)
			(xy 355.53787 -218.047502) (xy 355.515337 -218.002116) (xy 355.500013 -217.953817) (xy 355.49226 -217.903742)
			(xy 355.491796 -217.878406) (xy 355.210872 -217.878406) (xy 355.210364 -217.904293) (xy 355.202265 -217.955431)
			(xy 355.186266 -218.004671) (xy 355.16276 -218.050803) (xy 355.132328 -218.09269) (xy 355.095718 -218.1293)
			(xy 355.053831 -218.159732) (xy 355.007699 -218.183238) (xy 354.958459 -218.199237) (xy 354.907321 -218.207336)
			(xy 354.855547 -218.207336) (xy 354.804409 -218.199237) (xy 354.755169 -218.183238) (xy 354.709037 -218.159732)
			(xy 354.66715 -218.1293) (xy 354.63054 -218.09269) (xy 354.600108 -218.050803) (xy 354.576602 -218.004671)
			(xy 354.560603 -217.955431) (xy 354.552504 -217.904293) (xy 354.551996 -217.878406) (xy 354.271072 -217.878406)
			(xy 354.270541 -217.906114) (xy 354.261346 -217.960761) (xy 354.252784 -217.987118) (xy 354.24491 -218.009216)
			(xy 354.449888 -218.364054) (xy 354.472748 -218.368372) (xy 354.497563 -218.373563) (xy 354.545341 -218.390515)
			(xy 354.589959 -218.414584) (xy 354.630365 -218.445202) (xy 354.665606 -218.481645) (xy 354.69485 -218.523056)
			(xy 354.717409 -218.568456) (xy 354.732749 -218.616776) (xy 354.740508 -218.666874) (xy 354.740972 -218.692222)
			(xy 354.740464 -218.718129) (xy 354.732358 -218.769306) (xy 354.716346 -218.818585) (xy 354.692823 -218.864752)
			(xy 354.662367 -218.906671) (xy 354.625729 -218.943309) (xy 354.58381 -218.973765) (xy 354.537643 -218.997288)
			(xy 354.488364 -219.0133) (xy 354.437187 -219.021406) (xy 354.385373 -219.021406) (xy 354.334196 -219.0133)
			(xy 354.284917 -218.997288) (xy 354.23875 -218.973765) (xy 354.196831 -218.943309) (xy 354.160193 -218.906671)
			(xy 354.129737 -218.864752) (xy 354.106214 -218.818585) (xy 354.090202 -218.769306) (xy 354.082096 -218.718129)
			(xy 354.081588 -218.692222) (xy 354.082188 -218.664505) (xy 354.091507 -218.609859) (xy 354.10013 -218.58351)
			(xy 354.108004 -218.561412) (xy 353.903026 -218.206574) (xy 353.880166 -218.202256) (xy 353.855362 -218.197073)
			(xy 353.807624 -218.180081) (xy 353.763049 -218.155985) (xy 353.722684 -218.125353) (xy 353.687482 -218.088906)
			(xy 353.65827 -218.047502) (xy 353.635737 -218.002116) (xy 353.620413 -217.953817) (xy 353.61266 -217.903742)
			(xy 353.612196 -217.878406) (xy 353.331272 -217.878406) (xy 353.330764 -217.904293) (xy 353.322665 -217.955431)
			(xy 353.306666 -218.004671) (xy 353.28316 -218.050803) (xy 353.252728 -218.09269) (xy 353.216118 -218.1293)
			(xy 353.174231 -218.159732) (xy 353.128099 -218.183238) (xy 353.078859 -218.199237) (xy 353.027721 -218.207336)
			(xy 352.975947 -218.207336) (xy 352.924809 -218.199237) (xy 352.875569 -218.183238) (xy 352.829437 -218.159732)
			(xy 352.78755 -218.1293) (xy 352.75094 -218.09269) (xy 352.720508 -218.050803) (xy 352.697002 -218.004671)
			(xy 352.681003 -217.955431) (xy 352.672904 -217.904293) (xy 352.672396 -217.878406) (xy 352.391472 -217.878406)
			(xy 352.390941 -217.906114) (xy 352.381746 -217.960761) (xy 352.373184 -217.987118) (xy 352.36531 -218.009216)
			(xy 352.570288 -218.364054) (xy 352.593148 -218.368372) (xy 352.617963 -218.373563) (xy 352.665741 -218.390515)
			(xy 352.710359 -218.414584) (xy 352.750765 -218.445202) (xy 352.786006 -218.481645) (xy 352.81525 -218.523056)
			(xy 352.837809 -218.568456) (xy 352.853149 -218.616776) (xy 352.860908 -218.666874) (xy 352.861372 -218.692222)
			(xy 352.860864 -218.718129) (xy 352.852758 -218.769306) (xy 352.836746 -218.818585) (xy 352.813223 -218.864752)
			(xy 352.782767 -218.906671) (xy 352.746129 -218.943309) (xy 352.70421 -218.973765) (xy 352.658043 -218.997288)
			(xy 352.608764 -219.0133) (xy 352.557587 -219.021406) (xy 352.505773 -219.021406) (xy 352.454596 -219.0133)
			(xy 352.405317 -218.997288) (xy 352.35915 -218.973765) (xy 352.317231 -218.943309) (xy 352.280593 -218.906671)
			(xy 352.250137 -218.864752) (xy 352.226614 -218.818585) (xy 352.210602 -218.769306) (xy 352.202496 -218.718129)
			(xy 352.201988 -218.692222) (xy 352.202588 -218.664505) (xy 352.211907 -218.609859) (xy 352.22053 -218.58351)
			(xy 352.228404 -218.561412) (xy 352.023426 -218.206574) (xy 352.000566 -218.202256) (xy 351.975762 -218.197073)
			(xy 351.928024 -218.180081) (xy 351.883449 -218.155985) (xy 351.843084 -218.125353) (xy 351.807882 -218.088906)
			(xy 351.77867 -218.047502) (xy 351.756137 -218.002116) (xy 351.740813 -217.953817) (xy 351.73306 -217.903742)
			(xy 351.732596 -217.878406) (xy 351.451672 -217.878406) (xy 351.451164 -217.904293) (xy 351.443065 -217.955431)
			(xy 351.427066 -218.004671) (xy 351.40356 -218.050803) (xy 351.373128 -218.09269) (xy 351.336518 -218.1293)
			(xy 351.294631 -218.159732) (xy 351.248499 -218.183238) (xy 351.199259 -218.199237) (xy 351.148121 -218.207336)
			(xy 351.096347 -218.207336) (xy 351.045209 -218.199237) (xy 350.995969 -218.183238) (xy 350.949837 -218.159732)
			(xy 350.90795 -218.1293) (xy 350.87134 -218.09269) (xy 350.840908 -218.050803) (xy 350.817402 -218.004671)
			(xy 350.801403 -217.955431) (xy 350.793304 -217.904293) (xy 350.792796 -217.878406) (xy 350.511872 -217.878406)
			(xy 350.511341 -217.906114) (xy 350.502146 -217.960761) (xy 350.493584 -217.987118) (xy 350.48571 -218.009216)
			(xy 350.690688 -218.364054) (xy 350.713548 -218.368372) (xy 350.738363 -218.373563) (xy 350.786141 -218.390515)
			(xy 350.830759 -218.414584) (xy 350.871165 -218.445202) (xy 350.906406 -218.481645) (xy 350.93565 -218.523056)
			(xy 350.958209 -218.568456) (xy 350.973549 -218.616776) (xy 350.981308 -218.666874) (xy 350.981772 -218.692222)
			(xy 350.981264 -218.718129) (xy 350.973158 -218.769306) (xy 350.957146 -218.818585) (xy 350.933623 -218.864752)
			(xy 350.903167 -218.906671) (xy 350.866529 -218.943309) (xy 350.82461 -218.973765) (xy 350.778443 -218.997288)
			(xy 350.729164 -219.0133) (xy 350.677987 -219.021406) (xy 350.626173 -219.021406) (xy 350.574996 -219.0133)
			(xy 350.525717 -218.997288) (xy 350.47955 -218.973765) (xy 350.437631 -218.943309) (xy 350.400993 -218.906671)
			(xy 350.370537 -218.864752) (xy 350.347014 -218.818585) (xy 350.331002 -218.769306) (xy 350.322896 -218.718129)
			(xy 350.322388 -218.692222) (xy 350.322988 -218.664505) (xy 350.332307 -218.609859) (xy 350.34093 -218.58351)
			(xy 350.348804 -218.561412) (xy 350.143826 -218.206574) (xy 350.120966 -218.202256) (xy 350.096162 -218.197073)
			(xy 350.048424 -218.180081) (xy 350.003849 -218.155985) (xy 349.963484 -218.125353) (xy 349.928282 -218.088906)
			(xy 349.89907 -218.047502) (xy 349.876537 -218.002116) (xy 349.861213 -217.953817) (xy 349.85346 -217.903742)
			(xy 349.852996 -217.878406) (xy 349.572072 -217.878406) (xy 349.571564 -217.904293) (xy 349.563465 -217.955431)
			(xy 349.547466 -218.004671) (xy 349.52396 -218.050803) (xy 349.493528 -218.09269) (xy 349.456918 -218.1293)
			(xy 349.415031 -218.159732) (xy 349.368899 -218.183238) (xy 349.319659 -218.199237) (xy 349.268521 -218.207336)
			(xy 349.216747 -218.207336) (xy 349.165609 -218.199237) (xy 349.116369 -218.183238) (xy 349.070237 -218.159732)
			(xy 349.02835 -218.1293) (xy 348.99174 -218.09269) (xy 348.961308 -218.050803) (xy 348.937802 -218.004671)
			(xy 348.921803 -217.955431) (xy 348.913704 -217.904293) (xy 348.913196 -217.878406) (xy 348.632272 -217.878406)
			(xy 348.631741 -217.906114) (xy 348.622546 -217.960761) (xy 348.613984 -217.987118) (xy 348.60611 -218.009216)
			(xy 348.811088 -218.364054) (xy 348.833948 -218.368372) (xy 348.858763 -218.373563) (xy 348.906541 -218.390515)
			(xy 348.951159 -218.414584) (xy 348.991565 -218.445202) (xy 349.026806 -218.481645) (xy 349.05605 -218.523056)
			(xy 349.078609 -218.568456) (xy 349.093949 -218.616776) (xy 349.101708 -218.666874) (xy 349.102172 -218.692222)
			(xy 349.101664 -218.718129) (xy 349.093558 -218.769306) (xy 349.077546 -218.818585) (xy 349.054023 -218.864752)
			(xy 349.023567 -218.906671) (xy 348.986929 -218.943309) (xy 348.94501 -218.973765) (xy 348.898843 -218.997288)
			(xy 348.849564 -219.0133) (xy 348.798387 -219.021406) (xy 348.746573 -219.021406) (xy 348.695396 -219.0133)
			(xy 348.646117 -218.997288) (xy 348.59995 -218.973765) (xy 348.558031 -218.943309) (xy 348.521393 -218.906671)
			(xy 348.490937 -218.864752) (xy 348.467414 -218.818585) (xy 348.451402 -218.769306) (xy 348.443296 -218.718129)
			(xy 348.442788 -218.692222) (xy 348.443388 -218.664505) (xy 348.452707 -218.609859) (xy 348.46133 -218.58351)
			(xy 348.469204 -218.561412) (xy 348.264226 -218.206574) (xy 348.241366 -218.202256) (xy 348.216562 -218.197073)
			(xy 348.168824 -218.180081) (xy 348.124249 -218.155985) (xy 348.083884 -218.125353) (xy 348.048682 -218.088906)
			(xy 348.01947 -218.047502) (xy 347.996937 -218.002116) (xy 347.981613 -217.953817) (xy 347.97386 -217.903742)
			(xy 347.973396 -217.878406) (xy 347.692472 -217.878406) (xy 347.691964 -217.904293) (xy 347.683865 -217.955431)
			(xy 347.667866 -218.004671) (xy 347.64436 -218.050803) (xy 347.613928 -218.09269) (xy 347.577318 -218.1293)
			(xy 347.535431 -218.159732) (xy 347.489299 -218.183238) (xy 347.440059 -218.199237) (xy 347.388921 -218.207336)
			(xy 347.337147 -218.207336) (xy 347.286009 -218.199237) (xy 347.236769 -218.183238) (xy 347.190637 -218.159732)
			(xy 347.14875 -218.1293) (xy 347.11214 -218.09269) (xy 347.081708 -218.050803) (xy 347.058202 -218.004671)
			(xy 347.042203 -217.955431) (xy 347.034104 -217.904293) (xy 347.033596 -217.878406) (xy 346.752672 -217.878406)
			(xy 346.752141 -217.906114) (xy 346.742946 -217.960761) (xy 346.734384 -217.987118) (xy 346.72651 -218.009216)
			(xy 346.931488 -218.364054) (xy 346.954348 -218.368372) (xy 346.979163 -218.373563) (xy 347.026941 -218.390515)
			(xy 347.071559 -218.414584) (xy 347.111965 -218.445202) (xy 347.147206 -218.481645) (xy 347.17645 -218.523056)
			(xy 347.199009 -218.568456) (xy 347.214349 -218.616776) (xy 347.222108 -218.666874) (xy 347.222572 -218.692222)
			(xy 347.222064 -218.718129) (xy 347.213958 -218.769306) (xy 347.197946 -218.818585) (xy 347.174423 -218.864752)
			(xy 347.143967 -218.906671) (xy 347.107329 -218.943309) (xy 347.06541 -218.973765) (xy 347.019243 -218.997288)
			(xy 346.969964 -219.0133) (xy 346.918787 -219.021406) (xy 346.866973 -219.021406) (xy 346.815796 -219.0133)
			(xy 346.766517 -218.997288) (xy 346.72035 -218.973765) (xy 346.678431 -218.943309) (xy 346.641793 -218.906671)
			(xy 346.611337 -218.864752) (xy 346.587814 -218.818585) (xy 346.571802 -218.769306) (xy 346.563696 -218.718129)
			(xy 346.563188 -218.692222) (xy 346.563788 -218.664505) (xy 346.573107 -218.609859) (xy 346.58173 -218.58351)
			(xy 346.589604 -218.561412) (xy 346.384626 -218.206574) (xy 346.361766 -218.202256) (xy 346.336962 -218.197073)
			(xy 346.289224 -218.180081) (xy 346.244649 -218.155985) (xy 346.204284 -218.125353) (xy 346.169082 -218.088906)
			(xy 346.13987 -218.047502) (xy 346.117337 -218.002116) (xy 346.102013 -217.953817) (xy 346.09426 -217.903742)
			(xy 346.093796 -217.878406) (xy 345.812872 -217.878406) (xy 345.812364 -217.904293) (xy 345.804265 -217.955431)
			(xy 345.788266 -218.004671) (xy 345.76476 -218.050803) (xy 345.734328 -218.09269) (xy 345.697718 -218.1293)
			(xy 345.655831 -218.159732) (xy 345.609699 -218.183238) (xy 345.560459 -218.199237) (xy 345.509321 -218.207336)
			(xy 345.457547 -218.207336) (xy 345.406409 -218.199237) (xy 345.357169 -218.183238) (xy 345.311037 -218.159732)
			(xy 345.26915 -218.1293) (xy 345.23254 -218.09269) (xy 345.202108 -218.050803) (xy 345.178602 -218.004671)
			(xy 345.162603 -217.955431) (xy 345.154504 -217.904293) (xy 345.153996 -217.878406) (xy 344.873072 -217.878406)
			(xy 344.872541 -217.906114) (xy 344.863346 -217.960761) (xy 344.854784 -217.987118) (xy 344.84691 -218.009216)
			(xy 345.051888 -218.364054) (xy 345.074748 -218.368372) (xy 345.099563 -218.373563) (xy 345.147341 -218.390515)
			(xy 345.191959 -218.414584) (xy 345.232365 -218.445202) (xy 345.267606 -218.481645) (xy 345.29685 -218.523056)
			(xy 345.319409 -218.568456) (xy 345.334749 -218.616776) (xy 345.342508 -218.666874) (xy 345.342972 -218.692222)
			(xy 345.342464 -218.718129) (xy 345.334358 -218.769306) (xy 345.318346 -218.818585) (xy 345.294823 -218.864752)
			(xy 345.264367 -218.906671) (xy 345.227729 -218.943309) (xy 345.18581 -218.973765) (xy 345.139643 -218.997288)
			(xy 345.090364 -219.0133) (xy 345.039187 -219.021406) (xy 344.987373 -219.021406) (xy 344.936196 -219.0133)
			(xy 344.886917 -218.997288) (xy 344.84075 -218.973765) (xy 344.798831 -218.943309) (xy 344.762193 -218.906671)
			(xy 344.731737 -218.864752) (xy 344.708214 -218.818585) (xy 344.692202 -218.769306) (xy 344.684096 -218.718129)
			(xy 344.683588 -218.692222) (xy 344.684188 -218.664505) (xy 344.693507 -218.609859) (xy 344.70213 -218.58351)
			(xy 344.710004 -218.561412) (xy 344.505026 -218.206574) (xy 344.482166 -218.202256) (xy 344.457362 -218.197073)
			(xy 344.409624 -218.180081) (xy 344.365049 -218.155985) (xy 344.324684 -218.125353) (xy 344.289482 -218.088906)
			(xy 344.26027 -218.047502) (xy 344.237737 -218.002116) (xy 344.222413 -217.953817) (xy 344.21466 -217.903742)
			(xy 344.214196 -217.878406) (xy 343.933272 -217.878406) (xy 343.932764 -217.904293) (xy 343.924665 -217.955431)
			(xy 343.908666 -218.004671) (xy 343.88516 -218.050803) (xy 343.854728 -218.09269) (xy 343.818118 -218.1293)
			(xy 343.776231 -218.159732) (xy 343.730099 -218.183238) (xy 343.680859 -218.199237) (xy 343.629721 -218.207336)
			(xy 343.577947 -218.207336) (xy 343.526809 -218.199237) (xy 343.477569 -218.183238) (xy 343.431437 -218.159732)
			(xy 343.38955 -218.1293) (xy 343.35294 -218.09269) (xy 343.322508 -218.050803) (xy 343.299002 -218.004671)
			(xy 343.283003 -217.955431) (xy 343.274904 -217.904293) (xy 343.274396 -217.878406) (xy 342.993472 -217.878406)
			(xy 342.992941 -217.906114) (xy 342.983746 -217.960761) (xy 342.975184 -217.987118) (xy 342.96731 -218.009216)
			(xy 343.172288 -218.364054) (xy 343.195148 -218.368372) (xy 343.219963 -218.373563) (xy 343.267741 -218.390515)
			(xy 343.312359 -218.414584) (xy 343.352765 -218.445202) (xy 343.388006 -218.481645) (xy 343.41725 -218.523056)
			(xy 343.439809 -218.568456) (xy 343.455149 -218.616776) (xy 343.462908 -218.666874) (xy 343.463372 -218.692222)
			(xy 343.462864 -218.718129) (xy 343.454758 -218.769306) (xy 343.438746 -218.818585) (xy 343.415223 -218.864752)
			(xy 343.384767 -218.906671) (xy 343.348129 -218.943309) (xy 343.30621 -218.973765) (xy 343.260043 -218.997288)
			(xy 343.210764 -219.0133) (xy 343.159587 -219.021406) (xy 343.107773 -219.021406) (xy 343.056596 -219.0133)
			(xy 343.007317 -218.997288) (xy 342.96115 -218.973765) (xy 342.919231 -218.943309) (xy 342.882593 -218.906671)
			(xy 342.852137 -218.864752) (xy 342.828614 -218.818585) (xy 342.812602 -218.769306) (xy 342.804496 -218.718129)
			(xy 342.803988 -218.692222) (xy 342.804588 -218.664505) (xy 342.813907 -218.609859) (xy 342.82253 -218.58351)
			(xy 342.830404 -218.561412) (xy 342.625426 -218.206574) (xy 342.602566 -218.202256) (xy 342.577762 -218.197073)
			(xy 342.530024 -218.180081) (xy 342.485449 -218.155985) (xy 342.445084 -218.125353) (xy 342.409882 -218.088906)
			(xy 342.38067 -218.047502) (xy 342.358137 -218.002116) (xy 342.342813 -217.953817) (xy 342.33506 -217.903742)
			(xy 342.334596 -217.878406) (xy 342.053672 -217.878406) (xy 342.053164 -217.904293) (xy 342.045065 -217.955431)
			(xy 342.029066 -218.004671) (xy 342.00556 -218.050803) (xy 341.975128 -218.09269) (xy 341.938518 -218.1293)
			(xy 341.896631 -218.159732) (xy 341.850499 -218.183238) (xy 341.801259 -218.199237) (xy 341.750121 -218.207336)
			(xy 341.698347 -218.207336) (xy 341.647209 -218.199237) (xy 341.597969 -218.183238) (xy 341.551837 -218.159732)
			(xy 341.50995 -218.1293) (xy 341.47334 -218.09269) (xy 341.442908 -218.050803) (xy 341.419402 -218.004671)
			(xy 341.403403 -217.955431) (xy 341.395304 -217.904293) (xy 341.394796 -217.878406) (xy 341.113872 -217.878406)
			(xy 341.113341 -217.906114) (xy 341.104146 -217.960761) (xy 341.095584 -217.987118) (xy 341.08771 -218.009216)
			(xy 341.292688 -218.364054) (xy 341.315548 -218.368372) (xy 341.340363 -218.373563) (xy 341.388141 -218.390515)
			(xy 341.432759 -218.414584) (xy 341.473165 -218.445202) (xy 341.508406 -218.481645) (xy 341.53765 -218.523056)
			(xy 341.560209 -218.568456) (xy 341.575549 -218.616776) (xy 341.583308 -218.666874) (xy 341.583772 -218.692222)
			(xy 341.583264 -218.718129) (xy 341.575158 -218.769306) (xy 341.559146 -218.818585) (xy 341.535623 -218.864752)
			(xy 341.505167 -218.906671) (xy 341.468529 -218.943309) (xy 341.42661 -218.973765) (xy 341.380443 -218.997288)
			(xy 341.331164 -219.0133) (xy 341.279987 -219.021406) (xy 341.228173 -219.021406) (xy 341.176996 -219.0133)
			(xy 341.127717 -218.997288) (xy 341.08155 -218.973765) (xy 341.039631 -218.943309) (xy 341.002993 -218.906671)
			(xy 340.972537 -218.864752) (xy 340.949014 -218.818585) (xy 340.933002 -218.769306) (xy 340.924896 -218.718129)
			(xy 340.924388 -218.692222) (xy 340.924988 -218.664505) (xy 340.934307 -218.609859) (xy 340.94293 -218.58351)
			(xy 340.950804 -218.561412) (xy 340.745826 -218.206574) (xy 340.722966 -218.202256) (xy 340.698162 -218.197073)
			(xy 340.650424 -218.180081) (xy 340.605849 -218.155985) (xy 340.565484 -218.125353) (xy 340.530282 -218.088906)
			(xy 340.50107 -218.047502) (xy 340.478537 -218.002116) (xy 340.463213 -217.953817) (xy 340.45546 -217.903742)
			(xy 340.454996 -217.878406) (xy 340.174072 -217.878406) (xy 340.173564 -217.904293) (xy 340.165465 -217.955431)
			(xy 340.149466 -218.004671) (xy 340.12596 -218.050803) (xy 340.095528 -218.09269) (xy 340.058918 -218.1293)
			(xy 340.017031 -218.159732) (xy 339.970899 -218.183238) (xy 339.921659 -218.199237) (xy 339.870521 -218.207336)
			(xy 339.818747 -218.207336) (xy 339.767609 -218.199237) (xy 339.718369 -218.183238) (xy 339.672237 -218.159732)
			(xy 339.63035 -218.1293) (xy 339.59374 -218.09269) (xy 339.563308 -218.050803) (xy 339.539802 -218.004671)
			(xy 339.523803 -217.955431) (xy 339.515704 -217.904293) (xy 339.515196 -217.878406) (xy 339.234272 -217.878406)
			(xy 339.233741 -217.906114) (xy 339.224546 -217.960761) (xy 339.215984 -217.987118) (xy 339.20811 -218.009216)
			(xy 339.413088 -218.364054) (xy 339.435948 -218.368372) (xy 339.460763 -218.373563) (xy 339.508541 -218.390515)
			(xy 339.553159 -218.414584) (xy 339.593565 -218.445202) (xy 339.628806 -218.481645) (xy 339.65805 -218.523056)
			(xy 339.680609 -218.568456) (xy 339.695949 -218.616776) (xy 339.703708 -218.666874) (xy 339.704172 -218.692222)
			(xy 339.703664 -218.718129) (xy 339.695558 -218.769306) (xy 339.679546 -218.818585) (xy 339.656023 -218.864752)
			(xy 339.625567 -218.906671) (xy 339.588929 -218.943309) (xy 339.54701 -218.973765) (xy 339.500843 -218.997288)
			(xy 339.451564 -219.0133) (xy 339.400387 -219.021406) (xy 339.348573 -219.021406) (xy 339.297396 -219.0133)
			(xy 339.248117 -218.997288) (xy 339.20195 -218.973765) (xy 339.160031 -218.943309) (xy 339.123393 -218.906671)
			(xy 339.092937 -218.864752) (xy 339.069414 -218.818585) (xy 339.053402 -218.769306) (xy 339.045296 -218.718129)
			(xy 339.044788 -218.692222) (xy 339.045388 -218.664505) (xy 339.054707 -218.609859) (xy 339.06333 -218.58351)
			(xy 339.071204 -218.561412) (xy 338.866226 -218.206574) (xy 338.843366 -218.202256) (xy 338.818562 -218.197073)
			(xy 338.770824 -218.180081) (xy 338.726249 -218.155985) (xy 338.685884 -218.125353) (xy 338.650682 -218.088906)
			(xy 338.62147 -218.047502) (xy 338.598937 -218.002116) (xy 338.583613 -217.953817) (xy 338.57586 -217.903742)
			(xy 338.575396 -217.878406) (xy 338.294472 -217.878406) (xy 338.293964 -217.904293) (xy 338.285865 -217.955431)
			(xy 338.269866 -218.004671) (xy 338.24636 -218.050803) (xy 338.215928 -218.09269) (xy 338.179318 -218.1293)
			(xy 338.137431 -218.159732) (xy 338.091299 -218.183238) (xy 338.042059 -218.199237) (xy 337.990921 -218.207336)
			(xy 337.939147 -218.207336) (xy 337.888009 -218.199237) (xy 337.838769 -218.183238) (xy 337.792637 -218.159732)
			(xy 337.75075 -218.1293) (xy 337.71414 -218.09269) (xy 337.683708 -218.050803) (xy 337.660202 -218.004671)
			(xy 337.644203 -217.955431) (xy 337.636104 -217.904293) (xy 337.635596 -217.878406) (xy 337.354672 -217.878406)
			(xy 337.354141 -217.906114) (xy 337.344946 -217.960761) (xy 337.336384 -217.987118) (xy 337.32851 -218.009216)
			(xy 337.533488 -218.364054) (xy 337.556348 -218.368372) (xy 337.581163 -218.373563) (xy 337.628941 -218.390515)
			(xy 337.673559 -218.414584) (xy 337.713965 -218.445202) (xy 337.749206 -218.481645) (xy 337.77845 -218.523056)
			(xy 337.801009 -218.568456) (xy 337.816349 -218.616776) (xy 337.824108 -218.666874) (xy 337.824572 -218.692222)
			(xy 337.824064 -218.718129) (xy 337.815958 -218.769306) (xy 337.799946 -218.818585) (xy 337.776423 -218.864752)
			(xy 337.745967 -218.906671) (xy 337.709329 -218.943309) (xy 337.66741 -218.973765) (xy 337.621243 -218.997288)
			(xy 337.571964 -219.0133) (xy 337.520787 -219.021406) (xy 337.468973 -219.021406) (xy 337.417796 -219.0133)
			(xy 337.368517 -218.997288) (xy 337.32235 -218.973765) (xy 337.280431 -218.943309) (xy 337.243793 -218.906671)
			(xy 337.213337 -218.864752) (xy 337.189814 -218.818585) (xy 337.173802 -218.769306) (xy 337.165696 -218.718129)
			(xy 337.165188 -218.692222) (xy 337.165788 -218.664505) (xy 337.175107 -218.609859) (xy 337.18373 -218.58351)
			(xy 337.191604 -218.561412) (xy 336.986626 -218.206574) (xy 336.963766 -218.202256) (xy 336.938962 -218.197073)
			(xy 336.891224 -218.180081) (xy 336.846649 -218.155985) (xy 336.806284 -218.125353) (xy 336.771082 -218.088906)
			(xy 336.74187 -218.047502) (xy 336.719337 -218.002116) (xy 336.704013 -217.953817) (xy 336.69626 -217.903742)
			(xy 336.695796 -217.878406) (xy 134.525004 -217.878406) (xy 134.524496 -217.904293) (xy 134.516397 -217.955431)
			(xy 134.500398 -218.004671) (xy 134.476892 -218.050803) (xy 134.44646 -218.09269) (xy 134.40985 -218.1293)
			(xy 134.367963 -218.159732) (xy 134.321831 -218.183238) (xy 134.272591 -218.199237) (xy 134.221453 -218.207336)
			(xy 134.169679 -218.207336) (xy 134.118541 -218.199237) (xy 134.069301 -218.183238) (xy 134.023169 -218.159732)
			(xy 133.981282 -218.1293) (xy 133.944672 -218.09269) (xy 133.91424 -218.050803) (xy 133.890734 -218.004671)
			(xy 133.874735 -217.955431) (xy 133.866636 -217.904293) (xy 133.866128 -217.878406) (xy 133.866662 -217.850698)
			(xy 133.875855 -217.796051) (xy 133.884416 -217.769694) (xy 133.89229 -217.747596) (xy 133.687312 -217.392504)
			(xy 133.664452 -217.388186) (xy 133.639596 -217.383069) (xy 133.591748 -217.366166) (xy 133.547056 -217.342128)
			(xy 133.506577 -217.311523) (xy 133.471267 -217.275076) (xy 133.441961 -217.233647) (xy 133.419352 -217.188215)
			(xy 133.403974 -217.139855) (xy 133.39619 -217.089709) (xy 133.39572 -217.064336) (xy 132.175504 -217.064336)
			(xy 132.174889 -217.091989) (xy 132.165569 -217.146507) (xy 132.156962 -217.172794) (xy 132.149342 -217.194892)
			(xy 132.354574 -217.550238) (xy 132.377434 -217.554556) (xy 132.402241 -217.559728) (xy 132.449979 -217.576721)
			(xy 132.494556 -217.600818) (xy 132.53492 -217.631451) (xy 132.570123 -217.6679) (xy 132.599334 -217.709305)
			(xy 132.621866 -217.754693) (xy 132.637189 -217.802993) (xy 132.644941 -217.85307) (xy 132.645404 -217.878406)
			(xy 132.644896 -217.904293) (xy 132.636797 -217.955431) (xy 132.620798 -218.004671) (xy 132.597292 -218.050803)
			(xy 132.56686 -218.09269) (xy 132.53025 -218.1293) (xy 132.488363 -218.159732) (xy 132.442231 -218.183238)
			(xy 132.392991 -218.199237) (xy 132.341853 -218.207336) (xy 132.290079 -218.207336) (xy 132.238941 -218.199237)
			(xy 132.189701 -218.183238) (xy 132.143569 -218.159732) (xy 132.101682 -218.1293) (xy 132.065072 -218.09269)
			(xy 132.03464 -218.050803) (xy 132.011134 -218.004671) (xy 131.995135 -217.955431) (xy 131.987036 -217.904293)
			(xy 131.986528 -217.878406) (xy 131.987062 -217.850698) (xy 131.996255 -217.796051) (xy 132.004816 -217.769694)
			(xy 132.01269 -217.747596) (xy 131.807712 -217.392504) (xy 131.784852 -217.388186) (xy 131.759996 -217.383069)
			(xy 131.712148 -217.366166) (xy 131.667456 -217.342128) (xy 131.626977 -217.311523) (xy 131.591667 -217.275076)
			(xy 131.562361 -217.233647) (xy 131.539752 -217.188215) (xy 131.524374 -217.139855) (xy 131.51659 -217.089709)
			(xy 131.51612 -217.064336) (xy 130.295904 -217.064336) (xy 130.295289 -217.091989) (xy 130.285969 -217.146507)
			(xy 130.277362 -217.172794) (xy 130.269742 -217.194892) (xy 130.474974 -217.550238) (xy 130.497834 -217.554556)
			(xy 130.522641 -217.559728) (xy 130.570379 -217.576721) (xy 130.614956 -217.600818) (xy 130.65532 -217.631451)
			(xy 130.690523 -217.6679) (xy 130.719734 -217.709305) (xy 130.742266 -217.754693) (xy 130.757589 -217.802993)
			(xy 130.765341 -217.85307) (xy 130.765804 -217.878406) (xy 130.765296 -217.904293) (xy 130.757197 -217.955431)
			(xy 130.741198 -218.004671) (xy 130.717692 -218.050803) (xy 130.68726 -218.09269) (xy 130.65065 -218.1293)
			(xy 130.608763 -218.159732) (xy 130.562631 -218.183238) (xy 130.513391 -218.199237) (xy 130.462253 -218.207336)
			(xy 130.410479 -218.207336) (xy 130.359341 -218.199237) (xy 130.310101 -218.183238) (xy 130.263969 -218.159732)
			(xy 130.222082 -218.1293) (xy 130.185472 -218.09269) (xy 130.15504 -218.050803) (xy 130.131534 -218.004671)
			(xy 130.115535 -217.955431) (xy 130.107436 -217.904293) (xy 130.106928 -217.878406) (xy 130.107462 -217.850698)
			(xy 130.116655 -217.796051) (xy 130.125216 -217.769694) (xy 130.13309 -217.747596) (xy 129.928112 -217.392504)
			(xy 129.905252 -217.388186) (xy 129.880396 -217.383069) (xy 129.832548 -217.366166) (xy 129.787856 -217.342128)
			(xy 129.747377 -217.311523) (xy 129.712067 -217.275076) (xy 129.682761 -217.233647) (xy 129.660152 -217.188215)
			(xy 129.644774 -217.139855) (xy 129.63699 -217.089709) (xy 129.63652 -217.064336) (xy 128.416304 -217.064336)
			(xy 128.415689 -217.091989) (xy 128.406369 -217.146507) (xy 128.397762 -217.172794) (xy 128.390142 -217.194892)
			(xy 128.595374 -217.550238) (xy 128.618234 -217.554556) (xy 128.643041 -217.559728) (xy 128.690779 -217.576721)
			(xy 128.735356 -217.600818) (xy 128.77572 -217.631451) (xy 128.810923 -217.6679) (xy 128.840134 -217.709305)
			(xy 128.862666 -217.754693) (xy 128.877989 -217.802993) (xy 128.885741 -217.85307) (xy 128.886204 -217.878406)
			(xy 128.885696 -217.904293) (xy 128.877597 -217.955431) (xy 128.861598 -218.004671) (xy 128.838092 -218.050803)
			(xy 128.80766 -218.09269) (xy 128.77105 -218.1293) (xy 128.729163 -218.159732) (xy 128.683031 -218.183238)
			(xy 128.633791 -218.199237) (xy 128.582653 -218.207336) (xy 128.530879 -218.207336) (xy 128.479741 -218.199237)
			(xy 128.430501 -218.183238) (xy 128.384369 -218.159732) (xy 128.342482 -218.1293) (xy 128.305872 -218.09269)
			(xy 128.27544 -218.050803) (xy 128.251934 -218.004671) (xy 128.235935 -217.955431) (xy 128.227836 -217.904293)
			(xy 128.227328 -217.878406) (xy 128.227862 -217.850698) (xy 128.237055 -217.796051) (xy 128.245616 -217.769694)
			(xy 128.25349 -217.747596) (xy 128.048512 -217.392504) (xy 128.025652 -217.388186) (xy 128.000796 -217.383069)
			(xy 127.952948 -217.366166) (xy 127.908256 -217.342128) (xy 127.867777 -217.311523) (xy 127.832467 -217.275076)
			(xy 127.803161 -217.233647) (xy 127.780552 -217.188215) (xy 127.765174 -217.139855) (xy 127.75739 -217.089709)
			(xy 127.75692 -217.064336) (xy 126.536704 -217.064336) (xy 126.536089 -217.091989) (xy 126.526769 -217.146507)
			(xy 126.518162 -217.172794) (xy 126.510542 -217.194892) (xy 126.715774 -217.550238) (xy 126.738634 -217.554556)
			(xy 126.763441 -217.559728) (xy 126.811179 -217.576721) (xy 126.855756 -217.600818) (xy 126.89612 -217.631451)
			(xy 126.931323 -217.6679) (xy 126.960534 -217.709305) (xy 126.983066 -217.754693) (xy 126.998389 -217.802993)
			(xy 127.006141 -217.85307) (xy 127.006604 -217.878406) (xy 127.006096 -217.904293) (xy 126.997997 -217.955431)
			(xy 126.981998 -218.004671) (xy 126.958492 -218.050803) (xy 126.92806 -218.09269) (xy 126.89145 -218.1293)
			(xy 126.849563 -218.159732) (xy 126.803431 -218.183238) (xy 126.754191 -218.199237) (xy 126.703053 -218.207336)
			(xy 126.651279 -218.207336) (xy 126.600141 -218.199237) (xy 126.550901 -218.183238) (xy 126.504769 -218.159732)
			(xy 126.462882 -218.1293) (xy 126.426272 -218.09269) (xy 126.39584 -218.050803) (xy 126.372334 -218.004671)
			(xy 126.356335 -217.955431) (xy 126.348236 -217.904293) (xy 126.347728 -217.878406) (xy 126.348262 -217.850698)
			(xy 126.357455 -217.796051) (xy 126.366016 -217.769694) (xy 126.37389 -217.747596) (xy 126.168912 -217.392504)
			(xy 126.146052 -217.388186) (xy 126.121196 -217.383069) (xy 126.073348 -217.366166) (xy 126.028656 -217.342128)
			(xy 125.988177 -217.311523) (xy 125.952867 -217.275076) (xy 125.923561 -217.233647) (xy 125.900952 -217.188215)
			(xy 125.885574 -217.139855) (xy 125.87779 -217.089709) (xy 125.87732 -217.064336) (xy 124.657104 -217.064336)
			(xy 124.656489 -217.091989) (xy 124.647169 -217.146507) (xy 124.638562 -217.172794) (xy 124.630942 -217.194892)
			(xy 124.836174 -217.550238) (xy 124.859034 -217.554556) (xy 124.883841 -217.559728) (xy 124.931579 -217.576721)
			(xy 124.976156 -217.600818) (xy 125.01652 -217.631451) (xy 125.051723 -217.6679) (xy 125.080934 -217.709305)
			(xy 125.103466 -217.754693) (xy 125.118789 -217.802993) (xy 125.126541 -217.85307) (xy 125.127004 -217.878406)
			(xy 125.126496 -217.904293) (xy 125.118397 -217.955431) (xy 125.102398 -218.004671) (xy 125.078892 -218.050803)
			(xy 125.04846 -218.09269) (xy 125.01185 -218.1293) (xy 124.969963 -218.159732) (xy 124.923831 -218.183238)
			(xy 124.874591 -218.199237) (xy 124.823453 -218.207336) (xy 124.771679 -218.207336) (xy 124.720541 -218.199237)
			(xy 124.671301 -218.183238) (xy 124.625169 -218.159732) (xy 124.583282 -218.1293) (xy 124.546672 -218.09269)
			(xy 124.51624 -218.050803) (xy 124.492734 -218.004671) (xy 124.476735 -217.955431) (xy 124.468636 -217.904293)
			(xy 124.468128 -217.878406) (xy 124.468662 -217.850698) (xy 124.477855 -217.796051) (xy 124.486416 -217.769694)
			(xy 124.49429 -217.747596) (xy 124.289312 -217.392504) (xy 124.266452 -217.388186) (xy 124.241596 -217.383069)
			(xy 124.193748 -217.366166) (xy 124.149056 -217.342128) (xy 124.108577 -217.311523) (xy 124.073267 -217.275076)
			(xy 124.043961 -217.233647) (xy 124.021352 -217.188215) (xy 124.005974 -217.139855) (xy 123.99819 -217.089709)
			(xy 123.99772 -217.064336) (xy 122.777504 -217.064336) (xy 122.776889 -217.091989) (xy 122.767569 -217.146507)
			(xy 122.758962 -217.172794) (xy 122.751342 -217.194892) (xy 122.956574 -217.550238) (xy 122.979434 -217.554556)
			(xy 123.004241 -217.559728) (xy 123.051979 -217.576721) (xy 123.096556 -217.600818) (xy 123.13692 -217.631451)
			(xy 123.172123 -217.6679) (xy 123.201334 -217.709305) (xy 123.223866 -217.754693) (xy 123.239189 -217.802993)
			(xy 123.246941 -217.85307) (xy 123.247404 -217.878406) (xy 123.246896 -217.904293) (xy 123.238797 -217.955431)
			(xy 123.222798 -218.004671) (xy 123.199292 -218.050803) (xy 123.16886 -218.09269) (xy 123.13225 -218.1293)
			(xy 123.090363 -218.159732) (xy 123.044231 -218.183238) (xy 122.994991 -218.199237) (xy 122.943853 -218.207336)
			(xy 122.892079 -218.207336) (xy 122.840941 -218.199237) (xy 122.791701 -218.183238) (xy 122.745569 -218.159732)
			(xy 122.703682 -218.1293) (xy 122.667072 -218.09269) (xy 122.63664 -218.050803) (xy 122.613134 -218.004671)
			(xy 122.597135 -217.955431) (xy 122.589036 -217.904293) (xy 122.588528 -217.878406) (xy 122.589062 -217.850698)
			(xy 122.598255 -217.796051) (xy 122.606816 -217.769694) (xy 122.61469 -217.747596) (xy 122.409712 -217.392504)
			(xy 122.386852 -217.388186) (xy 122.361996 -217.383069) (xy 122.314148 -217.366166) (xy 122.269456 -217.342128)
			(xy 122.228977 -217.311523) (xy 122.193667 -217.275076) (xy 122.164361 -217.233647) (xy 122.141752 -217.188215)
			(xy 122.126374 -217.139855) (xy 122.11859 -217.089709) (xy 122.11812 -217.064336) (xy 120.897904 -217.064336)
			(xy 120.897289 -217.091989) (xy 120.887969 -217.146507) (xy 120.879362 -217.172794) (xy 120.871742 -217.194892)
			(xy 121.076974 -217.550238) (xy 121.099834 -217.554556) (xy 121.124641 -217.559728) (xy 121.172379 -217.576721)
			(xy 121.216956 -217.600818) (xy 121.25732 -217.631451) (xy 121.292523 -217.6679) (xy 121.321734 -217.709305)
			(xy 121.344266 -217.754693) (xy 121.359589 -217.802993) (xy 121.367341 -217.85307) (xy 121.367804 -217.878406)
			(xy 121.367296 -217.904293) (xy 121.359197 -217.955431) (xy 121.343198 -218.004671) (xy 121.319692 -218.050803)
			(xy 121.28926 -218.09269) (xy 121.25265 -218.1293) (xy 121.210763 -218.159732) (xy 121.164631 -218.183238)
			(xy 121.115391 -218.199237) (xy 121.064253 -218.207336) (xy 121.012479 -218.207336) (xy 120.961341 -218.199237)
			(xy 120.912101 -218.183238) (xy 120.865969 -218.159732) (xy 120.824082 -218.1293) (xy 120.787472 -218.09269)
			(xy 120.75704 -218.050803) (xy 120.733534 -218.004671) (xy 120.717535 -217.955431) (xy 120.709436 -217.904293)
			(xy 120.708928 -217.878406) (xy 120.709462 -217.850698) (xy 120.718655 -217.796051) (xy 120.727216 -217.769694)
			(xy 120.73509 -217.747596) (xy 120.530112 -217.392504) (xy 120.507252 -217.388186) (xy 120.482396 -217.383069)
			(xy 120.434548 -217.366166) (xy 120.389856 -217.342128) (xy 120.349377 -217.311523) (xy 120.314067 -217.275076)
			(xy 120.284761 -217.233647) (xy 120.262152 -217.188215) (xy 120.246774 -217.139855) (xy 120.23899 -217.089709)
			(xy 120.23852 -217.064336) (xy 119.018304 -217.064336) (xy 119.017689 -217.091989) (xy 119.008369 -217.146507)
			(xy 118.999762 -217.172794) (xy 118.992142 -217.194892) (xy 119.197374 -217.550238) (xy 119.220234 -217.554556)
			(xy 119.245041 -217.559728) (xy 119.292779 -217.576721) (xy 119.337356 -217.600818) (xy 119.37772 -217.631451)
			(xy 119.412923 -217.6679) (xy 119.442134 -217.709305) (xy 119.464666 -217.754693) (xy 119.479989 -217.802993)
			(xy 119.487741 -217.85307) (xy 119.488204 -217.878406) (xy 119.487696 -217.904293) (xy 119.479597 -217.955431)
			(xy 119.463598 -218.004671) (xy 119.440092 -218.050803) (xy 119.40966 -218.09269) (xy 119.37305 -218.1293)
			(xy 119.331163 -218.159732) (xy 119.285031 -218.183238) (xy 119.235791 -218.199237) (xy 119.184653 -218.207336)
			(xy 119.132879 -218.207336) (xy 119.081741 -218.199237) (xy 119.032501 -218.183238) (xy 118.986369 -218.159732)
			(xy 118.944482 -218.1293) (xy 118.907872 -218.09269) (xy 118.87744 -218.050803) (xy 118.853934 -218.004671)
			(xy 118.837935 -217.955431) (xy 118.829836 -217.904293) (xy 118.829328 -217.878406) (xy 118.829862 -217.850698)
			(xy 118.839055 -217.796051) (xy 118.847616 -217.769694) (xy 118.85549 -217.747596) (xy 118.650512 -217.392504)
			(xy 118.627652 -217.388186) (xy 118.602796 -217.383069) (xy 118.554948 -217.366166) (xy 118.510256 -217.342128)
			(xy 118.469777 -217.311523) (xy 118.434467 -217.275076) (xy 118.405161 -217.233647) (xy 118.382552 -217.188215)
			(xy 118.367174 -217.139855) (xy 118.35939 -217.089709) (xy 118.35892 -217.064336) (xy 117.138704 -217.064336)
			(xy 117.138089 -217.091989) (xy 117.128769 -217.146507) (xy 117.120162 -217.172794) (xy 117.112542 -217.194892)
			(xy 117.317774 -217.550238) (xy 117.340634 -217.554556) (xy 117.365441 -217.559728) (xy 117.413179 -217.576721)
			(xy 117.457756 -217.600818) (xy 117.49812 -217.631451) (xy 117.533323 -217.6679) (xy 117.562534 -217.709305)
			(xy 117.585066 -217.754693) (xy 117.600389 -217.802993) (xy 117.608141 -217.85307) (xy 117.608604 -217.878406)
			(xy 117.608096 -217.904293) (xy 117.599997 -217.955431) (xy 117.583998 -218.004671) (xy 117.560492 -218.050803)
			(xy 117.53006 -218.09269) (xy 117.49345 -218.1293) (xy 117.451563 -218.159732) (xy 117.405431 -218.183238)
			(xy 117.356191 -218.199237) (xy 117.305053 -218.207336) (xy 117.253279 -218.207336) (xy 117.202141 -218.199237)
			(xy 117.152901 -218.183238) (xy 117.106769 -218.159732) (xy 117.064882 -218.1293) (xy 117.028272 -218.09269)
			(xy 116.99784 -218.050803) (xy 116.974334 -218.004671) (xy 116.958335 -217.955431) (xy 116.950236 -217.904293)
			(xy 116.949728 -217.878406) (xy 116.950262 -217.850698) (xy 116.959455 -217.796051) (xy 116.968016 -217.769694)
			(xy 116.97589 -217.747596) (xy 116.770912 -217.392504) (xy 116.748052 -217.388186) (xy 116.723196 -217.383069)
			(xy 116.675348 -217.366166) (xy 116.630656 -217.342128) (xy 116.590177 -217.311523) (xy 116.554867 -217.275076)
			(xy 116.525561 -217.233647) (xy 116.502952 -217.188215) (xy 116.487574 -217.139855) (xy 116.47979 -217.089709)
			(xy 116.47932 -217.064336) (xy 115.259104 -217.064336) (xy 115.258489 -217.091989) (xy 115.249169 -217.146507)
			(xy 115.240562 -217.172794) (xy 115.232942 -217.194892) (xy 115.438174 -217.550238) (xy 115.461034 -217.554556)
			(xy 115.485841 -217.559728) (xy 115.533579 -217.576721) (xy 115.578156 -217.600818) (xy 115.61852 -217.631451)
			(xy 115.653723 -217.6679) (xy 115.682934 -217.709305) (xy 115.705466 -217.754693) (xy 115.720789 -217.802993)
			(xy 115.728541 -217.85307) (xy 115.729004 -217.878406) (xy 115.728496 -217.904293) (xy 115.720397 -217.955431)
			(xy 115.704398 -218.004671) (xy 115.680892 -218.050803) (xy 115.65046 -218.09269) (xy 115.61385 -218.1293)
			(xy 115.571963 -218.159732) (xy 115.525831 -218.183238) (xy 115.476591 -218.199237) (xy 115.425453 -218.207336)
			(xy 115.373679 -218.207336) (xy 115.322541 -218.199237) (xy 115.273301 -218.183238) (xy 115.227169 -218.159732)
			(xy 115.185282 -218.1293) (xy 115.148672 -218.09269) (xy 115.11824 -218.050803) (xy 115.094734 -218.004671)
			(xy 115.078735 -217.955431) (xy 115.070636 -217.904293) (xy 115.070128 -217.878406) (xy 115.070662 -217.850698)
			(xy 115.079855 -217.796051) (xy 115.088416 -217.769694) (xy 115.09629 -217.747596) (xy 114.891312 -217.392504)
			(xy 114.868452 -217.388186) (xy 114.843596 -217.383069) (xy 114.795748 -217.366166) (xy 114.751056 -217.342128)
			(xy 114.710577 -217.311523) (xy 114.675267 -217.275076) (xy 114.645961 -217.233647) (xy 114.623352 -217.188215)
			(xy 114.607974 -217.139855) (xy 114.60019 -217.089709) (xy 114.59972 -217.064336) (xy 113.379504 -217.064336)
			(xy 113.378889 -217.091989) (xy 113.369569 -217.146507) (xy 113.360962 -217.172794) (xy 113.353342 -217.194892)
			(xy 113.558574 -217.550238) (xy 113.581434 -217.554556) (xy 113.606241 -217.559728) (xy 113.653979 -217.576721)
			(xy 113.698556 -217.600818) (xy 113.73892 -217.631451) (xy 113.774123 -217.6679) (xy 113.803334 -217.709305)
			(xy 113.825866 -217.754693) (xy 113.841189 -217.802993) (xy 113.848941 -217.85307) (xy 113.849404 -217.878406)
			(xy 113.848896 -217.904293) (xy 113.840797 -217.955431) (xy 113.824798 -218.004671) (xy 113.801292 -218.050803)
			(xy 113.77086 -218.09269) (xy 113.73425 -218.1293) (xy 113.692363 -218.159732) (xy 113.646231 -218.183238)
			(xy 113.596991 -218.199237) (xy 113.545853 -218.207336) (xy 113.494079 -218.207336) (xy 113.442941 -218.199237)
			(xy 113.393701 -218.183238) (xy 113.347569 -218.159732) (xy 113.305682 -218.1293) (xy 113.269072 -218.09269)
			(xy 113.23864 -218.050803) (xy 113.215134 -218.004671) (xy 113.199135 -217.955431) (xy 113.191036 -217.904293)
			(xy 113.190528 -217.878406) (xy 113.191062 -217.850698) (xy 113.200255 -217.796051) (xy 113.208816 -217.769694)
			(xy 113.21669 -217.747596) (xy 113.011712 -217.392504) (xy 112.988852 -217.388186) (xy 112.963996 -217.383069)
			(xy 112.916148 -217.366166) (xy 112.871456 -217.342128) (xy 112.830977 -217.311523) (xy 112.795667 -217.275076)
			(xy 112.766361 -217.233647) (xy 112.743752 -217.188215) (xy 112.728374 -217.139855) (xy 112.72059 -217.089709)
			(xy 112.72012 -217.064336) (xy 111.499904 -217.064336) (xy 111.499412 -217.08968) (xy 111.491635 -217.13977)
			(xy 111.476286 -217.188079) (xy 111.453725 -217.233471) (xy 111.424484 -217.274876) (xy 111.389252 -217.311319)
			(xy 111.348859 -217.341943) (xy 111.304255 -217.366024) (xy 111.256492 -217.382998) (xy 111.23168 -217.388186)
			(xy 111.20882 -217.392504) (xy 111.003842 -217.747596) (xy 111.011716 -217.76944) (xy 111.020306 -217.795856)
			(xy 111.029495 -217.850633) (xy 111.030004 -217.878406) (xy 111.029496 -217.904293) (xy 111.021397 -217.955431)
			(xy 111.005398 -218.004671) (xy 110.981892 -218.050803) (xy 110.95146 -218.09269) (xy 110.91485 -218.1293)
			(xy 110.872963 -218.159732) (xy 110.826831 -218.183238) (xy 110.777591 -218.199237) (xy 110.726453 -218.207336)
			(xy 110.674679 -218.207336) (xy 110.623541 -218.199237) (xy 110.574301 -218.183238) (xy 110.528169 -218.159732)
			(xy 110.486282 -218.1293) (xy 110.449672 -218.09269) (xy 110.41924 -218.050803) (xy 110.395734 -218.004671)
			(xy 110.379735 -217.955431) (xy 110.371636 -217.904293) (xy 110.371128 -217.878406) (xy 110.090204 -217.878406)
			(xy 110.089676 -217.906114) (xy 110.08048 -217.960761) (xy 110.071916 -217.987118) (xy 110.064296 -218.008962)
			(xy 110.269274 -218.364054) (xy 110.292134 -218.368372) (xy 110.316944 -218.373529) (xy 110.364684 -218.390523)
			(xy 110.409261 -218.414621) (xy 110.449626 -218.445257) (xy 110.484829 -218.481707) (xy 110.51404 -218.523115)
			(xy 110.536571 -218.568504) (xy 110.551892 -218.616807) (xy 110.559642 -218.666885) (xy 110.560104 -218.692222)
			(xy 111.78032 -218.692222) (xy 111.780845 -218.666878) (xy 111.788614 -218.616789) (xy 111.803957 -218.56848)
			(xy 111.826512 -218.523087) (xy 111.855749 -218.481681) (xy 111.890978 -218.445236) (xy 111.931369 -218.414613)
			(xy 111.97597 -218.390531) (xy 112.023732 -218.373559) (xy 112.048544 -218.368372) (xy 112.071404 -218.364054)
			(xy 112.276636 -218.008708) (xy 112.268762 -217.98661) (xy 112.260294 -217.960366) (xy 112.251224 -217.905977)
			(xy 112.250728 -217.878406) (xy 112.251236 -217.852519) (xy 112.259335 -217.801381) (xy 112.275334 -217.752141)
			(xy 112.29884 -217.706009) (xy 112.329272 -217.664122) (xy 112.365882 -217.627512) (xy 112.407769 -217.59708)
			(xy 112.453901 -217.573574) (xy 112.503141 -217.557575) (xy 112.554279 -217.549476) (xy 112.606053 -217.549476)
			(xy 112.657191 -217.557575) (xy 112.706431 -217.573574) (xy 112.752563 -217.59708) (xy 112.79445 -217.627512)
			(xy 112.83106 -217.664122) (xy 112.861492 -217.706009) (xy 112.884998 -217.752141) (xy 112.900997 -217.801381)
			(xy 112.909096 -217.852519) (xy 112.909604 -217.878406) (xy 112.909131 -217.90378) (xy 112.901362 -217.953931)
			(xy 112.885993 -218.002296) (xy 112.863388 -218.047732) (xy 112.834082 -218.089163) (xy 112.798768 -218.125609)
			(xy 112.758282 -218.156208) (xy 112.713582 -218.180235) (xy 112.665726 -218.197122) (xy 112.640872 -218.202256)
			(xy 112.618012 -218.206574) (xy 112.413288 -218.561412) (xy 112.421162 -218.583256) (xy 112.429814 -218.609662)
			(xy 112.43913 -218.66444) (xy 112.439704 -218.692222) (xy 113.660428 -218.692222) (xy 113.660908 -218.666887)
			(xy 113.668658 -218.616813) (xy 113.683979 -218.568515) (xy 113.70651 -218.52313) (xy 113.73572 -218.481727)
			(xy 113.770922 -218.445282) (xy 113.811285 -218.414651) (xy 113.855861 -218.390558) (xy 113.903598 -218.37357)
			(xy 113.928398 -218.368372) (xy 113.951258 -218.364054) (xy 114.156236 -218.008962) (xy 114.148616 -217.986864)
			(xy 114.140092 -217.960694) (xy 114.130901 -217.906431) (xy 114.130328 -217.878914) (xy 114.130328 -217.878406)
			(xy 114.130836 -217.852519) (xy 114.138935 -217.801381) (xy 114.154934 -217.752141) (xy 114.17844 -217.706009)
			(xy 114.208872 -217.664122) (xy 114.245482 -217.627512) (xy 114.287369 -217.59708) (xy 114.333501 -217.573574)
			(xy 114.382741 -217.557575) (xy 114.433879 -217.549476) (xy 114.485653 -217.549476) (xy 114.536791 -217.557575)
			(xy 114.586031 -217.573574) (xy 114.632163 -217.59708) (xy 114.67405 -217.627512) (xy 114.71066 -217.664122)
			(xy 114.741092 -217.706009) (xy 114.764598 -217.752141) (xy 114.780597 -217.801381) (xy 114.788696 -217.852519)
			(xy 114.789204 -217.878406) (xy 114.788769 -217.903771) (xy 114.781019 -217.953906) (xy 114.765673 -218.002259)
			(xy 114.743093 -218.047686) (xy 114.713814 -218.089114) (xy 114.678529 -218.125562) (xy 114.638071 -218.156167)
			(xy 114.593399 -218.180207) (xy 114.545568 -218.197111) (xy 114.520726 -218.202256) (xy 114.497866 -218.206574)
			(xy 114.293142 -218.561412) (xy 114.301016 -218.583256) (xy 114.309609 -218.609671) (xy 114.318797 -218.664449)
			(xy 114.319304 -218.692222) (xy 115.53952 -218.692222) (xy 115.540045 -218.666878) (xy 115.547814 -218.616789)
			(xy 115.563157 -218.56848) (xy 115.585712 -218.523087) (xy 115.614949 -218.481681) (xy 115.650178 -218.445236)
			(xy 115.690569 -218.414613) (xy 115.73517 -218.390531) (xy 115.782932 -218.373559) (xy 115.807744 -218.368372)
			(xy 115.830604 -218.364054) (xy 116.035836 -218.008708) (xy 116.027962 -217.98661) (xy 116.019494 -217.960366)
			(xy 116.010424 -217.905977) (xy 116.009928 -217.878406) (xy 116.010436 -217.852519) (xy 116.018535 -217.801381)
			(xy 116.034534 -217.752141) (xy 116.05804 -217.706009) (xy 116.088472 -217.664122) (xy 116.125082 -217.627512)
			(xy 116.166969 -217.59708) (xy 116.213101 -217.573574) (xy 116.262341 -217.557575) (xy 116.313479 -217.549476)
			(xy 116.365253 -217.549476) (xy 116.416391 -217.557575) (xy 116.465631 -217.573574) (xy 116.511763 -217.59708)
			(xy 116.55365 -217.627512) (xy 116.59026 -217.664122) (xy 116.620692 -217.706009) (xy 116.644198 -217.752141)
			(xy 116.660197 -217.801381) (xy 116.668296 -217.852519) (xy 116.668804 -217.878406) (xy 116.668331 -217.90378)
			(xy 116.660562 -217.953931) (xy 116.645193 -218.002296) (xy 116.622588 -218.047732) (xy 116.593282 -218.089163)
			(xy 116.557968 -218.125609) (xy 116.517482 -218.156208) (xy 116.472782 -218.180235) (xy 116.424926 -218.197122)
			(xy 116.400072 -218.202256) (xy 116.377212 -218.206574) (xy 116.172488 -218.561412) (xy 116.180362 -218.583256)
			(xy 116.189014 -218.609662) (xy 116.19833 -218.66444) (xy 116.198904 -218.692222) (xy 117.41912 -218.692222)
			(xy 117.419645 -218.666878) (xy 117.427414 -218.616789) (xy 117.442757 -218.56848) (xy 117.465312 -218.523087)
			(xy 117.494549 -218.481681) (xy 117.529778 -218.445236) (xy 117.570169 -218.414613) (xy 117.61477 -218.390531)
			(xy 117.662532 -218.373559) (xy 117.687344 -218.368372) (xy 117.710204 -218.364054) (xy 117.915436 -218.008708)
			(xy 117.907562 -217.98661) (xy 117.899094 -217.960366) (xy 117.890024 -217.905977) (xy 117.889528 -217.878406)
			(xy 117.890036 -217.852519) (xy 117.898135 -217.801381) (xy 117.914134 -217.752141) (xy 117.93764 -217.706009)
			(xy 117.968072 -217.664122) (xy 118.004682 -217.627512) (xy 118.046569 -217.59708) (xy 118.092701 -217.573574)
			(xy 118.141941 -217.557575) (xy 118.193079 -217.549476) (xy 118.244853 -217.549476) (xy 118.295991 -217.557575)
			(xy 118.345231 -217.573574) (xy 118.391363 -217.59708) (xy 118.43325 -217.627512) (xy 118.46986 -217.664122)
			(xy 118.500292 -217.706009) (xy 118.523798 -217.752141) (xy 118.539797 -217.801381) (xy 118.547896 -217.852519)
			(xy 118.548404 -217.878406) (xy 118.547931 -217.90378) (xy 118.540162 -217.953931) (xy 118.524793 -218.002296)
			(xy 118.502188 -218.047732) (xy 118.472882 -218.089163) (xy 118.437568 -218.125609) (xy 118.397082 -218.156208)
			(xy 118.352382 -218.180235) (xy 118.304526 -218.197122) (xy 118.279672 -218.202256) (xy 118.256812 -218.206574)
			(xy 118.052088 -218.561412) (xy 118.059962 -218.583256) (xy 118.068614 -218.609662) (xy 118.07793 -218.66444)
			(xy 118.078504 -218.692222) (xy 119.29872 -218.692222) (xy 119.299245 -218.666878) (xy 119.307014 -218.616789)
			(xy 119.322357 -218.56848) (xy 119.344912 -218.523087) (xy 119.374149 -218.481681) (xy 119.409378 -218.445236)
			(xy 119.449769 -218.414613) (xy 119.49437 -218.390531) (xy 119.542132 -218.373559) (xy 119.566944 -218.368372)
			(xy 119.589804 -218.364054) (xy 119.795036 -218.008708) (xy 119.787162 -217.98661) (xy 119.778694 -217.960366)
			(xy 119.769624 -217.905977) (xy 119.769128 -217.878406) (xy 119.769636 -217.852519) (xy 119.777735 -217.801381)
			(xy 119.793734 -217.752141) (xy 119.81724 -217.706009) (xy 119.847672 -217.664122) (xy 119.884282 -217.627512)
			(xy 119.926169 -217.59708) (xy 119.972301 -217.573574) (xy 120.021541 -217.557575) (xy 120.072679 -217.549476)
			(xy 120.124453 -217.549476) (xy 120.175591 -217.557575) (xy 120.224831 -217.573574) (xy 120.270963 -217.59708)
			(xy 120.31285 -217.627512) (xy 120.34946 -217.664122) (xy 120.379892 -217.706009) (xy 120.403398 -217.752141)
			(xy 120.419397 -217.801381) (xy 120.427496 -217.852519) (xy 120.428004 -217.878406) (xy 120.427531 -217.90378)
			(xy 120.419762 -217.953931) (xy 120.404393 -218.002296) (xy 120.381788 -218.047732) (xy 120.352482 -218.089163)
			(xy 120.317168 -218.125609) (xy 120.276682 -218.156208) (xy 120.231982 -218.180235) (xy 120.184126 -218.197122)
			(xy 120.159272 -218.202256) (xy 120.136412 -218.206574) (xy 119.931688 -218.561412) (xy 119.939562 -218.583256)
			(xy 119.948214 -218.609662) (xy 119.95753 -218.66444) (xy 119.958104 -218.692222) (xy 121.17832 -218.692222)
			(xy 121.178845 -218.666878) (xy 121.186614 -218.616789) (xy 121.201957 -218.56848) (xy 121.224512 -218.523087)
			(xy 121.253749 -218.481681) (xy 121.288978 -218.445236) (xy 121.329369 -218.414613) (xy 121.37397 -218.390531)
			(xy 121.421732 -218.373559) (xy 121.446544 -218.368372) (xy 121.469404 -218.364054) (xy 121.674636 -218.008708)
			(xy 121.666762 -217.98661) (xy 121.658294 -217.960366) (xy 121.649224 -217.905977) (xy 121.648728 -217.878406)
			(xy 121.649236 -217.852519) (xy 121.657335 -217.801381) (xy 121.673334 -217.752141) (xy 121.69684 -217.706009)
			(xy 121.727272 -217.664122) (xy 121.763882 -217.627512) (xy 121.805769 -217.59708) (xy 121.851901 -217.573574)
			(xy 121.901141 -217.557575) (xy 121.952279 -217.549476) (xy 122.004053 -217.549476) (xy 122.055191 -217.557575)
			(xy 122.104431 -217.573574) (xy 122.150563 -217.59708) (xy 122.19245 -217.627512) (xy 122.22906 -217.664122)
			(xy 122.259492 -217.706009) (xy 122.282998 -217.752141) (xy 122.298997 -217.801381) (xy 122.307096 -217.852519)
			(xy 122.307604 -217.878406) (xy 122.307131 -217.90378) (xy 122.299362 -217.953931) (xy 122.283993 -218.002296)
			(xy 122.261388 -218.047732) (xy 122.232082 -218.089163) (xy 122.196768 -218.125609) (xy 122.156282 -218.156208)
			(xy 122.111582 -218.180235) (xy 122.063726 -218.197122) (xy 122.038872 -218.202256) (xy 122.016012 -218.206574)
			(xy 121.811288 -218.561412) (xy 121.819162 -218.583256) (xy 121.827814 -218.609662) (xy 121.83713 -218.66444)
			(xy 121.837704 -218.692222) (xy 123.05792 -218.692222) (xy 123.058445 -218.666878) (xy 123.066214 -218.616789)
			(xy 123.081557 -218.56848) (xy 123.104112 -218.523087) (xy 123.133349 -218.481681) (xy 123.168578 -218.445236)
			(xy 123.208969 -218.414613) (xy 123.25357 -218.390531) (xy 123.301332 -218.373559) (xy 123.326144 -218.368372)
			(xy 123.349004 -218.364054) (xy 123.554236 -218.008708) (xy 123.546362 -217.98661) (xy 123.537894 -217.960366)
			(xy 123.528824 -217.905977) (xy 123.528328 -217.878406) (xy 123.528836 -217.852519) (xy 123.536935 -217.801381)
			(xy 123.552934 -217.752141) (xy 123.57644 -217.706009) (xy 123.606872 -217.664122) (xy 123.643482 -217.627512)
			(xy 123.685369 -217.59708) (xy 123.731501 -217.573574) (xy 123.780741 -217.557575) (xy 123.831879 -217.549476)
			(xy 123.883653 -217.549476) (xy 123.934791 -217.557575) (xy 123.984031 -217.573574) (xy 124.030163 -217.59708)
			(xy 124.07205 -217.627512) (xy 124.10866 -217.664122) (xy 124.139092 -217.706009) (xy 124.162598 -217.752141)
			(xy 124.178597 -217.801381) (xy 124.186696 -217.852519) (xy 124.187204 -217.878406) (xy 124.186731 -217.90378)
			(xy 124.178962 -217.953931) (xy 124.163593 -218.002296) (xy 124.140988 -218.047732) (xy 124.111682 -218.089163)
			(xy 124.076368 -218.125609) (xy 124.035882 -218.156208) (xy 123.991182 -218.180235) (xy 123.943326 -218.197122)
			(xy 123.918472 -218.202256) (xy 123.895612 -218.206574) (xy 123.690888 -218.561412) (xy 123.698762 -218.583256)
			(xy 123.707414 -218.609662) (xy 123.71673 -218.66444) (xy 123.717304 -218.692222) (xy 124.93752 -218.692222)
			(xy 124.938045 -218.666878) (xy 124.945814 -218.616789) (xy 124.961157 -218.56848) (xy 124.983712 -218.523087)
			(xy 125.012949 -218.481681) (xy 125.048178 -218.445236) (xy 125.088569 -218.414613) (xy 125.13317 -218.390531)
			(xy 125.180932 -218.373559) (xy 125.205744 -218.368372) (xy 125.228604 -218.364054) (xy 125.433836 -218.008708)
			(xy 125.425962 -217.98661) (xy 125.417494 -217.960366) (xy 125.408424 -217.905977) (xy 125.407928 -217.878406)
			(xy 125.408436 -217.852519) (xy 125.416535 -217.801381) (xy 125.432534 -217.752141) (xy 125.45604 -217.706009)
			(xy 125.486472 -217.664122) (xy 125.523082 -217.627512) (xy 125.564969 -217.59708) (xy 125.611101 -217.573574)
			(xy 125.660341 -217.557575) (xy 125.711479 -217.549476) (xy 125.763253 -217.549476) (xy 125.814391 -217.557575)
			(xy 125.863631 -217.573574) (xy 125.909763 -217.59708) (xy 125.95165 -217.627512) (xy 125.98826 -217.664122)
			(xy 126.018692 -217.706009) (xy 126.042198 -217.752141) (xy 126.058197 -217.801381) (xy 126.066296 -217.852519)
			(xy 126.066804 -217.878406) (xy 126.066331 -217.90378) (xy 126.058562 -217.953931) (xy 126.043193 -218.002296)
			(xy 126.020588 -218.047732) (xy 125.991282 -218.089163) (xy 125.955968 -218.125609) (xy 125.915482 -218.156208)
			(xy 125.870782 -218.180235) (xy 125.822926 -218.197122) (xy 125.798072 -218.202256) (xy 125.775212 -218.206574)
			(xy 125.570488 -218.561412) (xy 125.578362 -218.583256) (xy 125.587014 -218.609662) (xy 125.59633 -218.66444)
			(xy 125.596904 -218.692222) (xy 126.81712 -218.692222) (xy 126.817645 -218.666878) (xy 126.825414 -218.616789)
			(xy 126.840757 -218.56848) (xy 126.863312 -218.523087) (xy 126.892549 -218.481681) (xy 126.927778 -218.445236)
			(xy 126.968169 -218.414613) (xy 127.01277 -218.390531) (xy 127.060532 -218.373559) (xy 127.085344 -218.368372)
			(xy 127.108204 -218.364054) (xy 127.313436 -218.008708) (xy 127.305562 -217.98661) (xy 127.297094 -217.960366)
			(xy 127.288024 -217.905977) (xy 127.287528 -217.878406) (xy 127.288036 -217.852519) (xy 127.296135 -217.801381)
			(xy 127.312134 -217.752141) (xy 127.33564 -217.706009) (xy 127.366072 -217.664122) (xy 127.402682 -217.627512)
			(xy 127.444569 -217.59708) (xy 127.490701 -217.573574) (xy 127.539941 -217.557575) (xy 127.591079 -217.549476)
			(xy 127.642853 -217.549476) (xy 127.693991 -217.557575) (xy 127.743231 -217.573574) (xy 127.789363 -217.59708)
			(xy 127.83125 -217.627512) (xy 127.86786 -217.664122) (xy 127.898292 -217.706009) (xy 127.921798 -217.752141)
			(xy 127.937797 -217.801381) (xy 127.945896 -217.852519) (xy 127.946404 -217.878406) (xy 127.945931 -217.90378)
			(xy 127.938162 -217.953931) (xy 127.922793 -218.002296) (xy 127.900188 -218.047732) (xy 127.870882 -218.089163)
			(xy 127.835568 -218.125609) (xy 127.795082 -218.156208) (xy 127.750382 -218.180235) (xy 127.702526 -218.197122)
			(xy 127.677672 -218.202256) (xy 127.654812 -218.206574) (xy 127.450088 -218.561412) (xy 127.457962 -218.583256)
			(xy 127.466614 -218.609662) (xy 127.47593 -218.66444) (xy 127.476504 -218.692222) (xy 128.69672 -218.692222)
			(xy 128.697245 -218.666878) (xy 128.705014 -218.616789) (xy 128.720357 -218.56848) (xy 128.742912 -218.523087)
			(xy 128.772149 -218.481681) (xy 128.807378 -218.445236) (xy 128.847769 -218.414613) (xy 128.89237 -218.390531)
			(xy 128.940132 -218.373559) (xy 128.964944 -218.368372) (xy 128.987804 -218.364054) (xy 129.193036 -218.008708)
			(xy 129.185162 -217.98661) (xy 129.176694 -217.960366) (xy 129.167624 -217.905977) (xy 129.167128 -217.878406)
			(xy 129.167636 -217.852519) (xy 129.175735 -217.801381) (xy 129.191734 -217.752141) (xy 129.21524 -217.706009)
			(xy 129.245672 -217.664122) (xy 129.282282 -217.627512) (xy 129.324169 -217.59708) (xy 129.370301 -217.573574)
			(xy 129.419541 -217.557575) (xy 129.470679 -217.549476) (xy 129.522453 -217.549476) (xy 129.573591 -217.557575)
			(xy 129.622831 -217.573574) (xy 129.668963 -217.59708) (xy 129.71085 -217.627512) (xy 129.74746 -217.664122)
			(xy 129.777892 -217.706009) (xy 129.801398 -217.752141) (xy 129.817397 -217.801381) (xy 129.825496 -217.852519)
			(xy 129.826004 -217.878406) (xy 129.825531 -217.90378) (xy 129.817762 -217.953931) (xy 129.802393 -218.002296)
			(xy 129.779788 -218.047732) (xy 129.750482 -218.089163) (xy 129.715168 -218.125609) (xy 129.674682 -218.156208)
			(xy 129.629982 -218.180235) (xy 129.582126 -218.197122) (xy 129.557272 -218.202256) (xy 129.534412 -218.206574)
			(xy 129.329688 -218.561412) (xy 129.337562 -218.583256) (xy 129.346214 -218.609662) (xy 129.35553 -218.66444)
			(xy 129.356104 -218.692222) (xy 130.57632 -218.692222) (xy 130.576845 -218.666878) (xy 130.584614 -218.616789)
			(xy 130.599957 -218.56848) (xy 130.622512 -218.523087) (xy 130.651749 -218.481681) (xy 130.686978 -218.445236)
			(xy 130.727369 -218.414613) (xy 130.77197 -218.390531) (xy 130.819732 -218.373559) (xy 130.844544 -218.368372)
			(xy 130.867404 -218.364054) (xy 131.072636 -218.008708) (xy 131.064762 -217.98661) (xy 131.056294 -217.960366)
			(xy 131.047224 -217.905977) (xy 131.046728 -217.878406) (xy 131.047236 -217.852519) (xy 131.055335 -217.801381)
			(xy 131.071334 -217.752141) (xy 131.09484 -217.706009) (xy 131.125272 -217.664122) (xy 131.161882 -217.627512)
			(xy 131.203769 -217.59708) (xy 131.249901 -217.573574) (xy 131.299141 -217.557575) (xy 131.350279 -217.549476)
			(xy 131.402053 -217.549476) (xy 131.453191 -217.557575) (xy 131.502431 -217.573574) (xy 131.548563 -217.59708)
			(xy 131.59045 -217.627512) (xy 131.62706 -217.664122) (xy 131.657492 -217.706009) (xy 131.680998 -217.752141)
			(xy 131.696997 -217.801381) (xy 131.705096 -217.852519) (xy 131.705604 -217.878406) (xy 131.705131 -217.90378)
			(xy 131.697362 -217.953931) (xy 131.681993 -218.002296) (xy 131.659388 -218.047732) (xy 131.630082 -218.089163)
			(xy 131.594768 -218.125609) (xy 131.554282 -218.156208) (xy 131.509582 -218.180235) (xy 131.461726 -218.197122)
			(xy 131.436872 -218.202256) (xy 131.414012 -218.206574) (xy 131.209288 -218.561412) (xy 131.217162 -218.583256)
			(xy 131.225814 -218.609662) (xy 131.23513 -218.66444) (xy 131.235704 -218.692222) (xy 132.45592 -218.692222)
			(xy 132.456445 -218.666878) (xy 132.464214 -218.616789) (xy 132.479557 -218.56848) (xy 132.502112 -218.523087)
			(xy 132.531349 -218.481681) (xy 132.566578 -218.445236) (xy 132.606969 -218.414613) (xy 132.65157 -218.390531)
			(xy 132.699332 -218.373559) (xy 132.724144 -218.368372) (xy 132.747004 -218.364054) (xy 132.952236 -218.008708)
			(xy 132.944362 -217.98661) (xy 132.935894 -217.960366) (xy 132.926824 -217.905977) (xy 132.926328 -217.878406)
			(xy 132.926836 -217.852519) (xy 132.934935 -217.801381) (xy 132.950934 -217.752141) (xy 132.97444 -217.706009)
			(xy 133.004872 -217.664122) (xy 133.041482 -217.627512) (xy 133.083369 -217.59708) (xy 133.129501 -217.573574)
			(xy 133.178741 -217.557575) (xy 133.229879 -217.549476) (xy 133.281653 -217.549476) (xy 133.332791 -217.557575)
			(xy 133.382031 -217.573574) (xy 133.428163 -217.59708) (xy 133.47005 -217.627512) (xy 133.50666 -217.664122)
			(xy 133.537092 -217.706009) (xy 133.560598 -217.752141) (xy 133.576597 -217.801381) (xy 133.584696 -217.852519)
			(xy 133.585204 -217.878406) (xy 133.584731 -217.90378) (xy 133.576962 -217.953931) (xy 133.561593 -218.002296)
			(xy 133.538988 -218.047732) (xy 133.509682 -218.089163) (xy 133.474368 -218.125609) (xy 133.433882 -218.156208)
			(xy 133.389182 -218.180235) (xy 133.341326 -218.197122) (xy 133.316472 -218.202256) (xy 133.293612 -218.206574)
			(xy 133.088888 -218.561412) (xy 133.096762 -218.583256) (xy 133.105414 -218.609662) (xy 133.11473 -218.66444)
			(xy 133.115304 -218.692222) (xy 133.114796 -218.718129) (xy 133.10669 -218.769306) (xy 133.090678 -218.818585)
			(xy 133.067155 -218.864752) (xy 133.036699 -218.906671) (xy 133.000061 -218.943309) (xy 132.958142 -218.973765)
			(xy 132.911975 -218.997288) (xy 132.862696 -219.0133) (xy 132.811519 -219.021406) (xy 132.759705 -219.021406)
			(xy 132.708528 -219.0133) (xy 132.659249 -218.997288) (xy 132.613082 -218.973765) (xy 132.571163 -218.943309)
			(xy 132.534525 -218.906671) (xy 132.504069 -218.864752) (xy 132.480546 -218.818585) (xy 132.464534 -218.769306)
			(xy 132.456428 -218.718129) (xy 132.45592 -218.692222) (xy 131.235704 -218.692222) (xy 131.235196 -218.718129)
			(xy 131.22709 -218.769306) (xy 131.211078 -218.818585) (xy 131.187555 -218.864752) (xy 131.157099 -218.906671)
			(xy 131.120461 -218.943309) (xy 131.078542 -218.973765) (xy 131.032375 -218.997288) (xy 130.983096 -219.0133)
			(xy 130.931919 -219.021406) (xy 130.880105 -219.021406) (xy 130.828928 -219.0133) (xy 130.779649 -218.997288)
			(xy 130.733482 -218.973765) (xy 130.691563 -218.943309) (xy 130.654925 -218.906671) (xy 130.624469 -218.864752)
			(xy 130.600946 -218.818585) (xy 130.584934 -218.769306) (xy 130.576828 -218.718129) (xy 130.57632 -218.692222)
			(xy 129.356104 -218.692222) (xy 129.355596 -218.718129) (xy 129.34749 -218.769306) (xy 129.331478 -218.818585)
			(xy 129.307955 -218.864752) (xy 129.277499 -218.906671) (xy 129.240861 -218.943309) (xy 129.198942 -218.973765)
			(xy 129.152775 -218.997288) (xy 129.103496 -219.0133) (xy 129.052319 -219.021406) (xy 129.000505 -219.021406)
			(xy 128.949328 -219.0133) (xy 128.900049 -218.997288) (xy 128.853882 -218.973765) (xy 128.811963 -218.943309)
			(xy 128.775325 -218.906671) (xy 128.744869 -218.864752) (xy 128.721346 -218.818585) (xy 128.705334 -218.769306)
			(xy 128.697228 -218.718129) (xy 128.69672 -218.692222) (xy 127.476504 -218.692222) (xy 127.475996 -218.718129)
			(xy 127.46789 -218.769306) (xy 127.451878 -218.818585) (xy 127.428355 -218.864752) (xy 127.397899 -218.906671)
			(xy 127.361261 -218.943309) (xy 127.319342 -218.973765) (xy 127.273175 -218.997288) (xy 127.223896 -219.0133)
			(xy 127.172719 -219.021406) (xy 127.120905 -219.021406) (xy 127.069728 -219.0133) (xy 127.020449 -218.997288)
			(xy 126.974282 -218.973765) (xy 126.932363 -218.943309) (xy 126.895725 -218.906671) (xy 126.865269 -218.864752)
			(xy 126.841746 -218.818585) (xy 126.825734 -218.769306) (xy 126.817628 -218.718129) (xy 126.81712 -218.692222)
			(xy 125.596904 -218.692222) (xy 125.596396 -218.718129) (xy 125.58829 -218.769306) (xy 125.572278 -218.818585)
			(xy 125.548755 -218.864752) (xy 125.518299 -218.906671) (xy 125.481661 -218.943309) (xy 125.439742 -218.973765)
			(xy 125.393575 -218.997288) (xy 125.344296 -219.0133) (xy 125.293119 -219.021406) (xy 125.241305 -219.021406)
			(xy 125.190128 -219.0133) (xy 125.140849 -218.997288) (xy 125.094682 -218.973765) (xy 125.052763 -218.943309)
			(xy 125.016125 -218.906671) (xy 124.985669 -218.864752) (xy 124.962146 -218.818585) (xy 124.946134 -218.769306)
			(xy 124.938028 -218.718129) (xy 124.93752 -218.692222) (xy 123.717304 -218.692222) (xy 123.716796 -218.718129)
			(xy 123.70869 -218.769306) (xy 123.692678 -218.818585) (xy 123.669155 -218.864752) (xy 123.638699 -218.906671)
			(xy 123.602061 -218.943309) (xy 123.560142 -218.973765) (xy 123.513975 -218.997288) (xy 123.464696 -219.0133)
			(xy 123.413519 -219.021406) (xy 123.361705 -219.021406) (xy 123.310528 -219.0133) (xy 123.261249 -218.997288)
			(xy 123.215082 -218.973765) (xy 123.173163 -218.943309) (xy 123.136525 -218.906671) (xy 123.106069 -218.864752)
			(xy 123.082546 -218.818585) (xy 123.066534 -218.769306) (xy 123.058428 -218.718129) (xy 123.05792 -218.692222)
			(xy 121.837704 -218.692222) (xy 121.837196 -218.718129) (xy 121.82909 -218.769306) (xy 121.813078 -218.818585)
			(xy 121.789555 -218.864752) (xy 121.759099 -218.906671) (xy 121.722461 -218.943309) (xy 121.680542 -218.973765)
			(xy 121.634375 -218.997288) (xy 121.585096 -219.0133) (xy 121.533919 -219.021406) (xy 121.482105 -219.021406)
			(xy 121.430928 -219.0133) (xy 121.381649 -218.997288) (xy 121.335482 -218.973765) (xy 121.293563 -218.943309)
			(xy 121.256925 -218.906671) (xy 121.226469 -218.864752) (xy 121.202946 -218.818585) (xy 121.186934 -218.769306)
			(xy 121.178828 -218.718129) (xy 121.17832 -218.692222) (xy 119.958104 -218.692222) (xy 119.957596 -218.718129)
			(xy 119.94949 -218.769306) (xy 119.933478 -218.818585) (xy 119.909955 -218.864752) (xy 119.879499 -218.906671)
			(xy 119.842861 -218.943309) (xy 119.800942 -218.973765) (xy 119.754775 -218.997288) (xy 119.705496 -219.0133)
			(xy 119.654319 -219.021406) (xy 119.602505 -219.021406) (xy 119.551328 -219.0133) (xy 119.502049 -218.997288)
			(xy 119.455882 -218.973765) (xy 119.413963 -218.943309) (xy 119.377325 -218.906671) (xy 119.346869 -218.864752)
			(xy 119.323346 -218.818585) (xy 119.307334 -218.769306) (xy 119.299228 -218.718129) (xy 119.29872 -218.692222)
			(xy 118.078504 -218.692222) (xy 118.077996 -218.718129) (xy 118.06989 -218.769306) (xy 118.053878 -218.818585)
			(xy 118.030355 -218.864752) (xy 117.999899 -218.906671) (xy 117.963261 -218.943309) (xy 117.921342 -218.973765)
			(xy 117.875175 -218.997288) (xy 117.825896 -219.0133) (xy 117.774719 -219.021406) (xy 117.722905 -219.021406)
			(xy 117.671728 -219.0133) (xy 117.622449 -218.997288) (xy 117.576282 -218.973765) (xy 117.534363 -218.943309)
			(xy 117.497725 -218.906671) (xy 117.467269 -218.864752) (xy 117.443746 -218.818585) (xy 117.427734 -218.769306)
			(xy 117.419628 -218.718129) (xy 117.41912 -218.692222) (xy 116.198904 -218.692222) (xy 116.198396 -218.718129)
			(xy 116.19029 -218.769306) (xy 116.174278 -218.818585) (xy 116.150755 -218.864752) (xy 116.120299 -218.906671)
			(xy 116.083661 -218.943309) (xy 116.041742 -218.973765) (xy 115.995575 -218.997288) (xy 115.946296 -219.0133)
			(xy 115.895119 -219.021406) (xy 115.843305 -219.021406) (xy 115.792128 -219.0133) (xy 115.742849 -218.997288)
			(xy 115.696682 -218.973765) (xy 115.654763 -218.943309) (xy 115.618125 -218.906671) (xy 115.587669 -218.864752)
			(xy 115.564146 -218.818585) (xy 115.548134 -218.769306) (xy 115.540028 -218.718129) (xy 115.53952 -218.692222)
			(xy 114.319304 -218.692222) (xy 114.318796 -218.718109) (xy 114.310697 -218.769247) (xy 114.294698 -218.818487)
			(xy 114.271192 -218.864619) (xy 114.24076 -218.906506) (xy 114.20415 -218.943116) (xy 114.162263 -218.973548)
			(xy 114.116131 -218.997054) (xy 114.066891 -219.013053) (xy 114.015753 -219.021152) (xy 113.963979 -219.021152)
			(xy 113.912841 -219.013053) (xy 113.863601 -218.997054) (xy 113.817469 -218.973548) (xy 113.775582 -218.943116)
			(xy 113.738972 -218.906506) (xy 113.70854 -218.864619) (xy 113.685034 -218.818487) (xy 113.669035 -218.769247)
			(xy 113.660936 -218.718109) (xy 113.660428 -218.692222) (xy 112.439704 -218.692222) (xy 112.439196 -218.718129)
			(xy 112.43109 -218.769306) (xy 112.415078 -218.818585) (xy 112.391555 -218.864752) (xy 112.361099 -218.906671)
			(xy 112.324461 -218.943309) (xy 112.282542 -218.973765) (xy 112.236375 -218.997288) (xy 112.187096 -219.0133)
			(xy 112.135919 -219.021406) (xy 112.084105 -219.021406) (xy 112.032928 -219.0133) (xy 111.983649 -218.997288)
			(xy 111.937482 -218.973765) (xy 111.895563 -218.943309) (xy 111.858925 -218.906671) (xy 111.828469 -218.864752)
			(xy 111.804946 -218.818585) (xy 111.788934 -218.769306) (xy 111.780828 -218.718129) (xy 111.78032 -218.692222)
			(xy 110.560104 -218.692222) (xy 110.559596 -218.718109) (xy 110.551497 -218.769247) (xy 110.535498 -218.818487)
			(xy 110.511992 -218.864619) (xy 110.48156 -218.906506) (xy 110.44495 -218.943116) (xy 110.403063 -218.973548)
			(xy 110.356931 -218.997054) (xy 110.307691 -219.013053) (xy 110.256553 -219.021152) (xy 110.204779 -219.021152)
			(xy 110.153641 -219.013053) (xy 110.104401 -218.997054) (xy 110.058269 -218.973548) (xy 110.016382 -218.943116)
			(xy 109.979772 -218.906506) (xy 109.94934 -218.864619) (xy 109.925834 -218.818487) (xy 109.909835 -218.769247)
			(xy 109.901736 -218.718109) (xy 109.901228 -218.692222) (xy 109.901766 -218.664514) (xy 109.910956 -218.609868)
			(xy 109.919516 -218.58351) (xy 109.92739 -218.561412) (xy 109.722412 -218.206574) (xy 109.699552 -218.202256)
			(xy 109.67472 -218.197133) (xy 109.626938 -218.180175) (xy 109.582316 -218.1561) (xy 109.541908 -218.125474)
			(xy 109.506667 -218.089022) (xy 109.477424 -218.047602) (xy 109.45487 -218.002192) (xy 109.439537 -217.953864)
			(xy 109.431786 -217.903757) (xy 109.431328 -217.878406) (xy 109.150404 -217.878406) (xy 109.149896 -217.904293)
			(xy 109.141797 -217.955431) (xy 109.125798 -218.004671) (xy 109.102292 -218.050803) (xy 109.07186 -218.09269)
			(xy 109.03525 -218.1293) (xy 108.993363 -218.159732) (xy 108.947231 -218.183238) (xy 108.897991 -218.199237)
			(xy 108.846853 -218.207336) (xy 108.795079 -218.207336) (xy 108.743941 -218.199237) (xy 108.694701 -218.183238)
			(xy 108.648569 -218.159732) (xy 108.606682 -218.1293) (xy 108.570072 -218.09269) (xy 108.53964 -218.050803)
			(xy 108.516134 -218.004671) (xy 108.500135 -217.955431) (xy 108.492036 -217.904293) (xy 108.491528 -217.878406)
			(xy 108.210604 -217.878406) (xy 108.210076 -217.906114) (xy 108.20088 -217.960761) (xy 108.192316 -217.987118)
			(xy 108.184442 -218.009216) (xy 108.38942 -218.364054) (xy 108.41228 -218.368372) (xy 108.4371 -218.37354)
			(xy 108.484878 -218.390497) (xy 108.529495 -218.41457) (xy 108.5699 -218.44519) (xy 108.60514 -218.481637)
			(xy 108.634384 -218.52305) (xy 108.656942 -218.568452) (xy 108.672281 -218.616773) (xy 108.680041 -218.666873)
			(xy 108.680504 -218.692222) (xy 108.679996 -218.718129) (xy 108.67189 -218.769306) (xy 108.655878 -218.818585)
			(xy 108.632355 -218.864752) (xy 108.601899 -218.906671) (xy 108.565261 -218.943309) (xy 108.523342 -218.973765)
			(xy 108.477175 -218.997288) (xy 108.427896 -219.0133) (xy 108.376719 -219.021406) (xy 108.324905 -219.021406)
			(xy 108.273728 -219.0133) (xy 108.224449 -218.997288) (xy 108.178282 -218.973765) (xy 108.136363 -218.943309)
			(xy 108.099725 -218.906671) (xy 108.069269 -218.864752) (xy 108.045746 -218.818585) (xy 108.029734 -218.769306)
			(xy 108.021628 -218.718129) (xy 108.02112 -218.692222) (xy 108.021718 -218.664505) (xy 108.031039 -218.609858)
			(xy 108.039662 -218.58351) (xy 108.047536 -218.561412) (xy 107.842558 -218.206574) (xy 107.819698 -218.202256)
			(xy 107.794899 -218.197049) (xy 107.747162 -218.180062) (xy 107.702585 -218.15597) (xy 107.66222 -218.125341)
			(xy 107.627017 -218.088897) (xy 107.597804 -218.047495) (xy 107.575271 -218.002112) (xy 107.559946 -217.953814)
			(xy 107.552192 -217.903741) (xy 107.551728 -217.878406) (xy 107.270804 -217.878406) (xy 107.270296 -217.904293)
			(xy 107.262197 -217.955431) (xy 107.246198 -218.004671) (xy 107.222692 -218.050803) (xy 107.19226 -218.09269)
			(xy 107.15565 -218.1293) (xy 107.113763 -218.159732) (xy 107.067631 -218.183238) (xy 107.018391 -218.199237)
			(xy 106.967253 -218.207336) (xy 106.915479 -218.207336) (xy 106.864341 -218.199237) (xy 106.815101 -218.183238)
			(xy 106.768969 -218.159732) (xy 106.727082 -218.1293) (xy 106.690472 -218.09269) (xy 106.66004 -218.050803)
			(xy 106.636534 -218.004671) (xy 106.620535 -217.955431) (xy 106.612436 -217.904293) (xy 106.611928 -217.878406)
			(xy 106.331004 -217.878406) (xy 106.330476 -217.906114) (xy 106.32128 -217.960761) (xy 106.312716 -217.987118)
			(xy 106.304842 -218.009216) (xy 106.50982 -218.364054) (xy 106.53268 -218.368372) (xy 106.5575 -218.37354)
			(xy 106.605278 -218.390497) (xy 106.649895 -218.41457) (xy 106.6903 -218.44519) (xy 106.72554 -218.481637)
			(xy 106.754784 -218.52305) (xy 106.777342 -218.568452) (xy 106.792681 -218.616773) (xy 106.800441 -218.666873)
			(xy 106.800904 -218.692222) (xy 106.800396 -218.718129) (xy 106.79229 -218.769306) (xy 106.776278 -218.818585)
			(xy 106.752755 -218.864752) (xy 106.722299 -218.906671) (xy 106.685661 -218.943309) (xy 106.643742 -218.973765)
			(xy 106.597575 -218.997288) (xy 106.548296 -219.0133) (xy 106.497119 -219.021406) (xy 106.445305 -219.021406)
			(xy 106.394128 -219.0133) (xy 106.344849 -218.997288) (xy 106.298682 -218.973765) (xy 106.256763 -218.943309)
			(xy 106.220125 -218.906671) (xy 106.189669 -218.864752) (xy 106.166146 -218.818585) (xy 106.150134 -218.769306)
			(xy 106.142028 -218.718129) (xy 106.14152 -218.692222) (xy 106.142118 -218.664505) (xy 106.151439 -218.609858)
			(xy 106.160062 -218.58351) (xy 106.167936 -218.561412) (xy 105.962958 -218.206574) (xy 105.940098 -218.202256)
			(xy 105.915299 -218.197049) (xy 105.867562 -218.180062) (xy 105.822985 -218.15597) (xy 105.78262 -218.125341)
			(xy 105.747417 -218.088897) (xy 105.718204 -218.047495) (xy 105.695671 -218.002112) (xy 105.680346 -217.953814)
			(xy 105.672592 -217.903741) (xy 105.672128 -217.878406) (xy 105.391204 -217.878406) (xy 105.390696 -217.904293)
			(xy 105.382597 -217.955431) (xy 105.366598 -218.004671) (xy 105.343092 -218.050803) (xy 105.31266 -218.09269)
			(xy 105.27605 -218.1293) (xy 105.234163 -218.159732) (xy 105.188031 -218.183238) (xy 105.138791 -218.199237)
			(xy 105.087653 -218.207336) (xy 105.035879 -218.207336) (xy 104.984741 -218.199237) (xy 104.935501 -218.183238)
			(xy 104.889369 -218.159732) (xy 104.847482 -218.1293) (xy 104.810872 -218.09269) (xy 104.78044 -218.050803)
			(xy 104.756934 -218.004671) (xy 104.740935 -217.955431) (xy 104.732836 -217.904293) (xy 104.732328 -217.878406)
			(xy 104.451404 -217.878406) (xy 104.450876 -217.906114) (xy 104.44168 -217.960761) (xy 104.433116 -217.987118)
			(xy 104.425242 -218.009216) (xy 104.63022 -218.364054) (xy 104.65308 -218.368372) (xy 104.6779 -218.37354)
			(xy 104.725678 -218.390497) (xy 104.770295 -218.41457) (xy 104.8107 -218.44519) (xy 104.84594 -218.481637)
			(xy 104.875184 -218.52305) (xy 104.897742 -218.568452) (xy 104.913081 -218.616773) (xy 104.920841 -218.666873)
			(xy 104.921304 -218.692222) (xy 104.920796 -218.718129) (xy 104.91269 -218.769306) (xy 104.896678 -218.818585)
			(xy 104.873155 -218.864752) (xy 104.842699 -218.906671) (xy 104.806061 -218.943309) (xy 104.764142 -218.973765)
			(xy 104.717975 -218.997288) (xy 104.668696 -219.0133) (xy 104.617519 -219.021406) (xy 104.565705 -219.021406)
			(xy 104.514528 -219.0133) (xy 104.465249 -218.997288) (xy 104.419082 -218.973765) (xy 104.377163 -218.943309)
			(xy 104.340525 -218.906671) (xy 104.310069 -218.864752) (xy 104.286546 -218.818585) (xy 104.270534 -218.769306)
			(xy 104.262428 -218.718129) (xy 104.26192 -218.692222) (xy 104.262518 -218.664505) (xy 104.271839 -218.609858)
			(xy 104.280462 -218.58351) (xy 104.288336 -218.561412) (xy 104.083358 -218.206574) (xy 104.060498 -218.202256)
			(xy 104.035699 -218.197049) (xy 103.987962 -218.180062) (xy 103.943385 -218.15597) (xy 103.90302 -218.125341)
			(xy 103.867817 -218.088897) (xy 103.838604 -218.047495) (xy 103.816071 -218.002112) (xy 103.800746 -217.953814)
			(xy 103.792992 -217.903741) (xy 103.792528 -217.878406) (xy 103.511604 -217.878406) (xy 103.511096 -217.904293)
			(xy 103.502997 -217.955431) (xy 103.486998 -218.004671) (xy 103.463492 -218.050803) (xy 103.43306 -218.09269)
			(xy 103.39645 -218.1293) (xy 103.354563 -218.159732) (xy 103.308431 -218.183238) (xy 103.259191 -218.199237)
			(xy 103.208053 -218.207336) (xy 103.156279 -218.207336) (xy 103.105141 -218.199237) (xy 103.055901 -218.183238)
			(xy 103.009769 -218.159732) (xy 102.967882 -218.1293) (xy 102.931272 -218.09269) (xy 102.90084 -218.050803)
			(xy 102.877334 -218.004671) (xy 102.861335 -217.955431) (xy 102.853236 -217.904293) (xy 102.852728 -217.878406)
			(xy 102.571804 -217.878406) (xy 102.571276 -217.906114) (xy 102.56208 -217.960761) (xy 102.553516 -217.987118)
			(xy 102.545642 -218.009216) (xy 102.75062 -218.364054) (xy 102.77348 -218.368372) (xy 102.7983 -218.37354)
			(xy 102.846078 -218.390497) (xy 102.890695 -218.41457) (xy 102.9311 -218.44519) (xy 102.96634 -218.481637)
			(xy 102.995584 -218.52305) (xy 103.018142 -218.568452) (xy 103.033481 -218.616773) (xy 103.041241 -218.666873)
			(xy 103.041704 -218.692222) (xy 103.041196 -218.718129) (xy 103.03309 -218.769306) (xy 103.017078 -218.818585)
			(xy 102.993555 -218.864752) (xy 102.963099 -218.906671) (xy 102.926461 -218.943309) (xy 102.884542 -218.973765)
			(xy 102.838375 -218.997288) (xy 102.789096 -219.0133) (xy 102.737919 -219.021406) (xy 102.686105 -219.021406)
			(xy 102.634928 -219.0133) (xy 102.585649 -218.997288) (xy 102.539482 -218.973765) (xy 102.497563 -218.943309)
			(xy 102.460925 -218.906671) (xy 102.430469 -218.864752) (xy 102.406946 -218.818585) (xy 102.390934 -218.769306)
			(xy 102.382828 -218.718129) (xy 102.38232 -218.692222) (xy 102.382918 -218.664505) (xy 102.392239 -218.609858)
			(xy 102.400862 -218.58351) (xy 102.408736 -218.561412) (xy 102.203758 -218.206574) (xy 102.180898 -218.202256)
			(xy 102.156099 -218.197049) (xy 102.108362 -218.180062) (xy 102.063785 -218.15597) (xy 102.02342 -218.125341)
			(xy 101.988217 -218.088897) (xy 101.959004 -218.047495) (xy 101.936471 -218.002112) (xy 101.921146 -217.953814)
			(xy 101.913392 -217.903741) (xy 101.912928 -217.878406) (xy 101.632004 -217.878406) (xy 101.631496 -217.904293)
			(xy 101.623397 -217.955431) (xy 101.607398 -218.004671) (xy 101.583892 -218.050803) (xy 101.55346 -218.09269)
			(xy 101.51685 -218.1293) (xy 101.474963 -218.159732) (xy 101.428831 -218.183238) (xy 101.379591 -218.199237)
			(xy 101.328453 -218.207336) (xy 101.276679 -218.207336) (xy 101.225541 -218.199237) (xy 101.176301 -218.183238)
			(xy 101.130169 -218.159732) (xy 101.088282 -218.1293) (xy 101.051672 -218.09269) (xy 101.02124 -218.050803)
			(xy 100.997734 -218.004671) (xy 100.981735 -217.955431) (xy 100.973636 -217.904293) (xy 100.973128 -217.878406)
			(xy 100.692204 -217.878406) (xy 100.691676 -217.906114) (xy 100.68248 -217.960761) (xy 100.673916 -217.987118)
			(xy 100.666042 -218.009216) (xy 100.87102 -218.364054) (xy 100.89388 -218.368372) (xy 100.9187 -218.37354)
			(xy 100.966478 -218.390497) (xy 101.011095 -218.41457) (xy 101.0515 -218.44519) (xy 101.08674 -218.481637)
			(xy 101.115984 -218.52305) (xy 101.138542 -218.568452) (xy 101.153881 -218.616773) (xy 101.161641 -218.666873)
			(xy 101.162104 -218.692222) (xy 101.161596 -218.718129) (xy 101.15349 -218.769306) (xy 101.137478 -218.818585)
			(xy 101.113955 -218.864752) (xy 101.083499 -218.906671) (xy 101.046861 -218.943309) (xy 101.004942 -218.973765)
			(xy 100.958775 -218.997288) (xy 100.909496 -219.0133) (xy 100.858319 -219.021406) (xy 100.806505 -219.021406)
			(xy 100.755328 -219.0133) (xy 100.706049 -218.997288) (xy 100.659882 -218.973765) (xy 100.617963 -218.943309)
			(xy 100.581325 -218.906671) (xy 100.550869 -218.864752) (xy 100.527346 -218.818585) (xy 100.511334 -218.769306)
			(xy 100.503228 -218.718129) (xy 100.50272 -218.692222) (xy 100.503318 -218.664505) (xy 100.512639 -218.609858)
			(xy 100.521262 -218.58351) (xy 100.529136 -218.561412) (xy 100.324158 -218.206574) (xy 100.301298 -218.202256)
			(xy 100.276499 -218.197049) (xy 100.228762 -218.180062) (xy 100.184185 -218.15597) (xy 100.14382 -218.125341)
			(xy 100.108617 -218.088897) (xy 100.079404 -218.047495) (xy 100.056871 -218.002112) (xy 100.041546 -217.953814)
			(xy 100.033792 -217.903741) (xy 100.033328 -217.878406) (xy 99.752404 -217.878406) (xy 99.751896 -217.904293)
			(xy 99.743797 -217.955431) (xy 99.727798 -218.004671) (xy 99.704292 -218.050803) (xy 99.67386 -218.09269)
			(xy 99.63725 -218.1293) (xy 99.595363 -218.159732) (xy 99.549231 -218.183238) (xy 99.499991 -218.199237)
			(xy 99.448853 -218.207336) (xy 99.397079 -218.207336) (xy 99.345941 -218.199237) (xy 99.296701 -218.183238)
			(xy 99.250569 -218.159732) (xy 99.208682 -218.1293) (xy 99.172072 -218.09269) (xy 99.14164 -218.050803)
			(xy 99.118134 -218.004671) (xy 99.102135 -217.955431) (xy 99.094036 -217.904293) (xy 99.093528 -217.878406)
			(xy 98.812604 -217.878406) (xy 98.812076 -217.906114) (xy 98.80288 -217.960761) (xy 98.794316 -217.987118)
			(xy 98.786442 -218.009216) (xy 98.99142 -218.364054) (xy 99.01428 -218.368372) (xy 99.0391 -218.37354)
			(xy 99.086878 -218.390497) (xy 99.131495 -218.41457) (xy 99.1719 -218.44519) (xy 99.20714 -218.481637)
			(xy 99.236384 -218.52305) (xy 99.258942 -218.568452) (xy 99.274281 -218.616773) (xy 99.282041 -218.666873)
			(xy 99.282504 -218.692222) (xy 99.281996 -218.718129) (xy 99.27389 -218.769306) (xy 99.257878 -218.818585)
			(xy 99.234355 -218.864752) (xy 99.203899 -218.906671) (xy 99.167261 -218.943309) (xy 99.125342 -218.973765)
			(xy 99.079175 -218.997288) (xy 99.029896 -219.0133) (xy 98.978719 -219.021406) (xy 98.926905 -219.021406)
			(xy 98.875728 -219.0133) (xy 98.826449 -218.997288) (xy 98.780282 -218.973765) (xy 98.738363 -218.943309)
			(xy 98.701725 -218.906671) (xy 98.671269 -218.864752) (xy 98.647746 -218.818585) (xy 98.631734 -218.769306)
			(xy 98.623628 -218.718129) (xy 98.62312 -218.692222) (xy 98.623718 -218.664505) (xy 98.633039 -218.609858)
			(xy 98.641662 -218.58351) (xy 98.649536 -218.561412) (xy 98.444558 -218.206574) (xy 98.421698 -218.202256)
			(xy 98.396899 -218.197049) (xy 98.349162 -218.180062) (xy 98.304585 -218.15597) (xy 98.26422 -218.125341)
			(xy 98.229017 -218.088897) (xy 98.199804 -218.047495) (xy 98.177271 -218.002112) (xy 98.161946 -217.953814)
			(xy 98.154192 -217.903741) (xy 98.153728 -217.878406) (xy 97.872804 -217.878406) (xy 97.872296 -217.904293)
			(xy 97.864197 -217.955431) (xy 97.848198 -218.004671) (xy 97.824692 -218.050803) (xy 97.79426 -218.09269)
			(xy 97.75765 -218.1293) (xy 97.715763 -218.159732) (xy 97.669631 -218.183238) (xy 97.620391 -218.199237)
			(xy 97.569253 -218.207336) (xy 97.517479 -218.207336) (xy 97.466341 -218.199237) (xy 97.417101 -218.183238)
			(xy 97.370969 -218.159732) (xy 97.329082 -218.1293) (xy 97.292472 -218.09269) (xy 97.26204 -218.050803)
			(xy 97.238534 -218.004671) (xy 97.222535 -217.955431) (xy 97.214436 -217.904293) (xy 97.213928 -217.878406)
			(xy 96.933004 -217.878406) (xy 96.932476 -217.906114) (xy 96.92328 -217.960761) (xy 96.914716 -217.987118)
			(xy 96.906842 -218.009216) (xy 97.11182 -218.364054) (xy 97.13468 -218.368372) (xy 97.1595 -218.37354)
			(xy 97.207278 -218.390497) (xy 97.251895 -218.41457) (xy 97.2923 -218.44519) (xy 97.32754 -218.481637)
			(xy 97.356784 -218.52305) (xy 97.379342 -218.568452) (xy 97.394681 -218.616773) (xy 97.402441 -218.666873)
			(xy 97.402904 -218.692222) (xy 97.402396 -218.718129) (xy 97.39429 -218.769306) (xy 97.378278 -218.818585)
			(xy 97.354755 -218.864752) (xy 97.324299 -218.906671) (xy 97.287661 -218.943309) (xy 97.245742 -218.973765)
			(xy 97.199575 -218.997288) (xy 97.150296 -219.0133) (xy 97.099119 -219.021406) (xy 97.047305 -219.021406)
			(xy 96.996128 -219.0133) (xy 96.946849 -218.997288) (xy 96.900682 -218.973765) (xy 96.858763 -218.943309)
			(xy 96.822125 -218.906671) (xy 96.791669 -218.864752) (xy 96.768146 -218.818585) (xy 96.752134 -218.769306)
			(xy 96.744028 -218.718129) (xy 96.74352 -218.692222) (xy 96.744118 -218.664505) (xy 96.753439 -218.609858)
			(xy 96.762062 -218.58351) (xy 96.769936 -218.561412) (xy 96.564958 -218.206574) (xy 96.542098 -218.202256)
			(xy 96.517299 -218.197049) (xy 96.469562 -218.180062) (xy 96.424985 -218.15597) (xy 96.38462 -218.125341)
			(xy 96.349417 -218.088897) (xy 96.320204 -218.047495) (xy 96.297671 -218.002112) (xy 96.282346 -217.953814)
			(xy 96.274592 -217.903741) (xy 96.274128 -217.878406) (xy 95.993204 -217.878406) (xy 95.992696 -217.904293)
			(xy 95.984597 -217.955431) (xy 95.968598 -218.004671) (xy 95.945092 -218.050803) (xy 95.91466 -218.09269)
			(xy 95.87805 -218.1293) (xy 95.836163 -218.159732) (xy 95.790031 -218.183238) (xy 95.740791 -218.199237)
			(xy 95.689653 -218.207336) (xy 95.637879 -218.207336) (xy 95.586741 -218.199237) (xy 95.537501 -218.183238)
			(xy 95.491369 -218.159732) (xy 95.449482 -218.1293) (xy 95.412872 -218.09269) (xy 95.38244 -218.050803)
			(xy 95.358934 -218.004671) (xy 95.342935 -217.955431) (xy 95.334836 -217.904293) (xy 95.334328 -217.878406)
			(xy 95.053404 -217.878406) (xy 95.052876 -217.906114) (xy 95.04368 -217.960761) (xy 95.035116 -217.987118)
			(xy 95.027242 -218.009216) (xy 95.23222 -218.364054) (xy 95.25508 -218.368372) (xy 95.2799 -218.37354)
			(xy 95.327678 -218.390497) (xy 95.372295 -218.41457) (xy 95.4127 -218.44519) (xy 95.44794 -218.481637)
			(xy 95.477184 -218.52305) (xy 95.499742 -218.568452) (xy 95.515081 -218.616773) (xy 95.522841 -218.666873)
			(xy 95.523304 -218.692222) (xy 95.522796 -218.718129) (xy 95.51469 -218.769306) (xy 95.498678 -218.818585)
			(xy 95.475155 -218.864752) (xy 95.444699 -218.906671) (xy 95.408061 -218.943309) (xy 95.366142 -218.973765)
			(xy 95.319975 -218.997288) (xy 95.270696 -219.0133) (xy 95.219519 -219.021406) (xy 95.167705 -219.021406)
			(xy 95.116528 -219.0133) (xy 95.067249 -218.997288) (xy 95.021082 -218.973765) (xy 94.979163 -218.943309)
			(xy 94.942525 -218.906671) (xy 94.912069 -218.864752) (xy 94.888546 -218.818585) (xy 94.872534 -218.769306)
			(xy 94.864428 -218.718129) (xy 94.86392 -218.692222) (xy 94.864518 -218.664505) (xy 94.873839 -218.609858)
			(xy 94.882462 -218.58351) (xy 94.890336 -218.561412) (xy 94.685358 -218.206574) (xy 94.662498 -218.202256)
			(xy 94.637699 -218.197049) (xy 94.589962 -218.180062) (xy 94.545385 -218.15597) (xy 94.50502 -218.125341)
			(xy 94.469817 -218.088897) (xy 94.440604 -218.047495) (xy 94.418071 -218.002112) (xy 94.402746 -217.953814)
			(xy 94.394992 -217.903741) (xy 94.394528 -217.878406) (xy 94.113604 -217.878406) (xy 94.113096 -217.904293)
			(xy 94.104997 -217.955431) (xy 94.088998 -218.004671) (xy 94.065492 -218.050803) (xy 94.03506 -218.09269)
			(xy 93.99845 -218.1293) (xy 93.956563 -218.159732) (xy 93.910431 -218.183238) (xy 93.861191 -218.199237)
			(xy 93.810053 -218.207336) (xy 93.758279 -218.207336) (xy 93.707141 -218.199237) (xy 93.657901 -218.183238)
			(xy 93.611769 -218.159732) (xy 93.569882 -218.1293) (xy 93.533272 -218.09269) (xy 93.50284 -218.050803)
			(xy 93.479334 -218.004671) (xy 93.463335 -217.955431) (xy 93.455236 -217.904293) (xy 93.454728 -217.878406)
			(xy 93.173804 -217.878406) (xy 93.173276 -217.906114) (xy 93.16408 -217.960761) (xy 93.155516 -217.987118)
			(xy 93.147642 -218.009216) (xy 93.35262 -218.364054) (xy 93.37548 -218.368372) (xy 93.4003 -218.37354)
			(xy 93.448078 -218.390497) (xy 93.492695 -218.41457) (xy 93.5331 -218.44519) (xy 93.56834 -218.481637)
			(xy 93.597584 -218.52305) (xy 93.620142 -218.568452) (xy 93.635481 -218.616773) (xy 93.643241 -218.666873)
			(xy 93.643704 -218.692222) (xy 93.643196 -218.718129) (xy 93.63509 -218.769306) (xy 93.619078 -218.818585)
			(xy 93.595555 -218.864752) (xy 93.565099 -218.906671) (xy 93.528461 -218.943309) (xy 93.486542 -218.973765)
			(xy 93.440375 -218.997288) (xy 93.391096 -219.0133) (xy 93.339919 -219.021406) (xy 93.288105 -219.021406)
			(xy 93.236928 -219.0133) (xy 93.187649 -218.997288) (xy 93.141482 -218.973765) (xy 93.099563 -218.943309)
			(xy 93.062925 -218.906671) (xy 93.032469 -218.864752) (xy 93.008946 -218.818585) (xy 92.992934 -218.769306)
			(xy 92.984828 -218.718129) (xy 92.98432 -218.692222) (xy 92.984918 -218.664505) (xy 92.994239 -218.609858)
			(xy 93.002862 -218.58351) (xy 93.010736 -218.561412) (xy 92.805758 -218.206574) (xy 92.782898 -218.202256)
			(xy 92.758099 -218.197049) (xy 92.710362 -218.180062) (xy 92.665785 -218.15597) (xy 92.62542 -218.125341)
			(xy 92.590217 -218.088897) (xy 92.561004 -218.047495) (xy 92.538471 -218.002112) (xy 92.523146 -217.953814)
			(xy 92.515392 -217.903741) (xy 92.514928 -217.878406) (xy 92.234004 -217.878406) (xy 92.233496 -217.904293)
			(xy 92.225397 -217.955431) (xy 92.209398 -218.004671) (xy 92.185892 -218.050803) (xy 92.15546 -218.09269)
			(xy 92.11885 -218.1293) (xy 92.076963 -218.159732) (xy 92.030831 -218.183238) (xy 91.981591 -218.199237)
			(xy 91.930453 -218.207336) (xy 91.878679 -218.207336) (xy 91.827541 -218.199237) (xy 91.778301 -218.183238)
			(xy 91.732169 -218.159732) (xy 91.690282 -218.1293) (xy 91.653672 -218.09269) (xy 91.62324 -218.050803)
			(xy 91.599734 -218.004671) (xy 91.583735 -217.955431) (xy 91.575636 -217.904293) (xy 91.575128 -217.878406)
			(xy 91.294204 -217.878406) (xy 91.293676 -217.906114) (xy 91.28448 -217.960761) (xy 91.275916 -217.987118)
			(xy 91.268042 -218.009216) (xy 91.47302 -218.364054) (xy 91.49588 -218.368372) (xy 91.5207 -218.37354)
			(xy 91.568478 -218.390497) (xy 91.613095 -218.41457) (xy 91.6535 -218.44519) (xy 91.68874 -218.481637)
			(xy 91.717984 -218.52305) (xy 91.740542 -218.568452) (xy 91.755881 -218.616773) (xy 91.763641 -218.666873)
			(xy 91.764104 -218.692222) (xy 91.763596 -218.718129) (xy 91.75549 -218.769306) (xy 91.739478 -218.818585)
			(xy 91.715955 -218.864752) (xy 91.685499 -218.906671) (xy 91.648861 -218.943309) (xy 91.606942 -218.973765)
			(xy 91.560775 -218.997288) (xy 91.511496 -219.0133) (xy 91.460319 -219.021406) (xy 91.408505 -219.021406)
			(xy 91.357328 -219.0133) (xy 91.308049 -218.997288) (xy 91.261882 -218.973765) (xy 91.219963 -218.943309)
			(xy 91.183325 -218.906671) (xy 91.152869 -218.864752) (xy 91.129346 -218.818585) (xy 91.113334 -218.769306)
			(xy 91.105228 -218.718129) (xy 91.10472 -218.692222) (xy 91.105318 -218.664505) (xy 91.114639 -218.609858)
			(xy 91.123262 -218.58351) (xy 91.131136 -218.561412) (xy 90.926158 -218.206574) (xy 90.903298 -218.202256)
			(xy 90.878499 -218.197049) (xy 90.830762 -218.180062) (xy 90.786185 -218.15597) (xy 90.74582 -218.125341)
			(xy 90.710617 -218.088897) (xy 90.681404 -218.047495) (xy 90.658871 -218.002112) (xy 90.643546 -217.953814)
			(xy 90.635792 -217.903741) (xy 90.635328 -217.878406) (xy 90.354404 -217.878406) (xy 90.353896 -217.904293)
			(xy 90.345797 -217.955431) (xy 90.329798 -218.004671) (xy 90.306292 -218.050803) (xy 90.27586 -218.09269)
			(xy 90.23925 -218.1293) (xy 90.197363 -218.159732) (xy 90.151231 -218.183238) (xy 90.101991 -218.199237)
			(xy 90.050853 -218.207336) (xy 89.999079 -218.207336) (xy 89.947941 -218.199237) (xy 89.898701 -218.183238)
			(xy 89.852569 -218.159732) (xy 89.810682 -218.1293) (xy 89.774072 -218.09269) (xy 89.74364 -218.050803)
			(xy 89.720134 -218.004671) (xy 89.704135 -217.955431) (xy 89.696036 -217.904293) (xy 89.695528 -217.878406)
			(xy 89.414604 -217.878406) (xy 89.414076 -217.906114) (xy 89.40488 -217.960761) (xy 89.396316 -217.987118)
			(xy 89.388442 -218.009216) (xy 89.59342 -218.364054) (xy 89.61628 -218.368372) (xy 89.6411 -218.37354)
			(xy 89.688878 -218.390497) (xy 89.733495 -218.41457) (xy 89.7739 -218.44519) (xy 89.80914 -218.481637)
			(xy 89.838384 -218.52305) (xy 89.860942 -218.568452) (xy 89.876281 -218.616773) (xy 89.884041 -218.666873)
			(xy 89.884504 -218.692222) (xy 89.883996 -218.718129) (xy 89.87589 -218.769306) (xy 89.859878 -218.818585)
			(xy 89.836355 -218.864752) (xy 89.805899 -218.906671) (xy 89.769261 -218.943309) (xy 89.727342 -218.973765)
			(xy 89.681175 -218.997288) (xy 89.631896 -219.0133) (xy 89.580719 -219.021406) (xy 89.528905 -219.021406)
			(xy 89.477728 -219.0133) (xy 89.428449 -218.997288) (xy 89.382282 -218.973765) (xy 89.340363 -218.943309)
			(xy 89.303725 -218.906671) (xy 89.273269 -218.864752) (xy 89.249746 -218.818585) (xy 89.233734 -218.769306)
			(xy 89.225628 -218.718129) (xy 89.22512 -218.692222) (xy 89.225718 -218.664505) (xy 89.235039 -218.609858)
			(xy 89.243662 -218.58351) (xy 89.251536 -218.561412) (xy 89.046558 -218.206574) (xy 89.023698 -218.202256)
			(xy 88.998899 -218.197049) (xy 88.951162 -218.180062) (xy 88.906585 -218.15597) (xy 88.86622 -218.125341)
			(xy 88.831017 -218.088897) (xy 88.801804 -218.047495) (xy 88.779271 -218.002112) (xy 88.763946 -217.953814)
			(xy 88.756192 -217.903741) (xy 88.755728 -217.878406) (xy 2.509012 -217.878406) (xy 2.509012 -221.133924)
			(xy 88.755728 -221.133924) (xy 88.756236 -221.108037) (xy 88.764335 -221.056899) (xy 88.780334 -221.007659)
			(xy 88.80384 -220.961527) (xy 88.834272 -220.91964) (xy 88.870882 -220.88303) (xy 88.912769 -220.852598)
			(xy 88.958901 -220.829092) (xy 89.008141 -220.813093) (xy 89.059279 -220.804994) (xy 89.111053 -220.804994)
			(xy 89.162191 -220.813093) (xy 89.211431 -220.829092) (xy 89.257563 -220.852598) (xy 89.29945 -220.88303)
			(xy 89.33606 -220.91964) (xy 89.366492 -220.961527) (xy 89.389998 -221.007659) (xy 89.405997 -221.056899)
			(xy 89.414096 -221.108037) (xy 89.414604 -221.133924) (xy 89.695528 -221.133924) (xy 89.69601 -221.108589)
			(xy 89.70376 -221.058515) (xy 89.71908 -221.010217) (xy 89.741611 -220.964832) (xy 89.770821 -220.923429)
			(xy 89.806022 -220.886984) (xy 89.846386 -220.856354) (xy 89.890961 -220.83226) (xy 89.938698 -220.815272)
			(xy 89.963498 -220.810074) (xy 89.986358 -220.805756) (xy 90.191336 -220.450664) (xy 90.183462 -220.42882)
			(xy 90.174829 -220.402408) (xy 90.1655 -220.347635) (xy 90.16492 -220.319854) (xy 90.165428 -220.293947)
			(xy 90.173534 -220.24277) (xy 90.189546 -220.193491) (xy 90.213069 -220.147324) (xy 90.243525 -220.105405)
			(xy 90.280163 -220.068767) (xy 90.322082 -220.038311) (xy 90.368249 -220.014788) (xy 90.417528 -219.998776)
			(xy 90.468705 -219.99067) (xy 90.520519 -219.99067) (xy 90.571696 -219.998776) (xy 90.620975 -220.014788)
			(xy 90.667142 -220.038311) (xy 90.709061 -220.068767) (xy 90.745699 -220.105405) (xy 90.776155 -220.147324)
			(xy 90.799678 -220.193491) (xy 90.81569 -220.24277) (xy 90.823796 -220.293947) (xy 90.824304 -220.319854)
			(xy 90.823828 -220.345199) (xy 90.816049 -220.395289) (xy 90.800697 -220.443599) (xy 90.778134 -220.48899)
			(xy 90.748891 -220.530396) (xy 90.713657 -220.566839) (xy 90.673262 -220.597461) (xy 90.628657 -220.621543)
			(xy 90.580893 -220.638516) (xy 90.55608 -220.643704) (xy 90.53322 -220.648022) (xy 90.328242 -221.003114)
			(xy 90.336116 -221.024958) (xy 90.34471 -221.051373) (xy 90.353897 -221.106151) (xy 90.354404 -221.133924)
			(xy 90.635328 -221.133924) (xy 90.635836 -221.108037) (xy 90.643935 -221.056899) (xy 90.659934 -221.007659)
			(xy 90.68344 -220.961527) (xy 90.713872 -220.91964) (xy 90.750482 -220.88303) (xy 90.792369 -220.852598)
			(xy 90.838501 -220.829092) (xy 90.887741 -220.813093) (xy 90.938879 -220.804994) (xy 90.990653 -220.804994)
			(xy 91.041791 -220.813093) (xy 91.091031 -220.829092) (xy 91.137163 -220.852598) (xy 91.17905 -220.88303)
			(xy 91.21566 -220.91964) (xy 91.246092 -220.961527) (xy 91.269598 -221.007659) (xy 91.285597 -221.056899)
			(xy 91.293696 -221.108037) (xy 91.294204 -221.133924) (xy 91.575128 -221.133924) (xy 91.57561 -221.108589)
			(xy 91.58336 -221.058515) (xy 91.59868 -221.010217) (xy 91.621211 -220.964832) (xy 91.650421 -220.923429)
			(xy 91.685622 -220.886984) (xy 91.725986 -220.856354) (xy 91.770561 -220.83226) (xy 91.818298 -220.815272)
			(xy 91.843098 -220.810074) (xy 91.865958 -220.805756) (xy 92.070936 -220.450664) (xy 92.063062 -220.42882)
			(xy 92.054429 -220.402408) (xy 92.0451 -220.347635) (xy 92.04452 -220.319854) (xy 92.045028 -220.293947)
			(xy 92.053134 -220.24277) (xy 92.069146 -220.193491) (xy 92.092669 -220.147324) (xy 92.123125 -220.105405)
			(xy 92.159763 -220.068767) (xy 92.201682 -220.038311) (xy 92.247849 -220.014788) (xy 92.297128 -219.998776)
			(xy 92.348305 -219.99067) (xy 92.400119 -219.99067) (xy 92.451296 -219.998776) (xy 92.500575 -220.014788)
			(xy 92.546742 -220.038311) (xy 92.588661 -220.068767) (xy 92.625299 -220.105405) (xy 92.655755 -220.147324)
			(xy 92.679278 -220.193491) (xy 92.69529 -220.24277) (xy 92.703396 -220.293947) (xy 92.703904 -220.319854)
			(xy 92.703428 -220.345199) (xy 92.695649 -220.395289) (xy 92.680297 -220.443599) (xy 92.657734 -220.48899)
			(xy 92.628491 -220.530396) (xy 92.593257 -220.566839) (xy 92.552862 -220.597461) (xy 92.508257 -220.621543)
			(xy 92.460493 -220.638516) (xy 92.43568 -220.643704) (xy 92.41282 -220.648022) (xy 92.207842 -221.003114)
			(xy 92.215716 -221.024958) (xy 92.22431 -221.051373) (xy 92.233497 -221.106151) (xy 92.234004 -221.133924)
			(xy 92.514928 -221.133924) (xy 92.515436 -221.108037) (xy 92.523535 -221.056899) (xy 92.539534 -221.007659)
			(xy 92.56304 -220.961527) (xy 92.593472 -220.91964) (xy 92.630082 -220.88303) (xy 92.671969 -220.852598)
			(xy 92.718101 -220.829092) (xy 92.767341 -220.813093) (xy 92.818479 -220.804994) (xy 92.870253 -220.804994)
			(xy 92.921391 -220.813093) (xy 92.970631 -220.829092) (xy 93.016763 -220.852598) (xy 93.05865 -220.88303)
			(xy 93.09526 -220.91964) (xy 93.125692 -220.961527) (xy 93.149198 -221.007659) (xy 93.165197 -221.056899)
			(xy 93.173296 -221.108037) (xy 93.173804 -221.133924) (xy 93.454728 -221.133924) (xy 93.45521 -221.108589)
			(xy 93.46296 -221.058515) (xy 93.47828 -221.010217) (xy 93.500811 -220.964832) (xy 93.530021 -220.923429)
			(xy 93.565222 -220.886984) (xy 93.605586 -220.856354) (xy 93.650161 -220.83226) (xy 93.697898 -220.815272)
			(xy 93.722698 -220.810074) (xy 93.745558 -220.805756) (xy 93.950536 -220.450664) (xy 93.942662 -220.42882)
			(xy 93.934029 -220.402408) (xy 93.9247 -220.347635) (xy 93.92412 -220.319854) (xy 93.924628 -220.293947)
			(xy 93.932734 -220.24277) (xy 93.948746 -220.193491) (xy 93.972269 -220.147324) (xy 94.002725 -220.105405)
			(xy 94.039363 -220.068767) (xy 94.081282 -220.038311) (xy 94.127449 -220.014788) (xy 94.176728 -219.998776)
			(xy 94.227905 -219.99067) (xy 94.279719 -219.99067) (xy 94.330896 -219.998776) (xy 94.380175 -220.014788)
			(xy 94.426342 -220.038311) (xy 94.468261 -220.068767) (xy 94.504899 -220.105405) (xy 94.535355 -220.147324)
			(xy 94.558878 -220.193491) (xy 94.57489 -220.24277) (xy 94.582996 -220.293947) (xy 94.583504 -220.319854)
			(xy 94.583028 -220.345199) (xy 94.575249 -220.395289) (xy 94.559897 -220.443599) (xy 94.537334 -220.48899)
			(xy 94.508091 -220.530396) (xy 94.472857 -220.566839) (xy 94.432462 -220.597461) (xy 94.387857 -220.621543)
			(xy 94.340093 -220.638516) (xy 94.31528 -220.643704) (xy 94.29242 -220.648022) (xy 94.087442 -221.003114)
			(xy 94.095316 -221.024958) (xy 94.10391 -221.051373) (xy 94.113097 -221.106151) (xy 94.113604 -221.133924)
			(xy 94.394528 -221.133924) (xy 94.395036 -221.108037) (xy 94.403135 -221.056899) (xy 94.419134 -221.007659)
			(xy 94.44264 -220.961527) (xy 94.473072 -220.91964) (xy 94.509682 -220.88303) (xy 94.551569 -220.852598)
			(xy 94.597701 -220.829092) (xy 94.646941 -220.813093) (xy 94.698079 -220.804994) (xy 94.749853 -220.804994)
			(xy 94.800991 -220.813093) (xy 94.850231 -220.829092) (xy 94.896363 -220.852598) (xy 94.93825 -220.88303)
			(xy 94.97486 -220.91964) (xy 95.005292 -220.961527) (xy 95.028798 -221.007659) (xy 95.044797 -221.056899)
			(xy 95.052896 -221.108037) (xy 95.053404 -221.133924) (xy 95.334328 -221.133924) (xy 95.33481 -221.108589)
			(xy 95.34256 -221.058515) (xy 95.35788 -221.010217) (xy 95.380411 -220.964832) (xy 95.409621 -220.923429)
			(xy 95.444822 -220.886984) (xy 95.485186 -220.856354) (xy 95.529761 -220.83226) (xy 95.577498 -220.815272)
			(xy 95.602298 -220.810074) (xy 95.625158 -220.805756) (xy 95.830136 -220.450664) (xy 95.822262 -220.42882)
			(xy 95.813629 -220.402408) (xy 95.8043 -220.347635) (xy 95.80372 -220.319854) (xy 95.804228 -220.293947)
			(xy 95.812334 -220.24277) (xy 95.828346 -220.193491) (xy 95.851869 -220.147324) (xy 95.882325 -220.105405)
			(xy 95.918963 -220.068767) (xy 95.960882 -220.038311) (xy 96.007049 -220.014788) (xy 96.056328 -219.998776)
			(xy 96.107505 -219.99067) (xy 96.159319 -219.99067) (xy 96.210496 -219.998776) (xy 96.259775 -220.014788)
			(xy 96.305942 -220.038311) (xy 96.347861 -220.068767) (xy 96.384499 -220.105405) (xy 96.414955 -220.147324)
			(xy 96.438478 -220.193491) (xy 96.45449 -220.24277) (xy 96.462596 -220.293947) (xy 96.463104 -220.319854)
			(xy 96.462628 -220.345199) (xy 96.454849 -220.395289) (xy 96.439497 -220.443599) (xy 96.416934 -220.48899)
			(xy 96.387691 -220.530396) (xy 96.352457 -220.566839) (xy 96.312062 -220.597461) (xy 96.267457 -220.621543)
			(xy 96.219693 -220.638516) (xy 96.19488 -220.643704) (xy 96.17202 -220.648022) (xy 95.967042 -221.003114)
			(xy 95.974916 -221.024958) (xy 95.98351 -221.051373) (xy 95.992697 -221.106151) (xy 95.993204 -221.133924)
			(xy 96.274128 -221.133924) (xy 96.274636 -221.108037) (xy 96.282735 -221.056899) (xy 96.298734 -221.007659)
			(xy 96.32224 -220.961527) (xy 96.352672 -220.91964) (xy 96.389282 -220.88303) (xy 96.431169 -220.852598)
			(xy 96.477301 -220.829092) (xy 96.526541 -220.813093) (xy 96.577679 -220.804994) (xy 96.629453 -220.804994)
			(xy 96.680591 -220.813093) (xy 96.729831 -220.829092) (xy 96.775963 -220.852598) (xy 96.81785 -220.88303)
			(xy 96.85446 -220.91964) (xy 96.884892 -220.961527) (xy 96.908398 -221.007659) (xy 96.924397 -221.056899)
			(xy 96.932496 -221.108037) (xy 96.933004 -221.133924) (xy 97.213928 -221.133924) (xy 97.21441 -221.108589)
			(xy 97.22216 -221.058515) (xy 97.23748 -221.010217) (xy 97.260011 -220.964832) (xy 97.289221 -220.923429)
			(xy 97.324422 -220.886984) (xy 97.364786 -220.856354) (xy 97.409361 -220.83226) (xy 97.457098 -220.815272)
			(xy 97.481898 -220.810074) (xy 97.504758 -220.805756) (xy 97.709736 -220.450664) (xy 97.701862 -220.42882)
			(xy 97.693229 -220.402408) (xy 97.6839 -220.347635) (xy 97.68332 -220.319854) (xy 97.683828 -220.293947)
			(xy 97.691934 -220.24277) (xy 97.707946 -220.193491) (xy 97.731469 -220.147324) (xy 97.761925 -220.105405)
			(xy 97.798563 -220.068767) (xy 97.840482 -220.038311) (xy 97.886649 -220.014788) (xy 97.935928 -219.998776)
			(xy 97.987105 -219.99067) (xy 98.038919 -219.99067) (xy 98.090096 -219.998776) (xy 98.139375 -220.014788)
			(xy 98.185542 -220.038311) (xy 98.227461 -220.068767) (xy 98.264099 -220.105405) (xy 98.294555 -220.147324)
			(xy 98.318078 -220.193491) (xy 98.33409 -220.24277) (xy 98.342196 -220.293947) (xy 98.342704 -220.319854)
			(xy 98.342228 -220.345199) (xy 98.334449 -220.395289) (xy 98.319097 -220.443599) (xy 98.296534 -220.48899)
			(xy 98.267291 -220.530396) (xy 98.232057 -220.566839) (xy 98.191662 -220.597461) (xy 98.147057 -220.621543)
			(xy 98.099293 -220.638516) (xy 98.07448 -220.643704) (xy 98.05162 -220.648022) (xy 97.846642 -221.003114)
			(xy 97.854516 -221.024958) (xy 97.86311 -221.051373) (xy 97.872297 -221.106151) (xy 97.872804 -221.133924)
			(xy 98.153728 -221.133924) (xy 98.154236 -221.108037) (xy 98.162335 -221.056899) (xy 98.178334 -221.007659)
			(xy 98.20184 -220.961527) (xy 98.232272 -220.91964) (xy 98.268882 -220.88303) (xy 98.310769 -220.852598)
			(xy 98.356901 -220.829092) (xy 98.406141 -220.813093) (xy 98.457279 -220.804994) (xy 98.509053 -220.804994)
			(xy 98.560191 -220.813093) (xy 98.609431 -220.829092) (xy 98.655563 -220.852598) (xy 98.69745 -220.88303)
			(xy 98.73406 -220.91964) (xy 98.764492 -220.961527) (xy 98.787998 -221.007659) (xy 98.803997 -221.056899)
			(xy 98.812096 -221.108037) (xy 98.812604 -221.133924) (xy 99.093528 -221.133924) (xy 99.09401 -221.108589)
			(xy 99.10176 -221.058515) (xy 99.11708 -221.010217) (xy 99.139611 -220.964832) (xy 99.168821 -220.923429)
			(xy 99.204022 -220.886984) (xy 99.244386 -220.856354) (xy 99.288961 -220.83226) (xy 99.336698 -220.815272)
			(xy 99.361498 -220.810074) (xy 99.384358 -220.805756) (xy 99.589336 -220.450664) (xy 99.581462 -220.42882)
			(xy 99.572829 -220.402408) (xy 99.5635 -220.347635) (xy 99.56292 -220.319854) (xy 99.563428 -220.293947)
			(xy 99.571534 -220.24277) (xy 99.587546 -220.193491) (xy 99.611069 -220.147324) (xy 99.641525 -220.105405)
			(xy 99.678163 -220.068767) (xy 99.720082 -220.038311) (xy 99.766249 -220.014788) (xy 99.815528 -219.998776)
			(xy 99.866705 -219.99067) (xy 99.918519 -219.99067) (xy 99.969696 -219.998776) (xy 100.018975 -220.014788)
			(xy 100.065142 -220.038311) (xy 100.107061 -220.068767) (xy 100.143699 -220.105405) (xy 100.174155 -220.147324)
			(xy 100.197678 -220.193491) (xy 100.21369 -220.24277) (xy 100.221796 -220.293947) (xy 100.222304 -220.319854)
			(xy 100.221828 -220.345199) (xy 100.214049 -220.395289) (xy 100.198697 -220.443599) (xy 100.176134 -220.48899)
			(xy 100.146891 -220.530396) (xy 100.111657 -220.566839) (xy 100.071262 -220.597461) (xy 100.026657 -220.621543)
			(xy 99.978893 -220.638516) (xy 99.95408 -220.643704) (xy 99.93122 -220.648022) (xy 99.726242 -221.003114)
			(xy 99.734116 -221.024958) (xy 99.74271 -221.051373) (xy 99.751897 -221.106151) (xy 99.752404 -221.133924)
			(xy 100.033328 -221.133924) (xy 100.033836 -221.108037) (xy 100.041935 -221.056899) (xy 100.057934 -221.007659)
			(xy 100.08144 -220.961527) (xy 100.111872 -220.91964) (xy 100.148482 -220.88303) (xy 100.190369 -220.852598)
			(xy 100.236501 -220.829092) (xy 100.285741 -220.813093) (xy 100.336879 -220.804994) (xy 100.388653 -220.804994)
			(xy 100.439791 -220.813093) (xy 100.489031 -220.829092) (xy 100.535163 -220.852598) (xy 100.57705 -220.88303)
			(xy 100.61366 -220.91964) (xy 100.644092 -220.961527) (xy 100.667598 -221.007659) (xy 100.683597 -221.056899)
			(xy 100.691696 -221.108037) (xy 100.692204 -221.133924) (xy 100.973128 -221.133924) (xy 100.97361 -221.108589)
			(xy 100.98136 -221.058515) (xy 100.99668 -221.010217) (xy 101.019211 -220.964832) (xy 101.048421 -220.923429)
			(xy 101.083622 -220.886984) (xy 101.123986 -220.856354) (xy 101.168561 -220.83226) (xy 101.216298 -220.815272)
			(xy 101.241098 -220.810074) (xy 101.263958 -220.805756) (xy 101.468936 -220.450664) (xy 101.461062 -220.42882)
			(xy 101.452429 -220.402408) (xy 101.4431 -220.347635) (xy 101.44252 -220.319854) (xy 101.443028 -220.293947)
			(xy 101.451134 -220.24277) (xy 101.467146 -220.193491) (xy 101.490669 -220.147324) (xy 101.521125 -220.105405)
			(xy 101.557763 -220.068767) (xy 101.599682 -220.038311) (xy 101.645849 -220.014788) (xy 101.695128 -219.998776)
			(xy 101.746305 -219.99067) (xy 101.798119 -219.99067) (xy 101.849296 -219.998776) (xy 101.898575 -220.014788)
			(xy 101.944742 -220.038311) (xy 101.986661 -220.068767) (xy 102.023299 -220.105405) (xy 102.053755 -220.147324)
			(xy 102.077278 -220.193491) (xy 102.09329 -220.24277) (xy 102.101396 -220.293947) (xy 102.101904 -220.319854)
			(xy 102.101428 -220.345199) (xy 102.093649 -220.395289) (xy 102.078297 -220.443599) (xy 102.055734 -220.48899)
			(xy 102.026491 -220.530396) (xy 101.991257 -220.566839) (xy 101.950862 -220.597461) (xy 101.906257 -220.621543)
			(xy 101.858493 -220.638516) (xy 101.83368 -220.643704) (xy 101.81082 -220.648022) (xy 101.605842 -221.003114)
			(xy 101.613716 -221.024958) (xy 101.62231 -221.051373) (xy 101.631497 -221.106151) (xy 101.632004 -221.133924)
			(xy 101.912928 -221.133924) (xy 101.913436 -221.108037) (xy 101.921535 -221.056899) (xy 101.937534 -221.007659)
			(xy 101.96104 -220.961527) (xy 101.991472 -220.91964) (xy 102.028082 -220.88303) (xy 102.069969 -220.852598)
			(xy 102.116101 -220.829092) (xy 102.165341 -220.813093) (xy 102.216479 -220.804994) (xy 102.268253 -220.804994)
			(xy 102.319391 -220.813093) (xy 102.368631 -220.829092) (xy 102.414763 -220.852598) (xy 102.45665 -220.88303)
			(xy 102.49326 -220.91964) (xy 102.523692 -220.961527) (xy 102.547198 -221.007659) (xy 102.563197 -221.056899)
			(xy 102.571296 -221.108037) (xy 102.571804 -221.133924) (xy 102.852728 -221.133924) (xy 102.85321 -221.108589)
			(xy 102.86096 -221.058515) (xy 102.87628 -221.010217) (xy 102.898811 -220.964832) (xy 102.928021 -220.923429)
			(xy 102.963222 -220.886984) (xy 103.003586 -220.856354) (xy 103.048161 -220.83226) (xy 103.095898 -220.815272)
			(xy 103.120698 -220.810074) (xy 103.143558 -220.805756) (xy 103.348536 -220.450664) (xy 103.340662 -220.42882)
			(xy 103.332029 -220.402408) (xy 103.3227 -220.347635) (xy 103.32212 -220.319854) (xy 103.322628 -220.293947)
			(xy 103.330734 -220.24277) (xy 103.346746 -220.193491) (xy 103.370269 -220.147324) (xy 103.400725 -220.105405)
			(xy 103.437363 -220.068767) (xy 103.479282 -220.038311) (xy 103.525449 -220.014788) (xy 103.574728 -219.998776)
			(xy 103.625905 -219.99067) (xy 103.677719 -219.99067) (xy 103.728896 -219.998776) (xy 103.778175 -220.014788)
			(xy 103.824342 -220.038311) (xy 103.866261 -220.068767) (xy 103.902899 -220.105405) (xy 103.933355 -220.147324)
			(xy 103.956878 -220.193491) (xy 103.97289 -220.24277) (xy 103.980996 -220.293947) (xy 103.981504 -220.319854)
			(xy 105.20172 -220.319854) (xy 105.202228 -220.293947) (xy 105.210334 -220.24277) (xy 105.226346 -220.193491)
			(xy 105.249869 -220.147324) (xy 105.280325 -220.105405) (xy 105.316963 -220.068767) (xy 105.358882 -220.038311)
			(xy 105.405049 -220.014788) (xy 105.454328 -219.998776) (xy 105.505505 -219.99067) (xy 105.557319 -219.99067)
			(xy 105.608496 -219.998776) (xy 105.657775 -220.014788) (xy 105.703942 -220.038311) (xy 105.745861 -220.068767)
			(xy 105.782499 -220.105405) (xy 105.812955 -220.147324) (xy 105.836478 -220.193491) (xy 105.85249 -220.24277)
			(xy 105.860596 -220.293947) (xy 105.861104 -220.319854) (xy 107.08132 -220.319854) (xy 107.081828 -220.293947)
			(xy 107.089934 -220.24277) (xy 107.105946 -220.193491) (xy 107.129469 -220.147324) (xy 107.159925 -220.105405)
			(xy 107.196563 -220.068767) (xy 107.238482 -220.038311) (xy 107.284649 -220.014788) (xy 107.333928 -219.998776)
			(xy 107.385105 -219.99067) (xy 107.436919 -219.99067) (xy 107.488096 -219.998776) (xy 107.537375 -220.014788)
			(xy 107.583542 -220.038311) (xy 107.625461 -220.068767) (xy 107.662099 -220.105405) (xy 107.692555 -220.147324)
			(xy 107.716078 -220.193491) (xy 107.73209 -220.24277) (xy 107.740196 -220.293947) (xy 107.740704 -220.319854)
			(xy 108.96092 -220.319854) (xy 108.961428 -220.293947) (xy 108.969534 -220.24277) (xy 108.985546 -220.193491)
			(xy 109.009069 -220.147324) (xy 109.039525 -220.105405) (xy 109.076163 -220.068767) (xy 109.118082 -220.038311)
			(xy 109.164249 -220.014788) (xy 109.213528 -219.998776) (xy 109.264705 -219.99067) (xy 109.316519 -219.99067)
			(xy 109.367696 -219.998776) (xy 109.416975 -220.014788) (xy 109.463142 -220.038311) (xy 109.505061 -220.068767)
			(xy 109.541699 -220.105405) (xy 109.572155 -220.147324) (xy 109.595678 -220.193491) (xy 109.61169 -220.24277)
			(xy 109.619796 -220.293947) (xy 109.620304 -220.319854) (xy 110.84052 -220.319854) (xy 110.841028 -220.293947)
			(xy 110.849134 -220.24277) (xy 110.865146 -220.193491) (xy 110.888669 -220.147324) (xy 110.919125 -220.105405)
			(xy 110.955763 -220.068767) (xy 110.997682 -220.038311) (xy 111.043849 -220.014788) (xy 111.093128 -219.998776)
			(xy 111.144305 -219.99067) (xy 111.196119 -219.99067) (xy 111.247296 -219.998776) (xy 111.296575 -220.014788)
			(xy 111.342742 -220.038311) (xy 111.384661 -220.068767) (xy 111.421299 -220.105405) (xy 111.451755 -220.147324)
			(xy 111.475278 -220.193491) (xy 111.49129 -220.24277) (xy 111.499396 -220.293947) (xy 111.499904 -220.319854)
			(xy 112.72012 -220.319854) (xy 112.720628 -220.293947) (xy 112.728734 -220.24277) (xy 112.744746 -220.193491)
			(xy 112.768269 -220.147324) (xy 112.798725 -220.105405) (xy 112.835363 -220.068767) (xy 112.877282 -220.038311)
			(xy 112.923449 -220.014788) (xy 112.972728 -219.998776) (xy 113.023905 -219.99067) (xy 113.075719 -219.99067)
			(xy 113.126896 -219.998776) (xy 113.176175 -220.014788) (xy 113.222342 -220.038311) (xy 113.264261 -220.068767)
			(xy 113.300899 -220.105405) (xy 113.331355 -220.147324) (xy 113.354878 -220.193491) (xy 113.37089 -220.24277)
			(xy 113.378996 -220.293947) (xy 113.379504 -220.319854) (xy 114.59972 -220.319854) (xy 114.600228 -220.293947)
			(xy 114.608334 -220.24277) (xy 114.624346 -220.193491) (xy 114.647869 -220.147324) (xy 114.678325 -220.105405)
			(xy 114.714963 -220.068767) (xy 114.756882 -220.038311) (xy 114.803049 -220.014788) (xy 114.852328 -219.998776)
			(xy 114.903505 -219.99067) (xy 114.955319 -219.99067) (xy 115.006496 -219.998776) (xy 115.055775 -220.014788)
			(xy 115.101942 -220.038311) (xy 115.143861 -220.068767) (xy 115.180499 -220.105405) (xy 115.210955 -220.147324)
			(xy 115.234478 -220.193491) (xy 115.25049 -220.24277) (xy 115.258596 -220.293947) (xy 115.259104 -220.319854)
			(xy 116.47932 -220.319854) (xy 116.479828 -220.293947) (xy 116.487934 -220.24277) (xy 116.503946 -220.193491)
			(xy 116.527469 -220.147324) (xy 116.557925 -220.105405) (xy 116.594563 -220.068767) (xy 116.636482 -220.038311)
			(xy 116.682649 -220.014788) (xy 116.731928 -219.998776) (xy 116.783105 -219.99067) (xy 116.834919 -219.99067)
			(xy 116.886096 -219.998776) (xy 116.935375 -220.014788) (xy 116.981542 -220.038311) (xy 117.023461 -220.068767)
			(xy 117.060099 -220.105405) (xy 117.090555 -220.147324) (xy 117.114078 -220.193491) (xy 117.13009 -220.24277)
			(xy 117.138196 -220.293947) (xy 117.138704 -220.319854) (xy 118.35892 -220.319854) (xy 118.359428 -220.293947)
			(xy 118.367534 -220.24277) (xy 118.383546 -220.193491) (xy 118.407069 -220.147324) (xy 118.437525 -220.105405)
			(xy 118.474163 -220.068767) (xy 118.516082 -220.038311) (xy 118.562249 -220.014788) (xy 118.611528 -219.998776)
			(xy 118.662705 -219.99067) (xy 118.714519 -219.99067) (xy 118.765696 -219.998776) (xy 118.814975 -220.014788)
			(xy 118.861142 -220.038311) (xy 118.903061 -220.068767) (xy 118.939699 -220.105405) (xy 118.970155 -220.147324)
			(xy 118.993678 -220.193491) (xy 119.00969 -220.24277) (xy 119.017796 -220.293947) (xy 119.018304 -220.319854)
			(xy 120.23852 -220.319854) (xy 120.239028 -220.293947) (xy 120.247134 -220.24277) (xy 120.263146 -220.193491)
			(xy 120.286669 -220.147324) (xy 120.317125 -220.105405) (xy 120.353763 -220.068767) (xy 120.395682 -220.038311)
			(xy 120.441849 -220.014788) (xy 120.491128 -219.998776) (xy 120.542305 -219.99067) (xy 120.594119 -219.99067)
			(xy 120.645296 -219.998776) (xy 120.694575 -220.014788) (xy 120.740742 -220.038311) (xy 120.782661 -220.068767)
			(xy 120.819299 -220.105405) (xy 120.849755 -220.147324) (xy 120.873278 -220.193491) (xy 120.88929 -220.24277)
			(xy 120.897396 -220.293947) (xy 120.897904 -220.319854) (xy 122.11812 -220.319854) (xy 122.118628 -220.293947)
			(xy 122.126734 -220.24277) (xy 122.142746 -220.193491) (xy 122.166269 -220.147324) (xy 122.196725 -220.105405)
			(xy 122.233363 -220.068767) (xy 122.275282 -220.038311) (xy 122.321449 -220.014788) (xy 122.370728 -219.998776)
			(xy 122.421905 -219.99067) (xy 122.473719 -219.99067) (xy 122.524896 -219.998776) (xy 122.574175 -220.014788)
			(xy 122.620342 -220.038311) (xy 122.662261 -220.068767) (xy 122.698899 -220.105405) (xy 122.729355 -220.147324)
			(xy 122.752878 -220.193491) (xy 122.76889 -220.24277) (xy 122.776996 -220.293947) (xy 122.777504 -220.319854)
			(xy 123.99772 -220.319854) (xy 123.998228 -220.293947) (xy 124.006334 -220.24277) (xy 124.022346 -220.193491)
			(xy 124.045869 -220.147324) (xy 124.076325 -220.105405) (xy 124.112963 -220.068767) (xy 124.154882 -220.038311)
			(xy 124.201049 -220.014788) (xy 124.250328 -219.998776) (xy 124.301505 -219.99067) (xy 124.353319 -219.99067)
			(xy 124.404496 -219.998776) (xy 124.453775 -220.014788) (xy 124.499942 -220.038311) (xy 124.541861 -220.068767)
			(xy 124.578499 -220.105405) (xy 124.608955 -220.147324) (xy 124.632478 -220.193491) (xy 124.64849 -220.24277)
			(xy 124.656596 -220.293947) (xy 124.657104 -220.319854) (xy 125.87732 -220.319854) (xy 125.877828 -220.293947)
			(xy 125.885934 -220.24277) (xy 125.901946 -220.193491) (xy 125.925469 -220.147324) (xy 125.955925 -220.105405)
			(xy 125.992563 -220.068767) (xy 126.034482 -220.038311) (xy 126.080649 -220.014788) (xy 126.129928 -219.998776)
			(xy 126.181105 -219.99067) (xy 126.232919 -219.99067) (xy 126.284096 -219.998776) (xy 126.333375 -220.014788)
			(xy 126.379542 -220.038311) (xy 126.421461 -220.068767) (xy 126.458099 -220.105405) (xy 126.488555 -220.147324)
			(xy 126.512078 -220.193491) (xy 126.52809 -220.24277) (xy 126.536196 -220.293947) (xy 126.536704 -220.319854)
			(xy 127.75692 -220.319854) (xy 127.757428 -220.293947) (xy 127.765534 -220.24277) (xy 127.781546 -220.193491)
			(xy 127.805069 -220.147324) (xy 127.835525 -220.105405) (xy 127.872163 -220.068767) (xy 127.914082 -220.038311)
			(xy 127.960249 -220.014788) (xy 128.009528 -219.998776) (xy 128.060705 -219.99067) (xy 128.112519 -219.99067)
			(xy 128.163696 -219.998776) (xy 128.212975 -220.014788) (xy 128.259142 -220.038311) (xy 128.301061 -220.068767)
			(xy 128.337699 -220.105405) (xy 128.368155 -220.147324) (xy 128.391678 -220.193491) (xy 128.40769 -220.24277)
			(xy 128.415796 -220.293947) (xy 128.416304 -220.319854) (xy 129.63652 -220.319854) (xy 129.637028 -220.293947)
			(xy 129.645134 -220.24277) (xy 129.661146 -220.193491) (xy 129.684669 -220.147324) (xy 129.715125 -220.105405)
			(xy 129.751763 -220.068767) (xy 129.793682 -220.038311) (xy 129.839849 -220.014788) (xy 129.889128 -219.998776)
			(xy 129.940305 -219.99067) (xy 129.992119 -219.99067) (xy 130.043296 -219.998776) (xy 130.092575 -220.014788)
			(xy 130.138742 -220.038311) (xy 130.180661 -220.068767) (xy 130.217299 -220.105405) (xy 130.247755 -220.147324)
			(xy 130.271278 -220.193491) (xy 130.28729 -220.24277) (xy 130.295396 -220.293947) (xy 130.295904 -220.319854)
			(xy 131.51612 -220.319854) (xy 131.516628 -220.293947) (xy 131.524734 -220.24277) (xy 131.540746 -220.193491)
			(xy 131.564269 -220.147324) (xy 131.594725 -220.105405) (xy 131.631363 -220.068767) (xy 131.673282 -220.038311)
			(xy 131.719449 -220.014788) (xy 131.768728 -219.998776) (xy 131.819905 -219.99067) (xy 131.871719 -219.99067)
			(xy 131.922896 -219.998776) (xy 131.972175 -220.014788) (xy 132.018342 -220.038311) (xy 132.060261 -220.068767)
			(xy 132.096899 -220.105405) (xy 132.127355 -220.147324) (xy 132.150878 -220.193491) (xy 132.16689 -220.24277)
			(xy 132.174996 -220.293947) (xy 132.175504 -220.319854) (xy 133.396228 -220.319854) (xy 133.396736 -220.293967)
			(xy 133.404835 -220.242829) (xy 133.420834 -220.193589) (xy 133.44434 -220.147457) (xy 133.474772 -220.10557)
			(xy 133.511382 -220.06896) (xy 133.553269 -220.038528) (xy 133.599401 -220.015022) (xy 133.648641 -219.999023)
			(xy 133.699779 -219.990924) (xy 133.751553 -219.990924) (xy 133.802691 -219.999023) (xy 133.851931 -220.015022)
			(xy 133.898063 -220.038528) (xy 133.93995 -220.06896) (xy 133.97656 -220.10557) (xy 134.006992 -220.147457)
			(xy 134.030498 -220.193589) (xy 134.046497 -220.242829) (xy 134.054596 -220.293967) (xy 134.055104 -220.319854)
			(xy 134.054563 -220.347562) (xy 134.045375 -220.402208) (xy 134.036816 -220.428566) (xy 134.029196 -220.450664)
			(xy 134.234174 -220.805756) (xy 134.257034 -220.810074) (xy 134.281845 -220.815229) (xy 134.329584 -220.832223)
			(xy 134.374162 -220.856322) (xy 134.414527 -220.886957) (xy 134.44973 -220.923408) (xy 134.47894 -220.964816)
			(xy 134.501472 -221.010206) (xy 134.516792 -221.058509) (xy 134.524542 -221.108587) (xy 134.525004 -221.133924)
			(xy 134.524496 -221.159811) (xy 134.516397 -221.210949) (xy 134.500398 -221.260189) (xy 134.476892 -221.306321)
			(xy 134.44646 -221.348208) (xy 134.40985 -221.384818) (xy 134.367963 -221.41525) (xy 134.321831 -221.438756)
			(xy 134.272591 -221.454755) (xy 134.221453 -221.462854) (xy 134.169679 -221.462854) (xy 134.118541 -221.454755)
			(xy 134.069301 -221.438756) (xy 134.023169 -221.41525) (xy 133.981282 -221.384818) (xy 133.944672 -221.348208)
			(xy 133.91424 -221.306321) (xy 133.890734 -221.260189) (xy 133.874735 -221.210949) (xy 133.866636 -221.159811)
			(xy 133.866128 -221.133924) (xy 133.866667 -221.106216) (xy 133.875856 -221.05157) (xy 133.884416 -221.025212)
			(xy 133.89229 -221.003114) (xy 133.687312 -220.648022) (xy 133.664452 -220.643704) (xy 133.639631 -220.638536)
			(xy 133.591852 -220.621582) (xy 133.547233 -220.59751) (xy 133.506826 -220.56689) (xy 133.471585 -220.530444)
			(xy 133.442341 -220.48903) (xy 133.419784 -220.443627) (xy 133.404447 -220.395304) (xy 133.39669 -220.345203)
			(xy 133.396228 -220.319854) (xy 132.175504 -220.319854) (xy 132.174894 -220.347507) (xy 132.165571 -220.402025)
			(xy 132.156962 -220.428312) (xy 132.149342 -220.45041) (xy 132.354574 -220.805756) (xy 132.377434 -220.810074)
			(xy 132.402245 -220.815229) (xy 132.449984 -220.832223) (xy 132.494562 -220.856322) (xy 132.534927 -220.886957)
			(xy 132.57013 -220.923408) (xy 132.59934 -220.964816) (xy 132.621872 -221.010206) (xy 132.637192 -221.058509)
			(xy 132.644942 -221.108587) (xy 132.645404 -221.133924) (xy 132.644896 -221.159811) (xy 132.636797 -221.210949)
			(xy 132.620798 -221.260189) (xy 132.597292 -221.306321) (xy 132.56686 -221.348208) (xy 132.53025 -221.384818)
			(xy 132.488363 -221.41525) (xy 132.442231 -221.438756) (xy 132.392991 -221.454755) (xy 132.341853 -221.462854)
			(xy 132.290079 -221.462854) (xy 132.238941 -221.454755) (xy 132.189701 -221.438756) (xy 132.143569 -221.41525)
			(xy 132.101682 -221.384818) (xy 132.065072 -221.348208) (xy 132.03464 -221.306321) (xy 132.011134 -221.260189)
			(xy 131.995135 -221.210949) (xy 131.987036 -221.159811) (xy 131.986528 -221.133924) (xy 131.987067 -221.106216)
			(xy 131.996256 -221.05157) (xy 132.004816 -221.025212) (xy 132.01269 -221.003114) (xy 131.807712 -220.648022)
			(xy 131.784852 -220.643704) (xy 131.76 -220.63857) (xy 131.712153 -220.621668) (xy 131.667462 -220.597632)
			(xy 131.626984 -220.567029) (xy 131.591674 -220.530584) (xy 131.562368 -220.489157) (xy 131.539757 -220.443728)
			(xy 131.524377 -220.39537) (xy 131.516591 -220.345226) (xy 131.51612 -220.319854) (xy 130.295904 -220.319854)
			(xy 130.295294 -220.347507) (xy 130.285971 -220.402025) (xy 130.277362 -220.428312) (xy 130.269742 -220.45041)
			(xy 130.474974 -220.805756) (xy 130.497834 -220.810074) (xy 130.522645 -220.815229) (xy 130.570384 -220.832223)
			(xy 130.614962 -220.856322) (xy 130.655327 -220.886957) (xy 130.69053 -220.923408) (xy 130.71974 -220.964816)
			(xy 130.742272 -221.010206) (xy 130.757592 -221.058509) (xy 130.765342 -221.108587) (xy 130.765804 -221.133924)
			(xy 130.765296 -221.159811) (xy 130.757197 -221.210949) (xy 130.741198 -221.260189) (xy 130.717692 -221.306321)
			(xy 130.68726 -221.348208) (xy 130.65065 -221.384818) (xy 130.608763 -221.41525) (xy 130.562631 -221.438756)
			(xy 130.513391 -221.454755) (xy 130.462253 -221.462854) (xy 130.410479 -221.462854) (xy 130.359341 -221.454755)
			(xy 130.310101 -221.438756) (xy 130.263969 -221.41525) (xy 130.222082 -221.384818) (xy 130.185472 -221.348208)
			(xy 130.15504 -221.306321) (xy 130.131534 -221.260189) (xy 130.115535 -221.210949) (xy 130.107436 -221.159811)
			(xy 130.106928 -221.133924) (xy 130.107467 -221.106216) (xy 130.116656 -221.05157) (xy 130.125216 -221.025212)
			(xy 130.13309 -221.003114) (xy 129.928112 -220.648022) (xy 129.905252 -220.643704) (xy 129.8804 -220.63857)
			(xy 129.832553 -220.621668) (xy 129.787862 -220.597632) (xy 129.747384 -220.567029) (xy 129.712074 -220.530584)
			(xy 129.682768 -220.489157) (xy 129.660157 -220.443728) (xy 129.644777 -220.39537) (xy 129.636991 -220.345226)
			(xy 129.63652 -220.319854) (xy 128.416304 -220.319854) (xy 128.415694 -220.347507) (xy 128.406371 -220.402025)
			(xy 128.397762 -220.428312) (xy 128.390142 -220.45041) (xy 128.595374 -220.805756) (xy 128.618234 -220.810074)
			(xy 128.643045 -220.815229) (xy 128.690784 -220.832223) (xy 128.735362 -220.856322) (xy 128.775727 -220.886957)
			(xy 128.81093 -220.923408) (xy 128.84014 -220.964816) (xy 128.862672 -221.010206) (xy 128.877992 -221.058509)
			(xy 128.885742 -221.108587) (xy 128.886204 -221.133924) (xy 128.885696 -221.159811) (xy 128.877597 -221.210949)
			(xy 128.861598 -221.260189) (xy 128.838092 -221.306321) (xy 128.80766 -221.348208) (xy 128.77105 -221.384818)
			(xy 128.729163 -221.41525) (xy 128.683031 -221.438756) (xy 128.633791 -221.454755) (xy 128.582653 -221.462854)
			(xy 128.530879 -221.462854) (xy 128.479741 -221.454755) (xy 128.430501 -221.438756) (xy 128.384369 -221.41525)
			(xy 128.342482 -221.384818) (xy 128.305872 -221.348208) (xy 128.27544 -221.306321) (xy 128.251934 -221.260189)
			(xy 128.235935 -221.210949) (xy 128.227836 -221.159811) (xy 128.227328 -221.133924) (xy 128.227867 -221.106216)
			(xy 128.237056 -221.05157) (xy 128.245616 -221.025212) (xy 128.25349 -221.003114) (xy 128.048512 -220.648022)
			(xy 128.025652 -220.643704) (xy 128.0008 -220.63857) (xy 127.952953 -220.621668) (xy 127.908262 -220.597632)
			(xy 127.867784 -220.567029) (xy 127.832474 -220.530584) (xy 127.803168 -220.489157) (xy 127.780557 -220.443728)
			(xy 127.765177 -220.39537) (xy 127.757391 -220.345226) (xy 127.75692 -220.319854) (xy 126.536704 -220.319854)
			(xy 126.536094 -220.347507) (xy 126.526771 -220.402025) (xy 126.518162 -220.428312) (xy 126.510542 -220.45041)
			(xy 126.715774 -220.805756) (xy 126.738634 -220.810074) (xy 126.763445 -220.815229) (xy 126.811184 -220.832223)
			(xy 126.855762 -220.856322) (xy 126.896127 -220.886957) (xy 126.93133 -220.923408) (xy 126.96054 -220.964816)
			(xy 126.983072 -221.010206) (xy 126.998392 -221.058509) (xy 127.006142 -221.108587) (xy 127.006604 -221.133924)
			(xy 127.006096 -221.159811) (xy 126.997997 -221.210949) (xy 126.981998 -221.260189) (xy 126.958492 -221.306321)
			(xy 126.92806 -221.348208) (xy 126.89145 -221.384818) (xy 126.849563 -221.41525) (xy 126.803431 -221.438756)
			(xy 126.754191 -221.454755) (xy 126.703053 -221.462854) (xy 126.651279 -221.462854) (xy 126.600141 -221.454755)
			(xy 126.550901 -221.438756) (xy 126.504769 -221.41525) (xy 126.462882 -221.384818) (xy 126.426272 -221.348208)
			(xy 126.39584 -221.306321) (xy 126.372334 -221.260189) (xy 126.356335 -221.210949) (xy 126.348236 -221.159811)
			(xy 126.347728 -221.133924) (xy 126.348267 -221.106216) (xy 126.357456 -221.05157) (xy 126.366016 -221.025212)
			(xy 126.37389 -221.003114) (xy 126.168912 -220.648022) (xy 126.146052 -220.643704) (xy 126.1212 -220.63857)
			(xy 126.073353 -220.621668) (xy 126.028662 -220.597632) (xy 125.988184 -220.567029) (xy 125.952874 -220.530584)
			(xy 125.923568 -220.489157) (xy 125.900957 -220.443728) (xy 125.885577 -220.39537) (xy 125.877791 -220.345226)
			(xy 125.87732 -220.319854) (xy 124.657104 -220.319854) (xy 124.656494 -220.347507) (xy 124.647171 -220.402025)
			(xy 124.638562 -220.428312) (xy 124.630942 -220.45041) (xy 124.836174 -220.805756) (xy 124.859034 -220.810074)
			(xy 124.883845 -220.815229) (xy 124.931584 -220.832223) (xy 124.976162 -220.856322) (xy 125.016527 -220.886957)
			(xy 125.05173 -220.923408) (xy 125.08094 -220.964816) (xy 125.103472 -221.010206) (xy 125.118792 -221.058509)
			(xy 125.126542 -221.108587) (xy 125.127004 -221.133924) (xy 125.126496 -221.159811) (xy 125.118397 -221.210949)
			(xy 125.102398 -221.260189) (xy 125.078892 -221.306321) (xy 125.04846 -221.348208) (xy 125.01185 -221.384818)
			(xy 124.969963 -221.41525) (xy 124.923831 -221.438756) (xy 124.874591 -221.454755) (xy 124.823453 -221.462854)
			(xy 124.771679 -221.462854) (xy 124.720541 -221.454755) (xy 124.671301 -221.438756) (xy 124.625169 -221.41525)
			(xy 124.583282 -221.384818) (xy 124.546672 -221.348208) (xy 124.51624 -221.306321) (xy 124.492734 -221.260189)
			(xy 124.476735 -221.210949) (xy 124.468636 -221.159811) (xy 124.468128 -221.133924) (xy 124.468667 -221.106216)
			(xy 124.477856 -221.05157) (xy 124.486416 -221.025212) (xy 124.49429 -221.003114) (xy 124.289312 -220.648022)
			(xy 124.266452 -220.643704) (xy 124.2416 -220.63857) (xy 124.193753 -220.621668) (xy 124.149062 -220.597632)
			(xy 124.108584 -220.567029) (xy 124.073274 -220.530584) (xy 124.043968 -220.489157) (xy 124.021357 -220.443728)
			(xy 124.005977 -220.39537) (xy 123.998191 -220.345226) (xy 123.99772 -220.319854) (xy 122.777504 -220.319854)
			(xy 122.776894 -220.347507) (xy 122.767571 -220.402025) (xy 122.758962 -220.428312) (xy 122.751342 -220.45041)
			(xy 122.956574 -220.805756) (xy 122.979434 -220.810074) (xy 123.004245 -220.815229) (xy 123.051984 -220.832223)
			(xy 123.096562 -220.856322) (xy 123.136927 -220.886957) (xy 123.17213 -220.923408) (xy 123.20134 -220.964816)
			(xy 123.223872 -221.010206) (xy 123.239192 -221.058509) (xy 123.246942 -221.108587) (xy 123.247404 -221.133924)
			(xy 123.246896 -221.159811) (xy 123.238797 -221.210949) (xy 123.222798 -221.260189) (xy 123.199292 -221.306321)
			(xy 123.16886 -221.348208) (xy 123.13225 -221.384818) (xy 123.090363 -221.41525) (xy 123.044231 -221.438756)
			(xy 122.994991 -221.454755) (xy 122.943853 -221.462854) (xy 122.892079 -221.462854) (xy 122.840941 -221.454755)
			(xy 122.791701 -221.438756) (xy 122.745569 -221.41525) (xy 122.703682 -221.384818) (xy 122.667072 -221.348208)
			(xy 122.63664 -221.306321) (xy 122.613134 -221.260189) (xy 122.597135 -221.210949) (xy 122.589036 -221.159811)
			(xy 122.588528 -221.133924) (xy 122.589067 -221.106216) (xy 122.598256 -221.05157) (xy 122.606816 -221.025212)
			(xy 122.61469 -221.003114) (xy 122.409712 -220.648022) (xy 122.386852 -220.643704) (xy 122.362 -220.63857)
			(xy 122.314153 -220.621668) (xy 122.269462 -220.597632) (xy 122.228984 -220.567029) (xy 122.193674 -220.530584)
			(xy 122.164368 -220.489157) (xy 122.141757 -220.443728) (xy 122.126377 -220.39537) (xy 122.118591 -220.345226)
			(xy 122.11812 -220.319854) (xy 120.897904 -220.319854) (xy 120.897294 -220.347507) (xy 120.887971 -220.402025)
			(xy 120.879362 -220.428312) (xy 120.871742 -220.45041) (xy 121.076974 -220.805756) (xy 121.099834 -220.810074)
			(xy 121.124645 -220.815229) (xy 121.172384 -220.832223) (xy 121.216962 -220.856322) (xy 121.257327 -220.886957)
			(xy 121.29253 -220.923408) (xy 121.32174 -220.964816) (xy 121.344272 -221.010206) (xy 121.359592 -221.058509)
			(xy 121.367342 -221.108587) (xy 121.367804 -221.133924) (xy 121.367296 -221.159811) (xy 121.359197 -221.210949)
			(xy 121.343198 -221.260189) (xy 121.319692 -221.306321) (xy 121.28926 -221.348208) (xy 121.25265 -221.384818)
			(xy 121.210763 -221.41525) (xy 121.164631 -221.438756) (xy 121.115391 -221.454755) (xy 121.064253 -221.462854)
			(xy 121.012479 -221.462854) (xy 120.961341 -221.454755) (xy 120.912101 -221.438756) (xy 120.865969 -221.41525)
			(xy 120.824082 -221.384818) (xy 120.787472 -221.348208) (xy 120.75704 -221.306321) (xy 120.733534 -221.260189)
			(xy 120.717535 -221.210949) (xy 120.709436 -221.159811) (xy 120.708928 -221.133924) (xy 120.709467 -221.106216)
			(xy 120.718656 -221.05157) (xy 120.727216 -221.025212) (xy 120.73509 -221.003114) (xy 120.530112 -220.648022)
			(xy 120.507252 -220.643704) (xy 120.4824 -220.63857) (xy 120.434553 -220.621668) (xy 120.389862 -220.597632)
			(xy 120.349384 -220.567029) (xy 120.314074 -220.530584) (xy 120.284768 -220.489157) (xy 120.262157 -220.443728)
			(xy 120.246777 -220.39537) (xy 120.238991 -220.345226) (xy 120.23852 -220.319854) (xy 119.018304 -220.319854)
			(xy 119.017694 -220.347507) (xy 119.008371 -220.402025) (xy 118.999762 -220.428312) (xy 118.992142 -220.45041)
			(xy 119.197374 -220.805756) (xy 119.220234 -220.810074) (xy 119.245045 -220.815229) (xy 119.292784 -220.832223)
			(xy 119.337362 -220.856322) (xy 119.377727 -220.886957) (xy 119.41293 -220.923408) (xy 119.44214 -220.964816)
			(xy 119.464672 -221.010206) (xy 119.479992 -221.058509) (xy 119.487742 -221.108587) (xy 119.488204 -221.133924)
			(xy 119.487696 -221.159811) (xy 119.479597 -221.210949) (xy 119.463598 -221.260189) (xy 119.440092 -221.306321)
			(xy 119.40966 -221.348208) (xy 119.37305 -221.384818) (xy 119.331163 -221.41525) (xy 119.285031 -221.438756)
			(xy 119.235791 -221.454755) (xy 119.184653 -221.462854) (xy 119.132879 -221.462854) (xy 119.081741 -221.454755)
			(xy 119.032501 -221.438756) (xy 118.986369 -221.41525) (xy 118.944482 -221.384818) (xy 118.907872 -221.348208)
			(xy 118.87744 -221.306321) (xy 118.853934 -221.260189) (xy 118.837935 -221.210949) (xy 118.829836 -221.159811)
			(xy 118.829328 -221.133924) (xy 118.829867 -221.106216) (xy 118.839056 -221.05157) (xy 118.847616 -221.025212)
			(xy 118.85549 -221.003114) (xy 118.650512 -220.648022) (xy 118.627652 -220.643704) (xy 118.6028 -220.63857)
			(xy 118.554953 -220.621668) (xy 118.510262 -220.597632) (xy 118.469784 -220.567029) (xy 118.434474 -220.530584)
			(xy 118.405168 -220.489157) (xy 118.382557 -220.443728) (xy 118.367177 -220.39537) (xy 118.359391 -220.345226)
			(xy 118.35892 -220.319854) (xy 117.138704 -220.319854) (xy 117.138094 -220.347507) (xy 117.128771 -220.402025)
			(xy 117.120162 -220.428312) (xy 117.112542 -220.45041) (xy 117.317774 -220.805756) (xy 117.340634 -220.810074)
			(xy 117.365445 -220.815229) (xy 117.413184 -220.832223) (xy 117.457762 -220.856322) (xy 117.498127 -220.886957)
			(xy 117.53333 -220.923408) (xy 117.56254 -220.964816) (xy 117.585072 -221.010206) (xy 117.600392 -221.058509)
			(xy 117.608142 -221.108587) (xy 117.608604 -221.133924) (xy 117.608096 -221.159811) (xy 117.599997 -221.210949)
			(xy 117.583998 -221.260189) (xy 117.560492 -221.306321) (xy 117.53006 -221.348208) (xy 117.49345 -221.384818)
			(xy 117.451563 -221.41525) (xy 117.405431 -221.438756) (xy 117.356191 -221.454755) (xy 117.305053 -221.462854)
			(xy 117.253279 -221.462854) (xy 117.202141 -221.454755) (xy 117.152901 -221.438756) (xy 117.106769 -221.41525)
			(xy 117.064882 -221.384818) (xy 117.028272 -221.348208) (xy 116.99784 -221.306321) (xy 116.974334 -221.260189)
			(xy 116.958335 -221.210949) (xy 116.950236 -221.159811) (xy 116.949728 -221.133924) (xy 116.950267 -221.106216)
			(xy 116.959456 -221.05157) (xy 116.968016 -221.025212) (xy 116.97589 -221.003114) (xy 116.770912 -220.648022)
			(xy 116.748052 -220.643704) (xy 116.7232 -220.63857) (xy 116.675353 -220.621668) (xy 116.630662 -220.597632)
			(xy 116.590184 -220.567029) (xy 116.554874 -220.530584) (xy 116.525568 -220.489157) (xy 116.502957 -220.443728)
			(xy 116.487577 -220.39537) (xy 116.479791 -220.345226) (xy 116.47932 -220.319854) (xy 115.259104 -220.319854)
			(xy 115.258494 -220.347507) (xy 115.249171 -220.402025) (xy 115.240562 -220.428312) (xy 115.232942 -220.45041)
			(xy 115.438174 -220.805756) (xy 115.461034 -220.810074) (xy 115.485845 -220.815229) (xy 115.533584 -220.832223)
			(xy 115.578162 -220.856322) (xy 115.618527 -220.886957) (xy 115.65373 -220.923408) (xy 115.68294 -220.964816)
			(xy 115.705472 -221.010206) (xy 115.720792 -221.058509) (xy 115.728542 -221.108587) (xy 115.729004 -221.133924)
			(xy 115.728496 -221.159811) (xy 115.720397 -221.210949) (xy 115.704398 -221.260189) (xy 115.680892 -221.306321)
			(xy 115.65046 -221.348208) (xy 115.61385 -221.384818) (xy 115.571963 -221.41525) (xy 115.525831 -221.438756)
			(xy 115.476591 -221.454755) (xy 115.425453 -221.462854) (xy 115.373679 -221.462854) (xy 115.322541 -221.454755)
			(xy 115.273301 -221.438756) (xy 115.227169 -221.41525) (xy 115.185282 -221.384818) (xy 115.148672 -221.348208)
			(xy 115.11824 -221.306321) (xy 115.094734 -221.260189) (xy 115.078735 -221.210949) (xy 115.070636 -221.159811)
			(xy 115.070128 -221.133924) (xy 115.070667 -221.106216) (xy 115.079856 -221.05157) (xy 115.088416 -221.025212)
			(xy 115.09629 -221.003114) (xy 114.891312 -220.648022) (xy 114.868452 -220.643704) (xy 114.8436 -220.63857)
			(xy 114.795753 -220.621668) (xy 114.751062 -220.597632) (xy 114.710584 -220.567029) (xy 114.675274 -220.530584)
			(xy 114.645968 -220.489157) (xy 114.623357 -220.443728) (xy 114.607977 -220.39537) (xy 114.600191 -220.345226)
			(xy 114.59972 -220.319854) (xy 113.379504 -220.319854) (xy 113.378894 -220.347507) (xy 113.369571 -220.402025)
			(xy 113.360962 -220.428312) (xy 113.353342 -220.45041) (xy 113.558574 -220.805756) (xy 113.581434 -220.810074)
			(xy 113.606245 -220.815229) (xy 113.653984 -220.832223) (xy 113.698562 -220.856322) (xy 113.738927 -220.886957)
			(xy 113.77413 -220.923408) (xy 113.80334 -220.964816) (xy 113.825872 -221.010206) (xy 113.841192 -221.058509)
			(xy 113.848942 -221.108587) (xy 113.849404 -221.133924) (xy 113.848896 -221.159811) (xy 113.840797 -221.210949)
			(xy 113.824798 -221.260189) (xy 113.801292 -221.306321) (xy 113.77086 -221.348208) (xy 113.73425 -221.384818)
			(xy 113.692363 -221.41525) (xy 113.646231 -221.438756) (xy 113.596991 -221.454755) (xy 113.545853 -221.462854)
			(xy 113.494079 -221.462854) (xy 113.442941 -221.454755) (xy 113.393701 -221.438756) (xy 113.347569 -221.41525)
			(xy 113.305682 -221.384818) (xy 113.269072 -221.348208) (xy 113.23864 -221.306321) (xy 113.215134 -221.260189)
			(xy 113.199135 -221.210949) (xy 113.191036 -221.159811) (xy 113.190528 -221.133924) (xy 113.191067 -221.106216)
			(xy 113.200256 -221.05157) (xy 113.208816 -221.025212) (xy 113.21669 -221.003114) (xy 113.011712 -220.648022)
			(xy 112.988852 -220.643704) (xy 112.964 -220.63857) (xy 112.916153 -220.621668) (xy 112.871462 -220.597632)
			(xy 112.830984 -220.567029) (xy 112.795674 -220.530584) (xy 112.766368 -220.489157) (xy 112.743757 -220.443728)
			(xy 112.728377 -220.39537) (xy 112.720591 -220.345226) (xy 112.72012 -220.319854) (xy 111.499904 -220.319854)
			(xy 111.499294 -220.347507) (xy 111.489971 -220.402025) (xy 111.481362 -220.428312) (xy 111.473742 -220.45041)
			(xy 111.678974 -220.805756) (xy 111.701834 -220.810074) (xy 111.726645 -220.815229) (xy 111.774384 -220.832223)
			(xy 111.818962 -220.856322) (xy 111.859327 -220.886957) (xy 111.89453 -220.923408) (xy 111.92374 -220.964816)
			(xy 111.946272 -221.010206) (xy 111.961592 -221.058509) (xy 111.969342 -221.108587) (xy 111.969804 -221.133924)
			(xy 111.969296 -221.159811) (xy 111.961197 -221.210949) (xy 111.945198 -221.260189) (xy 111.921692 -221.306321)
			(xy 111.89126 -221.348208) (xy 111.85465 -221.384818) (xy 111.812763 -221.41525) (xy 111.766631 -221.438756)
			(xy 111.717391 -221.454755) (xy 111.666253 -221.462854) (xy 111.614479 -221.462854) (xy 111.563341 -221.454755)
			(xy 111.514101 -221.438756) (xy 111.467969 -221.41525) (xy 111.426082 -221.384818) (xy 111.389472 -221.348208)
			(xy 111.35904 -221.306321) (xy 111.335534 -221.260189) (xy 111.319535 -221.210949) (xy 111.311436 -221.159811)
			(xy 111.310928 -221.133924) (xy 111.311467 -221.106216) (xy 111.320656 -221.05157) (xy 111.329216 -221.025212)
			(xy 111.33709 -221.003114) (xy 111.132112 -220.648022) (xy 111.109252 -220.643704) (xy 111.0844 -220.63857)
			(xy 111.036553 -220.621668) (xy 110.991862 -220.597632) (xy 110.951384 -220.567029) (xy 110.916074 -220.530584)
			(xy 110.886768 -220.489157) (xy 110.864157 -220.443728) (xy 110.848777 -220.39537) (xy 110.840991 -220.345226)
			(xy 110.84052 -220.319854) (xy 109.620304 -220.319854) (xy 109.619694 -220.347507) (xy 109.610371 -220.402025)
			(xy 109.601762 -220.428312) (xy 109.594142 -220.45041) (xy 109.799374 -220.805756) (xy 109.822234 -220.810074)
			(xy 109.847045 -220.815229) (xy 109.894784 -220.832223) (xy 109.939362 -220.856322) (xy 109.979727 -220.886957)
			(xy 110.01493 -220.923408) (xy 110.04414 -220.964816) (xy 110.066672 -221.010206) (xy 110.081992 -221.058509)
			(xy 110.089742 -221.108587) (xy 110.090204 -221.133924) (xy 110.089696 -221.159811) (xy 110.081597 -221.210949)
			(xy 110.065598 -221.260189) (xy 110.042092 -221.306321) (xy 110.01166 -221.348208) (xy 109.97505 -221.384818)
			(xy 109.933163 -221.41525) (xy 109.887031 -221.438756) (xy 109.837791 -221.454755) (xy 109.786653 -221.462854)
			(xy 109.734879 -221.462854) (xy 109.683741 -221.454755) (xy 109.634501 -221.438756) (xy 109.588369 -221.41525)
			(xy 109.546482 -221.384818) (xy 109.509872 -221.348208) (xy 109.47944 -221.306321) (xy 109.455934 -221.260189)
			(xy 109.439935 -221.210949) (xy 109.431836 -221.159811) (xy 109.431328 -221.133924) (xy 109.431867 -221.106216)
			(xy 109.441056 -221.05157) (xy 109.449616 -221.025212) (xy 109.45749 -221.003114) (xy 109.252512 -220.648022)
			(xy 109.229652 -220.643704) (xy 109.2048 -220.63857) (xy 109.156953 -220.621668) (xy 109.112262 -220.597632)
			(xy 109.071784 -220.567029) (xy 109.036474 -220.530584) (xy 109.007168 -220.489157) (xy 108.984557 -220.443728)
			(xy 108.969177 -220.39537) (xy 108.961391 -220.345226) (xy 108.96092 -220.319854) (xy 107.740704 -220.319854)
			(xy 107.740094 -220.347507) (xy 107.730771 -220.402025) (xy 107.722162 -220.428312) (xy 107.714542 -220.45041)
			(xy 107.919774 -220.805756) (xy 107.942634 -220.810074) (xy 107.967445 -220.815229) (xy 108.015184 -220.832223)
			(xy 108.059762 -220.856322) (xy 108.100127 -220.886957) (xy 108.13533 -220.923408) (xy 108.16454 -220.964816)
			(xy 108.187072 -221.010206) (xy 108.202392 -221.058509) (xy 108.210142 -221.108587) (xy 108.210604 -221.133924)
			(xy 108.210096 -221.159811) (xy 108.201997 -221.210949) (xy 108.185998 -221.260189) (xy 108.162492 -221.306321)
			(xy 108.13206 -221.348208) (xy 108.09545 -221.384818) (xy 108.053563 -221.41525) (xy 108.007431 -221.438756)
			(xy 107.958191 -221.454755) (xy 107.907053 -221.462854) (xy 107.855279 -221.462854) (xy 107.804141 -221.454755)
			(xy 107.754901 -221.438756) (xy 107.708769 -221.41525) (xy 107.666882 -221.384818) (xy 107.630272 -221.348208)
			(xy 107.59984 -221.306321) (xy 107.576334 -221.260189) (xy 107.560335 -221.210949) (xy 107.552236 -221.159811)
			(xy 107.551728 -221.133924) (xy 107.552267 -221.106216) (xy 107.561456 -221.05157) (xy 107.570016 -221.025212)
			(xy 107.57789 -221.003114) (xy 107.372912 -220.648022) (xy 107.350052 -220.643704) (xy 107.3252 -220.63857)
			(xy 107.277353 -220.621668) (xy 107.232662 -220.597632) (xy 107.192184 -220.567029) (xy 107.156874 -220.530584)
			(xy 107.127568 -220.489157) (xy 107.104957 -220.443728) (xy 107.089577 -220.39537) (xy 107.081791 -220.345226)
			(xy 107.08132 -220.319854) (xy 105.861104 -220.319854) (xy 105.860494 -220.347507) (xy 105.851171 -220.402025)
			(xy 105.842562 -220.428312) (xy 105.834942 -220.45041) (xy 106.040174 -220.805756) (xy 106.063034 -220.810074)
			(xy 106.087845 -220.815229) (xy 106.135584 -220.832223) (xy 106.180162 -220.856322) (xy 106.220527 -220.886957)
			(xy 106.25573 -220.923408) (xy 106.28494 -220.964816) (xy 106.307472 -221.010206) (xy 106.322792 -221.058509)
			(xy 106.330542 -221.108587) (xy 106.331004 -221.133924) (xy 106.330496 -221.159811) (xy 106.322397 -221.210949)
			(xy 106.306398 -221.260189) (xy 106.282892 -221.306321) (xy 106.25246 -221.348208) (xy 106.21585 -221.384818)
			(xy 106.173963 -221.41525) (xy 106.127831 -221.438756) (xy 106.078591 -221.454755) (xy 106.027453 -221.462854)
			(xy 105.975679 -221.462854) (xy 105.924541 -221.454755) (xy 105.875301 -221.438756) (xy 105.829169 -221.41525)
			(xy 105.787282 -221.384818) (xy 105.750672 -221.348208) (xy 105.72024 -221.306321) (xy 105.696734 -221.260189)
			(xy 105.680735 -221.210949) (xy 105.672636 -221.159811) (xy 105.672128 -221.133924) (xy 105.672667 -221.106216)
			(xy 105.681856 -221.05157) (xy 105.690416 -221.025212) (xy 105.69829 -221.003114) (xy 105.493312 -220.648022)
			(xy 105.470452 -220.643704) (xy 105.4456 -220.63857) (xy 105.397753 -220.621668) (xy 105.353062 -220.597632)
			(xy 105.312584 -220.567029) (xy 105.277274 -220.530584) (xy 105.247968 -220.489157) (xy 105.225357 -220.443728)
			(xy 105.209977 -220.39537) (xy 105.202191 -220.345226) (xy 105.20172 -220.319854) (xy 103.981504 -220.319854)
			(xy 103.981028 -220.345199) (xy 103.973249 -220.395289) (xy 103.957897 -220.443599) (xy 103.935334 -220.48899)
			(xy 103.906091 -220.530396) (xy 103.870857 -220.566839) (xy 103.830462 -220.597461) (xy 103.785857 -220.621543)
			(xy 103.738093 -220.638516) (xy 103.71328 -220.643704) (xy 103.69042 -220.648022) (xy 103.485442 -221.003114)
			(xy 103.493316 -221.024958) (xy 103.50191 -221.051373) (xy 103.511097 -221.106151) (xy 103.511604 -221.133924)
			(xy 103.511096 -221.159811) (xy 103.502997 -221.210949) (xy 103.486998 -221.260189) (xy 103.463492 -221.306321)
			(xy 103.43306 -221.348208) (xy 103.39645 -221.384818) (xy 103.354563 -221.41525) (xy 103.308431 -221.438756)
			(xy 103.259191 -221.454755) (xy 103.208053 -221.462854) (xy 103.156279 -221.462854) (xy 103.105141 -221.454755)
			(xy 103.055901 -221.438756) (xy 103.009769 -221.41525) (xy 102.967882 -221.384818) (xy 102.931272 -221.348208)
			(xy 102.90084 -221.306321) (xy 102.877334 -221.260189) (xy 102.861335 -221.210949) (xy 102.853236 -221.159811)
			(xy 102.852728 -221.133924) (xy 102.571804 -221.133924) (xy 102.57128 -221.161632) (xy 102.562081 -221.216279)
			(xy 102.553516 -221.242636) (xy 102.545642 -221.264734) (xy 102.75062 -221.619572) (xy 102.77348 -221.62389)
			(xy 102.798305 -221.629041) (xy 102.846083 -221.645999) (xy 102.890702 -221.670074) (xy 102.931107 -221.700696)
			(xy 102.966347 -221.737145) (xy 102.99559 -221.778561) (xy 103.018147 -221.823965) (xy 103.033485 -221.872289)
			(xy 103.041242 -221.92239) (xy 103.041704 -221.94774) (xy 104.26192 -221.94774) (xy 104.262371 -221.922394)
			(xy 104.270152 -221.872302) (xy 104.285506 -221.82399) (xy 104.308072 -221.778597) (xy 104.337318 -221.737192)
			(xy 104.372555 -221.700749) (xy 104.412954 -221.670127) (xy 104.457562 -221.646047) (xy 104.50533 -221.629076)
			(xy 104.530144 -221.62389) (xy 104.553004 -221.619572) (xy 104.758236 -221.264226) (xy 104.750362 -221.242128)
			(xy 104.741898 -221.215883) (xy 104.732825 -221.161495) (xy 104.732328 -221.133924) (xy 104.732836 -221.108037)
			(xy 104.740935 -221.056899) (xy 104.756934 -221.007659) (xy 104.78044 -220.961527) (xy 104.810872 -220.91964)
			(xy 104.847482 -220.88303) (xy 104.889369 -220.852598) (xy 104.935501 -220.829092) (xy 104.984741 -220.813093)
			(xy 105.035879 -220.804994) (xy 105.087653 -220.804994) (xy 105.138791 -220.813093) (xy 105.188031 -220.829092)
			(xy 105.234163 -220.852598) (xy 105.27605 -220.88303) (xy 105.31266 -220.91964) (xy 105.343092 -220.961527)
			(xy 105.366598 -221.007659) (xy 105.382597 -221.056899) (xy 105.390696 -221.108037) (xy 105.391204 -221.133924)
			(xy 105.390748 -221.159299) (xy 105.382976 -221.20945) (xy 105.367604 -221.257815) (xy 105.344997 -221.303251)
			(xy 105.315689 -221.344682) (xy 105.280373 -221.381128) (xy 105.239885 -221.411727) (xy 105.195184 -221.435754)
			(xy 105.147326 -221.452641) (xy 105.122472 -221.457774) (xy 105.099612 -221.462092) (xy 104.894888 -221.81693)
			(xy 104.902762 -221.838774) (xy 104.911419 -221.865179) (xy 104.920732 -221.919958) (xy 104.921304 -221.94774)
			(xy 106.14152 -221.94774) (xy 106.141971 -221.922394) (xy 106.149752 -221.872302) (xy 106.165106 -221.82399)
			(xy 106.187672 -221.778597) (xy 106.216918 -221.737192) (xy 106.252155 -221.700749) (xy 106.292554 -221.670127)
			(xy 106.337162 -221.646047) (xy 106.38493 -221.629076) (xy 106.409744 -221.62389) (xy 106.432604 -221.619572)
			(xy 106.637836 -221.264226) (xy 106.629962 -221.242128) (xy 106.621498 -221.215883) (xy 106.612425 -221.161495)
			(xy 106.611928 -221.133924) (xy 106.612436 -221.108037) (xy 106.620535 -221.056899) (xy 106.636534 -221.007659)
			(xy 106.66004 -220.961527) (xy 106.690472 -220.91964) (xy 106.727082 -220.88303) (xy 106.768969 -220.852598)
			(xy 106.815101 -220.829092) (xy 106.864341 -220.813093) (xy 106.915479 -220.804994) (xy 106.967253 -220.804994)
			(xy 107.018391 -220.813093) (xy 107.067631 -220.829092) (xy 107.113763 -220.852598) (xy 107.15565 -220.88303)
			(xy 107.19226 -220.91964) (xy 107.222692 -220.961527) (xy 107.246198 -221.007659) (xy 107.262197 -221.056899)
			(xy 107.270296 -221.108037) (xy 107.270804 -221.133924) (xy 107.270348 -221.159299) (xy 107.262576 -221.20945)
			(xy 107.247204 -221.257815) (xy 107.224597 -221.303251) (xy 107.195289 -221.344682) (xy 107.159973 -221.381128)
			(xy 107.119485 -221.411727) (xy 107.074784 -221.435754) (xy 107.026926 -221.452641) (xy 107.002072 -221.457774)
			(xy 106.979212 -221.462092) (xy 106.774488 -221.81693) (xy 106.782362 -221.838774) (xy 106.791019 -221.865179)
			(xy 106.800332 -221.919958) (xy 106.800904 -221.94774) (xy 108.02112 -221.94774) (xy 108.021571 -221.922394)
			(xy 108.029352 -221.872302) (xy 108.044706 -221.82399) (xy 108.067272 -221.778597) (xy 108.096518 -221.737192)
			(xy 108.131755 -221.700749) (xy 108.172154 -221.670127) (xy 108.216762 -221.646047) (xy 108.26453 -221.629076)
			(xy 108.289344 -221.62389) (xy 108.312204 -221.619572) (xy 108.517436 -221.264226) (xy 108.509562 -221.242128)
			(xy 108.501098 -221.215883) (xy 108.492025 -221.161495) (xy 108.491528 -221.133924) (xy 108.492036 -221.108037)
			(xy 108.500135 -221.056899) (xy 108.516134 -221.007659) (xy 108.53964 -220.961527) (xy 108.570072 -220.91964)
			(xy 108.606682 -220.88303) (xy 108.648569 -220.852598) (xy 108.694701 -220.829092) (xy 108.743941 -220.813093)
			(xy 108.795079 -220.804994) (xy 108.846853 -220.804994) (xy 108.897991 -220.813093) (xy 108.947231 -220.829092)
			(xy 108.993363 -220.852598) (xy 109.03525 -220.88303) (xy 109.07186 -220.91964) (xy 109.102292 -220.961527)
			(xy 109.125798 -221.007659) (xy 109.141797 -221.056899) (xy 109.149896 -221.108037) (xy 109.150404 -221.133924)
			(xy 109.149948 -221.159299) (xy 109.142176 -221.20945) (xy 109.126804 -221.257815) (xy 109.104197 -221.303251)
			(xy 109.074889 -221.344682) (xy 109.039573 -221.381128) (xy 108.999085 -221.411727) (xy 108.954384 -221.435754)
			(xy 108.906526 -221.452641) (xy 108.881672 -221.457774) (xy 108.858812 -221.462092) (xy 108.654088 -221.81693)
			(xy 108.661962 -221.838774) (xy 108.670619 -221.865179) (xy 108.679932 -221.919958) (xy 108.680504 -221.94774)
			(xy 109.901228 -221.94774) (xy 109.901634 -221.922403) (xy 109.909396 -221.872326) (xy 109.924728 -221.824026)
			(xy 109.947269 -221.77864) (xy 109.976489 -221.737238) (xy 110.011699 -221.700794) (xy 110.05207 -221.670165)
			(xy 110.096652 -221.646074) (xy 110.144395 -221.629087) (xy 110.169198 -221.62389) (xy 110.192058 -221.619572)
			(xy 110.397036 -221.26448) (xy 110.389416 -221.242382) (xy 110.380897 -221.216211) (xy 110.371703 -221.161949)
			(xy 110.371128 -221.134432) (xy 110.371128 -221.133924) (xy 110.371636 -221.108037) (xy 110.379735 -221.056899)
			(xy 110.395734 -221.007659) (xy 110.41924 -220.961527) (xy 110.449672 -220.91964) (xy 110.486282 -220.88303)
			(xy 110.528169 -220.852598) (xy 110.574301 -220.829092) (xy 110.623541 -220.813093) (xy 110.674679 -220.804994)
			(xy 110.726453 -220.804994) (xy 110.777591 -220.813093) (xy 110.826831 -220.829092) (xy 110.872963 -220.852598)
			(xy 110.91485 -220.88303) (xy 110.95146 -220.91964) (xy 110.981892 -220.961527) (xy 111.005398 -221.007659)
			(xy 111.021397 -221.056899) (xy 111.029496 -221.108037) (xy 111.030004 -221.133924) (xy 111.029585 -221.15929)
			(xy 111.021833 -221.209425) (xy 111.006484 -221.257778) (xy 110.983902 -221.303206) (xy 110.954621 -221.344633)
			(xy 110.919333 -221.381081) (xy 110.878874 -221.411686) (xy 110.8342 -221.435725) (xy 110.786369 -221.45263)
			(xy 110.761526 -221.457774) (xy 110.738666 -221.462092) (xy 110.533942 -221.81693) (xy 110.541816 -221.838774)
			(xy 110.550414 -221.865187) (xy 110.559598 -221.919967) (xy 110.560104 -221.94774) (xy 111.78032 -221.94774)
			(xy 111.780771 -221.922394) (xy 111.788552 -221.872302) (xy 111.803906 -221.82399) (xy 111.826472 -221.778597)
			(xy 111.855718 -221.737192) (xy 111.890955 -221.700749) (xy 111.931354 -221.670127) (xy 111.975962 -221.646047)
			(xy 112.02373 -221.629076) (xy 112.048544 -221.62389) (xy 112.071404 -221.619572) (xy 112.276636 -221.264226)
			(xy 112.268762 -221.242128) (xy 112.260298 -221.215883) (xy 112.251225 -221.161495) (xy 112.250728 -221.133924)
			(xy 112.251236 -221.108037) (xy 112.259335 -221.056899) (xy 112.275334 -221.007659) (xy 112.29884 -220.961527)
			(xy 112.329272 -220.91964) (xy 112.365882 -220.88303) (xy 112.407769 -220.852598) (xy 112.453901 -220.829092)
			(xy 112.503141 -220.813093) (xy 112.554279 -220.804994) (xy 112.606053 -220.804994) (xy 112.657191 -220.813093)
			(xy 112.706431 -220.829092) (xy 112.752563 -220.852598) (xy 112.79445 -220.88303) (xy 112.83106 -220.91964)
			(xy 112.861492 -220.961527) (xy 112.884998 -221.007659) (xy 112.900997 -221.056899) (xy 112.909096 -221.108037)
			(xy 112.909604 -221.133924) (xy 112.909148 -221.159299) (xy 112.901376 -221.20945) (xy 112.886004 -221.257815)
			(xy 112.863397 -221.303251) (xy 112.834089 -221.344682) (xy 112.798773 -221.381128) (xy 112.758285 -221.411727)
			(xy 112.713584 -221.435754) (xy 112.665726 -221.452641) (xy 112.640872 -221.457774) (xy 112.618012 -221.462092)
			(xy 112.413288 -221.81693) (xy 112.421162 -221.838774) (xy 112.429819 -221.865179) (xy 112.439132 -221.919958)
			(xy 112.439704 -221.94774) (xy 113.660428 -221.94774) (xy 113.660834 -221.922403) (xy 113.668596 -221.872326)
			(xy 113.683928 -221.824026) (xy 113.706469 -221.77864) (xy 113.735689 -221.737238) (xy 113.770899 -221.700794)
			(xy 113.81127 -221.670165) (xy 113.855852 -221.646074) (xy 113.903595 -221.629087) (xy 113.928398 -221.62389)
			(xy 113.951258 -221.619572) (xy 114.156236 -221.26448) (xy 114.148616 -221.242382) (xy 114.140097 -221.216211)
			(xy 114.130903 -221.161949) (xy 114.130328 -221.134432) (xy 114.130328 -221.133924) (xy 114.130836 -221.108037)
			(xy 114.138935 -221.056899) (xy 114.154934 -221.007659) (xy 114.17844 -220.961527) (xy 114.208872 -220.91964)
			(xy 114.245482 -220.88303) (xy 114.287369 -220.852598) (xy 114.333501 -220.829092) (xy 114.382741 -220.813093)
			(xy 114.433879 -220.804994) (xy 114.485653 -220.804994) (xy 114.536791 -220.813093) (xy 114.586031 -220.829092)
			(xy 114.632163 -220.852598) (xy 114.67405 -220.88303) (xy 114.71066 -220.91964) (xy 114.741092 -220.961527)
			(xy 114.764598 -221.007659) (xy 114.780597 -221.056899) (xy 114.788696 -221.108037) (xy 114.789204 -221.133924)
			(xy 114.788785 -221.15929) (xy 114.781033 -221.209425) (xy 114.765684 -221.257778) (xy 114.743102 -221.303206)
			(xy 114.713821 -221.344633) (xy 114.678533 -221.381081) (xy 114.638074 -221.411686) (xy 114.5934 -221.435725)
			(xy 114.545569 -221.45263) (xy 114.520726 -221.457774) (xy 114.497866 -221.462092) (xy 114.293142 -221.81693)
			(xy 114.301016 -221.838774) (xy 114.309614 -221.865187) (xy 114.318798 -221.919967) (xy 114.319304 -221.94774)
			(xy 115.53952 -221.94774) (xy 115.539971 -221.922394) (xy 115.547752 -221.872302) (xy 115.563106 -221.82399)
			(xy 115.585672 -221.778597) (xy 115.614918 -221.737192) (xy 115.650155 -221.700749) (xy 115.690554 -221.670127)
			(xy 115.735162 -221.646047) (xy 115.78293 -221.629076) (xy 115.807744 -221.62389) (xy 115.830604 -221.619572)
			(xy 116.035836 -221.264226) (xy 116.027962 -221.242128) (xy 116.019498 -221.215883) (xy 116.010425 -221.161495)
			(xy 116.009928 -221.133924) (xy 116.010436 -221.108037) (xy 116.018535 -221.056899) (xy 116.034534 -221.007659)
			(xy 116.05804 -220.961527) (xy 116.088472 -220.91964) (xy 116.125082 -220.88303) (xy 116.166969 -220.852598)
			(xy 116.213101 -220.829092) (xy 116.262341 -220.813093) (xy 116.313479 -220.804994) (xy 116.365253 -220.804994)
			(xy 116.416391 -220.813093) (xy 116.465631 -220.829092) (xy 116.511763 -220.852598) (xy 116.55365 -220.88303)
			(xy 116.59026 -220.91964) (xy 116.620692 -220.961527) (xy 116.644198 -221.007659) (xy 116.660197 -221.056899)
			(xy 116.668296 -221.108037) (xy 116.668804 -221.133924) (xy 116.668348 -221.159299) (xy 116.660576 -221.20945)
			(xy 116.645204 -221.257815) (xy 116.622597 -221.303251) (xy 116.593289 -221.344682) (xy 116.557973 -221.381128)
			(xy 116.517485 -221.411727) (xy 116.472784 -221.435754) (xy 116.424926 -221.452641) (xy 116.400072 -221.457774)
			(xy 116.377212 -221.462092) (xy 116.172488 -221.81693) (xy 116.180362 -221.838774) (xy 116.189019 -221.865179)
			(xy 116.198332 -221.919958) (xy 116.198904 -221.94774) (xy 117.41912 -221.94774) (xy 117.419571 -221.922394)
			(xy 117.427352 -221.872302) (xy 117.442706 -221.82399) (xy 117.465272 -221.778597) (xy 117.494518 -221.737192)
			(xy 117.529755 -221.700749) (xy 117.570154 -221.670127) (xy 117.614762 -221.646047) (xy 117.66253 -221.629076)
			(xy 117.687344 -221.62389) (xy 117.710204 -221.619572) (xy 117.915436 -221.264226) (xy 117.907562 -221.242128)
			(xy 117.899098 -221.215883) (xy 117.890025 -221.161495) (xy 117.889528 -221.133924) (xy 117.890036 -221.108037)
			(xy 117.898135 -221.056899) (xy 117.914134 -221.007659) (xy 117.93764 -220.961527) (xy 117.968072 -220.91964)
			(xy 118.004682 -220.88303) (xy 118.046569 -220.852598) (xy 118.092701 -220.829092) (xy 118.141941 -220.813093)
			(xy 118.193079 -220.804994) (xy 118.244853 -220.804994) (xy 118.295991 -220.813093) (xy 118.345231 -220.829092)
			(xy 118.391363 -220.852598) (xy 118.43325 -220.88303) (xy 118.46986 -220.91964) (xy 118.500292 -220.961527)
			(xy 118.523798 -221.007659) (xy 118.539797 -221.056899) (xy 118.547896 -221.108037) (xy 118.548404 -221.133924)
			(xy 118.547948 -221.159299) (xy 118.540176 -221.20945) (xy 118.524804 -221.257815) (xy 118.502197 -221.303251)
			(xy 118.472889 -221.344682) (xy 118.437573 -221.381128) (xy 118.397085 -221.411727) (xy 118.352384 -221.435754)
			(xy 118.304526 -221.452641) (xy 118.279672 -221.457774) (xy 118.256812 -221.462092) (xy 118.052088 -221.81693)
			(xy 118.059962 -221.838774) (xy 118.068619 -221.865179) (xy 118.077932 -221.919958) (xy 118.078504 -221.94774)
			(xy 121.17832 -221.94774) (xy 121.178771 -221.922394) (xy 121.186552 -221.872302) (xy 121.201906 -221.82399)
			(xy 121.224472 -221.778597) (xy 121.253718 -221.737192) (xy 121.288955 -221.700749) (xy 121.329354 -221.670127)
			(xy 121.373962 -221.646047) (xy 121.42173 -221.629076) (xy 121.446544 -221.62389) (xy 121.469404 -221.619572)
			(xy 121.674636 -221.264226) (xy 121.666762 -221.242128) (xy 121.658298 -221.215883) (xy 121.649225 -221.161495)
			(xy 121.648728 -221.133924) (xy 121.649236 -221.108037) (xy 121.657335 -221.056899) (xy 121.673334 -221.007659)
			(xy 121.69684 -220.961527) (xy 121.727272 -220.91964) (xy 121.763882 -220.88303) (xy 121.805769 -220.852598)
			(xy 121.851901 -220.829092) (xy 121.901141 -220.813093) (xy 121.952279 -220.804994) (xy 122.004053 -220.804994)
			(xy 122.055191 -220.813093) (xy 122.104431 -220.829092) (xy 122.150563 -220.852598) (xy 122.19245 -220.88303)
			(xy 122.22906 -220.91964) (xy 122.259492 -220.961527) (xy 122.282998 -221.007659) (xy 122.298997 -221.056899)
			(xy 122.307096 -221.108037) (xy 122.307604 -221.133924) (xy 122.307148 -221.159299) (xy 122.299376 -221.20945)
			(xy 122.284004 -221.257815) (xy 122.261397 -221.303251) (xy 122.232089 -221.344682) (xy 122.196773 -221.381128)
			(xy 122.156285 -221.411727) (xy 122.111584 -221.435754) (xy 122.063726 -221.452641) (xy 122.038872 -221.457774)
			(xy 122.016012 -221.462092) (xy 121.811288 -221.81693) (xy 121.819162 -221.838774) (xy 121.827819 -221.865179)
			(xy 121.837132 -221.919958) (xy 121.837704 -221.94774) (xy 123.05792 -221.94774) (xy 123.058371 -221.922394)
			(xy 123.066152 -221.872302) (xy 123.081506 -221.82399) (xy 123.104072 -221.778597) (xy 123.133318 -221.737192)
			(xy 123.168555 -221.700749) (xy 123.208954 -221.670127) (xy 123.253562 -221.646047) (xy 123.30133 -221.629076)
			(xy 123.326144 -221.62389) (xy 123.349004 -221.619572) (xy 123.554236 -221.264226) (xy 123.546362 -221.242128)
			(xy 123.537898 -221.215883) (xy 123.528825 -221.161495) (xy 123.528328 -221.133924) (xy 123.528836 -221.108037)
			(xy 123.536935 -221.056899) (xy 123.552934 -221.007659) (xy 123.57644 -220.961527) (xy 123.606872 -220.91964)
			(xy 123.643482 -220.88303) (xy 123.685369 -220.852598) (xy 123.731501 -220.829092) (xy 123.780741 -220.813093)
			(xy 123.831879 -220.804994) (xy 123.883653 -220.804994) (xy 123.934791 -220.813093) (xy 123.984031 -220.829092)
			(xy 124.030163 -220.852598) (xy 124.07205 -220.88303) (xy 124.10866 -220.91964) (xy 124.139092 -220.961527)
			(xy 124.162598 -221.007659) (xy 124.178597 -221.056899) (xy 124.186696 -221.108037) (xy 124.187204 -221.133924)
			(xy 124.186748 -221.159299) (xy 124.178976 -221.20945) (xy 124.163604 -221.257815) (xy 124.140997 -221.303251)
			(xy 124.111689 -221.344682) (xy 124.076373 -221.381128) (xy 124.035885 -221.411727) (xy 123.991184 -221.435754)
			(xy 123.943326 -221.452641) (xy 123.918472 -221.457774) (xy 123.895612 -221.462092) (xy 123.690888 -221.81693)
			(xy 123.698762 -221.838774) (xy 123.707419 -221.865179) (xy 123.716732 -221.919958) (xy 123.717304 -221.94774)
			(xy 124.93752 -221.94774) (xy 124.937971 -221.922394) (xy 124.945752 -221.872302) (xy 124.961106 -221.82399)
			(xy 124.983672 -221.778597) (xy 125.012918 -221.737192) (xy 125.048155 -221.700749) (xy 125.088554 -221.670127)
			(xy 125.133162 -221.646047) (xy 125.18093 -221.629076) (xy 125.205744 -221.62389) (xy 125.228604 -221.619572)
			(xy 125.433836 -221.264226) (xy 125.425962 -221.242128) (xy 125.417498 -221.215883) (xy 125.408425 -221.161495)
			(xy 125.407928 -221.133924) (xy 125.408436 -221.108037) (xy 125.416535 -221.056899) (xy 125.432534 -221.007659)
			(xy 125.45604 -220.961527) (xy 125.486472 -220.91964) (xy 125.523082 -220.88303) (xy 125.564969 -220.852598)
			(xy 125.611101 -220.829092) (xy 125.660341 -220.813093) (xy 125.711479 -220.804994) (xy 125.763253 -220.804994)
			(xy 125.814391 -220.813093) (xy 125.863631 -220.829092) (xy 125.909763 -220.852598) (xy 125.95165 -220.88303)
			(xy 125.98826 -220.91964) (xy 126.018692 -220.961527) (xy 126.042198 -221.007659) (xy 126.058197 -221.056899)
			(xy 126.066296 -221.108037) (xy 126.066804 -221.133924) (xy 126.066348 -221.159299) (xy 126.058576 -221.20945)
			(xy 126.043204 -221.257815) (xy 126.020597 -221.303251) (xy 125.991289 -221.344682) (xy 125.955973 -221.381128)
			(xy 125.915485 -221.411727) (xy 125.870784 -221.435754) (xy 125.822926 -221.452641) (xy 125.798072 -221.457774)
			(xy 125.775212 -221.462092) (xy 125.570488 -221.81693) (xy 125.578362 -221.838774) (xy 125.587019 -221.865179)
			(xy 125.596332 -221.919958) (xy 125.596904 -221.94774) (xy 126.81712 -221.94774) (xy 126.817571 -221.922394)
			(xy 126.825352 -221.872302) (xy 126.840706 -221.82399) (xy 126.863272 -221.778597) (xy 126.892518 -221.737192)
			(xy 126.927755 -221.700749) (xy 126.968154 -221.670127) (xy 127.012762 -221.646047) (xy 127.06053 -221.629076)
			(xy 127.085344 -221.62389) (xy 127.108204 -221.619572) (xy 127.313436 -221.264226) (xy 127.305562 -221.242128)
			(xy 127.297098 -221.215883) (xy 127.288025 -221.161495) (xy 127.287528 -221.133924) (xy 127.288036 -221.108037)
			(xy 127.296135 -221.056899) (xy 127.312134 -221.007659) (xy 127.33564 -220.961527) (xy 127.366072 -220.91964)
			(xy 127.402682 -220.88303) (xy 127.444569 -220.852598) (xy 127.490701 -220.829092) (xy 127.539941 -220.813093)
			(xy 127.591079 -220.804994) (xy 127.642853 -220.804994) (xy 127.693991 -220.813093) (xy 127.743231 -220.829092)
			(xy 127.789363 -220.852598) (xy 127.83125 -220.88303) (xy 127.86786 -220.91964) (xy 127.898292 -220.961527)
			(xy 127.921798 -221.007659) (xy 127.937797 -221.056899) (xy 127.945896 -221.108037) (xy 127.946404 -221.133924)
			(xy 127.945948 -221.159299) (xy 127.938176 -221.20945) (xy 127.922804 -221.257815) (xy 127.900197 -221.303251)
			(xy 127.870889 -221.344682) (xy 127.835573 -221.381128) (xy 127.795085 -221.411727) (xy 127.750384 -221.435754)
			(xy 127.702526 -221.452641) (xy 127.677672 -221.457774) (xy 127.654812 -221.462092) (xy 127.450088 -221.81693)
			(xy 127.457962 -221.838774) (xy 127.466619 -221.865179) (xy 127.475932 -221.919958) (xy 127.476504 -221.94774)
			(xy 128.69672 -221.94774) (xy 128.697171 -221.922394) (xy 128.704952 -221.872302) (xy 128.720306 -221.82399)
			(xy 128.742872 -221.778597) (xy 128.772118 -221.737192) (xy 128.807355 -221.700749) (xy 128.847754 -221.670127)
			(xy 128.892362 -221.646047) (xy 128.94013 -221.629076) (xy 128.964944 -221.62389) (xy 128.987804 -221.619572)
			(xy 129.193036 -221.264226) (xy 129.185162 -221.242128) (xy 129.176698 -221.215883) (xy 129.167625 -221.161495)
			(xy 129.167128 -221.133924) (xy 129.167636 -221.108037) (xy 129.175735 -221.056899) (xy 129.191734 -221.007659)
			(xy 129.21524 -220.961527) (xy 129.245672 -220.91964) (xy 129.282282 -220.88303) (xy 129.324169 -220.852598)
			(xy 129.370301 -220.829092) (xy 129.419541 -220.813093) (xy 129.470679 -220.804994) (xy 129.522453 -220.804994)
			(xy 129.573591 -220.813093) (xy 129.622831 -220.829092) (xy 129.668963 -220.852598) (xy 129.71085 -220.88303)
			(xy 129.74746 -220.91964) (xy 129.777892 -220.961527) (xy 129.801398 -221.007659) (xy 129.817397 -221.056899)
			(xy 129.825496 -221.108037) (xy 129.826004 -221.133924) (xy 129.825548 -221.159299) (xy 129.817776 -221.20945)
			(xy 129.802404 -221.257815) (xy 129.779797 -221.303251) (xy 129.750489 -221.344682) (xy 129.715173 -221.381128)
			(xy 129.674685 -221.411727) (xy 129.629984 -221.435754) (xy 129.582126 -221.452641) (xy 129.557272 -221.457774)
			(xy 129.534412 -221.462092) (xy 129.329688 -221.81693) (xy 129.337562 -221.838774) (xy 129.346219 -221.865179)
			(xy 129.355532 -221.919958) (xy 129.356104 -221.94774) (xy 130.57632 -221.94774) (xy 130.576771 -221.922394)
			(xy 130.584552 -221.872302) (xy 130.599906 -221.82399) (xy 130.622472 -221.778597) (xy 130.651718 -221.737192)
			(xy 130.686955 -221.700749) (xy 130.727354 -221.670127) (xy 130.771962 -221.646047) (xy 130.81973 -221.629076)
			(xy 130.844544 -221.62389) (xy 130.867404 -221.619572) (xy 131.072636 -221.264226) (xy 131.064762 -221.242128)
			(xy 131.056298 -221.215883) (xy 131.047225 -221.161495) (xy 131.046728 -221.133924) (xy 131.047236 -221.108037)
			(xy 131.055335 -221.056899) (xy 131.071334 -221.007659) (xy 131.09484 -220.961527) (xy 131.125272 -220.91964)
			(xy 131.161882 -220.88303) (xy 131.203769 -220.852598) (xy 131.249901 -220.829092) (xy 131.299141 -220.813093)
			(xy 131.350279 -220.804994) (xy 131.402053 -220.804994) (xy 131.453191 -220.813093) (xy 131.502431 -220.829092)
			(xy 131.548563 -220.852598) (xy 131.59045 -220.88303) (xy 131.62706 -220.91964) (xy 131.657492 -220.961527)
			(xy 131.680998 -221.007659) (xy 131.696997 -221.056899) (xy 131.705096 -221.108037) (xy 131.705604 -221.133924)
			(xy 131.705148 -221.159299) (xy 131.697376 -221.20945) (xy 131.682004 -221.257815) (xy 131.659397 -221.303251)
			(xy 131.630089 -221.344682) (xy 131.594773 -221.381128) (xy 131.554285 -221.411727) (xy 131.509584 -221.435754)
			(xy 131.461726 -221.452641) (xy 131.436872 -221.457774) (xy 131.414012 -221.462092) (xy 131.209288 -221.81693)
			(xy 131.217162 -221.838774) (xy 131.225819 -221.865179) (xy 131.235132 -221.919958) (xy 131.235704 -221.94774)
			(xy 132.45592 -221.94774) (xy 132.456371 -221.922394) (xy 132.464152 -221.872302) (xy 132.479506 -221.82399)
			(xy 132.502072 -221.778597) (xy 132.531318 -221.737192) (xy 132.566555 -221.700749) (xy 132.606954 -221.670127)
			(xy 132.651562 -221.646047) (xy 132.69933 -221.629076) (xy 132.724144 -221.62389) (xy 132.747004 -221.619572)
			(xy 132.951982 -221.263972) (xy 132.944362 -221.242128) (xy 132.935911 -221.215946) (xy 132.92684 -221.161685)
			(xy 132.926328 -221.134178) (xy 132.926328 -221.133924) (xy 132.926836 -221.108037) (xy 132.934935 -221.056899)
			(xy 132.950934 -221.007659) (xy 132.97444 -220.961527) (xy 133.004872 -220.91964) (xy 133.041482 -220.88303)
			(xy 133.083369 -220.852598) (xy 133.129501 -220.829092) (xy 133.178741 -220.813093) (xy 133.229879 -220.804994)
			(xy 133.281653 -220.804994) (xy 133.332791 -220.813093) (xy 133.382031 -220.829092) (xy 133.428163 -220.852598)
			(xy 133.47005 -220.88303) (xy 133.50666 -220.91964) (xy 133.537092 -220.961527) (xy 133.560598 -221.007659)
			(xy 133.576597 -221.056899) (xy 133.584696 -221.108037) (xy 133.585204 -221.133924) (xy 133.584785 -221.15929)
			(xy 133.577033 -221.209425) (xy 133.561684 -221.257778) (xy 133.539102 -221.303206) (xy 133.509821 -221.344633)
			(xy 133.474533 -221.381081) (xy 133.434074 -221.411686) (xy 133.3894 -221.435725) (xy 133.341569 -221.45263)
			(xy 133.316726 -221.457774) (xy 133.293866 -221.462092) (xy 133.089142 -221.81693) (xy 133.096762 -221.838774)
			(xy 133.105377 -221.865059) (xy 133.114698 -221.919578) (xy 133.115304 -221.947232) (xy 133.115304 -221.94774)
			(xy 134.33552 -221.94774) (xy 134.335971 -221.922394) (xy 134.343752 -221.872302) (xy 134.359106 -221.82399)
			(xy 134.381672 -221.778597) (xy 134.410918 -221.737192) (xy 134.446155 -221.700749) (xy 134.486554 -221.670127)
			(xy 134.531162 -221.646047) (xy 134.57893 -221.629076) (xy 134.603744 -221.62389) (xy 134.626604 -221.619572)
			(xy 134.831582 -221.263972) (xy 134.823962 -221.242128) (xy 134.815511 -221.215946) (xy 134.80644 -221.161685)
			(xy 134.805928 -221.134178) (xy 134.805928 -221.133924) (xy 134.806436 -221.108037) (xy 134.814535 -221.056899)
			(xy 134.830534 -221.007659) (xy 134.85404 -220.961527) (xy 134.884472 -220.91964) (xy 134.921082 -220.88303)
			(xy 134.962969 -220.852598) (xy 135.009101 -220.829092) (xy 135.058341 -220.813093) (xy 135.109479 -220.804994)
			(xy 135.161253 -220.804994) (xy 135.212391 -220.813093) (xy 135.261631 -220.829092) (xy 135.307763 -220.852598)
			(xy 135.34965 -220.88303) (xy 135.38626 -220.91964) (xy 135.416692 -220.961527) (xy 135.440198 -221.007659)
			(xy 135.456197 -221.056899) (xy 135.464296 -221.108037) (xy 135.464804 -221.133924) (xy 336.695796 -221.133924)
			(xy 336.696304 -221.108037) (xy 336.704403 -221.056899) (xy 336.720402 -221.007659) (xy 336.743908 -220.961527)
			(xy 336.77434 -220.91964) (xy 336.81095 -220.88303) (xy 336.852837 -220.852598) (xy 336.898969 -220.829092)
			(xy 336.948209 -220.813093) (xy 336.999347 -220.804994) (xy 337.051121 -220.804994) (xy 337.102259 -220.813093)
			(xy 337.151499 -220.829092) (xy 337.197631 -220.852598) (xy 337.239518 -220.88303) (xy 337.276128 -220.91964)
			(xy 337.30656 -220.961527) (xy 337.330066 -221.007659) (xy 337.346065 -221.056899) (xy 337.354164 -221.108037)
			(xy 337.354672 -221.133924) (xy 337.635596 -221.133924) (xy 337.636104 -221.10859) (xy 337.643853 -221.058519)
			(xy 337.659172 -221.010223) (xy 337.6817 -220.96484) (xy 337.710906 -220.923438) (xy 337.746104 -220.886992)
			(xy 337.786463 -220.856361) (xy 337.831034 -220.832266) (xy 337.878767 -220.815274) (xy 337.903566 -220.810074)
			(xy 337.926426 -220.805756) (xy 338.131404 -220.450664) (xy 338.12353 -220.42882) (xy 338.114896 -220.402408)
			(xy 338.105568 -220.347635) (xy 338.104988 -220.319854) (xy 338.105496 -220.293947) (xy 338.113602 -220.24277)
			(xy 338.129614 -220.193491) (xy 338.153137 -220.147324) (xy 338.183593 -220.105405) (xy 338.220231 -220.068767)
			(xy 338.26215 -220.038311) (xy 338.308317 -220.014788) (xy 338.357596 -219.998776) (xy 338.408773 -219.99067)
			(xy 338.460587 -219.99067) (xy 338.511764 -219.998776) (xy 338.561043 -220.014788) (xy 338.60721 -220.038311)
			(xy 338.649129 -220.068767) (xy 338.685767 -220.105405) (xy 338.716223 -220.147324) (xy 338.739746 -220.193491)
			(xy 338.755758 -220.24277) (xy 338.763864 -220.293947) (xy 338.764372 -220.319854) (xy 338.763922 -220.3452)
			(xy 338.756142 -220.395293) (xy 338.740788 -220.443604) (xy 338.718222 -220.488998) (xy 338.688976 -220.530404)
			(xy 338.653739 -220.566847) (xy 338.61334 -220.597469) (xy 338.568731 -220.621548) (xy 338.520963 -220.638518)
			(xy 338.496148 -220.643704) (xy 338.473288 -220.648022) (xy 338.26831 -221.003114) (xy 338.276184 -221.024958)
			(xy 338.284777 -221.051373) (xy 338.293965 -221.106151) (xy 338.294472 -221.133924) (xy 338.575396 -221.133924)
			(xy 338.575904 -221.108037) (xy 338.584003 -221.056899) (xy 338.600002 -221.007659) (xy 338.623508 -220.961527)
			(xy 338.65394 -220.91964) (xy 338.69055 -220.88303) (xy 338.732437 -220.852598) (xy 338.778569 -220.829092)
			(xy 338.827809 -220.813093) (xy 338.878947 -220.804994) (xy 338.930721 -220.804994) (xy 338.981859 -220.813093)
			(xy 339.031099 -220.829092) (xy 339.077231 -220.852598) (xy 339.119118 -220.88303) (xy 339.155728 -220.91964)
			(xy 339.18616 -220.961527) (xy 339.209666 -221.007659) (xy 339.225665 -221.056899) (xy 339.233764 -221.108037)
			(xy 339.234272 -221.133924) (xy 339.515196 -221.133924) (xy 339.515704 -221.10859) (xy 339.523453 -221.058519)
			(xy 339.538772 -221.010223) (xy 339.5613 -220.96484) (xy 339.590506 -220.923438) (xy 339.625704 -220.886992)
			(xy 339.666063 -220.856361) (xy 339.710634 -220.832266) (xy 339.758367 -220.815274) (xy 339.783166 -220.810074)
			(xy 339.806026 -220.805756) (xy 340.011004 -220.450664) (xy 340.00313 -220.42882) (xy 339.994496 -220.402408)
			(xy 339.985168 -220.347635) (xy 339.984588 -220.319854) (xy 339.985096 -220.293947) (xy 339.993202 -220.24277)
			(xy 340.009214 -220.193491) (xy 340.032737 -220.147324) (xy 340.063193 -220.105405) (xy 340.099831 -220.068767)
			(xy 340.14175 -220.038311) (xy 340.187917 -220.014788) (xy 340.237196 -219.998776) (xy 340.288373 -219.99067)
			(xy 340.340187 -219.99067) (xy 340.391364 -219.998776) (xy 340.440643 -220.014788) (xy 340.48681 -220.038311)
			(xy 340.528729 -220.068767) (xy 340.565367 -220.105405) (xy 340.595823 -220.147324) (xy 340.619346 -220.193491)
			(xy 340.635358 -220.24277) (xy 340.643464 -220.293947) (xy 340.643972 -220.319854) (xy 340.643522 -220.3452)
			(xy 340.635742 -220.395293) (xy 340.620388 -220.443604) (xy 340.597822 -220.488998) (xy 340.568576 -220.530404)
			(xy 340.533339 -220.566847) (xy 340.49294 -220.597469) (xy 340.448331 -220.621548) (xy 340.400563 -220.638518)
			(xy 340.375748 -220.643704) (xy 340.352888 -220.648022) (xy 340.14791 -221.003114) (xy 340.155784 -221.024958)
			(xy 340.164377 -221.051373) (xy 340.173565 -221.106151) (xy 340.174072 -221.133924) (xy 340.454996 -221.133924)
			(xy 340.455504 -221.108037) (xy 340.463603 -221.056899) (xy 340.479602 -221.007659) (xy 340.503108 -220.961527)
			(xy 340.53354 -220.91964) (xy 340.57015 -220.88303) (xy 340.612037 -220.852598) (xy 340.658169 -220.829092)
			(xy 340.707409 -220.813093) (xy 340.758547 -220.804994) (xy 340.810321 -220.804994) (xy 340.861459 -220.813093)
			(xy 340.910699 -220.829092) (xy 340.956831 -220.852598) (xy 340.998718 -220.88303) (xy 341.035328 -220.91964)
			(xy 341.06576 -220.961527) (xy 341.089266 -221.007659) (xy 341.105265 -221.056899) (xy 341.113364 -221.108037)
			(xy 341.113872 -221.133924) (xy 341.394796 -221.133924) (xy 341.395304 -221.10859) (xy 341.403053 -221.058519)
			(xy 341.418372 -221.010223) (xy 341.4409 -220.96484) (xy 341.470106 -220.923438) (xy 341.505304 -220.886992)
			(xy 341.545663 -220.856361) (xy 341.590234 -220.832266) (xy 341.637967 -220.815274) (xy 341.662766 -220.810074)
			(xy 341.685626 -220.805756) (xy 341.890604 -220.450664) (xy 341.88273 -220.42882) (xy 341.874096 -220.402408)
			(xy 341.864768 -220.347635) (xy 341.864188 -220.319854) (xy 341.864696 -220.293947) (xy 341.872802 -220.24277)
			(xy 341.888814 -220.193491) (xy 341.912337 -220.147324) (xy 341.942793 -220.105405) (xy 341.979431 -220.068767)
			(xy 342.02135 -220.038311) (xy 342.067517 -220.014788) (xy 342.116796 -219.998776) (xy 342.167973 -219.99067)
			(xy 342.219787 -219.99067) (xy 342.270964 -219.998776) (xy 342.320243 -220.014788) (xy 342.36641 -220.038311)
			(xy 342.408329 -220.068767) (xy 342.444967 -220.105405) (xy 342.475423 -220.147324) (xy 342.498946 -220.193491)
			(xy 342.514958 -220.24277) (xy 342.523064 -220.293947) (xy 342.523572 -220.319854) (xy 342.523122 -220.3452)
			(xy 342.515342 -220.395293) (xy 342.499988 -220.443604) (xy 342.477422 -220.488998) (xy 342.448176 -220.530404)
			(xy 342.412939 -220.566847) (xy 342.37254 -220.597469) (xy 342.327931 -220.621548) (xy 342.280163 -220.638518)
			(xy 342.255348 -220.643704) (xy 342.232488 -220.648022) (xy 342.02751 -221.003114) (xy 342.035384 -221.024958)
			(xy 342.043977 -221.051373) (xy 342.053165 -221.106151) (xy 342.053672 -221.133924) (xy 342.334596 -221.133924)
			(xy 342.335104 -221.108037) (xy 342.343203 -221.056899) (xy 342.359202 -221.007659) (xy 342.382708 -220.961527)
			(xy 342.41314 -220.91964) (xy 342.44975 -220.88303) (xy 342.491637 -220.852598) (xy 342.537769 -220.829092)
			(xy 342.587009 -220.813093) (xy 342.638147 -220.804994) (xy 342.689921 -220.804994) (xy 342.741059 -220.813093)
			(xy 342.790299 -220.829092) (xy 342.836431 -220.852598) (xy 342.878318 -220.88303) (xy 342.914928 -220.91964)
			(xy 342.94536 -220.961527) (xy 342.968866 -221.007659) (xy 342.984865 -221.056899) (xy 342.992964 -221.108037)
			(xy 342.993472 -221.133924) (xy 343.274396 -221.133924) (xy 343.274904 -221.10859) (xy 343.282653 -221.058519)
			(xy 343.297972 -221.010223) (xy 343.3205 -220.96484) (xy 343.349706 -220.923438) (xy 343.384904 -220.886992)
			(xy 343.425263 -220.856361) (xy 343.469834 -220.832266) (xy 343.517567 -220.815274) (xy 343.542366 -220.810074)
			(xy 343.565226 -220.805756) (xy 343.770204 -220.450664) (xy 343.76233 -220.42882) (xy 343.753696 -220.402408)
			(xy 343.744368 -220.347635) (xy 343.743788 -220.319854) (xy 343.744296 -220.293947) (xy 343.752402 -220.24277)
			(xy 343.768414 -220.193491) (xy 343.791937 -220.147324) (xy 343.822393 -220.105405) (xy 343.859031 -220.068767)
			(xy 343.90095 -220.038311) (xy 343.947117 -220.014788) (xy 343.996396 -219.998776) (xy 344.047573 -219.99067)
			(xy 344.099387 -219.99067) (xy 344.150564 -219.998776) (xy 344.199843 -220.014788) (xy 344.24601 -220.038311)
			(xy 344.287929 -220.068767) (xy 344.324567 -220.105405) (xy 344.355023 -220.147324) (xy 344.378546 -220.193491)
			(xy 344.394558 -220.24277) (xy 344.402664 -220.293947) (xy 344.403172 -220.319854) (xy 344.402722 -220.3452)
			(xy 344.394942 -220.395293) (xy 344.379588 -220.443604) (xy 344.357022 -220.488998) (xy 344.327776 -220.530404)
			(xy 344.292539 -220.566847) (xy 344.25214 -220.597469) (xy 344.207531 -220.621548) (xy 344.159763 -220.638518)
			(xy 344.134948 -220.643704) (xy 344.112088 -220.648022) (xy 343.90711 -221.003114) (xy 343.914984 -221.024958)
			(xy 343.923577 -221.051373) (xy 343.932765 -221.106151) (xy 343.933272 -221.133924) (xy 344.214196 -221.133924)
			(xy 344.214704 -221.108037) (xy 344.222803 -221.056899) (xy 344.238802 -221.007659) (xy 344.262308 -220.961527)
			(xy 344.29274 -220.91964) (xy 344.32935 -220.88303) (xy 344.371237 -220.852598) (xy 344.417369 -220.829092)
			(xy 344.466609 -220.813093) (xy 344.517747 -220.804994) (xy 344.569521 -220.804994) (xy 344.620659 -220.813093)
			(xy 344.669899 -220.829092) (xy 344.716031 -220.852598) (xy 344.757918 -220.88303) (xy 344.794528 -220.91964)
			(xy 344.82496 -220.961527) (xy 344.848466 -221.007659) (xy 344.864465 -221.056899) (xy 344.872564 -221.108037)
			(xy 344.873072 -221.133924) (xy 345.153996 -221.133924) (xy 345.154504 -221.10859) (xy 345.162253 -221.058519)
			(xy 345.177572 -221.010223) (xy 345.2001 -220.96484) (xy 345.229306 -220.923438) (xy 345.264504 -220.886992)
			(xy 345.304863 -220.856361) (xy 345.349434 -220.832266) (xy 345.397167 -220.815274) (xy 345.421966 -220.810074)
			(xy 345.444826 -220.805756) (xy 345.649804 -220.450664) (xy 345.64193 -220.42882) (xy 345.633296 -220.402408)
			(xy 345.623968 -220.347635) (xy 345.623388 -220.319854) (xy 345.623896 -220.293947) (xy 345.632002 -220.24277)
			(xy 345.648014 -220.193491) (xy 345.671537 -220.147324) (xy 345.701993 -220.105405) (xy 345.738631 -220.068767)
			(xy 345.78055 -220.038311) (xy 345.826717 -220.014788) (xy 345.875996 -219.998776) (xy 345.927173 -219.99067)
			(xy 345.978987 -219.99067) (xy 346.030164 -219.998776) (xy 346.079443 -220.014788) (xy 346.12561 -220.038311)
			(xy 346.167529 -220.068767) (xy 346.204167 -220.105405) (xy 346.234623 -220.147324) (xy 346.258146 -220.193491)
			(xy 346.274158 -220.24277) (xy 346.282264 -220.293947) (xy 346.282772 -220.319854) (xy 346.282322 -220.3452)
			(xy 346.274542 -220.395293) (xy 346.259188 -220.443604) (xy 346.236622 -220.488998) (xy 346.207376 -220.530404)
			(xy 346.172139 -220.566847) (xy 346.13174 -220.597469) (xy 346.087131 -220.621548) (xy 346.039363 -220.638518)
			(xy 346.014548 -220.643704) (xy 345.991688 -220.648022) (xy 345.78671 -221.003114) (xy 345.794584 -221.024958)
			(xy 345.803177 -221.051373) (xy 345.812365 -221.106151) (xy 345.812872 -221.133924) (xy 346.093796 -221.133924)
			(xy 346.094304 -221.108037) (xy 346.102403 -221.056899) (xy 346.118402 -221.007659) (xy 346.141908 -220.961527)
			(xy 346.17234 -220.91964) (xy 346.20895 -220.88303) (xy 346.250837 -220.852598) (xy 346.296969 -220.829092)
			(xy 346.346209 -220.813093) (xy 346.397347 -220.804994) (xy 346.449121 -220.804994) (xy 346.500259 -220.813093)
			(xy 346.549499 -220.829092) (xy 346.595631 -220.852598) (xy 346.637518 -220.88303) (xy 346.674128 -220.91964)
			(xy 346.70456 -220.961527) (xy 346.728066 -221.007659) (xy 346.744065 -221.056899) (xy 346.752164 -221.108037)
			(xy 346.752672 -221.133924) (xy 347.033596 -221.133924) (xy 347.034104 -221.10859) (xy 347.041853 -221.058519)
			(xy 347.057172 -221.010223) (xy 347.0797 -220.96484) (xy 347.108906 -220.923438) (xy 347.144104 -220.886992)
			(xy 347.184463 -220.856361) (xy 347.229034 -220.832266) (xy 347.276767 -220.815274) (xy 347.301566 -220.810074)
			(xy 347.324426 -220.805756) (xy 347.529404 -220.450664) (xy 347.52153 -220.42882) (xy 347.512896 -220.402408)
			(xy 347.503568 -220.347635) (xy 347.502988 -220.319854) (xy 347.503496 -220.293947) (xy 347.511602 -220.24277)
			(xy 347.527614 -220.193491) (xy 347.551137 -220.147324) (xy 347.581593 -220.105405) (xy 347.618231 -220.068767)
			(xy 347.66015 -220.038311) (xy 347.706317 -220.014788) (xy 347.755596 -219.998776) (xy 347.806773 -219.99067)
			(xy 347.858587 -219.99067) (xy 347.909764 -219.998776) (xy 347.959043 -220.014788) (xy 348.00521 -220.038311)
			(xy 348.047129 -220.068767) (xy 348.083767 -220.105405) (xy 348.114223 -220.147324) (xy 348.137746 -220.193491)
			(xy 348.153758 -220.24277) (xy 348.161864 -220.293947) (xy 348.162372 -220.319854) (xy 348.161922 -220.3452)
			(xy 348.154142 -220.395293) (xy 348.138788 -220.443604) (xy 348.116222 -220.488998) (xy 348.086976 -220.530404)
			(xy 348.051739 -220.566847) (xy 348.01134 -220.597469) (xy 347.966731 -220.621548) (xy 347.918963 -220.638518)
			(xy 347.894148 -220.643704) (xy 347.871288 -220.648022) (xy 347.66631 -221.003114) (xy 347.674184 -221.024958)
			(xy 347.682777 -221.051373) (xy 347.691965 -221.106151) (xy 347.692472 -221.133924) (xy 347.973396 -221.133924)
			(xy 347.973904 -221.108037) (xy 347.982003 -221.056899) (xy 347.998002 -221.007659) (xy 348.021508 -220.961527)
			(xy 348.05194 -220.91964) (xy 348.08855 -220.88303) (xy 348.130437 -220.852598) (xy 348.176569 -220.829092)
			(xy 348.225809 -220.813093) (xy 348.276947 -220.804994) (xy 348.328721 -220.804994) (xy 348.379859 -220.813093)
			(xy 348.429099 -220.829092) (xy 348.475231 -220.852598) (xy 348.517118 -220.88303) (xy 348.553728 -220.91964)
			(xy 348.58416 -220.961527) (xy 348.607666 -221.007659) (xy 348.623665 -221.056899) (xy 348.631764 -221.108037)
			(xy 348.632272 -221.133924) (xy 348.913196 -221.133924) (xy 348.913704 -221.10859) (xy 348.921453 -221.058519)
			(xy 348.936772 -221.010223) (xy 348.9593 -220.96484) (xy 348.988506 -220.923438) (xy 349.023704 -220.886992)
			(xy 349.064063 -220.856361) (xy 349.108634 -220.832266) (xy 349.156367 -220.815274) (xy 349.181166 -220.810074)
			(xy 349.204026 -220.805756) (xy 349.409004 -220.450664) (xy 349.40113 -220.42882) (xy 349.392496 -220.402408)
			(xy 349.383168 -220.347635) (xy 349.382588 -220.319854) (xy 349.383096 -220.293947) (xy 349.391202 -220.24277)
			(xy 349.407214 -220.193491) (xy 349.430737 -220.147324) (xy 349.461193 -220.105405) (xy 349.497831 -220.068767)
			(xy 349.53975 -220.038311) (xy 349.585917 -220.014788) (xy 349.635196 -219.998776) (xy 349.686373 -219.99067)
			(xy 349.738187 -219.99067) (xy 349.789364 -219.998776) (xy 349.838643 -220.014788) (xy 349.88481 -220.038311)
			(xy 349.926729 -220.068767) (xy 349.963367 -220.105405) (xy 349.993823 -220.147324) (xy 350.017346 -220.193491)
			(xy 350.033358 -220.24277) (xy 350.041464 -220.293947) (xy 350.041972 -220.319854) (xy 350.041522 -220.3452)
			(xy 350.033742 -220.395293) (xy 350.018388 -220.443604) (xy 349.995822 -220.488998) (xy 349.966576 -220.530404)
			(xy 349.931339 -220.566847) (xy 349.89094 -220.597469) (xy 349.846331 -220.621548) (xy 349.798563 -220.638518)
			(xy 349.773748 -220.643704) (xy 349.750888 -220.648022) (xy 349.54591 -221.003114) (xy 349.553784 -221.024958)
			(xy 349.562377 -221.051373) (xy 349.571565 -221.106151) (xy 349.572072 -221.133924) (xy 349.852996 -221.133924)
			(xy 349.853504 -221.108037) (xy 349.861603 -221.056899) (xy 349.877602 -221.007659) (xy 349.901108 -220.961527)
			(xy 349.93154 -220.91964) (xy 349.96815 -220.88303) (xy 350.010037 -220.852598) (xy 350.056169 -220.829092)
			(xy 350.105409 -220.813093) (xy 350.156547 -220.804994) (xy 350.208321 -220.804994) (xy 350.259459 -220.813093)
			(xy 350.308699 -220.829092) (xy 350.354831 -220.852598) (xy 350.396718 -220.88303) (xy 350.433328 -220.91964)
			(xy 350.46376 -220.961527) (xy 350.487266 -221.007659) (xy 350.503265 -221.056899) (xy 350.511364 -221.108037)
			(xy 350.511872 -221.133924) (xy 350.792796 -221.133924) (xy 350.793304 -221.10859) (xy 350.801053 -221.058519)
			(xy 350.816372 -221.010223) (xy 350.8389 -220.96484) (xy 350.868106 -220.923438) (xy 350.903304 -220.886992)
			(xy 350.943663 -220.856361) (xy 350.988234 -220.832266) (xy 351.035967 -220.815274) (xy 351.060766 -220.810074)
			(xy 351.083626 -220.805756) (xy 351.288604 -220.450664) (xy 351.28073 -220.42882) (xy 351.272096 -220.402408)
			(xy 351.262768 -220.347635) (xy 351.262188 -220.319854) (xy 351.262696 -220.293947) (xy 351.270802 -220.24277)
			(xy 351.286814 -220.193491) (xy 351.310337 -220.147324) (xy 351.340793 -220.105405) (xy 351.377431 -220.068767)
			(xy 351.41935 -220.038311) (xy 351.465517 -220.014788) (xy 351.514796 -219.998776) (xy 351.565973 -219.99067)
			(xy 351.617787 -219.99067) (xy 351.668964 -219.998776) (xy 351.718243 -220.014788) (xy 351.76441 -220.038311)
			(xy 351.806329 -220.068767) (xy 351.842967 -220.105405) (xy 351.873423 -220.147324) (xy 351.896946 -220.193491)
			(xy 351.912958 -220.24277) (xy 351.921064 -220.293947) (xy 351.921572 -220.319854) (xy 353.141788 -220.319854)
			(xy 353.142296 -220.293947) (xy 353.150402 -220.24277) (xy 353.166414 -220.193491) (xy 353.189937 -220.147324)
			(xy 353.220393 -220.105405) (xy 353.257031 -220.068767) (xy 353.29895 -220.038311) (xy 353.345117 -220.014788)
			(xy 353.394396 -219.998776) (xy 353.445573 -219.99067) (xy 353.497387 -219.99067) (xy 353.548564 -219.998776)
			(xy 353.597843 -220.014788) (xy 353.64401 -220.038311) (xy 353.685929 -220.068767) (xy 353.722567 -220.105405)
			(xy 353.753023 -220.147324) (xy 353.776546 -220.193491) (xy 353.792558 -220.24277) (xy 353.800664 -220.293947)
			(xy 353.801172 -220.319854) (xy 355.021388 -220.319854) (xy 355.021896 -220.293947) (xy 355.030002 -220.24277)
			(xy 355.046014 -220.193491) (xy 355.069537 -220.147324) (xy 355.099993 -220.105405) (xy 355.136631 -220.068767)
			(xy 355.17855 -220.038311) (xy 355.224717 -220.014788) (xy 355.273996 -219.998776) (xy 355.325173 -219.99067)
			(xy 355.376987 -219.99067) (xy 355.428164 -219.998776) (xy 355.477443 -220.014788) (xy 355.52361 -220.038311)
			(xy 355.565529 -220.068767) (xy 355.602167 -220.105405) (xy 355.632623 -220.147324) (xy 355.656146 -220.193491)
			(xy 355.672158 -220.24277) (xy 355.680264 -220.293947) (xy 355.680772 -220.319854) (xy 356.900988 -220.319854)
			(xy 356.901496 -220.293947) (xy 356.909602 -220.24277) (xy 356.925614 -220.193491) (xy 356.949137 -220.147324)
			(xy 356.979593 -220.105405) (xy 357.016231 -220.068767) (xy 357.05815 -220.038311) (xy 357.104317 -220.014788)
			(xy 357.153596 -219.998776) (xy 357.204773 -219.99067) (xy 357.256587 -219.99067) (xy 357.307764 -219.998776)
			(xy 357.357043 -220.014788) (xy 357.40321 -220.038311) (xy 357.445129 -220.068767) (xy 357.481767 -220.105405)
			(xy 357.512223 -220.147324) (xy 357.535746 -220.193491) (xy 357.551758 -220.24277) (xy 357.559864 -220.293947)
			(xy 357.560372 -220.319854) (xy 358.780588 -220.319854) (xy 358.781096 -220.293947) (xy 358.789202 -220.24277)
			(xy 358.805214 -220.193491) (xy 358.828737 -220.147324) (xy 358.859193 -220.105405) (xy 358.895831 -220.068767)
			(xy 358.93775 -220.038311) (xy 358.983917 -220.014788) (xy 359.033196 -219.998776) (xy 359.084373 -219.99067)
			(xy 359.136187 -219.99067) (xy 359.187364 -219.998776) (xy 359.236643 -220.014788) (xy 359.28281 -220.038311)
			(xy 359.324729 -220.068767) (xy 359.361367 -220.105405) (xy 359.391823 -220.147324) (xy 359.415346 -220.193491)
			(xy 359.431358 -220.24277) (xy 359.439464 -220.293947) (xy 359.439972 -220.319854) (xy 360.660188 -220.319854)
			(xy 360.660696 -220.293947) (xy 360.668802 -220.24277) (xy 360.684814 -220.193491) (xy 360.708337 -220.147324)
			(xy 360.738793 -220.105405) (xy 360.775431 -220.068767) (xy 360.81735 -220.038311) (xy 360.863517 -220.014788)
			(xy 360.912796 -219.998776) (xy 360.963973 -219.99067) (xy 361.015787 -219.99067) (xy 361.066964 -219.998776)
			(xy 361.116243 -220.014788) (xy 361.16241 -220.038311) (xy 361.204329 -220.068767) (xy 361.240967 -220.105405)
			(xy 361.271423 -220.147324) (xy 361.294946 -220.193491) (xy 361.310958 -220.24277) (xy 361.319064 -220.293947)
			(xy 361.319572 -220.319854) (xy 362.539788 -220.319854) (xy 362.540296 -220.293947) (xy 362.548402 -220.24277)
			(xy 362.564414 -220.193491) (xy 362.587937 -220.147324) (xy 362.618393 -220.105405) (xy 362.655031 -220.068767)
			(xy 362.69695 -220.038311) (xy 362.743117 -220.014788) (xy 362.792396 -219.998776) (xy 362.843573 -219.99067)
			(xy 362.895387 -219.99067) (xy 362.946564 -219.998776) (xy 362.995843 -220.014788) (xy 363.04201 -220.038311)
			(xy 363.083929 -220.068767) (xy 363.120567 -220.105405) (xy 363.151023 -220.147324) (xy 363.174546 -220.193491)
			(xy 363.190558 -220.24277) (xy 363.198664 -220.293947) (xy 363.199172 -220.319854) (xy 364.419388 -220.319854)
			(xy 364.419896 -220.293947) (xy 364.428002 -220.24277) (xy 364.444014 -220.193491) (xy 364.467537 -220.147324)
			(xy 364.497993 -220.105405) (xy 364.534631 -220.068767) (xy 364.57655 -220.038311) (xy 364.622717 -220.014788)
			(xy 364.671996 -219.998776) (xy 364.723173 -219.99067) (xy 364.774987 -219.99067) (xy 364.826164 -219.998776)
			(xy 364.875443 -220.014788) (xy 364.92161 -220.038311) (xy 364.963529 -220.068767) (xy 365.000167 -220.105405)
			(xy 365.030623 -220.147324) (xy 365.054146 -220.193491) (xy 365.070158 -220.24277) (xy 365.078264 -220.293947)
			(xy 365.078772 -220.319854) (xy 366.298988 -220.319854) (xy 366.299496 -220.293947) (xy 366.307602 -220.24277)
			(xy 366.323614 -220.193491) (xy 366.347137 -220.147324) (xy 366.377593 -220.105405) (xy 366.414231 -220.068767)
			(xy 366.45615 -220.038311) (xy 366.502317 -220.014788) (xy 366.551596 -219.998776) (xy 366.602773 -219.99067)
			(xy 366.654587 -219.99067) (xy 366.705764 -219.998776) (xy 366.755043 -220.014788) (xy 366.80121 -220.038311)
			(xy 366.843129 -220.068767) (xy 366.879767 -220.105405) (xy 366.910223 -220.147324) (xy 366.933746 -220.193491)
			(xy 366.949758 -220.24277) (xy 366.957864 -220.293947) (xy 366.958372 -220.319854) (xy 368.178588 -220.319854)
			(xy 368.179096 -220.293947) (xy 368.187202 -220.24277) (xy 368.203214 -220.193491) (xy 368.226737 -220.147324)
			(xy 368.257193 -220.105405) (xy 368.293831 -220.068767) (xy 368.33575 -220.038311) (xy 368.381917 -220.014788)
			(xy 368.431196 -219.998776) (xy 368.482373 -219.99067) (xy 368.534187 -219.99067) (xy 368.585364 -219.998776)
			(xy 368.634643 -220.014788) (xy 368.68081 -220.038311) (xy 368.722729 -220.068767) (xy 368.759367 -220.105405)
			(xy 368.789823 -220.147324) (xy 368.813346 -220.193491) (xy 368.829358 -220.24277) (xy 368.837464 -220.293947)
			(xy 368.837972 -220.319854) (xy 370.058188 -220.319854) (xy 370.058696 -220.293947) (xy 370.066802 -220.24277)
			(xy 370.082814 -220.193491) (xy 370.106337 -220.147324) (xy 370.136793 -220.105405) (xy 370.173431 -220.068767)
			(xy 370.21535 -220.038311) (xy 370.261517 -220.014788) (xy 370.310796 -219.998776) (xy 370.361973 -219.99067)
			(xy 370.413787 -219.99067) (xy 370.464964 -219.998776) (xy 370.514243 -220.014788) (xy 370.56041 -220.038311)
			(xy 370.602329 -220.068767) (xy 370.638967 -220.105405) (xy 370.669423 -220.147324) (xy 370.692946 -220.193491)
			(xy 370.708958 -220.24277) (xy 370.717064 -220.293947) (xy 370.717572 -220.319854) (xy 371.937788 -220.319854)
			(xy 371.938296 -220.293947) (xy 371.946402 -220.24277) (xy 371.962414 -220.193491) (xy 371.985937 -220.147324)
			(xy 372.016393 -220.105405) (xy 372.053031 -220.068767) (xy 372.09495 -220.038311) (xy 372.141117 -220.014788)
			(xy 372.190396 -219.998776) (xy 372.241573 -219.99067) (xy 372.293387 -219.99067) (xy 372.344564 -219.998776)
			(xy 372.393843 -220.014788) (xy 372.44001 -220.038311) (xy 372.481929 -220.068767) (xy 372.518567 -220.105405)
			(xy 372.549023 -220.147324) (xy 372.572546 -220.193491) (xy 372.588558 -220.24277) (xy 372.596664 -220.293947)
			(xy 372.597172 -220.319854) (xy 373.817388 -220.319854) (xy 373.817896 -220.293947) (xy 373.826002 -220.24277)
			(xy 373.842014 -220.193491) (xy 373.865537 -220.147324) (xy 373.895993 -220.105405) (xy 373.932631 -220.068767)
			(xy 373.97455 -220.038311) (xy 374.020717 -220.014788) (xy 374.069996 -219.998776) (xy 374.121173 -219.99067)
			(xy 374.172987 -219.99067) (xy 374.224164 -219.998776) (xy 374.273443 -220.014788) (xy 374.31961 -220.038311)
			(xy 374.361529 -220.068767) (xy 374.398167 -220.105405) (xy 374.428623 -220.147324) (xy 374.452146 -220.193491)
			(xy 374.468158 -220.24277) (xy 374.476264 -220.293947) (xy 374.476772 -220.319854) (xy 375.696988 -220.319854)
			(xy 375.697496 -220.293947) (xy 375.705602 -220.24277) (xy 375.721614 -220.193491) (xy 375.745137 -220.147324)
			(xy 375.775593 -220.105405) (xy 375.812231 -220.068767) (xy 375.85415 -220.038311) (xy 375.900317 -220.014788)
			(xy 375.949596 -219.998776) (xy 376.000773 -219.99067) (xy 376.052587 -219.99067) (xy 376.103764 -219.998776)
			(xy 376.153043 -220.014788) (xy 376.19921 -220.038311) (xy 376.241129 -220.068767) (xy 376.277767 -220.105405)
			(xy 376.308223 -220.147324) (xy 376.331746 -220.193491) (xy 376.347758 -220.24277) (xy 376.355864 -220.293947)
			(xy 376.356372 -220.319854) (xy 377.576588 -220.319854) (xy 377.577096 -220.293947) (xy 377.585202 -220.24277)
			(xy 377.601214 -220.193491) (xy 377.624737 -220.147324) (xy 377.655193 -220.105405) (xy 377.691831 -220.068767)
			(xy 377.73375 -220.038311) (xy 377.779917 -220.014788) (xy 377.829196 -219.998776) (xy 377.880373 -219.99067)
			(xy 377.932187 -219.99067) (xy 377.983364 -219.998776) (xy 378.032643 -220.014788) (xy 378.07881 -220.038311)
			(xy 378.120729 -220.068767) (xy 378.157367 -220.105405) (xy 378.187823 -220.147324) (xy 378.211346 -220.193491)
			(xy 378.227358 -220.24277) (xy 378.235464 -220.293947) (xy 378.235972 -220.319854) (xy 379.456188 -220.319854)
			(xy 379.456696 -220.293947) (xy 379.464802 -220.24277) (xy 379.480814 -220.193491) (xy 379.504337 -220.147324)
			(xy 379.534793 -220.105405) (xy 379.571431 -220.068767) (xy 379.61335 -220.038311) (xy 379.659517 -220.014788)
			(xy 379.708796 -219.998776) (xy 379.759973 -219.99067) (xy 379.811787 -219.99067) (xy 379.862964 -219.998776)
			(xy 379.912243 -220.014788) (xy 379.95841 -220.038311) (xy 380.000329 -220.068767) (xy 380.036967 -220.105405)
			(xy 380.067423 -220.147324) (xy 380.090946 -220.193491) (xy 380.106958 -220.24277) (xy 380.115064 -220.293947)
			(xy 380.115572 -220.319854) (xy 381.336296 -220.319854) (xy 381.336804 -220.293967) (xy 381.344903 -220.242829)
			(xy 381.360902 -220.193589) (xy 381.384408 -220.147457) (xy 381.41484 -220.10557) (xy 381.45145 -220.06896)
			(xy 381.493337 -220.038528) (xy 381.539469 -220.015022) (xy 381.588709 -219.999023) (xy 381.639847 -219.990924)
			(xy 381.691621 -219.990924) (xy 381.742759 -219.999023) (xy 381.791999 -220.015022) (xy 381.838131 -220.038528)
			(xy 381.880018 -220.06896) (xy 381.916628 -220.10557) (xy 381.94706 -220.147457) (xy 381.970566 -220.193589)
			(xy 381.986565 -220.242829) (xy 381.994664 -220.293967) (xy 381.995172 -220.319854) (xy 381.994628 -220.347561)
			(xy 381.985442 -220.402208) (xy 381.976884 -220.428566) (xy 381.969264 -220.450664) (xy 382.174242 -220.805756)
			(xy 382.197102 -220.810074) (xy 382.221908 -220.815252) (xy 382.269647 -220.832242) (xy 382.314225 -220.856337)
			(xy 382.354591 -220.886969) (xy 382.389795 -220.923417) (xy 382.419006 -220.964822) (xy 382.441538 -221.01021)
			(xy 382.45686 -221.058511) (xy 382.46461 -221.108588) (xy 382.465072 -221.133924) (xy 382.464564 -221.159811)
			(xy 382.456465 -221.210949) (xy 382.440466 -221.260189) (xy 382.41696 -221.306321) (xy 382.386528 -221.348208)
			(xy 382.349918 -221.384818) (xy 382.308031 -221.41525) (xy 382.261899 -221.438756) (xy 382.212659 -221.454755)
			(xy 382.161521 -221.462854) (xy 382.109747 -221.462854) (xy 382.058609 -221.454755) (xy 382.009369 -221.438756)
			(xy 381.963237 -221.41525) (xy 381.92135 -221.384818) (xy 381.88474 -221.348208) (xy 381.854308 -221.306321)
			(xy 381.830802 -221.260189) (xy 381.814803 -221.210949) (xy 381.806704 -221.159811) (xy 381.806196 -221.133924)
			(xy 381.806732 -221.106216) (xy 381.815923 -221.051569) (xy 381.824484 -221.025212) (xy 381.832358 -221.003114)
			(xy 381.62738 -220.648022) (xy 381.60452 -220.643704) (xy 381.579694 -220.638559) (xy 381.531915 -220.6216)
			(xy 381.487296 -220.597525) (xy 381.446891 -220.566902) (xy 381.41165 -220.530452) (xy 381.382408 -220.489036)
			(xy 381.359851 -220.44363) (xy 381.344514 -220.395306) (xy 381.336758 -220.345204) (xy 381.336296 -220.319854)
			(xy 380.115572 -220.319854) (xy 380.114963 -220.347508) (xy 380.105639 -220.402026) (xy 380.09703 -220.428312)
			(xy 380.08941 -220.45041) (xy 380.294642 -220.805756) (xy 380.317502 -220.810074) (xy 380.342308 -220.815252)
			(xy 380.390047 -220.832242) (xy 380.434625 -220.856337) (xy 380.474991 -220.886969) (xy 380.510195 -220.923417)
			(xy 380.539406 -220.964822) (xy 380.561938 -221.01021) (xy 380.57726 -221.058511) (xy 380.58501 -221.108588)
			(xy 380.585472 -221.133924) (xy 380.584964 -221.159811) (xy 380.576865 -221.210949) (xy 380.560866 -221.260189)
			(xy 380.53736 -221.306321) (xy 380.506928 -221.348208) (xy 380.470318 -221.384818) (xy 380.428431 -221.41525)
			(xy 380.382299 -221.438756) (xy 380.333059 -221.454755) (xy 380.281921 -221.462854) (xy 380.230147 -221.462854)
			(xy 380.179009 -221.454755) (xy 380.129769 -221.438756) (xy 380.083637 -221.41525) (xy 380.04175 -221.384818)
			(xy 380.00514 -221.348208) (xy 379.974708 -221.306321) (xy 379.951202 -221.260189) (xy 379.935203 -221.210949)
			(xy 379.927104 -221.159811) (xy 379.926596 -221.133924) (xy 379.927132 -221.106216) (xy 379.936323 -221.051569)
			(xy 379.944884 -221.025212) (xy 379.952758 -221.003114) (xy 379.74778 -220.648022) (xy 379.72492 -220.643704)
			(xy 379.700079 -220.638521) (xy 379.652232 -220.621628) (xy 379.60754 -220.5976) (xy 379.567059 -220.567005)
			(xy 379.531748 -220.530566) (xy 379.502439 -220.489145) (xy 379.479827 -220.44372) (xy 379.464446 -220.395365)
			(xy 379.456659 -220.345225) (xy 379.456188 -220.319854) (xy 378.235972 -220.319854) (xy 378.235363 -220.347508)
			(xy 378.226039 -220.402026) (xy 378.21743 -220.428312) (xy 378.20981 -220.45041) (xy 378.415042 -220.805756)
			(xy 378.437902 -220.810074) (xy 378.462708 -220.815252) (xy 378.510447 -220.832242) (xy 378.555025 -220.856337)
			(xy 378.595391 -220.886969) (xy 378.630595 -220.923417) (xy 378.659806 -220.964822) (xy 378.682338 -221.01021)
			(xy 378.69766 -221.058511) (xy 378.70541 -221.108588) (xy 378.705872 -221.133924) (xy 378.705364 -221.159811)
			(xy 378.697265 -221.210949) (xy 378.681266 -221.260189) (xy 378.65776 -221.306321) (xy 378.627328 -221.348208)
			(xy 378.590718 -221.384818) (xy 378.548831 -221.41525) (xy 378.502699 -221.438756) (xy 378.453459 -221.454755)
			(xy 378.402321 -221.462854) (xy 378.350547 -221.462854) (xy 378.299409 -221.454755) (xy 378.250169 -221.438756)
			(xy 378.204037 -221.41525) (xy 378.16215 -221.384818) (xy 378.12554 -221.348208) (xy 378.095108 -221.306321)
			(xy 378.071602 -221.260189) (xy 378.055603 -221.210949) (xy 378.047504 -221.159811) (xy 378.046996 -221.133924)
			(xy 378.047532 -221.106216) (xy 378.056723 -221.051569) (xy 378.065284 -221.025212) (xy 378.073158 -221.003114)
			(xy 377.86818 -220.648022) (xy 377.84532 -220.643704) (xy 377.820479 -220.638521) (xy 377.772632 -220.621628)
			(xy 377.72794 -220.5976) (xy 377.687459 -220.567005) (xy 377.652148 -220.530566) (xy 377.622839 -220.489145)
			(xy 377.600227 -220.44372) (xy 377.584846 -220.395365) (xy 377.577059 -220.345225) (xy 377.576588 -220.319854)
			(xy 376.356372 -220.319854) (xy 376.355763 -220.347508) (xy 376.346439 -220.402026) (xy 376.33783 -220.428312)
			(xy 376.33021 -220.45041) (xy 376.535442 -220.805756) (xy 376.558302 -220.810074) (xy 376.583108 -220.815252)
			(xy 376.630847 -220.832242) (xy 376.675425 -220.856337) (xy 376.715791 -220.886969) (xy 376.750995 -220.923417)
			(xy 376.780206 -220.964822) (xy 376.802738 -221.01021) (xy 376.81806 -221.058511) (xy 376.82581 -221.108588)
			(xy 376.826272 -221.133924) (xy 376.825764 -221.159811) (xy 376.817665 -221.210949) (xy 376.801666 -221.260189)
			(xy 376.77816 -221.306321) (xy 376.747728 -221.348208) (xy 376.711118 -221.384818) (xy 376.669231 -221.41525)
			(xy 376.623099 -221.438756) (xy 376.573859 -221.454755) (xy 376.522721 -221.462854) (xy 376.470947 -221.462854)
			(xy 376.419809 -221.454755) (xy 376.370569 -221.438756) (xy 376.324437 -221.41525) (xy 376.28255 -221.384818)
			(xy 376.24594 -221.348208) (xy 376.215508 -221.306321) (xy 376.192002 -221.260189) (xy 376.176003 -221.210949)
			(xy 376.167904 -221.159811) (xy 376.167396 -221.133924) (xy 376.167932 -221.106216) (xy 376.177123 -221.051569)
			(xy 376.185684 -221.025212) (xy 376.193558 -221.003114) (xy 375.98858 -220.648022) (xy 375.96572 -220.643704)
			(xy 375.940879 -220.638521) (xy 375.893032 -220.621628) (xy 375.84834 -220.5976) (xy 375.807859 -220.567005)
			(xy 375.772548 -220.530566) (xy 375.743239 -220.489145) (xy 375.720627 -220.44372) (xy 375.705246 -220.395365)
			(xy 375.697459 -220.345225) (xy 375.696988 -220.319854) (xy 374.476772 -220.319854) (xy 374.476163 -220.347508)
			(xy 374.466839 -220.402026) (xy 374.45823 -220.428312) (xy 374.45061 -220.45041) (xy 374.655842 -220.805756)
			(xy 374.678702 -220.810074) (xy 374.703508 -220.815252) (xy 374.751247 -220.832242) (xy 374.795825 -220.856337)
			(xy 374.836191 -220.886969) (xy 374.871395 -220.923417) (xy 374.900606 -220.964822) (xy 374.923138 -221.01021)
			(xy 374.93846 -221.058511) (xy 374.94621 -221.108588) (xy 374.946672 -221.133924) (xy 374.946164 -221.159811)
			(xy 374.938065 -221.210949) (xy 374.922066 -221.260189) (xy 374.89856 -221.306321) (xy 374.868128 -221.348208)
			(xy 374.831518 -221.384818) (xy 374.789631 -221.41525) (xy 374.743499 -221.438756) (xy 374.694259 -221.454755)
			(xy 374.643121 -221.462854) (xy 374.591347 -221.462854) (xy 374.540209 -221.454755) (xy 374.490969 -221.438756)
			(xy 374.444837 -221.41525) (xy 374.40295 -221.384818) (xy 374.36634 -221.348208) (xy 374.335908 -221.306321)
			(xy 374.312402 -221.260189) (xy 374.296403 -221.210949) (xy 374.288304 -221.159811) (xy 374.287796 -221.133924)
			(xy 374.288332 -221.106216) (xy 374.297523 -221.051569) (xy 374.306084 -221.025212) (xy 374.313958 -221.003114)
			(xy 374.10898 -220.648022) (xy 374.08612 -220.643704) (xy 374.061279 -220.638521) (xy 374.013432 -220.621628)
			(xy 373.96874 -220.5976) (xy 373.928259 -220.567005) (xy 373.892948 -220.530566) (xy 373.863639 -220.489145)
			(xy 373.841027 -220.44372) (xy 373.825646 -220.395365) (xy 373.817859 -220.345225) (xy 373.817388 -220.319854)
			(xy 372.597172 -220.319854) (xy 372.596563 -220.347508) (xy 372.587239 -220.402026) (xy 372.57863 -220.428312)
			(xy 372.57101 -220.45041) (xy 372.776242 -220.805756) (xy 372.799102 -220.810074) (xy 372.823908 -220.815252)
			(xy 372.871647 -220.832242) (xy 372.916225 -220.856337) (xy 372.956591 -220.886969) (xy 372.991795 -220.923417)
			(xy 373.021006 -220.964822) (xy 373.043538 -221.01021) (xy 373.05886 -221.058511) (xy 373.06661 -221.108588)
			(xy 373.067072 -221.133924) (xy 373.066564 -221.159811) (xy 373.058465 -221.210949) (xy 373.042466 -221.260189)
			(xy 373.01896 -221.306321) (xy 372.988528 -221.348208) (xy 372.951918 -221.384818) (xy 372.910031 -221.41525)
			(xy 372.863899 -221.438756) (xy 372.814659 -221.454755) (xy 372.763521 -221.462854) (xy 372.711747 -221.462854)
			(xy 372.660609 -221.454755) (xy 372.611369 -221.438756) (xy 372.565237 -221.41525) (xy 372.52335 -221.384818)
			(xy 372.48674 -221.348208) (xy 372.456308 -221.306321) (xy 372.432802 -221.260189) (xy 372.416803 -221.210949)
			(xy 372.408704 -221.159811) (xy 372.408196 -221.133924) (xy 372.408732 -221.106216) (xy 372.417923 -221.051569)
			(xy 372.426484 -221.025212) (xy 372.434358 -221.003114) (xy 372.22938 -220.648022) (xy 372.20652 -220.643704)
			(xy 372.181679 -220.638521) (xy 372.133832 -220.621628) (xy 372.08914 -220.5976) (xy 372.048659 -220.567005)
			(xy 372.013348 -220.530566) (xy 371.984039 -220.489145) (xy 371.961427 -220.44372) (xy 371.946046 -220.395365)
			(xy 371.938259 -220.345225) (xy 371.937788 -220.319854) (xy 370.717572 -220.319854) (xy 370.716963 -220.347508)
			(xy 370.707639 -220.402026) (xy 370.69903 -220.428312) (xy 370.69141 -220.45041) (xy 370.896642 -220.805756)
			(xy 370.919502 -220.810074) (xy 370.944308 -220.815252) (xy 370.992047 -220.832242) (xy 371.036625 -220.856337)
			(xy 371.076991 -220.886969) (xy 371.112195 -220.923417) (xy 371.141406 -220.964822) (xy 371.163938 -221.01021)
			(xy 371.17926 -221.058511) (xy 371.18701 -221.108588) (xy 371.187472 -221.133924) (xy 371.186964 -221.159811)
			(xy 371.178865 -221.210949) (xy 371.162866 -221.260189) (xy 371.13936 -221.306321) (xy 371.108928 -221.348208)
			(xy 371.072318 -221.384818) (xy 371.030431 -221.41525) (xy 370.984299 -221.438756) (xy 370.935059 -221.454755)
			(xy 370.883921 -221.462854) (xy 370.832147 -221.462854) (xy 370.781009 -221.454755) (xy 370.731769 -221.438756)
			(xy 370.685637 -221.41525) (xy 370.64375 -221.384818) (xy 370.60714 -221.348208) (xy 370.576708 -221.306321)
			(xy 370.553202 -221.260189) (xy 370.537203 -221.210949) (xy 370.529104 -221.159811) (xy 370.528596 -221.133924)
			(xy 370.529132 -221.106216) (xy 370.538323 -221.051569) (xy 370.546884 -221.025212) (xy 370.554758 -221.003114)
			(xy 370.34978 -220.648022) (xy 370.32692 -220.643704) (xy 370.302079 -220.638521) (xy 370.254232 -220.621628)
			(xy 370.20954 -220.5976) (xy 370.169059 -220.567005) (xy 370.133748 -220.530566) (xy 370.104439 -220.489145)
			(xy 370.081827 -220.44372) (xy 370.066446 -220.395365) (xy 370.058659 -220.345225) (xy 370.058188 -220.319854)
			(xy 368.837972 -220.319854) (xy 368.837363 -220.347508) (xy 368.828039 -220.402026) (xy 368.81943 -220.428312)
			(xy 368.81181 -220.45041) (xy 369.017042 -220.805756) (xy 369.039902 -220.810074) (xy 369.064708 -220.815252)
			(xy 369.112447 -220.832242) (xy 369.157025 -220.856337) (xy 369.197391 -220.886969) (xy 369.232595 -220.923417)
			(xy 369.261806 -220.964822) (xy 369.284338 -221.01021) (xy 369.29966 -221.058511) (xy 369.30741 -221.108588)
			(xy 369.307872 -221.133924) (xy 369.307364 -221.159811) (xy 369.299265 -221.210949) (xy 369.283266 -221.260189)
			(xy 369.25976 -221.306321) (xy 369.229328 -221.348208) (xy 369.192718 -221.384818) (xy 369.150831 -221.41525)
			(xy 369.104699 -221.438756) (xy 369.055459 -221.454755) (xy 369.004321 -221.462854) (xy 368.952547 -221.462854)
			(xy 368.901409 -221.454755) (xy 368.852169 -221.438756) (xy 368.806037 -221.41525) (xy 368.76415 -221.384818)
			(xy 368.72754 -221.348208) (xy 368.697108 -221.306321) (xy 368.673602 -221.260189) (xy 368.657603 -221.210949)
			(xy 368.649504 -221.159811) (xy 368.648996 -221.133924) (xy 368.649532 -221.106216) (xy 368.658723 -221.051569)
			(xy 368.667284 -221.025212) (xy 368.675158 -221.003114) (xy 368.47018 -220.648022) (xy 368.44732 -220.643704)
			(xy 368.422479 -220.638521) (xy 368.374632 -220.621628) (xy 368.32994 -220.5976) (xy 368.289459 -220.567005)
			(xy 368.254148 -220.530566) (xy 368.224839 -220.489145) (xy 368.202227 -220.44372) (xy 368.186846 -220.395365)
			(xy 368.179059 -220.345225) (xy 368.178588 -220.319854) (xy 366.958372 -220.319854) (xy 366.957763 -220.347508)
			(xy 366.948439 -220.402026) (xy 366.93983 -220.428312) (xy 366.93221 -220.45041) (xy 367.137442 -220.805756)
			(xy 367.160302 -220.810074) (xy 367.185108 -220.815252) (xy 367.232847 -220.832242) (xy 367.277425 -220.856337)
			(xy 367.317791 -220.886969) (xy 367.352995 -220.923417) (xy 367.382206 -220.964822) (xy 367.404738 -221.01021)
			(xy 367.42006 -221.058511) (xy 367.42781 -221.108588) (xy 367.428272 -221.133924) (xy 367.427764 -221.159811)
			(xy 367.419665 -221.210949) (xy 367.403666 -221.260189) (xy 367.38016 -221.306321) (xy 367.349728 -221.348208)
			(xy 367.313118 -221.384818) (xy 367.271231 -221.41525) (xy 367.225099 -221.438756) (xy 367.175859 -221.454755)
			(xy 367.124721 -221.462854) (xy 367.072947 -221.462854) (xy 367.021809 -221.454755) (xy 366.972569 -221.438756)
			(xy 366.926437 -221.41525) (xy 366.88455 -221.384818) (xy 366.84794 -221.348208) (xy 366.817508 -221.306321)
			(xy 366.794002 -221.260189) (xy 366.778003 -221.210949) (xy 366.769904 -221.159811) (xy 366.769396 -221.133924)
			(xy 366.769932 -221.106216) (xy 366.779123 -221.051569) (xy 366.787684 -221.025212) (xy 366.795558 -221.003114)
			(xy 366.59058 -220.648022) (xy 366.56772 -220.643704) (xy 366.542879 -220.638521) (xy 366.495032 -220.621628)
			(xy 366.45034 -220.5976) (xy 366.409859 -220.567005) (xy 366.374548 -220.530566) (xy 366.345239 -220.489145)
			(xy 366.322627 -220.44372) (xy 366.307246 -220.395365) (xy 366.299459 -220.345225) (xy 366.298988 -220.319854)
			(xy 365.078772 -220.319854) (xy 365.078163 -220.347508) (xy 365.068839 -220.402026) (xy 365.06023 -220.428312)
			(xy 365.05261 -220.45041) (xy 365.257842 -220.805756) (xy 365.280702 -220.810074) (xy 365.305508 -220.815252)
			(xy 365.353247 -220.832242) (xy 365.397825 -220.856337) (xy 365.438191 -220.886969) (xy 365.473395 -220.923417)
			(xy 365.502606 -220.964822) (xy 365.525138 -221.01021) (xy 365.54046 -221.058511) (xy 365.54821 -221.108588)
			(xy 365.548672 -221.133924) (xy 365.548164 -221.159811) (xy 365.540065 -221.210949) (xy 365.524066 -221.260189)
			(xy 365.50056 -221.306321) (xy 365.470128 -221.348208) (xy 365.433518 -221.384818) (xy 365.391631 -221.41525)
			(xy 365.345499 -221.438756) (xy 365.296259 -221.454755) (xy 365.245121 -221.462854) (xy 365.193347 -221.462854)
			(xy 365.142209 -221.454755) (xy 365.092969 -221.438756) (xy 365.046837 -221.41525) (xy 365.00495 -221.384818)
			(xy 364.96834 -221.348208) (xy 364.937908 -221.306321) (xy 364.914402 -221.260189) (xy 364.898403 -221.210949)
			(xy 364.890304 -221.159811) (xy 364.889796 -221.133924) (xy 364.890332 -221.106216) (xy 364.899523 -221.051569)
			(xy 364.908084 -221.025212) (xy 364.915958 -221.003114) (xy 364.71098 -220.648022) (xy 364.68812 -220.643704)
			(xy 364.663279 -220.638521) (xy 364.615432 -220.621628) (xy 364.57074 -220.5976) (xy 364.530259 -220.567005)
			(xy 364.494948 -220.530566) (xy 364.465639 -220.489145) (xy 364.443027 -220.44372) (xy 364.427646 -220.395365)
			(xy 364.419859 -220.345225) (xy 364.419388 -220.319854) (xy 363.199172 -220.319854) (xy 363.198563 -220.347508)
			(xy 363.189239 -220.402026) (xy 363.18063 -220.428312) (xy 363.17301 -220.45041) (xy 363.378242 -220.805756)
			(xy 363.401102 -220.810074) (xy 363.425908 -220.815252) (xy 363.473647 -220.832242) (xy 363.518225 -220.856337)
			(xy 363.558591 -220.886969) (xy 363.593795 -220.923417) (xy 363.623006 -220.964822) (xy 363.645538 -221.01021)
			(xy 363.66086 -221.058511) (xy 363.66861 -221.108588) (xy 363.669072 -221.133924) (xy 363.668564 -221.159811)
			(xy 363.660465 -221.210949) (xy 363.644466 -221.260189) (xy 363.62096 -221.306321) (xy 363.590528 -221.348208)
			(xy 363.553918 -221.384818) (xy 363.512031 -221.41525) (xy 363.465899 -221.438756) (xy 363.416659 -221.454755)
			(xy 363.365521 -221.462854) (xy 363.313747 -221.462854) (xy 363.262609 -221.454755) (xy 363.213369 -221.438756)
			(xy 363.167237 -221.41525) (xy 363.12535 -221.384818) (xy 363.08874 -221.348208) (xy 363.058308 -221.306321)
			(xy 363.034802 -221.260189) (xy 363.018803 -221.210949) (xy 363.010704 -221.159811) (xy 363.010196 -221.133924)
			(xy 363.010732 -221.106216) (xy 363.019923 -221.051569) (xy 363.028484 -221.025212) (xy 363.036358 -221.003114)
			(xy 362.83138 -220.648022) (xy 362.80852 -220.643704) (xy 362.783679 -220.638521) (xy 362.735832 -220.621628)
			(xy 362.69114 -220.5976) (xy 362.650659 -220.567005) (xy 362.615348 -220.530566) (xy 362.586039 -220.489145)
			(xy 362.563427 -220.44372) (xy 362.548046 -220.395365) (xy 362.540259 -220.345225) (xy 362.539788 -220.319854)
			(xy 361.319572 -220.319854) (xy 361.318963 -220.347508) (xy 361.309639 -220.402026) (xy 361.30103 -220.428312)
			(xy 361.29341 -220.45041) (xy 361.498642 -220.805756) (xy 361.521502 -220.810074) (xy 361.546308 -220.815252)
			(xy 361.594047 -220.832242) (xy 361.638625 -220.856337) (xy 361.678991 -220.886969) (xy 361.714195 -220.923417)
			(xy 361.743406 -220.964822) (xy 361.765938 -221.01021) (xy 361.78126 -221.058511) (xy 361.78901 -221.108588)
			(xy 361.789472 -221.133924) (xy 361.788964 -221.159811) (xy 361.780865 -221.210949) (xy 361.764866 -221.260189)
			(xy 361.74136 -221.306321) (xy 361.710928 -221.348208) (xy 361.674318 -221.384818) (xy 361.632431 -221.41525)
			(xy 361.586299 -221.438756) (xy 361.537059 -221.454755) (xy 361.485921 -221.462854) (xy 361.434147 -221.462854)
			(xy 361.383009 -221.454755) (xy 361.333769 -221.438756) (xy 361.287637 -221.41525) (xy 361.24575 -221.384818)
			(xy 361.20914 -221.348208) (xy 361.178708 -221.306321) (xy 361.155202 -221.260189) (xy 361.139203 -221.210949)
			(xy 361.131104 -221.159811) (xy 361.130596 -221.133924) (xy 361.131132 -221.106216) (xy 361.140323 -221.051569)
			(xy 361.148884 -221.025212) (xy 361.156758 -221.003114) (xy 360.95178 -220.648022) (xy 360.92892 -220.643704)
			(xy 360.904079 -220.638521) (xy 360.856232 -220.621628) (xy 360.81154 -220.5976) (xy 360.771059 -220.567005)
			(xy 360.735748 -220.530566) (xy 360.706439 -220.489145) (xy 360.683827 -220.44372) (xy 360.668446 -220.395365)
			(xy 360.660659 -220.345225) (xy 360.660188 -220.319854) (xy 359.439972 -220.319854) (xy 359.439363 -220.347508)
			(xy 359.430039 -220.402026) (xy 359.42143 -220.428312) (xy 359.41381 -220.45041) (xy 359.619042 -220.805756)
			(xy 359.641902 -220.810074) (xy 359.666708 -220.815252) (xy 359.714447 -220.832242) (xy 359.759025 -220.856337)
			(xy 359.799391 -220.886969) (xy 359.834595 -220.923417) (xy 359.863806 -220.964822) (xy 359.886338 -221.01021)
			(xy 359.90166 -221.058511) (xy 359.90941 -221.108588) (xy 359.909872 -221.133924) (xy 359.909364 -221.159811)
			(xy 359.901265 -221.210949) (xy 359.885266 -221.260189) (xy 359.86176 -221.306321) (xy 359.831328 -221.348208)
			(xy 359.794718 -221.384818) (xy 359.752831 -221.41525) (xy 359.706699 -221.438756) (xy 359.657459 -221.454755)
			(xy 359.606321 -221.462854) (xy 359.554547 -221.462854) (xy 359.503409 -221.454755) (xy 359.454169 -221.438756)
			(xy 359.408037 -221.41525) (xy 359.36615 -221.384818) (xy 359.32954 -221.348208) (xy 359.299108 -221.306321)
			(xy 359.275602 -221.260189) (xy 359.259603 -221.210949) (xy 359.251504 -221.159811) (xy 359.250996 -221.133924)
			(xy 359.251532 -221.106216) (xy 359.260723 -221.051569) (xy 359.269284 -221.025212) (xy 359.277158 -221.003114)
			(xy 359.07218 -220.648022) (xy 359.04932 -220.643704) (xy 359.024479 -220.638521) (xy 358.976632 -220.621628)
			(xy 358.93194 -220.5976) (xy 358.891459 -220.567005) (xy 358.856148 -220.530566) (xy 358.826839 -220.489145)
			(xy 358.804227 -220.44372) (xy 358.788846 -220.395365) (xy 358.781059 -220.345225) (xy 358.780588 -220.319854)
			(xy 357.560372 -220.319854) (xy 357.559763 -220.347508) (xy 357.550439 -220.402026) (xy 357.54183 -220.428312)
			(xy 357.53421 -220.45041) (xy 357.739442 -220.805756) (xy 357.762302 -220.810074) (xy 357.787108 -220.815252)
			(xy 357.834847 -220.832242) (xy 357.879425 -220.856337) (xy 357.919791 -220.886969) (xy 357.954995 -220.923417)
			(xy 357.984206 -220.964822) (xy 358.006738 -221.01021) (xy 358.02206 -221.058511) (xy 358.02981 -221.108588)
			(xy 358.030272 -221.133924) (xy 358.029764 -221.159811) (xy 358.021665 -221.210949) (xy 358.005666 -221.260189)
			(xy 357.98216 -221.306321) (xy 357.951728 -221.348208) (xy 357.915118 -221.384818) (xy 357.873231 -221.41525)
			(xy 357.827099 -221.438756) (xy 357.777859 -221.454755) (xy 357.726721 -221.462854) (xy 357.674947 -221.462854)
			(xy 357.623809 -221.454755) (xy 357.574569 -221.438756) (xy 357.528437 -221.41525) (xy 357.48655 -221.384818)
			(xy 357.44994 -221.348208) (xy 357.419508 -221.306321) (xy 357.396002 -221.260189) (xy 357.380003 -221.210949)
			(xy 357.371904 -221.159811) (xy 357.371396 -221.133924) (xy 357.371932 -221.106216) (xy 357.381123 -221.051569)
			(xy 357.389684 -221.025212) (xy 357.397558 -221.003114) (xy 357.19258 -220.648022) (xy 357.16972 -220.643704)
			(xy 357.144879 -220.638521) (xy 357.097032 -220.621628) (xy 357.05234 -220.5976) (xy 357.011859 -220.567005)
			(xy 356.976548 -220.530566) (xy 356.947239 -220.489145) (xy 356.924627 -220.44372) (xy 356.909246 -220.395365)
			(xy 356.901459 -220.345225) (xy 356.900988 -220.319854) (xy 355.680772 -220.319854) (xy 355.680163 -220.347508)
			(xy 355.670839 -220.402026) (xy 355.66223 -220.428312) (xy 355.65461 -220.45041) (xy 355.859842 -220.805756)
			(xy 355.882702 -220.810074) (xy 355.907508 -220.815252) (xy 355.955247 -220.832242) (xy 355.999825 -220.856337)
			(xy 356.040191 -220.886969) (xy 356.075395 -220.923417) (xy 356.104606 -220.964822) (xy 356.127138 -221.01021)
			(xy 356.14246 -221.058511) (xy 356.15021 -221.108588) (xy 356.150672 -221.133924) (xy 356.150164 -221.159811)
			(xy 356.142065 -221.210949) (xy 356.126066 -221.260189) (xy 356.10256 -221.306321) (xy 356.072128 -221.348208)
			(xy 356.035518 -221.384818) (xy 355.993631 -221.41525) (xy 355.947499 -221.438756) (xy 355.898259 -221.454755)
			(xy 355.847121 -221.462854) (xy 355.795347 -221.462854) (xy 355.744209 -221.454755) (xy 355.694969 -221.438756)
			(xy 355.648837 -221.41525) (xy 355.60695 -221.384818) (xy 355.57034 -221.348208) (xy 355.539908 -221.306321)
			(xy 355.516402 -221.260189) (xy 355.500403 -221.210949) (xy 355.492304 -221.159811) (xy 355.491796 -221.133924)
			(xy 355.492332 -221.106216) (xy 355.501523 -221.051569) (xy 355.510084 -221.025212) (xy 355.517958 -221.003114)
			(xy 355.31298 -220.648022) (xy 355.29012 -220.643704) (xy 355.265279 -220.638521) (xy 355.217432 -220.621628)
			(xy 355.17274 -220.5976) (xy 355.132259 -220.567005) (xy 355.096948 -220.530566) (xy 355.067639 -220.489145)
			(xy 355.045027 -220.44372) (xy 355.029646 -220.395365) (xy 355.021859 -220.345225) (xy 355.021388 -220.319854)
			(xy 353.801172 -220.319854) (xy 353.800563 -220.347508) (xy 353.791239 -220.402026) (xy 353.78263 -220.428312)
			(xy 353.77501 -220.45041) (xy 353.980242 -220.805756) (xy 354.003102 -220.810074) (xy 354.027908 -220.815252)
			(xy 354.075647 -220.832242) (xy 354.120225 -220.856337) (xy 354.160591 -220.886969) (xy 354.195795 -220.923417)
			(xy 354.225006 -220.964822) (xy 354.247538 -221.01021) (xy 354.26286 -221.058511) (xy 354.27061 -221.108588)
			(xy 354.271072 -221.133924) (xy 354.270564 -221.159811) (xy 354.262465 -221.210949) (xy 354.246466 -221.260189)
			(xy 354.22296 -221.306321) (xy 354.192528 -221.348208) (xy 354.155918 -221.384818) (xy 354.114031 -221.41525)
			(xy 354.067899 -221.438756) (xy 354.018659 -221.454755) (xy 353.967521 -221.462854) (xy 353.915747 -221.462854)
			(xy 353.864609 -221.454755) (xy 353.815369 -221.438756) (xy 353.769237 -221.41525) (xy 353.72735 -221.384818)
			(xy 353.69074 -221.348208) (xy 353.660308 -221.306321) (xy 353.636802 -221.260189) (xy 353.620803 -221.210949)
			(xy 353.612704 -221.159811) (xy 353.612196 -221.133924) (xy 353.612732 -221.106216) (xy 353.621923 -221.051569)
			(xy 353.630484 -221.025212) (xy 353.638358 -221.003114) (xy 353.43338 -220.648022) (xy 353.41052 -220.643704)
			(xy 353.385679 -220.638521) (xy 353.337832 -220.621628) (xy 353.29314 -220.5976) (xy 353.252659 -220.567005)
			(xy 353.217348 -220.530566) (xy 353.188039 -220.489145) (xy 353.165427 -220.44372) (xy 353.150046 -220.395365)
			(xy 353.142259 -220.345225) (xy 353.141788 -220.319854) (xy 351.921572 -220.319854) (xy 351.921122 -220.3452)
			(xy 351.913342 -220.395293) (xy 351.897988 -220.443604) (xy 351.875422 -220.488998) (xy 351.846176 -220.530404)
			(xy 351.810939 -220.566847) (xy 351.77054 -220.597469) (xy 351.725931 -220.621548) (xy 351.678163 -220.638518)
			(xy 351.653348 -220.643704) (xy 351.630488 -220.648022) (xy 351.42551 -221.003114) (xy 351.433384 -221.024958)
			(xy 351.441977 -221.051373) (xy 351.451165 -221.106151) (xy 351.451672 -221.133924) (xy 351.451164 -221.159811)
			(xy 351.443065 -221.210949) (xy 351.427066 -221.260189) (xy 351.40356 -221.306321) (xy 351.373128 -221.348208)
			(xy 351.336518 -221.384818) (xy 351.294631 -221.41525) (xy 351.248499 -221.438756) (xy 351.199259 -221.454755)
			(xy 351.148121 -221.462854) (xy 351.096347 -221.462854) (xy 351.045209 -221.454755) (xy 350.995969 -221.438756)
			(xy 350.949837 -221.41525) (xy 350.90795 -221.384818) (xy 350.87134 -221.348208) (xy 350.840908 -221.306321)
			(xy 350.817402 -221.260189) (xy 350.801403 -221.210949) (xy 350.793304 -221.159811) (xy 350.792796 -221.133924)
			(xy 350.511872 -221.133924) (xy 350.511345 -221.161632) (xy 350.502148 -221.216279) (xy 350.493584 -221.242636)
			(xy 350.48571 -221.264734) (xy 350.690688 -221.619572) (xy 350.713548 -221.62389) (xy 350.738367 -221.629064)
			(xy 350.786146 -221.646018) (xy 350.830765 -221.670088) (xy 350.871172 -221.700708) (xy 350.906413 -221.737154)
			(xy 350.935657 -221.778566) (xy 350.958214 -221.823969) (xy 350.973552 -221.872291) (xy 350.98131 -221.922391)
			(xy 350.981772 -221.94774) (xy 352.201988 -221.94774) (xy 352.202465 -221.922395) (xy 352.210245 -221.872306)
			(xy 352.225597 -221.823996) (xy 352.24816 -221.778605) (xy 352.277403 -221.7372) (xy 352.312637 -221.700757)
			(xy 352.353031 -221.670134) (xy 352.397636 -221.646052) (xy 352.445399 -221.629078) (xy 352.470212 -221.62389)
			(xy 352.493072 -221.619572) (xy 352.698304 -221.264226) (xy 352.69043 -221.242128) (xy 352.681965 -221.215883)
			(xy 352.672893 -221.161495) (xy 352.672396 -221.133924) (xy 352.672904 -221.108037) (xy 352.681003 -221.056899)
			(xy 352.697002 -221.007659) (xy 352.720508 -220.961527) (xy 352.75094 -220.91964) (xy 352.78755 -220.88303)
			(xy 352.829437 -220.852598) (xy 352.875569 -220.829092) (xy 352.924809 -220.813093) (xy 352.975947 -220.804994)
			(xy 353.027721 -220.804994) (xy 353.078859 -220.813093) (xy 353.128099 -220.829092) (xy 353.174231 -220.852598)
			(xy 353.216118 -220.88303) (xy 353.252728 -220.91964) (xy 353.28316 -220.961527) (xy 353.306666 -221.007659)
			(xy 353.322665 -221.056899) (xy 353.330764 -221.108037) (xy 353.331272 -221.133924) (xy 353.330842 -221.1593)
			(xy 353.323069 -221.209454) (xy 353.307696 -221.257821) (xy 353.285086 -221.303259) (xy 353.255774 -221.344691)
			(xy 353.220455 -221.381137) (xy 353.179963 -221.411734) (xy 353.135258 -221.435759) (xy 353.087396 -221.452643)
			(xy 353.06254 -221.457774) (xy 353.03968 -221.462092) (xy 352.834956 -221.81693) (xy 352.84283 -221.838774)
			(xy 352.851486 -221.865179) (xy 352.8608 -221.919958) (xy 352.861372 -221.94774) (xy 354.081588 -221.94774)
			(xy 354.082065 -221.922395) (xy 354.089845 -221.872306) (xy 354.105197 -221.823996) (xy 354.12776 -221.778605)
			(xy 354.157003 -221.7372) (xy 354.192237 -221.700757) (xy 354.232631 -221.670134) (xy 354.277236 -221.646052)
			(xy 354.324999 -221.629078) (xy 354.349812 -221.62389) (xy 354.372672 -221.619572) (xy 354.577904 -221.264226)
			(xy 354.57003 -221.242128) (xy 354.561565 -221.215883) (xy 354.552493 -221.161495) (xy 354.551996 -221.133924)
			(xy 354.552504 -221.108037) (xy 354.560603 -221.056899) (xy 354.576602 -221.007659) (xy 354.600108 -220.961527)
			(xy 354.63054 -220.91964) (xy 354.66715 -220.88303) (xy 354.709037 -220.852598) (xy 354.755169 -220.829092)
			(xy 354.804409 -220.813093) (xy 354.855547 -220.804994) (xy 354.907321 -220.804994) (xy 354.958459 -220.813093)
			(xy 355.007699 -220.829092) (xy 355.053831 -220.852598) (xy 355.095718 -220.88303) (xy 355.132328 -220.91964)
			(xy 355.16276 -220.961527) (xy 355.186266 -221.007659) (xy 355.202265 -221.056899) (xy 355.210364 -221.108037)
			(xy 355.210872 -221.133924) (xy 355.210442 -221.1593) (xy 355.202669 -221.209454) (xy 355.187296 -221.257821)
			(xy 355.164686 -221.303259) (xy 355.135374 -221.344691) (xy 355.100055 -221.381137) (xy 355.059563 -221.411734)
			(xy 355.014858 -221.435759) (xy 354.966996 -221.452643) (xy 354.94214 -221.457774) (xy 354.91928 -221.462092)
			(xy 354.714556 -221.81693) (xy 354.72243 -221.838774) (xy 354.731086 -221.865179) (xy 354.7404 -221.919958)
			(xy 354.740972 -221.94774) (xy 355.961188 -221.94774) (xy 355.961665 -221.922395) (xy 355.969445 -221.872306)
			(xy 355.984797 -221.823996) (xy 356.00736 -221.778605) (xy 356.036603 -221.7372) (xy 356.071837 -221.700757)
			(xy 356.112231 -221.670134) (xy 356.156836 -221.646052) (xy 356.204599 -221.629078) (xy 356.229412 -221.62389)
			(xy 356.252272 -221.619572) (xy 356.457504 -221.264226) (xy 356.44963 -221.242128) (xy 356.441165 -221.215883)
			(xy 356.432093 -221.161495) (xy 356.431596 -221.133924) (xy 356.432104 -221.108037) (xy 356.440203 -221.056899)
			(xy 356.456202 -221.007659) (xy 356.479708 -220.961527) (xy 356.51014 -220.91964) (xy 356.54675 -220.88303)
			(xy 356.588637 -220.852598) (xy 356.634769 -220.829092) (xy 356.684009 -220.813093) (xy 356.735147 -220.804994)
			(xy 356.786921 -220.804994) (xy 356.838059 -220.813093) (xy 356.887299 -220.829092) (xy 356.933431 -220.852598)
			(xy 356.975318 -220.88303) (xy 357.011928 -220.91964) (xy 357.04236 -220.961527) (xy 357.065866 -221.007659)
			(xy 357.081865 -221.056899) (xy 357.089964 -221.108037) (xy 357.090472 -221.133924) (xy 357.090042 -221.1593)
			(xy 357.082269 -221.209454) (xy 357.066896 -221.257821) (xy 357.044286 -221.303259) (xy 357.014974 -221.344691)
			(xy 356.979655 -221.381137) (xy 356.939163 -221.411734) (xy 356.894458 -221.435759) (xy 356.846596 -221.452643)
			(xy 356.82174 -221.457774) (xy 356.79888 -221.462092) (xy 356.594156 -221.81693) (xy 356.60203 -221.838774)
			(xy 356.610686 -221.865179) (xy 356.62 -221.919958) (xy 356.620572 -221.94774) (xy 357.841296 -221.94774)
			(xy 357.841727 -221.922404) (xy 357.849489 -221.872329) (xy 357.864819 -221.824032) (xy 357.887358 -221.778648)
			(xy 357.916574 -221.737246) (xy 357.95178 -221.700802) (xy 357.992148 -221.670172) (xy 358.036725 -221.646079)
			(xy 358.084465 -221.629089) (xy 358.109266 -221.62389) (xy 358.132126 -221.619572) (xy 358.337104 -221.26448)
			(xy 358.329484 -221.242382) (xy 358.320964 -221.216211) (xy 358.311771 -221.161949) (xy 358.311196 -221.134432)
			(xy 358.311196 -221.133924) (xy 358.311704 -221.108037) (xy 358.319803 -221.056899) (xy 358.335802 -221.007659)
			(xy 358.359308 -220.961527) (xy 358.38974 -220.91964) (xy 358.42635 -220.88303) (xy 358.468237 -220.852598)
			(xy 358.514369 -220.829092) (xy 358.563609 -220.813093) (xy 358.614747 -220.804994) (xy 358.666521 -220.804994)
			(xy 358.717659 -220.813093) (xy 358.766899 -220.829092) (xy 358.813031 -220.852598) (xy 358.854918 -220.88303)
			(xy 358.891528 -220.91964) (xy 358.92196 -220.961527) (xy 358.945466 -221.007659) (xy 358.961465 -221.056899)
			(xy 358.969564 -221.108037) (xy 358.970072 -221.133924) (xy 358.969679 -221.159291) (xy 358.961926 -221.209429)
			(xy 358.946575 -221.257784) (xy 358.923991 -221.303213) (xy 358.894706 -221.344642) (xy 358.859415 -221.381089)
			(xy 358.818952 -221.411694) (xy 358.774274 -221.435731) (xy 358.726438 -221.452632) (xy 358.701594 -221.457774)
			(xy 358.678734 -221.462092) (xy 358.47401 -221.81693) (xy 358.481884 -221.838774) (xy 358.490481 -221.865188)
			(xy 358.499666 -221.919967) (xy 358.500172 -221.94774) (xy 359.720388 -221.94774) (xy 359.720865 -221.922395)
			(xy 359.728645 -221.872306) (xy 359.743997 -221.823996) (xy 359.76656 -221.778605) (xy 359.795803 -221.7372)
			(xy 359.831037 -221.700757) (xy 359.871431 -221.670134) (xy 359.916036 -221.646052) (xy 359.963799 -221.629078)
			(xy 359.988612 -221.62389) (xy 360.011472 -221.619572) (xy 360.216704 -221.264226) (xy 360.20883 -221.242128)
			(xy 360.200365 -221.215883) (xy 360.191293 -221.161495) (xy 360.190796 -221.133924) (xy 360.191304 -221.108037)
			(xy 360.199403 -221.056899) (xy 360.215402 -221.007659) (xy 360.238908 -220.961527) (xy 360.26934 -220.91964)
			(xy 360.30595 -220.88303) (xy 360.347837 -220.852598) (xy 360.393969 -220.829092) (xy 360.443209 -220.813093)
			(xy 360.494347 -220.804994) (xy 360.546121 -220.804994) (xy 360.597259 -220.813093) (xy 360.646499 -220.829092)
			(xy 360.692631 -220.852598) (xy 360.734518 -220.88303) (xy 360.771128 -220.91964) (xy 360.80156 -220.961527)
			(xy 360.825066 -221.007659) (xy 360.841065 -221.056899) (xy 360.849164 -221.108037) (xy 360.849672 -221.133924)
			(xy 360.849242 -221.1593) (xy 360.841469 -221.209454) (xy 360.826096 -221.257821) (xy 360.803486 -221.303259)
			(xy 360.774174 -221.344691) (xy 360.738855 -221.381137) (xy 360.698363 -221.411734) (xy 360.653658 -221.435759)
			(xy 360.605796 -221.452643) (xy 360.58094 -221.457774) (xy 360.55808 -221.462092) (xy 360.353356 -221.81693)
			(xy 360.36123 -221.838774) (xy 360.369886 -221.865179) (xy 360.3792 -221.919958) (xy 360.379772 -221.94774)
			(xy 361.600496 -221.94774) (xy 361.600927 -221.922404) (xy 361.608689 -221.872329) (xy 361.624019 -221.824032)
			(xy 361.646558 -221.778648) (xy 361.675774 -221.737246) (xy 361.71098 -221.700802) (xy 361.751348 -221.670172)
			(xy 361.795925 -221.646079) (xy 361.843665 -221.629089) (xy 361.868466 -221.62389) (xy 361.891326 -221.619572)
			(xy 362.096304 -221.26448) (xy 362.088684 -221.242382) (xy 362.080164 -221.216211) (xy 362.070971 -221.161949)
			(xy 362.070396 -221.134432) (xy 362.070396 -221.133924) (xy 362.070904 -221.108037) (xy 362.079003 -221.056899)
			(xy 362.095002 -221.007659) (xy 362.118508 -220.961527) (xy 362.14894 -220.91964) (xy 362.18555 -220.88303)
			(xy 362.227437 -220.852598) (xy 362.273569 -220.829092) (xy 362.322809 -220.813093) (xy 362.373947 -220.804994)
			(xy 362.425721 -220.804994) (xy 362.476859 -220.813093) (xy 362.526099 -220.829092) (xy 362.572231 -220.852598)
			(xy 362.614118 -220.88303) (xy 362.650728 -220.91964) (xy 362.68116 -220.961527) (xy 362.704666 -221.007659)
			(xy 362.720665 -221.056899) (xy 362.728764 -221.108037) (xy 362.729272 -221.133924) (xy 362.728879 -221.159291)
			(xy 362.721126 -221.209429) (xy 362.705775 -221.257784) (xy 362.683191 -221.303213) (xy 362.653906 -221.344642)
			(xy 362.618615 -221.381089) (xy 362.578152 -221.411694) (xy 362.533474 -221.435731) (xy 362.485638 -221.452632)
			(xy 362.460794 -221.457774) (xy 362.437934 -221.462092) (xy 362.23321 -221.81693) (xy 362.241084 -221.838774)
			(xy 362.249681 -221.865188) (xy 362.258866 -221.919967) (xy 362.259372 -221.94774) (xy 363.479588 -221.94774)
			(xy 363.480065 -221.922395) (xy 363.487845 -221.872306) (xy 363.503197 -221.823996) (xy 363.52576 -221.778605)
			(xy 363.555003 -221.7372) (xy 363.590237 -221.700757) (xy 363.630631 -221.670134) (xy 363.675236 -221.646052)
			(xy 363.722999 -221.629078) (xy 363.747812 -221.62389) (xy 363.770672 -221.619572) (xy 363.975904 -221.264226)
			(xy 363.96803 -221.242128) (xy 363.959565 -221.215883) (xy 363.950493 -221.161495) (xy 363.949996 -221.133924)
			(xy 363.950504 -221.108037) (xy 363.958603 -221.056899) (xy 363.974602 -221.007659) (xy 363.998108 -220.961527)
			(xy 364.02854 -220.91964) (xy 364.06515 -220.88303) (xy 364.107037 -220.852598) (xy 364.153169 -220.829092)
			(xy 364.202409 -220.813093) (xy 364.253547 -220.804994) (xy 364.305321 -220.804994) (xy 364.356459 -220.813093)
			(xy 364.405699 -220.829092) (xy 364.451831 -220.852598) (xy 364.493718 -220.88303) (xy 364.530328 -220.91964)
			(xy 364.56076 -220.961527) (xy 364.584266 -221.007659) (xy 364.600265 -221.056899) (xy 364.608364 -221.108037)
			(xy 364.608872 -221.133924) (xy 364.608442 -221.1593) (xy 364.600669 -221.209454) (xy 364.585296 -221.257821)
			(xy 364.562686 -221.303259) (xy 364.533374 -221.344691) (xy 364.498055 -221.381137) (xy 364.457563 -221.411734)
			(xy 364.412858 -221.435759) (xy 364.364996 -221.452643) (xy 364.34014 -221.457774) (xy 364.31728 -221.462092)
			(xy 364.112556 -221.81693) (xy 364.12043 -221.838774) (xy 364.129086 -221.865179) (xy 364.1384 -221.919958)
			(xy 364.138972 -221.94774) (xy 365.359188 -221.94774) (xy 365.359665 -221.922395) (xy 365.367445 -221.872306)
			(xy 365.382797 -221.823996) (xy 365.40536 -221.778605) (xy 365.434603 -221.7372) (xy 365.469837 -221.700757)
			(xy 365.510231 -221.670134) (xy 365.554836 -221.646052) (xy 365.602599 -221.629078) (xy 365.627412 -221.62389)
			(xy 365.650272 -221.619572) (xy 365.855504 -221.264226) (xy 365.84763 -221.242128) (xy 365.839165 -221.215883)
			(xy 365.830093 -221.161495) (xy 365.829596 -221.133924) (xy 365.830104 -221.108037) (xy 365.838203 -221.056899)
			(xy 365.854202 -221.007659) (xy 365.877708 -220.961527) (xy 365.90814 -220.91964) (xy 365.94475 -220.88303)
			(xy 365.986637 -220.852598) (xy 366.032769 -220.829092) (xy 366.082009 -220.813093) (xy 366.133147 -220.804994)
			(xy 366.184921 -220.804994) (xy 366.236059 -220.813093) (xy 366.285299 -220.829092) (xy 366.331431 -220.852598)
			(xy 366.373318 -220.88303) (xy 366.409928 -220.91964) (xy 366.44036 -220.961527) (xy 366.463866 -221.007659)
			(xy 366.479865 -221.056899) (xy 366.487964 -221.108037) (xy 366.488472 -221.133924) (xy 366.488042 -221.1593)
			(xy 366.480269 -221.209454) (xy 366.464896 -221.257821) (xy 366.442286 -221.303259) (xy 366.412974 -221.344691)
			(xy 366.377655 -221.381137) (xy 366.337163 -221.411734) (xy 366.292458 -221.435759) (xy 366.244596 -221.452643)
			(xy 366.21974 -221.457774) (xy 366.19688 -221.462092) (xy 365.992156 -221.81693) (xy 366.00003 -221.838774)
			(xy 366.008686 -221.865179) (xy 366.018 -221.919958) (xy 366.018572 -221.94774) (xy 369.118388 -221.94774)
			(xy 369.118865 -221.922395) (xy 369.126645 -221.872306) (xy 369.141997 -221.823996) (xy 369.16456 -221.778605)
			(xy 369.193803 -221.7372) (xy 369.229037 -221.700757) (xy 369.269431 -221.670134) (xy 369.314036 -221.646052)
			(xy 369.361799 -221.629078) (xy 369.386612 -221.62389) (xy 369.409472 -221.619572) (xy 369.614704 -221.264226)
			(xy 369.60683 -221.242128) (xy 369.598365 -221.215883) (xy 369.589293 -221.161495) (xy 369.588796 -221.133924)
			(xy 369.589304 -221.108037) (xy 369.597403 -221.056899) (xy 369.613402 -221.007659) (xy 369.636908 -220.961527)
			(xy 369.66734 -220.91964) (xy 369.70395 -220.88303) (xy 369.745837 -220.852598) (xy 369.791969 -220.829092)
			(xy 369.841209 -220.813093) (xy 369.892347 -220.804994) (xy 369.944121 -220.804994) (xy 369.995259 -220.813093)
			(xy 370.044499 -220.829092) (xy 370.090631 -220.852598) (xy 370.132518 -220.88303) (xy 370.169128 -220.91964)
			(xy 370.19956 -220.961527) (xy 370.223066 -221.007659) (xy 370.239065 -221.056899) (xy 370.247164 -221.108037)
			(xy 370.247672 -221.133924) (xy 370.247242 -221.1593) (xy 370.239469 -221.209454) (xy 370.224096 -221.257821)
			(xy 370.201486 -221.303259) (xy 370.172174 -221.344691) (xy 370.136855 -221.381137) (xy 370.096363 -221.411734)
			(xy 370.051658 -221.435759) (xy 370.003796 -221.452643) (xy 369.97894 -221.457774) (xy 369.95608 -221.462092)
			(xy 369.751356 -221.81693) (xy 369.75923 -221.838774) (xy 369.767886 -221.865179) (xy 369.7772 -221.919958)
			(xy 369.777772 -221.94774) (xy 370.997988 -221.94774) (xy 370.998465 -221.922395) (xy 371.006245 -221.872306)
			(xy 371.021597 -221.823996) (xy 371.04416 -221.778605) (xy 371.073403 -221.7372) (xy 371.108637 -221.700757)
			(xy 371.149031 -221.670134) (xy 371.193636 -221.646052) (xy 371.241399 -221.629078) (xy 371.266212 -221.62389)
			(xy 371.289072 -221.619572) (xy 371.494304 -221.264226) (xy 371.48643 -221.242128) (xy 371.477965 -221.215883)
			(xy 371.468893 -221.161495) (xy 371.468396 -221.133924) (xy 371.468904 -221.108037) (xy 371.477003 -221.056899)
			(xy 371.493002 -221.007659) (xy 371.516508 -220.961527) (xy 371.54694 -220.91964) (xy 371.58355 -220.88303)
			(xy 371.625437 -220.852598) (xy 371.671569 -220.829092) (xy 371.720809 -220.813093) (xy 371.771947 -220.804994)
			(xy 371.823721 -220.804994) (xy 371.874859 -220.813093) (xy 371.924099 -220.829092) (xy 371.970231 -220.852598)
			(xy 372.012118 -220.88303) (xy 372.048728 -220.91964) (xy 372.07916 -220.961527) (xy 372.102666 -221.007659)
			(xy 372.118665 -221.056899) (xy 372.126764 -221.108037) (xy 372.127272 -221.133924) (xy 372.126842 -221.1593)
			(xy 372.119069 -221.209454) (xy 372.103696 -221.257821) (xy 372.081086 -221.303259) (xy 372.051774 -221.344691)
			(xy 372.016455 -221.381137) (xy 371.975963 -221.411734) (xy 371.931258 -221.435759) (xy 371.883396 -221.452643)
			(xy 371.85854 -221.457774) (xy 371.83568 -221.462092) (xy 371.630956 -221.81693) (xy 371.63883 -221.838774)
			(xy 371.647486 -221.865179) (xy 371.6568 -221.919958) (xy 371.657372 -221.94774) (xy 372.877588 -221.94774)
			(xy 372.878065 -221.922395) (xy 372.885845 -221.872306) (xy 372.901197 -221.823996) (xy 372.92376 -221.778605)
			(xy 372.953003 -221.7372) (xy 372.988237 -221.700757) (xy 373.028631 -221.670134) (xy 373.073236 -221.646052)
			(xy 373.120999 -221.629078) (xy 373.145812 -221.62389) (xy 373.168672 -221.619572) (xy 373.373904 -221.264226)
			(xy 373.36603 -221.242128) (xy 373.357565 -221.215883) (xy 373.348493 -221.161495) (xy 373.347996 -221.133924)
			(xy 373.348504 -221.108037) (xy 373.356603 -221.056899) (xy 373.372602 -221.007659) (xy 373.396108 -220.961527)
			(xy 373.42654 -220.91964) (xy 373.46315 -220.88303) (xy 373.505037 -220.852598) (xy 373.551169 -220.829092)
			(xy 373.600409 -220.813093) (xy 373.651547 -220.804994) (xy 373.703321 -220.804994) (xy 373.754459 -220.813093)
			(xy 373.803699 -220.829092) (xy 373.849831 -220.852598) (xy 373.891718 -220.88303) (xy 373.928328 -220.91964)
			(xy 373.95876 -220.961527) (xy 373.982266 -221.007659) (xy 373.998265 -221.056899) (xy 374.006364 -221.108037)
			(xy 374.006872 -221.133924) (xy 374.006442 -221.1593) (xy 373.998669 -221.209454) (xy 373.983296 -221.257821)
			(xy 373.960686 -221.303259) (xy 373.931374 -221.344691) (xy 373.896055 -221.381137) (xy 373.855563 -221.411734)
			(xy 373.810858 -221.435759) (xy 373.762996 -221.452643) (xy 373.73814 -221.457774) (xy 373.71528 -221.462092)
			(xy 373.510556 -221.81693) (xy 373.51843 -221.838774) (xy 373.527086 -221.865179) (xy 373.5364 -221.919958)
			(xy 373.536972 -221.94774) (xy 374.757188 -221.94774) (xy 374.757665 -221.922395) (xy 374.765445 -221.872306)
			(xy 374.780797 -221.823996) (xy 374.80336 -221.778605) (xy 374.832603 -221.7372) (xy 374.867837 -221.700757)
			(xy 374.908231 -221.670134) (xy 374.952836 -221.646052) (xy 375.000599 -221.629078) (xy 375.025412 -221.62389)
			(xy 375.048272 -221.619572) (xy 375.253504 -221.264226) (xy 375.24563 -221.242128) (xy 375.237165 -221.215883)
			(xy 375.228093 -221.161495) (xy 375.227596 -221.133924) (xy 375.228104 -221.108037) (xy 375.236203 -221.056899)
			(xy 375.252202 -221.007659) (xy 375.275708 -220.961527) (xy 375.30614 -220.91964) (xy 375.34275 -220.88303)
			(xy 375.384637 -220.852598) (xy 375.430769 -220.829092) (xy 375.480009 -220.813093) (xy 375.531147 -220.804994)
			(xy 375.582921 -220.804994) (xy 375.634059 -220.813093) (xy 375.683299 -220.829092) (xy 375.729431 -220.852598)
			(xy 375.771318 -220.88303) (xy 375.807928 -220.91964) (xy 375.83836 -220.961527) (xy 375.861866 -221.007659)
			(xy 375.877865 -221.056899) (xy 375.885964 -221.108037) (xy 375.886472 -221.133924) (xy 375.886042 -221.1593)
			(xy 375.878269 -221.209454) (xy 375.862896 -221.257821) (xy 375.840286 -221.303259) (xy 375.810974 -221.344691)
			(xy 375.775655 -221.381137) (xy 375.735163 -221.411734) (xy 375.690458 -221.435759) (xy 375.642596 -221.452643)
			(xy 375.61774 -221.457774) (xy 375.59488 -221.462092) (xy 375.390156 -221.81693) (xy 375.39803 -221.838774)
			(xy 375.406686 -221.865179) (xy 375.416 -221.919958) (xy 375.416572 -221.94774) (xy 376.636788 -221.94774)
			(xy 376.637265 -221.922395) (xy 376.645045 -221.872306) (xy 376.660397 -221.823996) (xy 376.68296 -221.778605)
			(xy 376.712203 -221.7372) (xy 376.747437 -221.700757) (xy 376.787831 -221.670134) (xy 376.832436 -221.646052)
			(xy 376.880199 -221.629078) (xy 376.905012 -221.62389) (xy 376.927872 -221.619572) (xy 377.133104 -221.264226)
			(xy 377.12523 -221.242128) (xy 377.116765 -221.215883) (xy 377.107693 -221.161495) (xy 377.107196 -221.133924)
			(xy 377.107704 -221.108037) (xy 377.115803 -221.056899) (xy 377.131802 -221.007659) (xy 377.155308 -220.961527)
			(xy 377.18574 -220.91964) (xy 377.22235 -220.88303) (xy 377.264237 -220.852598) (xy 377.310369 -220.829092)
			(xy 377.359609 -220.813093) (xy 377.410747 -220.804994) (xy 377.462521 -220.804994) (xy 377.513659 -220.813093)
			(xy 377.562899 -220.829092) (xy 377.609031 -220.852598) (xy 377.650918 -220.88303) (xy 377.687528 -220.91964)
			(xy 377.71796 -220.961527) (xy 377.741466 -221.007659) (xy 377.757465 -221.056899) (xy 377.765564 -221.108037)
			(xy 377.766072 -221.133924) (xy 377.765642 -221.1593) (xy 377.757869 -221.209454) (xy 377.742496 -221.257821)
			(xy 377.719886 -221.303259) (xy 377.690574 -221.344691) (xy 377.655255 -221.381137) (xy 377.614763 -221.411734)
			(xy 377.570058 -221.435759) (xy 377.522196 -221.452643) (xy 377.49734 -221.457774) (xy 377.47448 -221.462092)
			(xy 377.269756 -221.81693) (xy 377.27763 -221.838774) (xy 377.286286 -221.865179) (xy 377.2956 -221.919958)
			(xy 377.296172 -221.94774) (xy 378.516388 -221.94774) (xy 378.516865 -221.922395) (xy 378.524645 -221.872306)
			(xy 378.539997 -221.823996) (xy 378.56256 -221.778605) (xy 378.591803 -221.7372) (xy 378.627037 -221.700757)
			(xy 378.667431 -221.670134) (xy 378.712036 -221.646052) (xy 378.759799 -221.629078) (xy 378.784612 -221.62389)
			(xy 378.807472 -221.619572) (xy 379.012704 -221.264226) (xy 379.00483 -221.242128) (xy 378.996365 -221.215883)
			(xy 378.987293 -221.161495) (xy 378.986796 -221.133924) (xy 378.987304 -221.108037) (xy 378.995403 -221.056899)
			(xy 379.011402 -221.007659) (xy 379.034908 -220.961527) (xy 379.06534 -220.91964) (xy 379.10195 -220.88303)
			(xy 379.143837 -220.852598) (xy 379.189969 -220.829092) (xy 379.239209 -220.813093) (xy 379.290347 -220.804994)
			(xy 379.342121 -220.804994) (xy 379.393259 -220.813093) (xy 379.442499 -220.829092) (xy 379.488631 -220.852598)
			(xy 379.530518 -220.88303) (xy 379.567128 -220.91964) (xy 379.59756 -220.961527) (xy 379.621066 -221.007659)
			(xy 379.637065 -221.056899) (xy 379.645164 -221.108037) (xy 379.645672 -221.133924) (xy 379.645242 -221.1593)
			(xy 379.637469 -221.209454) (xy 379.622096 -221.257821) (xy 379.599486 -221.303259) (xy 379.570174 -221.344691)
			(xy 379.534855 -221.381137) (xy 379.494363 -221.411734) (xy 379.449658 -221.435759) (xy 379.401796 -221.452643)
			(xy 379.37694 -221.457774) (xy 379.35408 -221.462092) (xy 379.149356 -221.81693) (xy 379.15723 -221.838774)
			(xy 379.165886 -221.865179) (xy 379.1752 -221.919958) (xy 379.175772 -221.94774) (xy 380.395988 -221.94774)
			(xy 380.396465 -221.922395) (xy 380.404245 -221.872306) (xy 380.419597 -221.823996) (xy 380.44216 -221.778605)
			(xy 380.471403 -221.7372) (xy 380.506637 -221.700757) (xy 380.547031 -221.670134) (xy 380.591636 -221.646052)
			(xy 380.639399 -221.629078) (xy 380.664212 -221.62389) (xy 380.687072 -221.619572) (xy 380.89205 -221.263972)
			(xy 380.88443 -221.242128) (xy 380.875981 -221.215945) (xy 380.866909 -221.161685) (xy 380.866396 -221.134178)
			(xy 380.866396 -221.133924) (xy 380.866904 -221.108037) (xy 380.875003 -221.056899) (xy 380.891002 -221.007659)
			(xy 380.914508 -220.961527) (xy 380.94494 -220.91964) (xy 380.98155 -220.88303) (xy 381.023437 -220.852598)
			(xy 381.069569 -220.829092) (xy 381.118809 -220.813093) (xy 381.169947 -220.804994) (xy 381.221721 -220.804994)
			(xy 381.272859 -220.813093) (xy 381.322099 -220.829092) (xy 381.368231 -220.852598) (xy 381.410118 -220.88303)
			(xy 381.446728 -220.91964) (xy 381.47716 -220.961527) (xy 381.500666 -221.007659) (xy 381.516665 -221.056899)
			(xy 381.524764 -221.108037) (xy 381.525272 -221.133924) (xy 381.524879 -221.159291) (xy 381.517126 -221.209429)
			(xy 381.501775 -221.257784) (xy 381.479191 -221.303213) (xy 381.449906 -221.344642) (xy 381.414615 -221.381089)
			(xy 381.374152 -221.411694) (xy 381.329474 -221.435731) (xy 381.281638 -221.452632) (xy 381.256794 -221.457774)
			(xy 381.233934 -221.462092) (xy 381.02921 -221.81693) (xy 381.03683 -221.838774) (xy 381.045444 -221.865059)
			(xy 381.054766 -221.919578) (xy 381.055372 -221.947232) (xy 381.055372 -221.94774) (xy 382.275588 -221.94774)
			(xy 382.276065 -221.922395) (xy 382.283845 -221.872306) (xy 382.299197 -221.823996) (xy 382.32176 -221.778605)
			(xy 382.351003 -221.7372) (xy 382.386237 -221.700757) (xy 382.426631 -221.670134) (xy 382.471236 -221.646052)
			(xy 382.518999 -221.629078) (xy 382.543812 -221.62389) (xy 382.566672 -221.619572) (xy 382.77165 -221.263972)
			(xy 382.76403 -221.242128) (xy 382.755581 -221.215945) (xy 382.746509 -221.161685) (xy 382.745996 -221.134178)
			(xy 382.745996 -221.133924) (xy 382.746504 -221.108037) (xy 382.754603 -221.056899) (xy 382.770602 -221.007659)
			(xy 382.794108 -220.961527) (xy 382.82454 -220.91964) (xy 382.86115 -220.88303) (xy 382.903037 -220.852598)
			(xy 382.949169 -220.829092) (xy 382.998409 -220.813093) (xy 383.049547 -220.804994) (xy 383.101321 -220.804994)
			(xy 383.152459 -220.813093) (xy 383.201699 -220.829092) (xy 383.247831 -220.852598) (xy 383.289718 -220.88303)
			(xy 383.326328 -220.91964) (xy 383.35676 -220.961527) (xy 383.380266 -221.007659) (xy 383.396265 -221.056899)
			(xy 383.404364 -221.108037) (xy 383.404872 -221.133924) (xy 383.404479 -221.159291) (xy 383.396726 -221.209429)
			(xy 383.381375 -221.257784) (xy 383.358791 -221.303213) (xy 383.329506 -221.344642) (xy 383.294215 -221.381089)
			(xy 383.253752 -221.411694) (xy 383.209074 -221.435731) (xy 383.161238 -221.452632) (xy 383.136394 -221.457774)
			(xy 383.113534 -221.462092) (xy 382.90881 -221.81693) (xy 382.91643 -221.838774) (xy 382.925044 -221.865059)
			(xy 382.934366 -221.919578) (xy 382.934972 -221.947232) (xy 382.934972 -221.94774) (xy 382.934464 -221.973647)
			(xy 382.926358 -222.024824) (xy 382.910346 -222.074103) (xy 382.886823 -222.12027) (xy 382.856367 -222.162189)
			(xy 382.819729 -222.198827) (xy 382.77781 -222.229283) (xy 382.731643 -222.252806) (xy 382.682364 -222.268818)
			(xy 382.631187 -222.276924) (xy 382.579373 -222.276924) (xy 382.528196 -222.268818) (xy 382.478917 -222.252806)
			(xy 382.43275 -222.229283) (xy 382.390831 -222.198827) (xy 382.354193 -222.162189) (xy 382.323737 -222.12027)
			(xy 382.300214 -222.074103) (xy 382.284202 -222.024824) (xy 382.276096 -221.973647) (xy 382.275588 -221.94774)
			(xy 381.055372 -221.94774) (xy 381.054864 -221.973647) (xy 381.046758 -222.024824) (xy 381.030746 -222.074103)
			(xy 381.007223 -222.12027) (xy 380.976767 -222.162189) (xy 380.940129 -222.198827) (xy 380.89821 -222.229283)
			(xy 380.852043 -222.252806) (xy 380.802764 -222.268818) (xy 380.751587 -222.276924) (xy 380.699773 -222.276924)
			(xy 380.648596 -222.268818) (xy 380.599317 -222.252806) (xy 380.55315 -222.229283) (xy 380.511231 -222.198827)
			(xy 380.474593 -222.162189) (xy 380.444137 -222.12027) (xy 380.420614 -222.074103) (xy 380.404602 -222.024824)
			(xy 380.396496 -221.973647) (xy 380.395988 -221.94774) (xy 379.175772 -221.94774) (xy 379.175264 -221.973647)
			(xy 379.167158 -222.024824) (xy 379.151146 -222.074103) (xy 379.127623 -222.12027) (xy 379.097167 -222.162189)
			(xy 379.060529 -222.198827) (xy 379.01861 -222.229283) (xy 378.972443 -222.252806) (xy 378.923164 -222.268818)
			(xy 378.871987 -222.276924) (xy 378.820173 -222.276924) (xy 378.768996 -222.268818) (xy 378.719717 -222.252806)
			(xy 378.67355 -222.229283) (xy 378.631631 -222.198827) (xy 378.594993 -222.162189) (xy 378.564537 -222.12027)
			(xy 378.541014 -222.074103) (xy 378.525002 -222.024824) (xy 378.516896 -221.973647) (xy 378.516388 -221.94774)
			(xy 377.296172 -221.94774) (xy 377.295664 -221.973647) (xy 377.287558 -222.024824) (xy 377.271546 -222.074103)
			(xy 377.248023 -222.12027) (xy 377.217567 -222.162189) (xy 377.180929 -222.198827) (xy 377.13901 -222.229283)
			(xy 377.092843 -222.252806) (xy 377.043564 -222.268818) (xy 376.992387 -222.276924) (xy 376.940573 -222.276924)
			(xy 376.889396 -222.268818) (xy 376.840117 -222.252806) (xy 376.79395 -222.229283) (xy 376.752031 -222.198827)
			(xy 376.715393 -222.162189) (xy 376.684937 -222.12027) (xy 376.661414 -222.074103) (xy 376.645402 -222.024824)
			(xy 376.637296 -221.973647) (xy 376.636788 -221.94774) (xy 375.416572 -221.94774) (xy 375.416064 -221.973647)
			(xy 375.407958 -222.024824) (xy 375.391946 -222.074103) (xy 375.368423 -222.12027) (xy 375.337967 -222.162189)
			(xy 375.301329 -222.198827) (xy 375.25941 -222.229283) (xy 375.213243 -222.252806) (xy 375.163964 -222.268818)
			(xy 375.112787 -222.276924) (xy 375.060973 -222.276924) (xy 375.009796 -222.268818) (xy 374.960517 -222.252806)
			(xy 374.91435 -222.229283) (xy 374.872431 -222.198827) (xy 374.835793 -222.162189) (xy 374.805337 -222.12027)
			(xy 374.781814 -222.074103) (xy 374.765802 -222.024824) (xy 374.757696 -221.973647) (xy 374.757188 -221.94774)
			(xy 373.536972 -221.94774) (xy 373.536464 -221.973647) (xy 373.528358 -222.024824) (xy 373.512346 -222.074103)
			(xy 373.488823 -222.12027) (xy 373.458367 -222.162189) (xy 373.421729 -222.198827) (xy 373.37981 -222.229283)
			(xy 373.333643 -222.252806) (xy 373.284364 -222.268818) (xy 373.233187 -222.276924) (xy 373.181373 -222.276924)
			(xy 373.130196 -222.268818) (xy 373.080917 -222.252806) (xy 373.03475 -222.229283) (xy 372.992831 -222.198827)
			(xy 372.956193 -222.162189) (xy 372.925737 -222.12027) (xy 372.902214 -222.074103) (xy 372.886202 -222.024824)
			(xy 372.878096 -221.973647) (xy 372.877588 -221.94774) (xy 371.657372 -221.94774) (xy 371.656864 -221.973647)
			(xy 371.648758 -222.024824) (xy 371.632746 -222.074103) (xy 371.609223 -222.12027) (xy 371.578767 -222.162189)
			(xy 371.542129 -222.198827) (xy 371.50021 -222.229283) (xy 371.454043 -222.252806) (xy 371.404764 -222.268818)
			(xy 371.353587 -222.276924) (xy 371.301773 -222.276924) (xy 371.250596 -222.268818) (xy 371.201317 -222.252806)
			(xy 371.15515 -222.229283) (xy 371.113231 -222.198827) (xy 371.076593 -222.162189) (xy 371.046137 -222.12027)
			(xy 371.022614 -222.074103) (xy 371.006602 -222.024824) (xy 370.998496 -221.973647) (xy 370.997988 -221.94774)
			(xy 369.777772 -221.94774) (xy 369.777264 -221.973647) (xy 369.769158 -222.024824) (xy 369.753146 -222.074103)
			(xy 369.729623 -222.12027) (xy 369.699167 -222.162189) (xy 369.662529 -222.198827) (xy 369.62061 -222.229283)
			(xy 369.574443 -222.252806) (xy 369.525164 -222.268818) (xy 369.473987 -222.276924) (xy 369.422173 -222.276924)
			(xy 369.370996 -222.268818) (xy 369.321717 -222.252806) (xy 369.27555 -222.229283) (xy 369.233631 -222.198827)
			(xy 369.196993 -222.162189) (xy 369.166537 -222.12027) (xy 369.143014 -222.074103) (xy 369.127002 -222.024824)
			(xy 369.118896 -221.973647) (xy 369.118388 -221.94774) (xy 366.018572 -221.94774) (xy 366.018064 -221.973647)
			(xy 366.009958 -222.024824) (xy 365.993946 -222.074103) (xy 365.970423 -222.12027) (xy 365.939967 -222.162189)
			(xy 365.903329 -222.198827) (xy 365.86141 -222.229283) (xy 365.815243 -222.252806) (xy 365.765964 -222.268818)
			(xy 365.714787 -222.276924) (xy 365.662973 -222.276924) (xy 365.611796 -222.268818) (xy 365.562517 -222.252806)
			(xy 365.51635 -222.229283) (xy 365.474431 -222.198827) (xy 365.437793 -222.162189) (xy 365.407337 -222.12027)
			(xy 365.383814 -222.074103) (xy 365.367802 -222.024824) (xy 365.359696 -221.973647) (xy 365.359188 -221.94774)
			(xy 364.138972 -221.94774) (xy 364.138464 -221.973647) (xy 364.130358 -222.024824) (xy 364.114346 -222.074103)
			(xy 364.090823 -222.12027) (xy 364.060367 -222.162189) (xy 364.023729 -222.198827) (xy 363.98181 -222.229283)
			(xy 363.935643 -222.252806) (xy 363.886364 -222.268818) (xy 363.835187 -222.276924) (xy 363.783373 -222.276924)
			(xy 363.732196 -222.268818) (xy 363.682917 -222.252806) (xy 363.63675 -222.229283) (xy 363.594831 -222.198827)
			(xy 363.558193 -222.162189) (xy 363.527737 -222.12027) (xy 363.504214 -222.074103) (xy 363.488202 -222.024824)
			(xy 363.480096 -221.973647) (xy 363.479588 -221.94774) (xy 362.259372 -221.94774) (xy 362.258864 -221.973627)
			(xy 362.250765 -222.024765) (xy 362.234766 -222.074005) (xy 362.21126 -222.120137) (xy 362.180828 -222.162024)
			(xy 362.144218 -222.198634) (xy 362.102331 -222.229066) (xy 362.056199 -222.252572) (xy 362.006959 -222.268571)
			(xy 361.955821 -222.27667) (xy 361.904047 -222.27667) (xy 361.852909 -222.268571) (xy 361.803669 -222.252572)
			(xy 361.757537 -222.229066) (xy 361.71565 -222.198634) (xy 361.67904 -222.162024) (xy 361.648608 -222.120137)
			(xy 361.625102 -222.074005) (xy 361.609103 -222.024765) (xy 361.601004 -221.973627) (xy 361.600496 -221.94774)
			(xy 360.379772 -221.94774) (xy 360.379264 -221.973647) (xy 360.371158 -222.024824) (xy 360.355146 -222.074103)
			(xy 360.331623 -222.12027) (xy 360.301167 -222.162189) (xy 360.264529 -222.198827) (xy 360.22261 -222.229283)
			(xy 360.176443 -222.252806) (xy 360.127164 -222.268818) (xy 360.075987 -222.276924) (xy 360.024173 -222.276924)
			(xy 359.972996 -222.268818) (xy 359.923717 -222.252806) (xy 359.87755 -222.229283) (xy 359.835631 -222.198827)
			(xy 359.798993 -222.162189) (xy 359.768537 -222.12027) (xy 359.745014 -222.074103) (xy 359.729002 -222.024824)
			(xy 359.720896 -221.973647) (xy 359.720388 -221.94774) (xy 358.500172 -221.94774) (xy 358.499664 -221.973627)
			(xy 358.491565 -222.024765) (xy 358.475566 -222.074005) (xy 358.45206 -222.120137) (xy 358.421628 -222.162024)
			(xy 358.385018 -222.198634) (xy 358.343131 -222.229066) (xy 358.296999 -222.252572) (xy 358.247759 -222.268571)
			(xy 358.196621 -222.27667) (xy 358.144847 -222.27667) (xy 358.093709 -222.268571) (xy 358.044469 -222.252572)
			(xy 357.998337 -222.229066) (xy 357.95645 -222.198634) (xy 357.91984 -222.162024) (xy 357.889408 -222.120137)
			(xy 357.865902 -222.074005) (xy 357.849903 -222.024765) (xy 357.841804 -221.973627) (xy 357.841296 -221.94774)
			(xy 356.620572 -221.94774) (xy 356.620064 -221.973647) (xy 356.611958 -222.024824) (xy 356.595946 -222.074103)
			(xy 356.572423 -222.12027) (xy 356.541967 -222.162189) (xy 356.505329 -222.198827) (xy 356.46341 -222.229283)
			(xy 356.417243 -222.252806) (xy 356.367964 -222.268818) (xy 356.316787 -222.276924) (xy 356.264973 -222.276924)
			(xy 356.213796 -222.268818) (xy 356.164517 -222.252806) (xy 356.11835 -222.229283) (xy 356.076431 -222.198827)
			(xy 356.039793 -222.162189) (xy 356.009337 -222.12027) (xy 355.985814 -222.074103) (xy 355.969802 -222.024824)
			(xy 355.961696 -221.973647) (xy 355.961188 -221.94774) (xy 354.740972 -221.94774) (xy 354.740464 -221.973647)
			(xy 354.732358 -222.024824) (xy 354.716346 -222.074103) (xy 354.692823 -222.12027) (xy 354.662367 -222.162189)
			(xy 354.625729 -222.198827) (xy 354.58381 -222.229283) (xy 354.537643 -222.252806) (xy 354.488364 -222.268818)
			(xy 354.437187 -222.276924) (xy 354.385373 -222.276924) (xy 354.334196 -222.268818) (xy 354.284917 -222.252806)
			(xy 354.23875 -222.229283) (xy 354.196831 -222.198827) (xy 354.160193 -222.162189) (xy 354.129737 -222.12027)
			(xy 354.106214 -222.074103) (xy 354.090202 -222.024824) (xy 354.082096 -221.973647) (xy 354.081588 -221.94774)
			(xy 352.861372 -221.94774) (xy 352.860864 -221.973647) (xy 352.852758 -222.024824) (xy 352.836746 -222.074103)
			(xy 352.813223 -222.12027) (xy 352.782767 -222.162189) (xy 352.746129 -222.198827) (xy 352.70421 -222.229283)
			(xy 352.658043 -222.252806) (xy 352.608764 -222.268818) (xy 352.557587 -222.276924) (xy 352.505773 -222.276924)
			(xy 352.454596 -222.268818) (xy 352.405317 -222.252806) (xy 352.35915 -222.229283) (xy 352.317231 -222.198827)
			(xy 352.280593 -222.162189) (xy 352.250137 -222.12027) (xy 352.226614 -222.074103) (xy 352.210602 -222.024824)
			(xy 352.202496 -221.973647) (xy 352.201988 -221.94774) (xy 350.981772 -221.94774) (xy 350.981264 -221.973647)
			(xy 350.973158 -222.024824) (xy 350.957146 -222.074103) (xy 350.933623 -222.12027) (xy 350.903167 -222.162189)
			(xy 350.866529 -222.198827) (xy 350.82461 -222.229283) (xy 350.778443 -222.252806) (xy 350.729164 -222.268818)
			(xy 350.677987 -222.276924) (xy 350.626173 -222.276924) (xy 350.574996 -222.268818) (xy 350.525717 -222.252806)
			(xy 350.47955 -222.229283) (xy 350.437631 -222.198827) (xy 350.400993 -222.162189) (xy 350.370537 -222.12027)
			(xy 350.347014 -222.074103) (xy 350.331002 -222.024824) (xy 350.322896 -221.973647) (xy 350.322388 -221.94774)
			(xy 350.322992 -221.920023) (xy 350.332309 -221.865377) (xy 350.34093 -221.839028) (xy 350.348804 -221.81693)
			(xy 350.143826 -221.462092) (xy 350.120966 -221.457774) (xy 350.096166 -221.452574) (xy 350.04843 -221.435583)
			(xy 350.003855 -221.411489) (xy 349.963491 -221.380859) (xy 349.928289 -221.344414) (xy 349.899076 -221.303012)
			(xy 349.876542 -221.257629) (xy 349.861217 -221.209332) (xy 349.853461 -221.159259) (xy 349.852996 -221.133924)
			(xy 349.572072 -221.133924) (xy 349.571564 -221.159811) (xy 349.563465 -221.210949) (xy 349.547466 -221.260189)
			(xy 349.52396 -221.306321) (xy 349.493528 -221.348208) (xy 349.456918 -221.384818) (xy 349.415031 -221.41525)
			(xy 349.368899 -221.438756) (xy 349.319659 -221.454755) (xy 349.268521 -221.462854) (xy 349.216747 -221.462854)
			(xy 349.165609 -221.454755) (xy 349.116369 -221.438756) (xy 349.070237 -221.41525) (xy 349.02835 -221.384818)
			(xy 348.99174 -221.348208) (xy 348.961308 -221.306321) (xy 348.937802 -221.260189) (xy 348.921803 -221.210949)
			(xy 348.913704 -221.159811) (xy 348.913196 -221.133924) (xy 348.632272 -221.133924) (xy 348.631745 -221.161632)
			(xy 348.622548 -221.216279) (xy 348.613984 -221.242636) (xy 348.60611 -221.264734) (xy 348.811088 -221.619572)
			(xy 348.833948 -221.62389) (xy 348.858767 -221.629064) (xy 348.906546 -221.646018) (xy 348.951165 -221.670088)
			(xy 348.991572 -221.700708) (xy 349.026813 -221.737154) (xy 349.056057 -221.778566) (xy 349.078614 -221.823969)
			(xy 349.093952 -221.872291) (xy 349.10171 -221.922391) (xy 349.102172 -221.94774) (xy 349.101664 -221.973647)
			(xy 349.093558 -222.024824) (xy 349.077546 -222.074103) (xy 349.054023 -222.12027) (xy 349.023567 -222.162189)
			(xy 348.986929 -222.198827) (xy 348.94501 -222.229283) (xy 348.898843 -222.252806) (xy 348.849564 -222.268818)
			(xy 348.798387 -222.276924) (xy 348.746573 -222.276924) (xy 348.695396 -222.268818) (xy 348.646117 -222.252806)
			(xy 348.59995 -222.229283) (xy 348.558031 -222.198827) (xy 348.521393 -222.162189) (xy 348.490937 -222.12027)
			(xy 348.467414 -222.074103) (xy 348.451402 -222.024824) (xy 348.443296 -221.973647) (xy 348.442788 -221.94774)
			(xy 348.443392 -221.920023) (xy 348.452709 -221.865377) (xy 348.46133 -221.839028) (xy 348.469204 -221.81693)
			(xy 348.264226 -221.462092) (xy 348.241366 -221.457774) (xy 348.216566 -221.452574) (xy 348.16883 -221.435583)
			(xy 348.124255 -221.411489) (xy 348.083891 -221.380859) (xy 348.048689 -221.344414) (xy 348.019476 -221.303012)
			(xy 347.996942 -221.257629) (xy 347.981617 -221.209332) (xy 347.973861 -221.159259) (xy 347.973396 -221.133924)
			(xy 347.692472 -221.133924) (xy 347.691964 -221.159811) (xy 347.683865 -221.210949) (xy 347.667866 -221.260189)
			(xy 347.64436 -221.306321) (xy 347.613928 -221.348208) (xy 347.577318 -221.384818) (xy 347.535431 -221.41525)
			(xy 347.489299 -221.438756) (xy 347.440059 -221.454755) (xy 347.388921 -221.462854) (xy 347.337147 -221.462854)
			(xy 347.286009 -221.454755) (xy 347.236769 -221.438756) (xy 347.190637 -221.41525) (xy 347.14875 -221.384818)
			(xy 347.11214 -221.348208) (xy 347.081708 -221.306321) (xy 347.058202 -221.260189) (xy 347.042203 -221.210949)
			(xy 347.034104 -221.159811) (xy 347.033596 -221.133924) (xy 346.752672 -221.133924) (xy 346.752145 -221.161632)
			(xy 346.742948 -221.216279) (xy 346.734384 -221.242636) (xy 346.72651 -221.264734) (xy 346.931488 -221.619572)
			(xy 346.954348 -221.62389) (xy 346.979167 -221.629064) (xy 347.026946 -221.646018) (xy 347.071565 -221.670088)
			(xy 347.111972 -221.700708) (xy 347.147213 -221.737154) (xy 347.176457 -221.778566) (xy 347.199014 -221.823969)
			(xy 347.214352 -221.872291) (xy 347.22211 -221.922391) (xy 347.222572 -221.94774) (xy 347.222064 -221.973647)
			(xy 347.213958 -222.024824) (xy 347.197946 -222.074103) (xy 347.174423 -222.12027) (xy 347.143967 -222.162189)
			(xy 347.107329 -222.198827) (xy 347.06541 -222.229283) (xy 347.019243 -222.252806) (xy 346.969964 -222.268818)
			(xy 346.918787 -222.276924) (xy 346.866973 -222.276924) (xy 346.815796 -222.268818) (xy 346.766517 -222.252806)
			(xy 346.72035 -222.229283) (xy 346.678431 -222.198827) (xy 346.641793 -222.162189) (xy 346.611337 -222.12027)
			(xy 346.587814 -222.074103) (xy 346.571802 -222.024824) (xy 346.563696 -221.973647) (xy 346.563188 -221.94774)
			(xy 346.563792 -221.920023) (xy 346.573109 -221.865377) (xy 346.58173 -221.839028) (xy 346.589604 -221.81693)
			(xy 346.384626 -221.462092) (xy 346.361766 -221.457774) (xy 346.336966 -221.452574) (xy 346.28923 -221.435583)
			(xy 346.244655 -221.411489) (xy 346.204291 -221.380859) (xy 346.169089 -221.344414) (xy 346.139876 -221.303012)
			(xy 346.117342 -221.257629) (xy 346.102017 -221.209332) (xy 346.094261 -221.159259) (xy 346.093796 -221.133924)
			(xy 345.812872 -221.133924) (xy 345.812364 -221.159811) (xy 345.804265 -221.210949) (xy 345.788266 -221.260189)
			(xy 345.76476 -221.306321) (xy 345.734328 -221.348208) (xy 345.697718 -221.384818) (xy 345.655831 -221.41525)
			(xy 345.609699 -221.438756) (xy 345.560459 -221.454755) (xy 345.509321 -221.462854) (xy 345.457547 -221.462854)
			(xy 345.406409 -221.454755) (xy 345.357169 -221.438756) (xy 345.311037 -221.41525) (xy 345.26915 -221.384818)
			(xy 345.23254 -221.348208) (xy 345.202108 -221.306321) (xy 345.178602 -221.260189) (xy 345.162603 -221.210949)
			(xy 345.154504 -221.159811) (xy 345.153996 -221.133924) (xy 344.873072 -221.133924) (xy 344.872545 -221.161632)
			(xy 344.863348 -221.216279) (xy 344.854784 -221.242636) (xy 344.84691 -221.264734) (xy 345.051888 -221.619572)
			(xy 345.074748 -221.62389) (xy 345.099567 -221.629064) (xy 345.147346 -221.646018) (xy 345.191965 -221.670088)
			(xy 345.232372 -221.700708) (xy 345.267613 -221.737154) (xy 345.296857 -221.778566) (xy 345.319414 -221.823969)
			(xy 345.334752 -221.872291) (xy 345.34251 -221.922391) (xy 345.342972 -221.94774) (xy 345.342464 -221.973647)
			(xy 345.334358 -222.024824) (xy 345.318346 -222.074103) (xy 345.294823 -222.12027) (xy 345.264367 -222.162189)
			(xy 345.227729 -222.198827) (xy 345.18581 -222.229283) (xy 345.139643 -222.252806) (xy 345.090364 -222.268818)
			(xy 345.039187 -222.276924) (xy 344.987373 -222.276924) (xy 344.936196 -222.268818) (xy 344.886917 -222.252806)
			(xy 344.84075 -222.229283) (xy 344.798831 -222.198827) (xy 344.762193 -222.162189) (xy 344.731737 -222.12027)
			(xy 344.708214 -222.074103) (xy 344.692202 -222.024824) (xy 344.684096 -221.973647) (xy 344.683588 -221.94774)
			(xy 344.684192 -221.920023) (xy 344.693509 -221.865377) (xy 344.70213 -221.839028) (xy 344.710004 -221.81693)
			(xy 344.505026 -221.462092) (xy 344.482166 -221.457774) (xy 344.457366 -221.452574) (xy 344.40963 -221.435583)
			(xy 344.365055 -221.411489) (xy 344.324691 -221.380859) (xy 344.289489 -221.344414) (xy 344.260276 -221.303012)
			(xy 344.237742 -221.257629) (xy 344.222417 -221.209332) (xy 344.214661 -221.159259) (xy 344.214196 -221.133924)
			(xy 343.933272 -221.133924) (xy 343.932764 -221.159811) (xy 343.924665 -221.210949) (xy 343.908666 -221.260189)
			(xy 343.88516 -221.306321) (xy 343.854728 -221.348208) (xy 343.818118 -221.384818) (xy 343.776231 -221.41525)
			(xy 343.730099 -221.438756) (xy 343.680859 -221.454755) (xy 343.629721 -221.462854) (xy 343.577947 -221.462854)
			(xy 343.526809 -221.454755) (xy 343.477569 -221.438756) (xy 343.431437 -221.41525) (xy 343.38955 -221.384818)
			(xy 343.35294 -221.348208) (xy 343.322508 -221.306321) (xy 343.299002 -221.260189) (xy 343.283003 -221.210949)
			(xy 343.274904 -221.159811) (xy 343.274396 -221.133924) (xy 342.993472 -221.133924) (xy 342.992945 -221.161632)
			(xy 342.983748 -221.216279) (xy 342.975184 -221.242636) (xy 342.96731 -221.264734) (xy 343.172288 -221.619572)
			(xy 343.195148 -221.62389) (xy 343.219967 -221.629064) (xy 343.267746 -221.646018) (xy 343.312365 -221.670088)
			(xy 343.352772 -221.700708) (xy 343.388013 -221.737154) (xy 343.417257 -221.778566) (xy 343.439814 -221.823969)
			(xy 343.455152 -221.872291) (xy 343.46291 -221.922391) (xy 343.463372 -221.94774) (xy 343.462864 -221.973647)
			(xy 343.454758 -222.024824) (xy 343.438746 -222.074103) (xy 343.415223 -222.12027) (xy 343.384767 -222.162189)
			(xy 343.348129 -222.198827) (xy 343.30621 -222.229283) (xy 343.260043 -222.252806) (xy 343.210764 -222.268818)
			(xy 343.159587 -222.276924) (xy 343.107773 -222.276924) (xy 343.056596 -222.268818) (xy 343.007317 -222.252806)
			(xy 342.96115 -222.229283) (xy 342.919231 -222.198827) (xy 342.882593 -222.162189) (xy 342.852137 -222.12027)
			(xy 342.828614 -222.074103) (xy 342.812602 -222.024824) (xy 342.804496 -221.973647) (xy 342.803988 -221.94774)
			(xy 342.804592 -221.920023) (xy 342.813909 -221.865377) (xy 342.82253 -221.839028) (xy 342.830404 -221.81693)
			(xy 342.625426 -221.462092) (xy 342.602566 -221.457774) (xy 342.577766 -221.452574) (xy 342.53003 -221.435583)
			(xy 342.485455 -221.411489) (xy 342.445091 -221.380859) (xy 342.409889 -221.344414) (xy 342.380676 -221.303012)
			(xy 342.358142 -221.257629) (xy 342.342817 -221.209332) (xy 342.335061 -221.159259) (xy 342.334596 -221.133924)
			(xy 342.053672 -221.133924) (xy 342.053164 -221.159811) (xy 342.045065 -221.210949) (xy 342.029066 -221.260189)
			(xy 342.00556 -221.306321) (xy 341.975128 -221.348208) (xy 341.938518 -221.384818) (xy 341.896631 -221.41525)
			(xy 341.850499 -221.438756) (xy 341.801259 -221.454755) (xy 341.750121 -221.462854) (xy 341.698347 -221.462854)
			(xy 341.647209 -221.454755) (xy 341.597969 -221.438756) (xy 341.551837 -221.41525) (xy 341.50995 -221.384818)
			(xy 341.47334 -221.348208) (xy 341.442908 -221.306321) (xy 341.419402 -221.260189) (xy 341.403403 -221.210949)
			(xy 341.395304 -221.159811) (xy 341.394796 -221.133924) (xy 341.113872 -221.133924) (xy 341.113345 -221.161632)
			(xy 341.104148 -221.216279) (xy 341.095584 -221.242636) (xy 341.08771 -221.264734) (xy 341.292688 -221.619572)
			(xy 341.315548 -221.62389) (xy 341.340367 -221.629064) (xy 341.388146 -221.646018) (xy 341.432765 -221.670088)
			(xy 341.473172 -221.700708) (xy 341.508413 -221.737154) (xy 341.537657 -221.778566) (xy 341.560214 -221.823969)
			(xy 341.575552 -221.872291) (xy 341.58331 -221.922391) (xy 341.583772 -221.94774) (xy 341.583264 -221.973647)
			(xy 341.575158 -222.024824) (xy 341.559146 -222.074103) (xy 341.535623 -222.12027) (xy 341.505167 -222.162189)
			(xy 341.468529 -222.198827) (xy 341.42661 -222.229283) (xy 341.380443 -222.252806) (xy 341.331164 -222.268818)
			(xy 341.279987 -222.276924) (xy 341.228173 -222.276924) (xy 341.176996 -222.268818) (xy 341.127717 -222.252806)
			(xy 341.08155 -222.229283) (xy 341.039631 -222.198827) (xy 341.002993 -222.162189) (xy 340.972537 -222.12027)
			(xy 340.949014 -222.074103) (xy 340.933002 -222.024824) (xy 340.924896 -221.973647) (xy 340.924388 -221.94774)
			(xy 340.924992 -221.920023) (xy 340.934309 -221.865377) (xy 340.94293 -221.839028) (xy 340.950804 -221.81693)
			(xy 340.745826 -221.462092) (xy 340.722966 -221.457774) (xy 340.698166 -221.452574) (xy 340.65043 -221.435583)
			(xy 340.605855 -221.411489) (xy 340.565491 -221.380859) (xy 340.530289 -221.344414) (xy 340.501076 -221.303012)
			(xy 340.478542 -221.257629) (xy 340.463217 -221.209332) (xy 340.455461 -221.159259) (xy 340.454996 -221.133924)
			(xy 340.174072 -221.133924) (xy 340.173564 -221.159811) (xy 340.165465 -221.210949) (xy 340.149466 -221.260189)
			(xy 340.12596 -221.306321) (xy 340.095528 -221.348208) (xy 340.058918 -221.384818) (xy 340.017031 -221.41525)
			(xy 339.970899 -221.438756) (xy 339.921659 -221.454755) (xy 339.870521 -221.462854) (xy 339.818747 -221.462854)
			(xy 339.767609 -221.454755) (xy 339.718369 -221.438756) (xy 339.672237 -221.41525) (xy 339.63035 -221.384818)
			(xy 339.59374 -221.348208) (xy 339.563308 -221.306321) (xy 339.539802 -221.260189) (xy 339.523803 -221.210949)
			(xy 339.515704 -221.159811) (xy 339.515196 -221.133924) (xy 339.234272 -221.133924) (xy 339.233745 -221.161632)
			(xy 339.224548 -221.216279) (xy 339.215984 -221.242636) (xy 339.20811 -221.264734) (xy 339.413088 -221.619572)
			(xy 339.435948 -221.62389) (xy 339.460767 -221.629064) (xy 339.508546 -221.646018) (xy 339.553165 -221.670088)
			(xy 339.593572 -221.700708) (xy 339.628813 -221.737154) (xy 339.658057 -221.778566) (xy 339.680614 -221.823969)
			(xy 339.695952 -221.872291) (xy 339.70371 -221.922391) (xy 339.704172 -221.94774) (xy 339.703664 -221.973647)
			(xy 339.695558 -222.024824) (xy 339.679546 -222.074103) (xy 339.656023 -222.12027) (xy 339.625567 -222.162189)
			(xy 339.588929 -222.198827) (xy 339.54701 -222.229283) (xy 339.500843 -222.252806) (xy 339.451564 -222.268818)
			(xy 339.400387 -222.276924) (xy 339.348573 -222.276924) (xy 339.297396 -222.268818) (xy 339.248117 -222.252806)
			(xy 339.20195 -222.229283) (xy 339.160031 -222.198827) (xy 339.123393 -222.162189) (xy 339.092937 -222.12027)
			(xy 339.069414 -222.074103) (xy 339.053402 -222.024824) (xy 339.045296 -221.973647) (xy 339.044788 -221.94774)
			(xy 339.045392 -221.920023) (xy 339.054709 -221.865377) (xy 339.06333 -221.839028) (xy 339.071204 -221.81693)
			(xy 338.866226 -221.462092) (xy 338.843366 -221.457774) (xy 338.818566 -221.452574) (xy 338.77083 -221.435583)
			(xy 338.726255 -221.411489) (xy 338.685891 -221.380859) (xy 338.650689 -221.344414) (xy 338.621476 -221.303012)
			(xy 338.598942 -221.257629) (xy 338.583617 -221.209332) (xy 338.575861 -221.159259) (xy 338.575396 -221.133924)
			(xy 338.294472 -221.133924) (xy 338.293964 -221.159811) (xy 338.285865 -221.210949) (xy 338.269866 -221.260189)
			(xy 338.24636 -221.306321) (xy 338.215928 -221.348208) (xy 338.179318 -221.384818) (xy 338.137431 -221.41525)
			(xy 338.091299 -221.438756) (xy 338.042059 -221.454755) (xy 337.990921 -221.462854) (xy 337.939147 -221.462854)
			(xy 337.888009 -221.454755) (xy 337.838769 -221.438756) (xy 337.792637 -221.41525) (xy 337.75075 -221.384818)
			(xy 337.71414 -221.348208) (xy 337.683708 -221.306321) (xy 337.660202 -221.260189) (xy 337.644203 -221.210949)
			(xy 337.636104 -221.159811) (xy 337.635596 -221.133924) (xy 337.354672 -221.133924) (xy 337.354145 -221.161632)
			(xy 337.344948 -221.216279) (xy 337.336384 -221.242636) (xy 337.32851 -221.264734) (xy 337.533488 -221.619572)
			(xy 337.556348 -221.62389) (xy 337.581167 -221.629064) (xy 337.628946 -221.646018) (xy 337.673565 -221.670088)
			(xy 337.713972 -221.700708) (xy 337.749213 -221.737154) (xy 337.778457 -221.778566) (xy 337.801014 -221.823969)
			(xy 337.816352 -221.872291) (xy 337.82411 -221.922391) (xy 337.824572 -221.94774) (xy 337.824064 -221.973647)
			(xy 337.815958 -222.024824) (xy 337.799946 -222.074103) (xy 337.776423 -222.12027) (xy 337.745967 -222.162189)
			(xy 337.709329 -222.198827) (xy 337.66741 -222.229283) (xy 337.621243 -222.252806) (xy 337.571964 -222.268818)
			(xy 337.520787 -222.276924) (xy 337.468973 -222.276924) (xy 337.417796 -222.268818) (xy 337.368517 -222.252806)
			(xy 337.32235 -222.229283) (xy 337.280431 -222.198827) (xy 337.243793 -222.162189) (xy 337.213337 -222.12027)
			(xy 337.189814 -222.074103) (xy 337.173802 -222.024824) (xy 337.165696 -221.973647) (xy 337.165188 -221.94774)
			(xy 337.165792 -221.920023) (xy 337.175109 -221.865377) (xy 337.18373 -221.839028) (xy 337.191604 -221.81693)
			(xy 336.986626 -221.462092) (xy 336.963766 -221.457774) (xy 336.938966 -221.452574) (xy 336.89123 -221.435583)
			(xy 336.846655 -221.411489) (xy 336.806291 -221.380859) (xy 336.771089 -221.344414) (xy 336.741876 -221.303012)
			(xy 336.719342 -221.257629) (xy 336.704017 -221.209332) (xy 336.696261 -221.159259) (xy 336.695796 -221.133924)
			(xy 135.464804 -221.133924) (xy 135.464385 -221.15929) (xy 135.456633 -221.209425) (xy 135.441284 -221.257778)
			(xy 135.418702 -221.303206) (xy 135.389421 -221.344633) (xy 135.354133 -221.381081) (xy 135.313674 -221.411686)
			(xy 135.269 -221.435725) (xy 135.221169 -221.45263) (xy 135.196326 -221.457774) (xy 135.173466 -221.462092)
			(xy 134.968742 -221.81693) (xy 134.976362 -221.838774) (xy 134.984977 -221.865059) (xy 134.994298 -221.919578)
			(xy 134.994904 -221.947232) (xy 134.994904 -221.94774) (xy 134.994396 -221.973647) (xy 134.98629 -222.024824)
			(xy 134.970278 -222.074103) (xy 134.946755 -222.12027) (xy 134.916299 -222.162189) (xy 134.879661 -222.198827)
			(xy 134.837742 -222.229283) (xy 134.791575 -222.252806) (xy 134.742296 -222.268818) (xy 134.691119 -222.276924)
			(xy 134.639305 -222.276924) (xy 134.588128 -222.268818) (xy 134.538849 -222.252806) (xy 134.492682 -222.229283)
			(xy 134.450763 -222.198827) (xy 134.414125 -222.162189) (xy 134.383669 -222.12027) (xy 134.360146 -222.074103)
			(xy 134.344134 -222.024824) (xy 134.336028 -221.973647) (xy 134.33552 -221.94774) (xy 133.115304 -221.94774)
			(xy 133.114796 -221.973647) (xy 133.10669 -222.024824) (xy 133.090678 -222.074103) (xy 133.067155 -222.12027)
			(xy 133.036699 -222.162189) (xy 133.000061 -222.198827) (xy 132.958142 -222.229283) (xy 132.911975 -222.252806)
			(xy 132.862696 -222.268818) (xy 132.811519 -222.276924) (xy 132.759705 -222.276924) (xy 132.708528 -222.268818)
			(xy 132.659249 -222.252806) (xy 132.613082 -222.229283) (xy 132.571163 -222.198827) (xy 132.534525 -222.162189)
			(xy 132.504069 -222.12027) (xy 132.480546 -222.074103) (xy 132.464534 -222.024824) (xy 132.456428 -221.973647)
			(xy 132.45592 -221.94774) (xy 131.235704 -221.94774) (xy 131.235196 -221.973647) (xy 131.22709 -222.024824)
			(xy 131.211078 -222.074103) (xy 131.187555 -222.12027) (xy 131.157099 -222.162189) (xy 131.120461 -222.198827)
			(xy 131.078542 -222.229283) (xy 131.032375 -222.252806) (xy 130.983096 -222.268818) (xy 130.931919 -222.276924)
			(xy 130.880105 -222.276924) (xy 130.828928 -222.268818) (xy 130.779649 -222.252806) (xy 130.733482 -222.229283)
			(xy 130.691563 -222.198827) (xy 130.654925 -222.162189) (xy 130.624469 -222.12027) (xy 130.600946 -222.074103)
			(xy 130.584934 -222.024824) (xy 130.576828 -221.973647) (xy 130.57632 -221.94774) (xy 129.356104 -221.94774)
			(xy 129.355596 -221.973647) (xy 129.34749 -222.024824) (xy 129.331478 -222.074103) (xy 129.307955 -222.12027)
			(xy 129.277499 -222.162189) (xy 129.240861 -222.198827) (xy 129.198942 -222.229283) (xy 129.152775 -222.252806)
			(xy 129.103496 -222.268818) (xy 129.052319 -222.276924) (xy 129.000505 -222.276924) (xy 128.949328 -222.268818)
			(xy 128.900049 -222.252806) (xy 128.853882 -222.229283) (xy 128.811963 -222.198827) (xy 128.775325 -222.162189)
			(xy 128.744869 -222.12027) (xy 128.721346 -222.074103) (xy 128.705334 -222.024824) (xy 128.697228 -221.973647)
			(xy 128.69672 -221.94774) (xy 127.476504 -221.94774) (xy 127.475996 -221.973647) (xy 127.46789 -222.024824)
			(xy 127.451878 -222.074103) (xy 127.428355 -222.12027) (xy 127.397899 -222.162189) (xy 127.361261 -222.198827)
			(xy 127.319342 -222.229283) (xy 127.273175 -222.252806) (xy 127.223896 -222.268818) (xy 127.172719 -222.276924)
			(xy 127.120905 -222.276924) (xy 127.069728 -222.268818) (xy 127.020449 -222.252806) (xy 126.974282 -222.229283)
			(xy 126.932363 -222.198827) (xy 126.895725 -222.162189) (xy 126.865269 -222.12027) (xy 126.841746 -222.074103)
			(xy 126.825734 -222.024824) (xy 126.817628 -221.973647) (xy 126.81712 -221.94774) (xy 125.596904 -221.94774)
			(xy 125.596396 -221.973647) (xy 125.58829 -222.024824) (xy 125.572278 -222.074103) (xy 125.548755 -222.12027)
			(xy 125.518299 -222.162189) (xy 125.481661 -222.198827) (xy 125.439742 -222.229283) (xy 125.393575 -222.252806)
			(xy 125.344296 -222.268818) (xy 125.293119 -222.276924) (xy 125.241305 -222.276924) (xy 125.190128 -222.268818)
			(xy 125.140849 -222.252806) (xy 125.094682 -222.229283) (xy 125.052763 -222.198827) (xy 125.016125 -222.162189)
			(xy 124.985669 -222.12027) (xy 124.962146 -222.074103) (xy 124.946134 -222.024824) (xy 124.938028 -221.973647)
			(xy 124.93752 -221.94774) (xy 123.717304 -221.94774) (xy 123.716796 -221.973647) (xy 123.70869 -222.024824)
			(xy 123.692678 -222.074103) (xy 123.669155 -222.12027) (xy 123.638699 -222.162189) (xy 123.602061 -222.198827)
			(xy 123.560142 -222.229283) (xy 123.513975 -222.252806) (xy 123.464696 -222.268818) (xy 123.413519 -222.276924)
			(xy 123.361705 -222.276924) (xy 123.310528 -222.268818) (xy 123.261249 -222.252806) (xy 123.215082 -222.229283)
			(xy 123.173163 -222.198827) (xy 123.136525 -222.162189) (xy 123.106069 -222.12027) (xy 123.082546 -222.074103)
			(xy 123.066534 -222.024824) (xy 123.058428 -221.973647) (xy 123.05792 -221.94774) (xy 121.837704 -221.94774)
			(xy 121.837196 -221.973647) (xy 121.82909 -222.024824) (xy 121.813078 -222.074103) (xy 121.789555 -222.12027)
			(xy 121.759099 -222.162189) (xy 121.722461 -222.198827) (xy 121.680542 -222.229283) (xy 121.634375 -222.252806)
			(xy 121.585096 -222.268818) (xy 121.533919 -222.276924) (xy 121.482105 -222.276924) (xy 121.430928 -222.268818)
			(xy 121.381649 -222.252806) (xy 121.335482 -222.229283) (xy 121.293563 -222.198827) (xy 121.256925 -222.162189)
			(xy 121.226469 -222.12027) (xy 121.202946 -222.074103) (xy 121.186934 -222.024824) (xy 121.178828 -221.973647)
			(xy 121.17832 -221.94774) (xy 118.078504 -221.94774) (xy 118.077996 -221.973647) (xy 118.06989 -222.024824)
			(xy 118.053878 -222.074103) (xy 118.030355 -222.12027) (xy 117.999899 -222.162189) (xy 117.963261 -222.198827)
			(xy 117.921342 -222.229283) (xy 117.875175 -222.252806) (xy 117.825896 -222.268818) (xy 117.774719 -222.276924)
			(xy 117.722905 -222.276924) (xy 117.671728 -222.268818) (xy 117.622449 -222.252806) (xy 117.576282 -222.229283)
			(xy 117.534363 -222.198827) (xy 117.497725 -222.162189) (xy 117.467269 -222.12027) (xy 117.443746 -222.074103)
			(xy 117.427734 -222.024824) (xy 117.419628 -221.973647) (xy 117.41912 -221.94774) (xy 116.198904 -221.94774)
			(xy 116.198396 -221.973647) (xy 116.19029 -222.024824) (xy 116.174278 -222.074103) (xy 116.150755 -222.12027)
			(xy 116.120299 -222.162189) (xy 116.083661 -222.198827) (xy 116.041742 -222.229283) (xy 115.995575 -222.252806)
			(xy 115.946296 -222.268818) (xy 115.895119 -222.276924) (xy 115.843305 -222.276924) (xy 115.792128 -222.268818)
			(xy 115.742849 -222.252806) (xy 115.696682 -222.229283) (xy 115.654763 -222.198827) (xy 115.618125 -222.162189)
			(xy 115.587669 -222.12027) (xy 115.564146 -222.074103) (xy 115.548134 -222.024824) (xy 115.540028 -221.973647)
			(xy 115.53952 -221.94774) (xy 114.319304 -221.94774) (xy 114.318796 -221.973627) (xy 114.310697 -222.024765)
			(xy 114.294698 -222.074005) (xy 114.271192 -222.120137) (xy 114.24076 -222.162024) (xy 114.20415 -222.198634)
			(xy 114.162263 -222.229066) (xy 114.116131 -222.252572) (xy 114.066891 -222.268571) (xy 114.015753 -222.27667)
			(xy 113.963979 -222.27667) (xy 113.912841 -222.268571) (xy 113.863601 -222.252572) (xy 113.817469 -222.229066)
			(xy 113.775582 -222.198634) (xy 113.738972 -222.162024) (xy 113.70854 -222.120137) (xy 113.685034 -222.074005)
			(xy 113.669035 -222.024765) (xy 113.660936 -221.973627) (xy 113.660428 -221.94774) (xy 112.439704 -221.94774)
			(xy 112.439196 -221.973647) (xy 112.43109 -222.024824) (xy 112.415078 -222.074103) (xy 112.391555 -222.12027)
			(xy 112.361099 -222.162189) (xy 112.324461 -222.198827) (xy 112.282542 -222.229283) (xy 112.236375 -222.252806)
			(xy 112.187096 -222.268818) (xy 112.135919 -222.276924) (xy 112.084105 -222.276924) (xy 112.032928 -222.268818)
			(xy 111.983649 -222.252806) (xy 111.937482 -222.229283) (xy 111.895563 -222.198827) (xy 111.858925 -222.162189)
			(xy 111.828469 -222.12027) (xy 111.804946 -222.074103) (xy 111.788934 -222.024824) (xy 111.780828 -221.973647)
			(xy 111.78032 -221.94774) (xy 110.560104 -221.94774) (xy 110.559596 -221.973627) (xy 110.551497 -222.024765)
			(xy 110.535498 -222.074005) (xy 110.511992 -222.120137) (xy 110.48156 -222.162024) (xy 110.44495 -222.198634)
			(xy 110.403063 -222.229066) (xy 110.356931 -222.252572) (xy 110.307691 -222.268571) (xy 110.256553 -222.27667)
			(xy 110.204779 -222.27667) (xy 110.153641 -222.268571) (xy 110.104401 -222.252572) (xy 110.058269 -222.229066)
			(xy 110.016382 -222.198634) (xy 109.979772 -222.162024) (xy 109.94934 -222.120137) (xy 109.925834 -222.074005)
			(xy 109.909835 -222.024765) (xy 109.901736 -221.973627) (xy 109.901228 -221.94774) (xy 108.680504 -221.94774)
			(xy 108.679996 -221.973647) (xy 108.67189 -222.024824) (xy 108.655878 -222.074103) (xy 108.632355 -222.12027)
			(xy 108.601899 -222.162189) (xy 108.565261 -222.198827) (xy 108.523342 -222.229283) (xy 108.477175 -222.252806)
			(xy 108.427896 -222.268818) (xy 108.376719 -222.276924) (xy 108.324905 -222.276924) (xy 108.273728 -222.268818)
			(xy 108.224449 -222.252806) (xy 108.178282 -222.229283) (xy 108.136363 -222.198827) (xy 108.099725 -222.162189)
			(xy 108.069269 -222.12027) (xy 108.045746 -222.074103) (xy 108.029734 -222.024824) (xy 108.021628 -221.973647)
			(xy 108.02112 -221.94774) (xy 106.800904 -221.94774) (xy 106.800396 -221.973647) (xy 106.79229 -222.024824)
			(xy 106.776278 -222.074103) (xy 106.752755 -222.12027) (xy 106.722299 -222.162189) (xy 106.685661 -222.198827)
			(xy 106.643742 -222.229283) (xy 106.597575 -222.252806) (xy 106.548296 -222.268818) (xy 106.497119 -222.276924)
			(xy 106.445305 -222.276924) (xy 106.394128 -222.268818) (xy 106.344849 -222.252806) (xy 106.298682 -222.229283)
			(xy 106.256763 -222.198827) (xy 106.220125 -222.162189) (xy 106.189669 -222.12027) (xy 106.166146 -222.074103)
			(xy 106.150134 -222.024824) (xy 106.142028 -221.973647) (xy 106.14152 -221.94774) (xy 104.921304 -221.94774)
			(xy 104.920796 -221.973647) (xy 104.91269 -222.024824) (xy 104.896678 -222.074103) (xy 104.873155 -222.12027)
			(xy 104.842699 -222.162189) (xy 104.806061 -222.198827) (xy 104.764142 -222.229283) (xy 104.717975 -222.252806)
			(xy 104.668696 -222.268818) (xy 104.617519 -222.276924) (xy 104.565705 -222.276924) (xy 104.514528 -222.268818)
			(xy 104.465249 -222.252806) (xy 104.419082 -222.229283) (xy 104.377163 -222.198827) (xy 104.340525 -222.162189)
			(xy 104.310069 -222.12027) (xy 104.286546 -222.074103) (xy 104.270534 -222.024824) (xy 104.262428 -221.973647)
			(xy 104.26192 -221.94774) (xy 103.041704 -221.94774) (xy 103.041196 -221.973647) (xy 103.03309 -222.024824)
			(xy 103.017078 -222.074103) (xy 102.993555 -222.12027) (xy 102.963099 -222.162189) (xy 102.926461 -222.198827)
			(xy 102.884542 -222.229283) (xy 102.838375 -222.252806) (xy 102.789096 -222.268818) (xy 102.737919 -222.276924)
			(xy 102.686105 -222.276924) (xy 102.634928 -222.268818) (xy 102.585649 -222.252806) (xy 102.539482 -222.229283)
			(xy 102.497563 -222.198827) (xy 102.460925 -222.162189) (xy 102.430469 -222.12027) (xy 102.406946 -222.074103)
			(xy 102.390934 -222.024824) (xy 102.382828 -221.973647) (xy 102.38232 -221.94774) (xy 102.382923 -221.920023)
			(xy 102.39224 -221.865377) (xy 102.400862 -221.839028) (xy 102.408736 -221.81693) (xy 102.203758 -221.462092)
			(xy 102.180898 -221.457774) (xy 102.156103 -221.45255) (xy 102.108367 -221.435564) (xy 102.063792 -221.411474)
			(xy 102.023427 -221.380847) (xy 101.988224 -221.344405) (xy 101.959011 -221.303006) (xy 101.936476 -221.257625)
			(xy 101.92115 -221.20933) (xy 101.913394 -221.159258) (xy 101.912928 -221.133924) (xy 101.632004 -221.133924)
			(xy 101.631496 -221.159811) (xy 101.623397 -221.210949) (xy 101.607398 -221.260189) (xy 101.583892 -221.306321)
			(xy 101.55346 -221.348208) (xy 101.51685 -221.384818) (xy 101.474963 -221.41525) (xy 101.428831 -221.438756)
			(xy 101.379591 -221.454755) (xy 101.328453 -221.462854) (xy 101.276679 -221.462854) (xy 101.225541 -221.454755)
			(xy 101.176301 -221.438756) (xy 101.130169 -221.41525) (xy 101.088282 -221.384818) (xy 101.051672 -221.348208)
			(xy 101.02124 -221.306321) (xy 100.997734 -221.260189) (xy 100.981735 -221.210949) (xy 100.973636 -221.159811)
			(xy 100.973128 -221.133924) (xy 100.692204 -221.133924) (xy 100.69168 -221.161632) (xy 100.682481 -221.216279)
			(xy 100.673916 -221.242636) (xy 100.666042 -221.264734) (xy 100.87102 -221.619572) (xy 100.89388 -221.62389)
			(xy 100.918705 -221.629041) (xy 100.966483 -221.645999) (xy 101.011102 -221.670074) (xy 101.051507 -221.700696)
			(xy 101.086747 -221.737145) (xy 101.11599 -221.778561) (xy 101.138547 -221.823965) (xy 101.153885 -221.872289)
			(xy 101.161642 -221.92239) (xy 101.162104 -221.94774) (xy 101.161596 -221.973647) (xy 101.15349 -222.024824)
			(xy 101.137478 -222.074103) (xy 101.113955 -222.12027) (xy 101.083499 -222.162189) (xy 101.046861 -222.198827)
			(xy 101.004942 -222.229283) (xy 100.958775 -222.252806) (xy 100.909496 -222.268818) (xy 100.858319 -222.276924)
			(xy 100.806505 -222.276924) (xy 100.755328 -222.268818) (xy 100.706049 -222.252806) (xy 100.659882 -222.229283)
			(xy 100.617963 -222.198827) (xy 100.581325 -222.162189) (xy 100.550869 -222.12027) (xy 100.527346 -222.074103)
			(xy 100.511334 -222.024824) (xy 100.503228 -221.973647) (xy 100.50272 -221.94774) (xy 100.503323 -221.920023)
			(xy 100.51264 -221.865377) (xy 100.521262 -221.839028) (xy 100.529136 -221.81693) (xy 100.324158 -221.462092)
			(xy 100.301298 -221.457774) (xy 100.276503 -221.45255) (xy 100.228767 -221.435564) (xy 100.184192 -221.411474)
			(xy 100.143827 -221.380847) (xy 100.108624 -221.344405) (xy 100.079411 -221.303006) (xy 100.056876 -221.257625)
			(xy 100.04155 -221.20933) (xy 100.033794 -221.159258) (xy 100.033328 -221.133924) (xy 99.752404 -221.133924)
			(xy 99.751896 -221.159811) (xy 99.743797 -221.210949) (xy 99.727798 -221.260189) (xy 99.704292 -221.306321)
			(xy 99.67386 -221.348208) (xy 99.63725 -221.384818) (xy 99.595363 -221.41525) (xy 99.549231 -221.438756)
			(xy 99.499991 -221.454755) (xy 99.448853 -221.462854) (xy 99.397079 -221.462854) (xy 99.345941 -221.454755)
			(xy 99.296701 -221.438756) (xy 99.250569 -221.41525) (xy 99.208682 -221.384818) (xy 99.172072 -221.348208)
			(xy 99.14164 -221.306321) (xy 99.118134 -221.260189) (xy 99.102135 -221.210949) (xy 99.094036 -221.159811)
			(xy 99.093528 -221.133924) (xy 98.812604 -221.133924) (xy 98.81208 -221.161632) (xy 98.802881 -221.216279)
			(xy 98.794316 -221.242636) (xy 98.786442 -221.264734) (xy 98.99142 -221.619572) (xy 99.01428 -221.62389)
			(xy 99.039105 -221.629041) (xy 99.086883 -221.645999) (xy 99.131502 -221.670074) (xy 99.171907 -221.700696)
			(xy 99.207147 -221.737145) (xy 99.23639 -221.778561) (xy 99.258947 -221.823965) (xy 99.274285 -221.872289)
			(xy 99.282042 -221.92239) (xy 99.282504 -221.94774) (xy 99.281996 -221.973647) (xy 99.27389 -222.024824)
			(xy 99.257878 -222.074103) (xy 99.234355 -222.12027) (xy 99.203899 -222.162189) (xy 99.167261 -222.198827)
			(xy 99.125342 -222.229283) (xy 99.079175 -222.252806) (xy 99.029896 -222.268818) (xy 98.978719 -222.276924)
			(xy 98.926905 -222.276924) (xy 98.875728 -222.268818) (xy 98.826449 -222.252806) (xy 98.780282 -222.229283)
			(xy 98.738363 -222.198827) (xy 98.701725 -222.162189) (xy 98.671269 -222.12027) (xy 98.647746 -222.074103)
			(xy 98.631734 -222.024824) (xy 98.623628 -221.973647) (xy 98.62312 -221.94774) (xy 98.623723 -221.920023)
			(xy 98.63304 -221.865377) (xy 98.641662 -221.839028) (xy 98.649536 -221.81693) (xy 98.444558 -221.462092)
			(xy 98.421698 -221.457774) (xy 98.396903 -221.45255) (xy 98.349167 -221.435564) (xy 98.304592 -221.411474)
			(xy 98.264227 -221.380847) (xy 98.229024 -221.344405) (xy 98.199811 -221.303006) (xy 98.177276 -221.257625)
			(xy 98.16195 -221.20933) (xy 98.154194 -221.159258) (xy 98.153728 -221.133924) (xy 97.872804 -221.133924)
			(xy 97.872296 -221.159811) (xy 97.864197 -221.210949) (xy 97.848198 -221.260189) (xy 97.824692 -221.306321)
			(xy 97.79426 -221.348208) (xy 97.75765 -221.384818) (xy 97.715763 -221.41525) (xy 97.669631 -221.438756)
			(xy 97.620391 -221.454755) (xy 97.569253 -221.462854) (xy 97.517479 -221.462854) (xy 97.466341 -221.454755)
			(xy 97.417101 -221.438756) (xy 97.370969 -221.41525) (xy 97.329082 -221.384818) (xy 97.292472 -221.348208)
			(xy 97.26204 -221.306321) (xy 97.238534 -221.260189) (xy 97.222535 -221.210949) (xy 97.214436 -221.159811)
			(xy 97.213928 -221.133924) (xy 96.933004 -221.133924) (xy 96.93248 -221.161632) (xy 96.923281 -221.216279)
			(xy 96.914716 -221.242636) (xy 96.906842 -221.264734) (xy 97.11182 -221.619572) (xy 97.13468 -221.62389)
			(xy 97.159505 -221.629041) (xy 97.207283 -221.645999) (xy 97.251902 -221.670074) (xy 97.292307 -221.700696)
			(xy 97.327547 -221.737145) (xy 97.35679 -221.778561) (xy 97.379347 -221.823965) (xy 97.394685 -221.872289)
			(xy 97.402442 -221.92239) (xy 97.402904 -221.94774) (xy 97.402396 -221.973647) (xy 97.39429 -222.024824)
			(xy 97.378278 -222.074103) (xy 97.354755 -222.12027) (xy 97.324299 -222.162189) (xy 97.287661 -222.198827)
			(xy 97.245742 -222.229283) (xy 97.199575 -222.252806) (xy 97.150296 -222.268818) (xy 97.099119 -222.276924)
			(xy 97.047305 -222.276924) (xy 96.996128 -222.268818) (xy 96.946849 -222.252806) (xy 96.900682 -222.229283)
			(xy 96.858763 -222.198827) (xy 96.822125 -222.162189) (xy 96.791669 -222.12027) (xy 96.768146 -222.074103)
			(xy 96.752134 -222.024824) (xy 96.744028 -221.973647) (xy 96.74352 -221.94774) (xy 96.744123 -221.920023)
			(xy 96.75344 -221.865377) (xy 96.762062 -221.839028) (xy 96.769936 -221.81693) (xy 96.564958 -221.462092)
			(xy 96.542098 -221.457774) (xy 96.517303 -221.45255) (xy 96.469567 -221.435564) (xy 96.424992 -221.411474)
			(xy 96.384627 -221.380847) (xy 96.349424 -221.344405) (xy 96.320211 -221.303006) (xy 96.297676 -221.257625)
			(xy 96.28235 -221.20933) (xy 96.274594 -221.159258) (xy 96.274128 -221.133924) (xy 95.993204 -221.133924)
			(xy 95.992696 -221.159811) (xy 95.984597 -221.210949) (xy 95.968598 -221.260189) (xy 95.945092 -221.306321)
			(xy 95.91466 -221.348208) (xy 95.87805 -221.384818) (xy 95.836163 -221.41525) (xy 95.790031 -221.438756)
			(xy 95.740791 -221.454755) (xy 95.689653 -221.462854) (xy 95.637879 -221.462854) (xy 95.586741 -221.454755)
			(xy 95.537501 -221.438756) (xy 95.491369 -221.41525) (xy 95.449482 -221.384818) (xy 95.412872 -221.348208)
			(xy 95.38244 -221.306321) (xy 95.358934 -221.260189) (xy 95.342935 -221.210949) (xy 95.334836 -221.159811)
			(xy 95.334328 -221.133924) (xy 95.053404 -221.133924) (xy 95.05288 -221.161632) (xy 95.043681 -221.216279)
			(xy 95.035116 -221.242636) (xy 95.027242 -221.264734) (xy 95.23222 -221.619572) (xy 95.25508 -221.62389)
			(xy 95.279905 -221.629041) (xy 95.327683 -221.645999) (xy 95.372302 -221.670074) (xy 95.412707 -221.700696)
			(xy 95.447947 -221.737145) (xy 95.47719 -221.778561) (xy 95.499747 -221.823965) (xy 95.515085 -221.872289)
			(xy 95.522842 -221.92239) (xy 95.523304 -221.94774) (xy 95.522796 -221.973647) (xy 95.51469 -222.024824)
			(xy 95.498678 -222.074103) (xy 95.475155 -222.12027) (xy 95.444699 -222.162189) (xy 95.408061 -222.198827)
			(xy 95.366142 -222.229283) (xy 95.319975 -222.252806) (xy 95.270696 -222.268818) (xy 95.219519 -222.276924)
			(xy 95.167705 -222.276924) (xy 95.116528 -222.268818) (xy 95.067249 -222.252806) (xy 95.021082 -222.229283)
			(xy 94.979163 -222.198827) (xy 94.942525 -222.162189) (xy 94.912069 -222.12027) (xy 94.888546 -222.074103)
			(xy 94.872534 -222.024824) (xy 94.864428 -221.973647) (xy 94.86392 -221.94774) (xy 94.864523 -221.920023)
			(xy 94.87384 -221.865377) (xy 94.882462 -221.839028) (xy 94.890336 -221.81693) (xy 94.685358 -221.462092)
			(xy 94.662498 -221.457774) (xy 94.637703 -221.45255) (xy 94.589967 -221.435564) (xy 94.545392 -221.411474)
			(xy 94.505027 -221.380847) (xy 94.469824 -221.344405) (xy 94.440611 -221.303006) (xy 94.418076 -221.257625)
			(xy 94.40275 -221.20933) (xy 94.394994 -221.159258) (xy 94.394528 -221.133924) (xy 94.113604 -221.133924)
			(xy 94.113096 -221.159811) (xy 94.104997 -221.210949) (xy 94.088998 -221.260189) (xy 94.065492 -221.306321)
			(xy 94.03506 -221.348208) (xy 93.99845 -221.384818) (xy 93.956563 -221.41525) (xy 93.910431 -221.438756)
			(xy 93.861191 -221.454755) (xy 93.810053 -221.462854) (xy 93.758279 -221.462854) (xy 93.707141 -221.454755)
			(xy 93.657901 -221.438756) (xy 93.611769 -221.41525) (xy 93.569882 -221.384818) (xy 93.533272 -221.348208)
			(xy 93.50284 -221.306321) (xy 93.479334 -221.260189) (xy 93.463335 -221.210949) (xy 93.455236 -221.159811)
			(xy 93.454728 -221.133924) (xy 93.173804 -221.133924) (xy 93.17328 -221.161632) (xy 93.164081 -221.216279)
			(xy 93.155516 -221.242636) (xy 93.147642 -221.264734) (xy 93.35262 -221.619572) (xy 93.37548 -221.62389)
			(xy 93.400305 -221.629041) (xy 93.448083 -221.645999) (xy 93.492702 -221.670074) (xy 93.533107 -221.700696)
			(xy 93.568347 -221.737145) (xy 93.59759 -221.778561) (xy 93.620147 -221.823965) (xy 93.635485 -221.872289)
			(xy 93.643242 -221.92239) (xy 93.643704 -221.94774) (xy 93.643196 -221.973647) (xy 93.63509 -222.024824)
			(xy 93.619078 -222.074103) (xy 93.595555 -222.12027) (xy 93.565099 -222.162189) (xy 93.528461 -222.198827)
			(xy 93.486542 -222.229283) (xy 93.440375 -222.252806) (xy 93.391096 -222.268818) (xy 93.339919 -222.276924)
			(xy 93.288105 -222.276924) (xy 93.236928 -222.268818) (xy 93.187649 -222.252806) (xy 93.141482 -222.229283)
			(xy 93.099563 -222.198827) (xy 93.062925 -222.162189) (xy 93.032469 -222.12027) (xy 93.008946 -222.074103)
			(xy 92.992934 -222.024824) (xy 92.984828 -221.973647) (xy 92.98432 -221.94774) (xy 92.984923 -221.920023)
			(xy 92.99424 -221.865377) (xy 93.002862 -221.839028) (xy 93.010736 -221.81693) (xy 92.805758 -221.462092)
			(xy 92.782898 -221.457774) (xy 92.758103 -221.45255) (xy 92.710367 -221.435564) (xy 92.665792 -221.411474)
			(xy 92.625427 -221.380847) (xy 92.590224 -221.344405) (xy 92.561011 -221.303006) (xy 92.538476 -221.257625)
			(xy 92.52315 -221.20933) (xy 92.515394 -221.159258) (xy 92.514928 -221.133924) (xy 92.234004 -221.133924)
			(xy 92.233496 -221.159811) (xy 92.225397 -221.210949) (xy 92.209398 -221.260189) (xy 92.185892 -221.306321)
			(xy 92.15546 -221.348208) (xy 92.11885 -221.384818) (xy 92.076963 -221.41525) (xy 92.030831 -221.438756)
			(xy 91.981591 -221.454755) (xy 91.930453 -221.462854) (xy 91.878679 -221.462854) (xy 91.827541 -221.454755)
			(xy 91.778301 -221.438756) (xy 91.732169 -221.41525) (xy 91.690282 -221.384818) (xy 91.653672 -221.348208)
			(xy 91.62324 -221.306321) (xy 91.599734 -221.260189) (xy 91.583735 -221.210949) (xy 91.575636 -221.159811)
			(xy 91.575128 -221.133924) (xy 91.294204 -221.133924) (xy 91.29368 -221.161632) (xy 91.284481 -221.216279)
			(xy 91.275916 -221.242636) (xy 91.268042 -221.264734) (xy 91.47302 -221.619572) (xy 91.49588 -221.62389)
			(xy 91.520705 -221.629041) (xy 91.568483 -221.645999) (xy 91.613102 -221.670074) (xy 91.653507 -221.700696)
			(xy 91.688747 -221.737145) (xy 91.71799 -221.778561) (xy 91.740547 -221.823965) (xy 91.755885 -221.872289)
			(xy 91.763642 -221.92239) (xy 91.764104 -221.94774) (xy 91.763596 -221.973647) (xy 91.75549 -222.024824)
			(xy 91.739478 -222.074103) (xy 91.715955 -222.12027) (xy 91.685499 -222.162189) (xy 91.648861 -222.198827)
			(xy 91.606942 -222.229283) (xy 91.560775 -222.252806) (xy 91.511496 -222.268818) (xy 91.460319 -222.276924)
			(xy 91.408505 -222.276924) (xy 91.357328 -222.268818) (xy 91.308049 -222.252806) (xy 91.261882 -222.229283)
			(xy 91.219963 -222.198827) (xy 91.183325 -222.162189) (xy 91.152869 -222.12027) (xy 91.129346 -222.074103)
			(xy 91.113334 -222.024824) (xy 91.105228 -221.973647) (xy 91.10472 -221.94774) (xy 91.105323 -221.920023)
			(xy 91.11464 -221.865377) (xy 91.123262 -221.839028) (xy 91.131136 -221.81693) (xy 90.926158 -221.462092)
			(xy 90.903298 -221.457774) (xy 90.878503 -221.45255) (xy 90.830767 -221.435564) (xy 90.786192 -221.411474)
			(xy 90.745827 -221.380847) (xy 90.710624 -221.344405) (xy 90.681411 -221.303006) (xy 90.658876 -221.257625)
			(xy 90.64355 -221.20933) (xy 90.635794 -221.159258) (xy 90.635328 -221.133924) (xy 90.354404 -221.133924)
			(xy 90.353896 -221.159811) (xy 90.345797 -221.210949) (xy 90.329798 -221.260189) (xy 90.306292 -221.306321)
			(xy 90.27586 -221.348208) (xy 90.23925 -221.384818) (xy 90.197363 -221.41525) (xy 90.151231 -221.438756)
			(xy 90.101991 -221.454755) (xy 90.050853 -221.462854) (xy 89.999079 -221.462854) (xy 89.947941 -221.454755)
			(xy 89.898701 -221.438756) (xy 89.852569 -221.41525) (xy 89.810682 -221.384818) (xy 89.774072 -221.348208)
			(xy 89.74364 -221.306321) (xy 89.720134 -221.260189) (xy 89.704135 -221.210949) (xy 89.696036 -221.159811)
			(xy 89.695528 -221.133924) (xy 89.414604 -221.133924) (xy 89.41408 -221.161632) (xy 89.404881 -221.216279)
			(xy 89.396316 -221.242636) (xy 89.388442 -221.264734) (xy 89.59342 -221.619572) (xy 89.61628 -221.62389)
			(xy 89.641105 -221.629041) (xy 89.688883 -221.645999) (xy 89.733502 -221.670074) (xy 89.773907 -221.700696)
			(xy 89.809147 -221.737145) (xy 89.83839 -221.778561) (xy 89.860947 -221.823965) (xy 89.876285 -221.872289)
			(xy 89.884042 -221.92239) (xy 89.884504 -221.94774) (xy 89.883996 -221.973647) (xy 89.87589 -222.024824)
			(xy 89.859878 -222.074103) (xy 89.836355 -222.12027) (xy 89.805899 -222.162189) (xy 89.769261 -222.198827)
			(xy 89.727342 -222.229283) (xy 89.681175 -222.252806) (xy 89.631896 -222.268818) (xy 89.580719 -222.276924)
			(xy 89.528905 -222.276924) (xy 89.477728 -222.268818) (xy 89.428449 -222.252806) (xy 89.382282 -222.229283)
			(xy 89.340363 -222.198827) (xy 89.303725 -222.162189) (xy 89.273269 -222.12027) (xy 89.249746 -222.074103)
			(xy 89.233734 -222.024824) (xy 89.225628 -221.973647) (xy 89.22512 -221.94774) (xy 89.225723 -221.920023)
			(xy 89.23504 -221.865377) (xy 89.243662 -221.839028) (xy 89.251536 -221.81693) (xy 89.046558 -221.462092)
			(xy 89.023698 -221.457774) (xy 88.998903 -221.45255) (xy 88.951167 -221.435564) (xy 88.906592 -221.411474)
			(xy 88.866227 -221.380847) (xy 88.831024 -221.344405) (xy 88.801811 -221.303006) (xy 88.779276 -221.257625)
			(xy 88.76395 -221.20933) (xy 88.756194 -221.159258) (xy 88.755728 -221.133924) (xy 2.509012 -221.133924)
			(xy 2.509012 -224.389442) (xy 89.695528 -224.389442) (xy 89.695935 -224.364105) (xy 89.703697 -224.314028)
			(xy 89.719029 -224.265728) (xy 89.74157 -224.220343) (xy 89.770789 -224.17894) (xy 89.805999 -224.142496)
			(xy 89.84637 -224.111867) (xy 89.890952 -224.087776) (xy 89.938695 -224.070789) (xy 89.963498 -224.065592)
			(xy 89.986358 -224.061274) (xy 90.191082 -223.706182) (xy 90.183462 -223.684338) (xy 90.174817 -223.657995)
			(xy 90.165504 -223.603345) (xy 90.16492 -223.575626) (xy 90.165428 -223.549719) (xy 90.173534 -223.498542)
			(xy 90.189546 -223.449263) (xy 90.213069 -223.403096) (xy 90.243525 -223.361177) (xy 90.280163 -223.324539)
			(xy 90.322082 -223.294083) (xy 90.368249 -223.27056) (xy 90.417528 -223.254548) (xy 90.468705 -223.246442)
			(xy 90.520519 -223.246442) (xy 90.571696 -223.254548) (xy 90.620975 -223.27056) (xy 90.667142 -223.294083)
			(xy 90.709061 -223.324539) (xy 90.745699 -223.361177) (xy 90.776155 -223.403096) (xy 90.799678 -223.449263)
			(xy 90.81569 -223.498542) (xy 90.823796 -223.549719) (xy 90.824304 -223.575626) (xy 90.823803 -223.60097)
			(xy 90.816028 -223.651059) (xy 90.800679 -223.699368) (xy 90.77812 -223.74476) (xy 90.74888 -223.786165)
			(xy 90.713649 -223.822609) (xy 90.673257 -223.853232) (xy 90.628654 -223.877314) (xy 90.580892 -223.894288)
			(xy 90.55608 -223.899476) (xy 90.53322 -223.903794) (xy 90.328496 -224.258632) (xy 90.336116 -224.280476)
			(xy 90.344672 -224.306769) (xy 90.353865 -224.361289) (xy 90.354404 -224.388934) (xy 90.354404 -224.389442)
			(xy 90.635328 -224.389442) (xy 90.635836 -224.363555) (xy 90.643935 -224.312417) (xy 90.659934 -224.263177)
			(xy 90.68344 -224.217045) (xy 90.713872 -224.175158) (xy 90.750482 -224.138548) (xy 90.792369 -224.108116)
			(xy 90.838501 -224.08461) (xy 90.887741 -224.068611) (xy 90.938879 -224.060512) (xy 90.990653 -224.060512)
			(xy 91.041791 -224.068611) (xy 91.091031 -224.08461) (xy 91.137163 -224.108116) (xy 91.17905 -224.138548)
			(xy 91.21566 -224.175158) (xy 91.246092 -224.217045) (xy 91.269598 -224.263177) (xy 91.285597 -224.312417)
			(xy 91.293696 -224.363555) (xy 91.294204 -224.389442) (xy 91.575128 -224.389442) (xy 91.575535 -224.364105)
			(xy 91.583297 -224.314028) (xy 91.598629 -224.265728) (xy 91.62117 -224.220343) (xy 91.650389 -224.17894)
			(xy 91.685599 -224.142496) (xy 91.72597 -224.111867) (xy 91.770552 -224.087776) (xy 91.818295 -224.070789)
			(xy 91.843098 -224.065592) (xy 91.865958 -224.061274) (xy 92.070682 -223.706182) (xy 92.063062 -223.684338)
			(xy 92.054417 -223.657995) (xy 92.045104 -223.603345) (xy 92.04452 -223.575626) (xy 92.045028 -223.549719)
			(xy 92.053134 -223.498542) (xy 92.069146 -223.449263) (xy 92.092669 -223.403096) (xy 92.123125 -223.361177)
			(xy 92.159763 -223.324539) (xy 92.201682 -223.294083) (xy 92.247849 -223.27056) (xy 92.297128 -223.254548)
			(xy 92.348305 -223.246442) (xy 92.400119 -223.246442) (xy 92.451296 -223.254548) (xy 92.500575 -223.27056)
			(xy 92.546742 -223.294083) (xy 92.588661 -223.324539) (xy 92.625299 -223.361177) (xy 92.655755 -223.403096)
			(xy 92.679278 -223.449263) (xy 92.69529 -223.498542) (xy 92.703396 -223.549719) (xy 92.703904 -223.575626)
			(xy 92.703403 -223.60097) (xy 92.695628 -223.651059) (xy 92.680279 -223.699368) (xy 92.65772 -223.74476)
			(xy 92.62848 -223.786165) (xy 92.593249 -223.822609) (xy 92.552857 -223.853232) (xy 92.508254 -223.877314)
			(xy 92.460492 -223.894288) (xy 92.43568 -223.899476) (xy 92.41282 -223.903794) (xy 92.208096 -224.258632)
			(xy 92.215716 -224.280476) (xy 92.224272 -224.306769) (xy 92.233465 -224.361289) (xy 92.234004 -224.388934)
			(xy 92.234004 -224.389442) (xy 92.514928 -224.389442) (xy 92.515436 -224.363555) (xy 92.523535 -224.312417)
			(xy 92.539534 -224.263177) (xy 92.56304 -224.217045) (xy 92.593472 -224.175158) (xy 92.630082 -224.138548)
			(xy 92.671969 -224.108116) (xy 92.718101 -224.08461) (xy 92.767341 -224.068611) (xy 92.818479 -224.060512)
			(xy 92.870253 -224.060512) (xy 92.921391 -224.068611) (xy 92.970631 -224.08461) (xy 93.016763 -224.108116)
			(xy 93.05865 -224.138548) (xy 93.09526 -224.175158) (xy 93.125692 -224.217045) (xy 93.149198 -224.263177)
			(xy 93.165197 -224.312417) (xy 93.173296 -224.363555) (xy 93.173804 -224.389442) (xy 93.454728 -224.389442)
			(xy 93.455135 -224.364105) (xy 93.462897 -224.314028) (xy 93.478229 -224.265728) (xy 93.50077 -224.220343)
			(xy 93.529989 -224.17894) (xy 93.565199 -224.142496) (xy 93.60557 -224.111867) (xy 93.650152 -224.087776)
			(xy 93.697895 -224.070789) (xy 93.722698 -224.065592) (xy 93.745558 -224.061274) (xy 93.950282 -223.706436)
			(xy 93.942662 -223.684338) (xy 93.934031 -223.657991) (xy 93.92471 -223.603344) (xy 93.92412 -223.575626)
			(xy 93.924628 -223.549719) (xy 93.932734 -223.498542) (xy 93.948746 -223.449263) (xy 93.972269 -223.403096)
			(xy 94.002725 -223.361177) (xy 94.039363 -223.324539) (xy 94.081282 -223.294083) (xy 94.127449 -223.27056)
			(xy 94.176728 -223.254548) (xy 94.227905 -223.246442) (xy 94.279719 -223.246442) (xy 94.330896 -223.254548)
			(xy 94.380175 -223.27056) (xy 94.426342 -223.294083) (xy 94.468261 -223.324539) (xy 94.504899 -223.361177)
			(xy 94.535355 -223.403096) (xy 94.558878 -223.449263) (xy 94.57489 -223.498542) (xy 94.582996 -223.549719)
			(xy 94.583504 -223.575626) (xy 94.583087 -223.600992) (xy 94.575334 -223.651127) (xy 94.559985 -223.69948)
			(xy 94.537403 -223.744908) (xy 94.508122 -223.786336) (xy 94.472834 -223.822783) (xy 94.432375 -223.853388)
			(xy 94.387701 -223.877427) (xy 94.339869 -223.894332) (xy 94.315026 -223.899476) (xy 94.292166 -223.903794)
			(xy 94.087442 -224.258632) (xy 94.095316 -224.280476) (xy 94.10389 -224.306896) (xy 94.11309 -224.36167)
			(xy 94.113604 -224.389442) (xy 94.394528 -224.389442) (xy 94.395036 -224.363555) (xy 94.403135 -224.312417)
			(xy 94.419134 -224.263177) (xy 94.44264 -224.217045) (xy 94.473072 -224.175158) (xy 94.509682 -224.138548)
			(xy 94.551569 -224.108116) (xy 94.597701 -224.08461) (xy 94.646941 -224.068611) (xy 94.698079 -224.060512)
			(xy 94.749853 -224.060512) (xy 94.800991 -224.068611) (xy 94.850231 -224.08461) (xy 94.896363 -224.108116)
			(xy 94.93825 -224.138548) (xy 94.97486 -224.175158) (xy 95.005292 -224.217045) (xy 95.028798 -224.263177)
			(xy 95.044797 -224.312417) (xy 95.052896 -224.363555) (xy 95.053404 -224.389442) (xy 95.334328 -224.389442)
			(xy 95.334735 -224.364105) (xy 95.342497 -224.314028) (xy 95.357829 -224.265728) (xy 95.38037 -224.220343)
			(xy 95.409589 -224.17894) (xy 95.444799 -224.142496) (xy 95.48517 -224.111867) (xy 95.529752 -224.087776)
			(xy 95.577495 -224.070789) (xy 95.602298 -224.065592) (xy 95.625158 -224.061274) (xy 95.829882 -223.706436)
			(xy 95.822262 -223.684338) (xy 95.813631 -223.657991) (xy 95.80431 -223.603344) (xy 95.80372 -223.575626)
			(xy 95.804228 -223.549719) (xy 95.812334 -223.498542) (xy 95.828346 -223.449263) (xy 95.851869 -223.403096)
			(xy 95.882325 -223.361177) (xy 95.918963 -223.324539) (xy 95.960882 -223.294083) (xy 96.007049 -223.27056)
			(xy 96.056328 -223.254548) (xy 96.107505 -223.246442) (xy 96.159319 -223.246442) (xy 96.210496 -223.254548)
			(xy 96.259775 -223.27056) (xy 96.305942 -223.294083) (xy 96.347861 -223.324539) (xy 96.384499 -223.361177)
			(xy 96.414955 -223.403096) (xy 96.438478 -223.449263) (xy 96.45449 -223.498542) (xy 96.462596 -223.549719)
			(xy 96.463104 -223.575626) (xy 96.462687 -223.600992) (xy 96.454934 -223.651127) (xy 96.439585 -223.69948)
			(xy 96.417003 -223.744908) (xy 96.387722 -223.786336) (xy 96.352434 -223.822783) (xy 96.311975 -223.853388)
			(xy 96.267301 -223.877427) (xy 96.219469 -223.894332) (xy 96.194626 -223.899476) (xy 96.171766 -223.903794)
			(xy 95.967042 -224.258632) (xy 95.974916 -224.280476) (xy 95.98349 -224.306896) (xy 95.99269 -224.36167)
			(xy 95.993204 -224.389442) (xy 96.274128 -224.389442) (xy 96.274636 -224.363555) (xy 96.282735 -224.312417)
			(xy 96.298734 -224.263177) (xy 96.32224 -224.217045) (xy 96.352672 -224.175158) (xy 96.389282 -224.138548)
			(xy 96.431169 -224.108116) (xy 96.477301 -224.08461) (xy 96.526541 -224.068611) (xy 96.577679 -224.060512)
			(xy 96.629453 -224.060512) (xy 96.680591 -224.068611) (xy 96.729831 -224.08461) (xy 96.775963 -224.108116)
			(xy 96.81785 -224.138548) (xy 96.85446 -224.175158) (xy 96.884892 -224.217045) (xy 96.908398 -224.263177)
			(xy 96.924397 -224.312417) (xy 96.932496 -224.363555) (xy 96.933004 -224.389442) (xy 97.213928 -224.389442)
			(xy 97.214335 -224.364105) (xy 97.222097 -224.314028) (xy 97.237429 -224.265728) (xy 97.25997 -224.220343)
			(xy 97.289189 -224.17894) (xy 97.324399 -224.142496) (xy 97.36477 -224.111867) (xy 97.409352 -224.087776)
			(xy 97.457095 -224.070789) (xy 97.481898 -224.065592) (xy 97.504758 -224.061274) (xy 97.709482 -223.706436)
			(xy 97.701862 -223.684338) (xy 97.693231 -223.657991) (xy 97.68391 -223.603344) (xy 97.68332 -223.575626)
			(xy 97.683828 -223.549719) (xy 97.691934 -223.498542) (xy 97.707946 -223.449263) (xy 97.731469 -223.403096)
			(xy 97.761925 -223.361177) (xy 97.798563 -223.324539) (xy 97.840482 -223.294083) (xy 97.886649 -223.27056)
			(xy 97.935928 -223.254548) (xy 97.987105 -223.246442) (xy 98.038919 -223.246442) (xy 98.090096 -223.254548)
			(xy 98.139375 -223.27056) (xy 98.185542 -223.294083) (xy 98.227461 -223.324539) (xy 98.264099 -223.361177)
			(xy 98.294555 -223.403096) (xy 98.318078 -223.449263) (xy 98.33409 -223.498542) (xy 98.342196 -223.549719)
			(xy 98.342704 -223.575626) (xy 98.342287 -223.600992) (xy 98.334534 -223.651127) (xy 98.319185 -223.69948)
			(xy 98.296603 -223.744908) (xy 98.267322 -223.786336) (xy 98.232034 -223.822783) (xy 98.191575 -223.853388)
			(xy 98.146901 -223.877427) (xy 98.099069 -223.894332) (xy 98.074226 -223.899476) (xy 98.051366 -223.903794)
			(xy 97.846642 -224.258632) (xy 97.854516 -224.280476) (xy 97.86309 -224.306896) (xy 97.87229 -224.36167)
			(xy 97.872804 -224.389442) (xy 98.153728 -224.389442) (xy 98.154236 -224.363555) (xy 98.162335 -224.312417)
			(xy 98.178334 -224.263177) (xy 98.20184 -224.217045) (xy 98.232272 -224.175158) (xy 98.268882 -224.138548)
			(xy 98.310769 -224.108116) (xy 98.356901 -224.08461) (xy 98.406141 -224.068611) (xy 98.457279 -224.060512)
			(xy 98.509053 -224.060512) (xy 98.560191 -224.068611) (xy 98.609431 -224.08461) (xy 98.655563 -224.108116)
			(xy 98.69745 -224.138548) (xy 98.73406 -224.175158) (xy 98.764492 -224.217045) (xy 98.787998 -224.263177)
			(xy 98.803997 -224.312417) (xy 98.812096 -224.363555) (xy 98.812604 -224.389442) (xy 99.093528 -224.389442)
			(xy 99.093935 -224.364105) (xy 99.101697 -224.314028) (xy 99.117029 -224.265728) (xy 99.13957 -224.220343)
			(xy 99.168789 -224.17894) (xy 99.203999 -224.142496) (xy 99.24437 -224.111867) (xy 99.288952 -224.087776)
			(xy 99.336695 -224.070789) (xy 99.361498 -224.065592) (xy 99.384358 -224.061274) (xy 99.589082 -223.706436)
			(xy 99.581462 -223.684338) (xy 99.572831 -223.657991) (xy 99.56351 -223.603344) (xy 99.56292 -223.575626)
			(xy 99.563428 -223.549719) (xy 99.571534 -223.498542) (xy 99.587546 -223.449263) (xy 99.611069 -223.403096)
			(xy 99.641525 -223.361177) (xy 99.678163 -223.324539) (xy 99.720082 -223.294083) (xy 99.766249 -223.27056)
			(xy 99.815528 -223.254548) (xy 99.866705 -223.246442) (xy 99.918519 -223.246442) (xy 99.969696 -223.254548)
			(xy 100.018975 -223.27056) (xy 100.065142 -223.294083) (xy 100.107061 -223.324539) (xy 100.143699 -223.361177)
			(xy 100.174155 -223.403096) (xy 100.197678 -223.449263) (xy 100.21369 -223.498542) (xy 100.221796 -223.549719)
			(xy 100.222304 -223.575626) (xy 100.221887 -223.600992) (xy 100.214134 -223.651127) (xy 100.198785 -223.69948)
			(xy 100.176203 -223.744908) (xy 100.146922 -223.786336) (xy 100.111634 -223.822783) (xy 100.071175 -223.853388)
			(xy 100.026501 -223.877427) (xy 99.978669 -223.894332) (xy 99.953826 -223.899476) (xy 99.930966 -223.903794)
			(xy 99.726242 -224.258632) (xy 99.734116 -224.280476) (xy 99.74269 -224.306896) (xy 99.75189 -224.36167)
			(xy 99.752404 -224.389442) (xy 100.033328 -224.389442) (xy 100.033836 -224.363555) (xy 100.041935 -224.312417)
			(xy 100.057934 -224.263177) (xy 100.08144 -224.217045) (xy 100.111872 -224.175158) (xy 100.148482 -224.138548)
			(xy 100.190369 -224.108116) (xy 100.236501 -224.08461) (xy 100.285741 -224.068611) (xy 100.336879 -224.060512)
			(xy 100.388653 -224.060512) (xy 100.439791 -224.068611) (xy 100.489031 -224.08461) (xy 100.535163 -224.108116)
			(xy 100.57705 -224.138548) (xy 100.61366 -224.175158) (xy 100.644092 -224.217045) (xy 100.667598 -224.263177)
			(xy 100.683597 -224.312417) (xy 100.691696 -224.363555) (xy 100.692204 -224.389442) (xy 100.973128 -224.389442)
			(xy 100.973535 -224.364105) (xy 100.981297 -224.314028) (xy 100.996629 -224.265728) (xy 101.01917 -224.220343)
			(xy 101.048389 -224.17894) (xy 101.083599 -224.142496) (xy 101.12397 -224.111867) (xy 101.168552 -224.087776)
			(xy 101.216295 -224.070789) (xy 101.241098 -224.065592) (xy 101.263958 -224.061274) (xy 101.468682 -223.706436)
			(xy 101.461062 -223.684338) (xy 101.452431 -223.657991) (xy 101.44311 -223.603344) (xy 101.44252 -223.575626)
			(xy 101.443028 -223.549719) (xy 101.451134 -223.498542) (xy 101.467146 -223.449263) (xy 101.490669 -223.403096)
			(xy 101.521125 -223.361177) (xy 101.557763 -223.324539) (xy 101.599682 -223.294083) (xy 101.645849 -223.27056)
			(xy 101.695128 -223.254548) (xy 101.746305 -223.246442) (xy 101.798119 -223.246442) (xy 101.849296 -223.254548)
			(xy 101.898575 -223.27056) (xy 101.944742 -223.294083) (xy 101.986661 -223.324539) (xy 102.023299 -223.361177)
			(xy 102.053755 -223.403096) (xy 102.077278 -223.449263) (xy 102.09329 -223.498542) (xy 102.101396 -223.549719)
			(xy 102.101904 -223.575626) (xy 102.101487 -223.600992) (xy 102.093734 -223.651127) (xy 102.078385 -223.69948)
			(xy 102.055803 -223.744908) (xy 102.026522 -223.786336) (xy 101.991234 -223.822783) (xy 101.950775 -223.853388)
			(xy 101.906101 -223.877427) (xy 101.858269 -223.894332) (xy 101.833426 -223.899476) (xy 101.810566 -223.903794)
			(xy 101.605842 -224.258632) (xy 101.613716 -224.280476) (xy 101.62229 -224.306896) (xy 101.63149 -224.36167)
			(xy 101.632004 -224.389442) (xy 101.912928 -224.389442) (xy 101.913436 -224.363555) (xy 101.921535 -224.312417)
			(xy 101.937534 -224.263177) (xy 101.96104 -224.217045) (xy 101.991472 -224.175158) (xy 102.028082 -224.138548)
			(xy 102.069969 -224.108116) (xy 102.116101 -224.08461) (xy 102.165341 -224.068611) (xy 102.216479 -224.060512)
			(xy 102.268253 -224.060512) (xy 102.319391 -224.068611) (xy 102.368631 -224.08461) (xy 102.414763 -224.108116)
			(xy 102.45665 -224.138548) (xy 102.49326 -224.175158) (xy 102.523692 -224.217045) (xy 102.547198 -224.263177)
			(xy 102.563197 -224.312417) (xy 102.571296 -224.363555) (xy 102.571804 -224.389442) (xy 102.852728 -224.389442)
			(xy 102.853135 -224.364105) (xy 102.860897 -224.314028) (xy 102.876229 -224.265728) (xy 102.89877 -224.220343)
			(xy 102.927989 -224.17894) (xy 102.963199 -224.142496) (xy 103.00357 -224.111867) (xy 103.048152 -224.087776)
			(xy 103.095895 -224.070789) (xy 103.120698 -224.065592) (xy 103.143558 -224.061274) (xy 103.348282 -223.706436)
			(xy 103.340662 -223.684338) (xy 103.332031 -223.657991) (xy 103.32271 -223.603344) (xy 103.32212 -223.575626)
			(xy 103.322628 -223.549719) (xy 103.330734 -223.498542) (xy 103.346746 -223.449263) (xy 103.370269 -223.403096)
			(xy 103.400725 -223.361177) (xy 103.437363 -223.324539) (xy 103.479282 -223.294083) (xy 103.525449 -223.27056)
			(xy 103.574728 -223.254548) (xy 103.625905 -223.246442) (xy 103.677719 -223.246442) (xy 103.728896 -223.254548)
			(xy 103.778175 -223.27056) (xy 103.824342 -223.294083) (xy 103.866261 -223.324539) (xy 103.902899 -223.361177)
			(xy 103.933355 -223.403096) (xy 103.956878 -223.449263) (xy 103.97289 -223.498542) (xy 103.980996 -223.549719)
			(xy 103.981504 -223.575626) (xy 103.981087 -223.600992) (xy 103.973334 -223.651127) (xy 103.957985 -223.69948)
			(xy 103.935403 -223.744908) (xy 103.906122 -223.786336) (xy 103.870834 -223.822783) (xy 103.830375 -223.853388)
			(xy 103.785701 -223.877427) (xy 103.737869 -223.894332) (xy 103.713026 -223.899476) (xy 103.690166 -223.903794)
			(xy 103.485442 -224.258632) (xy 103.493316 -224.280476) (xy 103.50189 -224.306896) (xy 103.51109 -224.36167)
			(xy 103.511604 -224.389442) (xy 103.792528 -224.389442) (xy 103.793036 -224.363555) (xy 103.801135 -224.312417)
			(xy 103.817134 -224.263177) (xy 103.84064 -224.217045) (xy 103.871072 -224.175158) (xy 103.907682 -224.138548)
			(xy 103.949569 -224.108116) (xy 103.995701 -224.08461) (xy 104.044941 -224.068611) (xy 104.096079 -224.060512)
			(xy 104.147853 -224.060512) (xy 104.198991 -224.068611) (xy 104.248231 -224.08461) (xy 104.294363 -224.108116)
			(xy 104.33625 -224.138548) (xy 104.37286 -224.175158) (xy 104.403292 -224.217045) (xy 104.426798 -224.263177)
			(xy 104.442797 -224.312417) (xy 104.450896 -224.363555) (xy 104.451404 -224.389442) (xy 104.732328 -224.389442)
			(xy 104.732735 -224.364105) (xy 104.740497 -224.314028) (xy 104.755829 -224.265728) (xy 104.77837 -224.220343)
			(xy 104.807589 -224.17894) (xy 104.842799 -224.142496) (xy 104.88317 -224.111867) (xy 104.927752 -224.087776)
			(xy 104.975495 -224.070789) (xy 105.000298 -224.065592) (xy 105.023158 -224.061274) (xy 105.227882 -223.706436)
			(xy 105.220262 -223.684338) (xy 105.211631 -223.657991) (xy 105.20231 -223.603344) (xy 105.20172 -223.575626)
			(xy 105.202228 -223.549719) (xy 105.210334 -223.498542) (xy 105.226346 -223.449263) (xy 105.249869 -223.403096)
			(xy 105.280325 -223.361177) (xy 105.316963 -223.324539) (xy 105.358882 -223.294083) (xy 105.405049 -223.27056)
			(xy 105.454328 -223.254548) (xy 105.505505 -223.246442) (xy 105.557319 -223.246442) (xy 105.608496 -223.254548)
			(xy 105.657775 -223.27056) (xy 105.703942 -223.294083) (xy 105.745861 -223.324539) (xy 105.782499 -223.361177)
			(xy 105.812955 -223.403096) (xy 105.836478 -223.449263) (xy 105.85249 -223.498542) (xy 105.860596 -223.549719)
			(xy 105.861104 -223.575626) (xy 105.860687 -223.600992) (xy 105.852934 -223.651127) (xy 105.837585 -223.69948)
			(xy 105.815003 -223.744908) (xy 105.785722 -223.786336) (xy 105.750434 -223.822783) (xy 105.709975 -223.853388)
			(xy 105.665301 -223.877427) (xy 105.617469 -223.894332) (xy 105.592626 -223.899476) (xy 105.569766 -223.903794)
			(xy 105.365042 -224.258632) (xy 105.372916 -224.280476) (xy 105.38149 -224.306896) (xy 105.39069 -224.36167)
			(xy 105.391204 -224.389442) (xy 105.672128 -224.389442) (xy 105.672636 -224.363555) (xy 105.680735 -224.312417)
			(xy 105.696734 -224.263177) (xy 105.72024 -224.217045) (xy 105.750672 -224.175158) (xy 105.787282 -224.138548)
			(xy 105.829169 -224.108116) (xy 105.875301 -224.08461) (xy 105.924541 -224.068611) (xy 105.975679 -224.060512)
			(xy 106.027453 -224.060512) (xy 106.078591 -224.068611) (xy 106.127831 -224.08461) (xy 106.173963 -224.108116)
			(xy 106.21585 -224.138548) (xy 106.25246 -224.175158) (xy 106.282892 -224.217045) (xy 106.306398 -224.263177)
			(xy 106.322397 -224.312417) (xy 106.330496 -224.363555) (xy 106.331004 -224.389442) (xy 106.611928 -224.389442)
			(xy 106.612335 -224.364105) (xy 106.620097 -224.314028) (xy 106.635429 -224.265728) (xy 106.65797 -224.220343)
			(xy 106.687189 -224.17894) (xy 106.722399 -224.142496) (xy 106.76277 -224.111867) (xy 106.807352 -224.087776)
			(xy 106.855095 -224.070789) (xy 106.879898 -224.065592) (xy 106.902758 -224.061274) (xy 107.107482 -223.706436)
			(xy 107.099862 -223.684338) (xy 107.091231 -223.657991) (xy 107.08191 -223.603344) (xy 107.08132 -223.575626)
			(xy 107.081828 -223.549719) (xy 107.089934 -223.498542) (xy 107.105946 -223.449263) (xy 107.129469 -223.403096)
			(xy 107.159925 -223.361177) (xy 107.196563 -223.324539) (xy 107.238482 -223.294083) (xy 107.284649 -223.27056)
			(xy 107.333928 -223.254548) (xy 107.385105 -223.246442) (xy 107.436919 -223.246442) (xy 107.488096 -223.254548)
			(xy 107.537375 -223.27056) (xy 107.583542 -223.294083) (xy 107.625461 -223.324539) (xy 107.662099 -223.361177)
			(xy 107.692555 -223.403096) (xy 107.716078 -223.449263) (xy 107.73209 -223.498542) (xy 107.740196 -223.549719)
			(xy 107.740704 -223.575626) (xy 107.740287 -223.600992) (xy 107.732534 -223.651127) (xy 107.717185 -223.69948)
			(xy 107.694603 -223.744908) (xy 107.665322 -223.786336) (xy 107.630034 -223.822783) (xy 107.589575 -223.853388)
			(xy 107.544901 -223.877427) (xy 107.497069 -223.894332) (xy 107.472226 -223.899476) (xy 107.449366 -223.903794)
			(xy 107.244642 -224.258632) (xy 107.252516 -224.280476) (xy 107.26109 -224.306896) (xy 107.27029 -224.36167)
			(xy 107.270804 -224.389442) (xy 107.551728 -224.389442) (xy 107.552236 -224.363555) (xy 107.560335 -224.312417)
			(xy 107.576334 -224.263177) (xy 107.59984 -224.217045) (xy 107.630272 -224.175158) (xy 107.666882 -224.138548)
			(xy 107.708769 -224.108116) (xy 107.754901 -224.08461) (xy 107.804141 -224.068611) (xy 107.855279 -224.060512)
			(xy 107.907053 -224.060512) (xy 107.958191 -224.068611) (xy 108.007431 -224.08461) (xy 108.053563 -224.108116)
			(xy 108.09545 -224.138548) (xy 108.13206 -224.175158) (xy 108.162492 -224.217045) (xy 108.185998 -224.263177)
			(xy 108.201997 -224.312417) (xy 108.210096 -224.363555) (xy 108.210604 -224.389442) (xy 108.491528 -224.389442)
			(xy 108.491935 -224.364105) (xy 108.499697 -224.314028) (xy 108.515029 -224.265728) (xy 108.53757 -224.220343)
			(xy 108.566789 -224.17894) (xy 108.601999 -224.142496) (xy 108.64237 -224.111867) (xy 108.686952 -224.087776)
			(xy 108.734695 -224.070789) (xy 108.759498 -224.065592) (xy 108.782358 -224.061274) (xy 108.987082 -223.706436)
			(xy 108.979462 -223.684338) (xy 108.970831 -223.657991) (xy 108.96151 -223.603344) (xy 108.96092 -223.575626)
			(xy 108.961428 -223.549719) (xy 108.969534 -223.498542) (xy 108.985546 -223.449263) (xy 109.009069 -223.403096)
			(xy 109.039525 -223.361177) (xy 109.076163 -223.324539) (xy 109.118082 -223.294083) (xy 109.164249 -223.27056)
			(xy 109.213528 -223.254548) (xy 109.264705 -223.246442) (xy 109.316519 -223.246442) (xy 109.367696 -223.254548)
			(xy 109.416975 -223.27056) (xy 109.463142 -223.294083) (xy 109.505061 -223.324539) (xy 109.541699 -223.361177)
			(xy 109.572155 -223.403096) (xy 109.595678 -223.449263) (xy 109.61169 -223.498542) (xy 109.619796 -223.549719)
			(xy 109.620304 -223.575626) (xy 109.619887 -223.600992) (xy 109.612134 -223.651127) (xy 109.596785 -223.69948)
			(xy 109.574203 -223.744908) (xy 109.544922 -223.786336) (xy 109.509634 -223.822783) (xy 109.469175 -223.853388)
			(xy 109.424501 -223.877427) (xy 109.376669 -223.894332) (xy 109.351826 -223.899476) (xy 109.328966 -223.903794)
			(xy 109.124242 -224.258632) (xy 109.132116 -224.280476) (xy 109.14069 -224.306896) (xy 109.14989 -224.36167)
			(xy 109.150404 -224.389442) (xy 109.431328 -224.389442) (xy 109.431836 -224.363555) (xy 109.439935 -224.312417)
			(xy 109.455934 -224.263177) (xy 109.47944 -224.217045) (xy 109.509872 -224.175158) (xy 109.546482 -224.138548)
			(xy 109.588369 -224.108116) (xy 109.634501 -224.08461) (xy 109.683741 -224.068611) (xy 109.734879 -224.060512)
			(xy 109.786653 -224.060512) (xy 109.837791 -224.068611) (xy 109.887031 -224.08461) (xy 109.933163 -224.108116)
			(xy 109.97505 -224.138548) (xy 110.01166 -224.175158) (xy 110.042092 -224.217045) (xy 110.065598 -224.263177)
			(xy 110.081597 -224.312417) (xy 110.089696 -224.363555) (xy 110.090204 -224.389442) (xy 110.371128 -224.389442)
			(xy 110.371535 -224.364105) (xy 110.379297 -224.314028) (xy 110.394629 -224.265728) (xy 110.41717 -224.220343)
			(xy 110.446389 -224.17894) (xy 110.481599 -224.142496) (xy 110.52197 -224.111867) (xy 110.566552 -224.087776)
			(xy 110.614295 -224.070789) (xy 110.639098 -224.065592) (xy 110.661958 -224.061274) (xy 110.866682 -223.706436)
			(xy 110.859062 -223.684338) (xy 110.850431 -223.657991) (xy 110.84111 -223.603344) (xy 110.84052 -223.575626)
			(xy 110.841028 -223.549719) (xy 110.849134 -223.498542) (xy 110.865146 -223.449263) (xy 110.888669 -223.403096)
			(xy 110.919125 -223.361177) (xy 110.955763 -223.324539) (xy 110.997682 -223.294083) (xy 111.043849 -223.27056)
			(xy 111.093128 -223.254548) (xy 111.144305 -223.246442) (xy 111.196119 -223.246442) (xy 111.247296 -223.254548)
			(xy 111.296575 -223.27056) (xy 111.342742 -223.294083) (xy 111.384661 -223.324539) (xy 111.421299 -223.361177)
			(xy 111.451755 -223.403096) (xy 111.475278 -223.449263) (xy 111.49129 -223.498542) (xy 111.499396 -223.549719)
			(xy 111.499904 -223.575626) (xy 111.499487 -223.600992) (xy 111.491734 -223.651127) (xy 111.476385 -223.69948)
			(xy 111.453803 -223.744908) (xy 111.424522 -223.786336) (xy 111.389234 -223.822783) (xy 111.348775 -223.853388)
			(xy 111.304101 -223.877427) (xy 111.256269 -223.894332) (xy 111.231426 -223.899476) (xy 111.208566 -223.903794)
			(xy 111.003842 -224.258632) (xy 111.011716 -224.280476) (xy 111.02029 -224.306896) (xy 111.02949 -224.36167)
			(xy 111.030004 -224.389442) (xy 111.310928 -224.389442) (xy 111.311436 -224.363555) (xy 111.319535 -224.312417)
			(xy 111.335534 -224.263177) (xy 111.35904 -224.217045) (xy 111.389472 -224.175158) (xy 111.426082 -224.138548)
			(xy 111.467969 -224.108116) (xy 111.514101 -224.08461) (xy 111.563341 -224.068611) (xy 111.614479 -224.060512)
			(xy 111.666253 -224.060512) (xy 111.717391 -224.068611) (xy 111.766631 -224.08461) (xy 111.812763 -224.108116)
			(xy 111.85465 -224.138548) (xy 111.89126 -224.175158) (xy 111.921692 -224.217045) (xy 111.945198 -224.263177)
			(xy 111.961197 -224.312417) (xy 111.969296 -224.363555) (xy 111.969804 -224.389442) (xy 112.250728 -224.389442)
			(xy 112.251135 -224.364105) (xy 112.258897 -224.314028) (xy 112.274229 -224.265728) (xy 112.29677 -224.220343)
			(xy 112.325989 -224.17894) (xy 112.361199 -224.142496) (xy 112.40157 -224.111867) (xy 112.446152 -224.087776)
			(xy 112.493895 -224.070789) (xy 112.518698 -224.065592) (xy 112.541558 -224.061274) (xy 112.746282 -223.706436)
			(xy 112.738662 -223.684338) (xy 112.730031 -223.657991) (xy 112.72071 -223.603344) (xy 112.72012 -223.575626)
			(xy 112.720628 -223.549719) (xy 112.728734 -223.498542) (xy 112.744746 -223.449263) (xy 112.768269 -223.403096)
			(xy 112.798725 -223.361177) (xy 112.835363 -223.324539) (xy 112.877282 -223.294083) (xy 112.923449 -223.27056)
			(xy 112.972728 -223.254548) (xy 113.023905 -223.246442) (xy 113.075719 -223.246442) (xy 113.126896 -223.254548)
			(xy 113.176175 -223.27056) (xy 113.222342 -223.294083) (xy 113.264261 -223.324539) (xy 113.300899 -223.361177)
			(xy 113.331355 -223.403096) (xy 113.354878 -223.449263) (xy 113.37089 -223.498542) (xy 113.378996 -223.549719)
			(xy 113.379504 -223.575626) (xy 113.379087 -223.600992) (xy 113.371334 -223.651127) (xy 113.355985 -223.69948)
			(xy 113.333403 -223.744908) (xy 113.304122 -223.786336) (xy 113.268834 -223.822783) (xy 113.228375 -223.853388)
			(xy 113.183701 -223.877427) (xy 113.135869 -223.894332) (xy 113.111026 -223.899476) (xy 113.088166 -223.903794)
			(xy 112.883442 -224.258632) (xy 112.891316 -224.280476) (xy 112.89989 -224.306896) (xy 112.90909 -224.36167)
			(xy 112.909604 -224.389442) (xy 113.190528 -224.389442) (xy 113.191036 -224.363555) (xy 113.199135 -224.312417)
			(xy 113.215134 -224.263177) (xy 113.23864 -224.217045) (xy 113.269072 -224.175158) (xy 113.305682 -224.138548)
			(xy 113.347569 -224.108116) (xy 113.393701 -224.08461) (xy 113.442941 -224.068611) (xy 113.494079 -224.060512)
			(xy 113.545853 -224.060512) (xy 113.596991 -224.068611) (xy 113.646231 -224.08461) (xy 113.692363 -224.108116)
			(xy 113.73425 -224.138548) (xy 113.77086 -224.175158) (xy 113.801292 -224.217045) (xy 113.824798 -224.263177)
			(xy 113.840797 -224.312417) (xy 113.848896 -224.363555) (xy 113.849404 -224.389442) (xy 114.130328 -224.389442)
			(xy 114.130735 -224.364105) (xy 114.138497 -224.314028) (xy 114.153829 -224.265728) (xy 114.17637 -224.220343)
			(xy 114.205589 -224.17894) (xy 114.240799 -224.142496) (xy 114.28117 -224.111867) (xy 114.325752 -224.087776)
			(xy 114.373495 -224.070789) (xy 114.398298 -224.065592) (xy 114.421158 -224.061274) (xy 114.626136 -223.706182)
			(xy 114.618516 -223.684084) (xy 114.609997 -223.657912) (xy 114.600803 -223.603651) (xy 114.600228 -223.576134)
			(xy 114.600228 -223.575626) (xy 114.600736 -223.549739) (xy 114.608835 -223.498601) (xy 114.624834 -223.449361)
			(xy 114.64834 -223.403229) (xy 114.678772 -223.361342) (xy 114.715382 -223.324732) (xy 114.757269 -223.2943)
			(xy 114.803401 -223.270794) (xy 114.852641 -223.254795) (xy 114.903779 -223.246696) (xy 114.955553 -223.246696)
			(xy 115.006691 -223.254795) (xy 115.055931 -223.270794) (xy 115.102063 -223.2943) (xy 115.14395 -223.324732)
			(xy 115.18056 -223.361342) (xy 115.210992 -223.403229) (xy 115.234498 -223.449361) (xy 115.250497 -223.498601)
			(xy 115.258596 -223.549739) (xy 115.259104 -223.575626) (xy 115.258687 -223.600992) (xy 115.250934 -223.651127)
			(xy 115.235585 -223.69948) (xy 115.213003 -223.744908) (xy 115.183722 -223.786336) (xy 115.148434 -223.822783)
			(xy 115.107975 -223.853388) (xy 115.063301 -223.877427) (xy 115.015469 -223.894332) (xy 114.990626 -223.899476)
			(xy 114.967766 -223.903794) (xy 114.763042 -224.258632) (xy 114.770916 -224.280476) (xy 114.77949 -224.306896)
			(xy 114.78869 -224.36167) (xy 114.789204 -224.389442) (xy 115.070128 -224.389442) (xy 115.070636 -224.363555)
			(xy 115.078735 -224.312417) (xy 115.094734 -224.263177) (xy 115.11824 -224.217045) (xy 115.148672 -224.175158)
			(xy 115.185282 -224.138548) (xy 115.227169 -224.108116) (xy 115.273301 -224.08461) (xy 115.322541 -224.068611)
			(xy 115.373679 -224.060512) (xy 115.425453 -224.060512) (xy 115.476591 -224.068611) (xy 115.525831 -224.08461)
			(xy 115.571963 -224.108116) (xy 115.61385 -224.138548) (xy 115.65046 -224.175158) (xy 115.680892 -224.217045)
			(xy 115.704398 -224.263177) (xy 115.720397 -224.312417) (xy 115.728496 -224.363555) (xy 115.729004 -224.389442)
			(xy 116.009928 -224.389442) (xy 116.010335 -224.364105) (xy 116.018097 -224.314028) (xy 116.033429 -224.265728)
			(xy 116.05597 -224.220343) (xy 116.085189 -224.17894) (xy 116.120399 -224.142496) (xy 116.16077 -224.111867)
			(xy 116.205352 -224.087776) (xy 116.253095 -224.070789) (xy 116.277898 -224.065592) (xy 116.300758 -224.061274)
			(xy 116.505482 -223.706436) (xy 116.497862 -223.684338) (xy 116.489231 -223.657991) (xy 116.47991 -223.603344)
			(xy 116.47932 -223.575626) (xy 116.479828 -223.549719) (xy 116.487934 -223.498542) (xy 116.503946 -223.449263)
			(xy 116.527469 -223.403096) (xy 116.557925 -223.361177) (xy 116.594563 -223.324539) (xy 116.636482 -223.294083)
			(xy 116.682649 -223.27056) (xy 116.731928 -223.254548) (xy 116.783105 -223.246442) (xy 116.834919 -223.246442)
			(xy 116.886096 -223.254548) (xy 116.935375 -223.27056) (xy 116.981542 -223.294083) (xy 117.023461 -223.324539)
			(xy 117.060099 -223.361177) (xy 117.090555 -223.403096) (xy 117.114078 -223.449263) (xy 117.13009 -223.498542)
			(xy 117.138196 -223.549719) (xy 117.138704 -223.575626) (xy 117.138287 -223.600992) (xy 117.130534 -223.651127)
			(xy 117.115185 -223.69948) (xy 117.092603 -223.744908) (xy 117.063322 -223.786336) (xy 117.028034 -223.822783)
			(xy 116.987575 -223.853388) (xy 116.942901 -223.877427) (xy 116.895069 -223.894332) (xy 116.870226 -223.899476)
			(xy 116.847366 -223.903794) (xy 116.642642 -224.258632) (xy 116.650516 -224.280476) (xy 116.65909 -224.306896)
			(xy 116.66829 -224.36167) (xy 116.668804 -224.389442) (xy 116.949728 -224.389442) (xy 116.950236 -224.363555)
			(xy 116.958335 -224.312417) (xy 116.974334 -224.263177) (xy 116.99784 -224.217045) (xy 117.028272 -224.175158)
			(xy 117.064882 -224.138548) (xy 117.106769 -224.108116) (xy 117.152901 -224.08461) (xy 117.202141 -224.068611)
			(xy 117.253279 -224.060512) (xy 117.305053 -224.060512) (xy 117.356191 -224.068611) (xy 117.405431 -224.08461)
			(xy 117.451563 -224.108116) (xy 117.49345 -224.138548) (xy 117.53006 -224.175158) (xy 117.560492 -224.217045)
			(xy 117.583998 -224.263177) (xy 117.599997 -224.312417) (xy 117.608096 -224.363555) (xy 117.608604 -224.389442)
			(xy 117.889528 -224.389442) (xy 117.889935 -224.364105) (xy 117.897697 -224.314028) (xy 117.913029 -224.265728)
			(xy 117.93557 -224.220343) (xy 117.964789 -224.17894) (xy 117.999999 -224.142496) (xy 118.04037 -224.111867)
			(xy 118.084952 -224.087776) (xy 118.132695 -224.070789) (xy 118.157498 -224.065592) (xy 118.180358 -224.061274)
			(xy 118.385082 -223.706436) (xy 118.377462 -223.684338) (xy 118.368831 -223.657991) (xy 118.35951 -223.603344)
			(xy 118.35892 -223.575626) (xy 118.359428 -223.549719) (xy 118.367534 -223.498542) (xy 118.383546 -223.449263)
			(xy 118.407069 -223.403096) (xy 118.437525 -223.361177) (xy 118.474163 -223.324539) (xy 118.516082 -223.294083)
			(xy 118.562249 -223.27056) (xy 118.611528 -223.254548) (xy 118.662705 -223.246442) (xy 118.714519 -223.246442)
			(xy 118.765696 -223.254548) (xy 118.814975 -223.27056) (xy 118.861142 -223.294083) (xy 118.903061 -223.324539)
			(xy 118.939699 -223.361177) (xy 118.970155 -223.403096) (xy 118.993678 -223.449263) (xy 119.00969 -223.498542)
			(xy 119.017796 -223.549719) (xy 119.018304 -223.575626) (xy 119.017887 -223.600992) (xy 119.010134 -223.651127)
			(xy 118.994785 -223.69948) (xy 118.972203 -223.744908) (xy 118.942922 -223.786336) (xy 118.907634 -223.822783)
			(xy 118.867175 -223.853388) (xy 118.822501 -223.877427) (xy 118.774669 -223.894332) (xy 118.749826 -223.899476)
			(xy 118.726966 -223.903794) (xy 118.522242 -224.258632) (xy 118.530116 -224.280476) (xy 118.53869 -224.306896)
			(xy 118.54789 -224.36167) (xy 118.548404 -224.389442) (xy 118.829328 -224.389442) (xy 118.829836 -224.363555)
			(xy 118.837935 -224.312417) (xy 118.853934 -224.263177) (xy 118.87744 -224.217045) (xy 118.907872 -224.175158)
			(xy 118.944482 -224.138548) (xy 118.986369 -224.108116) (xy 119.032501 -224.08461) (xy 119.081741 -224.068611)
			(xy 119.132879 -224.060512) (xy 119.184653 -224.060512) (xy 119.235791 -224.068611) (xy 119.285031 -224.08461)
			(xy 119.331163 -224.108116) (xy 119.37305 -224.138548) (xy 119.40966 -224.175158) (xy 119.440092 -224.217045)
			(xy 119.463598 -224.263177) (xy 119.479597 -224.312417) (xy 119.487696 -224.363555) (xy 119.488204 -224.389442)
			(xy 119.769128 -224.389442) (xy 119.769535 -224.364105) (xy 119.777297 -224.314028) (xy 119.792629 -224.265728)
			(xy 119.81517 -224.220343) (xy 119.844389 -224.17894) (xy 119.879599 -224.142496) (xy 119.91997 -224.111867)
			(xy 119.964552 -224.087776) (xy 120.012295 -224.070789) (xy 120.037098 -224.065592) (xy 120.059958 -224.061274)
			(xy 120.264682 -223.706436) (xy 120.257062 -223.684338) (xy 120.248431 -223.657991) (xy 120.23911 -223.603344)
			(xy 120.23852 -223.575626) (xy 120.239028 -223.549719) (xy 120.247134 -223.498542) (xy 120.263146 -223.449263)
			(xy 120.286669 -223.403096) (xy 120.317125 -223.361177) (xy 120.353763 -223.324539) (xy 120.395682 -223.294083)
			(xy 120.441849 -223.27056) (xy 120.491128 -223.254548) (xy 120.542305 -223.246442) (xy 120.594119 -223.246442)
			(xy 120.645296 -223.254548) (xy 120.694575 -223.27056) (xy 120.740742 -223.294083) (xy 120.782661 -223.324539)
			(xy 120.819299 -223.361177) (xy 120.849755 -223.403096) (xy 120.873278 -223.449263) (xy 120.88929 -223.498542)
			(xy 120.897396 -223.549719) (xy 120.897904 -223.575626) (xy 120.897487 -223.600992) (xy 120.889734 -223.651127)
			(xy 120.874385 -223.69948) (xy 120.851803 -223.744908) (xy 120.822522 -223.786336) (xy 120.787234 -223.822783)
			(xy 120.746775 -223.853388) (xy 120.702101 -223.877427) (xy 120.654269 -223.894332) (xy 120.629426 -223.899476)
			(xy 120.606566 -223.903794) (xy 120.401842 -224.258632) (xy 120.409716 -224.280476) (xy 120.41829 -224.306896)
			(xy 120.42749 -224.36167) (xy 120.428004 -224.389442) (xy 120.708928 -224.389442) (xy 120.709436 -224.363555)
			(xy 120.717535 -224.312417) (xy 120.733534 -224.263177) (xy 120.75704 -224.217045) (xy 120.787472 -224.175158)
			(xy 120.824082 -224.138548) (xy 120.865969 -224.108116) (xy 120.912101 -224.08461) (xy 120.961341 -224.068611)
			(xy 121.012479 -224.060512) (xy 121.064253 -224.060512) (xy 121.115391 -224.068611) (xy 121.164631 -224.08461)
			(xy 121.210763 -224.108116) (xy 121.25265 -224.138548) (xy 121.28926 -224.175158) (xy 121.319692 -224.217045)
			(xy 121.343198 -224.263177) (xy 121.359197 -224.312417) (xy 121.367296 -224.363555) (xy 121.367804 -224.389442)
			(xy 121.648728 -224.389442) (xy 121.649135 -224.364105) (xy 121.656897 -224.314028) (xy 121.672229 -224.265728)
			(xy 121.69477 -224.220343) (xy 121.723989 -224.17894) (xy 121.759199 -224.142496) (xy 121.79957 -224.111867)
			(xy 121.844152 -224.087776) (xy 121.891895 -224.070789) (xy 121.916698 -224.065592) (xy 121.939558 -224.061274)
			(xy 122.144282 -223.706436) (xy 122.136662 -223.684338) (xy 122.128031 -223.657991) (xy 122.11871 -223.603344)
			(xy 122.11812 -223.575626) (xy 122.118628 -223.549719) (xy 122.126734 -223.498542) (xy 122.142746 -223.449263)
			(xy 122.166269 -223.403096) (xy 122.196725 -223.361177) (xy 122.233363 -223.324539) (xy 122.275282 -223.294083)
			(xy 122.321449 -223.27056) (xy 122.370728 -223.254548) (xy 122.421905 -223.246442) (xy 122.473719 -223.246442)
			(xy 122.524896 -223.254548) (xy 122.574175 -223.27056) (xy 122.620342 -223.294083) (xy 122.662261 -223.324539)
			(xy 122.698899 -223.361177) (xy 122.729355 -223.403096) (xy 122.752878 -223.449263) (xy 122.76889 -223.498542)
			(xy 122.776996 -223.549719) (xy 122.777504 -223.575626) (xy 122.777087 -223.600992) (xy 122.769334 -223.651127)
			(xy 122.753985 -223.69948) (xy 122.731403 -223.744908) (xy 122.702122 -223.786336) (xy 122.666834 -223.822783)
			(xy 122.626375 -223.853388) (xy 122.581701 -223.877427) (xy 122.533869 -223.894332) (xy 122.509026 -223.899476)
			(xy 122.486166 -223.903794) (xy 122.281442 -224.258632) (xy 122.289316 -224.280476) (xy 122.29789 -224.306896)
			(xy 122.30709 -224.36167) (xy 122.307604 -224.389442) (xy 122.588528 -224.389442) (xy 122.589036 -224.363555)
			(xy 122.597135 -224.312417) (xy 122.613134 -224.263177) (xy 122.63664 -224.217045) (xy 122.667072 -224.175158)
			(xy 122.703682 -224.138548) (xy 122.745569 -224.108116) (xy 122.791701 -224.08461) (xy 122.840941 -224.068611)
			(xy 122.892079 -224.060512) (xy 122.943853 -224.060512) (xy 122.994991 -224.068611) (xy 123.044231 -224.08461)
			(xy 123.090363 -224.108116) (xy 123.13225 -224.138548) (xy 123.16886 -224.175158) (xy 123.199292 -224.217045)
			(xy 123.222798 -224.263177) (xy 123.238797 -224.312417) (xy 123.246896 -224.363555) (xy 123.247404 -224.389442)
			(xy 123.528328 -224.389442) (xy 123.528735 -224.364105) (xy 123.536497 -224.314028) (xy 123.551829 -224.265728)
			(xy 123.57437 -224.220343) (xy 123.603589 -224.17894) (xy 123.638799 -224.142496) (xy 123.67917 -224.111867)
			(xy 123.723752 -224.087776) (xy 123.771495 -224.070789) (xy 123.796298 -224.065592) (xy 123.819158 -224.061274)
			(xy 124.023882 -223.706436) (xy 124.016262 -223.684338) (xy 124.007631 -223.657991) (xy 123.99831 -223.603344)
			(xy 123.99772 -223.575626) (xy 123.998228 -223.549719) (xy 124.006334 -223.498542) (xy 124.022346 -223.449263)
			(xy 124.045869 -223.403096) (xy 124.076325 -223.361177) (xy 124.112963 -223.324539) (xy 124.154882 -223.294083)
			(xy 124.201049 -223.27056) (xy 124.250328 -223.254548) (xy 124.301505 -223.246442) (xy 124.353319 -223.246442)
			(xy 124.404496 -223.254548) (xy 124.453775 -223.27056) (xy 124.499942 -223.294083) (xy 124.541861 -223.324539)
			(xy 124.578499 -223.361177) (xy 124.608955 -223.403096) (xy 124.632478 -223.449263) (xy 124.64849 -223.498542)
			(xy 124.656596 -223.549719) (xy 124.657104 -223.575626) (xy 124.656687 -223.600992) (xy 124.648934 -223.651127)
			(xy 124.633585 -223.69948) (xy 124.611003 -223.744908) (xy 124.581722 -223.786336) (xy 124.546434 -223.822783)
			(xy 124.505975 -223.853388) (xy 124.461301 -223.877427) (xy 124.413469 -223.894332) (xy 124.388626 -223.899476)
			(xy 124.365766 -223.903794) (xy 124.161042 -224.258632) (xy 124.168916 -224.280476) (xy 124.17749 -224.306896)
			(xy 124.18669 -224.36167) (xy 124.187204 -224.389442) (xy 124.468128 -224.389442) (xy 124.468636 -224.363555)
			(xy 124.476735 -224.312417) (xy 124.492734 -224.263177) (xy 124.51624 -224.217045) (xy 124.546672 -224.175158)
			(xy 124.583282 -224.138548) (xy 124.625169 -224.108116) (xy 124.671301 -224.08461) (xy 124.720541 -224.068611)
			(xy 124.771679 -224.060512) (xy 124.823453 -224.060512) (xy 124.874591 -224.068611) (xy 124.923831 -224.08461)
			(xy 124.969963 -224.108116) (xy 125.01185 -224.138548) (xy 125.04846 -224.175158) (xy 125.078892 -224.217045)
			(xy 125.102398 -224.263177) (xy 125.118397 -224.312417) (xy 125.126496 -224.363555) (xy 125.127004 -224.389442)
			(xy 125.407928 -224.389442) (xy 125.408335 -224.364105) (xy 125.416097 -224.314028) (xy 125.431429 -224.265728)
			(xy 125.45397 -224.220343) (xy 125.483189 -224.17894) (xy 125.518399 -224.142496) (xy 125.55877 -224.111867)
			(xy 125.603352 -224.087776) (xy 125.651095 -224.070789) (xy 125.675898 -224.065592) (xy 125.698758 -224.061274)
			(xy 125.903482 -223.706436) (xy 125.895862 -223.684338) (xy 125.887231 -223.657991) (xy 125.87791 -223.603344)
			(xy 125.87732 -223.575626) (xy 125.877828 -223.549719) (xy 125.885934 -223.498542) (xy 125.901946 -223.449263)
			(xy 125.925469 -223.403096) (xy 125.955925 -223.361177) (xy 125.992563 -223.324539) (xy 126.034482 -223.294083)
			(xy 126.080649 -223.27056) (xy 126.129928 -223.254548) (xy 126.181105 -223.246442) (xy 126.232919 -223.246442)
			(xy 126.284096 -223.254548) (xy 126.333375 -223.27056) (xy 126.379542 -223.294083) (xy 126.421461 -223.324539)
			(xy 126.458099 -223.361177) (xy 126.488555 -223.403096) (xy 126.512078 -223.449263) (xy 126.52809 -223.498542)
			(xy 126.536196 -223.549719) (xy 126.536704 -223.575626) (xy 126.536287 -223.600992) (xy 126.528534 -223.651127)
			(xy 126.513185 -223.69948) (xy 126.490603 -223.744908) (xy 126.461322 -223.786336) (xy 126.426034 -223.822783)
			(xy 126.385575 -223.853388) (xy 126.340901 -223.877427) (xy 126.293069 -223.894332) (xy 126.268226 -223.899476)
			(xy 126.245366 -223.903794) (xy 126.040642 -224.258632) (xy 126.048516 -224.280476) (xy 126.05709 -224.306896)
			(xy 126.06629 -224.36167) (xy 126.066804 -224.389442) (xy 126.347728 -224.389442) (xy 126.348236 -224.363555)
			(xy 126.356335 -224.312417) (xy 126.372334 -224.263177) (xy 126.39584 -224.217045) (xy 126.426272 -224.175158)
			(xy 126.462882 -224.138548) (xy 126.504769 -224.108116) (xy 126.550901 -224.08461) (xy 126.600141 -224.068611)
			(xy 126.651279 -224.060512) (xy 126.703053 -224.060512) (xy 126.754191 -224.068611) (xy 126.803431 -224.08461)
			(xy 126.849563 -224.108116) (xy 126.89145 -224.138548) (xy 126.92806 -224.175158) (xy 126.958492 -224.217045)
			(xy 126.981998 -224.263177) (xy 126.997997 -224.312417) (xy 127.006096 -224.363555) (xy 127.006604 -224.389442)
			(xy 127.287528 -224.389442) (xy 127.287935 -224.364105) (xy 127.295697 -224.314028) (xy 127.311029 -224.265728)
			(xy 127.33357 -224.220343) (xy 127.362789 -224.17894) (xy 127.397999 -224.142496) (xy 127.43837 -224.111867)
			(xy 127.482952 -224.087776) (xy 127.530695 -224.070789) (xy 127.555498 -224.065592) (xy 127.578358 -224.061274)
			(xy 127.783082 -223.706436) (xy 127.775462 -223.684338) (xy 127.766831 -223.657991) (xy 127.75751 -223.603344)
			(xy 127.75692 -223.575626) (xy 127.757428 -223.549719) (xy 127.765534 -223.498542) (xy 127.781546 -223.449263)
			(xy 127.805069 -223.403096) (xy 127.835525 -223.361177) (xy 127.872163 -223.324539) (xy 127.914082 -223.294083)
			(xy 127.960249 -223.27056) (xy 128.009528 -223.254548) (xy 128.060705 -223.246442) (xy 128.112519 -223.246442)
			(xy 128.163696 -223.254548) (xy 128.212975 -223.27056) (xy 128.259142 -223.294083) (xy 128.301061 -223.324539)
			(xy 128.337699 -223.361177) (xy 128.368155 -223.403096) (xy 128.391678 -223.449263) (xy 128.40769 -223.498542)
			(xy 128.415796 -223.549719) (xy 128.416304 -223.575626) (xy 128.415887 -223.600992) (xy 128.408134 -223.651127)
			(xy 128.392785 -223.69948) (xy 128.370203 -223.744908) (xy 128.340922 -223.786336) (xy 128.305634 -223.822783)
			(xy 128.265175 -223.853388) (xy 128.220501 -223.877427) (xy 128.172669 -223.894332) (xy 128.147826 -223.899476)
			(xy 128.124966 -223.903794) (xy 127.920242 -224.258632) (xy 127.928116 -224.280476) (xy 127.93669 -224.306896)
			(xy 127.94589 -224.36167) (xy 127.946404 -224.389442) (xy 128.227328 -224.389442) (xy 128.227836 -224.363555)
			(xy 128.235935 -224.312417) (xy 128.251934 -224.263177) (xy 128.27544 -224.217045) (xy 128.305872 -224.175158)
			(xy 128.342482 -224.138548) (xy 128.384369 -224.108116) (xy 128.430501 -224.08461) (xy 128.479741 -224.068611)
			(xy 128.530879 -224.060512) (xy 128.582653 -224.060512) (xy 128.633791 -224.068611) (xy 128.683031 -224.08461)
			(xy 128.729163 -224.108116) (xy 128.77105 -224.138548) (xy 128.80766 -224.175158) (xy 128.838092 -224.217045)
			(xy 128.861598 -224.263177) (xy 128.877597 -224.312417) (xy 128.885696 -224.363555) (xy 128.886204 -224.389442)
			(xy 129.167128 -224.389442) (xy 129.167535 -224.364105) (xy 129.175297 -224.314028) (xy 129.190629 -224.265728)
			(xy 129.21317 -224.220343) (xy 129.242389 -224.17894) (xy 129.277599 -224.142496) (xy 129.31797 -224.111867)
			(xy 129.362552 -224.087776) (xy 129.410295 -224.070789) (xy 129.435098 -224.065592) (xy 129.457958 -224.061274)
			(xy 129.662682 -223.706436) (xy 129.655062 -223.684338) (xy 129.646431 -223.657991) (xy 129.63711 -223.603344)
			(xy 129.63652 -223.575626) (xy 129.637028 -223.549719) (xy 129.645134 -223.498542) (xy 129.661146 -223.449263)
			(xy 129.684669 -223.403096) (xy 129.715125 -223.361177) (xy 129.751763 -223.324539) (xy 129.793682 -223.294083)
			(xy 129.839849 -223.27056) (xy 129.889128 -223.254548) (xy 129.940305 -223.246442) (xy 129.992119 -223.246442)
			(xy 130.043296 -223.254548) (xy 130.092575 -223.27056) (xy 130.138742 -223.294083) (xy 130.180661 -223.324539)
			(xy 130.217299 -223.361177) (xy 130.247755 -223.403096) (xy 130.271278 -223.449263) (xy 130.28729 -223.498542)
			(xy 130.295396 -223.549719) (xy 130.295904 -223.575626) (xy 130.295487 -223.600992) (xy 130.287734 -223.651127)
			(xy 130.272385 -223.69948) (xy 130.249803 -223.744908) (xy 130.220522 -223.786336) (xy 130.185234 -223.822783)
			(xy 130.144775 -223.853388) (xy 130.100101 -223.877427) (xy 130.052269 -223.894332) (xy 130.027426 -223.899476)
			(xy 130.004566 -223.903794) (xy 129.799842 -224.258632) (xy 129.807716 -224.280476) (xy 129.81629 -224.306896)
			(xy 129.82549 -224.36167) (xy 129.826004 -224.389442) (xy 130.106928 -224.389442) (xy 130.107436 -224.363555)
			(xy 130.115535 -224.312417) (xy 130.131534 -224.263177) (xy 130.15504 -224.217045) (xy 130.185472 -224.175158)
			(xy 130.222082 -224.138548) (xy 130.263969 -224.108116) (xy 130.310101 -224.08461) (xy 130.359341 -224.068611)
			(xy 130.410479 -224.060512) (xy 130.462253 -224.060512) (xy 130.513391 -224.068611) (xy 130.562631 -224.08461)
			(xy 130.608763 -224.108116) (xy 130.65065 -224.138548) (xy 130.68726 -224.175158) (xy 130.717692 -224.217045)
			(xy 130.741198 -224.263177) (xy 130.757197 -224.312417) (xy 130.765296 -224.363555) (xy 130.765804 -224.389442)
			(xy 131.046728 -224.389442) (xy 131.047135 -224.364105) (xy 131.054897 -224.314028) (xy 131.070229 -224.265728)
			(xy 131.09277 -224.220343) (xy 131.121989 -224.17894) (xy 131.157199 -224.142496) (xy 131.19757 -224.111867)
			(xy 131.242152 -224.087776) (xy 131.289895 -224.070789) (xy 131.314698 -224.065592) (xy 131.337558 -224.061274)
			(xy 131.542282 -223.706182) (xy 131.534662 -223.684338) (xy 131.526017 -223.657995) (xy 131.516704 -223.603345)
			(xy 131.51612 -223.575626) (xy 131.516628 -223.549719) (xy 131.524734 -223.498542) (xy 131.540746 -223.449263)
			(xy 131.564269 -223.403096) (xy 131.594725 -223.361177) (xy 131.631363 -223.324539) (xy 131.673282 -223.294083)
			(xy 131.719449 -223.27056) (xy 131.768728 -223.254548) (xy 131.819905 -223.246442) (xy 131.871719 -223.246442)
			(xy 131.922896 -223.254548) (xy 131.972175 -223.27056) (xy 132.018342 -223.294083) (xy 132.060261 -223.324539)
			(xy 132.096899 -223.361177) (xy 132.127355 -223.403096) (xy 132.150878 -223.449263) (xy 132.16689 -223.498542)
			(xy 132.174996 -223.549719) (xy 132.175504 -223.575626) (xy 132.175003 -223.60097) (xy 132.167228 -223.651059)
			(xy 132.151879 -223.699368) (xy 132.12932 -223.74476) (xy 132.10008 -223.786165) (xy 132.064849 -223.822609)
			(xy 132.024457 -223.853232) (xy 131.979854 -223.877314) (xy 131.932092 -223.894288) (xy 131.90728 -223.899476)
			(xy 131.88442 -223.903794) (xy 131.679696 -224.258632) (xy 131.687316 -224.280476) (xy 131.695872 -224.306769)
			(xy 131.705065 -224.361289) (xy 131.705604 -224.388934) (xy 131.705604 -224.389442) (xy 131.986528 -224.389442)
			(xy 131.987036 -224.363555) (xy 131.995135 -224.312417) (xy 132.011134 -224.263177) (xy 132.03464 -224.217045)
			(xy 132.065072 -224.175158) (xy 132.101682 -224.138548) (xy 132.143569 -224.108116) (xy 132.189701 -224.08461)
			(xy 132.238941 -224.068611) (xy 132.290079 -224.060512) (xy 132.341853 -224.060512) (xy 132.392991 -224.068611)
			(xy 132.442231 -224.08461) (xy 132.488363 -224.108116) (xy 132.53025 -224.138548) (xy 132.56686 -224.175158)
			(xy 132.597292 -224.217045) (xy 132.620798 -224.263177) (xy 132.636797 -224.312417) (xy 132.644896 -224.363555)
			(xy 132.645404 -224.389442) (xy 132.926328 -224.389442) (xy 132.926735 -224.364105) (xy 132.934497 -224.314028)
			(xy 132.949829 -224.265728) (xy 132.97237 -224.220343) (xy 133.001589 -224.17894) (xy 133.036799 -224.142496)
			(xy 133.07717 -224.111867) (xy 133.121752 -224.087776) (xy 133.169495 -224.070789) (xy 133.194298 -224.065592)
			(xy 133.217158 -224.061274) (xy 133.422136 -223.705928) (xy 133.414516 -223.684084) (xy 133.405997 -223.657912)
			(xy 133.396803 -223.603651) (xy 133.396228 -223.576134) (xy 133.396228 -223.575626) (xy 133.396736 -223.549739)
			(xy 133.404835 -223.498601) (xy 133.420834 -223.449361) (xy 133.44434 -223.403229) (xy 133.474772 -223.361342)
			(xy 133.511382 -223.324732) (xy 133.553269 -223.2943) (xy 133.599401 -223.270794) (xy 133.648641 -223.254795)
			(xy 133.699779 -223.246696) (xy 133.751553 -223.246696) (xy 133.802691 -223.254795) (xy 133.851931 -223.270794)
			(xy 133.898063 -223.2943) (xy 133.93995 -223.324732) (xy 133.97656 -223.361342) (xy 134.006992 -223.403229)
			(xy 134.030498 -223.449361) (xy 134.046497 -223.498601) (xy 134.054596 -223.549739) (xy 134.055104 -223.575626)
			(xy 134.054603 -223.60097) (xy 134.046828 -223.651059) (xy 134.031479 -223.699368) (xy 134.00892 -223.74476)
			(xy 133.97968 -223.786165) (xy 133.944449 -223.822609) (xy 133.904057 -223.853232) (xy 133.859454 -223.877314)
			(xy 133.811692 -223.894288) (xy 133.78688 -223.899476) (xy 133.76402 -223.903794) (xy 133.559296 -224.258632)
			(xy 133.566916 -224.280476) (xy 133.575472 -224.306769) (xy 133.584665 -224.361289) (xy 133.585204 -224.388934)
			(xy 133.585204 -224.389442) (xy 133.866128 -224.389442) (xy 133.866636 -224.363555) (xy 133.874735 -224.312417)
			(xy 133.890734 -224.263177) (xy 133.91424 -224.217045) (xy 133.944672 -224.175158) (xy 133.981282 -224.138548)
			(xy 134.023169 -224.108116) (xy 134.069301 -224.08461) (xy 134.118541 -224.068611) (xy 134.169679 -224.060512)
			(xy 134.221453 -224.060512) (xy 134.272591 -224.068611) (xy 134.321831 -224.08461) (xy 134.367963 -224.108116)
			(xy 134.40985 -224.138548) (xy 134.44646 -224.175158) (xy 134.476892 -224.217045) (xy 134.500398 -224.263177)
			(xy 134.516397 -224.312417) (xy 134.524496 -224.363555) (xy 134.525004 -224.389442) (xy 337.635596 -224.389442)
			(xy 337.636029 -224.364106) (xy 337.64379 -224.314032) (xy 337.65912 -224.265734) (xy 337.681659 -224.22035)
			(xy 337.710875 -224.178949) (xy 337.746081 -224.142504) (xy 337.786448 -224.111874) (xy 337.831026 -224.087781)
			(xy 337.878765 -224.070791) (xy 337.903566 -224.065592) (xy 337.926426 -224.061274) (xy 338.13115 -223.706182)
			(xy 338.12353 -223.684338) (xy 338.114887 -223.657995) (xy 338.105572 -223.603345) (xy 338.104988 -223.575626)
			(xy 338.105496 -223.549719) (xy 338.113602 -223.498542) (xy 338.129614 -223.449263) (xy 338.153137 -223.403096)
			(xy 338.183593 -223.361177) (xy 338.220231 -223.324539) (xy 338.26215 -223.294083) (xy 338.308317 -223.27056)
			(xy 338.357596 -223.254548) (xy 338.408773 -223.246442) (xy 338.460587 -223.246442) (xy 338.511764 -223.254548)
			(xy 338.561043 -223.27056) (xy 338.60721 -223.294083) (xy 338.649129 -223.324539) (xy 338.685767 -223.361177)
			(xy 338.716223 -223.403096) (xy 338.739746 -223.449263) (xy 338.755758 -223.498542) (xy 338.763864 -223.549719)
			(xy 338.764372 -223.575626) (xy 338.763897 -223.600971) (xy 338.756121 -223.651063) (xy 338.740771 -223.699374)
			(xy 338.718208 -223.744767) (xy 338.688966 -223.786173) (xy 338.653731 -223.822617) (xy 338.613335 -223.853239)
			(xy 338.568728 -223.877319) (xy 338.520962 -223.89429) (xy 338.496148 -223.899476) (xy 338.473288 -223.903794)
			(xy 338.268564 -224.258632) (xy 338.276184 -224.280476) (xy 338.284739 -224.306769) (xy 338.293932 -224.361289)
			(xy 338.294472 -224.388934) (xy 338.294472 -224.389442) (xy 338.575396 -224.389442) (xy 338.575904 -224.363555)
			(xy 338.584003 -224.312417) (xy 338.600002 -224.263177) (xy 338.623508 -224.217045) (xy 338.65394 -224.175158)
			(xy 338.69055 -224.138548) (xy 338.732437 -224.108116) (xy 338.778569 -224.08461) (xy 338.827809 -224.068611)
			(xy 338.878947 -224.060512) (xy 338.930721 -224.060512) (xy 338.981859 -224.068611) (xy 339.031099 -224.08461)
			(xy 339.077231 -224.108116) (xy 339.119118 -224.138548) (xy 339.155728 -224.175158) (xy 339.18616 -224.217045)
			(xy 339.209666 -224.263177) (xy 339.225665 -224.312417) (xy 339.233764 -224.363555) (xy 339.234272 -224.389442)
			(xy 339.515196 -224.389442) (xy 339.515629 -224.364106) (xy 339.52339 -224.314032) (xy 339.53872 -224.265734)
			(xy 339.561259 -224.22035) (xy 339.590475 -224.178949) (xy 339.625681 -224.142504) (xy 339.666048 -224.111874)
			(xy 339.710626 -224.087781) (xy 339.758365 -224.070791) (xy 339.783166 -224.065592) (xy 339.806026 -224.061274)
			(xy 340.01075 -223.706182) (xy 340.00313 -223.684338) (xy 339.994487 -223.657995) (xy 339.985172 -223.603345)
			(xy 339.984588 -223.575626) (xy 339.985096 -223.549719) (xy 339.993202 -223.498542) (xy 340.009214 -223.449263)
			(xy 340.032737 -223.403096) (xy 340.063193 -223.361177) (xy 340.099831 -223.324539) (xy 340.14175 -223.294083)
			(xy 340.187917 -223.27056) (xy 340.237196 -223.254548) (xy 340.288373 -223.246442) (xy 340.340187 -223.246442)
			(xy 340.391364 -223.254548) (xy 340.440643 -223.27056) (xy 340.48681 -223.294083) (xy 340.528729 -223.324539)
			(xy 340.565367 -223.361177) (xy 340.595823 -223.403096) (xy 340.619346 -223.449263) (xy 340.635358 -223.498542)
			(xy 340.643464 -223.549719) (xy 340.643972 -223.575626) (xy 340.643497 -223.600971) (xy 340.635721 -223.651063)
			(xy 340.620371 -223.699374) (xy 340.597808 -223.744767) (xy 340.568566 -223.786173) (xy 340.533331 -223.822617)
			(xy 340.492935 -223.853239) (xy 340.448328 -223.877319) (xy 340.400562 -223.89429) (xy 340.375748 -223.899476)
			(xy 340.352888 -223.903794) (xy 340.148164 -224.258632) (xy 340.155784 -224.280476) (xy 340.164339 -224.306769)
			(xy 340.173532 -224.361289) (xy 340.174072 -224.388934) (xy 340.174072 -224.389442) (xy 340.454996 -224.389442)
			(xy 340.455504 -224.363555) (xy 340.463603 -224.312417) (xy 340.479602 -224.263177) (xy 340.503108 -224.217045)
			(xy 340.53354 -224.175158) (xy 340.57015 -224.138548) (xy 340.612037 -224.108116) (xy 340.658169 -224.08461)
			(xy 340.707409 -224.068611) (xy 340.758547 -224.060512) (xy 340.810321 -224.060512) (xy 340.861459 -224.068611)
			(xy 340.910699 -224.08461) (xy 340.956831 -224.108116) (xy 340.998718 -224.138548) (xy 341.035328 -224.175158)
			(xy 341.06576 -224.217045) (xy 341.089266 -224.263177) (xy 341.105265 -224.312417) (xy 341.113364 -224.363555)
			(xy 341.113872 -224.389442) (xy 341.394796 -224.389442) (xy 341.395229 -224.364106) (xy 341.40299 -224.314032)
			(xy 341.41832 -224.265734) (xy 341.440859 -224.22035) (xy 341.470075 -224.178949) (xy 341.505281 -224.142504)
			(xy 341.545648 -224.111874) (xy 341.590226 -224.087781) (xy 341.637965 -224.070791) (xy 341.662766 -224.065592)
			(xy 341.685626 -224.061274) (xy 341.89035 -223.706436) (xy 341.88273 -223.684338) (xy 341.874102 -223.657991)
			(xy 341.864779 -223.603344) (xy 341.864188 -223.575626) (xy 341.864696 -223.549719) (xy 341.872802 -223.498542)
			(xy 341.888814 -223.449263) (xy 341.912337 -223.403096) (xy 341.942793 -223.361177) (xy 341.979431 -223.324539)
			(xy 342.02135 -223.294083) (xy 342.067517 -223.27056) (xy 342.116796 -223.254548) (xy 342.167973 -223.246442)
			(xy 342.219787 -223.246442) (xy 342.270964 -223.254548) (xy 342.320243 -223.27056) (xy 342.36641 -223.294083)
			(xy 342.408329 -223.324539) (xy 342.444967 -223.361177) (xy 342.475423 -223.403096) (xy 342.498946 -223.449263)
			(xy 342.514958 -223.498542) (xy 342.523064 -223.549719) (xy 342.523572 -223.575626) (xy 342.523181 -223.600993)
			(xy 342.515428 -223.651131) (xy 342.500077 -223.699486) (xy 342.477492 -223.744915) (xy 342.448207 -223.786344)
			(xy 342.412916 -223.822791) (xy 342.372452 -223.853396) (xy 342.327774 -223.877433) (xy 342.279939 -223.894334)
			(xy 342.255094 -223.899476) (xy 342.232234 -223.903794) (xy 342.02751 -224.258632) (xy 342.035384 -224.280476)
			(xy 342.043957 -224.306897) (xy 342.053158 -224.36167) (xy 342.053672 -224.389442) (xy 342.334596 -224.389442)
			(xy 342.335104 -224.363555) (xy 342.343203 -224.312417) (xy 342.359202 -224.263177) (xy 342.382708 -224.217045)
			(xy 342.41314 -224.175158) (xy 342.44975 -224.138548) (xy 342.491637 -224.108116) (xy 342.537769 -224.08461)
			(xy 342.587009 -224.068611) (xy 342.638147 -224.060512) (xy 342.689921 -224.060512) (xy 342.741059 -224.068611)
			(xy 342.790299 -224.08461) (xy 342.836431 -224.108116) (xy 342.878318 -224.138548) (xy 342.914928 -224.175158)
			(xy 342.94536 -224.217045) (xy 342.968866 -224.263177) (xy 342.984865 -224.312417) (xy 342.992964 -224.363555)
			(xy 342.993472 -224.389442) (xy 343.274396 -224.389442) (xy 343.274829 -224.364106) (xy 343.28259 -224.314032)
			(xy 343.29792 -224.265734) (xy 343.320459 -224.22035) (xy 343.349675 -224.178949) (xy 343.384881 -224.142504)
			(xy 343.425248 -224.111874) (xy 343.469826 -224.087781) (xy 343.517565 -224.070791) (xy 343.542366 -224.065592)
			(xy 343.565226 -224.061274) (xy 343.76995 -223.706436) (xy 343.76233 -223.684338) (xy 343.753702 -223.657991)
			(xy 343.744379 -223.603344) (xy 343.743788 -223.575626) (xy 343.744296 -223.549719) (xy 343.752402 -223.498542)
			(xy 343.768414 -223.449263) (xy 343.791937 -223.403096) (xy 343.822393 -223.361177) (xy 343.859031 -223.324539)
			(xy 343.90095 -223.294083) (xy 343.947117 -223.27056) (xy 343.996396 -223.254548) (xy 344.047573 -223.246442)
			(xy 344.099387 -223.246442) (xy 344.150564 -223.254548) (xy 344.199843 -223.27056) (xy 344.24601 -223.294083)
			(xy 344.287929 -223.324539) (xy 344.324567 -223.361177) (xy 344.355023 -223.403096) (xy 344.378546 -223.449263)
			(xy 344.394558 -223.498542) (xy 344.402664 -223.549719) (xy 344.403172 -223.575626) (xy 344.402781 -223.600993)
			(xy 344.395028 -223.651131) (xy 344.379677 -223.699486) (xy 344.357092 -223.744915) (xy 344.327807 -223.786344)
			(xy 344.292516 -223.822791) (xy 344.252052 -223.853396) (xy 344.207374 -223.877433) (xy 344.159539 -223.894334)
			(xy 344.134694 -223.899476) (xy 344.111834 -223.903794) (xy 343.90711 -224.258632) (xy 343.914984 -224.280476)
			(xy 343.923557 -224.306897) (xy 343.932758 -224.36167) (xy 343.933272 -224.389442) (xy 344.214196 -224.389442)
			(xy 344.214704 -224.363555) (xy 344.222803 -224.312417) (xy 344.238802 -224.263177) (xy 344.262308 -224.217045)
			(xy 344.29274 -224.175158) (xy 344.32935 -224.138548) (xy 344.371237 -224.108116) (xy 344.417369 -224.08461)
			(xy 344.466609 -224.068611) (xy 344.517747 -224.060512) (xy 344.569521 -224.060512) (xy 344.620659 -224.068611)
			(xy 344.669899 -224.08461) (xy 344.716031 -224.108116) (xy 344.757918 -224.138548) (xy 344.794528 -224.175158)
			(xy 344.82496 -224.217045) (xy 344.848466 -224.263177) (xy 344.864465 -224.312417) (xy 344.872564 -224.363555)
			(xy 344.873072 -224.389442) (xy 345.153996 -224.389442) (xy 345.154429 -224.364106) (xy 345.16219 -224.314032)
			(xy 345.17752 -224.265734) (xy 345.200059 -224.22035) (xy 345.229275 -224.178949) (xy 345.264481 -224.142504)
			(xy 345.304848 -224.111874) (xy 345.349426 -224.087781) (xy 345.397165 -224.070791) (xy 345.421966 -224.065592)
			(xy 345.444826 -224.061274) (xy 345.64955 -223.706436) (xy 345.64193 -223.684338) (xy 345.633302 -223.657991)
			(xy 345.623979 -223.603344) (xy 345.623388 -223.575626) (xy 345.623896 -223.549719) (xy 345.632002 -223.498542)
			(xy 345.648014 -223.449263) (xy 345.671537 -223.403096) (xy 345.701993 -223.361177) (xy 345.738631 -223.324539)
			(xy 345.78055 -223.294083) (xy 345.826717 -223.27056) (xy 345.875996 -223.254548) (xy 345.927173 -223.246442)
			(xy 345.978987 -223.246442) (xy 346.030164 -223.254548) (xy 346.079443 -223.27056) (xy 346.12561 -223.294083)
			(xy 346.167529 -223.324539) (xy 346.204167 -223.361177) (xy 346.234623 -223.403096) (xy 346.258146 -223.449263)
			(xy 346.274158 -223.498542) (xy 346.282264 -223.549719) (xy 346.282772 -223.575626) (xy 346.282381 -223.600993)
			(xy 346.274628 -223.651131) (xy 346.259277 -223.699486) (xy 346.236692 -223.744915) (xy 346.207407 -223.786344)
			(xy 346.172116 -223.822791) (xy 346.131652 -223.853396) (xy 346.086974 -223.877433) (xy 346.039139 -223.894334)
			(xy 346.014294 -223.899476) (xy 345.991434 -223.903794) (xy 345.78671 -224.258632) (xy 345.794584 -224.280476)
			(xy 345.803157 -224.306897) (xy 345.812358 -224.36167) (xy 345.812872 -224.389442) (xy 346.093796 -224.389442)
			(xy 346.094304 -224.363555) (xy 346.102403 -224.312417) (xy 346.118402 -224.263177) (xy 346.141908 -224.217045)
			(xy 346.17234 -224.175158) (xy 346.20895 -224.138548) (xy 346.250837 -224.108116) (xy 346.296969 -224.08461)
			(xy 346.346209 -224.068611) (xy 346.397347 -224.060512) (xy 346.449121 -224.060512) (xy 346.500259 -224.068611)
			(xy 346.549499 -224.08461) (xy 346.595631 -224.108116) (xy 346.637518 -224.138548) (xy 346.674128 -224.175158)
			(xy 346.70456 -224.217045) (xy 346.728066 -224.263177) (xy 346.744065 -224.312417) (xy 346.752164 -224.363555)
			(xy 346.752672 -224.389442) (xy 347.033596 -224.389442) (xy 347.034029 -224.364106) (xy 347.04179 -224.314032)
			(xy 347.05712 -224.265734) (xy 347.079659 -224.22035) (xy 347.108875 -224.178949) (xy 347.144081 -224.142504)
			(xy 347.184448 -224.111874) (xy 347.229026 -224.087781) (xy 347.276765 -224.070791) (xy 347.301566 -224.065592)
			(xy 347.324426 -224.061274) (xy 347.52915 -223.706436) (xy 347.52153 -223.684338) (xy 347.512902 -223.657991)
			(xy 347.503579 -223.603344) (xy 347.502988 -223.575626) (xy 347.503496 -223.549719) (xy 347.511602 -223.498542)
			(xy 347.527614 -223.449263) (xy 347.551137 -223.403096) (xy 347.581593 -223.361177) (xy 347.618231 -223.324539)
			(xy 347.66015 -223.294083) (xy 347.706317 -223.27056) (xy 347.755596 -223.254548) (xy 347.806773 -223.246442)
			(xy 347.858587 -223.246442) (xy 347.909764 -223.254548) (xy 347.959043 -223.27056) (xy 348.00521 -223.294083)
			(xy 348.047129 -223.324539) (xy 348.083767 -223.361177) (xy 348.114223 -223.403096) (xy 348.137746 -223.449263)
			(xy 348.153758 -223.498542) (xy 348.161864 -223.549719) (xy 348.162372 -223.575626) (xy 348.161981 -223.600993)
			(xy 348.154228 -223.651131) (xy 348.138877 -223.699486) (xy 348.116292 -223.744915) (xy 348.087007 -223.786344)
			(xy 348.051716 -223.822791) (xy 348.011252 -223.853396) (xy 347.966574 -223.877433) (xy 347.918739 -223.894334)
			(xy 347.893894 -223.899476) (xy 347.871034 -223.903794) (xy 347.66631 -224.258632) (xy 347.674184 -224.280476)
			(xy 347.682757 -224.306897) (xy 347.691958 -224.36167) (xy 347.692472 -224.389442) (xy 347.973396 -224.389442)
			(xy 347.973904 -224.363555) (xy 347.982003 -224.312417) (xy 347.998002 -224.263177) (xy 348.021508 -224.217045)
			(xy 348.05194 -224.175158) (xy 348.08855 -224.138548) (xy 348.130437 -224.108116) (xy 348.176569 -224.08461)
			(xy 348.225809 -224.068611) (xy 348.276947 -224.060512) (xy 348.328721 -224.060512) (xy 348.379859 -224.068611)
			(xy 348.429099 -224.08461) (xy 348.475231 -224.108116) (xy 348.517118 -224.138548) (xy 348.553728 -224.175158)
			(xy 348.58416 -224.217045) (xy 348.607666 -224.263177) (xy 348.623665 -224.312417) (xy 348.631764 -224.363555)
			(xy 348.632272 -224.389442) (xy 348.913196 -224.389442) (xy 348.913629 -224.364106) (xy 348.92139 -224.314032)
			(xy 348.93672 -224.265734) (xy 348.959259 -224.22035) (xy 348.988475 -224.178949) (xy 349.023681 -224.142504)
			(xy 349.064048 -224.111874) (xy 349.108626 -224.087781) (xy 349.156365 -224.070791) (xy 349.181166 -224.065592)
			(xy 349.204026 -224.061274) (xy 349.40875 -223.706436) (xy 349.40113 -223.684338) (xy 349.392502 -223.657991)
			(xy 349.383179 -223.603344) (xy 349.382588 -223.575626) (xy 349.383096 -223.549719) (xy 349.391202 -223.498542)
			(xy 349.407214 -223.449263) (xy 349.430737 -223.403096) (xy 349.461193 -223.361177) (xy 349.497831 -223.324539)
			(xy 349.53975 -223.294083) (xy 349.585917 -223.27056) (xy 349.635196 -223.254548) (xy 349.686373 -223.246442)
			(xy 349.738187 -223.246442) (xy 349.789364 -223.254548) (xy 349.838643 -223.27056) (xy 349.88481 -223.294083)
			(xy 349.926729 -223.324539) (xy 349.963367 -223.361177) (xy 349.993823 -223.403096) (xy 350.017346 -223.449263)
			(xy 350.033358 -223.498542) (xy 350.041464 -223.549719) (xy 350.041972 -223.575626) (xy 350.041581 -223.600993)
			(xy 350.033828 -223.651131) (xy 350.018477 -223.699486) (xy 349.995892 -223.744915) (xy 349.966607 -223.786344)
			(xy 349.931316 -223.822791) (xy 349.890852 -223.853396) (xy 349.846174 -223.877433) (xy 349.798339 -223.894334)
			(xy 349.773494 -223.899476) (xy 349.750634 -223.903794) (xy 349.54591 -224.258632) (xy 349.553784 -224.280476)
			(xy 349.562357 -224.306897) (xy 349.571558 -224.36167) (xy 349.572072 -224.389442) (xy 349.852996 -224.389442)
			(xy 349.853504 -224.363555) (xy 349.861603 -224.312417) (xy 349.877602 -224.263177) (xy 349.901108 -224.217045)
			(xy 349.93154 -224.175158) (xy 349.96815 -224.138548) (xy 350.010037 -224.108116) (xy 350.056169 -224.08461)
			(xy 350.105409 -224.068611) (xy 350.156547 -224.060512) (xy 350.208321 -224.060512) (xy 350.259459 -224.068611)
			(xy 350.308699 -224.08461) (xy 350.354831 -224.108116) (xy 350.396718 -224.138548) (xy 350.433328 -224.175158)
			(xy 350.46376 -224.217045) (xy 350.487266 -224.263177) (xy 350.503265 -224.312417) (xy 350.511364 -224.363555)
			(xy 350.511872 -224.389442) (xy 350.792796 -224.389442) (xy 350.793229 -224.364106) (xy 350.80099 -224.314032)
			(xy 350.81632 -224.265734) (xy 350.838859 -224.22035) (xy 350.868075 -224.178949) (xy 350.903281 -224.142504)
			(xy 350.943648 -224.111874) (xy 350.988226 -224.087781) (xy 351.035965 -224.070791) (xy 351.060766 -224.065592)
			(xy 351.083626 -224.061274) (xy 351.28835 -223.706436) (xy 351.28073 -223.684338) (xy 351.272102 -223.657991)
			(xy 351.262779 -223.603344) (xy 351.262188 -223.575626) (xy 351.262696 -223.549719) (xy 351.270802 -223.498542)
			(xy 351.286814 -223.449263) (xy 351.310337 -223.403096) (xy 351.340793 -223.361177) (xy 351.377431 -223.324539)
			(xy 351.41935 -223.294083) (xy 351.465517 -223.27056) (xy 351.514796 -223.254548) (xy 351.565973 -223.246442)
			(xy 351.617787 -223.246442) (xy 351.668964 -223.254548) (xy 351.718243 -223.27056) (xy 351.76441 -223.294083)
			(xy 351.806329 -223.324539) (xy 351.842967 -223.361177) (xy 351.873423 -223.403096) (xy 351.896946 -223.449263)
			(xy 351.912958 -223.498542) (xy 351.921064 -223.549719) (xy 351.921572 -223.575626) (xy 351.921181 -223.600993)
			(xy 351.913428 -223.651131) (xy 351.898077 -223.699486) (xy 351.875492 -223.744915) (xy 351.846207 -223.786344)
			(xy 351.810916 -223.822791) (xy 351.770452 -223.853396) (xy 351.725774 -223.877433) (xy 351.677939 -223.894334)
			(xy 351.653094 -223.899476) (xy 351.630234 -223.903794) (xy 351.42551 -224.258632) (xy 351.433384 -224.280476)
			(xy 351.441957 -224.306897) (xy 351.451158 -224.36167) (xy 351.451672 -224.389442) (xy 351.732596 -224.389442)
			(xy 351.733104 -224.363555) (xy 351.741203 -224.312417) (xy 351.757202 -224.263177) (xy 351.780708 -224.217045)
			(xy 351.81114 -224.175158) (xy 351.84775 -224.138548) (xy 351.889637 -224.108116) (xy 351.935769 -224.08461)
			(xy 351.985009 -224.068611) (xy 352.036147 -224.060512) (xy 352.087921 -224.060512) (xy 352.139059 -224.068611)
			(xy 352.188299 -224.08461) (xy 352.234431 -224.108116) (xy 352.276318 -224.138548) (xy 352.312928 -224.175158)
			(xy 352.34336 -224.217045) (xy 352.366866 -224.263177) (xy 352.382865 -224.312417) (xy 352.390964 -224.363555)
			(xy 352.391472 -224.389442) (xy 352.672396 -224.389442) (xy 352.672829 -224.364106) (xy 352.68059 -224.314032)
			(xy 352.69592 -224.265734) (xy 352.718459 -224.22035) (xy 352.747675 -224.178949) (xy 352.782881 -224.142504)
			(xy 352.823248 -224.111874) (xy 352.867826 -224.087781) (xy 352.915565 -224.070791) (xy 352.940366 -224.065592)
			(xy 352.963226 -224.061274) (xy 353.16795 -223.706436) (xy 353.16033 -223.684338) (xy 353.151702 -223.657991)
			(xy 353.142379 -223.603344) (xy 353.141788 -223.575626) (xy 353.142296 -223.549719) (xy 353.150402 -223.498542)
			(xy 353.166414 -223.449263) (xy 353.189937 -223.403096) (xy 353.220393 -223.361177) (xy 353.257031 -223.324539)
			(xy 353.29895 -223.294083) (xy 353.345117 -223.27056) (xy 353.394396 -223.254548) (xy 353.445573 -223.246442)
			(xy 353.497387 -223.246442) (xy 353.548564 -223.254548) (xy 353.597843 -223.27056) (xy 353.64401 -223.294083)
			(xy 353.685929 -223.324539) (xy 353.722567 -223.361177) (xy 353.753023 -223.403096) (xy 353.776546 -223.449263)
			(xy 353.792558 -223.498542) (xy 353.800664 -223.549719) (xy 353.801172 -223.575626) (xy 353.800781 -223.600993)
			(xy 353.793028 -223.651131) (xy 353.777677 -223.699486) (xy 353.755092 -223.744915) (xy 353.725807 -223.786344)
			(xy 353.690516 -223.822791) (xy 353.650052 -223.853396) (xy 353.605374 -223.877433) (xy 353.557539 -223.894334)
			(xy 353.532694 -223.899476) (xy 353.509834 -223.903794) (xy 353.30511 -224.258632) (xy 353.312984 -224.280476)
			(xy 353.321557 -224.306897) (xy 353.330758 -224.36167) (xy 353.331272 -224.389442) (xy 353.612196 -224.389442)
			(xy 353.612704 -224.363555) (xy 353.620803 -224.312417) (xy 353.636802 -224.263177) (xy 353.660308 -224.217045)
			(xy 353.69074 -224.175158) (xy 353.72735 -224.138548) (xy 353.769237 -224.108116) (xy 353.815369 -224.08461)
			(xy 353.864609 -224.068611) (xy 353.915747 -224.060512) (xy 353.967521 -224.060512) (xy 354.018659 -224.068611)
			(xy 354.067899 -224.08461) (xy 354.114031 -224.108116) (xy 354.155918 -224.138548) (xy 354.192528 -224.175158)
			(xy 354.22296 -224.217045) (xy 354.246466 -224.263177) (xy 354.262465 -224.312417) (xy 354.270564 -224.363555)
			(xy 354.271072 -224.389442) (xy 354.551996 -224.389442) (xy 354.552429 -224.364106) (xy 354.56019 -224.314032)
			(xy 354.57552 -224.265734) (xy 354.598059 -224.22035) (xy 354.627275 -224.178949) (xy 354.662481 -224.142504)
			(xy 354.702848 -224.111874) (xy 354.747426 -224.087781) (xy 354.795165 -224.070791) (xy 354.819966 -224.065592)
			(xy 354.842826 -224.061274) (xy 355.04755 -223.706436) (xy 355.03993 -223.684338) (xy 355.031302 -223.657991)
			(xy 355.021979 -223.603344) (xy 355.021388 -223.575626) (xy 355.021896 -223.549719) (xy 355.030002 -223.498542)
			(xy 355.046014 -223.449263) (xy 355.069537 -223.403096) (xy 355.099993 -223.361177) (xy 355.136631 -223.324539)
			(xy 355.17855 -223.294083) (xy 355.224717 -223.27056) (xy 355.273996 -223.254548) (xy 355.325173 -223.246442)
			(xy 355.376987 -223.246442) (xy 355.428164 -223.254548) (xy 355.477443 -223.27056) (xy 355.52361 -223.294083)
			(xy 355.565529 -223.324539) (xy 355.602167 -223.361177) (xy 355.632623 -223.403096) (xy 355.656146 -223.449263)
			(xy 355.672158 -223.498542) (xy 355.680264 -223.549719) (xy 355.680772 -223.575626) (xy 355.680381 -223.600993)
			(xy 355.672628 -223.651131) (xy 355.657277 -223.699486) (xy 355.634692 -223.744915) (xy 355.605407 -223.786344)
			(xy 355.570116 -223.822791) (xy 355.529652 -223.853396) (xy 355.484974 -223.877433) (xy 355.437139 -223.894334)
			(xy 355.412294 -223.899476) (xy 355.389434 -223.903794) (xy 355.18471 -224.258632) (xy 355.192584 -224.280476)
			(xy 355.201157 -224.306897) (xy 355.210358 -224.36167) (xy 355.210872 -224.389442) (xy 355.491796 -224.389442)
			(xy 355.492304 -224.363555) (xy 355.500403 -224.312417) (xy 355.516402 -224.263177) (xy 355.539908 -224.217045)
			(xy 355.57034 -224.175158) (xy 355.60695 -224.138548) (xy 355.648837 -224.108116) (xy 355.694969 -224.08461)
			(xy 355.744209 -224.068611) (xy 355.795347 -224.060512) (xy 355.847121 -224.060512) (xy 355.898259 -224.068611)
			(xy 355.947499 -224.08461) (xy 355.993631 -224.108116) (xy 356.035518 -224.138548) (xy 356.072128 -224.175158)
			(xy 356.10256 -224.217045) (xy 356.126066 -224.263177) (xy 356.142065 -224.312417) (xy 356.150164 -224.363555)
			(xy 356.150672 -224.389442) (xy 356.431596 -224.389442) (xy 356.432029 -224.364106) (xy 356.43979 -224.314032)
			(xy 356.45512 -224.265734) (xy 356.477659 -224.22035) (xy 356.506875 -224.178949) (xy 356.542081 -224.142504)
			(xy 356.582448 -224.111874) (xy 356.627026 -224.087781) (xy 356.674765 -224.070791) (xy 356.699566 -224.065592)
			(xy 356.722426 -224.061274) (xy 356.92715 -223.706436) (xy 356.91953 -223.684338) (xy 356.910902 -223.657991)
			(xy 356.901579 -223.603344) (xy 356.900988 -223.575626) (xy 356.901496 -223.549719) (xy 356.909602 -223.498542)
			(xy 356.925614 -223.449263) (xy 356.949137 -223.403096) (xy 356.979593 -223.361177) (xy 357.016231 -223.324539)
			(xy 357.05815 -223.294083) (xy 357.104317 -223.27056) (xy 357.153596 -223.254548) (xy 357.204773 -223.246442)
			(xy 357.256587 -223.246442) (xy 357.307764 -223.254548) (xy 357.357043 -223.27056) (xy 357.40321 -223.294083)
			(xy 357.445129 -223.324539) (xy 357.481767 -223.361177) (xy 357.512223 -223.403096) (xy 357.535746 -223.449263)
			(xy 357.551758 -223.498542) (xy 357.559864 -223.549719) (xy 357.560372 -223.575626) (xy 357.559981 -223.600993)
			(xy 357.552228 -223.651131) (xy 357.536877 -223.699486) (xy 357.514292 -223.744915) (xy 357.485007 -223.786344)
			(xy 357.449716 -223.822791) (xy 357.409252 -223.853396) (xy 357.364574 -223.877433) (xy 357.316739 -223.894334)
			(xy 357.291894 -223.899476) (xy 357.269034 -223.903794) (xy 357.06431 -224.258632) (xy 357.072184 -224.280476)
			(xy 357.080757 -224.306897) (xy 357.089958 -224.36167) (xy 357.090472 -224.389442) (xy 357.371396 -224.389442)
			(xy 357.371904 -224.363555) (xy 357.380003 -224.312417) (xy 357.396002 -224.263177) (xy 357.419508 -224.217045)
			(xy 357.44994 -224.175158) (xy 357.48655 -224.138548) (xy 357.528437 -224.108116) (xy 357.574569 -224.08461)
			(xy 357.623809 -224.068611) (xy 357.674947 -224.060512) (xy 357.726721 -224.060512) (xy 357.777859 -224.068611)
			(xy 357.827099 -224.08461) (xy 357.873231 -224.108116) (xy 357.915118 -224.138548) (xy 357.951728 -224.175158)
			(xy 357.98216 -224.217045) (xy 358.005666 -224.263177) (xy 358.021665 -224.312417) (xy 358.029764 -224.363555)
			(xy 358.030272 -224.389442) (xy 358.311196 -224.389442) (xy 358.311629 -224.364106) (xy 358.31939 -224.314032)
			(xy 358.33472 -224.265734) (xy 358.357259 -224.22035) (xy 358.386475 -224.178949) (xy 358.421681 -224.142504)
			(xy 358.462048 -224.111874) (xy 358.506626 -224.087781) (xy 358.554365 -224.070791) (xy 358.579166 -224.065592)
			(xy 358.602026 -224.061274) (xy 358.80675 -223.706436) (xy 358.79913 -223.684338) (xy 358.790502 -223.657991)
			(xy 358.781179 -223.603344) (xy 358.780588 -223.575626) (xy 358.781096 -223.549719) (xy 358.789202 -223.498542)
			(xy 358.805214 -223.449263) (xy 358.828737 -223.403096) (xy 358.859193 -223.361177) (xy 358.895831 -223.324539)
			(xy 358.93775 -223.294083) (xy 358.983917 -223.27056) (xy 359.033196 -223.254548) (xy 359.084373 -223.246442)
			(xy 359.136187 -223.246442) (xy 359.187364 -223.254548) (xy 359.236643 -223.27056) (xy 359.28281 -223.294083)
			(xy 359.324729 -223.324539) (xy 359.361367 -223.361177) (xy 359.391823 -223.403096) (xy 359.415346 -223.449263)
			(xy 359.431358 -223.498542) (xy 359.439464 -223.549719) (xy 359.439972 -223.575626) (xy 359.439581 -223.600993)
			(xy 359.431828 -223.651131) (xy 359.416477 -223.699486) (xy 359.393892 -223.744915) (xy 359.364607 -223.786344)
			(xy 359.329316 -223.822791) (xy 359.288852 -223.853396) (xy 359.244174 -223.877433) (xy 359.196339 -223.894334)
			(xy 359.171494 -223.899476) (xy 359.148634 -223.903794) (xy 358.94391 -224.258632) (xy 358.951784 -224.280476)
			(xy 358.960357 -224.306897) (xy 358.969558 -224.36167) (xy 358.970072 -224.389442) (xy 359.250996 -224.389442)
			(xy 359.251504 -224.363555) (xy 359.259603 -224.312417) (xy 359.275602 -224.263177) (xy 359.299108 -224.217045)
			(xy 359.32954 -224.175158) (xy 359.36615 -224.138548) (xy 359.408037 -224.108116) (xy 359.454169 -224.08461)
			(xy 359.503409 -224.068611) (xy 359.554547 -224.060512) (xy 359.606321 -224.060512) (xy 359.657459 -224.068611)
			(xy 359.706699 -224.08461) (xy 359.752831 -224.108116) (xy 359.794718 -224.138548) (xy 359.831328 -224.175158)
			(xy 359.86176 -224.217045) (xy 359.885266 -224.263177) (xy 359.901265 -224.312417) (xy 359.909364 -224.363555)
			(xy 359.909872 -224.389442) (xy 360.190796 -224.389442) (xy 360.191229 -224.364106) (xy 360.19899 -224.314032)
			(xy 360.21432 -224.265734) (xy 360.236859 -224.22035) (xy 360.266075 -224.178949) (xy 360.301281 -224.142504)
			(xy 360.341648 -224.111874) (xy 360.386226 -224.087781) (xy 360.433965 -224.070791) (xy 360.458766 -224.065592)
			(xy 360.481626 -224.061274) (xy 360.68635 -223.706436) (xy 360.67873 -223.684338) (xy 360.670102 -223.657991)
			(xy 360.660779 -223.603344) (xy 360.660188 -223.575626) (xy 360.660696 -223.549719) (xy 360.668802 -223.498542)
			(xy 360.684814 -223.449263) (xy 360.708337 -223.403096) (xy 360.738793 -223.361177) (xy 360.775431 -223.324539)
			(xy 360.81735 -223.294083) (xy 360.863517 -223.27056) (xy 360.912796 -223.254548) (xy 360.963973 -223.246442)
			(xy 361.015787 -223.246442) (xy 361.066964 -223.254548) (xy 361.116243 -223.27056) (xy 361.16241 -223.294083)
			(xy 361.204329 -223.324539) (xy 361.240967 -223.361177) (xy 361.271423 -223.403096) (xy 361.294946 -223.449263)
			(xy 361.310958 -223.498542) (xy 361.319064 -223.549719) (xy 361.319572 -223.575626) (xy 361.319181 -223.600993)
			(xy 361.311428 -223.651131) (xy 361.296077 -223.699486) (xy 361.273492 -223.744915) (xy 361.244207 -223.786344)
			(xy 361.208916 -223.822791) (xy 361.168452 -223.853396) (xy 361.123774 -223.877433) (xy 361.075939 -223.894334)
			(xy 361.051094 -223.899476) (xy 361.028234 -223.903794) (xy 360.82351 -224.258632) (xy 360.831384 -224.280476)
			(xy 360.839957 -224.306897) (xy 360.849158 -224.36167) (xy 360.849672 -224.389442) (xy 361.130596 -224.389442)
			(xy 361.131104 -224.363555) (xy 361.139203 -224.312417) (xy 361.155202 -224.263177) (xy 361.178708 -224.217045)
			(xy 361.20914 -224.175158) (xy 361.24575 -224.138548) (xy 361.287637 -224.108116) (xy 361.333769 -224.08461)
			(xy 361.383009 -224.068611) (xy 361.434147 -224.060512) (xy 361.485921 -224.060512) (xy 361.537059 -224.068611)
			(xy 361.586299 -224.08461) (xy 361.632431 -224.108116) (xy 361.674318 -224.138548) (xy 361.710928 -224.175158)
			(xy 361.74136 -224.217045) (xy 361.764866 -224.263177) (xy 361.780865 -224.312417) (xy 361.788964 -224.363555)
			(xy 361.789472 -224.389442) (xy 362.070396 -224.389442) (xy 362.070829 -224.364106) (xy 362.07859 -224.314032)
			(xy 362.09392 -224.265734) (xy 362.116459 -224.22035) (xy 362.145675 -224.178949) (xy 362.180881 -224.142504)
			(xy 362.221248 -224.111874) (xy 362.265826 -224.087781) (xy 362.313565 -224.070791) (xy 362.338366 -224.065592)
			(xy 362.361226 -224.061274) (xy 362.566204 -223.706182) (xy 362.558584 -223.684084) (xy 362.550064 -223.657913)
			(xy 362.540871 -223.603651) (xy 362.540296 -223.576134) (xy 362.540296 -223.575626) (xy 362.540804 -223.549739)
			(xy 362.548903 -223.498601) (xy 362.564902 -223.449361) (xy 362.588408 -223.403229) (xy 362.61884 -223.361342)
			(xy 362.65545 -223.324732) (xy 362.697337 -223.2943) (xy 362.743469 -223.270794) (xy 362.792709 -223.254795)
			(xy 362.843847 -223.246696) (xy 362.895621 -223.246696) (xy 362.946759 -223.254795) (xy 362.995999 -223.270794)
			(xy 363.042131 -223.2943) (xy 363.084018 -223.324732) (xy 363.120628 -223.361342) (xy 363.15106 -223.403229)
			(xy 363.174566 -223.449361) (xy 363.190565 -223.498601) (xy 363.198664 -223.549739) (xy 363.199172 -223.575626)
			(xy 363.198781 -223.600993) (xy 363.191028 -223.651131) (xy 363.175677 -223.699486) (xy 363.153092 -223.744915)
			(xy 363.123807 -223.786344) (xy 363.088516 -223.822791) (xy 363.048052 -223.853396) (xy 363.003374 -223.877433)
			(xy 362.955539 -223.894334) (xy 362.930694 -223.899476) (xy 362.907834 -223.903794) (xy 362.70311 -224.258632)
			(xy 362.710984 -224.280476) (xy 362.719557 -224.306897) (xy 362.728758 -224.36167) (xy 362.729272 -224.389442)
			(xy 363.010196 -224.389442) (xy 363.010704 -224.363555) (xy 363.018803 -224.312417) (xy 363.034802 -224.263177)
			(xy 363.058308 -224.217045) (xy 363.08874 -224.175158) (xy 363.12535 -224.138548) (xy 363.167237 -224.108116)
			(xy 363.213369 -224.08461) (xy 363.262609 -224.068611) (xy 363.313747 -224.060512) (xy 363.365521 -224.060512)
			(xy 363.416659 -224.068611) (xy 363.465899 -224.08461) (xy 363.512031 -224.108116) (xy 363.553918 -224.138548)
			(xy 363.590528 -224.175158) (xy 363.62096 -224.217045) (xy 363.644466 -224.263177) (xy 363.660465 -224.312417)
			(xy 363.668564 -224.363555) (xy 363.669072 -224.389442) (xy 363.949996 -224.389442) (xy 363.950429 -224.364106)
			(xy 363.95819 -224.314032) (xy 363.97352 -224.265734) (xy 363.996059 -224.22035) (xy 364.025275 -224.178949)
			(xy 364.060481 -224.142504) (xy 364.100848 -224.111874) (xy 364.145426 -224.087781) (xy 364.193165 -224.070791)
			(xy 364.217966 -224.065592) (xy 364.240826 -224.061274) (xy 364.44555 -223.706436) (xy 364.43793 -223.684338)
			(xy 364.429302 -223.657991) (xy 364.419979 -223.603344) (xy 364.419388 -223.575626) (xy 364.419896 -223.549719)
			(xy 364.428002 -223.498542) (xy 364.444014 -223.449263) (xy 364.467537 -223.403096) (xy 364.497993 -223.361177)
			(xy 364.534631 -223.324539) (xy 364.57655 -223.294083) (xy 364.622717 -223.27056) (xy 364.671996 -223.254548)
			(xy 364.723173 -223.246442) (xy 364.774987 -223.246442) (xy 364.826164 -223.254548) (xy 364.875443 -223.27056)
			(xy 364.92161 -223.294083) (xy 364.963529 -223.324539) (xy 365.000167 -223.361177) (xy 365.030623 -223.403096)
			(xy 365.054146 -223.449263) (xy 365.070158 -223.498542) (xy 365.078264 -223.549719) (xy 365.078772 -223.575626)
			(xy 365.078381 -223.600993) (xy 365.070628 -223.651131) (xy 365.055277 -223.699486) (xy 365.032692 -223.744915)
			(xy 365.003407 -223.786344) (xy 364.968116 -223.822791) (xy 364.927652 -223.853396) (xy 364.882974 -223.877433)
			(xy 364.835139 -223.894334) (xy 364.810294 -223.899476) (xy 364.787434 -223.903794) (xy 364.58271 -224.258632)
			(xy 364.590584 -224.280476) (xy 364.599157 -224.306897) (xy 364.608358 -224.36167) (xy 364.608872 -224.389442)
			(xy 364.889796 -224.389442) (xy 364.890304 -224.363555) (xy 364.898403 -224.312417) (xy 364.914402 -224.263177)
			(xy 364.937908 -224.217045) (xy 364.96834 -224.175158) (xy 365.00495 -224.138548) (xy 365.046837 -224.108116)
			(xy 365.092969 -224.08461) (xy 365.142209 -224.068611) (xy 365.193347 -224.060512) (xy 365.245121 -224.060512)
			(xy 365.296259 -224.068611) (xy 365.345499 -224.08461) (xy 365.391631 -224.108116) (xy 365.433518 -224.138548)
			(xy 365.470128 -224.175158) (xy 365.50056 -224.217045) (xy 365.524066 -224.263177) (xy 365.540065 -224.312417)
			(xy 365.548164 -224.363555) (xy 365.548672 -224.389442) (xy 365.829596 -224.389442) (xy 365.830029 -224.364106)
			(xy 365.83779 -224.314032) (xy 365.85312 -224.265734) (xy 365.875659 -224.22035) (xy 365.904875 -224.178949)
			(xy 365.940081 -224.142504) (xy 365.980448 -224.111874) (xy 366.025026 -224.087781) (xy 366.072765 -224.070791)
			(xy 366.097566 -224.065592) (xy 366.120426 -224.061274) (xy 366.32515 -223.706436) (xy 366.31753 -223.684338)
			(xy 366.308902 -223.657991) (xy 366.299579 -223.603344) (xy 366.298988 -223.575626) (xy 366.299496 -223.549719)
			(xy 366.307602 -223.498542) (xy 366.323614 -223.449263) (xy 366.347137 -223.403096) (xy 366.377593 -223.361177)
			(xy 366.414231 -223.324539) (xy 366.45615 -223.294083) (xy 366.502317 -223.27056) (xy 366.551596 -223.254548)
			(xy 366.602773 -223.246442) (xy 366.654587 -223.246442) (xy 366.705764 -223.254548) (xy 366.755043 -223.27056)
			(xy 366.80121 -223.294083) (xy 366.843129 -223.324539) (xy 366.879767 -223.361177) (xy 366.910223 -223.403096)
			(xy 366.933746 -223.449263) (xy 366.949758 -223.498542) (xy 366.957864 -223.549719) (xy 366.958372 -223.575626)
			(xy 366.957981 -223.600993) (xy 366.950228 -223.651131) (xy 366.934877 -223.699486) (xy 366.912292 -223.744915)
			(xy 366.883007 -223.786344) (xy 366.847716 -223.822791) (xy 366.807252 -223.853396) (xy 366.762574 -223.877433)
			(xy 366.714739 -223.894334) (xy 366.689894 -223.899476) (xy 366.667034 -223.903794) (xy 366.46231 -224.258632)
			(xy 366.470184 -224.280476) (xy 366.478757 -224.306897) (xy 366.487958 -224.36167) (xy 366.488472 -224.389442)
			(xy 366.769396 -224.389442) (xy 366.769904 -224.363555) (xy 366.778003 -224.312417) (xy 366.794002 -224.263177)
			(xy 366.817508 -224.217045) (xy 366.84794 -224.175158) (xy 366.88455 -224.138548) (xy 366.926437 -224.108116)
			(xy 366.972569 -224.08461) (xy 367.021809 -224.068611) (xy 367.072947 -224.060512) (xy 367.124721 -224.060512)
			(xy 367.175859 -224.068611) (xy 367.225099 -224.08461) (xy 367.271231 -224.108116) (xy 367.313118 -224.138548)
			(xy 367.349728 -224.175158) (xy 367.38016 -224.217045) (xy 367.403666 -224.263177) (xy 367.419665 -224.312417)
			(xy 367.427764 -224.363555) (xy 367.428272 -224.389442) (xy 367.709196 -224.389442) (xy 367.709629 -224.364106)
			(xy 367.71739 -224.314032) (xy 367.73272 -224.265734) (xy 367.755259 -224.22035) (xy 367.784475 -224.178949)
			(xy 367.819681 -224.142504) (xy 367.860048 -224.111874) (xy 367.904626 -224.087781) (xy 367.952365 -224.070791)
			(xy 367.977166 -224.065592) (xy 368.000026 -224.061274) (xy 368.20475 -223.706436) (xy 368.19713 -223.684338)
			(xy 368.188502 -223.657991) (xy 368.179179 -223.603344) (xy 368.178588 -223.575626) (xy 368.179096 -223.549719)
			(xy 368.187202 -223.498542) (xy 368.203214 -223.449263) (xy 368.226737 -223.403096) (xy 368.257193 -223.361177)
			(xy 368.293831 -223.324539) (xy 368.33575 -223.294083) (xy 368.381917 -223.27056) (xy 368.431196 -223.254548)
			(xy 368.482373 -223.246442) (xy 368.534187 -223.246442) (xy 368.585364 -223.254548) (xy 368.634643 -223.27056)
			(xy 368.68081 -223.294083) (xy 368.722729 -223.324539) (xy 368.759367 -223.361177) (xy 368.789823 -223.403096)
			(xy 368.813346 -223.449263) (xy 368.829358 -223.498542) (xy 368.837464 -223.549719) (xy 368.837972 -223.575626)
			(xy 368.837581 -223.600993) (xy 368.829828 -223.651131) (xy 368.814477 -223.699486) (xy 368.791892 -223.744915)
			(xy 368.762607 -223.786344) (xy 368.727316 -223.822791) (xy 368.686852 -223.853396) (xy 368.642174 -223.877433)
			(xy 368.594339 -223.894334) (xy 368.569494 -223.899476) (xy 368.546634 -223.903794) (xy 368.34191 -224.258632)
			(xy 368.349784 -224.280476) (xy 368.358357 -224.306897) (xy 368.367558 -224.36167) (xy 368.368072 -224.389442)
			(xy 368.648996 -224.389442) (xy 368.649504 -224.363555) (xy 368.657603 -224.312417) (xy 368.673602 -224.263177)
			(xy 368.697108 -224.217045) (xy 368.72754 -224.175158) (xy 368.76415 -224.138548) (xy 368.806037 -224.108116)
			(xy 368.852169 -224.08461) (xy 368.901409 -224.068611) (xy 368.952547 -224.060512) (xy 369.004321 -224.060512)
			(xy 369.055459 -224.068611) (xy 369.104699 -224.08461) (xy 369.150831 -224.108116) (xy 369.192718 -224.138548)
			(xy 369.229328 -224.175158) (xy 369.25976 -224.217045) (xy 369.283266 -224.263177) (xy 369.299265 -224.312417)
			(xy 369.307364 -224.363555) (xy 369.307872 -224.389442) (xy 369.588796 -224.389442) (xy 369.589229 -224.364106)
			(xy 369.59699 -224.314032) (xy 369.61232 -224.265734) (xy 369.634859 -224.22035) (xy 369.664075 -224.178949)
			(xy 369.699281 -224.142504) (xy 369.739648 -224.111874) (xy 369.784226 -224.087781) (xy 369.831965 -224.070791)
			(xy 369.856766 -224.065592) (xy 369.879626 -224.061274) (xy 370.08435 -223.706436) (xy 370.07673 -223.684338)
			(xy 370.068102 -223.657991) (xy 370.058779 -223.603344) (xy 370.058188 -223.575626) (xy 370.058696 -223.549719)
			(xy 370.066802 -223.498542) (xy 370.082814 -223.449263) (xy 370.106337 -223.403096) (xy 370.136793 -223.361177)
			(xy 370.173431 -223.324539) (xy 370.21535 -223.294083) (xy 370.261517 -223.27056) (xy 370.310796 -223.254548)
			(xy 370.361973 -223.246442) (xy 370.413787 -223.246442) (xy 370.464964 -223.254548) (xy 370.514243 -223.27056)
			(xy 370.56041 -223.294083) (xy 370.602329 -223.324539) (xy 370.638967 -223.361177) (xy 370.669423 -223.403096)
			(xy 370.692946 -223.449263) (xy 370.708958 -223.498542) (xy 370.717064 -223.549719) (xy 370.717572 -223.575626)
			(xy 370.717181 -223.600993) (xy 370.709428 -223.651131) (xy 370.694077 -223.699486) (xy 370.671492 -223.744915)
			(xy 370.642207 -223.786344) (xy 370.606916 -223.822791) (xy 370.566452 -223.853396) (xy 370.521774 -223.877433)
			(xy 370.473939 -223.894334) (xy 370.449094 -223.899476) (xy 370.426234 -223.903794) (xy 370.22151 -224.258632)
			(xy 370.229384 -224.280476) (xy 370.237957 -224.306897) (xy 370.247158 -224.36167) (xy 370.247672 -224.389442)
			(xy 370.528596 -224.389442) (xy 370.529104 -224.363555) (xy 370.537203 -224.312417) (xy 370.553202 -224.263177)
			(xy 370.576708 -224.217045) (xy 370.60714 -224.175158) (xy 370.64375 -224.138548) (xy 370.685637 -224.108116)
			(xy 370.731769 -224.08461) (xy 370.781009 -224.068611) (xy 370.832147 -224.060512) (xy 370.883921 -224.060512)
			(xy 370.935059 -224.068611) (xy 370.984299 -224.08461) (xy 371.030431 -224.108116) (xy 371.072318 -224.138548)
			(xy 371.108928 -224.175158) (xy 371.13936 -224.217045) (xy 371.162866 -224.263177) (xy 371.178865 -224.312417)
			(xy 371.186964 -224.363555) (xy 371.187472 -224.389442) (xy 371.468396 -224.389442) (xy 371.468829 -224.364106)
			(xy 371.47659 -224.314032) (xy 371.49192 -224.265734) (xy 371.514459 -224.22035) (xy 371.543675 -224.178949)
			(xy 371.578881 -224.142504) (xy 371.619248 -224.111874) (xy 371.663826 -224.087781) (xy 371.711565 -224.070791)
			(xy 371.736366 -224.065592) (xy 371.759226 -224.061274) (xy 371.96395 -223.706436) (xy 371.95633 -223.684338)
			(xy 371.947702 -223.657991) (xy 371.938379 -223.603344) (xy 371.937788 -223.575626) (xy 371.938296 -223.549719)
			(xy 371.946402 -223.498542) (xy 371.962414 -223.449263) (xy 371.985937 -223.403096) (xy 372.016393 -223.361177)
			(xy 372.053031 -223.324539) (xy 372.09495 -223.294083) (xy 372.141117 -223.27056) (xy 372.190396 -223.254548)
			(xy 372.241573 -223.246442) (xy 372.293387 -223.246442) (xy 372.344564 -223.254548) (xy 372.393843 -223.27056)
			(xy 372.44001 -223.294083) (xy 372.481929 -223.324539) (xy 372.518567 -223.361177) (xy 372.549023 -223.403096)
			(xy 372.572546 -223.449263) (xy 372.588558 -223.498542) (xy 372.596664 -223.549719) (xy 372.597172 -223.575626)
			(xy 372.596781 -223.600993) (xy 372.589028 -223.651131) (xy 372.573677 -223.699486) (xy 372.551092 -223.744915)
			(xy 372.521807 -223.786344) (xy 372.486516 -223.822791) (xy 372.446052 -223.853396) (xy 372.401374 -223.877433)
			(xy 372.353539 -223.894334) (xy 372.328694 -223.899476) (xy 372.305834 -223.903794) (xy 372.10111 -224.258632)
			(xy 372.108984 -224.280476) (xy 372.117557 -224.306897) (xy 372.126758 -224.36167) (xy 372.127272 -224.389442)
			(xy 372.408196 -224.389442) (xy 372.408704 -224.363555) (xy 372.416803 -224.312417) (xy 372.432802 -224.263177)
			(xy 372.456308 -224.217045) (xy 372.48674 -224.175158) (xy 372.52335 -224.138548) (xy 372.565237 -224.108116)
			(xy 372.611369 -224.08461) (xy 372.660609 -224.068611) (xy 372.711747 -224.060512) (xy 372.763521 -224.060512)
			(xy 372.814659 -224.068611) (xy 372.863899 -224.08461) (xy 372.910031 -224.108116) (xy 372.951918 -224.138548)
			(xy 372.988528 -224.175158) (xy 373.01896 -224.217045) (xy 373.042466 -224.263177) (xy 373.058465 -224.312417)
			(xy 373.066564 -224.363555) (xy 373.067072 -224.389442) (xy 373.347996 -224.389442) (xy 373.348429 -224.364106)
			(xy 373.35619 -224.314032) (xy 373.37152 -224.265734) (xy 373.394059 -224.22035) (xy 373.423275 -224.178949)
			(xy 373.458481 -224.142504) (xy 373.498848 -224.111874) (xy 373.543426 -224.087781) (xy 373.591165 -224.070791)
			(xy 373.615966 -224.065592) (xy 373.638826 -224.061274) (xy 373.84355 -223.706436) (xy 373.83593 -223.684338)
			(xy 373.827302 -223.657991) (xy 373.817979 -223.603344) (xy 373.817388 -223.575626) (xy 373.817896 -223.549719)
			(xy 373.826002 -223.498542) (xy 373.842014 -223.449263) (xy 373.865537 -223.403096) (xy 373.895993 -223.361177)
			(xy 373.932631 -223.324539) (xy 373.97455 -223.294083) (xy 374.020717 -223.27056) (xy 374.069996 -223.254548)
			(xy 374.121173 -223.246442) (xy 374.172987 -223.246442) (xy 374.224164 -223.254548) (xy 374.273443 -223.27056)
			(xy 374.31961 -223.294083) (xy 374.361529 -223.324539) (xy 374.398167 -223.361177) (xy 374.428623 -223.403096)
			(xy 374.452146 -223.449263) (xy 374.468158 -223.498542) (xy 374.476264 -223.549719) (xy 374.476772 -223.575626)
			(xy 374.476381 -223.600993) (xy 374.468628 -223.651131) (xy 374.453277 -223.699486) (xy 374.430692 -223.744915)
			(xy 374.401407 -223.786344) (xy 374.366116 -223.822791) (xy 374.325652 -223.853396) (xy 374.280974 -223.877433)
			(xy 374.233139 -223.894334) (xy 374.208294 -223.899476) (xy 374.185434 -223.903794) (xy 373.98071 -224.258632)
			(xy 373.988584 -224.280476) (xy 373.997157 -224.306897) (xy 374.006358 -224.36167) (xy 374.006872 -224.389442)
			(xy 374.287796 -224.389442) (xy 374.288304 -224.363555) (xy 374.296403 -224.312417) (xy 374.312402 -224.263177)
			(xy 374.335908 -224.217045) (xy 374.36634 -224.175158) (xy 374.40295 -224.138548) (xy 374.444837 -224.108116)
			(xy 374.490969 -224.08461) (xy 374.540209 -224.068611) (xy 374.591347 -224.060512) (xy 374.643121 -224.060512)
			(xy 374.694259 -224.068611) (xy 374.743499 -224.08461) (xy 374.789631 -224.108116) (xy 374.831518 -224.138548)
			(xy 374.868128 -224.175158) (xy 374.89856 -224.217045) (xy 374.922066 -224.263177) (xy 374.938065 -224.312417)
			(xy 374.946164 -224.363555) (xy 374.946672 -224.389442) (xy 375.227596 -224.389442) (xy 375.228029 -224.364106)
			(xy 375.23579 -224.314032) (xy 375.25112 -224.265734) (xy 375.273659 -224.22035) (xy 375.302875 -224.178949)
			(xy 375.338081 -224.142504) (xy 375.378448 -224.111874) (xy 375.423026 -224.087781) (xy 375.470765 -224.070791)
			(xy 375.495566 -224.065592) (xy 375.518426 -224.061274) (xy 375.72315 -223.706436) (xy 375.71553 -223.684338)
			(xy 375.706902 -223.657991) (xy 375.697579 -223.603344) (xy 375.696988 -223.575626) (xy 375.697496 -223.549719)
			(xy 375.705602 -223.498542) (xy 375.721614 -223.449263) (xy 375.745137 -223.403096) (xy 375.775593 -223.361177)
			(xy 375.812231 -223.324539) (xy 375.85415 -223.294083) (xy 375.900317 -223.27056) (xy 375.949596 -223.254548)
			(xy 376.000773 -223.246442) (xy 376.052587 -223.246442) (xy 376.103764 -223.254548) (xy 376.153043 -223.27056)
			(xy 376.19921 -223.294083) (xy 376.241129 -223.324539) (xy 376.277767 -223.361177) (xy 376.308223 -223.403096)
			(xy 376.331746 -223.449263) (xy 376.347758 -223.498542) (xy 376.355864 -223.549719) (xy 376.356372 -223.575626)
			(xy 376.355981 -223.600993) (xy 376.348228 -223.651131) (xy 376.332877 -223.699486) (xy 376.310292 -223.744915)
			(xy 376.281007 -223.786344) (xy 376.245716 -223.822791) (xy 376.205252 -223.853396) (xy 376.160574 -223.877433)
			(xy 376.112739 -223.894334) (xy 376.087894 -223.899476) (xy 376.065034 -223.903794) (xy 375.86031 -224.258632)
			(xy 375.868184 -224.280476) (xy 375.876757 -224.306897) (xy 375.885958 -224.36167) (xy 375.886472 -224.389442)
			(xy 376.167396 -224.389442) (xy 376.167904 -224.363555) (xy 376.176003 -224.312417) (xy 376.192002 -224.263177)
			(xy 376.215508 -224.217045) (xy 376.24594 -224.175158) (xy 376.28255 -224.138548) (xy 376.324437 -224.108116)
			(xy 376.370569 -224.08461) (xy 376.419809 -224.068611) (xy 376.470947 -224.060512) (xy 376.522721 -224.060512)
			(xy 376.573859 -224.068611) (xy 376.623099 -224.08461) (xy 376.669231 -224.108116) (xy 376.711118 -224.138548)
			(xy 376.747728 -224.175158) (xy 376.77816 -224.217045) (xy 376.801666 -224.263177) (xy 376.817665 -224.312417)
			(xy 376.825764 -224.363555) (xy 376.826272 -224.389442) (xy 377.107196 -224.389442) (xy 377.107629 -224.364106)
			(xy 377.11539 -224.314032) (xy 377.13072 -224.265734) (xy 377.153259 -224.22035) (xy 377.182475 -224.178949)
			(xy 377.217681 -224.142504) (xy 377.258048 -224.111874) (xy 377.302626 -224.087781) (xy 377.350365 -224.070791)
			(xy 377.375166 -224.065592) (xy 377.398026 -224.061274) (xy 377.60275 -223.706436) (xy 377.59513 -223.684338)
			(xy 377.586502 -223.657991) (xy 377.577179 -223.603344) (xy 377.576588 -223.575626) (xy 377.577096 -223.549719)
			(xy 377.585202 -223.498542) (xy 377.601214 -223.449263) (xy 377.624737 -223.403096) (xy 377.655193 -223.361177)
			(xy 377.691831 -223.324539) (xy 377.73375 -223.294083) (xy 377.779917 -223.27056) (xy 377.829196 -223.254548)
			(xy 377.880373 -223.246442) (xy 377.932187 -223.246442) (xy 377.983364 -223.254548) (xy 378.032643 -223.27056)
			(xy 378.07881 -223.294083) (xy 378.120729 -223.324539) (xy 378.157367 -223.361177) (xy 378.187823 -223.403096)
			(xy 378.211346 -223.449263) (xy 378.227358 -223.498542) (xy 378.235464 -223.549719) (xy 378.235972 -223.575626)
			(xy 378.235581 -223.600993) (xy 378.227828 -223.651131) (xy 378.212477 -223.699486) (xy 378.189892 -223.744915)
			(xy 378.160607 -223.786344) (xy 378.125316 -223.822791) (xy 378.084852 -223.853396) (xy 378.040174 -223.877433)
			(xy 377.992339 -223.894334) (xy 377.967494 -223.899476) (xy 377.944634 -223.903794) (xy 377.73991 -224.258632)
			(xy 377.747784 -224.280476) (xy 377.756357 -224.306897) (xy 377.765558 -224.36167) (xy 377.766072 -224.389442)
			(xy 378.046996 -224.389442) (xy 378.047504 -224.363555) (xy 378.055603 -224.312417) (xy 378.071602 -224.263177)
			(xy 378.095108 -224.217045) (xy 378.12554 -224.175158) (xy 378.16215 -224.138548) (xy 378.204037 -224.108116)
			(xy 378.250169 -224.08461) (xy 378.299409 -224.068611) (xy 378.350547 -224.060512) (xy 378.402321 -224.060512)
			(xy 378.453459 -224.068611) (xy 378.502699 -224.08461) (xy 378.548831 -224.108116) (xy 378.590718 -224.138548)
			(xy 378.627328 -224.175158) (xy 378.65776 -224.217045) (xy 378.681266 -224.263177) (xy 378.697265 -224.312417)
			(xy 378.705364 -224.363555) (xy 378.705872 -224.389442) (xy 378.986796 -224.389442) (xy 378.987229 -224.364106)
			(xy 378.99499 -224.314032) (xy 379.01032 -224.265734) (xy 379.032859 -224.22035) (xy 379.062075 -224.178949)
			(xy 379.097281 -224.142504) (xy 379.137648 -224.111874) (xy 379.182226 -224.087781) (xy 379.229965 -224.070791)
			(xy 379.254766 -224.065592) (xy 379.277626 -224.061274) (xy 379.48235 -223.706182) (xy 379.47473 -223.684338)
			(xy 379.466087 -223.657995) (xy 379.456772 -223.603345) (xy 379.456188 -223.575626) (xy 379.456696 -223.549719)
			(xy 379.464802 -223.498542) (xy 379.480814 -223.449263) (xy 379.504337 -223.403096) (xy 379.534793 -223.361177)
			(xy 379.571431 -223.324539) (xy 379.61335 -223.294083) (xy 379.659517 -223.27056) (xy 379.708796 -223.254548)
			(xy 379.759973 -223.246442) (xy 379.811787 -223.246442) (xy 379.862964 -223.254548) (xy 379.912243 -223.27056)
			(xy 379.95841 -223.294083) (xy 380.000329 -223.324539) (xy 380.036967 -223.361177) (xy 380.067423 -223.403096)
			(xy 380.090946 -223.449263) (xy 380.106958 -223.498542) (xy 380.115064 -223.549719) (xy 380.115572 -223.575626)
			(xy 380.115097 -223.600971) (xy 380.107321 -223.651063) (xy 380.091971 -223.699374) (xy 380.069408 -223.744767)
			(xy 380.040166 -223.786173) (xy 380.004931 -223.822617) (xy 379.964535 -223.853239) (xy 379.919928 -223.877319)
			(xy 379.872162 -223.89429) (xy 379.847348 -223.899476) (xy 379.824488 -223.903794) (xy 379.619764 -224.258632)
			(xy 379.627384 -224.280476) (xy 379.635939 -224.306769) (xy 379.645132 -224.361289) (xy 379.645672 -224.388934)
			(xy 379.645672 -224.389442) (xy 379.926596 -224.389442) (xy 379.927104 -224.363555) (xy 379.935203 -224.312417)
			(xy 379.951202 -224.263177) (xy 379.974708 -224.217045) (xy 380.00514 -224.175158) (xy 380.04175 -224.138548)
			(xy 380.083637 -224.108116) (xy 380.129769 -224.08461) (xy 380.179009 -224.068611) (xy 380.230147 -224.060512)
			(xy 380.281921 -224.060512) (xy 380.333059 -224.068611) (xy 380.382299 -224.08461) (xy 380.428431 -224.108116)
			(xy 380.470318 -224.138548) (xy 380.506928 -224.175158) (xy 380.53736 -224.217045) (xy 380.560866 -224.263177)
			(xy 380.576865 -224.312417) (xy 380.584964 -224.363555) (xy 380.585472 -224.389442) (xy 380.866396 -224.389442)
			(xy 380.866829 -224.364106) (xy 380.87459 -224.314032) (xy 380.88992 -224.265734) (xy 380.912459 -224.22035)
			(xy 380.941675 -224.178949) (xy 380.976881 -224.142504) (xy 381.017248 -224.111874) (xy 381.061826 -224.087781)
			(xy 381.109565 -224.070791) (xy 381.134366 -224.065592) (xy 381.157226 -224.061274) (xy 381.362204 -223.705928)
			(xy 381.354584 -223.684084) (xy 381.346064 -223.657913) (xy 381.336871 -223.603651) (xy 381.336296 -223.576134)
			(xy 381.336296 -223.575626) (xy 381.336804 -223.549739) (xy 381.344903 -223.498601) (xy 381.360902 -223.449361)
			(xy 381.384408 -223.403229) (xy 381.41484 -223.361342) (xy 381.45145 -223.324732) (xy 381.493337 -223.2943)
			(xy 381.539469 -223.270794) (xy 381.588709 -223.254795) (xy 381.639847 -223.246696) (xy 381.691621 -223.246696)
			(xy 381.742759 -223.254795) (xy 381.791999 -223.270794) (xy 381.838131 -223.2943) (xy 381.880018 -223.324732)
			(xy 381.916628 -223.361342) (xy 381.94706 -223.403229) (xy 381.970566 -223.449361) (xy 381.986565 -223.498601)
			(xy 381.994664 -223.549739) (xy 381.995172 -223.575626) (xy 381.994697 -223.600971) (xy 381.986921 -223.651063)
			(xy 381.971571 -223.699374) (xy 381.949008 -223.744767) (xy 381.919766 -223.786173) (xy 381.884531 -223.822617)
			(xy 381.844135 -223.853239) (xy 381.799528 -223.877319) (xy 381.751762 -223.89429) (xy 381.726948 -223.899476)
			(xy 381.704088 -223.903794) (xy 381.499364 -224.258632) (xy 381.506984 -224.280476) (xy 381.515539 -224.306769)
			(xy 381.524732 -224.361289) (xy 381.525272 -224.388934) (xy 381.525272 -224.389442) (xy 381.806196 -224.389442)
			(xy 381.806704 -224.363555) (xy 381.814803 -224.312417) (xy 381.830802 -224.263177) (xy 381.854308 -224.217045)
			(xy 381.88474 -224.175158) (xy 381.92135 -224.138548) (xy 381.963237 -224.108116) (xy 382.009369 -224.08461)
			(xy 382.058609 -224.068611) (xy 382.109747 -224.060512) (xy 382.161521 -224.060512) (xy 382.212659 -224.068611)
			(xy 382.261899 -224.08461) (xy 382.308031 -224.108116) (xy 382.349918 -224.138548) (xy 382.386528 -224.175158)
			(xy 382.41696 -224.217045) (xy 382.440466 -224.263177) (xy 382.456465 -224.312417) (xy 382.464564 -224.363555)
			(xy 382.465072 -224.389442) (xy 382.464539 -224.41715) (xy 382.455342 -224.471795) (xy 382.446784 -224.498154)
			(xy 382.439164 -224.519998) (xy 382.644142 -224.87509) (xy 382.667002 -224.879408) (xy 382.691815 -224.884555)
			(xy 382.739557 -224.901547) (xy 382.784137 -224.925644) (xy 382.824504 -224.95628) (xy 382.859707 -224.992732)
			(xy 382.888918 -225.034142) (xy 382.911448 -225.079534) (xy 382.926766 -225.12784) (xy 382.934512 -225.17792)
			(xy 382.934972 -225.203258) (xy 382.934464 -225.229145) (xy 382.926365 -225.280283) (xy 382.910366 -225.329523)
			(xy 382.88686 -225.375655) (xy 382.856428 -225.417542) (xy 382.819818 -225.454152) (xy 382.777931 -225.484584)
			(xy 382.731799 -225.50809) (xy 382.682559 -225.524089) (xy 382.631421 -225.532188) (xy 382.579647 -225.532188)
			(xy 382.528509 -225.524089) (xy 382.479269 -225.50809) (xy 382.433137 -225.484584) (xy 382.39125 -225.454152)
			(xy 382.35464 -225.417542) (xy 382.324208 -225.375655) (xy 382.300702 -225.329523) (xy 382.284703 -225.280283)
			(xy 382.276604 -225.229145) (xy 382.276096 -225.203258) (xy 382.276096 -225.20275) (xy 382.276653 -225.175107)
			(xy 382.285844 -225.120589) (xy 382.294384 -225.094292) (xy 382.302004 -225.072448) (xy 382.09728 -224.71761)
			(xy 382.07442 -224.713292) (xy 382.049591 -224.708158) (xy 382.001812 -224.691199) (xy 381.957192 -224.667122)
			(xy 381.916786 -224.636498) (xy 381.881546 -224.600046) (xy 381.852303 -224.558629) (xy 381.829748 -224.513222)
			(xy 381.814412 -224.464896) (xy 381.806657 -224.414792) (xy 381.806196 -224.389442) (xy 381.525272 -224.389442)
			(xy 381.524764 -224.415329) (xy 381.516665 -224.466467) (xy 381.500666 -224.515707) (xy 381.47716 -224.561839)
			(xy 381.446728 -224.603726) (xy 381.410118 -224.640336) (xy 381.368231 -224.670768) (xy 381.322099 -224.694274)
			(xy 381.272859 -224.710273) (xy 381.221721 -224.718372) (xy 381.169947 -224.718372) (xy 381.118809 -224.710273)
			(xy 381.069569 -224.694274) (xy 381.023437 -224.670768) (xy 380.98155 -224.640336) (xy 380.94494 -224.603726)
			(xy 380.914508 -224.561839) (xy 380.891002 -224.515707) (xy 380.875003 -224.466467) (xy 380.866904 -224.415329)
			(xy 380.866396 -224.389442) (xy 380.585472 -224.389442) (xy 380.584925 -224.417149) (xy 380.575741 -224.471796)
			(xy 380.567184 -224.498154) (xy 380.55931 -224.520252) (xy 380.764288 -224.87509) (xy 380.787148 -224.879408)
			(xy 380.811971 -224.884565) (xy 380.859751 -224.90152) (xy 380.904371 -224.925592) (xy 380.944778 -224.956214)
			(xy 380.980019 -224.992662) (xy 381.009263 -225.034077) (xy 381.031819 -225.079482) (xy 381.047156 -225.127806)
			(xy 381.054911 -225.177908) (xy 381.055372 -225.203258) (xy 381.054864 -225.229165) (xy 381.046758 -225.280342)
			(xy 381.030746 -225.329621) (xy 381.007223 -225.375788) (xy 380.976767 -225.417707) (xy 380.940129 -225.454345)
			(xy 380.89821 -225.484801) (xy 380.852043 -225.508324) (xy 380.802764 -225.524336) (xy 380.751587 -225.532442)
			(xy 380.699773 -225.532442) (xy 380.648596 -225.524336) (xy 380.599317 -225.508324) (xy 380.55315 -225.484801)
			(xy 380.511231 -225.454345) (xy 380.474593 -225.417707) (xy 380.444137 -225.375788) (xy 380.420614 -225.329621)
			(xy 380.404602 -225.280342) (xy 380.396496 -225.229165) (xy 380.395988 -225.203258) (xy 380.396597 -225.175541)
			(xy 380.40591 -225.120895) (xy 380.41453 -225.094546) (xy 380.422404 -225.072448) (xy 380.217426 -224.71761)
			(xy 380.194566 -224.713292) (xy 380.169748 -224.708169) (xy 380.122005 -224.691172) (xy 380.077426 -224.667071)
			(xy 380.03706 -224.636431) (xy 380.001857 -224.599976) (xy 379.972648 -224.558564) (xy 379.950119 -224.51317)
			(xy 379.934801 -224.464863) (xy 379.927055 -224.414781) (xy 379.926596 -224.389442) (xy 379.645672 -224.389442)
			(xy 379.645164 -224.415329) (xy 379.637065 -224.466467) (xy 379.621066 -224.515707) (xy 379.59756 -224.561839)
			(xy 379.567128 -224.603726) (xy 379.530518 -224.640336) (xy 379.488631 -224.670768) (xy 379.442499 -224.694274)
			(xy 379.393259 -224.710273) (xy 379.342121 -224.718372) (xy 379.290347 -224.718372) (xy 379.239209 -224.710273)
			(xy 379.189969 -224.694274) (xy 379.143837 -224.670768) (xy 379.10195 -224.640336) (xy 379.06534 -224.603726)
			(xy 379.034908 -224.561839) (xy 379.011402 -224.515707) (xy 378.995403 -224.466467) (xy 378.987304 -224.415329)
			(xy 378.986796 -224.389442) (xy 378.705872 -224.389442) (xy 378.705325 -224.417149) (xy 378.696141 -224.471796)
			(xy 378.687584 -224.498154) (xy 378.67971 -224.520252) (xy 378.884688 -224.87509) (xy 378.907548 -224.879408)
			(xy 378.932371 -224.884565) (xy 378.980151 -224.90152) (xy 379.024771 -224.925592) (xy 379.065178 -224.956214)
			(xy 379.100419 -224.992662) (xy 379.129663 -225.034077) (xy 379.152219 -225.079482) (xy 379.167556 -225.127806)
			(xy 379.175311 -225.177908) (xy 379.175772 -225.203258) (xy 379.175264 -225.229165) (xy 379.167158 -225.280342)
			(xy 379.151146 -225.329621) (xy 379.127623 -225.375788) (xy 379.097167 -225.417707) (xy 379.060529 -225.454345)
			(xy 379.01861 -225.484801) (xy 378.972443 -225.508324) (xy 378.923164 -225.524336) (xy 378.871987 -225.532442)
			(xy 378.820173 -225.532442) (xy 378.768996 -225.524336) (xy 378.719717 -225.508324) (xy 378.67355 -225.484801)
			(xy 378.631631 -225.454345) (xy 378.594993 -225.417707) (xy 378.564537 -225.375788) (xy 378.541014 -225.329621)
			(xy 378.525002 -225.280342) (xy 378.516896 -225.229165) (xy 378.516388 -225.203258) (xy 378.516997 -225.175541)
			(xy 378.52631 -225.120895) (xy 378.53493 -225.094546) (xy 378.542804 -225.072448) (xy 378.337826 -224.71761)
			(xy 378.314966 -224.713292) (xy 378.290148 -224.708169) (xy 378.242405 -224.691172) (xy 378.197826 -224.667071)
			(xy 378.15746 -224.636431) (xy 378.122257 -224.599976) (xy 378.093048 -224.558564) (xy 378.070519 -224.51317)
			(xy 378.055201 -224.464863) (xy 378.047455 -224.414781) (xy 378.046996 -224.389442) (xy 377.766072 -224.389442)
			(xy 377.765564 -224.415329) (xy 377.757465 -224.466467) (xy 377.741466 -224.515707) (xy 377.71796 -224.561839)
			(xy 377.687528 -224.603726) (xy 377.650918 -224.640336) (xy 377.609031 -224.670768) (xy 377.562899 -224.694274)
			(xy 377.513659 -224.710273) (xy 377.462521 -224.718372) (xy 377.410747 -224.718372) (xy 377.359609 -224.710273)
			(xy 377.310369 -224.694274) (xy 377.264237 -224.670768) (xy 377.22235 -224.640336) (xy 377.18574 -224.603726)
			(xy 377.155308 -224.561839) (xy 377.131802 -224.515707) (xy 377.115803 -224.466467) (xy 377.107704 -224.415329)
			(xy 377.107196 -224.389442) (xy 376.826272 -224.389442) (xy 376.825725 -224.417149) (xy 376.816541 -224.471796)
			(xy 376.807984 -224.498154) (xy 376.80011 -224.520252) (xy 377.005088 -224.87509) (xy 377.027948 -224.879408)
			(xy 377.052771 -224.884565) (xy 377.100551 -224.90152) (xy 377.145171 -224.925592) (xy 377.185578 -224.956214)
			(xy 377.220819 -224.992662) (xy 377.250063 -225.034077) (xy 377.272619 -225.079482) (xy 377.287956 -225.127806)
			(xy 377.295711 -225.177908) (xy 377.296172 -225.203258) (xy 377.295664 -225.229165) (xy 377.287558 -225.280342)
			(xy 377.271546 -225.329621) (xy 377.248023 -225.375788) (xy 377.217567 -225.417707) (xy 377.180929 -225.454345)
			(xy 377.13901 -225.484801) (xy 377.092843 -225.508324) (xy 377.043564 -225.524336) (xy 376.992387 -225.532442)
			(xy 376.940573 -225.532442) (xy 376.889396 -225.524336) (xy 376.840117 -225.508324) (xy 376.79395 -225.484801)
			(xy 376.752031 -225.454345) (xy 376.715393 -225.417707) (xy 376.684937 -225.375788) (xy 376.661414 -225.329621)
			(xy 376.645402 -225.280342) (xy 376.637296 -225.229165) (xy 376.636788 -225.203258) (xy 376.637397 -225.175541)
			(xy 376.64671 -225.120895) (xy 376.65533 -225.094546) (xy 376.663204 -225.072448) (xy 376.458226 -224.71761)
			(xy 376.435366 -224.713292) (xy 376.410548 -224.708169) (xy 376.362805 -224.691172) (xy 376.318226 -224.667071)
			(xy 376.27786 -224.636431) (xy 376.242657 -224.599976) (xy 376.213448 -224.558564) (xy 376.190919 -224.51317)
			(xy 376.175601 -224.464863) (xy 376.167855 -224.414781) (xy 376.167396 -224.389442) (xy 375.886472 -224.389442)
			(xy 375.885964 -224.415329) (xy 375.877865 -224.466467) (xy 375.861866 -224.515707) (xy 375.83836 -224.561839)
			(xy 375.807928 -224.603726) (xy 375.771318 -224.640336) (xy 375.729431 -224.670768) (xy 375.683299 -224.694274)
			(xy 375.634059 -224.710273) (xy 375.582921 -224.718372) (xy 375.531147 -224.718372) (xy 375.480009 -224.710273)
			(xy 375.430769 -224.694274) (xy 375.384637 -224.670768) (xy 375.34275 -224.640336) (xy 375.30614 -224.603726)
			(xy 375.275708 -224.561839) (xy 375.252202 -224.515707) (xy 375.236203 -224.466467) (xy 375.228104 -224.415329)
			(xy 375.227596 -224.389442) (xy 374.946672 -224.389442) (xy 374.946125 -224.417149) (xy 374.936941 -224.471796)
			(xy 374.928384 -224.498154) (xy 374.92051 -224.520252) (xy 375.125488 -224.87509) (xy 375.148348 -224.879408)
			(xy 375.173171 -224.884565) (xy 375.220951 -224.90152) (xy 375.265571 -224.925592) (xy 375.305978 -224.956214)
			(xy 375.341219 -224.992662) (xy 375.370463 -225.034077) (xy 375.393019 -225.079482) (xy 375.408356 -225.127806)
			(xy 375.416111 -225.177908) (xy 375.416572 -225.203258) (xy 375.416064 -225.229165) (xy 375.407958 -225.280342)
			(xy 375.391946 -225.329621) (xy 375.368423 -225.375788) (xy 375.337967 -225.417707) (xy 375.301329 -225.454345)
			(xy 375.25941 -225.484801) (xy 375.213243 -225.508324) (xy 375.163964 -225.524336) (xy 375.112787 -225.532442)
			(xy 375.060973 -225.532442) (xy 375.009796 -225.524336) (xy 374.960517 -225.508324) (xy 374.91435 -225.484801)
			(xy 374.872431 -225.454345) (xy 374.835793 -225.417707) (xy 374.805337 -225.375788) (xy 374.781814 -225.329621)
			(xy 374.765802 -225.280342) (xy 374.757696 -225.229165) (xy 374.757188 -225.203258) (xy 374.757797 -225.175541)
			(xy 374.76711 -225.120895) (xy 374.77573 -225.094546) (xy 374.783604 -225.072448) (xy 374.578626 -224.71761)
			(xy 374.555766 -224.713292) (xy 374.530948 -224.708169) (xy 374.483205 -224.691172) (xy 374.438626 -224.667071)
			(xy 374.39826 -224.636431) (xy 374.363057 -224.599976) (xy 374.333848 -224.558564) (xy 374.311319 -224.51317)
			(xy 374.296001 -224.464863) (xy 374.288255 -224.414781) (xy 374.287796 -224.389442) (xy 374.006872 -224.389442)
			(xy 374.006364 -224.415329) (xy 373.998265 -224.466467) (xy 373.982266 -224.515707) (xy 373.95876 -224.561839)
			(xy 373.928328 -224.603726) (xy 373.891718 -224.640336) (xy 373.849831 -224.670768) (xy 373.803699 -224.694274)
			(xy 373.754459 -224.710273) (xy 373.703321 -224.718372) (xy 373.651547 -224.718372) (xy 373.600409 -224.710273)
			(xy 373.551169 -224.694274) (xy 373.505037 -224.670768) (xy 373.46315 -224.640336) (xy 373.42654 -224.603726)
			(xy 373.396108 -224.561839) (xy 373.372602 -224.515707) (xy 373.356603 -224.466467) (xy 373.348504 -224.415329)
			(xy 373.347996 -224.389442) (xy 373.067072 -224.389442) (xy 373.066525 -224.417149) (xy 373.057341 -224.471796)
			(xy 373.048784 -224.498154) (xy 373.04091 -224.520252) (xy 373.245888 -224.87509) (xy 373.268748 -224.879408)
			(xy 373.293571 -224.884565) (xy 373.341351 -224.90152) (xy 373.385971 -224.925592) (xy 373.426378 -224.956214)
			(xy 373.461619 -224.992662) (xy 373.490863 -225.034077) (xy 373.513419 -225.079482) (xy 373.528756 -225.127806)
			(xy 373.536511 -225.177908) (xy 373.536972 -225.203258) (xy 373.536464 -225.229165) (xy 373.528358 -225.280342)
			(xy 373.512346 -225.329621) (xy 373.488823 -225.375788) (xy 373.458367 -225.417707) (xy 373.421729 -225.454345)
			(xy 373.37981 -225.484801) (xy 373.333643 -225.508324) (xy 373.284364 -225.524336) (xy 373.233187 -225.532442)
			(xy 373.181373 -225.532442) (xy 373.130196 -225.524336) (xy 373.080917 -225.508324) (xy 373.03475 -225.484801)
			(xy 372.992831 -225.454345) (xy 372.956193 -225.417707) (xy 372.925737 -225.375788) (xy 372.902214 -225.329621)
			(xy 372.886202 -225.280342) (xy 372.878096 -225.229165) (xy 372.877588 -225.203258) (xy 372.878197 -225.175541)
			(xy 372.88751 -225.120895) (xy 372.89613 -225.094546) (xy 372.904004 -225.072448) (xy 372.699026 -224.71761)
			(xy 372.676166 -224.713292) (xy 372.651348 -224.708169) (xy 372.603605 -224.691172) (xy 372.559026 -224.667071)
			(xy 372.51866 -224.636431) (xy 372.483457 -224.599976) (xy 372.454248 -224.558564) (xy 372.431719 -224.51317)
			(xy 372.416401 -224.464863) (xy 372.408655 -224.414781) (xy 372.408196 -224.389442) (xy 372.127272 -224.389442)
			(xy 372.126764 -224.415329) (xy 372.118665 -224.466467) (xy 372.102666 -224.515707) (xy 372.07916 -224.561839)
			(xy 372.048728 -224.603726) (xy 372.012118 -224.640336) (xy 371.970231 -224.670768) (xy 371.924099 -224.694274)
			(xy 371.874859 -224.710273) (xy 371.823721 -224.718372) (xy 371.771947 -224.718372) (xy 371.720809 -224.710273)
			(xy 371.671569 -224.694274) (xy 371.625437 -224.670768) (xy 371.58355 -224.640336) (xy 371.54694 -224.603726)
			(xy 371.516508 -224.561839) (xy 371.493002 -224.515707) (xy 371.477003 -224.466467) (xy 371.468904 -224.415329)
			(xy 371.468396 -224.389442) (xy 371.187472 -224.389442) (xy 371.186925 -224.417149) (xy 371.177741 -224.471796)
			(xy 371.169184 -224.498154) (xy 371.16131 -224.520252) (xy 371.366288 -224.87509) (xy 371.389148 -224.879408)
			(xy 371.413971 -224.884565) (xy 371.461751 -224.90152) (xy 371.506371 -224.925592) (xy 371.546778 -224.956214)
			(xy 371.582019 -224.992662) (xy 371.611263 -225.034077) (xy 371.633819 -225.079482) (xy 371.649156 -225.127806)
			(xy 371.656911 -225.177908) (xy 371.657372 -225.203258) (xy 371.656864 -225.229165) (xy 371.648758 -225.280342)
			(xy 371.632746 -225.329621) (xy 371.609223 -225.375788) (xy 371.578767 -225.417707) (xy 371.542129 -225.454345)
			(xy 371.50021 -225.484801) (xy 371.454043 -225.508324) (xy 371.404764 -225.524336) (xy 371.353587 -225.532442)
			(xy 371.301773 -225.532442) (xy 371.250596 -225.524336) (xy 371.201317 -225.508324) (xy 371.15515 -225.484801)
			(xy 371.113231 -225.454345) (xy 371.076593 -225.417707) (xy 371.046137 -225.375788) (xy 371.022614 -225.329621)
			(xy 371.006602 -225.280342) (xy 370.998496 -225.229165) (xy 370.997988 -225.203258) (xy 370.998597 -225.175541)
			(xy 371.00791 -225.120895) (xy 371.01653 -225.094546) (xy 371.024404 -225.072448) (xy 370.819426 -224.71761)
			(xy 370.796566 -224.713292) (xy 370.771748 -224.708169) (xy 370.724005 -224.691172) (xy 370.679426 -224.667071)
			(xy 370.63906 -224.636431) (xy 370.603857 -224.599976) (xy 370.574648 -224.558564) (xy 370.552119 -224.51317)
			(xy 370.536801 -224.464863) (xy 370.529055 -224.414781) (xy 370.528596 -224.389442) (xy 370.247672 -224.389442)
			(xy 370.247164 -224.415329) (xy 370.239065 -224.466467) (xy 370.223066 -224.515707) (xy 370.19956 -224.561839)
			(xy 370.169128 -224.603726) (xy 370.132518 -224.640336) (xy 370.090631 -224.670768) (xy 370.044499 -224.694274)
			(xy 369.995259 -224.710273) (xy 369.944121 -224.718372) (xy 369.892347 -224.718372) (xy 369.841209 -224.710273)
			(xy 369.791969 -224.694274) (xy 369.745837 -224.670768) (xy 369.70395 -224.640336) (xy 369.66734 -224.603726)
			(xy 369.636908 -224.561839) (xy 369.613402 -224.515707) (xy 369.597403 -224.466467) (xy 369.589304 -224.415329)
			(xy 369.588796 -224.389442) (xy 369.307872 -224.389442) (xy 369.307325 -224.417149) (xy 369.298141 -224.471796)
			(xy 369.289584 -224.498154) (xy 369.28171 -224.520252) (xy 369.486688 -224.87509) (xy 369.509548 -224.879408)
			(xy 369.534371 -224.884565) (xy 369.582151 -224.90152) (xy 369.626771 -224.925592) (xy 369.667178 -224.956214)
			(xy 369.702419 -224.992662) (xy 369.731663 -225.034077) (xy 369.754219 -225.079482) (xy 369.769556 -225.127806)
			(xy 369.777311 -225.177908) (xy 369.777772 -225.203258) (xy 369.777264 -225.229165) (xy 369.769158 -225.280342)
			(xy 369.753146 -225.329621) (xy 369.729623 -225.375788) (xy 369.699167 -225.417707) (xy 369.662529 -225.454345)
			(xy 369.62061 -225.484801) (xy 369.574443 -225.508324) (xy 369.525164 -225.524336) (xy 369.473987 -225.532442)
			(xy 369.422173 -225.532442) (xy 369.370996 -225.524336) (xy 369.321717 -225.508324) (xy 369.27555 -225.484801)
			(xy 369.233631 -225.454345) (xy 369.196993 -225.417707) (xy 369.166537 -225.375788) (xy 369.143014 -225.329621)
			(xy 369.127002 -225.280342) (xy 369.118896 -225.229165) (xy 369.118388 -225.203258) (xy 369.118997 -225.175541)
			(xy 369.12831 -225.120895) (xy 369.13693 -225.094546) (xy 369.144804 -225.072448) (xy 368.939826 -224.71761)
			(xy 368.916966 -224.713292) (xy 368.892148 -224.708169) (xy 368.844405 -224.691172) (xy 368.799826 -224.667071)
			(xy 368.75946 -224.636431) (xy 368.724257 -224.599976) (xy 368.695048 -224.558564) (xy 368.672519 -224.51317)
			(xy 368.657201 -224.464863) (xy 368.649455 -224.414781) (xy 368.648996 -224.389442) (xy 368.368072 -224.389442)
			(xy 368.367564 -224.415329) (xy 368.359465 -224.466467) (xy 368.343466 -224.515707) (xy 368.31996 -224.561839)
			(xy 368.289528 -224.603726) (xy 368.252918 -224.640336) (xy 368.211031 -224.670768) (xy 368.164899 -224.694274)
			(xy 368.115659 -224.710273) (xy 368.064521 -224.718372) (xy 368.012747 -224.718372) (xy 367.961609 -224.710273)
			(xy 367.912369 -224.694274) (xy 367.866237 -224.670768) (xy 367.82435 -224.640336) (xy 367.78774 -224.603726)
			(xy 367.757308 -224.561839) (xy 367.733802 -224.515707) (xy 367.717803 -224.466467) (xy 367.709704 -224.415329)
			(xy 367.709196 -224.389442) (xy 367.428272 -224.389442) (xy 367.427725 -224.417149) (xy 367.418541 -224.471796)
			(xy 367.409984 -224.498154) (xy 367.40211 -224.520252) (xy 367.607088 -224.87509) (xy 367.629948 -224.879408)
			(xy 367.654771 -224.884565) (xy 367.702551 -224.90152) (xy 367.747171 -224.925592) (xy 367.787578 -224.956214)
			(xy 367.822819 -224.992662) (xy 367.852063 -225.034077) (xy 367.874619 -225.079482) (xy 367.889956 -225.127806)
			(xy 367.897711 -225.177908) (xy 367.898172 -225.203258) (xy 367.897664 -225.229165) (xy 367.889558 -225.280342)
			(xy 367.873546 -225.329621) (xy 367.850023 -225.375788) (xy 367.819567 -225.417707) (xy 367.782929 -225.454345)
			(xy 367.74101 -225.484801) (xy 367.694843 -225.508324) (xy 367.645564 -225.524336) (xy 367.594387 -225.532442)
			(xy 367.542573 -225.532442) (xy 367.491396 -225.524336) (xy 367.442117 -225.508324) (xy 367.39595 -225.484801)
			(xy 367.354031 -225.454345) (xy 367.317393 -225.417707) (xy 367.286937 -225.375788) (xy 367.263414 -225.329621)
			(xy 367.247402 -225.280342) (xy 367.239296 -225.229165) (xy 367.238788 -225.203258) (xy 367.239397 -225.175541)
			(xy 367.24871 -225.120895) (xy 367.25733 -225.094546) (xy 367.265204 -225.072448) (xy 367.060226 -224.71761)
			(xy 367.037366 -224.713292) (xy 367.012548 -224.708169) (xy 366.964805 -224.691172) (xy 366.920226 -224.667071)
			(xy 366.87986 -224.636431) (xy 366.844657 -224.599976) (xy 366.815448 -224.558564) (xy 366.792919 -224.51317)
			(xy 366.777601 -224.464863) (xy 366.769855 -224.414781) (xy 366.769396 -224.389442) (xy 366.488472 -224.389442)
			(xy 366.487964 -224.415329) (xy 366.479865 -224.466467) (xy 366.463866 -224.515707) (xy 366.44036 -224.561839)
			(xy 366.409928 -224.603726) (xy 366.373318 -224.640336) (xy 366.331431 -224.670768) (xy 366.285299 -224.694274)
			(xy 366.236059 -224.710273) (xy 366.184921 -224.718372) (xy 366.133147 -224.718372) (xy 366.082009 -224.710273)
			(xy 366.032769 -224.694274) (xy 365.986637 -224.670768) (xy 365.94475 -224.640336) (xy 365.90814 -224.603726)
			(xy 365.877708 -224.561839) (xy 365.854202 -224.515707) (xy 365.838203 -224.466467) (xy 365.830104 -224.415329)
			(xy 365.829596 -224.389442) (xy 365.548672 -224.389442) (xy 365.548125 -224.417149) (xy 365.538941 -224.471796)
			(xy 365.530384 -224.498154) (xy 365.52251 -224.520252) (xy 365.727488 -224.87509) (xy 365.750348 -224.879408)
			(xy 365.775171 -224.884565) (xy 365.822951 -224.90152) (xy 365.867571 -224.925592) (xy 365.907978 -224.956214)
			(xy 365.943219 -224.992662) (xy 365.972463 -225.034077) (xy 365.995019 -225.079482) (xy 366.010356 -225.127806)
			(xy 366.018111 -225.177908) (xy 366.018572 -225.203258) (xy 366.018064 -225.229165) (xy 366.009958 -225.280342)
			(xy 365.993946 -225.329621) (xy 365.970423 -225.375788) (xy 365.939967 -225.417707) (xy 365.903329 -225.454345)
			(xy 365.86141 -225.484801) (xy 365.815243 -225.508324) (xy 365.765964 -225.524336) (xy 365.714787 -225.532442)
			(xy 365.662973 -225.532442) (xy 365.611796 -225.524336) (xy 365.562517 -225.508324) (xy 365.51635 -225.484801)
			(xy 365.474431 -225.454345) (xy 365.437793 -225.417707) (xy 365.407337 -225.375788) (xy 365.383814 -225.329621)
			(xy 365.367802 -225.280342) (xy 365.359696 -225.229165) (xy 365.359188 -225.203258) (xy 365.359797 -225.175541)
			(xy 365.36911 -225.120895) (xy 365.37773 -225.094546) (xy 365.385604 -225.072448) (xy 365.180626 -224.71761)
			(xy 365.157766 -224.713292) (xy 365.132948 -224.708169) (xy 365.085205 -224.691172) (xy 365.040626 -224.667071)
			(xy 365.00026 -224.636431) (xy 364.965057 -224.599976) (xy 364.935848 -224.558564) (xy 364.913319 -224.51317)
			(xy 364.898001 -224.464863) (xy 364.890255 -224.414781) (xy 364.889796 -224.389442) (xy 364.608872 -224.389442)
			(xy 364.608364 -224.415329) (xy 364.600265 -224.466467) (xy 364.584266 -224.515707) (xy 364.56076 -224.561839)
			(xy 364.530328 -224.603726) (xy 364.493718 -224.640336) (xy 364.451831 -224.670768) (xy 364.405699 -224.694274)
			(xy 364.356459 -224.710273) (xy 364.305321 -224.718372) (xy 364.253547 -224.718372) (xy 364.202409 -224.710273)
			(xy 364.153169 -224.694274) (xy 364.107037 -224.670768) (xy 364.06515 -224.640336) (xy 364.02854 -224.603726)
			(xy 363.998108 -224.561839) (xy 363.974602 -224.515707) (xy 363.958603 -224.466467) (xy 363.950504 -224.415329)
			(xy 363.949996 -224.389442) (xy 363.669072 -224.389442) (xy 363.668525 -224.417149) (xy 363.659341 -224.471796)
			(xy 363.650784 -224.498154) (xy 363.64291 -224.520252) (xy 363.847888 -224.87509) (xy 363.870748 -224.879408)
			(xy 363.895571 -224.884565) (xy 363.943351 -224.90152) (xy 363.987971 -224.925592) (xy 364.028378 -224.956214)
			(xy 364.063619 -224.992662) (xy 364.092863 -225.034077) (xy 364.115419 -225.079482) (xy 364.130756 -225.127806)
			(xy 364.138511 -225.177908) (xy 364.138972 -225.203258) (xy 364.138464 -225.229165) (xy 364.130358 -225.280342)
			(xy 364.114346 -225.329621) (xy 364.090823 -225.375788) (xy 364.060367 -225.417707) (xy 364.023729 -225.454345)
			(xy 363.98181 -225.484801) (xy 363.935643 -225.508324) (xy 363.886364 -225.524336) (xy 363.835187 -225.532442)
			(xy 363.783373 -225.532442) (xy 363.732196 -225.524336) (xy 363.682917 -225.508324) (xy 363.63675 -225.484801)
			(xy 363.594831 -225.454345) (xy 363.558193 -225.417707) (xy 363.527737 -225.375788) (xy 363.504214 -225.329621)
			(xy 363.488202 -225.280342) (xy 363.480096 -225.229165) (xy 363.479588 -225.203258) (xy 363.480197 -225.175541)
			(xy 363.48951 -225.120895) (xy 363.49813 -225.094546) (xy 363.506004 -225.072448) (xy 363.301026 -224.71761)
			(xy 363.278166 -224.713292) (xy 363.253348 -224.708169) (xy 363.205605 -224.691172) (xy 363.161026 -224.667071)
			(xy 363.12066 -224.636431) (xy 363.085457 -224.599976) (xy 363.056248 -224.558564) (xy 363.033719 -224.51317)
			(xy 363.018401 -224.464863) (xy 363.010655 -224.414781) (xy 363.010196 -224.389442) (xy 362.729272 -224.389442)
			(xy 362.728764 -224.415329) (xy 362.720665 -224.466467) (xy 362.704666 -224.515707) (xy 362.68116 -224.561839)
			(xy 362.650728 -224.603726) (xy 362.614118 -224.640336) (xy 362.572231 -224.670768) (xy 362.526099 -224.694274)
			(xy 362.476859 -224.710273) (xy 362.425721 -224.718372) (xy 362.373947 -224.718372) (xy 362.322809 -224.710273)
			(xy 362.273569 -224.694274) (xy 362.227437 -224.670768) (xy 362.18555 -224.640336) (xy 362.14894 -224.603726)
			(xy 362.118508 -224.561839) (xy 362.095002 -224.515707) (xy 362.079003 -224.466467) (xy 362.070904 -224.415329)
			(xy 362.070396 -224.389442) (xy 361.789472 -224.389442) (xy 361.788925 -224.417149) (xy 361.779741 -224.471796)
			(xy 361.771184 -224.498154) (xy 361.76331 -224.520252) (xy 361.968288 -224.87509) (xy 361.991148 -224.879408)
			(xy 362.015971 -224.884565) (xy 362.063751 -224.90152) (xy 362.108371 -224.925592) (xy 362.148778 -224.956214)
			(xy 362.184019 -224.992662) (xy 362.213263 -225.034077) (xy 362.235819 -225.079482) (xy 362.251156 -225.127806)
			(xy 362.258911 -225.177908) (xy 362.259372 -225.203258) (xy 362.258864 -225.229165) (xy 362.250758 -225.280342)
			(xy 362.234746 -225.329621) (xy 362.211223 -225.375788) (xy 362.180767 -225.417707) (xy 362.144129 -225.454345)
			(xy 362.10221 -225.484801) (xy 362.056043 -225.508324) (xy 362.006764 -225.524336) (xy 361.955587 -225.532442)
			(xy 361.903773 -225.532442) (xy 361.852596 -225.524336) (xy 361.803317 -225.508324) (xy 361.75715 -225.484801)
			(xy 361.715231 -225.454345) (xy 361.678593 -225.417707) (xy 361.648137 -225.375788) (xy 361.624614 -225.329621)
			(xy 361.608602 -225.280342) (xy 361.600496 -225.229165) (xy 361.599988 -225.203258) (xy 361.600597 -225.175541)
			(xy 361.60991 -225.120895) (xy 361.61853 -225.094546) (xy 361.626404 -225.072448) (xy 361.421426 -224.71761)
			(xy 361.398566 -224.713292) (xy 361.373748 -224.708169) (xy 361.326005 -224.691172) (xy 361.281426 -224.667071)
			(xy 361.24106 -224.636431) (xy 361.205857 -224.599976) (xy 361.176648 -224.558564) (xy 361.154119 -224.51317)
			(xy 361.138801 -224.464863) (xy 361.131055 -224.414781) (xy 361.130596 -224.389442) (xy 360.849672 -224.389442)
			(xy 360.849164 -224.415329) (xy 360.841065 -224.466467) (xy 360.825066 -224.515707) (xy 360.80156 -224.561839)
			(xy 360.771128 -224.603726) (xy 360.734518 -224.640336) (xy 360.692631 -224.670768) (xy 360.646499 -224.694274)
			(xy 360.597259 -224.710273) (xy 360.546121 -224.718372) (xy 360.494347 -224.718372) (xy 360.443209 -224.710273)
			(xy 360.393969 -224.694274) (xy 360.347837 -224.670768) (xy 360.30595 -224.640336) (xy 360.26934 -224.603726)
			(xy 360.238908 -224.561839) (xy 360.215402 -224.515707) (xy 360.199403 -224.466467) (xy 360.191304 -224.415329)
			(xy 360.190796 -224.389442) (xy 359.909872 -224.389442) (xy 359.909325 -224.417149) (xy 359.900141 -224.471796)
			(xy 359.891584 -224.498154) (xy 359.88371 -224.520252) (xy 360.088688 -224.87509) (xy 360.111548 -224.879408)
			(xy 360.136371 -224.884565) (xy 360.184151 -224.90152) (xy 360.228771 -224.925592) (xy 360.269178 -224.956214)
			(xy 360.304419 -224.992662) (xy 360.333663 -225.034077) (xy 360.356219 -225.079482) (xy 360.371556 -225.127806)
			(xy 360.379311 -225.177908) (xy 360.379772 -225.203258) (xy 360.379264 -225.229165) (xy 360.371158 -225.280342)
			(xy 360.355146 -225.329621) (xy 360.331623 -225.375788) (xy 360.301167 -225.417707) (xy 360.264529 -225.454345)
			(xy 360.22261 -225.484801) (xy 360.176443 -225.508324) (xy 360.127164 -225.524336) (xy 360.075987 -225.532442)
			(xy 360.024173 -225.532442) (xy 359.972996 -225.524336) (xy 359.923717 -225.508324) (xy 359.87755 -225.484801)
			(xy 359.835631 -225.454345) (xy 359.798993 -225.417707) (xy 359.768537 -225.375788) (xy 359.745014 -225.329621)
			(xy 359.729002 -225.280342) (xy 359.720896 -225.229165) (xy 359.720388 -225.203258) (xy 359.720997 -225.175541)
			(xy 359.73031 -225.120895) (xy 359.73893 -225.094546) (xy 359.746804 -225.072448) (xy 359.541826 -224.71761)
			(xy 359.518966 -224.713292) (xy 359.494148 -224.708169) (xy 359.446405 -224.691172) (xy 359.401826 -224.667071)
			(xy 359.36146 -224.636431) (xy 359.326257 -224.599976) (xy 359.297048 -224.558564) (xy 359.274519 -224.51317)
			(xy 359.259201 -224.464863) (xy 359.251455 -224.414781) (xy 359.250996 -224.389442) (xy 358.970072 -224.389442)
			(xy 358.969564 -224.415329) (xy 358.961465 -224.466467) (xy 358.945466 -224.515707) (xy 358.92196 -224.561839)
			(xy 358.891528 -224.603726) (xy 358.854918 -224.640336) (xy 358.813031 -224.670768) (xy 358.766899 -224.694274)
			(xy 358.717659 -224.710273) (xy 358.666521 -224.718372) (xy 358.614747 -224.718372) (xy 358.563609 -224.710273)
			(xy 358.514369 -224.694274) (xy 358.468237 -224.670768) (xy 358.42635 -224.640336) (xy 358.38974 -224.603726)
			(xy 358.359308 -224.561839) (xy 358.335802 -224.515707) (xy 358.319803 -224.466467) (xy 358.311704 -224.415329)
			(xy 358.311196 -224.389442) (xy 358.030272 -224.389442) (xy 358.029725 -224.417149) (xy 358.020541 -224.471796)
			(xy 358.011984 -224.498154) (xy 358.00411 -224.520252) (xy 358.209088 -224.87509) (xy 358.231948 -224.879408)
			(xy 358.256771 -224.884565) (xy 358.304551 -224.90152) (xy 358.349171 -224.925592) (xy 358.389578 -224.956214)
			(xy 358.424819 -224.992662) (xy 358.454063 -225.034077) (xy 358.476619 -225.079482) (xy 358.491956 -225.127806)
			(xy 358.499711 -225.177908) (xy 358.500172 -225.203258) (xy 358.499664 -225.229165) (xy 358.491558 -225.280342)
			(xy 358.475546 -225.329621) (xy 358.452023 -225.375788) (xy 358.421567 -225.417707) (xy 358.384929 -225.454345)
			(xy 358.34301 -225.484801) (xy 358.296843 -225.508324) (xy 358.247564 -225.524336) (xy 358.196387 -225.532442)
			(xy 358.144573 -225.532442) (xy 358.093396 -225.524336) (xy 358.044117 -225.508324) (xy 357.99795 -225.484801)
			(xy 357.956031 -225.454345) (xy 357.919393 -225.417707) (xy 357.888937 -225.375788) (xy 357.865414 -225.329621)
			(xy 357.849402 -225.280342) (xy 357.841296 -225.229165) (xy 357.840788 -225.203258) (xy 357.841397 -225.175541)
			(xy 357.85071 -225.120895) (xy 357.85933 -225.094546) (xy 357.867204 -225.072448) (xy 357.662226 -224.71761)
			(xy 357.639366 -224.713292) (xy 357.614548 -224.708169) (xy 357.566805 -224.691172) (xy 357.522226 -224.667071)
			(xy 357.48186 -224.636431) (xy 357.446657 -224.599976) (xy 357.417448 -224.558564) (xy 357.394919 -224.51317)
			(xy 357.379601 -224.464863) (xy 357.371855 -224.414781) (xy 357.371396 -224.389442) (xy 357.090472 -224.389442)
			(xy 357.089964 -224.415329) (xy 357.081865 -224.466467) (xy 357.065866 -224.515707) (xy 357.04236 -224.561839)
			(xy 357.011928 -224.603726) (xy 356.975318 -224.640336) (xy 356.933431 -224.670768) (xy 356.887299 -224.694274)
			(xy 356.838059 -224.710273) (xy 356.786921 -224.718372) (xy 356.735147 -224.718372) (xy 356.684009 -224.710273)
			(xy 356.634769 -224.694274) (xy 356.588637 -224.670768) (xy 356.54675 -224.640336) (xy 356.51014 -224.603726)
			(xy 356.479708 -224.561839) (xy 356.456202 -224.515707) (xy 356.440203 -224.466467) (xy 356.432104 -224.415329)
			(xy 356.431596 -224.389442) (xy 356.150672 -224.389442) (xy 356.150125 -224.417149) (xy 356.140941 -224.471796)
			(xy 356.132384 -224.498154) (xy 356.12451 -224.520252) (xy 356.329488 -224.87509) (xy 356.352348 -224.879408)
			(xy 356.377171 -224.884565) (xy 356.424951 -224.90152) (xy 356.469571 -224.925592) (xy 356.509978 -224.956214)
			(xy 356.545219 -224.992662) (xy 356.574463 -225.034077) (xy 356.597019 -225.079482) (xy 356.612356 -225.127806)
			(xy 356.620111 -225.177908) (xy 356.620572 -225.203258) (xy 356.620064 -225.229165) (xy 356.611958 -225.280342)
			(xy 356.595946 -225.329621) (xy 356.572423 -225.375788) (xy 356.541967 -225.417707) (xy 356.505329 -225.454345)
			(xy 356.46341 -225.484801) (xy 356.417243 -225.508324) (xy 356.367964 -225.524336) (xy 356.316787 -225.532442)
			(xy 356.264973 -225.532442) (xy 356.213796 -225.524336) (xy 356.164517 -225.508324) (xy 356.11835 -225.484801)
			(xy 356.076431 -225.454345) (xy 356.039793 -225.417707) (xy 356.009337 -225.375788) (xy 355.985814 -225.329621)
			(xy 355.969802 -225.280342) (xy 355.961696 -225.229165) (xy 355.961188 -225.203258) (xy 355.961797 -225.175541)
			(xy 355.97111 -225.120895) (xy 355.97973 -225.094546) (xy 355.987604 -225.072448) (xy 355.782626 -224.71761)
			(xy 355.759766 -224.713292) (xy 355.734948 -224.708169) (xy 355.687205 -224.691172) (xy 355.642626 -224.667071)
			(xy 355.60226 -224.636431) (xy 355.567057 -224.599976) (xy 355.537848 -224.558564) (xy 355.515319 -224.51317)
			(xy 355.500001 -224.464863) (xy 355.492255 -224.414781) (xy 355.491796 -224.389442) (xy 355.210872 -224.389442)
			(xy 355.210364 -224.415329) (xy 355.202265 -224.466467) (xy 355.186266 -224.515707) (xy 355.16276 -224.561839)
			(xy 355.132328 -224.603726) (xy 355.095718 -224.640336) (xy 355.053831 -224.670768) (xy 355.007699 -224.694274)
			(xy 354.958459 -224.710273) (xy 354.907321 -224.718372) (xy 354.855547 -224.718372) (xy 354.804409 -224.710273)
			(xy 354.755169 -224.694274) (xy 354.709037 -224.670768) (xy 354.66715 -224.640336) (xy 354.63054 -224.603726)
			(xy 354.600108 -224.561839) (xy 354.576602 -224.515707) (xy 354.560603 -224.466467) (xy 354.552504 -224.415329)
			(xy 354.551996 -224.389442) (xy 354.271072 -224.389442) (xy 354.270525 -224.417149) (xy 354.261341 -224.471796)
			(xy 354.252784 -224.498154) (xy 354.24491 -224.520252) (xy 354.449888 -224.87509) (xy 354.472748 -224.879408)
			(xy 354.497571 -224.884565) (xy 354.545351 -224.90152) (xy 354.589971 -224.925592) (xy 354.630378 -224.956214)
			(xy 354.665619 -224.992662) (xy 354.694863 -225.034077) (xy 354.717419 -225.079482) (xy 354.732756 -225.127806)
			(xy 354.740511 -225.177908) (xy 354.740972 -225.203258) (xy 354.740464 -225.229165) (xy 354.732358 -225.280342)
			(xy 354.716346 -225.329621) (xy 354.692823 -225.375788) (xy 354.662367 -225.417707) (xy 354.625729 -225.454345)
			(xy 354.58381 -225.484801) (xy 354.537643 -225.508324) (xy 354.488364 -225.524336) (xy 354.437187 -225.532442)
			(xy 354.385373 -225.532442) (xy 354.334196 -225.524336) (xy 354.284917 -225.508324) (xy 354.23875 -225.484801)
			(xy 354.196831 -225.454345) (xy 354.160193 -225.417707) (xy 354.129737 -225.375788) (xy 354.106214 -225.329621)
			(xy 354.090202 -225.280342) (xy 354.082096 -225.229165) (xy 354.081588 -225.203258) (xy 354.082197 -225.175541)
			(xy 354.09151 -225.120895) (xy 354.10013 -225.094546) (xy 354.108004 -225.072448) (xy 353.903026 -224.71761)
			(xy 353.880166 -224.713292) (xy 353.855348 -224.708169) (xy 353.807605 -224.691172) (xy 353.763026 -224.667071)
			(xy 353.72266 -224.636431) (xy 353.687457 -224.599976) (xy 353.658248 -224.558564) (xy 353.635719 -224.51317)
			(xy 353.620401 -224.464863) (xy 353.612655 -224.414781) (xy 353.612196 -224.389442) (xy 353.331272 -224.389442)
			(xy 353.330764 -224.415329) (xy 353.322665 -224.466467) (xy 353.306666 -224.515707) (xy 353.28316 -224.561839)
			(xy 353.252728 -224.603726) (xy 353.216118 -224.640336) (xy 353.174231 -224.670768) (xy 353.128099 -224.694274)
			(xy 353.078859 -224.710273) (xy 353.027721 -224.718372) (xy 352.975947 -224.718372) (xy 352.924809 -224.710273)
			(xy 352.875569 -224.694274) (xy 352.829437 -224.670768) (xy 352.78755 -224.640336) (xy 352.75094 -224.603726)
			(xy 352.720508 -224.561839) (xy 352.697002 -224.515707) (xy 352.681003 -224.466467) (xy 352.672904 -224.415329)
			(xy 352.672396 -224.389442) (xy 352.391472 -224.389442) (xy 352.390925 -224.417149) (xy 352.381741 -224.471796)
			(xy 352.373184 -224.498154) (xy 352.36531 -224.520252) (xy 352.570288 -224.87509) (xy 352.593148 -224.879408)
			(xy 352.617971 -224.884565) (xy 352.665751 -224.90152) (xy 352.710371 -224.925592) (xy 352.750778 -224.956214)
			(xy 352.786019 -224.992662) (xy 352.815263 -225.034077) (xy 352.837819 -225.079482) (xy 352.853156 -225.127806)
			(xy 352.860911 -225.177908) (xy 352.861372 -225.203258) (xy 352.860864 -225.229165) (xy 352.852758 -225.280342)
			(xy 352.836746 -225.329621) (xy 352.813223 -225.375788) (xy 352.782767 -225.417707) (xy 352.746129 -225.454345)
			(xy 352.70421 -225.484801) (xy 352.658043 -225.508324) (xy 352.608764 -225.524336) (xy 352.557587 -225.532442)
			(xy 352.505773 -225.532442) (xy 352.454596 -225.524336) (xy 352.405317 -225.508324) (xy 352.35915 -225.484801)
			(xy 352.317231 -225.454345) (xy 352.280593 -225.417707) (xy 352.250137 -225.375788) (xy 352.226614 -225.329621)
			(xy 352.210602 -225.280342) (xy 352.202496 -225.229165) (xy 352.201988 -225.203258) (xy 352.202597 -225.175541)
			(xy 352.21191 -225.120895) (xy 352.22053 -225.094546) (xy 352.228404 -225.072448) (xy 352.023426 -224.71761)
			(xy 352.000566 -224.713292) (xy 351.975748 -224.708169) (xy 351.928005 -224.691172) (xy 351.883426 -224.667071)
			(xy 351.84306 -224.636431) (xy 351.807857 -224.599976) (xy 351.778648 -224.558564) (xy 351.756119 -224.51317)
			(xy 351.740801 -224.464863) (xy 351.733055 -224.414781) (xy 351.732596 -224.389442) (xy 351.451672 -224.389442)
			(xy 351.451164 -224.415329) (xy 351.443065 -224.466467) (xy 351.427066 -224.515707) (xy 351.40356 -224.561839)
			(xy 351.373128 -224.603726) (xy 351.336518 -224.640336) (xy 351.294631 -224.670768) (xy 351.248499 -224.694274)
			(xy 351.199259 -224.710273) (xy 351.148121 -224.718372) (xy 351.096347 -224.718372) (xy 351.045209 -224.710273)
			(xy 350.995969 -224.694274) (xy 350.949837 -224.670768) (xy 350.90795 -224.640336) (xy 350.87134 -224.603726)
			(xy 350.840908 -224.561839) (xy 350.817402 -224.515707) (xy 350.801403 -224.466467) (xy 350.793304 -224.415329)
			(xy 350.792796 -224.389442) (xy 350.511872 -224.389442) (xy 350.511325 -224.417149) (xy 350.502141 -224.471796)
			(xy 350.493584 -224.498154) (xy 350.48571 -224.520252) (xy 350.690688 -224.87509) (xy 350.713548 -224.879408)
			(xy 350.738371 -224.884565) (xy 350.786151 -224.90152) (xy 350.830771 -224.925592) (xy 350.871178 -224.956214)
			(xy 350.906419 -224.992662) (xy 350.935663 -225.034077) (xy 350.958219 -225.079482) (xy 350.973556 -225.127806)
			(xy 350.981311 -225.177908) (xy 350.981772 -225.203258) (xy 350.981264 -225.229165) (xy 350.973158 -225.280342)
			(xy 350.957146 -225.329621) (xy 350.933623 -225.375788) (xy 350.903167 -225.417707) (xy 350.866529 -225.454345)
			(xy 350.82461 -225.484801) (xy 350.778443 -225.508324) (xy 350.729164 -225.524336) (xy 350.677987 -225.532442)
			(xy 350.626173 -225.532442) (xy 350.574996 -225.524336) (xy 350.525717 -225.508324) (xy 350.47955 -225.484801)
			(xy 350.437631 -225.454345) (xy 350.400993 -225.417707) (xy 350.370537 -225.375788) (xy 350.347014 -225.329621)
			(xy 350.331002 -225.280342) (xy 350.322896 -225.229165) (xy 350.322388 -225.203258) (xy 350.322997 -225.175541)
			(xy 350.33231 -225.120895) (xy 350.34093 -225.094546) (xy 350.348804 -225.072448) (xy 350.143826 -224.71761)
			(xy 350.120966 -224.713292) (xy 350.096148 -224.708169) (xy 350.048405 -224.691172) (xy 350.003826 -224.667071)
			(xy 349.96346 -224.636431) (xy 349.928257 -224.599976) (xy 349.899048 -224.558564) (xy 349.876519 -224.51317)
			(xy 349.861201 -224.464863) (xy 349.853455 -224.414781) (xy 349.852996 -224.389442) (xy 349.572072 -224.389442)
			(xy 349.571564 -224.415329) (xy 349.563465 -224.466467) (xy 349.547466 -224.515707) (xy 349.52396 -224.561839)
			(xy 349.493528 -224.603726) (xy 349.456918 -224.640336) (xy 349.415031 -224.670768) (xy 349.368899 -224.694274)
			(xy 349.319659 -224.710273) (xy 349.268521 -224.718372) (xy 349.216747 -224.718372) (xy 349.165609 -224.710273)
			(xy 349.116369 -224.694274) (xy 349.070237 -224.670768) (xy 349.02835 -224.640336) (xy 348.99174 -224.603726)
			(xy 348.961308 -224.561839) (xy 348.937802 -224.515707) (xy 348.921803 -224.466467) (xy 348.913704 -224.415329)
			(xy 348.913196 -224.389442) (xy 348.632272 -224.389442) (xy 348.631725 -224.417149) (xy 348.622541 -224.471796)
			(xy 348.613984 -224.498154) (xy 348.60611 -224.520252) (xy 348.811088 -224.87509) (xy 348.833948 -224.879408)
			(xy 348.858771 -224.884565) (xy 348.906551 -224.90152) (xy 348.951171 -224.925592) (xy 348.991578 -224.956214)
			(xy 349.026819 -224.992662) (xy 349.056063 -225.034077) (xy 349.078619 -225.079482) (xy 349.093956 -225.127806)
			(xy 349.101711 -225.177908) (xy 349.102172 -225.203258) (xy 349.101664 -225.229165) (xy 349.093558 -225.280342)
			(xy 349.077546 -225.329621) (xy 349.054023 -225.375788) (xy 349.023567 -225.417707) (xy 348.986929 -225.454345)
			(xy 348.94501 -225.484801) (xy 348.898843 -225.508324) (xy 348.849564 -225.524336) (xy 348.798387 -225.532442)
			(xy 348.746573 -225.532442) (xy 348.695396 -225.524336) (xy 348.646117 -225.508324) (xy 348.59995 -225.484801)
			(xy 348.558031 -225.454345) (xy 348.521393 -225.417707) (xy 348.490937 -225.375788) (xy 348.467414 -225.329621)
			(xy 348.451402 -225.280342) (xy 348.443296 -225.229165) (xy 348.442788 -225.203258) (xy 348.443397 -225.175541)
			(xy 348.45271 -225.120895) (xy 348.46133 -225.094546) (xy 348.469204 -225.072448) (xy 348.264226 -224.71761)
			(xy 348.241366 -224.713292) (xy 348.216548 -224.708169) (xy 348.168805 -224.691172) (xy 348.124226 -224.667071)
			(xy 348.08386 -224.636431) (xy 348.048657 -224.599976) (xy 348.019448 -224.558564) (xy 347.996919 -224.51317)
			(xy 347.981601 -224.464863) (xy 347.973855 -224.414781) (xy 347.973396 -224.389442) (xy 347.692472 -224.389442)
			(xy 347.691964 -224.415329) (xy 347.683865 -224.466467) (xy 347.667866 -224.515707) (xy 347.64436 -224.561839)
			(xy 347.613928 -224.603726) (xy 347.577318 -224.640336) (xy 347.535431 -224.670768) (xy 347.489299 -224.694274)
			(xy 347.440059 -224.710273) (xy 347.388921 -224.718372) (xy 347.337147 -224.718372) (xy 347.286009 -224.710273)
			(xy 347.236769 -224.694274) (xy 347.190637 -224.670768) (xy 347.14875 -224.640336) (xy 347.11214 -224.603726)
			(xy 347.081708 -224.561839) (xy 347.058202 -224.515707) (xy 347.042203 -224.466467) (xy 347.034104 -224.415329)
			(xy 347.033596 -224.389442) (xy 346.752672 -224.389442) (xy 346.752125 -224.417149) (xy 346.742941 -224.471796)
			(xy 346.734384 -224.498154) (xy 346.72651 -224.520252) (xy 346.931488 -224.87509) (xy 346.954348 -224.879408)
			(xy 346.979171 -224.884565) (xy 347.026951 -224.90152) (xy 347.071571 -224.925592) (xy 347.111978 -224.956214)
			(xy 347.147219 -224.992662) (xy 347.176463 -225.034077) (xy 347.199019 -225.079482) (xy 347.214356 -225.127806)
			(xy 347.222111 -225.177908) (xy 347.222572 -225.203258) (xy 347.222064 -225.229165) (xy 347.213958 -225.280342)
			(xy 347.197946 -225.329621) (xy 347.174423 -225.375788) (xy 347.143967 -225.417707) (xy 347.107329 -225.454345)
			(xy 347.06541 -225.484801) (xy 347.019243 -225.508324) (xy 346.969964 -225.524336) (xy 346.918787 -225.532442)
			(xy 346.866973 -225.532442) (xy 346.815796 -225.524336) (xy 346.766517 -225.508324) (xy 346.72035 -225.484801)
			(xy 346.678431 -225.454345) (xy 346.641793 -225.417707) (xy 346.611337 -225.375788) (xy 346.587814 -225.329621)
			(xy 346.571802 -225.280342) (xy 346.563696 -225.229165) (xy 346.563188 -225.203258) (xy 346.563797 -225.175541)
			(xy 346.57311 -225.120895) (xy 346.58173 -225.094546) (xy 346.589604 -225.072448) (xy 346.384626 -224.71761)
			(xy 346.361766 -224.713292) (xy 346.336948 -224.708169) (xy 346.289205 -224.691172) (xy 346.244626 -224.667071)
			(xy 346.20426 -224.636431) (xy 346.169057 -224.599976) (xy 346.139848 -224.558564) (xy 346.117319 -224.51317)
			(xy 346.102001 -224.464863) (xy 346.094255 -224.414781) (xy 346.093796 -224.389442) (xy 345.812872 -224.389442)
			(xy 345.812364 -224.415329) (xy 345.804265 -224.466467) (xy 345.788266 -224.515707) (xy 345.76476 -224.561839)
			(xy 345.734328 -224.603726) (xy 345.697718 -224.640336) (xy 345.655831 -224.670768) (xy 345.609699 -224.694274)
			(xy 345.560459 -224.710273) (xy 345.509321 -224.718372) (xy 345.457547 -224.718372) (xy 345.406409 -224.710273)
			(xy 345.357169 -224.694274) (xy 345.311037 -224.670768) (xy 345.26915 -224.640336) (xy 345.23254 -224.603726)
			(xy 345.202108 -224.561839) (xy 345.178602 -224.515707) (xy 345.162603 -224.466467) (xy 345.154504 -224.415329)
			(xy 345.153996 -224.389442) (xy 344.873072 -224.389442) (xy 344.872525 -224.417149) (xy 344.863341 -224.471796)
			(xy 344.854784 -224.498154) (xy 344.84691 -224.520252) (xy 345.051888 -224.87509) (xy 345.074748 -224.879408)
			(xy 345.099571 -224.884565) (xy 345.147351 -224.90152) (xy 345.191971 -224.925592) (xy 345.232378 -224.956214)
			(xy 345.267619 -224.992662) (xy 345.296863 -225.034077) (xy 345.319419 -225.079482) (xy 345.334756 -225.127806)
			(xy 345.342511 -225.177908) (xy 345.342972 -225.203258) (xy 345.342464 -225.229165) (xy 345.334358 -225.280342)
			(xy 345.318346 -225.329621) (xy 345.294823 -225.375788) (xy 345.264367 -225.417707) (xy 345.227729 -225.454345)
			(xy 345.18581 -225.484801) (xy 345.139643 -225.508324) (xy 345.090364 -225.524336) (xy 345.039187 -225.532442)
			(xy 344.987373 -225.532442) (xy 344.936196 -225.524336) (xy 344.886917 -225.508324) (xy 344.84075 -225.484801)
			(xy 344.798831 -225.454345) (xy 344.762193 -225.417707) (xy 344.731737 -225.375788) (xy 344.708214 -225.329621)
			(xy 344.692202 -225.280342) (xy 344.684096 -225.229165) (xy 344.683588 -225.203258) (xy 344.684197 -225.175541)
			(xy 344.69351 -225.120895) (xy 344.70213 -225.094546) (xy 344.710004 -225.072448) (xy 344.505026 -224.71761)
			(xy 344.482166 -224.713292) (xy 344.457348 -224.708169) (xy 344.409605 -224.691172) (xy 344.365026 -224.667071)
			(xy 344.32466 -224.636431) (xy 344.289457 -224.599976) (xy 344.260248 -224.558564) (xy 344.237719 -224.51317)
			(xy 344.222401 -224.464863) (xy 344.214655 -224.414781) (xy 344.214196 -224.389442) (xy 343.933272 -224.389442)
			(xy 343.932764 -224.415329) (xy 343.924665 -224.466467) (xy 343.908666 -224.515707) (xy 343.88516 -224.561839)
			(xy 343.854728 -224.603726) (xy 343.818118 -224.640336) (xy 343.776231 -224.670768) (xy 343.730099 -224.694274)
			(xy 343.680859 -224.710273) (xy 343.629721 -224.718372) (xy 343.577947 -224.718372) (xy 343.526809 -224.710273)
			(xy 343.477569 -224.694274) (xy 343.431437 -224.670768) (xy 343.38955 -224.640336) (xy 343.35294 -224.603726)
			(xy 343.322508 -224.561839) (xy 343.299002 -224.515707) (xy 343.283003 -224.466467) (xy 343.274904 -224.415329)
			(xy 343.274396 -224.389442) (xy 342.993472 -224.389442) (xy 342.992925 -224.417149) (xy 342.983741 -224.471796)
			(xy 342.975184 -224.498154) (xy 342.96731 -224.520252) (xy 343.172288 -224.87509) (xy 343.195148 -224.879408)
			(xy 343.219971 -224.884565) (xy 343.267751 -224.90152) (xy 343.312371 -224.925592) (xy 343.352778 -224.956214)
			(xy 343.388019 -224.992662) (xy 343.417263 -225.034077) (xy 343.439819 -225.079482) (xy 343.455156 -225.127806)
			(xy 343.462911 -225.177908) (xy 343.463372 -225.203258) (xy 343.462864 -225.229165) (xy 343.454758 -225.280342)
			(xy 343.438746 -225.329621) (xy 343.415223 -225.375788) (xy 343.384767 -225.417707) (xy 343.348129 -225.454345)
			(xy 343.30621 -225.484801) (xy 343.260043 -225.508324) (xy 343.210764 -225.524336) (xy 343.159587 -225.532442)
			(xy 343.107773 -225.532442) (xy 343.056596 -225.524336) (xy 343.007317 -225.508324) (xy 342.96115 -225.484801)
			(xy 342.919231 -225.454345) (xy 342.882593 -225.417707) (xy 342.852137 -225.375788) (xy 342.828614 -225.329621)
			(xy 342.812602 -225.280342) (xy 342.804496 -225.229165) (xy 342.803988 -225.203258) (xy 342.804597 -225.175541)
			(xy 342.81391 -225.120895) (xy 342.82253 -225.094546) (xy 342.830404 -225.072448) (xy 342.625426 -224.71761)
			(xy 342.602566 -224.713292) (xy 342.577748 -224.708169) (xy 342.530005 -224.691172) (xy 342.485426 -224.667071)
			(xy 342.44506 -224.636431) (xy 342.409857 -224.599976) (xy 342.380648 -224.558564) (xy 342.358119 -224.51317)
			(xy 342.342801 -224.464863) (xy 342.335055 -224.414781) (xy 342.334596 -224.389442) (xy 342.053672 -224.389442)
			(xy 342.053164 -224.415329) (xy 342.045065 -224.466467) (xy 342.029066 -224.515707) (xy 342.00556 -224.561839)
			(xy 341.975128 -224.603726) (xy 341.938518 -224.640336) (xy 341.896631 -224.670768) (xy 341.850499 -224.694274)
			(xy 341.801259 -224.710273) (xy 341.750121 -224.718372) (xy 341.698347 -224.718372) (xy 341.647209 -224.710273)
			(xy 341.597969 -224.694274) (xy 341.551837 -224.670768) (xy 341.50995 -224.640336) (xy 341.47334 -224.603726)
			(xy 341.442908 -224.561839) (xy 341.419402 -224.515707) (xy 341.403403 -224.466467) (xy 341.395304 -224.415329)
			(xy 341.394796 -224.389442) (xy 341.113872 -224.389442) (xy 341.113872 -224.38995) (xy 341.113311 -224.417593)
			(xy 341.104122 -224.472111) (xy 341.095584 -224.498408) (xy 341.087964 -224.520252) (xy 341.292688 -224.87509)
			(xy 341.315548 -224.879408) (xy 341.340371 -224.884565) (xy 341.388151 -224.90152) (xy 341.432771 -224.925592)
			(xy 341.473178 -224.956214) (xy 341.508419 -224.992662) (xy 341.537663 -225.034077) (xy 341.560219 -225.079482)
			(xy 341.575556 -225.127806) (xy 341.583311 -225.177908) (xy 341.583772 -225.203258) (xy 341.583264 -225.229165)
			(xy 341.575158 -225.280342) (xy 341.559146 -225.329621) (xy 341.535623 -225.375788) (xy 341.505167 -225.417707)
			(xy 341.468529 -225.454345) (xy 341.42661 -225.484801) (xy 341.380443 -225.508324) (xy 341.331164 -225.524336)
			(xy 341.279987 -225.532442) (xy 341.228173 -225.532442) (xy 341.176996 -225.524336) (xy 341.127717 -225.508324)
			(xy 341.08155 -225.484801) (xy 341.039631 -225.454345) (xy 341.002993 -225.417707) (xy 340.972537 -225.375788)
			(xy 340.949014 -225.329621) (xy 340.933002 -225.280342) (xy 340.924896 -225.229165) (xy 340.924388 -225.203258)
			(xy 340.924388 -225.20275) (xy 340.924995 -225.175096) (xy 340.93432 -225.120578) (xy 340.94293 -225.094292)
			(xy 340.95055 -225.072448) (xy 340.745826 -224.71761) (xy 340.722966 -224.713292) (xy 340.698148 -224.708169)
			(xy 340.650405 -224.691172) (xy 340.605826 -224.667071) (xy 340.56546 -224.636431) (xy 340.530257 -224.599976)
			(xy 340.501048 -224.558564) (xy 340.478519 -224.51317) (xy 340.463201 -224.464863) (xy 340.455455 -224.414781)
			(xy 340.454996 -224.389442) (xy 340.174072 -224.389442) (xy 340.173564 -224.415329) (xy 340.165465 -224.466467)
			(xy 340.149466 -224.515707) (xy 340.12596 -224.561839) (xy 340.095528 -224.603726) (xy 340.058918 -224.640336)
			(xy 340.017031 -224.670768) (xy 339.970899 -224.694274) (xy 339.921659 -224.710273) (xy 339.870521 -224.718372)
			(xy 339.818747 -224.718372) (xy 339.767609 -224.710273) (xy 339.718369 -224.694274) (xy 339.672237 -224.670768)
			(xy 339.63035 -224.640336) (xy 339.59374 -224.603726) (xy 339.563308 -224.561839) (xy 339.539802 -224.515707)
			(xy 339.523803 -224.466467) (xy 339.515704 -224.415329) (xy 339.515196 -224.389442) (xy 339.234272 -224.389442)
			(xy 339.234272 -224.38995) (xy 339.233711 -224.417593) (xy 339.224522 -224.472111) (xy 339.215984 -224.498408)
			(xy 339.208364 -224.520252) (xy 339.413088 -224.87509) (xy 339.435948 -224.879408) (xy 339.460771 -224.884565)
			(xy 339.508551 -224.90152) (xy 339.553171 -224.925592) (xy 339.593578 -224.956214) (xy 339.628819 -224.992662)
			(xy 339.658063 -225.034077) (xy 339.680619 -225.079482) (xy 339.695956 -225.127806) (xy 339.703711 -225.177908)
			(xy 339.704172 -225.203258) (xy 339.703664 -225.229165) (xy 339.695558 -225.280342) (xy 339.679546 -225.329621)
			(xy 339.656023 -225.375788) (xy 339.625567 -225.417707) (xy 339.588929 -225.454345) (xy 339.54701 -225.484801)
			(xy 339.500843 -225.508324) (xy 339.451564 -225.524336) (xy 339.400387 -225.532442) (xy 339.348573 -225.532442)
			(xy 339.297396 -225.524336) (xy 339.248117 -225.508324) (xy 339.20195 -225.484801) (xy 339.160031 -225.454345)
			(xy 339.123393 -225.417707) (xy 339.092937 -225.375788) (xy 339.069414 -225.329621) (xy 339.053402 -225.280342)
			(xy 339.045296 -225.229165) (xy 339.044788 -225.203258) (xy 339.044788 -225.20275) (xy 339.045395 -225.175096)
			(xy 339.05472 -225.120578) (xy 339.06333 -225.094292) (xy 339.07095 -225.072448) (xy 338.866226 -224.71761)
			(xy 338.843366 -224.713292) (xy 338.818548 -224.708169) (xy 338.770805 -224.691172) (xy 338.726226 -224.667071)
			(xy 338.68586 -224.636431) (xy 338.650657 -224.599976) (xy 338.621448 -224.558564) (xy 338.598919 -224.51317)
			(xy 338.583601 -224.464863) (xy 338.575855 -224.414781) (xy 338.575396 -224.389442) (xy 338.294472 -224.389442)
			(xy 338.293964 -224.415329) (xy 338.285865 -224.466467) (xy 338.269866 -224.515707) (xy 338.24636 -224.561839)
			(xy 338.215928 -224.603726) (xy 338.179318 -224.640336) (xy 338.137431 -224.670768) (xy 338.091299 -224.694274)
			(xy 338.042059 -224.710273) (xy 337.990921 -224.718372) (xy 337.939147 -224.718372) (xy 337.888009 -224.710273)
			(xy 337.838769 -224.694274) (xy 337.792637 -224.670768) (xy 337.75075 -224.640336) (xy 337.71414 -224.603726)
			(xy 337.683708 -224.561839) (xy 337.660202 -224.515707) (xy 337.644203 -224.466467) (xy 337.636104 -224.415329)
			(xy 337.635596 -224.389442) (xy 134.525004 -224.389442) (xy 134.524474 -224.41715) (xy 134.515275 -224.471796)
			(xy 134.506716 -224.498154) (xy 134.499096 -224.519998) (xy 134.704074 -224.87509) (xy 134.726934 -224.879408)
			(xy 134.751752 -224.884531) (xy 134.799495 -224.901528) (xy 134.844074 -224.925629) (xy 134.88444 -224.956269)
			(xy 134.919643 -224.992724) (xy 134.948852 -225.034136) (xy 134.971381 -225.07953) (xy 134.986699 -225.127837)
			(xy 134.994445 -225.177919) (xy 134.994904 -225.203258) (xy 134.994396 -225.229145) (xy 134.986297 -225.280283)
			(xy 134.970298 -225.329523) (xy 134.946792 -225.375655) (xy 134.91636 -225.417542) (xy 134.87975 -225.454152)
			(xy 134.837863 -225.484584) (xy 134.791731 -225.50809) (xy 134.742491 -225.524089) (xy 134.691353 -225.532188)
			(xy 134.639579 -225.532188) (xy 134.588441 -225.524089) (xy 134.539201 -225.50809) (xy 134.493069 -225.484584)
			(xy 134.451182 -225.454152) (xy 134.414572 -225.417542) (xy 134.38414 -225.375655) (xy 134.360634 -225.329523)
			(xy 134.344635 -225.280283) (xy 134.336536 -225.229145) (xy 134.336028 -225.203258) (xy 134.336028 -225.20275)
			(xy 134.336589 -225.175107) (xy 134.345778 -225.120589) (xy 134.354316 -225.094292) (xy 134.361936 -225.072448)
			(xy 134.157212 -224.71761) (xy 134.134352 -224.713292) (xy 134.109529 -224.708135) (xy 134.061749 -224.69118)
			(xy 134.017129 -224.667108) (xy 133.976722 -224.636486) (xy 133.941481 -224.600038) (xy 133.912237 -224.558623)
			(xy 133.889681 -224.513218) (xy 133.874344 -224.464894) (xy 133.866589 -224.414792) (xy 133.866128 -224.389442)
			(xy 133.585204 -224.389442) (xy 133.584696 -224.415329) (xy 133.576597 -224.466467) (xy 133.560598 -224.515707)
			(xy 133.537092 -224.561839) (xy 133.50666 -224.603726) (xy 133.47005 -224.640336) (xy 133.428163 -224.670768)
			(xy 133.382031 -224.694274) (xy 133.332791 -224.710273) (xy 133.281653 -224.718372) (xy 133.229879 -224.718372)
			(xy 133.178741 -224.710273) (xy 133.129501 -224.694274) (xy 133.083369 -224.670768) (xy 133.041482 -224.640336)
			(xy 133.004872 -224.603726) (xy 132.97444 -224.561839) (xy 132.950934 -224.515707) (xy 132.934935 -224.466467)
			(xy 132.926836 -224.415329) (xy 132.926328 -224.389442) (xy 132.645404 -224.389442) (xy 132.64486 -224.417149)
			(xy 132.635674 -224.471796) (xy 132.627116 -224.498154) (xy 132.619242 -224.520252) (xy 132.82422 -224.87509)
			(xy 132.84708 -224.879408) (xy 132.871909 -224.884542) (xy 132.919688 -224.901501) (xy 132.964308 -224.925578)
			(xy 133.004714 -224.956202) (xy 133.039954 -224.992654) (xy 133.069197 -225.034071) (xy 133.091752 -225.079478)
			(xy 133.107088 -225.127804) (xy 133.114843 -225.177908) (xy 133.115304 -225.203258) (xy 133.114796 -225.229165)
			(xy 133.10669 -225.280342) (xy 133.090678 -225.329621) (xy 133.067155 -225.375788) (xy 133.036699 -225.417707)
			(xy 133.000061 -225.454345) (xy 132.958142 -225.484801) (xy 132.911975 -225.508324) (xy 132.862696 -225.524336)
			(xy 132.811519 -225.532442) (xy 132.759705 -225.532442) (xy 132.708528 -225.524336) (xy 132.659249 -225.508324)
			(xy 132.613082 -225.484801) (xy 132.571163 -225.454345) (xy 132.534525 -225.417707) (xy 132.504069 -225.375788)
			(xy 132.480546 -225.329621) (xy 132.464534 -225.280342) (xy 132.456428 -225.229165) (xy 132.45592 -225.203258)
			(xy 132.456527 -225.175541) (xy 132.465842 -225.120895) (xy 132.474462 -225.094546) (xy 132.482336 -225.072448)
			(xy 132.277358 -224.71761) (xy 132.254498 -224.713292) (xy 132.229685 -224.708145) (xy 132.181943 -224.691153)
			(xy 132.137363 -224.667056) (xy 132.096996 -224.63642) (xy 132.061793 -224.599968) (xy 132.032582 -224.558558)
			(xy 132.010052 -224.513166) (xy 131.994734 -224.46486) (xy 131.986988 -224.41478) (xy 131.986528 -224.389442)
			(xy 131.705604 -224.389442) (xy 131.705096 -224.415329) (xy 131.696997 -224.466467) (xy 131.680998 -224.515707)
			(xy 131.657492 -224.561839) (xy 131.62706 -224.603726) (xy 131.59045 -224.640336) (xy 131.548563 -224.670768)
			(xy 131.502431 -224.694274) (xy 131.453191 -224.710273) (xy 131.402053 -224.718372) (xy 131.350279 -224.718372)
			(xy 131.299141 -224.710273) (xy 131.249901 -224.694274) (xy 131.203769 -224.670768) (xy 131.161882 -224.640336)
			(xy 131.125272 -224.603726) (xy 131.09484 -224.561839) (xy 131.071334 -224.515707) (xy 131.055335 -224.466467)
			(xy 131.047236 -224.415329) (xy 131.046728 -224.389442) (xy 130.765804 -224.389442) (xy 130.76526 -224.417149)
			(xy 130.756074 -224.471796) (xy 130.747516 -224.498154) (xy 130.739642 -224.520252) (xy 130.94462 -224.87509)
			(xy 130.96748 -224.879408) (xy 130.992309 -224.884542) (xy 131.040088 -224.901501) (xy 131.084708 -224.925578)
			(xy 131.125114 -224.956202) (xy 131.160354 -224.992654) (xy 131.189597 -225.034071) (xy 131.212152 -225.079478)
			(xy 131.227488 -225.127804) (xy 131.235243 -225.177908) (xy 131.235704 -225.203258) (xy 131.235196 -225.229165)
			(xy 131.22709 -225.280342) (xy 131.211078 -225.329621) (xy 131.187555 -225.375788) (xy 131.157099 -225.417707)
			(xy 131.120461 -225.454345) (xy 131.078542 -225.484801) (xy 131.032375 -225.508324) (xy 130.983096 -225.524336)
			(xy 130.931919 -225.532442) (xy 130.880105 -225.532442) (xy 130.828928 -225.524336) (xy 130.779649 -225.508324)
			(xy 130.733482 -225.484801) (xy 130.691563 -225.454345) (xy 130.654925 -225.417707) (xy 130.624469 -225.375788)
			(xy 130.600946 -225.329621) (xy 130.584934 -225.280342) (xy 130.576828 -225.229165) (xy 130.57632 -225.203258)
			(xy 130.576927 -225.175541) (xy 130.586242 -225.120895) (xy 130.594862 -225.094546) (xy 130.602736 -225.072448)
			(xy 130.397758 -224.71761) (xy 130.374898 -224.713292) (xy 130.350085 -224.708145) (xy 130.302343 -224.691153)
			(xy 130.257763 -224.667056) (xy 130.217396 -224.63642) (xy 130.182193 -224.599968) (xy 130.152982 -224.558558)
			(xy 130.130452 -224.513166) (xy 130.115134 -224.46486) (xy 130.107388 -224.41478) (xy 130.106928 -224.389442)
			(xy 129.826004 -224.389442) (xy 129.825496 -224.415329) (xy 129.817397 -224.466467) (xy 129.801398 -224.515707)
			(xy 129.777892 -224.561839) (xy 129.74746 -224.603726) (xy 129.71085 -224.640336) (xy 129.668963 -224.670768)
			(xy 129.622831 -224.694274) (xy 129.573591 -224.710273) (xy 129.522453 -224.718372) (xy 129.470679 -224.718372)
			(xy 129.419541 -224.710273) (xy 129.370301 -224.694274) (xy 129.324169 -224.670768) (xy 129.282282 -224.640336)
			(xy 129.245672 -224.603726) (xy 129.21524 -224.561839) (xy 129.191734 -224.515707) (xy 129.175735 -224.466467)
			(xy 129.167636 -224.415329) (xy 129.167128 -224.389442) (xy 128.886204 -224.389442) (xy 128.88566 -224.417149)
			(xy 128.876474 -224.471796) (xy 128.867916 -224.498154) (xy 128.860042 -224.520252) (xy 129.06502 -224.87509)
			(xy 129.08788 -224.879408) (xy 129.112709 -224.884542) (xy 129.160488 -224.901501) (xy 129.205108 -224.925578)
			(xy 129.245514 -224.956202) (xy 129.280754 -224.992654) (xy 129.309997 -225.034071) (xy 129.332552 -225.079478)
			(xy 129.347888 -225.127804) (xy 129.355643 -225.177908) (xy 129.356104 -225.203258) (xy 129.355596 -225.229165)
			(xy 129.34749 -225.280342) (xy 129.331478 -225.329621) (xy 129.307955 -225.375788) (xy 129.277499 -225.417707)
			(xy 129.240861 -225.454345) (xy 129.198942 -225.484801) (xy 129.152775 -225.508324) (xy 129.103496 -225.524336)
			(xy 129.052319 -225.532442) (xy 129.000505 -225.532442) (xy 128.949328 -225.524336) (xy 128.900049 -225.508324)
			(xy 128.853882 -225.484801) (xy 128.811963 -225.454345) (xy 128.775325 -225.417707) (xy 128.744869 -225.375788)
			(xy 128.721346 -225.329621) (xy 128.705334 -225.280342) (xy 128.697228 -225.229165) (xy 128.69672 -225.203258)
			(xy 128.697327 -225.175541) (xy 128.706642 -225.120895) (xy 128.715262 -225.094546) (xy 128.723136 -225.072448)
			(xy 128.518158 -224.71761) (xy 128.495298 -224.713292) (xy 128.470485 -224.708145) (xy 128.422743 -224.691153)
			(xy 128.378163 -224.667056) (xy 128.337796 -224.63642) (xy 128.302593 -224.599968) (xy 128.273382 -224.558558)
			(xy 128.250852 -224.513166) (xy 128.235534 -224.46486) (xy 128.227788 -224.41478) (xy 128.227328 -224.389442)
			(xy 127.946404 -224.389442) (xy 127.945896 -224.415329) (xy 127.937797 -224.466467) (xy 127.921798 -224.515707)
			(xy 127.898292 -224.561839) (xy 127.86786 -224.603726) (xy 127.83125 -224.640336) (xy 127.789363 -224.670768)
			(xy 127.743231 -224.694274) (xy 127.693991 -224.710273) (xy 127.642853 -224.718372) (xy 127.591079 -224.718372)
			(xy 127.539941 -224.710273) (xy 127.490701 -224.694274) (xy 127.444569 -224.670768) (xy 127.402682 -224.640336)
			(xy 127.366072 -224.603726) (xy 127.33564 -224.561839) (xy 127.312134 -224.515707) (xy 127.296135 -224.466467)
			(xy 127.288036 -224.415329) (xy 127.287528 -224.389442) (xy 127.006604 -224.389442) (xy 127.00606 -224.417149)
			(xy 126.996874 -224.471796) (xy 126.988316 -224.498154) (xy 126.980442 -224.520252) (xy 127.18542 -224.87509)
			(xy 127.20828 -224.879408) (xy 127.233109 -224.884542) (xy 127.280888 -224.901501) (xy 127.325508 -224.925578)
			(xy 127.365914 -224.956202) (xy 127.401154 -224.992654) (xy 127.430397 -225.034071) (xy 127.452952 -225.079478)
			(xy 127.468288 -225.127804) (xy 127.476043 -225.177908) (xy 127.476504 -225.203258) (xy 127.475996 -225.229165)
			(xy 127.46789 -225.280342) (xy 127.451878 -225.329621) (xy 127.428355 -225.375788) (xy 127.397899 -225.417707)
			(xy 127.361261 -225.454345) (xy 127.319342 -225.484801) (xy 127.273175 -225.508324) (xy 127.223896 -225.524336)
			(xy 127.172719 -225.532442) (xy 127.120905 -225.532442) (xy 127.069728 -225.524336) (xy 127.020449 -225.508324)
			(xy 126.974282 -225.484801) (xy 126.932363 -225.454345) (xy 126.895725 -225.417707) (xy 126.865269 -225.375788)
			(xy 126.841746 -225.329621) (xy 126.825734 -225.280342) (xy 126.817628 -225.229165) (xy 126.81712 -225.203258)
			(xy 126.817727 -225.175541) (xy 126.827042 -225.120895) (xy 126.835662 -225.094546) (xy 126.843536 -225.072448)
			(xy 126.638558 -224.71761) (xy 126.615698 -224.713292) (xy 126.590885 -224.708145) (xy 126.543143 -224.691153)
			(xy 126.498563 -224.667056) (xy 126.458196 -224.63642) (xy 126.422993 -224.599968) (xy 126.393782 -224.558558)
			(xy 126.371252 -224.513166) (xy 126.355934 -224.46486) (xy 126.348188 -224.41478) (xy 126.347728 -224.389442)
			(xy 126.066804 -224.389442) (xy 126.066296 -224.415329) (xy 126.058197 -224.466467) (xy 126.042198 -224.515707)
			(xy 126.018692 -224.561839) (xy 125.98826 -224.603726) (xy 125.95165 -224.640336) (xy 125.909763 -224.670768)
			(xy 125.863631 -224.694274) (xy 125.814391 -224.710273) (xy 125.763253 -224.718372) (xy 125.711479 -224.718372)
			(xy 125.660341 -224.710273) (xy 125.611101 -224.694274) (xy 125.564969 -224.670768) (xy 125.523082 -224.640336)
			(xy 125.486472 -224.603726) (xy 125.45604 -224.561839) (xy 125.432534 -224.515707) (xy 125.416535 -224.466467)
			(xy 125.408436 -224.415329) (xy 125.407928 -224.389442) (xy 125.127004 -224.389442) (xy 125.12646 -224.417149)
			(xy 125.117274 -224.471796) (xy 125.108716 -224.498154) (xy 125.100842 -224.520252) (xy 125.30582 -224.87509)
			(xy 125.32868 -224.879408) (xy 125.353509 -224.884542) (xy 125.401288 -224.901501) (xy 125.445908 -224.925578)
			(xy 125.486314 -224.956202) (xy 125.521554 -224.992654) (xy 125.550797 -225.034071) (xy 125.573352 -225.079478)
			(xy 125.588688 -225.127804) (xy 125.596443 -225.177908) (xy 125.596904 -225.203258) (xy 125.596396 -225.229165)
			(xy 125.58829 -225.280342) (xy 125.572278 -225.329621) (xy 125.548755 -225.375788) (xy 125.518299 -225.417707)
			(xy 125.481661 -225.454345) (xy 125.439742 -225.484801) (xy 125.393575 -225.508324) (xy 125.344296 -225.524336)
			(xy 125.293119 -225.532442) (xy 125.241305 -225.532442) (xy 125.190128 -225.524336) (xy 125.140849 -225.508324)
			(xy 125.094682 -225.484801) (xy 125.052763 -225.454345) (xy 125.016125 -225.417707) (xy 124.985669 -225.375788)
			(xy 124.962146 -225.329621) (xy 124.946134 -225.280342) (xy 124.938028 -225.229165) (xy 124.93752 -225.203258)
			(xy 124.938127 -225.175541) (xy 124.947442 -225.120895) (xy 124.956062 -225.094546) (xy 124.963936 -225.072448)
			(xy 124.758958 -224.71761) (xy 124.736098 -224.713292) (xy 124.711285 -224.708145) (xy 124.663543 -224.691153)
			(xy 124.618963 -224.667056) (xy 124.578596 -224.63642) (xy 124.543393 -224.599968) (xy 124.514182 -224.558558)
			(xy 124.491652 -224.513166) (xy 124.476334 -224.46486) (xy 124.468588 -224.41478) (xy 124.468128 -224.389442)
			(xy 124.187204 -224.389442) (xy 124.186696 -224.415329) (xy 124.178597 -224.466467) (xy 124.162598 -224.515707)
			(xy 124.139092 -224.561839) (xy 124.10866 -224.603726) (xy 124.07205 -224.640336) (xy 124.030163 -224.670768)
			(xy 123.984031 -224.694274) (xy 123.934791 -224.710273) (xy 123.883653 -224.718372) (xy 123.831879 -224.718372)
			(xy 123.780741 -224.710273) (xy 123.731501 -224.694274) (xy 123.685369 -224.670768) (xy 123.643482 -224.640336)
			(xy 123.606872 -224.603726) (xy 123.57644 -224.561839) (xy 123.552934 -224.515707) (xy 123.536935 -224.466467)
			(xy 123.528836 -224.415329) (xy 123.528328 -224.389442) (xy 123.247404 -224.389442) (xy 123.24686 -224.417149)
			(xy 123.237674 -224.471796) (xy 123.229116 -224.498154) (xy 123.221242 -224.520252) (xy 123.42622 -224.87509)
			(xy 123.44908 -224.879408) (xy 123.473909 -224.884542) (xy 123.521688 -224.901501) (xy 123.566308 -224.925578)
			(xy 123.606714 -224.956202) (xy 123.641954 -224.992654) (xy 123.671197 -225.034071) (xy 123.693752 -225.079478)
			(xy 123.709088 -225.127804) (xy 123.716843 -225.177908) (xy 123.717304 -225.203258) (xy 123.716796 -225.229165)
			(xy 123.70869 -225.280342) (xy 123.692678 -225.329621) (xy 123.669155 -225.375788) (xy 123.638699 -225.417707)
			(xy 123.602061 -225.454345) (xy 123.560142 -225.484801) (xy 123.513975 -225.508324) (xy 123.464696 -225.524336)
			(xy 123.413519 -225.532442) (xy 123.361705 -225.532442) (xy 123.310528 -225.524336) (xy 123.261249 -225.508324)
			(xy 123.215082 -225.484801) (xy 123.173163 -225.454345) (xy 123.136525 -225.417707) (xy 123.106069 -225.375788)
			(xy 123.082546 -225.329621) (xy 123.066534 -225.280342) (xy 123.058428 -225.229165) (xy 123.05792 -225.203258)
			(xy 123.058527 -225.175541) (xy 123.067842 -225.120895) (xy 123.076462 -225.094546) (xy 123.084336 -225.072448)
			(xy 122.879358 -224.71761) (xy 122.856498 -224.713292) (xy 122.831685 -224.708145) (xy 122.783943 -224.691153)
			(xy 122.739363 -224.667056) (xy 122.698996 -224.63642) (xy 122.663793 -224.599968) (xy 122.634582 -224.558558)
			(xy 122.612052 -224.513166) (xy 122.596734 -224.46486) (xy 122.588988 -224.41478) (xy 122.588528 -224.389442)
			(xy 122.307604 -224.389442) (xy 122.307096 -224.415329) (xy 122.298997 -224.466467) (xy 122.282998 -224.515707)
			(xy 122.259492 -224.561839) (xy 122.22906 -224.603726) (xy 122.19245 -224.640336) (xy 122.150563 -224.670768)
			(xy 122.104431 -224.694274) (xy 122.055191 -224.710273) (xy 122.004053 -224.718372) (xy 121.952279 -224.718372)
			(xy 121.901141 -224.710273) (xy 121.851901 -224.694274) (xy 121.805769 -224.670768) (xy 121.763882 -224.640336)
			(xy 121.727272 -224.603726) (xy 121.69684 -224.561839) (xy 121.673334 -224.515707) (xy 121.657335 -224.466467)
			(xy 121.649236 -224.415329) (xy 121.648728 -224.389442) (xy 121.367804 -224.389442) (xy 121.36726 -224.417149)
			(xy 121.358074 -224.471796) (xy 121.349516 -224.498154) (xy 121.341642 -224.520252) (xy 121.54662 -224.87509)
			(xy 121.56948 -224.879408) (xy 121.594309 -224.884542) (xy 121.642088 -224.901501) (xy 121.686708 -224.925578)
			(xy 121.727114 -224.956202) (xy 121.762354 -224.992654) (xy 121.791597 -225.034071) (xy 121.814152 -225.079478)
			(xy 121.829488 -225.127804) (xy 121.837243 -225.177908) (xy 121.837704 -225.203258) (xy 121.837196 -225.229165)
			(xy 121.82909 -225.280342) (xy 121.813078 -225.329621) (xy 121.789555 -225.375788) (xy 121.759099 -225.417707)
			(xy 121.722461 -225.454345) (xy 121.680542 -225.484801) (xy 121.634375 -225.508324) (xy 121.585096 -225.524336)
			(xy 121.533919 -225.532442) (xy 121.482105 -225.532442) (xy 121.430928 -225.524336) (xy 121.381649 -225.508324)
			(xy 121.335482 -225.484801) (xy 121.293563 -225.454345) (xy 121.256925 -225.417707) (xy 121.226469 -225.375788)
			(xy 121.202946 -225.329621) (xy 121.186934 -225.280342) (xy 121.178828 -225.229165) (xy 121.17832 -225.203258)
			(xy 121.178927 -225.175541) (xy 121.188242 -225.120895) (xy 121.196862 -225.094546) (xy 121.204736 -225.072448)
			(xy 120.999758 -224.71761) (xy 120.976898 -224.713292) (xy 120.952085 -224.708145) (xy 120.904343 -224.691153)
			(xy 120.859763 -224.667056) (xy 120.819396 -224.63642) (xy 120.784193 -224.599968) (xy 120.754982 -224.558558)
			(xy 120.732452 -224.513166) (xy 120.717134 -224.46486) (xy 120.709388 -224.41478) (xy 120.708928 -224.389442)
			(xy 120.428004 -224.389442) (xy 120.427496 -224.415329) (xy 120.419397 -224.466467) (xy 120.403398 -224.515707)
			(xy 120.379892 -224.561839) (xy 120.34946 -224.603726) (xy 120.31285 -224.640336) (xy 120.270963 -224.670768)
			(xy 120.224831 -224.694274) (xy 120.175591 -224.710273) (xy 120.124453 -224.718372) (xy 120.072679 -224.718372)
			(xy 120.021541 -224.710273) (xy 119.972301 -224.694274) (xy 119.926169 -224.670768) (xy 119.884282 -224.640336)
			(xy 119.847672 -224.603726) (xy 119.81724 -224.561839) (xy 119.793734 -224.515707) (xy 119.777735 -224.466467)
			(xy 119.769636 -224.415329) (xy 119.769128 -224.389442) (xy 119.488204 -224.389442) (xy 119.48766 -224.417149)
			(xy 119.478474 -224.471796) (xy 119.469916 -224.498154) (xy 119.462042 -224.520252) (xy 119.66702 -224.87509)
			(xy 119.68988 -224.879408) (xy 119.714709 -224.884542) (xy 119.762488 -224.901501) (xy 119.807108 -224.925578)
			(xy 119.847514 -224.956202) (xy 119.882754 -224.992654) (xy 119.911997 -225.034071) (xy 119.934552 -225.079478)
			(xy 119.949888 -225.127804) (xy 119.957643 -225.177908) (xy 119.958104 -225.203258) (xy 119.957596 -225.229165)
			(xy 119.94949 -225.280342) (xy 119.933478 -225.329621) (xy 119.909955 -225.375788) (xy 119.879499 -225.417707)
			(xy 119.842861 -225.454345) (xy 119.800942 -225.484801) (xy 119.754775 -225.508324) (xy 119.705496 -225.524336)
			(xy 119.654319 -225.532442) (xy 119.602505 -225.532442) (xy 119.551328 -225.524336) (xy 119.502049 -225.508324)
			(xy 119.455882 -225.484801) (xy 119.413963 -225.454345) (xy 119.377325 -225.417707) (xy 119.346869 -225.375788)
			(xy 119.323346 -225.329621) (xy 119.307334 -225.280342) (xy 119.299228 -225.229165) (xy 119.29872 -225.203258)
			(xy 119.299327 -225.175541) (xy 119.308642 -225.120895) (xy 119.317262 -225.094546) (xy 119.325136 -225.072448)
			(xy 119.120158 -224.71761) (xy 119.097298 -224.713292) (xy 119.072485 -224.708145) (xy 119.024743 -224.691153)
			(xy 118.980163 -224.667056) (xy 118.939796 -224.63642) (xy 118.904593 -224.599968) (xy 118.875382 -224.558558)
			(xy 118.852852 -224.513166) (xy 118.837534 -224.46486) (xy 118.829788 -224.41478) (xy 118.829328 -224.389442)
			(xy 118.548404 -224.389442) (xy 118.547896 -224.415329) (xy 118.539797 -224.466467) (xy 118.523798 -224.515707)
			(xy 118.500292 -224.561839) (xy 118.46986 -224.603726) (xy 118.43325 -224.640336) (xy 118.391363 -224.670768)
			(xy 118.345231 -224.694274) (xy 118.295991 -224.710273) (xy 118.244853 -224.718372) (xy 118.193079 -224.718372)
			(xy 118.141941 -224.710273) (xy 118.092701 -224.694274) (xy 118.046569 -224.670768) (xy 118.004682 -224.640336)
			(xy 117.968072 -224.603726) (xy 117.93764 -224.561839) (xy 117.914134 -224.515707) (xy 117.898135 -224.466467)
			(xy 117.890036 -224.415329) (xy 117.889528 -224.389442) (xy 117.608604 -224.389442) (xy 117.60806 -224.417149)
			(xy 117.598874 -224.471796) (xy 117.590316 -224.498154) (xy 117.582442 -224.520252) (xy 117.78742 -224.87509)
			(xy 117.81028 -224.879408) (xy 117.835109 -224.884542) (xy 117.882888 -224.901501) (xy 117.927508 -224.925578)
			(xy 117.967914 -224.956202) (xy 118.003154 -224.992654) (xy 118.032397 -225.034071) (xy 118.054952 -225.079478)
			(xy 118.070288 -225.127804) (xy 118.078043 -225.177908) (xy 118.078504 -225.203258) (xy 118.077996 -225.229165)
			(xy 118.06989 -225.280342) (xy 118.053878 -225.329621) (xy 118.030355 -225.375788) (xy 117.999899 -225.417707)
			(xy 117.963261 -225.454345) (xy 117.921342 -225.484801) (xy 117.875175 -225.508324) (xy 117.825896 -225.524336)
			(xy 117.774719 -225.532442) (xy 117.722905 -225.532442) (xy 117.671728 -225.524336) (xy 117.622449 -225.508324)
			(xy 117.576282 -225.484801) (xy 117.534363 -225.454345) (xy 117.497725 -225.417707) (xy 117.467269 -225.375788)
			(xy 117.443746 -225.329621) (xy 117.427734 -225.280342) (xy 117.419628 -225.229165) (xy 117.41912 -225.203258)
			(xy 117.419727 -225.175541) (xy 117.429042 -225.120895) (xy 117.437662 -225.094546) (xy 117.445536 -225.072448)
			(xy 117.240558 -224.71761) (xy 117.217698 -224.713292) (xy 117.192885 -224.708145) (xy 117.145143 -224.691153)
			(xy 117.100563 -224.667056) (xy 117.060196 -224.63642) (xy 117.024993 -224.599968) (xy 116.995782 -224.558558)
			(xy 116.973252 -224.513166) (xy 116.957934 -224.46486) (xy 116.950188 -224.41478) (xy 116.949728 -224.389442)
			(xy 116.668804 -224.389442) (xy 116.668296 -224.415329) (xy 116.660197 -224.466467) (xy 116.644198 -224.515707)
			(xy 116.620692 -224.561839) (xy 116.59026 -224.603726) (xy 116.55365 -224.640336) (xy 116.511763 -224.670768)
			(xy 116.465631 -224.694274) (xy 116.416391 -224.710273) (xy 116.365253 -224.718372) (xy 116.313479 -224.718372)
			(xy 116.262341 -224.710273) (xy 116.213101 -224.694274) (xy 116.166969 -224.670768) (xy 116.125082 -224.640336)
			(xy 116.088472 -224.603726) (xy 116.05804 -224.561839) (xy 116.034534 -224.515707) (xy 116.018535 -224.466467)
			(xy 116.010436 -224.415329) (xy 116.009928 -224.389442) (xy 115.729004 -224.389442) (xy 115.72846 -224.417149)
			(xy 115.719274 -224.471796) (xy 115.710716 -224.498154) (xy 115.702842 -224.520252) (xy 115.90782 -224.87509)
			(xy 115.93068 -224.879408) (xy 115.955509 -224.884542) (xy 116.003288 -224.901501) (xy 116.047908 -224.925578)
			(xy 116.088314 -224.956202) (xy 116.123554 -224.992654) (xy 116.152797 -225.034071) (xy 116.175352 -225.079478)
			(xy 116.190688 -225.127804) (xy 116.198443 -225.177908) (xy 116.198904 -225.203258) (xy 116.198396 -225.229165)
			(xy 116.19029 -225.280342) (xy 116.174278 -225.329621) (xy 116.150755 -225.375788) (xy 116.120299 -225.417707)
			(xy 116.083661 -225.454345) (xy 116.041742 -225.484801) (xy 115.995575 -225.508324) (xy 115.946296 -225.524336)
			(xy 115.895119 -225.532442) (xy 115.843305 -225.532442) (xy 115.792128 -225.524336) (xy 115.742849 -225.508324)
			(xy 115.696682 -225.484801) (xy 115.654763 -225.454345) (xy 115.618125 -225.417707) (xy 115.587669 -225.375788)
			(xy 115.564146 -225.329621) (xy 115.548134 -225.280342) (xy 115.540028 -225.229165) (xy 115.53952 -225.203258)
			(xy 115.540127 -225.175541) (xy 115.549442 -225.120895) (xy 115.558062 -225.094546) (xy 115.565936 -225.072448)
			(xy 115.360958 -224.71761) (xy 115.338098 -224.713292) (xy 115.313285 -224.708145) (xy 115.265543 -224.691153)
			(xy 115.220963 -224.667056) (xy 115.180596 -224.63642) (xy 115.145393 -224.599968) (xy 115.116182 -224.558558)
			(xy 115.093652 -224.513166) (xy 115.078334 -224.46486) (xy 115.070588 -224.41478) (xy 115.070128 -224.389442)
			(xy 114.789204 -224.389442) (xy 114.788696 -224.415329) (xy 114.780597 -224.466467) (xy 114.764598 -224.515707)
			(xy 114.741092 -224.561839) (xy 114.71066 -224.603726) (xy 114.67405 -224.640336) (xy 114.632163 -224.670768)
			(xy 114.586031 -224.694274) (xy 114.536791 -224.710273) (xy 114.485653 -224.718372) (xy 114.433879 -224.718372)
			(xy 114.382741 -224.710273) (xy 114.333501 -224.694274) (xy 114.287369 -224.670768) (xy 114.245482 -224.640336)
			(xy 114.208872 -224.603726) (xy 114.17844 -224.561839) (xy 114.154934 -224.515707) (xy 114.138935 -224.466467)
			(xy 114.130836 -224.415329) (xy 114.130328 -224.389442) (xy 113.849404 -224.389442) (xy 113.84886 -224.417149)
			(xy 113.839674 -224.471796) (xy 113.831116 -224.498154) (xy 113.823242 -224.520252) (xy 114.02822 -224.87509)
			(xy 114.05108 -224.879408) (xy 114.075909 -224.884542) (xy 114.123688 -224.901501) (xy 114.168308 -224.925578)
			(xy 114.208714 -224.956202) (xy 114.243954 -224.992654) (xy 114.273197 -225.034071) (xy 114.295752 -225.079478)
			(xy 114.311088 -225.127804) (xy 114.318843 -225.177908) (xy 114.319304 -225.203258) (xy 114.318796 -225.229165)
			(xy 114.31069 -225.280342) (xy 114.294678 -225.329621) (xy 114.271155 -225.375788) (xy 114.240699 -225.417707)
			(xy 114.204061 -225.454345) (xy 114.162142 -225.484801) (xy 114.115975 -225.508324) (xy 114.066696 -225.524336)
			(xy 114.015519 -225.532442) (xy 113.963705 -225.532442) (xy 113.912528 -225.524336) (xy 113.863249 -225.508324)
			(xy 113.817082 -225.484801) (xy 113.775163 -225.454345) (xy 113.738525 -225.417707) (xy 113.708069 -225.375788)
			(xy 113.684546 -225.329621) (xy 113.668534 -225.280342) (xy 113.660428 -225.229165) (xy 113.65992 -225.203258)
			(xy 113.660527 -225.175541) (xy 113.669842 -225.120895) (xy 113.678462 -225.094546) (xy 113.686336 -225.072448)
			(xy 113.481358 -224.71761) (xy 113.458498 -224.713292) (xy 113.433685 -224.708145) (xy 113.385943 -224.691153)
			(xy 113.341363 -224.667056) (xy 113.300996 -224.63642) (xy 113.265793 -224.599968) (xy 113.236582 -224.558558)
			(xy 113.214052 -224.513166) (xy 113.198734 -224.46486) (xy 113.190988 -224.41478) (xy 113.190528 -224.389442)
			(xy 112.909604 -224.389442) (xy 112.909096 -224.415329) (xy 112.900997 -224.466467) (xy 112.884998 -224.515707)
			(xy 112.861492 -224.561839) (xy 112.83106 -224.603726) (xy 112.79445 -224.640336) (xy 112.752563 -224.670768)
			(xy 112.706431 -224.694274) (xy 112.657191 -224.710273) (xy 112.606053 -224.718372) (xy 112.554279 -224.718372)
			(xy 112.503141 -224.710273) (xy 112.453901 -224.694274) (xy 112.407769 -224.670768) (xy 112.365882 -224.640336)
			(xy 112.329272 -224.603726) (xy 112.29884 -224.561839) (xy 112.275334 -224.515707) (xy 112.259335 -224.466467)
			(xy 112.251236 -224.415329) (xy 112.250728 -224.389442) (xy 111.969804 -224.389442) (xy 111.96926 -224.417149)
			(xy 111.960074 -224.471796) (xy 111.951516 -224.498154) (xy 111.943642 -224.520252) (xy 112.14862 -224.87509)
			(xy 112.17148 -224.879408) (xy 112.196309 -224.884542) (xy 112.244088 -224.901501) (xy 112.288708 -224.925578)
			(xy 112.329114 -224.956202) (xy 112.364354 -224.992654) (xy 112.393597 -225.034071) (xy 112.416152 -225.079478)
			(xy 112.431488 -225.127804) (xy 112.439243 -225.177908) (xy 112.439704 -225.203258) (xy 112.439196 -225.229165)
			(xy 112.43109 -225.280342) (xy 112.415078 -225.329621) (xy 112.391555 -225.375788) (xy 112.361099 -225.417707)
			(xy 112.324461 -225.454345) (xy 112.282542 -225.484801) (xy 112.236375 -225.508324) (xy 112.187096 -225.524336)
			(xy 112.135919 -225.532442) (xy 112.084105 -225.532442) (xy 112.032928 -225.524336) (xy 111.983649 -225.508324)
			(xy 111.937482 -225.484801) (xy 111.895563 -225.454345) (xy 111.858925 -225.417707) (xy 111.828469 -225.375788)
			(xy 111.804946 -225.329621) (xy 111.788934 -225.280342) (xy 111.780828 -225.229165) (xy 111.78032 -225.203258)
			(xy 111.780927 -225.175541) (xy 111.790242 -225.120895) (xy 111.798862 -225.094546) (xy 111.806736 -225.072448)
			(xy 111.601758 -224.71761) (xy 111.578898 -224.713292) (xy 111.554085 -224.708145) (xy 111.506343 -224.691153)
			(xy 111.461763 -224.667056) (xy 111.421396 -224.63642) (xy 111.386193 -224.599968) (xy 111.356982 -224.558558)
			(xy 111.334452 -224.513166) (xy 111.319134 -224.46486) (xy 111.311388 -224.41478) (xy 111.310928 -224.389442)
			(xy 111.030004 -224.389442) (xy 111.029496 -224.415329) (xy 111.021397 -224.466467) (xy 111.005398 -224.515707)
			(xy 110.981892 -224.561839) (xy 110.95146 -224.603726) (xy 110.91485 -224.640336) (xy 110.872963 -224.670768)
			(xy 110.826831 -224.694274) (xy 110.777591 -224.710273) (xy 110.726453 -224.718372) (xy 110.674679 -224.718372)
			(xy 110.623541 -224.710273) (xy 110.574301 -224.694274) (xy 110.528169 -224.670768) (xy 110.486282 -224.640336)
			(xy 110.449672 -224.603726) (xy 110.41924 -224.561839) (xy 110.395734 -224.515707) (xy 110.379735 -224.466467)
			(xy 110.371636 -224.415329) (xy 110.371128 -224.389442) (xy 110.090204 -224.389442) (xy 110.08966 -224.417149)
			(xy 110.080474 -224.471796) (xy 110.071916 -224.498154) (xy 110.064042 -224.520252) (xy 110.26902 -224.87509)
			(xy 110.29188 -224.879408) (xy 110.316709 -224.884542) (xy 110.364488 -224.901501) (xy 110.409108 -224.925578)
			(xy 110.449514 -224.956202) (xy 110.484754 -224.992654) (xy 110.513997 -225.034071) (xy 110.536552 -225.079478)
			(xy 110.551888 -225.127804) (xy 110.559643 -225.177908) (xy 110.560104 -225.203258) (xy 110.559596 -225.229165)
			(xy 110.55149 -225.280342) (xy 110.535478 -225.329621) (xy 110.511955 -225.375788) (xy 110.481499 -225.417707)
			(xy 110.444861 -225.454345) (xy 110.402942 -225.484801) (xy 110.356775 -225.508324) (xy 110.307496 -225.524336)
			(xy 110.256319 -225.532442) (xy 110.204505 -225.532442) (xy 110.153328 -225.524336) (xy 110.104049 -225.508324)
			(xy 110.057882 -225.484801) (xy 110.015963 -225.454345) (xy 109.979325 -225.417707) (xy 109.948869 -225.375788)
			(xy 109.925346 -225.329621) (xy 109.909334 -225.280342) (xy 109.901228 -225.229165) (xy 109.90072 -225.203258)
			(xy 109.901327 -225.175541) (xy 109.910642 -225.120895) (xy 109.919262 -225.094546) (xy 109.927136 -225.072448)
			(xy 109.722158 -224.71761) (xy 109.699298 -224.713292) (xy 109.674485 -224.708145) (xy 109.626743 -224.691153)
			(xy 109.582163 -224.667056) (xy 109.541796 -224.63642) (xy 109.506593 -224.599968) (xy 109.477382 -224.558558)
			(xy 109.454852 -224.513166) (xy 109.439534 -224.46486) (xy 109.431788 -224.41478) (xy 109.431328 -224.389442)
			(xy 109.150404 -224.389442) (xy 109.149896 -224.415329) (xy 109.141797 -224.466467) (xy 109.125798 -224.515707)
			(xy 109.102292 -224.561839) (xy 109.07186 -224.603726) (xy 109.03525 -224.640336) (xy 108.993363 -224.670768)
			(xy 108.947231 -224.694274) (xy 108.897991 -224.710273) (xy 108.846853 -224.718372) (xy 108.795079 -224.718372)
			(xy 108.743941 -224.710273) (xy 108.694701 -224.694274) (xy 108.648569 -224.670768) (xy 108.606682 -224.640336)
			(xy 108.570072 -224.603726) (xy 108.53964 -224.561839) (xy 108.516134 -224.515707) (xy 108.500135 -224.466467)
			(xy 108.492036 -224.415329) (xy 108.491528 -224.389442) (xy 108.210604 -224.389442) (xy 108.21006 -224.417149)
			(xy 108.200874 -224.471796) (xy 108.192316 -224.498154) (xy 108.184442 -224.520252) (xy 108.38942 -224.87509)
			(xy 108.41228 -224.879408) (xy 108.437109 -224.884542) (xy 108.484888 -224.901501) (xy 108.529508 -224.925578)
			(xy 108.569914 -224.956202) (xy 108.605154 -224.992654) (xy 108.634397 -225.034071) (xy 108.656952 -225.079478)
			(xy 108.672288 -225.127804) (xy 108.680043 -225.177908) (xy 108.680504 -225.203258) (xy 108.679996 -225.229165)
			(xy 108.67189 -225.280342) (xy 108.655878 -225.329621) (xy 108.632355 -225.375788) (xy 108.601899 -225.417707)
			(xy 108.565261 -225.454345) (xy 108.523342 -225.484801) (xy 108.477175 -225.508324) (xy 108.427896 -225.524336)
			(xy 108.376719 -225.532442) (xy 108.324905 -225.532442) (xy 108.273728 -225.524336) (xy 108.224449 -225.508324)
			(xy 108.178282 -225.484801) (xy 108.136363 -225.454345) (xy 108.099725 -225.417707) (xy 108.069269 -225.375788)
			(xy 108.045746 -225.329621) (xy 108.029734 -225.280342) (xy 108.021628 -225.229165) (xy 108.02112 -225.203258)
			(xy 108.021727 -225.175541) (xy 108.031042 -225.120895) (xy 108.039662 -225.094546) (xy 108.047536 -225.072448)
			(xy 107.842558 -224.71761) (xy 107.819698 -224.713292) (xy 107.794885 -224.708145) (xy 107.747143 -224.691153)
			(xy 107.702563 -224.667056) (xy 107.662196 -224.63642) (xy 107.626993 -224.599968) (xy 107.597782 -224.558558)
			(xy 107.575252 -224.513166) (xy 107.559934 -224.46486) (xy 107.552188 -224.41478) (xy 107.551728 -224.389442)
			(xy 107.270804 -224.389442) (xy 107.270296 -224.415329) (xy 107.262197 -224.466467) (xy 107.246198 -224.515707)
			(xy 107.222692 -224.561839) (xy 107.19226 -224.603726) (xy 107.15565 -224.640336) (xy 107.113763 -224.670768)
			(xy 107.067631 -224.694274) (xy 107.018391 -224.710273) (xy 106.967253 -224.718372) (xy 106.915479 -224.718372)
			(xy 106.864341 -224.710273) (xy 106.815101 -224.694274) (xy 106.768969 -224.670768) (xy 106.727082 -224.640336)
			(xy 106.690472 -224.603726) (xy 106.66004 -224.561839) (xy 106.636534 -224.515707) (xy 106.620535 -224.466467)
			(xy 106.612436 -224.415329) (xy 106.611928 -224.389442) (xy 106.331004 -224.389442) (xy 106.33046 -224.417149)
			(xy 106.321274 -224.471796) (xy 106.312716 -224.498154) (xy 106.304842 -224.520252) (xy 106.50982 -224.87509)
			(xy 106.53268 -224.879408) (xy 106.557509 -224.884542) (xy 106.605288 -224.901501) (xy 106.649908 -224.925578)
			(xy 106.690314 -224.956202) (xy 106.725554 -224.992654) (xy 106.754797 -225.034071) (xy 106.777352 -225.079478)
			(xy 106.792688 -225.127804) (xy 106.800443 -225.177908) (xy 106.800904 -225.203258) (xy 106.800396 -225.229165)
			(xy 106.79229 -225.280342) (xy 106.776278 -225.329621) (xy 106.752755 -225.375788) (xy 106.722299 -225.417707)
			(xy 106.685661 -225.454345) (xy 106.643742 -225.484801) (xy 106.597575 -225.508324) (xy 106.548296 -225.524336)
			(xy 106.497119 -225.532442) (xy 106.445305 -225.532442) (xy 106.394128 -225.524336) (xy 106.344849 -225.508324)
			(xy 106.298682 -225.484801) (xy 106.256763 -225.454345) (xy 106.220125 -225.417707) (xy 106.189669 -225.375788)
			(xy 106.166146 -225.329621) (xy 106.150134 -225.280342) (xy 106.142028 -225.229165) (xy 106.14152 -225.203258)
			(xy 106.142127 -225.175541) (xy 106.151442 -225.120895) (xy 106.160062 -225.094546) (xy 106.167936 -225.072448)
			(xy 105.962958 -224.71761) (xy 105.940098 -224.713292) (xy 105.915285 -224.708145) (xy 105.867543 -224.691153)
			(xy 105.822963 -224.667056) (xy 105.782596 -224.63642) (xy 105.747393 -224.599968) (xy 105.718182 -224.558558)
			(xy 105.695652 -224.513166) (xy 105.680334 -224.46486) (xy 105.672588 -224.41478) (xy 105.672128 -224.389442)
			(xy 105.391204 -224.389442) (xy 105.390696 -224.415329) (xy 105.382597 -224.466467) (xy 105.366598 -224.515707)
			(xy 105.343092 -224.561839) (xy 105.31266 -224.603726) (xy 105.27605 -224.640336) (xy 105.234163 -224.670768)
			(xy 105.188031 -224.694274) (xy 105.138791 -224.710273) (xy 105.087653 -224.718372) (xy 105.035879 -224.718372)
			(xy 104.984741 -224.710273) (xy 104.935501 -224.694274) (xy 104.889369 -224.670768) (xy 104.847482 -224.640336)
			(xy 104.810872 -224.603726) (xy 104.78044 -224.561839) (xy 104.756934 -224.515707) (xy 104.740935 -224.466467)
			(xy 104.732836 -224.415329) (xy 104.732328 -224.389442) (xy 104.451404 -224.389442) (xy 104.45086 -224.417149)
			(xy 104.441674 -224.471796) (xy 104.433116 -224.498154) (xy 104.425242 -224.520252) (xy 104.63022 -224.87509)
			(xy 104.65308 -224.879408) (xy 104.677909 -224.884542) (xy 104.725688 -224.901501) (xy 104.770308 -224.925578)
			(xy 104.810714 -224.956202) (xy 104.845954 -224.992654) (xy 104.875197 -225.034071) (xy 104.897752 -225.079478)
			(xy 104.913088 -225.127804) (xy 104.920843 -225.177908) (xy 104.921304 -225.203258) (xy 104.920796 -225.229165)
			(xy 104.91269 -225.280342) (xy 104.896678 -225.329621) (xy 104.873155 -225.375788) (xy 104.842699 -225.417707)
			(xy 104.806061 -225.454345) (xy 104.764142 -225.484801) (xy 104.717975 -225.508324) (xy 104.668696 -225.524336)
			(xy 104.617519 -225.532442) (xy 104.565705 -225.532442) (xy 104.514528 -225.524336) (xy 104.465249 -225.508324)
			(xy 104.419082 -225.484801) (xy 104.377163 -225.454345) (xy 104.340525 -225.417707) (xy 104.310069 -225.375788)
			(xy 104.286546 -225.329621) (xy 104.270534 -225.280342) (xy 104.262428 -225.229165) (xy 104.26192 -225.203258)
			(xy 104.262527 -225.175541) (xy 104.271842 -225.120895) (xy 104.280462 -225.094546) (xy 104.288336 -225.072448)
			(xy 104.083358 -224.71761) (xy 104.060498 -224.713292) (xy 104.035685 -224.708145) (xy 103.987943 -224.691153)
			(xy 103.943363 -224.667056) (xy 103.902996 -224.63642) (xy 103.867793 -224.599968) (xy 103.838582 -224.558558)
			(xy 103.816052 -224.513166) (xy 103.800734 -224.46486) (xy 103.792988 -224.41478) (xy 103.792528 -224.389442)
			(xy 103.511604 -224.389442) (xy 103.511096 -224.415329) (xy 103.502997 -224.466467) (xy 103.486998 -224.515707)
			(xy 103.463492 -224.561839) (xy 103.43306 -224.603726) (xy 103.39645 -224.640336) (xy 103.354563 -224.670768)
			(xy 103.308431 -224.694274) (xy 103.259191 -224.710273) (xy 103.208053 -224.718372) (xy 103.156279 -224.718372)
			(xy 103.105141 -224.710273) (xy 103.055901 -224.694274) (xy 103.009769 -224.670768) (xy 102.967882 -224.640336)
			(xy 102.931272 -224.603726) (xy 102.90084 -224.561839) (xy 102.877334 -224.515707) (xy 102.861335 -224.466467)
			(xy 102.853236 -224.415329) (xy 102.852728 -224.389442) (xy 102.571804 -224.389442) (xy 102.57126 -224.417149)
			(xy 102.562074 -224.471796) (xy 102.553516 -224.498154) (xy 102.545642 -224.520252) (xy 102.75062 -224.87509)
			(xy 102.77348 -224.879408) (xy 102.798309 -224.884542) (xy 102.846088 -224.901501) (xy 102.890708 -224.925578)
			(xy 102.931114 -224.956202) (xy 102.966354 -224.992654) (xy 102.995597 -225.034071) (xy 103.018152 -225.079478)
			(xy 103.033488 -225.127804) (xy 103.041243 -225.177908) (xy 103.041704 -225.203258) (xy 103.041196 -225.229165)
			(xy 103.03309 -225.280342) (xy 103.017078 -225.329621) (xy 102.993555 -225.375788) (xy 102.963099 -225.417707)
			(xy 102.926461 -225.454345) (xy 102.884542 -225.484801) (xy 102.838375 -225.508324) (xy 102.789096 -225.524336)
			(xy 102.737919 -225.532442) (xy 102.686105 -225.532442) (xy 102.634928 -225.524336) (xy 102.585649 -225.508324)
			(xy 102.539482 -225.484801) (xy 102.497563 -225.454345) (xy 102.460925 -225.417707) (xy 102.430469 -225.375788)
			(xy 102.406946 -225.329621) (xy 102.390934 -225.280342) (xy 102.382828 -225.229165) (xy 102.38232 -225.203258)
			(xy 102.382927 -225.175541) (xy 102.392242 -225.120895) (xy 102.400862 -225.094546) (xy 102.408736 -225.072448)
			(xy 102.203758 -224.71761) (xy 102.180898 -224.713292) (xy 102.156085 -224.708145) (xy 102.108343 -224.691153)
			(xy 102.063763 -224.667056) (xy 102.023396 -224.63642) (xy 101.988193 -224.599968) (xy 101.958982 -224.558558)
			(xy 101.936452 -224.513166) (xy 101.921134 -224.46486) (xy 101.913388 -224.41478) (xy 101.912928 -224.389442)
			(xy 101.632004 -224.389442) (xy 101.631496 -224.415329) (xy 101.623397 -224.466467) (xy 101.607398 -224.515707)
			(xy 101.583892 -224.561839) (xy 101.55346 -224.603726) (xy 101.51685 -224.640336) (xy 101.474963 -224.670768)
			(xy 101.428831 -224.694274) (xy 101.379591 -224.710273) (xy 101.328453 -224.718372) (xy 101.276679 -224.718372)
			(xy 101.225541 -224.710273) (xy 101.176301 -224.694274) (xy 101.130169 -224.670768) (xy 101.088282 -224.640336)
			(xy 101.051672 -224.603726) (xy 101.02124 -224.561839) (xy 100.997734 -224.515707) (xy 100.981735 -224.466467)
			(xy 100.973636 -224.415329) (xy 100.973128 -224.389442) (xy 100.692204 -224.389442) (xy 100.69166 -224.417149)
			(xy 100.682474 -224.471796) (xy 100.673916 -224.498154) (xy 100.666042 -224.520252) (xy 100.87102 -224.87509)
			(xy 100.89388 -224.879408) (xy 100.918709 -224.884542) (xy 100.966488 -224.901501) (xy 101.011108 -224.925578)
			(xy 101.051514 -224.956202) (xy 101.086754 -224.992654) (xy 101.115997 -225.034071) (xy 101.138552 -225.079478)
			(xy 101.153888 -225.127804) (xy 101.161643 -225.177908) (xy 101.162104 -225.203258) (xy 101.161596 -225.229165)
			(xy 101.15349 -225.280342) (xy 101.137478 -225.329621) (xy 101.113955 -225.375788) (xy 101.083499 -225.417707)
			(xy 101.046861 -225.454345) (xy 101.004942 -225.484801) (xy 100.958775 -225.508324) (xy 100.909496 -225.524336)
			(xy 100.858319 -225.532442) (xy 100.806505 -225.532442) (xy 100.755328 -225.524336) (xy 100.706049 -225.508324)
			(xy 100.659882 -225.484801) (xy 100.617963 -225.454345) (xy 100.581325 -225.417707) (xy 100.550869 -225.375788)
			(xy 100.527346 -225.329621) (xy 100.511334 -225.280342) (xy 100.503228 -225.229165) (xy 100.50272 -225.203258)
			(xy 100.503327 -225.175541) (xy 100.512642 -225.120895) (xy 100.521262 -225.094546) (xy 100.529136 -225.072448)
			(xy 100.324158 -224.71761) (xy 100.301298 -224.713292) (xy 100.276485 -224.708145) (xy 100.228743 -224.691153)
			(xy 100.184163 -224.667056) (xy 100.143796 -224.63642) (xy 100.108593 -224.599968) (xy 100.079382 -224.558558)
			(xy 100.056852 -224.513166) (xy 100.041534 -224.46486) (xy 100.033788 -224.41478) (xy 100.033328 -224.389442)
			(xy 99.752404 -224.389442) (xy 99.751896 -224.415329) (xy 99.743797 -224.466467) (xy 99.727798 -224.515707)
			(xy 99.704292 -224.561839) (xy 99.67386 -224.603726) (xy 99.63725 -224.640336) (xy 99.595363 -224.670768)
			(xy 99.549231 -224.694274) (xy 99.499991 -224.710273) (xy 99.448853 -224.718372) (xy 99.397079 -224.718372)
			(xy 99.345941 -224.710273) (xy 99.296701 -224.694274) (xy 99.250569 -224.670768) (xy 99.208682 -224.640336)
			(xy 99.172072 -224.603726) (xy 99.14164 -224.561839) (xy 99.118134 -224.515707) (xy 99.102135 -224.466467)
			(xy 99.094036 -224.415329) (xy 99.093528 -224.389442) (xy 98.812604 -224.389442) (xy 98.81206 -224.417149)
			(xy 98.802874 -224.471796) (xy 98.794316 -224.498154) (xy 98.786442 -224.520252) (xy 98.99142 -224.87509)
			(xy 99.01428 -224.879408) (xy 99.039109 -224.884542) (xy 99.086888 -224.901501) (xy 99.131508 -224.925578)
			(xy 99.171914 -224.956202) (xy 99.207154 -224.992654) (xy 99.236397 -225.034071) (xy 99.258952 -225.079478)
			(xy 99.274288 -225.127804) (xy 99.282043 -225.177908) (xy 99.282504 -225.203258) (xy 99.281996 -225.229165)
			(xy 99.27389 -225.280342) (xy 99.257878 -225.329621) (xy 99.234355 -225.375788) (xy 99.203899 -225.417707)
			(xy 99.167261 -225.454345) (xy 99.125342 -225.484801) (xy 99.079175 -225.508324) (xy 99.029896 -225.524336)
			(xy 98.978719 -225.532442) (xy 98.926905 -225.532442) (xy 98.875728 -225.524336) (xy 98.826449 -225.508324)
			(xy 98.780282 -225.484801) (xy 98.738363 -225.454345) (xy 98.701725 -225.417707) (xy 98.671269 -225.375788)
			(xy 98.647746 -225.329621) (xy 98.631734 -225.280342) (xy 98.623628 -225.229165) (xy 98.62312 -225.203258)
			(xy 98.623727 -225.175541) (xy 98.633042 -225.120895) (xy 98.641662 -225.094546) (xy 98.649536 -225.072448)
			(xy 98.444558 -224.71761) (xy 98.421698 -224.713292) (xy 98.396885 -224.708145) (xy 98.349143 -224.691153)
			(xy 98.304563 -224.667056) (xy 98.264196 -224.63642) (xy 98.228993 -224.599968) (xy 98.199782 -224.558558)
			(xy 98.177252 -224.513166) (xy 98.161934 -224.46486) (xy 98.154188 -224.41478) (xy 98.153728 -224.389442)
			(xy 97.872804 -224.389442) (xy 97.872296 -224.415329) (xy 97.864197 -224.466467) (xy 97.848198 -224.515707)
			(xy 97.824692 -224.561839) (xy 97.79426 -224.603726) (xy 97.75765 -224.640336) (xy 97.715763 -224.670768)
			(xy 97.669631 -224.694274) (xy 97.620391 -224.710273) (xy 97.569253 -224.718372) (xy 97.517479 -224.718372)
			(xy 97.466341 -224.710273) (xy 97.417101 -224.694274) (xy 97.370969 -224.670768) (xy 97.329082 -224.640336)
			(xy 97.292472 -224.603726) (xy 97.26204 -224.561839) (xy 97.238534 -224.515707) (xy 97.222535 -224.466467)
			(xy 97.214436 -224.415329) (xy 97.213928 -224.389442) (xy 96.933004 -224.389442) (xy 96.93246 -224.417149)
			(xy 96.923274 -224.471796) (xy 96.914716 -224.498154) (xy 96.906842 -224.520252) (xy 97.11182 -224.87509)
			(xy 97.13468 -224.879408) (xy 97.159509 -224.884542) (xy 97.207288 -224.901501) (xy 97.251908 -224.925578)
			(xy 97.292314 -224.956202) (xy 97.327554 -224.992654) (xy 97.356797 -225.034071) (xy 97.379352 -225.079478)
			(xy 97.394688 -225.127804) (xy 97.402443 -225.177908) (xy 97.402904 -225.203258) (xy 97.402396 -225.229165)
			(xy 97.39429 -225.280342) (xy 97.378278 -225.329621) (xy 97.354755 -225.375788) (xy 97.324299 -225.417707)
			(xy 97.287661 -225.454345) (xy 97.245742 -225.484801) (xy 97.199575 -225.508324) (xy 97.150296 -225.524336)
			(xy 97.099119 -225.532442) (xy 97.047305 -225.532442) (xy 96.996128 -225.524336) (xy 96.946849 -225.508324)
			(xy 96.900682 -225.484801) (xy 96.858763 -225.454345) (xy 96.822125 -225.417707) (xy 96.791669 -225.375788)
			(xy 96.768146 -225.329621) (xy 96.752134 -225.280342) (xy 96.744028 -225.229165) (xy 96.74352 -225.203258)
			(xy 96.744127 -225.175541) (xy 96.753442 -225.120895) (xy 96.762062 -225.094546) (xy 96.769936 -225.072448)
			(xy 96.564958 -224.71761) (xy 96.542098 -224.713292) (xy 96.517285 -224.708145) (xy 96.469543 -224.691153)
			(xy 96.424963 -224.667056) (xy 96.384596 -224.63642) (xy 96.349393 -224.599968) (xy 96.320182 -224.558558)
			(xy 96.297652 -224.513166) (xy 96.282334 -224.46486) (xy 96.274588 -224.41478) (xy 96.274128 -224.389442)
			(xy 95.993204 -224.389442) (xy 95.992696 -224.415329) (xy 95.984597 -224.466467) (xy 95.968598 -224.515707)
			(xy 95.945092 -224.561839) (xy 95.91466 -224.603726) (xy 95.87805 -224.640336) (xy 95.836163 -224.670768)
			(xy 95.790031 -224.694274) (xy 95.740791 -224.710273) (xy 95.689653 -224.718372) (xy 95.637879 -224.718372)
			(xy 95.586741 -224.710273) (xy 95.537501 -224.694274) (xy 95.491369 -224.670768) (xy 95.449482 -224.640336)
			(xy 95.412872 -224.603726) (xy 95.38244 -224.561839) (xy 95.358934 -224.515707) (xy 95.342935 -224.466467)
			(xy 95.334836 -224.415329) (xy 95.334328 -224.389442) (xy 95.053404 -224.389442) (xy 95.05286 -224.417149)
			(xy 95.043674 -224.471796) (xy 95.035116 -224.498154) (xy 95.027242 -224.520252) (xy 95.23222 -224.87509)
			(xy 95.25508 -224.879408) (xy 95.279909 -224.884542) (xy 95.327688 -224.901501) (xy 95.372308 -224.925578)
			(xy 95.412714 -224.956202) (xy 95.447954 -224.992654) (xy 95.477197 -225.034071) (xy 95.499752 -225.079478)
			(xy 95.515088 -225.127804) (xy 95.522843 -225.177908) (xy 95.523304 -225.203258) (xy 95.522796 -225.229165)
			(xy 95.51469 -225.280342) (xy 95.498678 -225.329621) (xy 95.475155 -225.375788) (xy 95.444699 -225.417707)
			(xy 95.408061 -225.454345) (xy 95.366142 -225.484801) (xy 95.319975 -225.508324) (xy 95.270696 -225.524336)
			(xy 95.219519 -225.532442) (xy 95.167705 -225.532442) (xy 95.116528 -225.524336) (xy 95.067249 -225.508324)
			(xy 95.021082 -225.484801) (xy 94.979163 -225.454345) (xy 94.942525 -225.417707) (xy 94.912069 -225.375788)
			(xy 94.888546 -225.329621) (xy 94.872534 -225.280342) (xy 94.864428 -225.229165) (xy 94.86392 -225.203258)
			(xy 94.864527 -225.175541) (xy 94.873842 -225.120895) (xy 94.882462 -225.094546) (xy 94.890336 -225.072448)
			(xy 94.685358 -224.71761) (xy 94.662498 -224.713292) (xy 94.637685 -224.708145) (xy 94.589943 -224.691153)
			(xy 94.545363 -224.667056) (xy 94.504996 -224.63642) (xy 94.469793 -224.599968) (xy 94.440582 -224.558558)
			(xy 94.418052 -224.513166) (xy 94.402734 -224.46486) (xy 94.394988 -224.41478) (xy 94.394528 -224.389442)
			(xy 94.113604 -224.389442) (xy 94.113096 -224.415329) (xy 94.104997 -224.466467) (xy 94.088998 -224.515707)
			(xy 94.065492 -224.561839) (xy 94.03506 -224.603726) (xy 93.99845 -224.640336) (xy 93.956563 -224.670768)
			(xy 93.910431 -224.694274) (xy 93.861191 -224.710273) (xy 93.810053 -224.718372) (xy 93.758279 -224.718372)
			(xy 93.707141 -224.710273) (xy 93.657901 -224.694274) (xy 93.611769 -224.670768) (xy 93.569882 -224.640336)
			(xy 93.533272 -224.603726) (xy 93.50284 -224.561839) (xy 93.479334 -224.515707) (xy 93.463335 -224.466467)
			(xy 93.455236 -224.415329) (xy 93.454728 -224.389442) (xy 93.173804 -224.389442) (xy 93.173804 -224.38995)
			(xy 93.173247 -224.417593) (xy 93.164056 -224.472111) (xy 93.155516 -224.498408) (xy 93.147896 -224.520252)
			(xy 93.35262 -224.87509) (xy 93.37548 -224.879408) (xy 93.400309 -224.884542) (xy 93.448088 -224.901501)
			(xy 93.492708 -224.925578) (xy 93.533114 -224.956202) (xy 93.568354 -224.992654) (xy 93.597597 -225.034071)
			(xy 93.620152 -225.079478) (xy 93.635488 -225.127804) (xy 93.643243 -225.177908) (xy 93.643704 -225.203258)
			(xy 93.643196 -225.229165) (xy 93.63509 -225.280342) (xy 93.619078 -225.329621) (xy 93.595555 -225.375788)
			(xy 93.565099 -225.417707) (xy 93.528461 -225.454345) (xy 93.486542 -225.484801) (xy 93.440375 -225.508324)
			(xy 93.391096 -225.524336) (xy 93.339919 -225.532442) (xy 93.288105 -225.532442) (xy 93.236928 -225.524336)
			(xy 93.187649 -225.508324) (xy 93.141482 -225.484801) (xy 93.099563 -225.454345) (xy 93.062925 -225.417707)
			(xy 93.032469 -225.375788) (xy 93.008946 -225.329621) (xy 92.992934 -225.280342) (xy 92.984828 -225.229165)
			(xy 92.98432 -225.203258) (xy 92.98432 -225.20275) (xy 92.98493 -225.175096) (xy 92.994253 -225.120579)
			(xy 93.002862 -225.094292) (xy 93.010482 -225.072448) (xy 92.805758 -224.71761) (xy 92.782898 -224.713292)
			(xy 92.758085 -224.708145) (xy 92.710343 -224.691153) (xy 92.665763 -224.667056) (xy 92.625396 -224.63642)
			(xy 92.590193 -224.599968) (xy 92.560982 -224.558558) (xy 92.538452 -224.513166) (xy 92.523134 -224.46486)
			(xy 92.515388 -224.41478) (xy 92.514928 -224.389442) (xy 92.234004 -224.389442) (xy 92.233496 -224.415329)
			(xy 92.225397 -224.466467) (xy 92.209398 -224.515707) (xy 92.185892 -224.561839) (xy 92.15546 -224.603726)
			(xy 92.11885 -224.640336) (xy 92.076963 -224.670768) (xy 92.030831 -224.694274) (xy 91.981591 -224.710273)
			(xy 91.930453 -224.718372) (xy 91.878679 -224.718372) (xy 91.827541 -224.710273) (xy 91.778301 -224.694274)
			(xy 91.732169 -224.670768) (xy 91.690282 -224.640336) (xy 91.653672 -224.603726) (xy 91.62324 -224.561839)
			(xy 91.599734 -224.515707) (xy 91.583735 -224.466467) (xy 91.575636 -224.415329) (xy 91.575128 -224.389442)
			(xy 91.294204 -224.389442) (xy 91.294204 -224.38995) (xy 91.293647 -224.417593) (xy 91.284456 -224.472111)
			(xy 91.275916 -224.498408) (xy 91.268296 -224.520252) (xy 91.47302 -224.87509) (xy 91.49588 -224.879408)
			(xy 91.520709 -224.884542) (xy 91.568488 -224.901501) (xy 91.613108 -224.925578) (xy 91.653514 -224.956202)
			(xy 91.688754 -224.992654) (xy 91.717997 -225.034071) (xy 91.740552 -225.079478) (xy 91.755888 -225.127804)
			(xy 91.763643 -225.177908) (xy 91.764104 -225.203258) (xy 91.763596 -225.229165) (xy 91.75549 -225.280342)
			(xy 91.739478 -225.329621) (xy 91.715955 -225.375788) (xy 91.685499 -225.417707) (xy 91.648861 -225.454345)
			(xy 91.606942 -225.484801) (xy 91.560775 -225.508324) (xy 91.511496 -225.524336) (xy 91.460319 -225.532442)
			(xy 91.408505 -225.532442) (xy 91.357328 -225.524336) (xy 91.308049 -225.508324) (xy 91.261882 -225.484801)
			(xy 91.219963 -225.454345) (xy 91.183325 -225.417707) (xy 91.152869 -225.375788) (xy 91.129346 -225.329621)
			(xy 91.113334 -225.280342) (xy 91.105228 -225.229165) (xy 91.10472 -225.203258) (xy 91.10472 -225.20275)
			(xy 91.10533 -225.175096) (xy 91.114653 -225.120579) (xy 91.123262 -225.094292) (xy 91.130882 -225.072448)
			(xy 90.926158 -224.71761) (xy 90.903298 -224.713292) (xy 90.878485 -224.708145) (xy 90.830743 -224.691153)
			(xy 90.786163 -224.667056) (xy 90.745796 -224.63642) (xy 90.710593 -224.599968) (xy 90.681382 -224.558558)
			(xy 90.658852 -224.513166) (xy 90.643534 -224.46486) (xy 90.635788 -224.41478) (xy 90.635328 -224.389442)
			(xy 90.354404 -224.389442) (xy 90.353896 -224.415329) (xy 90.345797 -224.466467) (xy 90.329798 -224.515707)
			(xy 90.306292 -224.561839) (xy 90.27586 -224.603726) (xy 90.23925 -224.640336) (xy 90.197363 -224.670768)
			(xy 90.151231 -224.694274) (xy 90.101991 -224.710273) (xy 90.050853 -224.718372) (xy 89.999079 -224.718372)
			(xy 89.947941 -224.710273) (xy 89.898701 -224.694274) (xy 89.852569 -224.670768) (xy 89.810682 -224.640336)
			(xy 89.774072 -224.603726) (xy 89.74364 -224.561839) (xy 89.720134 -224.515707) (xy 89.704135 -224.466467)
			(xy 89.696036 -224.415329) (xy 89.695528 -224.389442) (xy 2.509012 -224.389442) (xy 2.509012 -247.620536)
			(xy 228.175312 -247.620536) (xy 228.175312 -246.756936) (xy 228.175798 -246.729685) (xy 228.183554 -246.675737)
			(xy 228.198909 -246.623442) (xy 228.221551 -246.573865) (xy 228.251017 -246.528015) (xy 228.286708 -246.486824)
			(xy 228.327899 -246.451133) (xy 228.373749 -246.421667) (xy 228.423326 -246.399025) (xy 228.475621 -246.38367)
			(xy 228.529569 -246.375914) (xy 228.584071 -246.375914) (xy 228.638019 -246.38367) (xy 228.690314 -246.399025)
			(xy 228.739891 -246.421667) (xy 228.785741 -246.451133) (xy 228.826932 -246.486824) (xy 228.862623 -246.528015)
			(xy 228.892089 -246.573865) (xy 228.914731 -246.623442) (xy 228.930086 -246.675737) (xy 228.937842 -246.729685)
			(xy 228.938328 -246.756936) (xy 228.938328 -247.620536) (xy 228.937842 -247.647787) (xy 228.930086 -247.701735)
			(xy 228.914731 -247.75403) (xy 228.892089 -247.803607) (xy 228.862623 -247.849457) (xy 228.826932 -247.890648)
			(xy 228.785741 -247.926339) (xy 228.739891 -247.955805) (xy 228.690314 -247.978447) (xy 228.638019 -247.993802)
			(xy 228.584071 -248.001558) (xy 228.529569 -248.001558) (xy 228.475621 -247.993802) (xy 228.423326 -247.978447)
			(xy 228.373749 -247.955805) (xy 228.327899 -247.926339) (xy 228.286708 -247.890648) (xy 228.251017 -247.849457)
			(xy 228.221551 -247.803607) (xy 228.198909 -247.75403) (xy 228.183554 -247.701735) (xy 228.175798 -247.647787)
			(xy 228.175312 -247.620536) (xy 2.509012 -247.620536) (xy 2.509012 -251.76988) (xy 75.695566 -251.76988)
			(xy 75.699547 -251.63686) (xy 75.711476 -251.504315) (xy 75.731311 -251.372722) (xy 75.75898 -251.24255)
			(xy 75.794384 -251.114265) (xy 75.837397 -250.988328) (xy 75.887864 -250.865189) (xy 75.945605 -250.745288)
			(xy 76.010414 -250.629055) (xy 76.082058 -250.516905) (xy 76.16028 -250.409241) (xy 76.244801 -250.306448)
			(xy 76.335319 -250.208893) (xy 76.431508 -250.116927) (xy 76.533026 -250.030877) (xy 76.639507 -249.951053)
			(xy 76.750572 -249.87774) (xy 76.865823 -249.8112) (xy 76.984847 -249.751671) (xy 77.107218 -249.699367)
			(xy 77.232497 -249.654475) (xy 77.360238 -249.617156) (xy 77.489981 -249.587543) (xy 77.621263 -249.565742)
			(xy 77.753614 -249.551832) (xy 77.88656 -249.545861) (xy 78.019625 -249.547852) (xy 78.152333 -249.557797)
			(xy 78.284209 -249.575661) (xy 78.41478 -249.601379) (xy 78.54358 -249.63486) (xy 78.670146 -249.675984)
			(xy 78.794027 -249.724604) (xy 78.914778 -249.780545) (xy 79.031968 -249.843607) (xy 79.145177 -249.913565)
			(xy 79.253999 -249.990169) (xy 79.358045 -250.073143) (xy 79.456943 -250.162191) (xy 79.550338 -250.256994)
			(xy 79.637896 -250.357212) (xy 79.719305 -250.462488) (xy 79.794271 -250.572444) (xy 79.862528 -250.686686)
			(xy 79.92383 -250.804806) (xy 79.977959 -250.926381) (xy 80.02472 -251.050975) (xy 80.063946 -251.178143)
			(xy 80.095496 -251.307429) (xy 80.119259 -251.43837) (xy 80.135148 -251.570498) (xy 80.143106 -251.70334)
			(xy 80.143604 -251.76988) (xy 143.715496 -251.76988) (xy 143.719477 -251.63686) (xy 143.731406 -251.504315)
			(xy 143.751241 -251.372722) (xy 143.77891 -251.24255) (xy 143.814314 -251.114265) (xy 143.857327 -250.988328)
			(xy 143.907794 -250.865189) (xy 143.965535 -250.745288) (xy 144.030344 -250.629055) (xy 144.101988 -250.516905)
			(xy 144.18021 -250.409241) (xy 144.264731 -250.306448) (xy 144.355249 -250.208893) (xy 144.451438 -250.116927)
			(xy 144.552956 -250.030877) (xy 144.659437 -249.951053) (xy 144.770502 -249.87774) (xy 144.885753 -249.8112)
			(xy 145.004777 -249.751671) (xy 145.127148 -249.699367) (xy 145.252427 -249.654475) (xy 145.380168 -249.617156)
			(xy 145.509911 -249.587543) (xy 145.641193 -249.565742) (xy 145.773544 -249.551832) (xy 145.90649 -249.545861)
			(xy 146.039555 -249.547852) (xy 146.172263 -249.557797) (xy 146.304139 -249.575661) (xy 146.43471 -249.601379)
			(xy 146.56351 -249.63486) (xy 146.690076 -249.675984) (xy 146.813957 -249.724604) (xy 146.934708 -249.780545)
			(xy 147.051898 -249.843607) (xy 147.165107 -249.913565) (xy 147.273929 -249.990169) (xy 147.377975 -250.073143)
			(xy 147.476873 -250.162191) (xy 147.570268 -250.256994) (xy 147.657826 -250.357212) (xy 147.739235 -250.462488)
			(xy 147.814201 -250.572444) (xy 147.882458 -250.686686) (xy 147.94376 -250.804806) (xy 147.997889 -250.926381)
			(xy 148.04465 -251.050975) (xy 148.083876 -251.178143) (xy 148.115426 -251.307429) (xy 148.139189 -251.43837)
			(xy 148.155078 -251.570498) (xy 148.163036 -251.70334) (xy 148.163534 -251.76988) (xy 323.635634 -251.76988)
			(xy 323.639615 -251.63686) (xy 323.651544 -251.504315) (xy 323.671379 -251.372722) (xy 323.699048 -251.24255)
			(xy 323.734452 -251.114265) (xy 323.777465 -250.988328) (xy 323.827932 -250.865189) (xy 323.885673 -250.745288)
			(xy 323.950482 -250.629055) (xy 324.022126 -250.516905) (xy 324.100348 -250.409241) (xy 324.184869 -250.306448)
			(xy 324.275387 -250.208893) (xy 324.371576 -250.116927) (xy 324.473094 -250.030877) (xy 324.579575 -249.951053)
			(xy 324.69064 -249.87774) (xy 324.805891 -249.8112) (xy 324.924915 -249.751671) (xy 325.047286 -249.699367)
			(xy 325.172565 -249.654475) (xy 325.300306 -249.617156) (xy 325.430049 -249.587543) (xy 325.561331 -249.565742)
			(xy 325.693682 -249.551832) (xy 325.826628 -249.545861) (xy 325.959693 -249.547852) (xy 326.092401 -249.557797)
			(xy 326.224277 -249.575661) (xy 326.354848 -249.601379) (xy 326.483648 -249.63486) (xy 326.610214 -249.675984)
			(xy 326.734095 -249.724604) (xy 326.854846 -249.780545) (xy 326.972036 -249.843607) (xy 327.085245 -249.913565)
			(xy 327.194067 -249.990169) (xy 327.298113 -250.073143) (xy 327.397011 -250.162191) (xy 327.490406 -250.256994)
			(xy 327.577964 -250.357212) (xy 327.659373 -250.462488) (xy 327.734339 -250.572444) (xy 327.802596 -250.686686)
			(xy 327.863898 -250.804806) (xy 327.918027 -250.926381) (xy 327.964788 -251.050975) (xy 328.004014 -251.178143)
			(xy 328.035564 -251.307429) (xy 328.059327 -251.43837) (xy 328.075216 -251.570498) (xy 328.083174 -251.70334)
			(xy 328.083672 -251.76988) (xy 391.655564 -251.76988) (xy 391.659545 -251.63686) (xy 391.671474 -251.504315)
			(xy 391.691309 -251.372722) (xy 391.718978 -251.24255) (xy 391.754382 -251.114265) (xy 391.797395 -250.988328)
			(xy 391.847862 -250.865189) (xy 391.905603 -250.745288) (xy 391.970412 -250.629055) (xy 392.042056 -250.516905)
			(xy 392.120278 -250.409241) (xy 392.204799 -250.306448) (xy 392.295317 -250.208893) (xy 392.391506 -250.116927)
			(xy 392.493024 -250.030877) (xy 392.599505 -249.951053) (xy 392.71057 -249.87774) (xy 392.825821 -249.8112)
			(xy 392.944845 -249.751671) (xy 393.067216 -249.699367) (xy 393.192495 -249.654475) (xy 393.320236 -249.617156)
			(xy 393.449979 -249.587543) (xy 393.581261 -249.565742) (xy 393.713612 -249.551832) (xy 393.846558 -249.545861)
			(xy 393.979623 -249.547852) (xy 394.112331 -249.557797) (xy 394.244207 -249.575661) (xy 394.374778 -249.601379)
			(xy 394.503578 -249.63486) (xy 394.630144 -249.675984) (xy 394.754025 -249.724604) (xy 394.874776 -249.780545)
			(xy 394.991966 -249.843607) (xy 395.105175 -249.913565) (xy 395.213997 -249.990169) (xy 395.318043 -250.073143)
			(xy 395.416941 -250.162191) (xy 395.510336 -250.256994) (xy 395.597894 -250.357212) (xy 395.679303 -250.462488)
			(xy 395.754269 -250.572444) (xy 395.822526 -250.686686) (xy 395.883828 -250.804806) (xy 395.937957 -250.926381)
			(xy 395.984718 -251.050975) (xy 396.023944 -251.178143) (xy 396.055494 -251.307429) (xy 396.079257 -251.43837)
			(xy 396.095146 -251.570498) (xy 396.103104 -251.70334) (xy 396.103602 -251.76988) (xy 396.103104 -251.83642)
			(xy 396.095146 -251.969262) (xy 396.079257 -252.10139) (xy 396.055494 -252.232331) (xy 396.023944 -252.361617)
			(xy 395.984718 -252.488785) (xy 395.937957 -252.613379) (xy 395.883828 -252.734954) (xy 395.822526 -252.853074)
			(xy 395.754269 -252.967316) (xy 395.679303 -253.077272) (xy 395.597894 -253.182548) (xy 395.510336 -253.282766)
			(xy 395.416941 -253.377569) (xy 395.318043 -253.466617) (xy 395.213997 -253.549591) (xy 395.105175 -253.626195)
			(xy 394.991966 -253.696153) (xy 394.874776 -253.759215) (xy 394.754025 -253.815156) (xy 394.630144 -253.863776)
			(xy 394.503578 -253.9049) (xy 394.374778 -253.938381) (xy 394.244207 -253.964099) (xy 394.112331 -253.981963)
			(xy 393.979623 -253.991908) (xy 393.846558 -253.993899) (xy 393.713612 -253.987928) (xy 393.581261 -253.974018)
			(xy 393.449979 -253.952217) (xy 393.320236 -253.922604) (xy 393.192495 -253.885285) (xy 393.067216 -253.840393)
			(xy 392.944845 -253.788089) (xy 392.825821 -253.72856) (xy 392.71057 -253.66202) (xy 392.599505 -253.588707)
			(xy 392.493024 -253.508883) (xy 392.391506 -253.422833) (xy 392.295317 -253.330867) (xy 392.204799 -253.233312)
			(xy 392.120278 -253.130519) (xy 392.042056 -253.022855) (xy 391.970412 -252.910705) (xy 391.905603 -252.794472)
			(xy 391.847862 -252.674571) (xy 391.797395 -252.551432) (xy 391.754382 -252.425495) (xy 391.718978 -252.29721)
			(xy 391.691309 -252.167038) (xy 391.671474 -252.035445) (xy 391.659545 -251.9029) (xy 391.655564 -251.76988)
			(xy 328.083672 -251.76988) (xy 328.083174 -251.83642) (xy 328.075216 -251.969262) (xy 328.059327 -252.10139)
			(xy 328.035564 -252.232331) (xy 328.004014 -252.361617) (xy 327.964788 -252.488785) (xy 327.918027 -252.613379)
			(xy 327.863898 -252.734954) (xy 327.802596 -252.853074) (xy 327.734339 -252.967316) (xy 327.659373 -253.077272)
			(xy 327.577964 -253.182548) (xy 327.490406 -253.282766) (xy 327.397011 -253.377569) (xy 327.298113 -253.466617)
			(xy 327.194067 -253.549591) (xy 327.085245 -253.626195) (xy 326.972036 -253.696153) (xy 326.854846 -253.759215)
			(xy 326.734095 -253.815156) (xy 326.610214 -253.863776) (xy 326.483648 -253.9049) (xy 326.354848 -253.938381)
			(xy 326.224277 -253.964099) (xy 326.092401 -253.981963) (xy 325.959693 -253.991908) (xy 325.826628 -253.993899)
			(xy 325.693682 -253.987928) (xy 325.561331 -253.974018) (xy 325.430049 -253.952217) (xy 325.300306 -253.922604)
			(xy 325.172565 -253.885285) (xy 325.047286 -253.840393) (xy 324.924915 -253.788089) (xy 324.805891 -253.72856)
			(xy 324.69064 -253.66202) (xy 324.579575 -253.588707) (xy 324.473094 -253.508883) (xy 324.371576 -253.422833)
			(xy 324.275387 -253.330867) (xy 324.184869 -253.233312) (xy 324.100348 -253.130519) (xy 324.022126 -253.022855)
			(xy 323.950482 -252.910705) (xy 323.885673 -252.794472) (xy 323.827932 -252.674571) (xy 323.777465 -252.551432)
			(xy 323.734452 -252.425495) (xy 323.699048 -252.29721) (xy 323.671379 -252.167038) (xy 323.651544 -252.035445)
			(xy 323.639615 -251.9029) (xy 323.635634 -251.76988) (xy 148.163534 -251.76988) (xy 148.163036 -251.83642)
			(xy 148.155078 -251.969262) (xy 148.139189 -252.10139) (xy 148.115426 -252.232331) (xy 148.083876 -252.361617)
			(xy 148.04465 -252.488785) (xy 147.997889 -252.613379) (xy 147.94376 -252.734954) (xy 147.882458 -252.853074)
			(xy 147.814201 -252.967316) (xy 147.739235 -253.077272) (xy 147.657826 -253.182548) (xy 147.570268 -253.282766)
			(xy 147.476873 -253.377569) (xy 147.377975 -253.466617) (xy 147.273929 -253.549591) (xy 147.165107 -253.626195)
			(xy 147.051898 -253.696153) (xy 146.934708 -253.759215) (xy 146.813957 -253.815156) (xy 146.690076 -253.863776)
			(xy 146.56351 -253.9049) (xy 146.43471 -253.938381) (xy 146.304139 -253.964099) (xy 146.172263 -253.981963)
			(xy 146.039555 -253.991908) (xy 145.90649 -253.993899) (xy 145.773544 -253.987928) (xy 145.641193 -253.974018)
			(xy 145.509911 -253.952217) (xy 145.380168 -253.922604) (xy 145.252427 -253.885285) (xy 145.127148 -253.840393)
			(xy 145.004777 -253.788089) (xy 144.885753 -253.72856) (xy 144.770502 -253.66202) (xy 144.659437 -253.588707)
			(xy 144.552956 -253.508883) (xy 144.451438 -253.422833) (xy 144.355249 -253.330867) (xy 144.264731 -253.233312)
			(xy 144.18021 -253.130519) (xy 144.101988 -253.022855) (xy 144.030344 -252.910705) (xy 143.965535 -252.794472)
			(xy 143.907794 -252.674571) (xy 143.857327 -252.551432) (xy 143.814314 -252.425495) (xy 143.77891 -252.29721)
			(xy 143.751241 -252.167038) (xy 143.731406 -252.035445) (xy 143.719477 -251.9029) (xy 143.715496 -251.76988)
			(xy 80.143604 -251.76988) (xy 80.143106 -251.83642) (xy 80.135148 -251.969262) (xy 80.119259 -252.10139)
			(xy 80.095496 -252.232331) (xy 80.063946 -252.361617) (xy 80.02472 -252.488785) (xy 79.977959 -252.613379)
			(xy 79.92383 -252.734954) (xy 79.862528 -252.853074) (xy 79.794271 -252.967316) (xy 79.719305 -253.077272)
			(xy 79.637896 -253.182548) (xy 79.550338 -253.282766) (xy 79.456943 -253.377569) (xy 79.358045 -253.466617)
			(xy 79.253999 -253.549591) (xy 79.145177 -253.626195) (xy 79.031968 -253.696153) (xy 78.914778 -253.759215)
			(xy 78.794027 -253.815156) (xy 78.670146 -253.863776) (xy 78.54358 -253.9049) (xy 78.41478 -253.938381)
			(xy 78.284209 -253.964099) (xy 78.152333 -253.981963) (xy 78.019625 -253.991908) (xy 77.88656 -253.993899)
			(xy 77.753614 -253.987928) (xy 77.621263 -253.974018) (xy 77.489981 -253.952217) (xy 77.360238 -253.922604)
			(xy 77.232497 -253.885285) (xy 77.107218 -253.840393) (xy 76.984847 -253.788089) (xy 76.865823 -253.72856)
			(xy 76.750572 -253.66202) (xy 76.639507 -253.588707) (xy 76.533026 -253.508883) (xy 76.431508 -253.422833)
			(xy 76.335319 -253.330867) (xy 76.244801 -253.233312) (xy 76.16028 -253.130519) (xy 76.082058 -253.022855)
			(xy 76.010414 -252.910705) (xy 75.945605 -252.794472) (xy 75.887864 -252.674571) (xy 75.837397 -252.551432)
			(xy 75.794384 -252.425495) (xy 75.75898 -252.29721) (xy 75.731311 -252.167038) (xy 75.711476 -252.035445)
			(xy 75.699547 -251.9029) (xy 75.695566 -251.76988) (xy 2.509012 -251.76988) (xy 2.509012 -273.453098)
			(xy 108.601256 -273.453098) (xy 108.601764 -273.427211) (xy 108.609863 -273.376073) (xy 108.625862 -273.326833)
			(xy 108.649368 -273.280701) (xy 108.6798 -273.238814) (xy 108.71641 -273.202204) (xy 108.758297 -273.171772)
			(xy 108.804429 -273.148266) (xy 108.853669 -273.132267) (xy 108.904807 -273.124168) (xy 108.956581 -273.124168)
			(xy 109.007719 -273.132267) (xy 109.056959 -273.148266) (xy 109.103091 -273.171772) (xy 109.144978 -273.202204)
			(xy 109.181588 -273.238814) (xy 109.21202 -273.280701) (xy 109.235526 -273.326833) (xy 109.251525 -273.376073)
			(xy 109.259624 -273.427211) (xy 109.260132 -273.453098) (xy 356.541324 -273.453098) (xy 356.541832 -273.427211)
			(xy 356.549931 -273.376073) (xy 356.56593 -273.326833) (xy 356.589436 -273.280701) (xy 356.619868 -273.238814)
			(xy 356.656478 -273.202204) (xy 356.698365 -273.171772) (xy 356.744497 -273.148266) (xy 356.793737 -273.132267)
			(xy 356.844875 -273.124168) (xy 356.896649 -273.124168) (xy 356.947787 -273.132267) (xy 356.997027 -273.148266)
			(xy 357.043159 -273.171772) (xy 357.085046 -273.202204) (xy 357.121656 -273.238814) (xy 357.152088 -273.280701)
			(xy 357.175594 -273.326833) (xy 357.191593 -273.376073) (xy 357.199692 -273.427211) (xy 357.2002 -273.453098)
			(xy 357.19967 -273.480806) (xy 357.190475 -273.535453) (xy 357.181912 -273.56181) (xy 357.174292 -273.583654)
			(xy 357.37927 -273.938746) (xy 357.40213 -273.943064) (xy 357.426938 -273.948232) (xy 357.474677 -273.965225)
			(xy 357.519254 -273.989322) (xy 357.559619 -274.019956) (xy 357.594821 -274.056405) (xy 357.624032 -274.097811)
			(xy 357.646564 -274.143199) (xy 357.661886 -274.191501) (xy 357.669637 -274.241577) (xy 357.6701 -274.266914)
			(xy 357.669592 -274.292801) (xy 357.661493 -274.343939) (xy 357.645494 -274.393179) (xy 357.621988 -274.439311)
			(xy 357.591556 -274.481198) (xy 357.554946 -274.517808) (xy 357.513059 -274.54824) (xy 357.466927 -274.571746)
			(xy 357.417687 -274.587745) (xy 357.366549 -274.595844) (xy 357.314775 -274.595844) (xy 357.263637 -274.587745)
			(xy 357.214397 -274.571746) (xy 357.168265 -274.54824) (xy 357.126378 -274.517808) (xy 357.089768 -274.481198)
			(xy 357.059336 -274.439311) (xy 357.03583 -274.393179) (xy 357.019831 -274.343939) (xy 357.011732 -274.292801)
			(xy 357.011224 -274.266914) (xy 357.011756 -274.239206) (xy 357.020949 -274.184559) (xy 357.029512 -274.158202)
			(xy 357.037386 -274.136104) (xy 356.832408 -273.781266) (xy 356.809548 -273.776948) (xy 356.784736 -273.771741)
			(xy 356.73696 -273.75479) (xy 356.692344 -273.730722) (xy 356.651938 -273.700106) (xy 356.616698 -273.663665)
			(xy 356.587453 -273.622257) (xy 356.564893 -273.576859) (xy 356.549551 -273.528542) (xy 356.541789 -273.478445)
			(xy 356.541324 -273.453098) (xy 109.260132 -273.453098) (xy 109.259601 -273.480806) (xy 109.250407 -273.535453)
			(xy 109.241844 -273.56181) (xy 109.234224 -273.583654) (xy 109.439202 -273.938746) (xy 109.462062 -273.943064)
			(xy 109.486859 -273.948281) (xy 109.534598 -273.965264) (xy 109.579176 -273.989353) (xy 109.619543 -274.019979)
			(xy 109.654747 -274.056422) (xy 109.683961 -274.097824) (xy 109.706494 -274.143208) (xy 109.721817 -274.191505)
			(xy 109.729569 -274.241579) (xy 109.730032 -274.266914) (xy 351.372424 -274.266914) (xy 351.372932 -274.241027)
			(xy 351.381031 -274.189889) (xy 351.39703 -274.140649) (xy 351.420536 -274.094517) (xy 351.450968 -274.05263)
			(xy 351.487578 -274.01602) (xy 351.529465 -273.985588) (xy 351.575597 -273.962082) (xy 351.624837 -273.946083)
			(xy 351.675975 -273.937984) (xy 351.727749 -273.937984) (xy 351.778887 -273.946083) (xy 351.828127 -273.962082)
			(xy 351.874259 -273.985588) (xy 351.916146 -274.01602) (xy 351.952756 -274.05263) (xy 351.983188 -274.094517)
			(xy 352.006694 -274.140649) (xy 352.022693 -274.189889) (xy 352.030792 -274.241027) (xy 352.0313 -274.266914)
			(xy 352.0313 -274.267422) (xy 352.030713 -274.294938) (xy 352.021525 -274.349199) (xy 352.013012 -274.375372)
			(xy 352.005392 -274.397216) (xy 352.210624 -274.752562) (xy 352.233484 -274.75688) (xy 352.258307 -274.762037)
			(xy 352.306085 -274.778995) (xy 352.350703 -274.80307) (xy 352.391108 -274.833692) (xy 352.426348 -274.87014)
			(xy 352.455591 -274.911554) (xy 352.478148 -274.956958) (xy 352.493487 -275.00528) (xy 352.501245 -275.055381)
			(xy 352.501708 -275.08073) (xy 352.5012 -275.106637) (xy 352.493094 -275.157814) (xy 352.477082 -275.207093)
			(xy 352.453559 -275.25326) (xy 352.423103 -275.295179) (xy 352.386465 -275.331817) (xy 352.344546 -275.362273)
			(xy 352.298379 -275.385796) (xy 352.2491 -275.401808) (xy 352.197923 -275.409914) (xy 352.146109 -275.409914)
			(xy 352.094932 -275.401808) (xy 352.045653 -275.385796) (xy 351.999486 -275.362273) (xy 351.957567 -275.331817)
			(xy 351.920929 -275.295179) (xy 351.890473 -275.25326) (xy 351.86695 -275.207093) (xy 351.850938 -275.157814)
			(xy 351.842832 -275.106637) (xy 351.842324 -275.08073) (xy 351.842924 -275.053013) (xy 351.852243 -274.998366)
			(xy 351.860866 -274.972018) (xy 351.86874 -274.94992) (xy 351.663762 -274.595082) (xy 351.640902 -274.590764)
			(xy 351.616074 -274.585582) (xy 351.568269 -274.568647) (xy 351.523622 -274.544591) (xy 351.483185 -274.513981)
			(xy 351.447913 -274.47754) (xy 351.418638 -274.436127) (xy 351.39605 -274.390718) (xy 351.380683 -274.342387)
			(xy 351.372898 -274.292272) (xy 351.372424 -274.266914) (xy 109.730032 -274.266914) (xy 109.729524 -274.292801)
			(xy 109.721425 -274.343939) (xy 109.705426 -274.393179) (xy 109.68192 -274.439311) (xy 109.651488 -274.481198)
			(xy 109.614878 -274.517808) (xy 109.572991 -274.54824) (xy 109.526859 -274.571746) (xy 109.477619 -274.587745)
			(xy 109.426481 -274.595844) (xy 109.374707 -274.595844) (xy 109.323569 -274.587745) (xy 109.274329 -274.571746)
			(xy 109.228197 -274.54824) (xy 109.18631 -274.517808) (xy 109.1497 -274.481198) (xy 109.119268 -274.439311)
			(xy 109.095762 -274.393179) (xy 109.079763 -274.343939) (xy 109.071664 -274.292801) (xy 109.071156 -274.266914)
			(xy 109.071691 -274.239206) (xy 109.080883 -274.184559) (xy 109.089444 -274.158202) (xy 109.097318 -274.136104)
			(xy 108.89234 -273.781266) (xy 108.86948 -273.776948) (xy 108.844673 -273.771718) (xy 108.796897 -273.754771)
			(xy 108.75228 -273.730708) (xy 108.711874 -273.700095) (xy 108.676632 -273.663656) (xy 108.647386 -273.622251)
			(xy 108.624826 -273.576855) (xy 108.609484 -273.528539) (xy 108.601721 -273.478444) (xy 108.601256 -273.453098)
			(xy 2.509012 -273.453098) (xy 2.509012 -274.266914) (xy 103.432356 -274.266914) (xy 103.432864 -274.241027)
			(xy 103.440963 -274.189889) (xy 103.456962 -274.140649) (xy 103.480468 -274.094517) (xy 103.5109 -274.05263)
			(xy 103.54751 -274.01602) (xy 103.589397 -273.985588) (xy 103.635529 -273.962082) (xy 103.684769 -273.946083)
			(xy 103.735907 -273.937984) (xy 103.787681 -273.937984) (xy 103.838819 -273.946083) (xy 103.888059 -273.962082)
			(xy 103.934191 -273.985588) (xy 103.976078 -274.01602) (xy 104.012688 -274.05263) (xy 104.04312 -274.094517)
			(xy 104.066626 -274.140649) (xy 104.082625 -274.189889) (xy 104.090724 -274.241027) (xy 104.091232 -274.266914)
			(xy 104.091232 -274.267422) (xy 104.090643 -274.294938) (xy 104.081456 -274.349199) (xy 104.072944 -274.375372)
			(xy 104.065324 -274.397216) (xy 104.270556 -274.752562) (xy 104.293416 -274.75688) (xy 104.318228 -274.762086)
			(xy 104.366006 -274.779035) (xy 104.410625 -274.803101) (xy 104.451032 -274.833715) (xy 104.486274 -274.870157)
			(xy 104.515519 -274.911566) (xy 104.538078 -274.956966) (xy 104.553418 -275.005285) (xy 104.561177 -275.055382)
			(xy 104.56164 -275.08073) (xy 104.561132 -275.106637) (xy 104.553026 -275.157814) (xy 104.537014 -275.207093)
			(xy 104.513491 -275.25326) (xy 104.483035 -275.295179) (xy 104.446397 -275.331817) (xy 104.404478 -275.362273)
			(xy 104.358311 -275.385796) (xy 104.309032 -275.401808) (xy 104.257855 -275.409914) (xy 104.206041 -275.409914)
			(xy 104.154864 -275.401808) (xy 104.105585 -275.385796) (xy 104.059418 -275.362273) (xy 104.017499 -275.331817)
			(xy 103.980861 -275.295179) (xy 103.950405 -275.25326) (xy 103.926882 -275.207093) (xy 103.91087 -275.157814)
			(xy 103.902764 -275.106637) (xy 103.902256 -275.08073) (xy 103.902854 -275.053013) (xy 103.912174 -274.998366)
			(xy 103.920798 -274.972018) (xy 103.928672 -274.94992) (xy 103.723694 -274.595082) (xy 103.700834 -274.590764)
			(xy 103.676011 -274.585559) (xy 103.628206 -274.568629) (xy 103.583558 -274.544577) (xy 103.543121 -274.51397)
			(xy 103.507847 -274.477532) (xy 103.478571 -274.436121) (xy 103.455983 -274.390715) (xy 103.440615 -274.342385)
			(xy 103.43283 -274.292271) (xy 103.432356 -274.266914) (xy 2.509012 -274.266914) (xy 2.509012 -275.10659)
			(xy 102.023373 -275.10659) (xy 102.023373 -275.05481) (xy 102.031474 -275.003669) (xy 102.047476 -274.954425)
			(xy 102.070985 -274.90829) (xy 102.101423 -274.866402) (xy 102.138039 -274.829791) (xy 102.179931 -274.79936)
			(xy 102.226069 -274.775858) (xy 102.275316 -274.759863) (xy 102.326458 -274.75177) (xy 102.352348 -274.751292)
			(xy 102.377861 -274.751741) (xy 102.428277 -274.759608) (xy 102.476879 -274.775148) (xy 102.522507 -274.79799)
			(xy 102.564072 -274.827588) (xy 102.600581 -274.863235) (xy 102.616254 -274.883372) (xy 103.028242 -274.883372)
			(xy 103.043883 -274.86321) (xy 103.0804 -274.827569) (xy 103.121973 -274.797979) (xy 103.167607 -274.775148)
			(xy 103.216215 -274.75962) (xy 103.266634 -274.751765) (xy 103.292148 -274.751292) (xy 103.318035 -274.751743)
			(xy 103.369171 -274.759849) (xy 103.41841 -274.775854) (xy 103.464539 -274.799364) (xy 103.506423 -274.8298)
			(xy 103.543031 -274.866413) (xy 103.573461 -274.908302) (xy 103.596964 -274.954434) (xy 103.612962 -275.003675)
			(xy 103.62106 -275.054813) (xy 103.62106 -275.106587) (xy 103.612962 -275.157725) (xy 103.596964 -275.206966)
			(xy 103.573461 -275.253098) (xy 103.543031 -275.294987) (xy 103.506423 -275.3316) (xy 103.464539 -275.362036)
			(xy 103.41841 -275.385546) (xy 103.369171 -275.401551) (xy 103.318035 -275.409657) (xy 103.292148 -275.410168)
			(xy 103.266637 -275.409665) (xy 103.216223 -275.401811) (xy 103.167621 -275.386283) (xy 103.121992 -275.363452)
			(xy 103.080426 -275.333862) (xy 103.043916 -275.298222) (xy 103.028242 -275.278088) (xy 102.616254 -275.278088)
			(xy 102.600546 -275.298195) (xy 102.564044 -275.333841) (xy 102.522486 -275.363438) (xy 102.476864 -275.386279)
			(xy 102.428268 -275.401819) (xy 102.377858 -275.409687) (xy 102.352348 -275.410168) (xy 102.326458 -275.40963)
			(xy 102.275316 -275.401537) (xy 102.226069 -275.385542) (xy 102.179931 -275.36204) (xy 102.138039 -275.331609)
			(xy 102.101423 -275.294998) (xy 102.070985 -275.25311) (xy 102.047476 -275.206975) (xy 102.031474 -275.157731)
			(xy 102.023373 -275.10659) (xy 2.509012 -275.10659) (xy 2.509012 -276.708616) (xy 102.022656 -276.708616)
			(xy 102.023189 -276.683284) (xy 102.030938 -276.633215) (xy 102.046256 -276.584922) (xy 102.068781 -276.53954)
			(xy 102.097985 -276.498139) (xy 102.133179 -276.461694) (xy 102.173534 -276.431062) (xy 102.218101 -276.406964)
			(xy 102.265829 -276.389968) (xy 102.290626 -276.384766) (xy 102.313486 -276.380448) (xy 102.518464 -276.025356)
			(xy 102.510844 -276.003512) (xy 102.502285 -275.977153) (xy 102.493085 -275.922508) (xy 102.492556 -275.8948)
			(xy 102.493064 -275.868913) (xy 102.501163 -275.817775) (xy 102.517162 -275.768535) (xy 102.540668 -275.722403)
			(xy 102.5711 -275.680516) (xy 102.60771 -275.643906) (xy 102.649597 -275.613474) (xy 102.695729 -275.589968)
			(xy 102.744969 -275.573969) (xy 102.796107 -275.56587) (xy 102.847881 -275.56587) (xy 102.899019 -275.573969)
			(xy 102.948259 -275.589968) (xy 102.994391 -275.613474) (xy 103.036278 -275.643906) (xy 103.072888 -275.680516)
			(xy 103.10332 -275.722403) (xy 103.126826 -275.768535) (xy 103.142825 -275.817775) (xy 103.150924 -275.868913)
			(xy 103.151432 -275.8948) (xy 104.372156 -275.8948) (xy 104.372675 -275.869467) (xy 104.380426 -275.819398)
			(xy 104.395746 -275.771105) (xy 104.418273 -275.725723) (xy 104.447479 -275.684322) (xy 104.482674 -275.647877)
			(xy 104.523031 -275.617245) (xy 104.567599 -275.593147) (xy 104.615329 -275.576152) (xy 104.640126 -275.57095)
			(xy 104.662986 -275.566632) (xy 104.868218 -275.211286) (xy 104.860598 -275.189188) (xy 104.851972 -275.162906)
			(xy 104.842659 -275.108385) (xy 104.842056 -275.08073) (xy 104.842564 -275.054823) (xy 104.85067 -275.003646)
			(xy 104.866682 -274.954367) (xy 104.890205 -274.9082) (xy 104.920661 -274.866281) (xy 104.957299 -274.829643)
			(xy 104.999218 -274.799187) (xy 105.045385 -274.775664) (xy 105.094664 -274.759652) (xy 105.145841 -274.751546)
			(xy 105.197655 -274.751546) (xy 105.248832 -274.759652) (xy 105.298111 -274.775664) (xy 105.344278 -274.799187)
			(xy 105.386197 -274.829643) (xy 105.422835 -274.866281) (xy 105.453291 -274.9082) (xy 105.476814 -274.954367)
			(xy 105.492826 -275.003646) (xy 105.500932 -275.054823) (xy 105.50144 -275.08073) (xy 107.661456 -275.08073)
			(xy 107.661964 -275.054823) (xy 107.67007 -275.003646) (xy 107.686082 -274.954367) (xy 107.709605 -274.9082)
			(xy 107.740061 -274.866281) (xy 107.776699 -274.829643) (xy 107.818618 -274.799187) (xy 107.864785 -274.775664)
			(xy 107.914064 -274.759652) (xy 107.965241 -274.751546) (xy 108.017055 -274.751546) (xy 108.068232 -274.759652)
			(xy 108.117511 -274.775664) (xy 108.163678 -274.799187) (xy 108.205597 -274.829643) (xy 108.242235 -274.866281)
			(xy 108.272691 -274.9082) (xy 108.296214 -274.954367) (xy 108.312226 -275.003646) (xy 108.320332 -275.054823)
			(xy 108.32084 -275.08073) (xy 108.320273 -275.106588) (xy 349.963473 -275.106588) (xy 349.963473 -275.054812)
			(xy 349.971573 -275.003674) (xy 349.987573 -274.954432) (xy 350.011079 -274.9083) (xy 350.041513 -274.866413)
			(xy 350.078125 -274.829803) (xy 350.120014 -274.799371) (xy 350.166147 -274.775867) (xy 350.215389 -274.759869)
			(xy 350.266528 -274.751772) (xy 350.292416 -274.751292) (xy 350.317928 -274.751764) (xy 350.368343 -274.759627)
			(xy 350.416945 -274.775162) (xy 350.462573 -274.797999) (xy 350.504138 -274.827593) (xy 350.540648 -274.863237)
			(xy 350.556322 -274.883372) (xy 350.96831 -274.883372) (xy 350.98397 -274.863226) (xy 351.020483 -274.827584)
			(xy 351.062052 -274.797992) (xy 351.107683 -274.775158) (xy 351.156287 -274.759626) (xy 351.206703 -274.751768)
			(xy 351.232216 -274.751292) (xy 351.258105 -274.751741) (xy 351.309245 -274.759843) (xy 351.358488 -274.775845)
			(xy 351.404622 -274.799353) (xy 351.44651 -274.829789) (xy 351.483122 -274.866402) (xy 351.513555 -274.908292)
			(xy 351.537061 -274.954427) (xy 351.553061 -275.003671) (xy 351.56116 -275.054811) (xy 351.56116 -275.106589)
			(xy 351.553061 -275.157729) (xy 351.537061 -275.206973) (xy 351.513555 -275.253108) (xy 351.483122 -275.294998)
			(xy 351.44651 -275.331611) (xy 351.404622 -275.362047) (xy 351.358488 -275.385555) (xy 351.309245 -275.401557)
			(xy 351.258105 -275.409659) (xy 351.232216 -275.410168) (xy 351.206704 -275.409689) (xy 351.156289 -275.401829)
			(xy 351.107687 -275.386297) (xy 351.062058 -275.363461) (xy 351.020493 -275.333868) (xy 350.983983 -275.298224)
			(xy 350.96831 -275.278088) (xy 350.556322 -275.278088) (xy 350.540633 -275.29821) (xy 350.504126 -275.333856)
			(xy 350.462565 -275.363451) (xy 350.416939 -275.386289) (xy 350.36834 -275.401826) (xy 350.317927 -275.409689)
			(xy 350.292416 -275.410168) (xy 350.266528 -275.409628) (xy 350.215389 -275.401531) (xy 350.166147 -275.385533)
			(xy 350.120014 -275.362029) (xy 350.078125 -275.331597) (xy 350.041513 -275.294987) (xy 350.011079 -275.2531)
			(xy 349.987573 -275.206968) (xy 349.971573 -275.157726) (xy 349.963473 -275.106588) (xy 108.320273 -275.106588)
			(xy 108.320232 -275.108447) (xy 108.310918 -275.163093) (xy 108.302298 -275.189442) (xy 108.294424 -275.21154)
			(xy 108.499656 -275.566632) (xy 108.522516 -275.57095) (xy 108.547321 -275.576185) (xy 108.595097 -275.593131)
			(xy 108.639715 -275.617194) (xy 108.680121 -275.647805) (xy 108.715363 -275.684244) (xy 108.744609 -275.725649)
			(xy 108.767169 -275.771044) (xy 108.782512 -275.819359) (xy 108.790275 -275.869454) (xy 108.79074 -275.8948)
			(xy 108.790232 -275.920707) (xy 108.782126 -275.971884) (xy 108.766114 -276.021163) (xy 108.742591 -276.06733)
			(xy 108.712135 -276.109249) (xy 108.675497 -276.145887) (xy 108.633578 -276.176343) (xy 108.587411 -276.199866)
			(xy 108.538132 -276.215878) (xy 108.486955 -276.223984) (xy 108.435141 -276.223984) (xy 108.383964 -276.215878)
			(xy 108.334685 -276.199866) (xy 108.288518 -276.176343) (xy 108.246599 -276.145887) (xy 108.209961 -276.109249)
			(xy 108.179505 -276.06733) (xy 108.155982 -276.021163) (xy 108.13997 -275.971884) (xy 108.131864 -275.920707)
			(xy 108.131356 -275.8948) (xy 108.131947 -275.867082) (xy 108.141272 -275.812436) (xy 108.149898 -275.786088)
			(xy 108.157772 -275.76399) (xy 107.95254 -275.408898) (xy 107.92968 -275.40458) (xy 107.904858 -275.399414)
			(xy 107.857077 -275.382462) (xy 107.812456 -275.358392) (xy 107.772048 -275.327773) (xy 107.736806 -275.291325)
			(xy 107.707562 -275.249911) (xy 107.685006 -275.204506) (xy 107.66967 -275.156182) (xy 107.661916 -275.10608)
			(xy 107.661456 -275.08073) (xy 105.50144 -275.08073) (xy 105.500998 -275.106094) (xy 105.493245 -275.156227)
			(xy 105.477898 -275.204578) (xy 105.455318 -275.250004) (xy 105.42604 -275.291431) (xy 105.390756 -275.327878)
			(xy 105.350301 -275.358484) (xy 105.305631 -275.382526) (xy 105.257803 -275.399433) (xy 105.232962 -275.40458)
			(xy 105.209848 -275.408898) (xy 105.00487 -275.76399) (xy 105.012744 -275.786088) (xy 105.021303 -275.812447)
			(xy 105.030503 -275.867092) (xy 105.031032 -275.8948) (xy 105.030524 -275.920687) (xy 105.030521 -275.920707)
			(xy 106.252016 -275.920707) (xy 106.252016 -275.868893) (xy 106.260122 -275.817717) (xy 106.276133 -275.768439)
			(xy 106.299656 -275.722272) (xy 106.330111 -275.680353) (xy 106.366749 -275.643715) (xy 106.408667 -275.613259)
			(xy 106.454833 -275.589735) (xy 106.504111 -275.573723) (xy 106.555287 -275.565617) (xy 106.581194 -275.565108)
			(xy 106.606706 -275.56559) (xy 106.65712 -275.57345) (xy 106.705722 -275.588983) (xy 106.75135 -275.611818)
			(xy 106.792916 -275.64141) (xy 106.829426 -275.677053) (xy 106.8451 -275.697188) (xy 107.257088 -275.697188)
			(xy 107.272765 -275.677056) (xy 107.309275 -275.641412) (xy 107.350839 -275.611819) (xy 107.396467 -275.588982)
			(xy 107.445068 -275.573448) (xy 107.495482 -275.565586) (xy 107.520994 -275.565108) (xy 107.546904 -275.565589)
			(xy 107.598085 -275.573695) (xy 107.647369 -275.589707) (xy 107.693541 -275.613232) (xy 107.735464 -275.64369)
			(xy 107.772106 -275.680332) (xy 107.802565 -275.722254) (xy 107.826091 -275.768426) (xy 107.842104 -275.817709)
			(xy 107.85021 -275.86889) (xy 107.85021 -275.92071) (xy 107.842104 -275.971891) (xy 107.826091 -276.021174)
			(xy 107.802565 -276.067346) (xy 107.772106 -276.109268) (xy 107.735464 -276.14591) (xy 107.693541 -276.176368)
			(xy 107.647369 -276.199893) (xy 107.598085 -276.215905) (xy 107.546904 -276.224011) (xy 107.520994 -276.224492)
			(xy 107.495482 -276.224019) (xy 107.445067 -276.216157) (xy 107.396465 -276.200622) (xy 107.350837 -276.177785)
			(xy 107.309271 -276.148192) (xy 107.272762 -276.112547) (xy 107.257088 -276.092412) (xy 106.8451 -276.092412)
			(xy 106.82943 -276.11255) (xy 106.792919 -276.148193) (xy 106.751353 -276.177786) (xy 106.705724 -276.200622)
			(xy 106.657121 -276.216155) (xy 106.606706 -276.224015) (xy 106.581194 -276.224492) (xy 106.555287 -276.223983)
			(xy 106.504111 -276.215877) (xy 106.454833 -276.199865) (xy 106.408667 -276.176341) (xy 106.366749 -276.145885)
			(xy 106.330111 -276.109247) (xy 106.299656 -276.067328) (xy 106.276133 -276.021161) (xy 106.260122 -275.971883)
			(xy 106.252016 -275.920707) (xy 105.030521 -275.920707) (xy 105.022425 -275.971825) (xy 105.006426 -276.021065)
			(xy 104.98292 -276.067197) (xy 104.952488 -276.109084) (xy 104.915878 -276.145694) (xy 104.873991 -276.176126)
			(xy 104.827859 -276.199632) (xy 104.778619 -276.215631) (xy 104.727481 -276.22373) (xy 104.675707 -276.22373)
			(xy 104.624569 -276.215631) (xy 104.575329 -276.199632) (xy 104.529197 -276.176126) (xy 104.48731 -276.145694)
			(xy 104.4507 -276.109084) (xy 104.420268 -276.067197) (xy 104.396762 -276.021065) (xy 104.380763 -275.971825)
			(xy 104.372664 -275.920687) (xy 104.372156 -275.8948) (xy 103.151432 -275.8948) (xy 103.150966 -275.920146)
			(xy 103.143192 -275.97024) (xy 103.127843 -276.018553) (xy 103.105281 -276.063948) (xy 103.076038 -276.105356)
			(xy 103.040801 -276.1418) (xy 103.000402 -276.172421) (xy 102.955792 -276.196499) (xy 102.908023 -276.213466)
			(xy 102.883208 -276.21865) (xy 102.860348 -276.222968) (xy 102.65537 -276.577806) (xy 102.663244 -276.599904)
			(xy 102.671807 -276.626262) (xy 102.681004 -276.680908) (xy 102.681532 -276.708616) (xy 102.962456 -276.708616)
			(xy 102.962964 -276.682709) (xy 102.97107 -276.631532) (xy 102.987082 -276.582253) (xy 103.010605 -276.536086)
			(xy 103.041061 -276.494167) (xy 103.077699 -276.457529) (xy 103.119618 -276.427073) (xy 103.165785 -276.40355)
			(xy 103.215064 -276.387538) (xy 103.266241 -276.379432) (xy 103.318055 -276.379432) (xy 103.369232 -276.387538)
			(xy 103.418511 -276.40355) (xy 103.464678 -276.427073) (xy 103.506597 -276.457529) (xy 103.543235 -276.494167)
			(xy 103.573691 -276.536086) (xy 103.597214 -276.582253) (xy 103.613226 -276.631532) (xy 103.621332 -276.682709)
			(xy 103.62184 -276.708616) (xy 103.621308 -276.734511) (xy 103.902706 -276.734511) (xy 103.902706 -276.682689)
			(xy 103.910813 -276.631506) (xy 103.926828 -276.582222) (xy 103.950356 -276.53605) (xy 103.980818 -276.494128)
			(xy 104.017464 -276.457487) (xy 104.059391 -276.427031) (xy 104.105566 -276.40351) (xy 104.154853 -276.387502)
			(xy 104.206037 -276.379402) (xy 104.231948 -276.378924) (xy 104.257462 -276.37936) (xy 104.307879 -276.387228)
			(xy 104.356482 -276.40277) (xy 104.40211 -276.425614) (xy 104.443674 -276.455215) (xy 104.480182 -276.490865)
			(xy 104.495854 -276.511004) (xy 104.907842 -276.511004) (xy 104.923492 -276.490849) (xy 104.960006 -276.455206)
			(xy 105.001577 -276.425615) (xy 105.04721 -276.402782) (xy 105.095816 -276.387253) (xy 105.146235 -276.379398)
			(xy 105.171748 -276.378924) (xy 105.197654 -276.379404) (xy 105.248828 -276.387515) (xy 105.298102 -276.403532)
			(xy 105.344265 -276.427059) (xy 105.38618 -276.457517) (xy 105.422814 -276.494157) (xy 105.453266 -276.536076)
			(xy 105.476786 -276.582242) (xy 105.492796 -276.631519) (xy 105.5009 -276.682694) (xy 105.5009 -276.734506)
			(xy 105.492796 -276.785681) (xy 105.476786 -276.834958) (xy 105.453266 -276.881124) (xy 105.422814 -276.923043)
			(xy 105.38618 -276.959683) (xy 105.344265 -276.990141) (xy 105.298102 -277.013668) (xy 105.248828 -277.029685)
			(xy 105.197654 -277.037796) (xy 105.171748 -277.038308) (xy 105.146238 -277.037789) (xy 105.095825 -277.029936)
			(xy 105.047224 -277.01441) (xy 105.001596 -276.991582) (xy 104.960029 -276.961996) (xy 104.923517 -276.92636)
			(xy 104.907842 -276.906228) (xy 104.495854 -276.906228) (xy 104.480157 -276.926344) (xy 104.443651 -276.961988)
			(xy 104.40209 -276.991583) (xy 104.356467 -277.014422) (xy 104.307869 -277.029961) (xy 104.257458 -277.037827)
			(xy 104.231948 -277.038308) (xy 104.206037 -277.037798) (xy 104.154853 -277.029698) (xy 104.105566 -277.01369)
			(xy 104.059391 -276.990169) (xy 104.017464 -276.959713) (xy 103.980818 -276.923072) (xy 103.950356 -276.88115)
			(xy 103.926828 -276.834978) (xy 103.910813 -276.785694) (xy 103.902706 -276.734511) (xy 103.621308 -276.734511)
			(xy 103.621269 -276.736398) (xy 103.611945 -276.791174) (xy 103.603298 -276.817582) (xy 103.595424 -276.839426)
			(xy 103.800402 -277.194264) (xy 103.823262 -277.198582) (xy 103.848063 -277.203782) (xy 103.895803 -277.220766)
			(xy 103.940382 -277.244857) (xy 103.98075 -277.275485) (xy 104.015954 -277.311931) (xy 104.045167 -277.353334)
			(xy 104.067699 -277.398721) (xy 104.083021 -277.44702) (xy 104.09077 -277.497096) (xy 104.091232 -277.522432)
			(xy 106.251756 -277.522432) (xy 106.252213 -277.497097) (xy 106.259974 -277.447026) (xy 106.275303 -277.39873)
			(xy 106.297839 -277.353349) (xy 106.327053 -277.311948) (xy 106.362255 -277.275504) (xy 106.402618 -277.244873)
			(xy 106.447192 -277.220777) (xy 106.494926 -277.203783) (xy 106.519726 -277.198582) (xy 106.542586 -277.194264)
			(xy 106.747818 -276.838918) (xy 106.740198 -276.817074) (xy 106.731593 -276.790786) (xy 106.722266 -276.736269)
			(xy 106.721656 -276.708616) (xy 106.722164 -276.682709) (xy 106.73027 -276.631532) (xy 106.746282 -276.582253)
			(xy 106.769805 -276.536086) (xy 106.800261 -276.494167) (xy 106.836899 -276.457529) (xy 106.878818 -276.427073)
			(xy 106.924985 -276.40355) (xy 106.974264 -276.387538) (xy 107.025441 -276.379432) (xy 107.077255 -276.379432)
			(xy 107.128432 -276.387538) (xy 107.177711 -276.40355) (xy 107.223878 -276.427073) (xy 107.265797 -276.457529)
			(xy 107.302435 -276.494167) (xy 107.332891 -276.536086) (xy 107.356414 -276.582253) (xy 107.372426 -276.631532)
			(xy 107.380532 -276.682709) (xy 107.38104 -276.708616) (xy 108.601256 -276.708616) (xy 108.601789 -276.683284)
			(xy 108.609538 -276.633215) (xy 108.624856 -276.584922) (xy 108.647381 -276.53954) (xy 108.676585 -276.498139)
			(xy 108.711779 -276.461694) (xy 108.752134 -276.431062) (xy 108.796701 -276.406964) (xy 108.844429 -276.389968)
			(xy 108.869226 -276.384766) (xy 108.892086 -276.380448) (xy 109.097064 -276.02561) (xy 109.08919 -276.003766)
			(xy 109.080545 -275.977358) (xy 109.071224 -275.922582) (xy 109.070648 -275.8948) (xy 109.071156 -275.868893)
			(xy 109.079262 -275.817716) (xy 109.095274 -275.768437) (xy 109.118797 -275.72227) (xy 109.149253 -275.680351)
			(xy 109.185891 -275.643713) (xy 109.22781 -275.613257) (xy 109.273977 -275.589734) (xy 109.323256 -275.573722)
			(xy 109.374433 -275.565616) (xy 109.426247 -275.565616) (xy 109.477424 -275.573722) (xy 109.526703 -275.589734)
			(xy 109.57287 -275.613257) (xy 109.614789 -275.643713) (xy 109.651427 -275.680351) (xy 109.681883 -275.72227)
			(xy 109.705406 -275.768437) (xy 109.721418 -275.817716) (xy 109.729524 -275.868893) (xy 109.730032 -275.8948)
			(xy 109.729566 -275.920146) (xy 109.721792 -275.97024) (xy 109.706443 -276.018553) (xy 109.683881 -276.063948)
			(xy 109.654638 -276.105356) (xy 109.619401 -276.1418) (xy 109.579002 -276.172421) (xy 109.534392 -276.196499)
			(xy 109.486623 -276.213466) (xy 109.461808 -276.21865) (xy 109.438948 -276.222968) (xy 109.23397 -276.577806)
			(xy 109.241844 -276.599904) (xy 109.250407 -276.626262) (xy 109.259604 -276.680908) (xy 109.260132 -276.708616)
			(xy 349.962724 -276.708616) (xy 349.963202 -276.683281) (xy 349.970953 -276.633207) (xy 349.986274 -276.584909)
			(xy 350.008806 -276.539525) (xy 350.038016 -276.498122) (xy 350.073218 -276.461676) (xy 350.113581 -276.431046)
			(xy 350.158157 -276.406953) (xy 350.205894 -276.389964) (xy 350.230694 -276.384766) (xy 350.253554 -276.380448)
			(xy 350.458532 -276.025356) (xy 350.450912 -276.003512) (xy 350.442352 -275.977154) (xy 350.433153 -275.922508)
			(xy 350.432624 -275.8948) (xy 350.433132 -275.868913) (xy 350.441231 -275.817775) (xy 350.45723 -275.768535)
			(xy 350.480736 -275.722403) (xy 350.511168 -275.680516) (xy 350.547778 -275.643906) (xy 350.589665 -275.613474)
			(xy 350.635797 -275.589968) (xy 350.685037 -275.573969) (xy 350.736175 -275.56587) (xy 350.787949 -275.56587)
			(xy 350.839087 -275.573969) (xy 350.888327 -275.589968) (xy 350.934459 -275.613474) (xy 350.976346 -275.643906)
			(xy 351.012956 -275.680516) (xy 351.043388 -275.722403) (xy 351.066894 -275.768535) (xy 351.082893 -275.817775)
			(xy 351.090992 -275.868913) (xy 351.0915 -275.8948) (xy 352.312224 -275.8948) (xy 352.312688 -275.869465)
			(xy 352.320441 -275.81939) (xy 352.335764 -275.771092) (xy 352.358298 -275.725707) (xy 352.38751 -275.684304)
			(xy 352.422713 -275.647859) (xy 352.463078 -275.617229) (xy 352.507655 -275.593136) (xy 352.555393 -275.576148)
			(xy 352.580194 -275.57095) (xy 352.603054 -275.566632) (xy 352.808286 -275.211286) (xy 352.800666 -275.189188)
			(xy 352.792042 -275.162906) (xy 352.782727 -275.108385) (xy 352.782124 -275.08073) (xy 352.782632 -275.054823)
			(xy 352.790738 -275.003646) (xy 352.80675 -274.954367) (xy 352.830273 -274.9082) (xy 352.860729 -274.866281)
			(xy 352.897367 -274.829643) (xy 352.939286 -274.799187) (xy 352.985453 -274.775664) (xy 353.034732 -274.759652)
			(xy 353.085909 -274.751546) (xy 353.137723 -274.751546) (xy 353.1889 -274.759652) (xy 353.238179 -274.775664)
			(xy 353.284346 -274.799187) (xy 353.326265 -274.829643) (xy 353.362903 -274.866281) (xy 353.393359 -274.9082)
			(xy 353.416882 -274.954367) (xy 353.432894 -275.003646) (xy 353.441 -275.054823) (xy 353.441508 -275.08073)
			(xy 355.601524 -275.08073) (xy 355.602032 -275.054823) (xy 355.610138 -275.003646) (xy 355.62615 -274.954367)
			(xy 355.649673 -274.9082) (xy 355.680129 -274.866281) (xy 355.716767 -274.829643) (xy 355.758686 -274.799187)
			(xy 355.804853 -274.775664) (xy 355.854132 -274.759652) (xy 355.905309 -274.751546) (xy 355.957123 -274.751546)
			(xy 356.0083 -274.759652) (xy 356.057579 -274.775664) (xy 356.103746 -274.799187) (xy 356.145665 -274.829643)
			(xy 356.182303 -274.866281) (xy 356.212759 -274.9082) (xy 356.236282 -274.954367) (xy 356.252294 -275.003646)
			(xy 356.2604 -275.054823) (xy 356.260908 -275.08073) (xy 356.260296 -275.108446) (xy 356.250985 -275.163093)
			(xy 356.242366 -275.189442) (xy 356.234492 -275.21154) (xy 356.439724 -275.566632) (xy 356.462584 -275.57095)
			(xy 356.4874 -275.576135) (xy 356.535176 -275.593092) (xy 356.579792 -275.617163) (xy 356.620197 -275.647782)
			(xy 356.655436 -275.684226) (xy 356.684681 -275.725636) (xy 356.707239 -275.771036) (xy 356.722581 -275.819355)
			(xy 356.730343 -275.869452) (xy 356.730808 -275.8948) (xy 356.7303 -275.920707) (xy 356.722194 -275.971884)
			(xy 356.706182 -276.021163) (xy 356.682659 -276.06733) (xy 356.652203 -276.109249) (xy 356.615565 -276.145887)
			(xy 356.573646 -276.176343) (xy 356.527479 -276.199866) (xy 356.4782 -276.215878) (xy 356.427023 -276.223984)
			(xy 356.375209 -276.223984) (xy 356.324032 -276.215878) (xy 356.274753 -276.199866) (xy 356.228586 -276.176343)
			(xy 356.186667 -276.145887) (xy 356.150029 -276.109249) (xy 356.119573 -276.06733) (xy 356.09605 -276.021163)
			(xy 356.080038 -275.971884) (xy 356.071932 -275.920707) (xy 356.071424 -275.8948) (xy 356.072017 -275.867083)
			(xy 356.081341 -275.812436) (xy 356.089966 -275.786088) (xy 356.09784 -275.76399) (xy 355.892608 -275.408898)
			(xy 355.869748 -275.40458) (xy 355.844921 -275.399437) (xy 355.79714 -275.382481) (xy 355.75252 -275.358407)
			(xy 355.712113 -275.327784) (xy 355.676872 -275.291334) (xy 355.647629 -275.249917) (xy 355.625073 -275.20451)
			(xy 355.609738 -275.156184) (xy 355.601984 -275.10608) (xy 355.601524 -275.08073) (xy 353.441508 -275.08073)
			(xy 353.441092 -275.106096) (xy 353.433338 -275.156231) (xy 353.417989 -275.204584) (xy 353.395406 -275.250011)
			(xy 353.366125 -275.291439) (xy 353.330837 -275.327886) (xy 353.290378 -275.358492) (xy 353.245704 -275.382531)
			(xy 353.197873 -275.399435) (xy 353.17303 -275.40458) (xy 353.149916 -275.408898) (xy 352.944938 -275.76399)
			(xy 352.952812 -275.786088) (xy 352.96137 -275.812447) (xy 352.97057 -275.867092) (xy 352.9711 -275.8948)
			(xy 352.970592 -275.920687) (xy 352.970589 -275.920705) (xy 354.192116 -275.920705) (xy 354.192116 -275.868895)
			(xy 354.200221 -275.817722) (xy 354.21623 -275.768446) (xy 354.23975 -275.722282) (xy 354.270202 -275.680364)
			(xy 354.306835 -275.643726) (xy 354.348749 -275.61327) (xy 354.394911 -275.589745) (xy 354.444185 -275.57373)
			(xy 354.495357 -275.565619) (xy 354.521262 -275.565108) (xy 354.546773 -275.565613) (xy 354.597186 -275.573468)
			(xy 354.645788 -275.588996) (xy 354.691416 -275.611827) (xy 354.732982 -275.641416) (xy 354.769494 -275.677055)
			(xy 354.785168 -275.697188) (xy 355.197156 -275.697188) (xy 355.212852 -275.677071) (xy 355.249357 -275.641427)
			(xy 355.290918 -275.611831) (xy 355.336542 -275.588992) (xy 355.38514 -275.573454) (xy 355.435551 -275.565588)
			(xy 355.461062 -275.565108) (xy 355.486973 -275.565587) (xy 355.538159 -275.573688) (xy 355.587447 -275.589698)
			(xy 355.633623 -275.613221) (xy 355.67555 -275.643679) (xy 355.712197 -275.680321) (xy 355.742659 -275.722245)
			(xy 355.766188 -275.768418) (xy 355.782203 -275.817704) (xy 355.79031 -275.868889) (xy 355.79031 -275.920711)
			(xy 355.782203 -275.971896) (xy 355.766188 -276.021182) (xy 355.742659 -276.067355) (xy 355.712197 -276.109279)
			(xy 355.67555 -276.145921) (xy 355.633623 -276.176379) (xy 355.587447 -276.199902) (xy 355.538159 -276.215912)
			(xy 355.486973 -276.224013) (xy 355.461062 -276.224492) (xy 355.435549 -276.224043) (xy 355.385133 -276.216176)
			(xy 355.336531 -276.200636) (xy 355.290902 -276.177795) (xy 355.249337 -276.148197) (xy 355.212829 -276.112549)
			(xy 355.197156 -276.092412) (xy 354.785168 -276.092412) (xy 354.769516 -276.112565) (xy 354.733002 -276.148208)
			(xy 354.691432 -276.177799) (xy 354.645799 -276.200632) (xy 354.597193 -276.216162) (xy 354.546775 -276.224017)
			(xy 354.521262 -276.224492) (xy 354.495357 -276.223981) (xy 354.444185 -276.21587) (xy 354.394911 -276.199855)
			(xy 354.348749 -276.17633) (xy 354.306835 -276.145874) (xy 354.270202 -276.109236) (xy 354.23975 -276.067318)
			(xy 354.21623 -276.021154) (xy 354.200221 -275.971878) (xy 354.192116 -275.920705) (xy 352.970589 -275.920705)
			(xy 352.962493 -275.971825) (xy 352.946494 -276.021065) (xy 352.922988 -276.067197) (xy 352.892556 -276.109084)
			(xy 352.855946 -276.145694) (xy 352.814059 -276.176126) (xy 352.767927 -276.199632) (xy 352.718687 -276.215631)
			(xy 352.667549 -276.22373) (xy 352.615775 -276.22373) (xy 352.564637 -276.215631) (xy 352.515397 -276.199632)
			(xy 352.469265 -276.176126) (xy 352.427378 -276.145694) (xy 352.390768 -276.109084) (xy 352.360336 -276.067197)
			(xy 352.33683 -276.021065) (xy 352.320831 -275.971825) (xy 352.312732 -275.920687) (xy 352.312224 -275.8948)
			(xy 351.0915 -275.8948) (xy 351.090979 -275.920144) (xy 351.083207 -275.970232) (xy 351.067862 -276.018541)
			(xy 351.045306 -276.063932) (xy 351.016069 -276.105338) (xy 350.98084 -276.141782) (xy 350.940449 -276.172406)
			(xy 350.895848 -276.196488) (xy 350.848087 -276.213462) (xy 350.823276 -276.21865) (xy 350.800416 -276.222968)
			(xy 350.595438 -276.577806) (xy 350.603312 -276.599904) (xy 350.611874 -276.626262) (xy 350.621072 -276.680908)
			(xy 350.6216 -276.708616) (xy 350.902524 -276.708616) (xy 350.903032 -276.682709) (xy 350.911138 -276.631532)
			(xy 350.92715 -276.582253) (xy 350.950673 -276.536086) (xy 350.981129 -276.494167) (xy 351.017767 -276.457529)
			(xy 351.059686 -276.427073) (xy 351.105853 -276.40355) (xy 351.155132 -276.387538) (xy 351.206309 -276.379432)
			(xy 351.258123 -276.379432) (xy 351.3093 -276.387538) (xy 351.358579 -276.40355) (xy 351.404746 -276.427073)
			(xy 351.446665 -276.457529) (xy 351.483303 -276.494167) (xy 351.513759 -276.536086) (xy 351.537282 -276.582253)
			(xy 351.553294 -276.631532) (xy 351.5614 -276.682709) (xy 351.561908 -276.708616) (xy 351.561377 -276.734509)
			(xy 351.842805 -276.734509) (xy 351.842805 -276.682691) (xy 351.850912 -276.631511) (xy 351.866925 -276.582229)
			(xy 351.89045 -276.53606) (xy 351.920909 -276.494139) (xy 351.957551 -276.457499) (xy 351.999473 -276.427042)
			(xy 352.045644 -276.403519) (xy 352.094927 -276.387508) (xy 352.146107 -276.379404) (xy 352.172016 -276.378924)
			(xy 352.197529 -276.379383) (xy 352.247945 -276.387247) (xy 352.296547 -276.402784) (xy 352.342175 -276.425624)
			(xy 352.38374 -276.45522) (xy 352.420249 -276.490867) (xy 352.435922 -276.511004) (xy 352.84791 -276.511004)
			(xy 352.863579 -276.490865) (xy 352.900089 -276.455221) (xy 352.941656 -276.425628) (xy 352.987285 -276.402792)
			(xy 353.035888 -276.387259) (xy 353.086304 -276.3794) (xy 353.111816 -276.378924) (xy 353.137724 -276.379401)
			(xy 353.188901 -276.387509) (xy 353.23818 -276.403523) (xy 353.284347 -276.427048) (xy 353.326266 -276.457506)
			(xy 353.362904 -276.494146) (xy 353.39336 -276.536066) (xy 353.416883 -276.582235) (xy 353.432895 -276.631514)
			(xy 353.441 -276.682692) (xy 353.441 -276.734508) (xy 353.432895 -276.785686) (xy 353.416883 -276.834965)
			(xy 353.39336 -276.881134) (xy 353.362904 -276.923054) (xy 353.326266 -276.959694) (xy 353.284347 -276.990152)
			(xy 353.23818 -277.013677) (xy 353.188901 -277.029691) (xy 353.137724 -277.037799) (xy 353.111816 -277.038308)
			(xy 353.086305 -277.037813) (xy 353.035891 -277.029955) (xy 352.98729 -277.014424) (xy 352.941662 -276.991591)
			(xy 352.900096 -276.962001) (xy 352.863585 -276.926361) (xy 352.84791 -276.906228) (xy 352.435922 -276.906228)
			(xy 352.420244 -276.926359) (xy 352.383734 -276.962002) (xy 352.342169 -276.991595) (xy 352.296542 -277.014432)
			(xy 352.247941 -277.029967) (xy 352.197528 -277.03783) (xy 352.172016 -277.038308) (xy 352.146107 -277.037796)
			(xy 352.094927 -277.029692) (xy 352.045644 -277.013681) (xy 351.999473 -276.990158) (xy 351.957551 -276.959701)
			(xy 351.920909 -276.923061) (xy 351.89045 -276.88114) (xy 351.866925 -276.834971) (xy 351.850912 -276.785689)
			(xy 351.842805 -276.734509) (xy 351.561377 -276.734509) (xy 351.561338 -276.736398) (xy 351.552014 -276.791174)
			(xy 351.543366 -276.817582) (xy 351.535492 -276.839426) (xy 351.74047 -277.194264) (xy 351.76333 -277.198582)
			(xy 351.788142 -277.203733) (xy 351.835882 -277.220727) (xy 351.88046 -277.244826) (xy 351.920825 -277.275462)
			(xy 351.956028 -277.311913) (xy 351.985239 -277.353322) (xy 352.007769 -277.398712) (xy 352.02309 -277.447016)
			(xy 352.030838 -277.497095) (xy 352.0313 -277.522432) (xy 354.191824 -277.522432) (xy 354.192226 -277.497095)
			(xy 354.199989 -277.447018) (xy 354.215322 -277.398718) (xy 354.237864 -277.353333) (xy 354.267084 -277.31193)
			(xy 354.302294 -277.275486) (xy 354.342666 -277.244857) (xy 354.387248 -277.220766) (xy 354.434991 -277.203779)
			(xy 354.459794 -277.198582) (xy 354.482654 -277.194264) (xy 354.687886 -276.838918) (xy 354.680266 -276.817074)
			(xy 354.671663 -276.790785) (xy 354.662334 -276.736269) (xy 354.661724 -276.708616) (xy 354.662232 -276.682709)
			(xy 354.670338 -276.631532) (xy 354.68635 -276.582253) (xy 354.709873 -276.536086) (xy 354.740329 -276.494167)
			(xy 354.776967 -276.457529) (xy 354.818886 -276.427073) (xy 354.865053 -276.40355) (xy 354.914332 -276.387538)
			(xy 354.965509 -276.379432) (xy 355.017323 -276.379432) (xy 355.0685 -276.387538) (xy 355.117779 -276.40355)
			(xy 355.163946 -276.427073) (xy 355.205865 -276.457529) (xy 355.242503 -276.494167) (xy 355.272959 -276.536086)
			(xy 355.296482 -276.582253) (xy 355.312494 -276.631532) (xy 355.3206 -276.682709) (xy 355.321108 -276.708616)
			(xy 356.541324 -276.708616) (xy 356.541802 -276.683281) (xy 356.549553 -276.633207) (xy 356.564874 -276.584909)
			(xy 356.587406 -276.539525) (xy 356.616616 -276.498122) (xy 356.651818 -276.461676) (xy 356.692181 -276.431046)
			(xy 356.736757 -276.406953) (xy 356.784494 -276.389964) (xy 356.809294 -276.384766) (xy 356.832154 -276.380448)
			(xy 357.037132 -276.02561) (xy 357.029258 -276.003766) (xy 357.020612 -275.977358) (xy 357.011292 -275.922582)
			(xy 357.010716 -275.8948) (xy 357.011224 -275.868893) (xy 357.01933 -275.817716) (xy 357.035342 -275.768437)
			(xy 357.058865 -275.72227) (xy 357.089321 -275.680351) (xy 357.125959 -275.643713) (xy 357.167878 -275.613257)
			(xy 357.214045 -275.589734) (xy 357.263324 -275.573722) (xy 357.314501 -275.565616) (xy 357.366315 -275.565616)
			(xy 357.417492 -275.573722) (xy 357.466771 -275.589734) (xy 357.512938 -275.613257) (xy 357.554857 -275.643713)
			(xy 357.591495 -275.680351) (xy 357.621951 -275.72227) (xy 357.645474 -275.768437) (xy 357.661486 -275.817716)
			(xy 357.669592 -275.868893) (xy 357.6701 -275.8948) (xy 357.669579 -275.920144) (xy 357.661807 -275.970232)
			(xy 357.646462 -276.018541) (xy 357.623906 -276.063932) (xy 357.594669 -276.105338) (xy 357.55944 -276.141782)
			(xy 357.519049 -276.172406) (xy 357.474448 -276.196488) (xy 357.426687 -276.213462) (xy 357.401876 -276.21865)
			(xy 357.379016 -276.222968) (xy 357.174038 -276.577806) (xy 357.181912 -276.599904) (xy 357.190474 -276.626262)
			(xy 357.199672 -276.680908) (xy 357.2002 -276.708616) (xy 357.199692 -276.734503) (xy 357.191593 -276.785641)
			(xy 357.175594 -276.834881) (xy 357.152088 -276.881013) (xy 357.121656 -276.9229) (xy 357.085046 -276.95951)
			(xy 357.043159 -276.989942) (xy 356.997027 -277.013448) (xy 356.947787 -277.029447) (xy 356.896649 -277.037546)
			(xy 356.844875 -277.037546) (xy 356.793737 -277.029447) (xy 356.744497 -277.013448) (xy 356.698365 -276.989942)
			(xy 356.656478 -276.95951) (xy 356.619868 -276.9229) (xy 356.589436 -276.881013) (xy 356.56593 -276.834881)
			(xy 356.549931 -276.785641) (xy 356.541832 -276.734503) (xy 356.541324 -276.708616) (xy 355.321108 -276.708616)
			(xy 355.320641 -276.73399) (xy 355.312871 -276.784141) (xy 355.297501 -276.832506) (xy 355.274895 -276.877942)
			(xy 355.245588 -276.919373) (xy 355.210273 -276.955819) (xy 355.169787 -276.986418) (xy 355.125087 -277.010445)
			(xy 355.07723 -277.027332) (xy 355.052376 -277.032466) (xy 355.029516 -277.036784) (xy 354.824538 -277.391622)
			(xy 354.832412 -277.41372) (xy 354.840977 -277.440077) (xy 354.850173 -277.494724) (xy 354.8507 -277.522432)
			(xy 355.131624 -277.522432) (xy 355.132132 -277.496545) (xy 355.140231 -277.445407) (xy 355.15623 -277.396167)
			(xy 355.179736 -277.350035) (xy 355.210168 -277.308148) (xy 355.246778 -277.271538) (xy 355.288665 -277.241106)
			(xy 355.334797 -277.2176) (xy 355.384037 -277.201601) (xy 355.435175 -277.193502) (xy 355.486949 -277.193502)
			(xy 355.538087 -277.201601) (xy 355.587327 -277.2176) (xy 355.633459 -277.241106) (xy 355.675346 -277.271538)
			(xy 355.711956 -277.308148) (xy 355.742388 -277.350035) (xy 355.765894 -277.396167) (xy 355.781893 -277.445407)
			(xy 355.789992 -277.496545) (xy 355.7905 -277.522432) (xy 355.7905 -277.52294) (xy 355.789963 -277.548303)
			(xy 356.071748 -277.548303) (xy 356.071748 -277.496497) (xy 356.079852 -277.445329) (xy 356.09586 -277.396058)
			(xy 356.119377 -277.349898) (xy 356.149826 -277.307985) (xy 356.186456 -277.271351) (xy 356.228366 -277.240897)
			(xy 356.274523 -277.217374) (xy 356.323792 -277.201361) (xy 356.374959 -277.193251) (xy 356.400862 -277.19274)
			(xy 356.426374 -277.193232) (xy 356.476788 -277.201088) (xy 356.52539 -277.216618) (xy 356.571019 -277.239452)
			(xy 356.612585 -277.269043) (xy 356.649095 -277.304685) (xy 356.664768 -277.32482) (xy 357.076756 -277.32482)
			(xy 357.09246 -277.30471) (xy 357.128963 -277.269063) (xy 357.170522 -277.239467) (xy 357.216144 -277.216626)
			(xy 357.264741 -277.201087) (xy 357.315152 -277.19322) (xy 357.340662 -277.19274) (xy 357.366576 -277.193155)
			(xy 357.417766 -277.201257) (xy 357.467059 -277.217268) (xy 357.51324 -277.240794) (xy 357.555171 -277.271254)
			(xy 357.591821 -277.3079) (xy 357.622286 -277.349828) (xy 357.645817 -277.396006) (xy 357.661834 -277.445297)
			(xy 357.669942 -277.496486) (xy 357.669942 -277.548314) (xy 357.661834 -277.599503) (xy 357.645817 -277.648794)
			(xy 357.622286 -277.694972) (xy 357.591821 -277.7369) (xy 357.555171 -277.773546) (xy 357.51324 -277.804006)
			(xy 357.467059 -277.827532) (xy 357.417766 -277.843543) (xy 357.366576 -277.851645) (xy 357.340662 -277.852124)
			(xy 357.31515 -277.851662) (xy 357.264735 -277.843796) (xy 357.216133 -277.828258) (xy 357.170505 -277.805419)
			(xy 357.12894 -277.775824) (xy 357.09243 -277.74018) (xy 357.076756 -277.720044) (xy 356.664768 -277.720044)
			(xy 356.649125 -277.740204) (xy 356.612608 -277.775845) (xy 356.571036 -277.805434) (xy 356.525401 -277.828266)
			(xy 356.476795 -277.843795) (xy 356.426376 -277.85165) (xy 356.400862 -277.852124) (xy 356.374959 -277.851549)
			(xy 356.323792 -277.843439) (xy 356.274523 -277.827426) (xy 356.228366 -277.803903) (xy 356.186456 -277.773449)
			(xy 356.149826 -277.736815) (xy 356.119377 -277.694902) (xy 356.09586 -277.648742) (xy 356.079852 -277.599471)
			(xy 356.071748 -277.548303) (xy 355.789963 -277.548303) (xy 355.789917 -277.550456) (xy 355.780726 -277.604717)
			(xy 355.772212 -277.63089) (xy 355.764592 -277.652988) (xy 355.969824 -278.008334) (xy 355.992684 -278.012652)
			(xy 356.017501 -278.017836) (xy 356.065277 -278.034792) (xy 356.109893 -278.058863) (xy 356.150297 -278.089482)
			(xy 356.185537 -278.125927) (xy 356.214781 -278.167338) (xy 356.23734 -278.212738) (xy 356.252681 -278.261056)
			(xy 356.260443 -278.311154) (xy 356.260908 -278.336502) (xy 356.2604 -278.362409) (xy 356.252294 -278.413586)
			(xy 356.236282 -278.462865) (xy 356.212759 -278.509032) (xy 356.182303 -278.550951) (xy 356.145665 -278.587589)
			(xy 356.103746 -278.618045) (xy 356.057579 -278.641568) (xy 356.0083 -278.65758) (xy 355.957123 -278.665686)
			(xy 355.905309 -278.665686) (xy 355.854132 -278.65758) (xy 355.804853 -278.641568) (xy 355.758686 -278.618045)
			(xy 355.716767 -278.587589) (xy 355.680129 -278.550951) (xy 355.649673 -278.509032) (xy 355.62615 -278.462865)
			(xy 355.610138 -278.413586) (xy 355.602032 -278.362409) (xy 355.601524 -278.336502) (xy 355.602117 -278.308785)
			(xy 355.611441 -278.254138) (xy 355.620066 -278.22779) (xy 355.62794 -278.205692) (xy 355.422962 -277.8506)
			(xy 355.399848 -277.846282) (xy 355.375022 -277.841137) (xy 355.327241 -277.824181) (xy 355.282621 -277.800107)
			(xy 355.242213 -277.769484) (xy 355.206972 -277.733035) (xy 355.177729 -277.691618) (xy 355.155174 -277.646211)
			(xy 355.139838 -277.597886) (xy 355.132084 -277.547782) (xy 355.131624 -277.522432) (xy 354.8507 -277.522432)
			(xy 354.850192 -277.548319) (xy 354.842093 -277.599457) (xy 354.826094 -277.648697) (xy 354.802588 -277.694829)
			(xy 354.772156 -277.736716) (xy 354.735546 -277.773326) (xy 354.693659 -277.803758) (xy 354.647527 -277.827264)
			(xy 354.598287 -277.843263) (xy 354.547149 -277.851362) (xy 354.495375 -277.851362) (xy 354.444237 -277.843263)
			(xy 354.394997 -277.827264) (xy 354.348865 -277.803758) (xy 354.306978 -277.773326) (xy 354.270368 -277.736716)
			(xy 354.239936 -277.694829) (xy 354.21643 -277.648697) (xy 354.200431 -277.599457) (xy 354.192332 -277.548319)
			(xy 354.191824 -277.522432) (xy 352.0313 -277.522432) (xy 352.030792 -277.548319) (xy 352.022693 -277.599457)
			(xy 352.006694 -277.648697) (xy 351.983188 -277.694829) (xy 351.952756 -277.736716) (xy 351.916146 -277.773326)
			(xy 351.874259 -277.803758) (xy 351.828127 -277.827264) (xy 351.778887 -277.843263) (xy 351.727749 -277.851362)
			(xy 351.675975 -277.851362) (xy 351.624837 -277.843263) (xy 351.575597 -277.827264) (xy 351.529465 -277.803758)
			(xy 351.487578 -277.773326) (xy 351.450968 -277.736716) (xy 351.420536 -277.694829) (xy 351.39703 -277.648697)
			(xy 351.381031 -277.599457) (xy 351.372932 -277.548319) (xy 351.372424 -277.522432) (xy 351.37296 -277.494724)
			(xy 351.382151 -277.440077) (xy 351.390712 -277.41372) (xy 351.398586 -277.391622) (xy 351.193608 -277.036784)
			(xy 351.170748 -277.032466) (xy 351.145918 -277.027336) (xy 351.098136 -277.010379) (xy 351.053515 -276.986304)
			(xy 351.013107 -276.955679) (xy 350.977866 -276.919227) (xy 350.948624 -276.877808) (xy 350.926069 -276.8324)
			(xy 350.910735 -276.784072) (xy 350.902983 -276.733967) (xy 350.902524 -276.708616) (xy 350.6216 -276.708616)
			(xy 350.621092 -276.734503) (xy 350.612993 -276.785641) (xy 350.596994 -276.834881) (xy 350.573488 -276.881013)
			(xy 350.543056 -276.9229) (xy 350.506446 -276.95951) (xy 350.464559 -276.989942) (xy 350.418427 -277.013448)
			(xy 350.369187 -277.029447) (xy 350.318049 -277.037546) (xy 350.266275 -277.037546) (xy 350.215137 -277.029447)
			(xy 350.165897 -277.013448) (xy 350.119765 -276.989942) (xy 350.077878 -276.95951) (xy 350.041268 -276.9229)
			(xy 350.010836 -276.881013) (xy 349.98733 -276.834881) (xy 349.971331 -276.785641) (xy 349.963232 -276.734503)
			(xy 349.962724 -276.708616) (xy 109.260132 -276.708616) (xy 109.259624 -276.734503) (xy 109.251525 -276.785641)
			(xy 109.235526 -276.834881) (xy 109.21202 -276.881013) (xy 109.181588 -276.9229) (xy 109.144978 -276.95951)
			(xy 109.103091 -276.989942) (xy 109.056959 -277.013448) (xy 109.007719 -277.029447) (xy 108.956581 -277.037546)
			(xy 108.904807 -277.037546) (xy 108.853669 -277.029447) (xy 108.804429 -277.013448) (xy 108.758297 -276.989942)
			(xy 108.71641 -276.95951) (xy 108.6798 -276.9229) (xy 108.649368 -276.881013) (xy 108.625862 -276.834881)
			(xy 108.609863 -276.785641) (xy 108.601764 -276.734503) (xy 108.601256 -276.708616) (xy 107.38104 -276.708616)
			(xy 107.380628 -276.733993) (xy 107.372856 -276.784149) (xy 107.357482 -276.832518) (xy 107.334871 -276.877958)
			(xy 107.305557 -276.91939) (xy 107.270234 -276.955836) (xy 107.229739 -276.986433) (xy 107.18503 -277.010456)
			(xy 107.137166 -277.027337) (xy 107.112308 -277.032466) (xy 107.089448 -277.036784) (xy 106.88447 -277.391622)
			(xy 106.892344 -277.41372) (xy 106.90091 -277.440076) (xy 106.910105 -277.494723) (xy 106.910632 -277.522432)
			(xy 107.191556 -277.522432) (xy 107.192064 -277.496545) (xy 107.200163 -277.445407) (xy 107.216162 -277.396167)
			(xy 107.239668 -277.350035) (xy 107.2701 -277.308148) (xy 107.30671 -277.271538) (xy 107.348597 -277.241106)
			(xy 107.394729 -277.2176) (xy 107.443969 -277.201601) (xy 107.495107 -277.193502) (xy 107.546881 -277.193502)
			(xy 107.598019 -277.201601) (xy 107.647259 -277.2176) (xy 107.693391 -277.241106) (xy 107.735278 -277.271538)
			(xy 107.771888 -277.308148) (xy 107.80232 -277.350035) (xy 107.825826 -277.396167) (xy 107.841825 -277.445407)
			(xy 107.849924 -277.496545) (xy 107.850432 -277.522432) (xy 107.850432 -277.52294) (xy 107.849894 -277.548305)
			(xy 108.131648 -277.548305) (xy 108.131648 -277.496495) (xy 108.139753 -277.445324) (xy 108.155763 -277.396051)
			(xy 108.179283 -277.349889) (xy 108.209735 -277.307974) (xy 108.24637 -277.271339) (xy 108.288284 -277.240886)
			(xy 108.334445 -277.217365) (xy 108.383718 -277.201354) (xy 108.43489 -277.193249) (xy 108.460794 -277.19274)
			(xy 108.486306 -277.193209) (xy 108.536722 -277.20107) (xy 108.585325 -277.216605) (xy 108.630953 -277.239442)
			(xy 108.672518 -277.269037) (xy 108.709027 -277.304684) (xy 108.7247 -277.32482) (xy 109.136688 -277.32482)
			(xy 109.152374 -277.304695) (xy 109.18888 -277.269049) (xy 109.230443 -277.239454) (xy 109.276069 -277.216616)
			(xy 109.324669 -277.20108) (xy 109.375083 -277.193218) (xy 109.400594 -277.19274) (xy 109.426506 -277.193157)
			(xy 109.477693 -277.201263) (xy 109.526981 -277.217277) (xy 109.573157 -277.240805) (xy 109.615085 -277.271266)
			(xy 109.65173 -277.307911) (xy 109.682192 -277.349838) (xy 109.70572 -277.396013) (xy 109.721735 -277.445301)
			(xy 109.729842 -277.496488) (xy 109.729842 -277.548312) (xy 109.721735 -277.599499) (xy 109.70572 -277.648787)
			(xy 109.682192 -277.694962) (xy 109.65173 -277.736889) (xy 109.615085 -277.773534) (xy 109.573157 -277.803995)
			(xy 109.526981 -277.827523) (xy 109.477693 -277.843537) (xy 109.426506 -277.851643) (xy 109.400594 -277.852124)
			(xy 109.375083 -277.851639) (xy 109.324669 -277.843778) (xy 109.276068 -277.828245) (xy 109.230439 -277.80541)
			(xy 109.188874 -277.775819) (xy 109.152362 -277.740178) (xy 109.136688 -277.720044) (xy 108.7247 -277.720044)
			(xy 108.709039 -277.740189) (xy 108.672525 -277.77583) (xy 108.630957 -277.805422) (xy 108.585326 -277.828256)
			(xy 108.536723 -277.843788) (xy 108.486307 -277.851647) (xy 108.460794 -277.852124) (xy 108.43489 -277.851551)
			(xy 108.383718 -277.843446) (xy 108.334445 -277.827435) (xy 108.288284 -277.803914) (xy 108.24637 -277.773461)
			(xy 108.209735 -277.736826) (xy 108.179283 -277.694911) (xy 108.155763 -277.648749) (xy 108.139753 -277.599476)
			(xy 108.131648 -277.548305) (xy 107.849894 -277.548305) (xy 107.849848 -277.550456) (xy 107.840658 -277.604717)
			(xy 107.832144 -277.63089) (xy 107.824524 -277.652988) (xy 108.029756 -278.008334) (xy 108.052616 -278.012652)
			(xy 108.077422 -278.017885) (xy 108.125198 -278.034831) (xy 108.169815 -278.058894) (xy 108.210222 -278.089506)
			(xy 108.245463 -278.125945) (xy 108.27471 -278.16735) (xy 108.29727 -278.212746) (xy 108.312612 -278.261061)
			(xy 108.320375 -278.311156) (xy 108.32084 -278.336502) (xy 108.320332 -278.362409) (xy 108.312226 -278.413586)
			(xy 108.296214 -278.462865) (xy 108.272691 -278.509032) (xy 108.242235 -278.550951) (xy 108.205597 -278.587589)
			(xy 108.163678 -278.618045) (xy 108.117511 -278.641568) (xy 108.068232 -278.65758) (xy 108.017055 -278.665686)
			(xy 107.965241 -278.665686) (xy 107.914064 -278.65758) (xy 107.864785 -278.641568) (xy 107.818618 -278.618045)
			(xy 107.776699 -278.587589) (xy 107.740061 -278.550951) (xy 107.709605 -278.509032) (xy 107.686082 -278.462865)
			(xy 107.67007 -278.413586) (xy 107.661964 -278.362409) (xy 107.661456 -278.336502) (xy 107.662047 -278.308784)
			(xy 107.671372 -278.254138) (xy 107.679998 -278.22779) (xy 107.687872 -278.205692) (xy 107.482894 -277.8506)
			(xy 107.45978 -277.846282) (xy 107.434959 -277.841114) (xy 107.387178 -277.824162) (xy 107.342557 -277.800093)
			(xy 107.302149 -277.769473) (xy 107.266907 -277.733026) (xy 107.237663 -277.691612) (xy 107.215107 -277.646207)
			(xy 107.199771 -277.597884) (xy 107.192016 -277.547781) (xy 107.191556 -277.522432) (xy 106.910632 -277.522432)
			(xy 106.910124 -277.548319) (xy 106.902025 -277.599457) (xy 106.886026 -277.648697) (xy 106.86252 -277.694829)
			(xy 106.832088 -277.736716) (xy 106.795478 -277.773326) (xy 106.753591 -277.803758) (xy 106.707459 -277.827264)
			(xy 106.658219 -277.843263) (xy 106.607081 -277.851362) (xy 106.555307 -277.851362) (xy 106.504169 -277.843263)
			(xy 106.454929 -277.827264) (xy 106.408797 -277.803758) (xy 106.36691 -277.773326) (xy 106.3303 -277.736716)
			(xy 106.299868 -277.694829) (xy 106.276362 -277.648697) (xy 106.260363 -277.599457) (xy 106.252264 -277.548319)
			(xy 106.251756 -277.522432) (xy 104.091232 -277.522432) (xy 104.090724 -277.548319) (xy 104.082625 -277.599457)
			(xy 104.066626 -277.648697) (xy 104.04312 -277.694829) (xy 104.012688 -277.736716) (xy 103.976078 -277.773326)
			(xy 103.934191 -277.803758) (xy 103.888059 -277.827264) (xy 103.838819 -277.843263) (xy 103.787681 -277.851362)
			(xy 103.735907 -277.851362) (xy 103.684769 -277.843263) (xy 103.635529 -277.827264) (xy 103.589397 -277.803758)
			(xy 103.54751 -277.773326) (xy 103.5109 -277.736716) (xy 103.480468 -277.694829) (xy 103.456962 -277.648697)
			(xy 103.440963 -277.599457) (xy 103.432864 -277.548319) (xy 103.432356 -277.522432) (xy 103.432895 -277.494724)
			(xy 103.442084 -277.440078) (xy 103.450644 -277.41372) (xy 103.458518 -277.391622) (xy 103.25354 -277.036784)
			(xy 103.23068 -277.032466) (xy 103.205855 -277.027313) (xy 103.158073 -277.01036) (xy 103.113452 -276.986289)
			(xy 103.073043 -276.955668) (xy 103.037801 -276.919219) (xy 103.008557 -276.877803) (xy 102.986002 -276.832396)
			(xy 102.970667 -276.78407) (xy 102.962915 -276.733966) (xy 102.962456 -276.708616) (xy 102.681532 -276.708616)
			(xy 102.681024 -276.734503) (xy 102.672925 -276.785641) (xy 102.656926 -276.834881) (xy 102.63342 -276.881013)
			(xy 102.602988 -276.9229) (xy 102.566378 -276.95951) (xy 102.524491 -276.989942) (xy 102.478359 -277.013448)
			(xy 102.429119 -277.029447) (xy 102.377981 -277.037546) (xy 102.326207 -277.037546) (xy 102.275069 -277.029447)
			(xy 102.225829 -277.013448) (xy 102.179697 -276.989942) (xy 102.13781 -276.95951) (xy 102.1012 -276.9229)
			(xy 102.070768 -276.881013) (xy 102.047262 -276.834881) (xy 102.031263 -276.785641) (xy 102.023164 -276.734503)
			(xy 102.022656 -276.708616) (xy 2.509012 -276.708616) (xy 2.509012 -279.150318) (xy 101.552756 -279.150318)
			(xy 101.553264 -279.124431) (xy 101.561363 -279.073293) (xy 101.577362 -279.024053) (xy 101.600868 -278.977921)
			(xy 101.6313 -278.936034) (xy 101.66791 -278.899424) (xy 101.709797 -278.868992) (xy 101.755929 -278.845486)
			(xy 101.805169 -278.829487) (xy 101.856307 -278.821388) (xy 101.908081 -278.821388) (xy 101.959219 -278.829487)
			(xy 102.008459 -278.845486) (xy 102.054591 -278.868992) (xy 102.096478 -278.899424) (xy 102.133088 -278.936034)
			(xy 102.16352 -278.977921) (xy 102.187026 -279.024053) (xy 102.203025 -279.073293) (xy 102.211124 -279.124431)
			(xy 102.211632 -279.150318) (xy 102.211632 -279.150826) (xy 102.21109 -279.176186) (xy 102.493088 -279.176186)
			(xy 102.493088 -279.124414) (xy 102.501186 -279.07328) (xy 102.517184 -279.024043) (xy 102.540688 -278.977914)
			(xy 102.571118 -278.93603) (xy 102.607725 -278.899422) (xy 102.649609 -278.868991) (xy 102.695737 -278.845487)
			(xy 102.744975 -278.829488) (xy 102.796108 -278.821388) (xy 102.821994 -278.82088) (xy 102.847505 -278.821372)
			(xy 102.897919 -278.829232) (xy 102.94652 -278.844763) (xy 102.992148 -278.867597) (xy 103.033714 -278.897186)
			(xy 103.070226 -278.932826) (xy 103.0859 -278.95296) (xy 103.497888 -278.95296) (xy 103.513557 -278.932822)
			(xy 103.550069 -278.89718) (xy 103.591636 -278.867588) (xy 103.637265 -278.844752) (xy 103.685867 -278.829219)
			(xy 103.736282 -278.821357) (xy 103.761794 -278.82088) (xy 103.787685 -278.821325) (xy 103.83883 -278.829425)
			(xy 103.888078 -278.845425) (xy 103.934217 -278.868934) (xy 103.97611 -278.89937) (xy 104.012726 -278.935985)
			(xy 104.043163 -278.977878) (xy 104.066672 -279.024016) (xy 104.082674 -279.073264) (xy 104.090775 -279.124409)
			(xy 104.090775 -279.150318) (xy 349.492824 -279.150318) (xy 349.493332 -279.124431) (xy 349.501431 -279.073293)
			(xy 349.51743 -279.024053) (xy 349.540936 -278.977921) (xy 349.571368 -278.936034) (xy 349.607978 -278.899424)
			(xy 349.649865 -278.868992) (xy 349.695997 -278.845486) (xy 349.745237 -278.829487) (xy 349.796375 -278.821388)
			(xy 349.848149 -278.821388) (xy 349.899287 -278.829487) (xy 349.948527 -278.845486) (xy 349.994659 -278.868992)
			(xy 350.036546 -278.899424) (xy 350.073156 -278.936034) (xy 350.103588 -278.977921) (xy 350.127094 -279.024053)
			(xy 350.143093 -279.073293) (xy 350.151192 -279.124431) (xy 350.1517 -279.150318) (xy 350.1517 -279.150826)
			(xy 350.15116 -279.176184) (xy 350.433187 -279.176184) (xy 350.433187 -279.124416) (xy 350.441285 -279.073285)
			(xy 350.457281 -279.02405) (xy 350.480782 -278.977924) (xy 350.511209 -278.936041) (xy 350.547812 -278.899433)
			(xy 350.589691 -278.869002) (xy 350.635815 -278.845496) (xy 350.685048 -278.829494) (xy 350.736178 -278.82139)
			(xy 350.762062 -278.82088) (xy 350.787572 -278.821396) (xy 350.837985 -278.82925) (xy 350.886585 -278.844777)
			(xy 350.932214 -278.867606) (xy 350.97378 -278.897192) (xy 351.010293 -278.932828) (xy 351.025968 -278.95296)
			(xy 351.437956 -278.95296) (xy 351.453644 -278.932837) (xy 351.490152 -278.897194) (xy 351.531715 -278.8676)
			(xy 351.57734 -278.844762) (xy 351.625939 -278.829225) (xy 351.676351 -278.82136) (xy 351.701862 -278.82088)
			(xy 351.727755 -278.821322) (xy 351.778904 -278.829418) (xy 351.828156 -278.845416) (xy 351.874299 -278.868923)
			(xy 351.916197 -278.899359) (xy 351.952817 -278.935974) (xy 351.983257 -278.977868) (xy 352.006769 -279.024009)
			(xy 352.022773 -279.073259) (xy 352.030875 -279.124407) (xy 352.030875 -279.176193) (xy 352.022773 -279.227341)
			(xy 352.006769 -279.276591) (xy 351.983257 -279.322732) (xy 351.952817 -279.364626) (xy 351.916197 -279.401241)
			(xy 351.874299 -279.431677) (xy 351.828156 -279.455184) (xy 351.778904 -279.471182) (xy 351.727755 -279.479278)
			(xy 351.701862 -279.479756) (xy 351.676348 -279.47932) (xy 351.625931 -279.471453) (xy 351.577328 -279.455912)
			(xy 351.531699 -279.433068) (xy 351.490135 -279.403466) (xy 351.453628 -279.367815) (xy 351.437956 -279.347676)
			(xy 351.025968 -279.347676) (xy 351.010307 -279.367822) (xy 350.973795 -279.403466) (xy 350.932228 -279.433059)
			(xy 350.886597 -279.455894) (xy 350.837992 -279.471425) (xy 350.787575 -279.479281) (xy 350.762062 -279.479756)
			(xy 350.736178 -279.47921) (xy 350.685048 -279.471106) (xy 350.635815 -279.455104) (xy 350.589691 -279.431598)
			(xy 350.547812 -279.401167) (xy 350.511209 -279.364559) (xy 350.480782 -279.322676) (xy 350.457281 -279.27655)
			(xy 350.441285 -279.227315) (xy 350.433187 -279.176184) (xy 350.15116 -279.176184) (xy 350.151114 -279.178342)
			(xy 350.141925 -279.232603) (xy 350.133412 -279.258776) (xy 350.125792 -279.28062) (xy 350.331024 -279.635966)
			(xy 350.353884 -279.640284) (xy 350.378708 -279.645438) (xy 350.426486 -279.662396) (xy 350.471104 -279.68647)
			(xy 350.511509 -279.717093) (xy 350.546749 -279.753542) (xy 350.575992 -279.794956) (xy 350.598549 -279.84036)
			(xy 350.613887 -279.888683) (xy 350.621645 -279.938785) (xy 350.622108 -279.964134) (xy 350.6216 -279.990041)
			(xy 350.613494 -280.041218) (xy 350.597482 -280.090497) (xy 350.573959 -280.136664) (xy 350.543503 -280.178583)
			(xy 350.506865 -280.215221) (xy 350.464946 -280.245677) (xy 350.418779 -280.2692) (xy 350.3695 -280.285212)
			(xy 350.318323 -280.293318) (xy 350.266509 -280.293318) (xy 350.215332 -280.285212) (xy 350.166053 -280.2692)
			(xy 350.119886 -280.245677) (xy 350.077967 -280.215221) (xy 350.041329 -280.178583) (xy 350.010873 -280.136664)
			(xy 349.98735 -280.090497) (xy 349.971338 -280.041218) (xy 349.963232 -279.990041) (xy 349.962724 -279.964134)
			(xy 349.963325 -279.936417) (xy 349.972644 -279.88177) (xy 349.981266 -279.855422) (xy 349.98914 -279.833324)
			(xy 349.784162 -279.478486) (xy 349.761302 -279.474168) (xy 349.736475 -279.468982) (xy 349.688671 -279.452048)
			(xy 349.644023 -279.427992) (xy 349.603586 -279.397383) (xy 349.568314 -279.360942) (xy 349.539039 -279.319529)
			(xy 349.516451 -279.274121) (xy 349.501083 -279.22579) (xy 349.493299 -279.175676) (xy 349.492824 -279.150318)
			(xy 104.090775 -279.150318) (xy 104.090775 -279.176191) (xy 104.082674 -279.227336) (xy 104.066672 -279.276584)
			(xy 104.043163 -279.322722) (xy 104.012726 -279.364615) (xy 103.97611 -279.40123) (xy 103.934217 -279.431666)
			(xy 103.888078 -279.455175) (xy 103.83883 -279.471175) (xy 103.787685 -279.479275) (xy 103.761794 -279.479756)
			(xy 103.736281 -279.479297) (xy 103.685865 -279.471435) (xy 103.637262 -279.455898) (xy 103.591633 -279.433058)
			(xy 103.550069 -279.403461) (xy 103.51356 -279.367813) (xy 103.497888 -279.347676) (xy 103.0859 -279.347676)
			(xy 103.07022 -279.367806) (xy 103.033713 -279.403452) (xy 102.992149 -279.433046) (xy 102.946521 -279.455884)
			(xy 102.89792 -279.471418) (xy 102.847506 -279.479279) (xy 102.821994 -279.479756) (xy 102.796108 -279.479212)
			(xy 102.744975 -279.471112) (xy 102.695737 -279.455113) (xy 102.649609 -279.431609) (xy 102.607725 -279.401178)
			(xy 102.571118 -279.36457) (xy 102.540688 -279.322686) (xy 102.517184 -279.276557) (xy 102.501186 -279.22732)
			(xy 102.493088 -279.176186) (xy 102.21109 -279.176186) (xy 102.211044 -279.178342) (xy 102.201856 -279.232603)
			(xy 102.193344 -279.258776) (xy 102.185724 -279.28062) (xy 102.390956 -279.635966) (xy 102.413816 -279.640284)
			(xy 102.438629 -279.645487) (xy 102.486407 -279.662435) (xy 102.531027 -279.686501) (xy 102.571434 -279.717117)
			(xy 102.606676 -279.753559) (xy 102.635921 -279.794969) (xy 102.658479 -279.840369) (xy 102.673819 -279.888688)
			(xy 102.681577 -279.938786) (xy 102.68204 -279.964134) (xy 102.681532 -279.990041) (xy 102.673426 -280.041218)
			(xy 102.657414 -280.090497) (xy 102.633891 -280.136664) (xy 102.603435 -280.178583) (xy 102.566797 -280.215221)
			(xy 102.524878 -280.245677) (xy 102.478711 -280.2692) (xy 102.429432 -280.285212) (xy 102.378255 -280.293318)
			(xy 102.326441 -280.293318) (xy 102.275264 -280.285212) (xy 102.225985 -280.2692) (xy 102.179818 -280.245677)
			(xy 102.137899 -280.215221) (xy 102.101261 -280.178583) (xy 102.070805 -280.136664) (xy 102.047282 -280.090497)
			(xy 102.03127 -280.041218) (xy 102.023164 -279.990041) (xy 102.022656 -279.964134) (xy 102.023255 -279.936417)
			(xy 102.032575 -279.88177) (xy 102.041198 -279.855422) (xy 102.049072 -279.833324) (xy 101.844094 -279.478486)
			(xy 101.821234 -279.474168) (xy 101.796412 -279.468959) (xy 101.748608 -279.452029) (xy 101.70396 -279.427978)
			(xy 101.663522 -279.397372) (xy 101.628249 -279.360934) (xy 101.598973 -279.319523) (xy 101.576384 -279.274117)
			(xy 101.561016 -279.225788) (xy 101.553231 -279.175675) (xy 101.552756 -279.150318) (xy 2.509012 -279.150318)
			(xy 2.509012 -279.989984) (xy 88.866003 -279.989984) (xy 88.866003 -279.938216) (xy 88.874102 -279.887084)
			(xy 88.890099 -279.837849) (xy 88.913601 -279.791722) (xy 88.94403 -279.74984) (xy 88.980636 -279.713234)
			(xy 89.022517 -279.682805) (xy 89.068643 -279.659301) (xy 89.117878 -279.643303) (xy 89.16901 -279.635204)
			(xy 89.194894 -279.634696) (xy 89.220406 -279.635183) (xy 89.27082 -279.643042) (xy 89.319421 -279.658575)
			(xy 89.365049 -279.681409) (xy 89.406615 -279.711) (xy 89.443126 -279.746642) (xy 89.4588 -279.766776)
			(xy 89.870788 -279.766776) (xy 89.886462 -279.746641) (xy 89.922972 -279.710998) (xy 89.964538 -279.681405)
			(xy 90.010166 -279.658569) (xy 90.058768 -279.643035) (xy 90.109182 -279.635173) (xy 90.134694 -279.634696)
			(xy 90.160586 -279.635109) (xy 90.211734 -279.643209) (xy 90.260984 -279.659211) (xy 90.307125 -279.68272)
			(xy 90.349021 -279.713158) (xy 90.385638 -279.749775) (xy 90.416077 -279.791669) (xy 90.439587 -279.83781)
			(xy 90.45559 -279.88706) (xy 90.463691 -279.938208) (xy 90.463691 -279.964134) (xy 96.383856 -279.964134)
			(xy 96.384364 -279.938227) (xy 96.39247 -279.88705) (xy 96.408482 -279.837771) (xy 96.432005 -279.791604)
			(xy 96.462461 -279.749685) (xy 96.499099 -279.713047) (xy 96.541018 -279.682591) (xy 96.587185 -279.659068)
			(xy 96.636464 -279.643056) (xy 96.687641 -279.63495) (xy 96.739455 -279.63495) (xy 96.790632 -279.643056)
			(xy 96.839911 -279.659068) (xy 96.886078 -279.682591) (xy 96.927997 -279.713047) (xy 96.964635 -279.749685)
			(xy 96.995091 -279.791604) (xy 97.018614 -279.837771) (xy 97.034626 -279.88705) (xy 97.042732 -279.938227)
			(xy 97.04324 -279.964134) (xy 97.042606 -279.991926) (xy 97.033158 -280.046702) (xy 97.024444 -280.0731)
			(xy 97.016824 -280.095198) (xy 97.221802 -280.450036) (xy 97.244662 -280.454354) (xy 97.269457 -280.45958)
			(xy 97.317195 -280.476563) (xy 97.361773 -280.50065) (xy 97.402139 -280.531276) (xy 97.437344 -280.567718)
			(xy 97.466557 -280.609118) (xy 97.489091 -280.6545) (xy 97.504415 -280.702797) (xy 97.512168 -280.752869)
			(xy 97.512632 -280.778204) (xy 97.512124 -280.804091) (xy 97.504025 -280.855229) (xy 97.488026 -280.904469)
			(xy 97.46452 -280.950601) (xy 97.434088 -280.992488) (xy 97.397478 -281.029098) (xy 97.355591 -281.05953)
			(xy 97.309459 -281.083036) (xy 97.260219 -281.099035) (xy 97.209081 -281.107134) (xy 97.157307 -281.107134)
			(xy 97.106169 -281.099035) (xy 97.056929 -281.083036) (xy 97.010797 -281.05953) (xy 96.96891 -281.029098)
			(xy 96.9323 -280.992488) (xy 96.901868 -280.950601) (xy 96.878362 -280.904469) (xy 96.862363 -280.855229)
			(xy 96.854264 -280.804091) (xy 96.853756 -280.778204) (xy 96.854288 -280.750496) (xy 96.863482 -280.695849)
			(xy 96.872044 -280.669492) (xy 96.879918 -280.647394) (xy 96.674686 -280.292302) (xy 96.651826 -280.287984)
			(xy 96.627038 -280.282731) (xy 96.579302 -280.265749) (xy 96.534727 -280.241664) (xy 96.494362 -280.211041)
			(xy 96.459158 -280.174603) (xy 96.429944 -280.133207) (xy 96.407407 -280.087828) (xy 96.39208 -280.039536)
			(xy 96.384322 -279.989467) (xy 96.383856 -279.964134) (xy 90.463691 -279.964134) (xy 90.463691 -279.989992)
			(xy 90.45559 -280.04114) (xy 90.439587 -280.09039) (xy 90.416077 -280.13653) (xy 90.385638 -280.178425)
			(xy 90.349021 -280.215042) (xy 90.307125 -280.24548) (xy 90.260984 -280.268989) (xy 90.211734 -280.284991)
			(xy 90.160586 -280.293091) (xy 90.134694 -280.293572) (xy 90.109181 -280.293107) (xy 90.058766 -280.285245)
			(xy 90.010163 -280.269709) (xy 89.964535 -280.24687) (xy 89.92297 -280.217275) (xy 89.886461 -280.181628)
			(xy 89.870788 -280.161492) (xy 89.4588 -280.161492) (xy 89.443124 -280.181626) (xy 89.406615 -280.21727)
			(xy 89.365051 -280.246864) (xy 89.319422 -280.269701) (xy 89.270821 -280.285235) (xy 89.220406 -280.293095)
			(xy 89.194894 -280.293572) (xy 89.16901 -280.292996) (xy 89.117878 -280.284897) (xy 89.068643 -280.268899)
			(xy 89.022517 -280.245395) (xy 88.980636 -280.214966) (xy 88.94403 -280.17836) (xy 88.913601 -280.136478)
			(xy 88.890099 -280.090351) (xy 88.874102 -280.041116) (xy 88.866003 -279.989984) (xy 2.509012 -279.989984)
			(xy 2.509012 -280.804107) (xy 86.51622 -280.804107) (xy 86.51622 -280.752293) (xy 86.524326 -280.701118)
			(xy 86.540337 -280.65184) (xy 86.563859 -280.605674) (xy 86.594314 -280.563756) (xy 86.630951 -280.527118)
			(xy 86.672869 -280.496662) (xy 86.719035 -280.473139) (xy 86.768312 -280.457127) (xy 86.819487 -280.449021)
			(xy 86.845394 -280.448512) (xy 86.870888 -280.448996) (xy 86.921265 -280.456856) (xy 86.969828 -280.472391)
			(xy 87.015416 -280.495227) (xy 87.056936 -280.52482) (xy 87.093398 -280.56046) (xy 87.109046 -280.580592)
			(xy 87.521542 -280.580592) (xy 87.537192 -280.560462) (xy 87.573653 -280.52482) (xy 87.615173 -280.495227)
			(xy 87.66076 -280.472389) (xy 87.709323 -280.456853) (xy 87.7597 -280.448991) (xy 87.785194 -280.448512)
			(xy 87.811104 -280.448985) (xy 87.862286 -280.457091) (xy 87.91157 -280.473103) (xy 87.957743 -280.496628)
			(xy 87.999666 -280.527087) (xy 88.036309 -280.563729) (xy 88.066768 -280.605652) (xy 88.090294 -280.651824)
			(xy 88.106308 -280.701108) (xy 88.114414 -280.75229) (xy 88.114414 -280.80411) (xy 88.106308 -280.855292)
			(xy 88.090294 -280.904576) (xy 88.066768 -280.950748) (xy 88.036309 -280.992671) (xy 87.999666 -281.029313)
			(xy 87.957743 -281.059772) (xy 87.91157 -281.083297) (xy 87.862286 -281.099309) (xy 87.811104 -281.107415)
			(xy 87.785194 -281.107896) (xy 87.7597 -281.107418) (xy 87.709323 -281.099555) (xy 87.660759 -281.08402)
			(xy 87.615172 -281.061182) (xy 87.573652 -281.031589) (xy 87.53719 -280.995948) (xy 87.521542 -280.975816)
			(xy 87.109046 -280.975816) (xy 87.093405 -280.995954) (xy 87.056942 -281.031594) (xy 87.01542 -281.061187)
			(xy 86.969831 -281.084023) (xy 86.921267 -281.099558) (xy 86.870888 -281.107418) (xy 86.845394 -281.107896)
			(xy 86.819487 -281.107379) (xy 86.768312 -281.099273) (xy 86.719035 -281.083261) (xy 86.672869 -281.059738)
			(xy 86.630951 -281.029282) (xy 86.594314 -280.992644) (xy 86.563859 -280.950726) (xy 86.540337 -280.90456)
			(xy 86.524326 -280.855282) (xy 86.51622 -280.804107) (xy 2.509012 -280.804107) (xy 2.509012 -282.405836)
			(xy 86.515956 -282.405836) (xy 86.516374 -282.380488) (xy 86.524157 -282.330393) (xy 86.539514 -282.282079)
			(xy 86.562083 -282.236685) (xy 86.591333 -282.195278) (xy 86.626575 -282.158835) (xy 86.666978 -282.128214)
			(xy 86.711591 -282.104137) (xy 86.759364 -282.08717) (xy 86.78418 -282.081986) (xy 86.80704 -282.077668)
			(xy 87.012018 -281.722576) (xy 87.004398 -281.700732) (xy 86.995753 -281.67439) (xy 86.986439 -281.619739)
			(xy 86.985856 -281.59202) (xy 86.986364 -281.566113) (xy 86.99447 -281.514936) (xy 87.010482 -281.465657)
			(xy 87.034005 -281.41949) (xy 87.064461 -281.377571) (xy 87.101099 -281.340933) (xy 87.143018 -281.310477)
			(xy 87.189185 -281.286954) (xy 87.238464 -281.270942) (xy 87.289641 -281.262836) (xy 87.341455 -281.262836)
			(xy 87.392632 -281.270942) (xy 87.441911 -281.286954) (xy 87.488078 -281.310477) (xy 87.529997 -281.340933)
			(xy 87.566635 -281.377571) (xy 87.597091 -281.41949) (xy 87.620614 -281.465657) (xy 87.636626 -281.514936)
			(xy 87.644732 -281.566113) (xy 87.64524 -281.59202) (xy 88.865456 -281.59202) (xy 88.86595 -281.566675)
			(xy 88.87372 -281.516583) (xy 88.889066 -281.468271) (xy 88.911624 -281.422876) (xy 88.940864 -281.381469)
			(xy 88.976098 -281.345025) (xy 89.016493 -281.314403) (xy 89.0611 -281.290323) (xy 89.108866 -281.273355)
			(xy 89.13368 -281.26817) (xy 89.15654 -281.263852) (xy 89.361518 -280.909014) (xy 89.353898 -280.88717)
			(xy 89.345254 -280.860761) (xy 89.335932 -280.805986) (xy 89.335356 -280.778204) (xy 89.335819 -280.752307)
			(xy 89.343918 -280.70115) (xy 89.359916 -280.651889) (xy 89.383421 -280.605736) (xy 89.413854 -280.563826)
			(xy 89.450466 -280.527191) (xy 89.492357 -280.496731) (xy 89.538495 -280.473197) (xy 89.587746 -280.457167)
			(xy 89.638897 -280.449036) (xy 89.664794 -280.448512) (xy 89.690671 -280.448974) (xy 89.741789 -280.457066)
			(xy 89.791012 -280.473052) (xy 89.83713 -280.496539) (xy 89.879007 -280.526949) (xy 89.915615 -280.563533)
			(xy 89.946051 -280.605391) (xy 89.969567 -280.651494) (xy 89.985584 -280.700707) (xy 89.993709 -280.751819)
			(xy 89.994232 -280.777696) (xy 89.994232 -280.778204) (xy 92.154756 -280.778204) (xy 92.155193 -280.752292)
			(xy 92.163301 -280.701107) (xy 92.179316 -280.65182) (xy 92.202845 -280.605646) (xy 92.233308 -280.563722)
			(xy 92.269955 -280.527079) (xy 92.311884 -280.496622) (xy 92.358061 -280.473099) (xy 92.40735 -280.45709)
			(xy 92.458536 -280.44899) (xy 92.484448 -280.448512) (xy 92.510327 -280.448924) (xy 92.561446 -280.457025)
			(xy 92.61067 -280.473018) (xy 92.656788 -280.496511) (xy 92.698665 -280.526927) (xy 92.735272 -280.563516)
			(xy 92.765707 -280.605379) (xy 92.789222 -280.651486) (xy 92.805239 -280.700702) (xy 92.813363 -280.751818)
			(xy 92.813886 -280.777696) (xy 92.813886 -280.778204) (xy 92.813354 -280.804107) (xy 94.97442 -280.804107)
			(xy 94.97442 -280.752293) (xy 94.982526 -280.701118) (xy 94.998537 -280.65184) (xy 95.022059 -280.605674)
			(xy 95.052514 -280.563756) (xy 95.089151 -280.527118) (xy 95.131069 -280.496662) (xy 95.177235 -280.473139)
			(xy 95.226512 -280.457127) (xy 95.277687 -280.449021) (xy 95.303594 -280.448512) (xy 95.329106 -280.448992)
			(xy 95.379521 -280.456852) (xy 95.428122 -280.472385) (xy 95.473751 -280.495221) (xy 95.515316 -280.524814)
			(xy 95.551826 -280.560457) (xy 95.5675 -280.580592) (xy 95.979742 -280.580592) (xy 95.995389 -280.560435)
			(xy 96.031904 -280.524793) (xy 96.073475 -280.495202) (xy 96.119109 -280.472369) (xy 96.167716 -280.45684)
			(xy 96.218134 -280.448986) (xy 96.243648 -280.448512) (xy 96.269553 -280.449016) (xy 96.320725 -280.457128)
			(xy 96.369997 -280.473144) (xy 96.416159 -280.49667) (xy 96.458071 -280.527127) (xy 96.494704 -280.563765)
			(xy 96.525155 -280.605682) (xy 96.548675 -280.651847) (xy 96.564684 -280.701122) (xy 96.572788 -280.752295)
			(xy 96.572788 -280.804105) (xy 96.564684 -280.855278) (xy 96.548675 -280.904553) (xy 96.525155 -280.950718)
			(xy 96.494704 -280.992635) (xy 96.458071 -281.029273) (xy 96.416159 -281.05973) (xy 96.369997 -281.083256)
			(xy 96.320725 -281.099272) (xy 96.269553 -281.107384) (xy 96.243648 -281.107896) (xy 96.218137 -281.107382)
			(xy 96.167724 -281.099529) (xy 96.119123 -281.084002) (xy 96.073495 -281.061173) (xy 96.031928 -281.031586)
			(xy 95.995417 -280.995948) (xy 95.979742 -280.975816) (xy 95.5675 -280.975816) (xy 95.551831 -280.995955)
			(xy 95.51532 -281.031598) (xy 95.473753 -281.06119) (xy 95.428124 -281.084026) (xy 95.379522 -281.099559)
			(xy 95.329106 -281.107419) (xy 95.303594 -281.107896) (xy 95.277687 -281.107379) (xy 95.226512 -281.099273)
			(xy 95.177235 -281.083261) (xy 95.131069 -281.059738) (xy 95.089151 -281.029282) (xy 95.052514 -280.992644)
			(xy 95.022059 -280.950726) (xy 94.998537 -280.90456) (xy 94.982526 -280.855282) (xy 94.97442 -280.804107)
			(xy 92.813354 -280.804107) (xy 92.813315 -280.805986) (xy 92.803991 -280.860762) (xy 92.795344 -280.88717)
			(xy 92.787724 -280.909014) (xy 92.992702 -281.263852) (xy 93.015562 -281.26817) (xy 93.04036 -281.273381)
			(xy 93.0881 -281.290365) (xy 93.132678 -281.314454) (xy 93.173045 -281.345081) (xy 93.20825 -281.381525)
			(xy 93.237463 -281.422927) (xy 93.259996 -281.468312) (xy 93.275318 -281.51661) (xy 93.283069 -281.566685)
			(xy 93.283532 -281.59202) (xy 93.283024 -281.617907) (xy 93.274925 -281.669045) (xy 93.258926 -281.718285)
			(xy 93.23542 -281.764417) (xy 93.204988 -281.806304) (xy 93.168378 -281.842914) (xy 93.126491 -281.873346)
			(xy 93.080359 -281.896852) (xy 93.031119 -281.912851) (xy 92.979981 -281.92095) (xy 92.928207 -281.92095)
			(xy 92.877069 -281.912851) (xy 92.827829 -281.896852) (xy 92.781697 -281.873346) (xy 92.73981 -281.842914)
			(xy 92.7032 -281.806304) (xy 92.672768 -281.764417) (xy 92.649262 -281.718285) (xy 92.633263 -281.669045)
			(xy 92.625164 -281.617907) (xy 92.624656 -281.59202) (xy 92.625203 -281.564313) (xy 92.634391 -281.509667)
			(xy 92.642944 -281.483308) (xy 92.650564 -281.461464) (xy 92.445586 -281.106372) (xy 92.422726 -281.102054)
			(xy 92.397931 -281.096829) (xy 92.350193 -281.079845) (xy 92.305616 -281.055757) (xy 92.265251 -281.025131)
			(xy 92.230046 -280.988689) (xy 92.200833 -280.947289) (xy 92.178299 -280.901907) (xy 92.162974 -280.853611)
			(xy 92.15522 -280.803539) (xy 92.154756 -280.778204) (xy 89.994232 -280.778204) (xy 89.993765 -280.803528)
			(xy 89.986033 -280.853583) (xy 89.970734 -280.901865) (xy 89.94823 -280.947239) (xy 89.91905 -280.988637)
			(xy 89.883881 -281.025084) (xy 89.843551 -281.055722) (xy 89.799008 -281.079831) (xy 89.751302 -281.096842)
			(xy 89.726516 -281.102054) (xy 89.703656 -281.106372) (xy 89.498678 -281.46121) (xy 89.506298 -281.483054)
			(xy 89.51491 -281.50934) (xy 89.524233 -281.563858) (xy 89.52484 -281.591512) (xy 89.52484 -281.59202)
			(xy 89.524332 -281.617905) (xy 90.745336 -281.617905) (xy 90.745336 -281.566095) (xy 90.753441 -281.514922)
			(xy 90.769451 -281.465646) (xy 90.792973 -281.419482) (xy 90.823426 -281.377566) (xy 90.860062 -281.34093)
			(xy 90.901977 -281.310476) (xy 90.948141 -281.286954) (xy 90.997416 -281.270943) (xy 91.048589 -281.262837)
			(xy 91.074494 -281.262328) (xy 91.100006 -281.262802) (xy 91.150421 -281.270662) (xy 91.199024 -281.286196)
			(xy 91.244652 -281.309033) (xy 91.286218 -281.338627) (xy 91.322727 -281.374272) (xy 91.3384 -281.394408)
			(xy 91.750388 -281.394408) (xy 91.766071 -281.37428) (xy 91.802578 -281.338635) (xy 91.844142 -281.309041)
			(xy 91.889768 -281.286203) (xy 91.938369 -281.270668) (xy 91.988782 -281.262806) (xy 92.014294 -281.262328)
			(xy 92.040205 -281.262769) (xy 92.09139 -281.270875) (xy 92.140676 -281.286888) (xy 92.186851 -281.310415)
			(xy 92.228777 -281.340875) (xy 92.265421 -281.377519) (xy 92.295882 -281.419444) (xy 92.319409 -281.465618)
			(xy 92.335423 -281.514904) (xy 92.34353 -281.566089) (xy 92.34353 -281.617911) (xy 92.335423 -281.669096)
			(xy 92.319409 -281.718382) (xy 92.295882 -281.764556) (xy 92.265421 -281.806481) (xy 92.228777 -281.843125)
			(xy 92.186851 -281.873585) (xy 92.140676 -281.897112) (xy 92.09139 -281.913125) (xy 92.040205 -281.921231)
			(xy 92.014294 -281.921712) (xy 91.988782 -281.921231) (xy 91.938368 -281.91337) (xy 91.889767 -281.897836)
			(xy 91.844138 -281.875001) (xy 91.802573 -281.845409) (xy 91.766062 -281.809767) (xy 91.750388 -281.789632)
			(xy 91.3384 -281.789632) (xy 91.322735 -281.809774) (xy 91.286223 -281.845417) (xy 91.244655 -281.875008)
			(xy 91.199025 -281.897843) (xy 91.150422 -281.913376) (xy 91.100006 -281.921235) (xy 91.074494 -281.921712)
			(xy 91.048589 -281.921163) (xy 90.997416 -281.913057) (xy 90.948141 -281.897046) (xy 90.901977 -281.873524)
			(xy 90.860062 -281.84307) (xy 90.823426 -281.806434) (xy 90.792973 -281.764518) (xy 90.769451 -281.718354)
			(xy 90.753441 -281.669078) (xy 90.745336 -281.617905) (xy 89.524332 -281.617905) (xy 89.524332 -281.617927)
			(xy 89.516226 -281.669104) (xy 89.500214 -281.718383) (xy 89.476691 -281.76455) (xy 89.446235 -281.806469)
			(xy 89.409597 -281.843107) (xy 89.367678 -281.873563) (xy 89.321511 -281.897086) (xy 89.272232 -281.913098)
			(xy 89.221055 -281.921204) (xy 89.169241 -281.921204) (xy 89.118064 -281.913098) (xy 89.068785 -281.897086)
			(xy 89.022618 -281.873563) (xy 88.980699 -281.843107) (xy 88.944061 -281.806469) (xy 88.913605 -281.76455)
			(xy 88.890082 -281.718383) (xy 88.87407 -281.669104) (xy 88.865964 -281.617927) (xy 88.865456 -281.59202)
			(xy 87.64524 -281.59202) (xy 87.644785 -281.617367) (xy 87.637009 -281.66746) (xy 87.621658 -281.715773)
			(xy 87.599094 -281.761168) (xy 87.569849 -281.802575) (xy 87.534611 -281.839019) (xy 87.494211 -281.86964)
			(xy 87.449601 -281.893718) (xy 87.401831 -281.910686) (xy 87.377016 -281.91587) (xy 87.354156 -281.920188)
			(xy 87.149178 -282.27528) (xy 87.156798 -282.297124) (xy 87.165433 -282.32347) (xy 87.174753 -282.378118)
			(xy 87.17534 -282.405836) (xy 87.455756 -282.405836) (xy 87.456264 -282.379949) (xy 87.464363 -282.328811)
			(xy 87.480362 -282.279571) (xy 87.503868 -282.233439) (xy 87.5343 -282.191552) (xy 87.57091 -282.154942)
			(xy 87.612797 -282.12451) (xy 87.658929 -282.101004) (xy 87.708169 -282.085005) (xy 87.759307 -282.076906)
			(xy 87.811081 -282.076906) (xy 87.862219 -282.085005) (xy 87.911459 -282.101004) (xy 87.957591 -282.12451)
			(xy 87.999478 -282.154942) (xy 88.036088 -282.191552) (xy 88.06652 -282.233439) (xy 88.090026 -282.279571)
			(xy 88.106025 -282.328811) (xy 88.114124 -282.379949) (xy 88.114632 -282.405836) (xy 88.114145 -282.431709)
			(xy 88.396026 -282.431709) (xy 88.396026 -282.379891) (xy 88.404133 -282.328711) (xy 88.420147 -282.27943)
			(xy 88.443674 -282.233261) (xy 88.474134 -282.191341) (xy 88.510778 -282.154703) (xy 88.552702 -282.124249)
			(xy 88.598874 -282.100729) (xy 88.648158 -282.084722) (xy 88.699339 -282.076622) (xy 88.725248 -282.076144)
			(xy 88.750741 -282.076648) (xy 88.801118 -282.084503) (xy 88.849682 -282.100032) (xy 88.895269 -282.122865)
			(xy 88.936791 -282.152454) (xy 88.973252 -282.188093) (xy 88.9889 -282.208224) (xy 89.401396 -282.208224)
			(xy 89.417024 -282.188075) (xy 89.453488 -282.152433) (xy 89.495013 -282.122841) (xy 89.540604 -282.100006)
			(xy 89.589171 -282.084474) (xy 89.639553 -282.076619) (xy 89.665048 -282.076144) (xy 89.690956 -282.076584)
			(xy 89.742132 -282.084696) (xy 89.79141 -282.100714) (xy 89.837576 -282.124242) (xy 89.879493 -282.154702)
			(xy 89.916129 -282.191344) (xy 89.946583 -282.233265) (xy 89.970105 -282.279434) (xy 89.986115 -282.328714)
			(xy 89.99422 -282.379892) (xy 89.99422 -282.431708) (xy 89.986115 -282.482886) (xy 89.970105 -282.532166)
			(xy 89.946583 -282.578335) (xy 89.916129 -282.620256) (xy 89.879493 -282.656898) (xy 89.837576 -282.687358)
			(xy 89.79141 -282.710886) (xy 89.742132 -282.726904) (xy 89.690956 -282.735016) (xy 89.665048 -282.735528)
			(xy 89.639556 -282.734998) (xy 89.589182 -282.727145) (xy 89.54062 -282.711619) (xy 89.495033 -282.688791)
			(xy 89.453511 -282.659207) (xy 89.417046 -282.623576) (xy 89.401396 -282.603448) (xy 88.9889 -282.603448)
			(xy 88.973236 -282.623567) (xy 88.936776 -282.659207) (xy 88.895259 -282.6888) (xy 88.849675 -282.71164)
			(xy 88.801115 -282.727179) (xy 88.750741 -282.735046) (xy 88.725248 -282.735528) (xy 88.699339 -282.734978)
			(xy 88.648158 -282.726878) (xy 88.598874 -282.710871) (xy 88.552702 -282.687351) (xy 88.510778 -282.656897)
			(xy 88.474134 -282.620259) (xy 88.443674 -282.578339) (xy 88.420147 -282.53217) (xy 88.404133 -282.482889)
			(xy 88.396026 -282.431709) (xy 88.114145 -282.431709) (xy 88.11411 -282.433545) (xy 88.10491 -282.488191)
			(xy 88.096344 -282.514548) (xy 88.08847 -282.536646) (xy 88.293702 -282.891738) (xy 88.316562 -282.896056)
			(xy 88.341357 -282.90128) (xy 88.389096 -282.918263) (xy 88.433673 -282.942351) (xy 88.47404 -282.972977)
			(xy 88.509244 -283.009419) (xy 88.538458 -283.050819) (xy 88.560992 -283.096202) (xy 88.576316 -283.144498)
			(xy 88.584068 -283.194571) (xy 88.584532 -283.219906) (xy 90.745056 -283.219906) (xy 90.74558 -283.194573)
			(xy 90.75333 -283.144505) (xy 90.768649 -283.096211) (xy 90.791176 -283.05083) (xy 90.820381 -283.009429)
			(xy 90.855576 -282.972983) (xy 90.895932 -282.942351) (xy 90.9405 -282.918254) (xy 90.988229 -282.901258)
			(xy 91.013026 -282.896056) (xy 91.035886 -282.891738) (xy 91.241118 -282.536392) (xy 91.233498 -282.514548)
			(xy 91.224857 -282.488204) (xy 91.215541 -282.433555) (xy 91.214956 -282.405836) (xy 91.215464 -282.379929)
			(xy 91.22357 -282.328752) (xy 91.239582 -282.279473) (xy 91.263105 -282.233306) (xy 91.293561 -282.191387)
			(xy 91.330199 -282.154749) (xy 91.372118 -282.124293) (xy 91.418285 -282.10077) (xy 91.467564 -282.084758)
			(xy 91.518741 -282.076652) (xy 91.570555 -282.076652) (xy 91.621732 -282.084758) (xy 91.671011 -282.10077)
			(xy 91.717178 -282.124293) (xy 91.759097 -282.154749) (xy 91.795735 -282.191387) (xy 91.826191 -282.233306)
			(xy 91.849714 -282.279473) (xy 91.865726 -282.328752) (xy 91.873832 -282.379929) (xy 91.87434 -282.405836)
			(xy 93.094556 -282.405836) (xy 93.094974 -282.380488) (xy 93.102757 -282.330393) (xy 93.118114 -282.282079)
			(xy 93.140683 -282.236685) (xy 93.169933 -282.195278) (xy 93.205175 -282.158835) (xy 93.245578 -282.128214)
			(xy 93.290191 -282.104137) (xy 93.337964 -282.08717) (xy 93.36278 -282.081986) (xy 93.38564 -282.077668)
			(xy 93.590618 -281.72283) (xy 93.582744 -281.700986) (xy 93.574162 -281.674568) (xy 93.564967 -281.619792)
			(xy 93.564456 -281.59202) (xy 93.564964 -281.566133) (xy 93.573063 -281.514995) (xy 93.589062 -281.465755)
			(xy 93.612568 -281.419623) (xy 93.643 -281.377736) (xy 93.67961 -281.341126) (xy 93.721497 -281.310694)
			(xy 93.767629 -281.287188) (xy 93.816869 -281.271189) (xy 93.868007 -281.26309) (xy 93.919781 -281.26309)
			(xy 93.970919 -281.271189) (xy 94.020159 -281.287188) (xy 94.066291 -281.310694) (xy 94.108178 -281.341126)
			(xy 94.144788 -281.377736) (xy 94.17522 -281.419623) (xy 94.198726 -281.465755) (xy 94.214725 -281.514995)
			(xy 94.222824 -281.566133) (xy 94.223332 -281.59202) (xy 94.222842 -281.617354) (xy 94.215087 -281.667425)
			(xy 94.199764 -281.71572) (xy 94.177233 -281.761102) (xy 94.148024 -281.802503) (xy 94.112825 -281.838948)
			(xy 94.072465 -281.869579) (xy 94.027893 -281.893676) (xy 93.980161 -281.910669) (xy 93.955362 -281.91587)
			(xy 93.932502 -281.920188) (xy 93.727524 -282.275026) (xy 93.735398 -282.297124) (xy 93.744018 -282.323474)
			(xy 93.753346 -282.378119) (xy 93.75394 -282.405836) (xy 94.974156 -282.405836) (xy 94.974616 -282.380501)
			(xy 94.982377 -282.33043) (xy 94.997705 -282.282135) (xy 95.020241 -282.236753) (xy 95.049454 -282.195352)
			(xy 95.084656 -282.158908) (xy 95.125019 -282.128277) (xy 95.169592 -282.104181) (xy 95.217327 -282.087187)
			(xy 95.242126 -282.081986) (xy 95.264986 -282.077668) (xy 95.470218 -281.722322) (xy 95.462598 -281.700478)
			(xy 95.45397 -281.674197) (xy 95.444658 -281.619675) (xy 95.444056 -281.59202) (xy 95.444564 -281.566113)
			(xy 95.45267 -281.514936) (xy 95.468682 -281.465657) (xy 95.492205 -281.41949) (xy 95.522661 -281.377571)
			(xy 95.559299 -281.340933) (xy 95.601218 -281.310477) (xy 95.647385 -281.286954) (xy 95.696664 -281.270942)
			(xy 95.747841 -281.262836) (xy 95.799655 -281.262836) (xy 95.850832 -281.270942) (xy 95.900111 -281.286954)
			(xy 95.946278 -281.310477) (xy 95.988197 -281.340933) (xy 96.024835 -281.377571) (xy 96.055291 -281.41949)
			(xy 96.078814 -281.465657) (xy 96.094826 -281.514936) (xy 96.102932 -281.566113) (xy 96.10344 -281.59202)
			(xy 97.323656 -281.59202) (xy 97.32415 -281.566675) (xy 97.33192 -281.516583) (xy 97.347266 -281.468271)
			(xy 97.369824 -281.422876) (xy 97.399064 -281.381469) (xy 97.434298 -281.345025) (xy 97.474693 -281.314403)
			(xy 97.5193 -281.290323) (xy 97.567066 -281.273355) (xy 97.59188 -281.26817) (xy 97.61474 -281.263852)
			(xy 97.819718 -280.909014) (xy 97.811844 -280.88717) (xy 97.803259 -280.860753) (xy 97.794066 -280.805977)
			(xy 97.793556 -280.778204) (xy 97.794064 -280.752317) (xy 97.802163 -280.701179) (xy 97.818162 -280.651939)
			(xy 97.841668 -280.605807) (xy 97.8721 -280.56392) (xy 97.90871 -280.52731) (xy 97.950597 -280.496878)
			(xy 97.996729 -280.473372) (xy 98.045969 -280.457373) (xy 98.097107 -280.449274) (xy 98.148881 -280.449274)
			(xy 98.200019 -280.457373) (xy 98.249259 -280.473372) (xy 98.295391 -280.496878) (xy 98.337278 -280.52731)
			(xy 98.373888 -280.56392) (xy 98.40432 -280.605807) (xy 98.427826 -280.651939) (xy 98.443825 -280.701179)
			(xy 98.451924 -280.752317) (xy 98.452432 -280.778204) (xy 100.612956 -280.778204) (xy 100.613464 -280.752317)
			(xy 100.621563 -280.701179) (xy 100.637562 -280.651939) (xy 100.661068 -280.605807) (xy 100.6915 -280.56392)
			(xy 100.72811 -280.52731) (xy 100.769997 -280.496878) (xy 100.816129 -280.473372) (xy 100.865369 -280.457373)
			(xy 100.916507 -280.449274) (xy 100.968281 -280.449274) (xy 101.019419 -280.457373) (xy 101.068659 -280.473372)
			(xy 101.114791 -280.496878) (xy 101.156678 -280.52731) (xy 101.193288 -280.56392) (xy 101.22372 -280.605807)
			(xy 101.247226 -280.651939) (xy 101.263225 -280.701179) (xy 101.271324 -280.752317) (xy 101.271832 -280.778204)
			(xy 103.432356 -280.778204) (xy 103.432864 -280.752317) (xy 103.440963 -280.701179) (xy 103.456962 -280.651939)
			(xy 103.480468 -280.605807) (xy 103.5109 -280.56392) (xy 103.54751 -280.52731) (xy 103.589397 -280.496878)
			(xy 103.635529 -280.473372) (xy 103.684769 -280.457373) (xy 103.735907 -280.449274) (xy 103.787681 -280.449274)
			(xy 103.838819 -280.457373) (xy 103.888059 -280.473372) (xy 103.934191 -280.496878) (xy 103.976078 -280.52731)
			(xy 104.012688 -280.56392) (xy 104.04312 -280.605807) (xy 104.066626 -280.651939) (xy 104.082625 -280.701179)
			(xy 104.090724 -280.752317) (xy 104.091232 -280.778204) (xy 104.372156 -280.778204) (xy 104.372678 -280.752871)
			(xy 104.380429 -280.702803) (xy 104.395748 -280.654509) (xy 104.418275 -280.609127) (xy 104.44748 -280.567726)
			(xy 104.482675 -280.531281) (xy 104.523032 -280.500649) (xy 104.567599 -280.476552) (xy 104.615329 -280.459556)
			(xy 104.640126 -280.454354) (xy 104.662986 -280.450036) (xy 104.868218 -280.09469) (xy 104.860598 -280.072592)
			(xy 104.851973 -280.04631) (xy 104.842659 -279.991789) (xy 104.842056 -279.964134) (xy 104.842564 -279.938227)
			(xy 104.85067 -279.88705) (xy 104.866682 -279.837771) (xy 104.890205 -279.791604) (xy 104.920661 -279.749685)
			(xy 104.957299 -279.713047) (xy 104.999218 -279.682591) (xy 105.045385 -279.659068) (xy 105.094664 -279.643056)
			(xy 105.145841 -279.63495) (xy 105.197655 -279.63495) (xy 105.248832 -279.643056) (xy 105.298111 -279.659068)
			(xy 105.344278 -279.682591) (xy 105.386197 -279.713047) (xy 105.422835 -279.749685) (xy 105.453291 -279.791604)
			(xy 105.476814 -279.837771) (xy 105.492826 -279.88705) (xy 105.500932 -279.938227) (xy 105.50144 -279.964134)
			(xy 105.501001 -279.989499) (xy 105.500926 -279.989983) (xy 336.806103 -279.989983) (xy 336.806103 -279.938217)
			(xy 336.814201 -279.887089) (xy 336.830196 -279.837856) (xy 336.853696 -279.791732) (xy 336.884121 -279.749851)
			(xy 336.920722 -279.713245) (xy 336.9626 -279.682815) (xy 337.008721 -279.659311) (xy 337.057952 -279.64331)
			(xy 337.109079 -279.635206) (xy 337.134962 -279.634696) (xy 337.160473 -279.635206) (xy 337.210886 -279.64306)
			(xy 337.259487 -279.658588) (xy 337.305115 -279.681418) (xy 337.346681 -279.711006) (xy 337.383193 -279.746643)
			(xy 337.398868 -279.766776) (xy 337.810856 -279.766776) (xy 337.826548 -279.746656) (xy 337.863055 -279.711012)
			(xy 337.904617 -279.681418) (xy 337.950241 -279.658579) (xy 337.998839 -279.643041) (xy 338.049251 -279.635176)
			(xy 338.074762 -279.634696) (xy 338.100656 -279.635106) (xy 338.151807 -279.643203) (xy 338.201062 -279.659201)
			(xy 338.247208 -279.682709) (xy 338.289107 -279.713146) (xy 338.325729 -279.749764) (xy 338.356171 -279.79166)
			(xy 338.379684 -279.837803) (xy 338.395689 -279.887056) (xy 338.403791 -279.938206) (xy 338.403791 -279.964134)
			(xy 344.323924 -279.964134) (xy 344.324432 -279.938227) (xy 344.332538 -279.88705) (xy 344.34855 -279.837771)
			(xy 344.372073 -279.791604) (xy 344.402529 -279.749685) (xy 344.439167 -279.713047) (xy 344.481086 -279.682591)
			(xy 344.527253 -279.659068) (xy 344.576532 -279.643056) (xy 344.627709 -279.63495) (xy 344.679523 -279.63495)
			(xy 344.7307 -279.643056) (xy 344.779979 -279.659068) (xy 344.826146 -279.682591) (xy 344.868065 -279.713047)
			(xy 344.904703 -279.749685) (xy 344.935159 -279.791604) (xy 344.958682 -279.837771) (xy 344.974694 -279.88705)
			(xy 344.9828 -279.938227) (xy 344.983308 -279.964134) (xy 344.982671 -279.991925) (xy 344.973225 -280.046702)
			(xy 344.964512 -280.0731) (xy 344.956892 -280.095198) (xy 345.16187 -280.450036) (xy 345.18473 -280.454354)
			(xy 345.209535 -280.459531) (xy 345.257274 -280.476523) (xy 345.30185 -280.500619) (xy 345.342215 -280.531252)
			(xy 345.377417 -280.5677) (xy 345.406629 -280.609105) (xy 345.429161 -280.654492) (xy 345.444484 -280.702792)
			(xy 345.452236 -280.752868) (xy 345.4527 -280.778204) (xy 345.452192 -280.804091) (xy 345.444093 -280.855229)
			(xy 345.428094 -280.904469) (xy 345.404588 -280.950601) (xy 345.374156 -280.992488) (xy 345.337546 -281.029098)
			(xy 345.295659 -281.05953) (xy 345.249527 -281.083036) (xy 345.200287 -281.099035) (xy 345.149149 -281.107134)
			(xy 345.097375 -281.107134) (xy 345.046237 -281.099035) (xy 344.996997 -281.083036) (xy 344.950865 -281.05953)
			(xy 344.908978 -281.029098) (xy 344.872368 -280.992488) (xy 344.841936 -280.950601) (xy 344.81843 -280.904469)
			(xy 344.802431 -280.855229) (xy 344.794332 -280.804091) (xy 344.793824 -280.778204) (xy 344.794353 -280.750496)
			(xy 344.803549 -280.695849) (xy 344.812112 -280.669492) (xy 344.819986 -280.647394) (xy 344.614754 -280.292302)
			(xy 344.591894 -280.287984) (xy 344.567101 -280.282754) (xy 344.519365 -280.265768) (xy 344.47479 -280.241678)
			(xy 344.434426 -280.211052) (xy 344.399223 -280.174611) (xy 344.37001 -280.133213) (xy 344.347475 -280.087832)
			(xy 344.332148 -280.039538) (xy 344.32439 -279.989468) (xy 344.323924 -279.964134) (xy 338.403791 -279.964134)
			(xy 338.403791 -279.989994) (xy 338.395689 -280.041144) (xy 338.379684 -280.090397) (xy 338.356171 -280.13654)
			(xy 338.325729 -280.178436) (xy 338.289107 -280.215054) (xy 338.247208 -280.245491) (xy 338.201062 -280.268999)
			(xy 338.151807 -280.284997) (xy 338.100656 -280.293094) (xy 338.074762 -280.293572) (xy 338.049249 -280.293131)
			(xy 337.998832 -280.285263) (xy 337.950229 -280.269723) (xy 337.9046 -280.24688) (xy 337.863036 -280.21728)
			(xy 337.826528 -280.18163) (xy 337.810856 -280.161492) (xy 337.398868 -280.161492) (xy 337.383211 -280.181641)
			(xy 337.346698 -280.217284) (xy 337.305129 -280.246877) (xy 337.259498 -280.269711) (xy 337.210893 -280.285241)
			(xy 337.160475 -280.293097) (xy 337.134962 -280.293572) (xy 337.109079 -280.292994) (xy 337.057952 -280.28489)
			(xy 337.008721 -280.268889) (xy 336.9626 -280.245385) (xy 336.920722 -280.214955) (xy 336.884121 -280.178349)
			(xy 336.853696 -280.136468) (xy 336.830196 -280.090344) (xy 336.814201 -280.041111) (xy 336.806103 -279.989983)
			(xy 105.500926 -279.989983) (xy 105.493248 -280.039631) (xy 105.4779 -280.087982) (xy 105.45532 -280.133408)
			(xy 105.426041 -280.174835) (xy 105.390757 -280.211282) (xy 105.350301 -280.241888) (xy 105.305631 -280.26593)
			(xy 105.257803 -280.282837) (xy 105.232962 -280.287984) (xy 105.209848 -280.292302) (xy 105.00487 -280.647394)
			(xy 105.012744 -280.669492) (xy 105.021304 -280.69585) (xy 105.030503 -280.750496) (xy 105.031032 -280.778204)
			(xy 105.030524 -280.804091) (xy 105.030521 -280.804107) (xy 105.31222 -280.804107) (xy 105.31222 -280.752293)
			(xy 105.320326 -280.701118) (xy 105.336337 -280.65184) (xy 105.359859 -280.605674) (xy 105.390314 -280.563756)
			(xy 105.426951 -280.527118) (xy 105.468869 -280.496662) (xy 105.515035 -280.473139) (xy 105.564312 -280.457127)
			(xy 105.615487 -280.449021) (xy 105.641394 -280.448512) (xy 105.666906 -280.448992) (xy 105.717321 -280.456852)
			(xy 105.765922 -280.472385) (xy 105.811551 -280.495221) (xy 105.853116 -280.524814) (xy 105.889626 -280.560457)
			(xy 105.9053 -280.580592) (xy 106.317288 -280.580592) (xy 106.332966 -280.560461) (xy 106.369475 -280.524817)
			(xy 106.41104 -280.495223) (xy 106.456667 -280.472386) (xy 106.505268 -280.456852) (xy 106.555682 -280.44899)
			(xy 106.581194 -280.448512) (xy 106.607104 -280.448985) (xy 106.658286 -280.457091) (xy 106.70757 -280.473103)
			(xy 106.753743 -280.496628) (xy 106.795666 -280.527087) (xy 106.832309 -280.563729) (xy 106.862768 -280.605652)
			(xy 106.886294 -280.651824) (xy 106.902308 -280.701108) (xy 106.910414 -280.75229) (xy 106.910414 -280.804105)
			(xy 334.45632 -280.804105) (xy 334.45632 -280.752295) (xy 334.464425 -280.701122) (xy 334.480434 -280.651848)
			(xy 334.503953 -280.605684) (xy 334.534405 -280.563767) (xy 334.571038 -280.527129) (xy 334.612951 -280.496673)
			(xy 334.659113 -280.473148) (xy 334.708385 -280.457133) (xy 334.759557 -280.449023) (xy 334.785462 -280.448512)
			(xy 334.810955 -280.449019) (xy 334.861331 -280.456875) (xy 334.909894 -280.472404) (xy 334.955481 -280.495237)
			(xy 334.997003 -280.524825) (xy 335.033465 -280.560462) (xy 335.049114 -280.580592) (xy 335.46161 -280.580592)
			(xy 335.477279 -280.560477) (xy 335.513736 -280.524835) (xy 335.555252 -280.495239) (xy 335.600835 -280.472399)
			(xy 335.649395 -280.45686) (xy 335.699769 -280.448993) (xy 335.725262 -280.448512) (xy 335.751174 -280.448983)
			(xy 335.80236 -280.457084) (xy 335.851648 -280.473094) (xy 335.897825 -280.496618) (xy 335.939753 -280.527076)
			(xy 335.9764 -280.563718) (xy 336.006863 -280.605643) (xy 336.030391 -280.651817) (xy 336.046407 -280.701103)
			(xy 336.054514 -280.752288) (xy 336.054514 -280.804112) (xy 336.046407 -280.855297) (xy 336.030391 -280.904583)
			(xy 336.006863 -280.950757) (xy 335.9764 -280.992682) (xy 335.939753 -281.029324) (xy 335.897825 -281.059782)
			(xy 335.851648 -281.083306) (xy 335.80236 -281.099316) (xy 335.751174 -281.107417) (xy 335.725262 -281.107896)
			(xy 335.699767 -281.107441) (xy 335.649389 -281.099574) (xy 335.600825 -281.084033) (xy 335.555238 -281.061192)
			(xy 335.513718 -281.031594) (xy 335.477257 -280.99595) (xy 335.46161 -280.975816) (xy 335.049114 -280.975816)
			(xy 335.033491 -280.995969) (xy 334.997025 -281.031609) (xy 334.955498 -281.061199) (xy 334.909906 -281.084033)
			(xy 334.861339 -281.099564) (xy 334.810957 -281.107421) (xy 334.785462 -281.107896) (xy 334.759557 -281.107377)
			(xy 334.708385 -281.099267) (xy 334.659113 -281.083252) (xy 334.612951 -281.059727) (xy 334.571038 -281.029271)
			(xy 334.534405 -280.992633) (xy 334.503953 -280.950716) (xy 334.480434 -280.904552) (xy 334.464425 -280.855278)
			(xy 334.45632 -280.804105) (xy 106.910414 -280.804105) (xy 106.910414 -280.80411) (xy 106.902308 -280.855292)
			(xy 106.886294 -280.904576) (xy 106.862768 -280.950748) (xy 106.832309 -280.992671) (xy 106.795666 -281.029313)
			(xy 106.753743 -281.059772) (xy 106.70757 -281.083297) (xy 106.658286 -281.099309) (xy 106.607104 -281.107415)
			(xy 106.581194 -281.107896) (xy 106.555682 -281.107421) (xy 106.505267 -281.09956) (xy 106.456665 -281.084025)
			(xy 106.411037 -281.061188) (xy 106.369472 -281.031595) (xy 106.332962 -280.995951) (xy 106.317288 -280.975816)
			(xy 105.9053 -280.975816) (xy 105.889631 -280.995955) (xy 105.85312 -281.031598) (xy 105.811553 -281.06119)
			(xy 105.765924 -281.084026) (xy 105.717322 -281.099559) (xy 105.666906 -281.107419) (xy 105.641394 -281.107896)
			(xy 105.615487 -281.107379) (xy 105.564312 -281.099273) (xy 105.515035 -281.083261) (xy 105.468869 -281.059738)
			(xy 105.426951 -281.029282) (xy 105.390314 -280.992644) (xy 105.359859 -280.950726) (xy 105.336337 -280.90456)
			(xy 105.320326 -280.855282) (xy 105.31222 -280.804107) (xy 105.030521 -280.804107) (xy 105.022425 -280.855229)
			(xy 105.006426 -280.904469) (xy 104.98292 -280.950601) (xy 104.952488 -280.992488) (xy 104.915878 -281.029098)
			(xy 104.873991 -281.05953) (xy 104.827859 -281.083036) (xy 104.778619 -281.099035) (xy 104.727481 -281.107134)
			(xy 104.675707 -281.107134) (xy 104.624569 -281.099035) (xy 104.575329 -281.083036) (xy 104.529197 -281.05953)
			(xy 104.48731 -281.029098) (xy 104.4507 -280.992488) (xy 104.420268 -280.950601) (xy 104.396762 -280.904469)
			(xy 104.380763 -280.855229) (xy 104.372664 -280.804091) (xy 104.372156 -280.778204) (xy 104.091232 -280.778204)
			(xy 104.091232 -280.778712) (xy 104.090641 -280.806228) (xy 104.081455 -280.860489) (xy 104.072944 -280.886662)
			(xy 104.065324 -280.908506) (xy 104.270556 -281.263852) (xy 104.293416 -281.26817) (xy 104.318226 -281.273386)
			(xy 104.366003 -281.290334) (xy 104.410622 -281.314398) (xy 104.451028 -281.345012) (xy 104.48627 -281.381453)
			(xy 104.515516 -281.422861) (xy 104.538075 -281.468259) (xy 104.553416 -281.516576) (xy 104.561176 -281.566673)
			(xy 104.56164 -281.59202) (xy 105.781856 -281.59202) (xy 105.782364 -281.566113) (xy 105.79047 -281.514936)
			(xy 105.806482 -281.465657) (xy 105.830005 -281.41949) (xy 105.860461 -281.377571) (xy 105.897099 -281.340933)
			(xy 105.939018 -281.310477) (xy 105.985185 -281.286954) (xy 106.034464 -281.270942) (xy 106.085641 -281.262836)
			(xy 106.137455 -281.262836) (xy 106.188632 -281.270942) (xy 106.237911 -281.286954) (xy 106.284078 -281.310477)
			(xy 106.325997 -281.340933) (xy 106.362635 -281.377571) (xy 106.393091 -281.41949) (xy 106.416614 -281.465657)
			(xy 106.432626 -281.514936) (xy 106.440732 -281.566113) (xy 106.44124 -281.59202) (xy 106.44067 -281.619802)
			(xy 106.431345 -281.674578) (xy 106.422698 -281.700986) (xy 106.414824 -281.72283) (xy 106.619802 -282.077668)
			(xy 106.642662 -282.081986) (xy 106.667464 -282.087182) (xy 106.715205 -282.104167) (xy 106.759784 -282.128258)
			(xy 106.800151 -282.158887) (xy 106.835356 -282.195333) (xy 106.864568 -282.236737) (xy 106.8871 -282.282123)
			(xy 106.902422 -282.330424) (xy 106.910171 -282.3805) (xy 106.910632 -282.405836) (xy 334.456024 -282.405836)
			(xy 334.456468 -282.38049) (xy 334.46425 -282.330397) (xy 334.479605 -282.282085) (xy 334.502171 -282.236692)
			(xy 334.531418 -282.195286) (xy 334.566656 -282.158843) (xy 334.607056 -282.128222) (xy 334.651665 -282.104142)
			(xy 334.699433 -282.087172) (xy 334.724248 -282.081986) (xy 334.747108 -282.077668) (xy 334.952086 -281.722576)
			(xy 334.944466 -281.700732) (xy 334.93582 -281.67439) (xy 334.926507 -281.619739) (xy 334.925924 -281.59202)
			(xy 334.926432 -281.566113) (xy 334.934538 -281.514936) (xy 334.95055 -281.465657) (xy 334.974073 -281.41949)
			(xy 335.004529 -281.377571) (xy 335.041167 -281.340933) (xy 335.083086 -281.310477) (xy 335.129253 -281.286954)
			(xy 335.178532 -281.270942) (xy 335.229709 -281.262836) (xy 335.281523 -281.262836) (xy 335.3327 -281.270942)
			(xy 335.381979 -281.286954) (xy 335.428146 -281.310477) (xy 335.470065 -281.340933) (xy 335.506703 -281.377571)
			(xy 335.537159 -281.41949) (xy 335.560682 -281.465657) (xy 335.576694 -281.514936) (xy 335.5848 -281.566113)
			(xy 335.585308 -281.59202) (xy 336.805524 -281.59202) (xy 336.806044 -281.566676) (xy 336.813813 -281.516587)
			(xy 336.829157 -281.468277) (xy 336.851713 -281.422884) (xy 336.88095 -281.381477) (xy 336.916179 -281.345033)
			(xy 336.956571 -281.31441) (xy 337.001174 -281.290329) (xy 337.048936 -281.273357) (xy 337.073748 -281.26817)
			(xy 337.096608 -281.263852) (xy 337.301586 -280.909014) (xy 337.293966 -280.88717) (xy 337.285321 -280.860761)
			(xy 337.276 -280.805986) (xy 337.275424 -280.778204) (xy 337.275919 -280.752309) (xy 337.284017 -280.701155)
			(xy 337.300013 -280.651897) (xy 337.323515 -280.605746) (xy 337.353945 -280.563837) (xy 337.390553 -280.527202)
			(xy 337.432439 -280.496742) (xy 337.478573 -280.473206) (xy 337.527819 -280.457173) (xy 337.578967 -280.449038)
			(xy 337.604862 -280.448512) (xy 337.630738 -280.449004) (xy 337.681855 -280.457091) (xy 337.731077 -280.473073)
			(xy 337.777195 -280.496556) (xy 337.819073 -280.526962) (xy 337.855681 -280.563542) (xy 337.886118 -280.605398)
			(xy 337.909634 -280.651499) (xy 337.925652 -280.70071) (xy 337.933777 -280.75182) (xy 337.9343 -280.777696)
			(xy 337.9343 -280.778204) (xy 340.094824 -280.778204) (xy 340.095293 -280.752294) (xy 340.103399 -280.701112)
			(xy 340.119413 -280.651828) (xy 340.142939 -280.605656) (xy 340.173399 -280.563733) (xy 340.210042 -280.527091)
			(xy 340.251966 -280.496633) (xy 340.298139 -280.473108) (xy 340.347423 -280.457097) (xy 340.398606 -280.448992)
			(xy 340.424516 -280.448512) (xy 340.450394 -280.448954) (xy 340.501512 -280.457049) (xy 340.550736 -280.473038)
			(xy 340.596853 -280.496528) (xy 340.638731 -280.52694) (xy 340.675338 -280.563526) (xy 340.705774 -280.605386)
			(xy 340.729289 -280.651491) (xy 340.745307 -280.700705) (xy 340.753431 -280.751819) (xy 340.753954 -280.777696)
			(xy 340.753954 -280.778204) (xy 340.753418 -280.804105) (xy 342.91452 -280.804105) (xy 342.91452 -280.752295)
			(xy 342.922625 -280.701122) (xy 342.938634 -280.651848) (xy 342.962153 -280.605684) (xy 342.992605 -280.563767)
			(xy 343.029238 -280.527129) (xy 343.071151 -280.496673) (xy 343.117313 -280.473148) (xy 343.166585 -280.457133)
			(xy 343.217757 -280.449023) (xy 343.243662 -280.448512) (xy 343.269173 -280.449015) (xy 343.319587 -280.45687)
			(xy 343.368188 -280.472399) (xy 343.413817 -280.49523) (xy 343.455383 -280.524819) (xy 343.491894 -280.560459)
			(xy 343.507568 -280.580592) (xy 343.91981 -280.580592) (xy 343.935476 -280.56045) (xy 343.971987 -280.524807)
			(xy 344.013554 -280.495214) (xy 344.059184 -280.472379) (xy 344.107788 -280.456847) (xy 344.158204 -280.448988)
			(xy 344.183716 -280.448512) (xy 344.209623 -280.449014) (xy 344.260798 -280.457121) (xy 344.310075 -280.473134)
			(xy 344.356241 -280.496659) (xy 344.398158 -280.527115) (xy 344.434795 -280.563754) (xy 344.465249 -280.605673)
			(xy 344.488772 -280.65184) (xy 344.504782 -280.701117) (xy 344.512888 -280.752293) (xy 344.512888 -280.804107)
			(xy 344.504782 -280.855283) (xy 344.488772 -280.90456) (xy 344.465249 -280.950727) (xy 344.434795 -280.992646)
			(xy 344.398158 -281.029285) (xy 344.356241 -281.059741) (xy 344.310075 -281.083266) (xy 344.260798 -281.099279)
			(xy 344.209623 -281.107386) (xy 344.183716 -281.107896) (xy 344.158205 -281.107405) (xy 344.107791 -281.099547)
			(xy 344.059189 -281.084016) (xy 344.013561 -281.061182) (xy 343.971995 -281.031591) (xy 343.935484 -280.99595)
			(xy 343.91981 -280.975816) (xy 343.507568 -280.975816) (xy 343.491917 -280.99597) (xy 343.455403 -281.031612)
			(xy 343.413832 -281.061203) (xy 343.368199 -281.084036) (xy 343.319593 -281.099566) (xy 343.269175 -281.107421)
			(xy 343.243662 -281.107896) (xy 343.217757 -281.107377) (xy 343.166585 -281.099267) (xy 343.117313 -281.083252)
			(xy 343.071151 -281.059727) (xy 343.029238 -281.029271) (xy 342.992605 -280.992633) (xy 342.962153 -280.950716)
			(xy 342.938634 -280.904552) (xy 342.922625 -280.855278) (xy 342.91452 -280.804105) (xy 340.753418 -280.804105)
			(xy 340.753379 -280.805986) (xy 340.744058 -280.860762) (xy 340.735412 -280.88717) (xy 340.727792 -280.909014)
			(xy 340.93277 -281.263852) (xy 340.95563 -281.26817) (xy 340.980439 -281.273332) (xy 341.028178 -281.290325)
			(xy 341.072756 -281.314423) (xy 341.113121 -281.345058) (xy 341.148323 -281.381508) (xy 341.177534 -281.422915)
			(xy 341.200066 -281.468304) (xy 341.215387 -281.516606) (xy 341.223138 -281.566683) (xy 341.2236 -281.59202)
			(xy 341.223092 -281.617907) (xy 341.214993 -281.669045) (xy 341.198994 -281.718285) (xy 341.175488 -281.764417)
			(xy 341.145056 -281.806304) (xy 341.108446 -281.842914) (xy 341.066559 -281.873346) (xy 341.020427 -281.896852)
			(xy 340.971187 -281.912851) (xy 340.920049 -281.92095) (xy 340.868275 -281.92095) (xy 340.817137 -281.912851)
			(xy 340.767897 -281.896852) (xy 340.721765 -281.873346) (xy 340.679878 -281.842914) (xy 340.643268 -281.806304)
			(xy 340.612836 -281.764417) (xy 340.58933 -281.718285) (xy 340.573331 -281.669045) (xy 340.565232 -281.617907)
			(xy 340.564724 -281.59202) (xy 340.565273 -281.564313) (xy 340.574459 -281.509667) (xy 340.583012 -281.483308)
			(xy 340.590632 -281.461464) (xy 340.385654 -281.106372) (xy 340.362794 -281.102054) (xy 340.337994 -281.096852)
			(xy 340.290256 -281.079864) (xy 340.24568 -281.055771) (xy 340.205315 -281.025142) (xy 340.170112 -280.988697)
			(xy 340.140899 -280.947295) (xy 340.118366 -280.901911) (xy 340.103042 -280.853613) (xy 340.095288 -280.803539)
			(xy 340.094824 -280.778204) (xy 337.9343 -280.778204) (xy 337.933779 -280.803526) (xy 337.926048 -280.853575)
			(xy 337.910753 -280.901853) (xy 337.888254 -280.947223) (xy 337.859081 -280.988619) (xy 337.82392 -281.025066)
			(xy 337.783598 -281.055707) (xy 337.739064 -281.07982) (xy 337.691367 -281.096838) (xy 337.666584 -281.102054)
			(xy 337.643724 -281.106372) (xy 337.438746 -281.46121) (xy 337.446366 -281.483054) (xy 337.454977 -281.50934)
			(xy 337.464301 -281.563858) (xy 337.464908 -281.591512) (xy 337.464908 -281.59202) (xy 337.4644 -281.617904)
			(xy 338.685436 -281.617904) (xy 338.685436 -281.566096) (xy 338.69354 -281.514926) (xy 338.709548 -281.465654)
			(xy 338.733067 -281.419492) (xy 338.763517 -281.377577) (xy 338.800148 -281.340942) (xy 338.84206 -281.310487)
			(xy 338.888219 -281.286963) (xy 338.937489 -281.270949) (xy 338.988658 -281.262839) (xy 339.014562 -281.262328)
			(xy 339.040073 -281.262825) (xy 339.090487 -281.270681) (xy 339.139089 -281.28621) (xy 339.184718 -281.309042)
			(xy 339.226284 -281.338633) (xy 339.262794 -281.374274) (xy 339.278468 -281.394408) (xy 339.690456 -281.394408)
			(xy 339.706157 -281.374295) (xy 339.742661 -281.33865) (xy 339.784221 -281.309053) (xy 339.829844 -281.286213)
			(xy 339.878441 -281.270675) (xy 339.928852 -281.262808) (xy 339.954362 -281.262328) (xy 339.980275 -281.262767)
			(xy 340.031464 -281.270869) (xy 340.080754 -281.286879) (xy 340.126933 -281.310404) (xy 340.168863 -281.340863)
			(xy 340.205512 -281.377508) (xy 340.235976 -281.419434) (xy 340.259506 -281.465611) (xy 340.275522 -281.514899)
			(xy 340.28363 -281.566087) (xy 340.28363 -281.617913) (xy 340.275522 -281.669101) (xy 340.259506 -281.718389)
			(xy 340.235976 -281.764566) (xy 340.205512 -281.806492) (xy 340.168863 -281.843137) (xy 340.126933 -281.873596)
			(xy 340.080754 -281.897121) (xy 340.031464 -281.913131) (xy 339.980275 -281.921233) (xy 339.954362 -281.921712)
			(xy 339.928849 -281.921255) (xy 339.878434 -281.913389) (xy 339.829832 -281.89785) (xy 339.784204 -281.87501)
			(xy 339.742639 -281.845414) (xy 339.706129 -281.809768) (xy 339.690456 -281.789632) (xy 339.278468 -281.789632)
			(xy 339.262822 -281.80979) (xy 339.226306 -281.845431) (xy 339.184734 -281.875021) (xy 339.139101 -281.897853)
			(xy 339.090494 -281.913382) (xy 339.040076 -281.921238) (xy 339.014562 -281.921712) (xy 338.988658 -281.921161)
			(xy 338.937489 -281.913051) (xy 338.888219 -281.897037) (xy 338.84206 -281.873513) (xy 338.800148 -281.843058)
			(xy 338.763517 -281.806423) (xy 338.733067 -281.764508) (xy 338.709548 -281.718346) (xy 338.69354 -281.669074)
			(xy 338.685436 -281.617904) (xy 337.4644 -281.617904) (xy 337.4644 -281.617927) (xy 337.456294 -281.669104)
			(xy 337.440282 -281.718383) (xy 337.416759 -281.76455) (xy 337.386303 -281.806469) (xy 337.349665 -281.843107)
			(xy 337.307746 -281.873563) (xy 337.261579 -281.897086) (xy 337.2123 -281.913098) (xy 337.161123 -281.921204)
			(xy 337.109309 -281.921204) (xy 337.058132 -281.913098) (xy 337.008853 -281.897086) (xy 336.962686 -281.873563)
			(xy 336.920767 -281.843107) (xy 336.884129 -281.806469) (xy 336.853673 -281.76455) (xy 336.83015 -281.718383)
			(xy 336.814138 -281.669104) (xy 336.806032 -281.617927) (xy 336.805524 -281.59202) (xy 335.585308 -281.59202)
			(xy 335.584798 -281.617364) (xy 335.577024 -281.667452) (xy 335.561677 -281.715761) (xy 335.539118 -281.761152)
			(xy 335.50988 -281.802558) (xy 335.47465 -281.839001) (xy 335.434259 -281.869625) (xy 335.389657 -281.893707)
			(xy 335.341896 -281.910681) (xy 335.317084 -281.91587) (xy 335.294224 -281.920188) (xy 335.089246 -282.27528)
			(xy 335.096866 -282.297124) (xy 335.1055 -282.32347) (xy 335.114821 -282.378118) (xy 335.115408 -282.405836)
			(xy 335.395824 -282.405836) (xy 335.396332 -282.379949) (xy 335.404431 -282.328811) (xy 335.42043 -282.279571)
			(xy 335.443936 -282.233439) (xy 335.474368 -282.191552) (xy 335.510978 -282.154942) (xy 335.552865 -282.12451)
			(xy 335.598997 -282.101004) (xy 335.648237 -282.085005) (xy 335.699375 -282.076906) (xy 335.751149 -282.076906)
			(xy 335.802287 -282.085005) (xy 335.851527 -282.101004) (xy 335.897659 -282.12451) (xy 335.939546 -282.154942)
			(xy 335.976156 -282.191552) (xy 336.006588 -282.233439) (xy 336.030094 -282.279571) (xy 336.046093 -282.328811)
			(xy 336.054192 -282.379949) (xy 336.0547 -282.405836) (xy 336.054214 -282.431707) (xy 336.336126 -282.431707)
			(xy 336.336126 -282.379893) (xy 336.344232 -282.328716) (xy 336.360244 -282.279437) (xy 336.383768 -282.23327)
			(xy 336.414225 -282.191352) (xy 336.450864 -282.154714) (xy 336.492784 -282.12426) (xy 336.538952 -282.100738)
			(xy 336.588231 -282.084728) (xy 336.639409 -282.076625) (xy 336.665316 -282.076144) (xy 336.690811 -282.076599)
			(xy 336.74119 -282.084464) (xy 336.789755 -282.100003) (xy 336.835342 -282.122845) (xy 336.876862 -282.152443)
			(xy 336.913321 -282.188089) (xy 336.928968 -282.208224) (xy 337.341464 -282.208224) (xy 337.35711 -282.18809)
			(xy 337.393571 -282.152447) (xy 337.435092 -282.122853) (xy 337.480679 -282.100016) (xy 337.529243 -282.084481)
			(xy 337.579622 -282.076621) (xy 337.605116 -282.076144) (xy 337.631025 -282.076581) (xy 337.682206 -282.08469)
			(xy 337.731488 -282.100704) (xy 337.777658 -282.124231) (xy 337.819579 -282.154691) (xy 337.85622 -282.191333)
			(xy 337.886677 -282.233256) (xy 337.910202 -282.279427) (xy 337.926214 -282.32871) (xy 337.93432 -282.379891)
			(xy 337.93432 -282.431709) (xy 337.926214 -282.48289) (xy 337.910202 -282.532173) (xy 337.886677 -282.578344)
			(xy 337.85622 -282.620267) (xy 337.819579 -282.656909) (xy 337.777658 -282.687369) (xy 337.731488 -282.710896)
			(xy 337.682206 -282.72691) (xy 337.631025 -282.735019) (xy 337.605116 -282.735528) (xy 337.579623 -282.735021)
			(xy 337.529248 -282.727163) (xy 337.480686 -282.711632) (xy 337.435099 -282.6888) (xy 337.393577 -282.659213)
			(xy 337.357114 -282.623577) (xy 337.341464 -282.603448) (xy 336.928968 -282.603448) (xy 336.913322 -282.623582)
			(xy 336.876859 -282.659221) (xy 336.835338 -282.688813) (xy 336.78975 -282.71165) (xy 336.741187 -282.727186)
			(xy 336.69081 -282.735049) (xy 336.665316 -282.735528) (xy 336.639409 -282.734975) (xy 336.588231 -282.726872)
			(xy 336.538952 -282.710862) (xy 336.492784 -282.68734) (xy 336.450864 -282.656886) (xy 336.414225 -282.620248)
			(xy 336.383768 -282.57833) (xy 336.360244 -282.532163) (xy 336.344232 -282.482884) (xy 336.336126 -282.431707)
			(xy 336.054214 -282.431707) (xy 336.054179 -282.433545) (xy 336.044978 -282.488191) (xy 336.036412 -282.514548)
			(xy 336.028538 -282.536646) (xy 336.23377 -282.891738) (xy 336.25663 -282.896056) (xy 336.281436 -282.901231)
			(xy 336.329174 -282.918223) (xy 336.373751 -282.94232) (xy 336.414116 -282.972953) (xy 336.449318 -283.009401)
			(xy 336.478529 -283.050806) (xy 336.501062 -283.096194) (xy 336.516384 -283.144494) (xy 336.524137 -283.19457)
			(xy 336.5246 -283.219906) (xy 338.685124 -283.219906) (xy 338.685593 -283.194571) (xy 338.693345 -283.144497)
			(xy 338.708668 -283.096199) (xy 338.731201 -283.050814) (xy 338.760412 -283.009411) (xy 338.795615 -282.972966)
			(xy 338.83598 -282.942336) (xy 338.880556 -282.918243) (xy 338.928293 -282.901254) (xy 338.953094 -282.896056)
			(xy 338.975954 -282.891738) (xy 339.181186 -282.536392) (xy 339.173566 -282.514548) (xy 339.164924 -282.488205)
			(xy 339.155609 -282.433555) (xy 339.155024 -282.405836) (xy 339.155532 -282.379929) (xy 339.163638 -282.328752)
			(xy 339.17965 -282.279473) (xy 339.203173 -282.233306) (xy 339.233629 -282.191387) (xy 339.270267 -282.154749)
			(xy 339.312186 -282.124293) (xy 339.358353 -282.10077) (xy 339.407632 -282.084758) (xy 339.458809 -282.076652)
			(xy 339.510623 -282.076652) (xy 339.5618 -282.084758) (xy 339.611079 -282.10077) (xy 339.657246 -282.124293)
			(xy 339.699165 -282.154749) (xy 339.735803 -282.191387) (xy 339.766259 -282.233306) (xy 339.789782 -282.279473)
			(xy 339.805794 -282.328752) (xy 339.8139 -282.379929) (xy 339.814408 -282.405836) (xy 341.034624 -282.405836)
			(xy 341.035068 -282.38049) (xy 341.04285 -282.330397) (xy 341.058205 -282.282085) (xy 341.080771 -282.236692)
			(xy 341.110018 -282.195286) (xy 341.145256 -282.158843) (xy 341.185656 -282.128222) (xy 341.230265 -282.104142)
			(xy 341.278033 -282.087172) (xy 341.302848 -282.081986) (xy 341.325708 -282.077668) (xy 341.530686 -281.72283)
			(xy 341.522812 -281.700986) (xy 341.514229 -281.674568) (xy 341.505035 -281.619792) (xy 341.504524 -281.59202)
			(xy 341.505032 -281.566133) (xy 341.513131 -281.514995) (xy 341.52913 -281.465755) (xy 341.552636 -281.419623)
			(xy 341.583068 -281.377736) (xy 341.619678 -281.341126) (xy 341.661565 -281.310694) (xy 341.707697 -281.287188)
			(xy 341.756937 -281.271189) (xy 341.808075 -281.26309) (xy 341.859849 -281.26309) (xy 341.910987 -281.271189)
			(xy 341.960227 -281.287188) (xy 342.006359 -281.310694) (xy 342.048246 -281.341126) (xy 342.084856 -281.377736)
			(xy 342.115288 -281.419623) (xy 342.138794 -281.465755) (xy 342.154793 -281.514995) (xy 342.162892 -281.566133)
			(xy 342.1634 -281.59202) (xy 342.162935 -281.617355) (xy 342.15518 -281.667428) (xy 342.139855 -281.715725)
			(xy 342.117321 -281.761109) (xy 342.088109 -281.802511) (xy 342.052906 -281.838956) (xy 342.012542 -281.869586)
			(xy 341.967967 -281.89368) (xy 341.92023 -281.910671) (xy 341.89543 -281.91587) (xy 341.87257 -281.920188)
			(xy 341.667592 -282.275026) (xy 341.675466 -282.297124) (xy 341.684085 -282.323474) (xy 341.693414 -282.378119)
			(xy 341.694008 -282.405836) (xy 342.914224 -282.405836) (xy 342.914629 -282.380499) (xy 342.922392 -282.330422)
			(xy 342.937724 -282.282122) (xy 342.960266 -282.236737) (xy 342.989485 -282.195335) (xy 343.024695 -282.15889)
			(xy 343.065066 -282.128262) (xy 343.109648 -282.10417) (xy 343.157391 -282.087183) (xy 343.182194 -282.081986)
			(xy 343.205054 -282.077668) (xy 343.410286 -281.722322) (xy 343.402666 -281.700478) (xy 343.39404 -281.674196)
			(xy 343.384726 -281.619675) (xy 343.384124 -281.59202) (xy 343.384632 -281.566113) (xy 343.392738 -281.514936)
			(xy 343.40875 -281.465657) (xy 343.432273 -281.41949) (xy 343.462729 -281.377571) (xy 343.499367 -281.340933)
			(xy 343.541286 -281.310477) (xy 343.587453 -281.286954) (xy 343.636732 -281.270942) (xy 343.687909 -281.262836)
			(xy 343.739723 -281.262836) (xy 343.7909 -281.270942) (xy 343.840179 -281.286954) (xy 343.886346 -281.310477)
			(xy 343.928265 -281.340933) (xy 343.964903 -281.377571) (xy 343.995359 -281.41949) (xy 344.018882 -281.465657)
			(xy 344.034894 -281.514936) (xy 344.043 -281.566113) (xy 344.043508 -281.59202) (xy 345.263724 -281.59202)
			(xy 345.264244 -281.566676) (xy 345.272013 -281.516587) (xy 345.287357 -281.468277) (xy 345.309913 -281.422884)
			(xy 345.33915 -281.381477) (xy 345.374379 -281.345033) (xy 345.414771 -281.31441) (xy 345.459374 -281.290329)
			(xy 345.507136 -281.273357) (xy 345.531948 -281.26817) (xy 345.554808 -281.263852) (xy 345.759786 -280.909014)
			(xy 345.751912 -280.88717) (xy 345.743326 -280.860753) (xy 345.734134 -280.805977) (xy 345.733624 -280.778204)
			(xy 345.734132 -280.752317) (xy 345.742231 -280.701179) (xy 345.75823 -280.651939) (xy 345.781736 -280.605807)
			(xy 345.812168 -280.56392) (xy 345.848778 -280.52731) (xy 345.890665 -280.496878) (xy 345.936797 -280.473372)
			(xy 345.986037 -280.457373) (xy 346.037175 -280.449274) (xy 346.088949 -280.449274) (xy 346.140087 -280.457373)
			(xy 346.189327 -280.473372) (xy 346.235459 -280.496878) (xy 346.277346 -280.52731) (xy 346.313956 -280.56392)
			(xy 346.344388 -280.605807) (xy 346.367894 -280.651939) (xy 346.383893 -280.701179) (xy 346.391992 -280.752317)
			(xy 346.3925 -280.778204) (xy 348.553024 -280.778204) (xy 348.553532 -280.752317) (xy 348.561631 -280.701179)
			(xy 348.57763 -280.651939) (xy 348.601136 -280.605807) (xy 348.631568 -280.56392) (xy 348.668178 -280.52731)
			(xy 348.710065 -280.496878) (xy 348.756197 -280.473372) (xy 348.805437 -280.457373) (xy 348.856575 -280.449274)
			(xy 348.908349 -280.449274) (xy 348.959487 -280.457373) (xy 349.008727 -280.473372) (xy 349.054859 -280.496878)
			(xy 349.096746 -280.52731) (xy 349.133356 -280.56392) (xy 349.163788 -280.605807) (xy 349.187294 -280.651939)
			(xy 349.203293 -280.701179) (xy 349.211392 -280.752317) (xy 349.2119 -280.778204) (xy 351.372424 -280.778204)
			(xy 351.372932 -280.752317) (xy 351.381031 -280.701179) (xy 351.39703 -280.651939) (xy 351.420536 -280.605807)
			(xy 351.450968 -280.56392) (xy 351.487578 -280.52731) (xy 351.529465 -280.496878) (xy 351.575597 -280.473372)
			(xy 351.624837 -280.457373) (xy 351.675975 -280.449274) (xy 351.727749 -280.449274) (xy 351.778887 -280.457373)
			(xy 351.828127 -280.473372) (xy 351.874259 -280.496878) (xy 351.916146 -280.52731) (xy 351.952756 -280.56392)
			(xy 351.983188 -280.605807) (xy 352.006694 -280.651939) (xy 352.022693 -280.701179) (xy 352.030792 -280.752317)
			(xy 352.0313 -280.778204) (xy 352.312224 -280.778204) (xy 352.312691 -280.752869) (xy 352.320444 -280.702795)
			(xy 352.335767 -280.654496) (xy 352.3583 -280.609112) (xy 352.387511 -280.567709) (xy 352.422714 -280.531263)
			(xy 352.463079 -280.500633) (xy 352.507655 -280.47654) (xy 352.555393 -280.459552) (xy 352.580194 -280.454354)
			(xy 352.603054 -280.450036) (xy 352.808286 -280.09469) (xy 352.800666 -280.072592) (xy 352.792043 -280.046309)
			(xy 352.782727 -279.991789) (xy 352.782124 -279.964134) (xy 352.782632 -279.938227) (xy 352.790738 -279.88705)
			(xy 352.80675 -279.837771) (xy 352.830273 -279.791604) (xy 352.860729 -279.749685) (xy 352.897367 -279.713047)
			(xy 352.939286 -279.682591) (xy 352.985453 -279.659068) (xy 353.034732 -279.643056) (xy 353.085909 -279.63495)
			(xy 353.137723 -279.63495) (xy 353.1889 -279.643056) (xy 353.238179 -279.659068) (xy 353.284346 -279.682591)
			(xy 353.326265 -279.713047) (xy 353.362903 -279.749685) (xy 353.393359 -279.791604) (xy 353.416882 -279.837771)
			(xy 353.432894 -279.88705) (xy 353.441 -279.938227) (xy 353.441508 -279.964134) (xy 353.441095 -279.9895)
			(xy 353.433341 -280.039635) (xy 353.417991 -280.087988) (xy 353.395408 -280.133416) (xy 353.366127 -280.174843)
			(xy 353.330839 -280.211291) (xy 353.290379 -280.241896) (xy 353.245705 -280.265935) (xy 353.197873 -280.282839)
			(xy 353.17303 -280.287984) (xy 353.149916 -280.292302) (xy 352.944938 -280.647394) (xy 352.952812 -280.669492)
			(xy 352.961371 -280.695851) (xy 352.970571 -280.750496) (xy 352.9711 -280.778204) (xy 352.970592 -280.804091)
			(xy 352.97059 -280.804105) (xy 353.25232 -280.804105) (xy 353.25232 -280.752295) (xy 353.260425 -280.701122)
			(xy 353.276434 -280.651848) (xy 353.299953 -280.605684) (xy 353.330405 -280.563767) (xy 353.367038 -280.527129)
			(xy 353.408951 -280.496673) (xy 353.455113 -280.473148) (xy 353.504385 -280.457133) (xy 353.555557 -280.449023)
			(xy 353.581462 -280.448512) (xy 353.606973 -280.449015) (xy 353.657387 -280.45687) (xy 353.705988 -280.472399)
			(xy 353.751617 -280.49523) (xy 353.793183 -280.524819) (xy 353.829694 -280.560459) (xy 353.845368 -280.580592)
			(xy 354.257356 -280.580592) (xy 354.273053 -280.560476) (xy 354.309558 -280.524831) (xy 354.351119 -280.495236)
			(xy 354.396742 -280.472396) (xy 354.44534 -280.456858) (xy 354.495751 -280.448992) (xy 354.521262 -280.448512)
			(xy 354.547174 -280.448983) (xy 354.59836 -280.457084) (xy 354.647648 -280.473094) (xy 354.693825 -280.496618)
			(xy 354.735753 -280.527076) (xy 354.7724 -280.563718) (xy 354.802863 -280.605643) (xy 354.826391 -280.651817)
			(xy 354.842407 -280.701103) (xy 354.850514 -280.752288) (xy 354.850514 -280.804112) (xy 354.842407 -280.855297)
			(xy 354.826391 -280.904583) (xy 354.802863 -280.950757) (xy 354.7724 -280.992682) (xy 354.735753 -281.029324)
			(xy 354.693825 -281.059782) (xy 354.647648 -281.083306) (xy 354.59836 -281.099316) (xy 354.547174 -281.107417)
			(xy 354.521262 -281.107896) (xy 354.495749 -281.107445) (xy 354.445333 -281.099578) (xy 354.396731 -281.084039)
			(xy 354.351103 -281.061198) (xy 354.309538 -281.031601) (xy 354.273029 -280.995953) (xy 354.257356 -280.975816)
			(xy 353.845368 -280.975816) (xy 353.829717 -280.99597) (xy 353.793203 -281.031612) (xy 353.751632 -281.061203)
			(xy 353.705999 -281.084036) (xy 353.657393 -281.099566) (xy 353.606975 -281.107421) (xy 353.581462 -281.107896)
			(xy 353.555557 -281.107377) (xy 353.504385 -281.099267) (xy 353.455113 -281.083252) (xy 353.408951 -281.059727)
			(xy 353.367038 -281.029271) (xy 353.330405 -280.992633) (xy 353.299953 -280.950716) (xy 353.276434 -280.904552)
			(xy 353.260425 -280.855278) (xy 353.25232 -280.804105) (xy 352.97059 -280.804105) (xy 352.962493 -280.855229)
			(xy 352.946494 -280.904469) (xy 352.922988 -280.950601) (xy 352.892556 -280.992488) (xy 352.855946 -281.029098)
			(xy 352.814059 -281.05953) (xy 352.767927 -281.083036) (xy 352.718687 -281.099035) (xy 352.667549 -281.107134)
			(xy 352.615775 -281.107134) (xy 352.564637 -281.099035) (xy 352.515397 -281.083036) (xy 352.469265 -281.05953)
			(xy 352.427378 -281.029098) (xy 352.390768 -280.992488) (xy 352.360336 -280.950601) (xy 352.33683 -280.904469)
			(xy 352.320831 -280.855229) (xy 352.312732 -280.804091) (xy 352.312224 -280.778204) (xy 352.0313 -280.778204)
			(xy 352.0313 -280.778712) (xy 352.03071 -280.806228) (xy 352.021524 -280.860489) (xy 352.013012 -280.886662)
			(xy 352.005392 -280.908506) (xy 352.210624 -281.263852) (xy 352.233484 -281.26817) (xy 352.258305 -281.273337)
			(xy 352.306082 -281.290294) (xy 352.350699 -281.314367) (xy 352.391104 -281.344988) (xy 352.426344 -281.381435)
			(xy 352.455588 -281.422848) (xy 352.478145 -281.46825) (xy 352.493485 -281.516571) (xy 352.501244 -281.566671)
			(xy 352.501708 -281.59202) (xy 353.721924 -281.59202) (xy 353.722432 -281.566113) (xy 353.730538 -281.514936)
			(xy 353.74655 -281.465657) (xy 353.770073 -281.41949) (xy 353.800529 -281.377571) (xy 353.837167 -281.340933)
			(xy 353.879086 -281.310477) (xy 353.925253 -281.286954) (xy 353.974532 -281.270942) (xy 354.025709 -281.262836)
			(xy 354.077523 -281.262836) (xy 354.1287 -281.270942) (xy 354.177979 -281.286954) (xy 354.224146 -281.310477)
			(xy 354.266065 -281.340933) (xy 354.302703 -281.377571) (xy 354.333159 -281.41949) (xy 354.356682 -281.465657)
			(xy 354.372694 -281.514936) (xy 354.3808 -281.566113) (xy 354.381308 -281.59202) (xy 354.380739 -281.619802)
			(xy 354.371414 -281.674578) (xy 354.362766 -281.700986) (xy 354.354892 -281.72283) (xy 354.55987 -282.077668)
			(xy 354.58273 -282.081986) (xy 354.607543 -282.087133) (xy 354.655283 -282.104127) (xy 354.699861 -282.128227)
			(xy 354.740227 -282.158863) (xy 354.775429 -282.195315) (xy 354.80464 -282.236724) (xy 354.82717 -282.282115)
			(xy 354.84249 -282.330419) (xy 354.850239 -282.380498) (xy 354.8507 -282.405836) (xy 354.850192 -282.431723)
			(xy 354.842093 -282.482861) (xy 354.826094 -282.532101) (xy 354.802588 -282.578233) (xy 354.772156 -282.62012)
			(xy 354.735546 -282.65673) (xy 354.693659 -282.687162) (xy 354.647527 -282.710668) (xy 354.598287 -282.726667)
			(xy 354.547149 -282.734766) (xy 354.495375 -282.734766) (xy 354.444237 -282.726667) (xy 354.394997 -282.710668)
			(xy 354.348865 -282.687162) (xy 354.306978 -282.65673) (xy 354.270368 -282.62012) (xy 354.239936 -282.578233)
			(xy 354.21643 -282.532101) (xy 354.200431 -282.482861) (xy 354.192332 -282.431723) (xy 354.191824 -282.405836)
			(xy 354.192361 -282.378128) (xy 354.201551 -282.323481) (xy 354.210112 -282.297124) (xy 354.217986 -282.275026)
			(xy 354.013008 -281.920188) (xy 353.990148 -281.91587) (xy 353.965319 -281.910737) (xy 353.917537 -281.893779)
			(xy 353.872916 -281.869705) (xy 353.832509 -281.83908) (xy 353.797268 -281.802629) (xy 353.768025 -281.761211)
			(xy 353.74547 -281.715803) (xy 353.730136 -281.667476) (xy 353.722383 -281.617371) (xy 353.721924 -281.59202)
			(xy 352.501708 -281.59202) (xy 352.5012 -281.617927) (xy 352.493094 -281.669104) (xy 352.477082 -281.718383)
			(xy 352.453559 -281.76455) (xy 352.423103 -281.806469) (xy 352.386465 -281.843107) (xy 352.344546 -281.873563)
			(xy 352.298379 -281.897086) (xy 352.2491 -281.913098) (xy 352.197923 -281.921204) (xy 352.146109 -281.921204)
			(xy 352.094932 -281.913098) (xy 352.045653 -281.897086) (xy 351.999486 -281.873563) (xy 351.957567 -281.843107)
			(xy 351.920929 -281.806469) (xy 351.890473 -281.76455) (xy 351.86695 -281.718383) (xy 351.850938 -281.669104)
			(xy 351.842832 -281.617927) (xy 351.842324 -281.59202) (xy 351.842922 -281.564303) (xy 351.852242 -281.509656)
			(xy 351.860866 -281.483308) (xy 351.86874 -281.46121) (xy 351.663762 -281.106372) (xy 351.640902 -281.102054)
			(xy 351.616072 -281.096882) (xy 351.568266 -281.079946) (xy 351.523618 -281.055889) (xy 351.483181 -281.025278)
			(xy 351.447909 -280.988835) (xy 351.418634 -280.947421) (xy 351.396047 -280.902011) (xy 351.380681 -280.853678)
			(xy 351.372898 -280.803562) (xy 351.372424 -280.778204) (xy 349.2119 -280.778204) (xy 349.2119 -280.778712)
			(xy 349.21131 -280.806228) (xy 349.202124 -280.860489) (xy 349.193612 -280.886662) (xy 349.185992 -280.908506)
			(xy 349.391224 -281.263852) (xy 349.414084 -281.26817) (xy 349.438905 -281.273337) (xy 349.486682 -281.290294)
			(xy 349.531299 -281.314367) (xy 349.571704 -281.344988) (xy 349.606944 -281.381435) (xy 349.636188 -281.422848)
			(xy 349.658745 -281.46825) (xy 349.674085 -281.516571) (xy 349.681844 -281.566671) (xy 349.682308 -281.59202)
			(xy 349.6818 -281.617927) (xy 349.673694 -281.669104) (xy 349.657682 -281.718383) (xy 349.634159 -281.76455)
			(xy 349.603703 -281.806469) (xy 349.567065 -281.843107) (xy 349.525146 -281.873563) (xy 349.478979 -281.897086)
			(xy 349.4297 -281.913098) (xy 349.378523 -281.921204) (xy 349.326709 -281.921204) (xy 349.275532 -281.913098)
			(xy 349.226253 -281.897086) (xy 349.180086 -281.873563) (xy 349.138167 -281.843107) (xy 349.101529 -281.806469)
			(xy 349.071073 -281.76455) (xy 349.04755 -281.718383) (xy 349.031538 -281.669104) (xy 349.023432 -281.617927)
			(xy 349.022924 -281.59202) (xy 349.023522 -281.564303) (xy 349.032842 -281.509656) (xy 349.041466 -281.483308)
			(xy 349.04934 -281.46121) (xy 348.844362 -281.106372) (xy 348.821502 -281.102054) (xy 348.796672 -281.096882)
			(xy 348.748866 -281.079946) (xy 348.704218 -281.055889) (xy 348.663781 -281.025278) (xy 348.628509 -280.988835)
			(xy 348.599234 -280.947421) (xy 348.576647 -280.902011) (xy 348.561281 -280.853678) (xy 348.553498 -280.803562)
			(xy 348.553024 -280.778204) (xy 346.3925 -280.778204) (xy 346.392021 -280.803539) (xy 346.384268 -280.853611)
			(xy 346.368945 -280.901908) (xy 346.346413 -280.947292) (xy 346.317203 -280.988694) (xy 346.282002 -281.025139)
			(xy 346.241639 -281.055769) (xy 346.197065 -281.079864) (xy 346.14933 -281.096855) (xy 346.12453 -281.102054)
			(xy 346.10167 -281.106372) (xy 345.896692 -281.46121) (xy 345.904566 -281.483308) (xy 345.913205 -281.509652)
			(xy 345.922521 -281.564301) (xy 345.923108 -281.59202) (xy 345.9226 -281.617909) (xy 347.143809 -281.617909)
			(xy 347.143809 -281.566091) (xy 347.151916 -281.514912) (xy 347.167929 -281.465631) (xy 347.191454 -281.419462)
			(xy 347.221912 -281.377541) (xy 347.258553 -281.340902) (xy 347.300475 -281.310446) (xy 347.346646 -281.286923)
			(xy 347.395928 -281.270912) (xy 347.447107 -281.262808) (xy 347.473016 -281.262328) (xy 347.498529 -281.262786)
			(xy 347.548945 -281.27065) (xy 347.597547 -281.286187) (xy 347.643176 -281.309027) (xy 347.684741 -281.338624)
			(xy 347.721249 -281.374271) (xy 347.736922 -281.394408) (xy 348.14891 -281.394408) (xy 348.16458 -281.37427)
			(xy 348.20109 -281.338625) (xy 348.242656 -281.309032) (xy 348.288285 -281.286196) (xy 348.336888 -281.270663)
			(xy 348.387304 -281.262804) (xy 348.412816 -281.262328) (xy 348.438724 -281.262797) (xy 348.489902 -281.270905)
			(xy 348.539182 -281.286919) (xy 348.585349 -281.310445) (xy 348.627269 -281.340903) (xy 348.663907 -281.377543)
			(xy 348.694363 -281.419464) (xy 348.717887 -281.465633) (xy 348.733899 -281.514914) (xy 348.742004 -281.566092)
			(xy 348.742004 -281.617908) (xy 348.733899 -281.669086) (xy 348.717887 -281.718367) (xy 348.694363 -281.764536)
			(xy 348.663907 -281.806457) (xy 348.627269 -281.843097) (xy 348.585349 -281.873555) (xy 348.539182 -281.897081)
			(xy 348.489902 -281.913095) (xy 348.438724 -281.921203) (xy 348.412816 -281.921712) (xy 348.387305 -281.921215)
			(xy 348.336891 -281.913357) (xy 348.28829 -281.897827) (xy 348.242662 -281.874994) (xy 348.201096 -281.845405)
			(xy 348.164585 -281.809765) (xy 348.14891 -281.789632) (xy 347.736922 -281.789632) (xy 347.721245 -281.809764)
			(xy 347.684735 -281.845407) (xy 347.64317 -281.875) (xy 347.597542 -281.897836) (xy 347.548942 -281.913371)
			(xy 347.498528 -281.921234) (xy 347.473016 -281.921712) (xy 347.447107 -281.921192) (xy 347.395928 -281.913088)
			(xy 347.346646 -281.897077) (xy 347.300475 -281.873554) (xy 347.258553 -281.843098) (xy 347.221912 -281.806459)
			(xy 347.191454 -281.764538) (xy 347.167929 -281.718369) (xy 347.151916 -281.669088) (xy 347.143809 -281.617909)
			(xy 345.9226 -281.617909) (xy 345.9226 -281.617927) (xy 345.914494 -281.669104) (xy 345.898482 -281.718383)
			(xy 345.874959 -281.76455) (xy 345.844503 -281.806469) (xy 345.807865 -281.843107) (xy 345.765946 -281.873563)
			(xy 345.719779 -281.897086) (xy 345.6705 -281.913098) (xy 345.619323 -281.921204) (xy 345.567509 -281.921204)
			(xy 345.516332 -281.913098) (xy 345.467053 -281.897086) (xy 345.420886 -281.873563) (xy 345.378967 -281.843107)
			(xy 345.342329 -281.806469) (xy 345.311873 -281.76455) (xy 345.28835 -281.718383) (xy 345.272338 -281.669104)
			(xy 345.264232 -281.617927) (xy 345.263724 -281.59202) (xy 344.043508 -281.59202) (xy 344.043045 -281.617395)
			(xy 344.035274 -281.667545) (xy 344.019903 -281.71591) (xy 343.997297 -281.761346) (xy 343.967989 -281.802777)
			(xy 343.932674 -281.839223) (xy 343.892188 -281.869822) (xy 343.847487 -281.893849) (xy 343.79963 -281.910736)
			(xy 343.774776 -281.91587) (xy 343.751916 -281.920188) (xy 343.546938 -282.275026) (xy 343.554812 -282.297124)
			(xy 343.563378 -282.32348) (xy 343.572573 -282.378127) (xy 343.5731 -282.405836) (xy 343.854024 -282.405836)
			(xy 343.854532 -282.379949) (xy 343.862631 -282.328811) (xy 343.87863 -282.279571) (xy 343.902136 -282.233439)
			(xy 343.932568 -282.191552) (xy 343.969178 -282.154942) (xy 344.011065 -282.12451) (xy 344.057197 -282.101004)
			(xy 344.106437 -282.085005) (xy 344.157575 -282.076906) (xy 344.209349 -282.076906) (xy 344.260487 -282.085005)
			(xy 344.309727 -282.101004) (xy 344.355859 -282.12451) (xy 344.397746 -282.154942) (xy 344.434356 -282.191552)
			(xy 344.464788 -282.233439) (xy 344.488294 -282.279571) (xy 344.504293 -282.328811) (xy 344.512392 -282.379949)
			(xy 344.5129 -282.405836) (xy 344.5129 -282.406344) (xy 344.512364 -282.431703) (xy 344.794152 -282.431703)
			(xy 344.794152 -282.379897) (xy 344.802256 -282.32873) (xy 344.818263 -282.27946) (xy 344.841781 -282.2333)
			(xy 344.872229 -282.191388) (xy 344.908859 -282.154754) (xy 344.950768 -282.124301) (xy 344.996925 -282.100778)
			(xy 345.046193 -282.084765) (xy 345.097359 -282.076655) (xy 345.123262 -282.076144) (xy 345.148774 -282.076635)
			(xy 345.199188 -282.084491) (xy 345.247791 -282.100021) (xy 345.293419 -282.122855) (xy 345.334985 -282.152446)
			(xy 345.371495 -282.188089) (xy 345.387168 -282.208224) (xy 345.799156 -282.208224) (xy 345.814861 -282.188115)
			(xy 345.851364 -282.152468) (xy 345.892922 -282.122871) (xy 345.938545 -282.10003) (xy 345.987141 -282.084491)
			(xy 346.037552 -282.076624) (xy 346.063062 -282.076144) (xy 346.088976 -282.076551) (xy 346.140167 -282.084653)
			(xy 346.18946 -282.100664) (xy 346.235642 -282.12419) (xy 346.277574 -282.154651) (xy 346.314224 -282.191297)
			(xy 346.34469 -282.233226) (xy 346.368221 -282.279404) (xy 346.384238 -282.328696) (xy 346.392346 -282.379886)
			(xy 346.392346 -282.431714) (xy 346.384238 -282.482904) (xy 346.368221 -282.532196) (xy 346.34469 -282.578374)
			(xy 346.314224 -282.620303) (xy 346.277574 -282.656949) (xy 346.235642 -282.68741) (xy 346.18946 -282.710936)
			(xy 346.140167 -282.726947) (xy 346.088976 -282.735049) (xy 346.063062 -282.735528) (xy 346.03755 -282.735064)
			(xy 345.987135 -282.727199) (xy 345.938534 -282.711661) (xy 345.892906 -282.688822) (xy 345.85134 -282.659228)
			(xy 345.81483 -282.623584) (xy 345.799156 -282.603448) (xy 345.387168 -282.603448) (xy 345.371526 -282.623609)
			(xy 345.335009 -282.659249) (xy 345.293436 -282.688839) (xy 345.247802 -282.71167) (xy 345.199195 -282.727199)
			(xy 345.148776 -282.735054) (xy 345.123262 -282.735528) (xy 345.097359 -282.734945) (xy 345.046193 -282.726835)
			(xy 344.996925 -282.710822) (xy 344.950768 -282.687299) (xy 344.908859 -282.656846) (xy 344.872229 -282.620212)
			(xy 344.841781 -282.5783) (xy 344.818263 -282.53214) (xy 344.802256 -282.48287) (xy 344.794152 -282.431703)
			(xy 344.512364 -282.431703) (xy 344.512318 -282.43386) (xy 344.503126 -282.488122) (xy 344.494612 -282.514294)
			(xy 344.486992 -282.536392) (xy 344.692224 -282.891738) (xy 344.715084 -282.896056) (xy 344.739902 -282.901236)
			(xy 344.787678 -282.918192) (xy 344.832294 -282.942264) (xy 344.872699 -282.972884) (xy 344.907939 -283.009329)
			(xy 344.937183 -283.05074) (xy 344.959741 -283.09614) (xy 344.975082 -283.14446) (xy 344.982843 -283.194558)
			(xy 344.983308 -283.219906) (xy 347.143324 -283.219906) (xy 347.143831 -283.194562) (xy 347.151603 -283.144472)
			(xy 347.166948 -283.096161) (xy 347.189506 -283.050768) (xy 347.218745 -283.009362) (xy 347.253975 -282.972918)
			(xy 347.294368 -282.942295) (xy 347.338972 -282.918214) (xy 347.386736 -282.901243) (xy 347.411548 -282.896056)
			(xy 347.434408 -282.891738) (xy 347.639386 -282.5369) (xy 347.631766 -282.514802) (xy 347.623129 -282.488391)
			(xy 347.613803 -282.433617) (xy 347.613224 -282.405836) (xy 347.613732 -282.379949) (xy 347.621831 -282.328811)
			(xy 347.63783 -282.279571) (xy 347.661336 -282.233439) (xy 347.691768 -282.191552) (xy 347.728378 -282.154942)
			(xy 347.770265 -282.12451) (xy 347.816397 -282.101004) (xy 347.865637 -282.085005) (xy 347.916775 -282.076906)
			(xy 347.968549 -282.076906) (xy 348.019687 -282.085005) (xy 348.068927 -282.101004) (xy 348.115059 -282.12451)
			(xy 348.156946 -282.154942) (xy 348.193556 -282.191552) (xy 348.223988 -282.233439) (xy 348.247494 -282.279571)
			(xy 348.263493 -282.328811) (xy 348.271592 -282.379949) (xy 348.2721 -282.405836) (xy 349.492824 -282.405836)
			(xy 349.493229 -282.380499) (xy 349.500992 -282.330422) (xy 349.516324 -282.282122) (xy 349.538866 -282.236737)
			(xy 349.568085 -282.195335) (xy 349.603295 -282.15889) (xy 349.643666 -282.128262) (xy 349.688248 -282.10417)
			(xy 349.735991 -282.087183) (xy 349.760794 -282.081986) (xy 349.783654 -282.077668) (xy 349.988886 -281.722322)
			(xy 349.981266 -281.700478) (xy 349.97264 -281.674196) (xy 349.963326 -281.619675) (xy 349.962724 -281.59202)
			(xy 349.963232 -281.566113) (xy 349.971338 -281.514936) (xy 349.98735 -281.465657) (xy 350.010873 -281.41949)
			(xy 350.041329 -281.377571) (xy 350.077967 -281.340933) (xy 350.119886 -281.310477) (xy 350.166053 -281.286954)
			(xy 350.215332 -281.270942) (xy 350.266509 -281.262836) (xy 350.318323 -281.262836) (xy 350.3695 -281.270942)
			(xy 350.418779 -281.286954) (xy 350.464946 -281.310477) (xy 350.506865 -281.340933) (xy 350.543503 -281.377571)
			(xy 350.573959 -281.41949) (xy 350.597482 -281.465657) (xy 350.613494 -281.514936) (xy 350.6216 -281.566113)
			(xy 350.622108 -281.59202) (xy 350.621645 -281.617395) (xy 350.613874 -281.667545) (xy 350.598503 -281.71591)
			(xy 350.575897 -281.761346) (xy 350.546589 -281.802777) (xy 350.511274 -281.839223) (xy 350.470788 -281.869822)
			(xy 350.426087 -281.893849) (xy 350.37823 -281.910736) (xy 350.353376 -281.91587) (xy 350.330516 -281.920188)
			(xy 350.125538 -282.275026) (xy 350.133412 -282.297124) (xy 350.141978 -282.32348) (xy 350.151173 -282.378127)
			(xy 350.1517 -282.405836) (xy 350.151192 -282.431703) (xy 351.372752 -282.431703) (xy 351.372752 -282.379897)
			(xy 351.380856 -282.32873) (xy 351.396863 -282.27946) (xy 351.420381 -282.2333) (xy 351.450829 -282.191388)
			(xy 351.487459 -282.154754) (xy 351.529368 -282.124301) (xy 351.575525 -282.100778) (xy 351.624793 -282.084765)
			(xy 351.675959 -282.076655) (xy 351.701862 -282.076144) (xy 351.727374 -282.076635) (xy 351.777788 -282.084491)
			(xy 351.826391 -282.100021) (xy 351.872019 -282.122855) (xy 351.913585 -282.152446) (xy 351.950095 -282.188089)
			(xy 351.965768 -282.208224) (xy 352.377756 -282.208224) (xy 352.393461 -282.188115) (xy 352.429964 -282.152468)
			(xy 352.471522 -282.122871) (xy 352.517145 -282.10003) (xy 352.565741 -282.084491) (xy 352.616152 -282.076624)
			(xy 352.641662 -282.076144) (xy 352.667576 -282.076551) (xy 352.718767 -282.084653) (xy 352.76806 -282.100664)
			(xy 352.814242 -282.12419) (xy 352.856174 -282.154651) (xy 352.892824 -282.191297) (xy 352.92329 -282.233226)
			(xy 352.946821 -282.279404) (xy 352.962838 -282.328696) (xy 352.970946 -282.379886) (xy 352.970946 -282.431714)
			(xy 352.962838 -282.482904) (xy 352.946821 -282.532196) (xy 352.92329 -282.578374) (xy 352.892824 -282.620303)
			(xy 352.856174 -282.656949) (xy 352.814242 -282.68741) (xy 352.76806 -282.710936) (xy 352.718767 -282.726947)
			(xy 352.667576 -282.735049) (xy 352.641662 -282.735528) (xy 352.61615 -282.735064) (xy 352.565735 -282.727199)
			(xy 352.517134 -282.711661) (xy 352.471506 -282.688822) (xy 352.42994 -282.659228) (xy 352.39343 -282.623584)
			(xy 352.377756 -282.603448) (xy 351.965768 -282.603448) (xy 351.950126 -282.623609) (xy 351.913609 -282.659249)
			(xy 351.872036 -282.688839) (xy 351.826402 -282.71167) (xy 351.777795 -282.727199) (xy 351.727376 -282.735054)
			(xy 351.701862 -282.735528) (xy 351.675959 -282.734945) (xy 351.624793 -282.726835) (xy 351.575525 -282.710822)
			(xy 351.529368 -282.687299) (xy 351.487459 -282.656846) (xy 351.450829 -282.620212) (xy 351.420381 -282.5783)
			(xy 351.396863 -282.53214) (xy 351.380856 -282.48287) (xy 351.372752 -282.431703) (xy 350.151192 -282.431703)
			(xy 350.151192 -282.431723) (xy 350.143093 -282.482861) (xy 350.127094 -282.532101) (xy 350.103588 -282.578233)
			(xy 350.073156 -282.62012) (xy 350.036546 -282.65673) (xy 349.994659 -282.687162) (xy 349.948527 -282.710668)
			(xy 349.899287 -282.726667) (xy 349.848149 -282.734766) (xy 349.796375 -282.734766) (xy 349.745237 -282.726667)
			(xy 349.695997 -282.710668) (xy 349.649865 -282.687162) (xy 349.607978 -282.65673) (xy 349.571368 -282.62012)
			(xy 349.540936 -282.578233) (xy 349.51743 -282.532101) (xy 349.501431 -282.482861) (xy 349.493332 -282.431723)
			(xy 349.492824 -282.405836) (xy 348.2721 -282.405836) (xy 348.271608 -282.431158) (xy 348.263872 -282.481209)
			(xy 348.248573 -282.529487) (xy 348.22607 -282.574858) (xy 348.196893 -282.616254) (xy 348.161729 -282.6527)
			(xy 348.121404 -282.68334) (xy 348.076868 -282.707453) (xy 348.029168 -282.72447) (xy 348.004384 -282.729686)
			(xy 347.981524 -282.734004) (xy 347.776292 -283.089096) (xy 347.784166 -283.111194) (xy 347.792802 -283.137539)
			(xy 347.80212 -283.192188) (xy 347.802708 -283.219906) (xy 347.8022 -283.24579) (xy 349.023649 -283.24579)
			(xy 349.023649 -283.19401) (xy 349.03175 -283.142868) (xy 349.047751 -283.093623) (xy 349.071259 -283.047487)
			(xy 349.101695 -283.005597) (xy 349.13831 -282.968985) (xy 349.180201 -282.938551) (xy 349.226338 -282.915045)
			(xy 349.275584 -282.899046) (xy 349.326726 -282.890948) (xy 349.352616 -282.890468) (xy 349.378128 -282.890949)
			(xy 349.428541 -282.898811) (xy 349.477143 -282.914346) (xy 349.522771 -282.937181) (xy 349.564336 -282.966773)
			(xy 349.600848 -283.002414) (xy 349.616522 -283.022548) (xy 350.02851 -283.022548) (xy 350.044163 -283.002397)
			(xy 350.080679 -282.966756) (xy 350.122249 -282.937166) (xy 350.167881 -282.914333) (xy 350.216486 -282.898802)
			(xy 350.266903 -282.890944) (xy 350.292416 -282.890468) (xy 350.318303 -282.890965) (xy 350.369439 -282.899066)
			(xy 350.418679 -282.915067) (xy 350.464809 -282.938574) (xy 350.506694 -282.969007) (xy 350.543303 -283.005618)
			(xy 350.573735 -283.047505) (xy 350.597239 -283.093636) (xy 350.613237 -283.142876) (xy 350.621336 -283.194013)
			(xy 350.621336 -283.219906) (xy 352.782124 -283.219906) (xy 352.782631 -283.194562) (xy 352.790403 -283.144472)
			(xy 352.805748 -283.096161) (xy 352.828306 -283.050768) (xy 352.857545 -283.009362) (xy 352.892775 -282.972918)
			(xy 352.933168 -282.942295) (xy 352.977772 -282.918214) (xy 353.025536 -282.901243) (xy 353.050348 -282.896056)
			(xy 353.073208 -282.891738) (xy 353.278186 -282.5369) (xy 353.270566 -282.514802) (xy 353.261929 -282.488391)
			(xy 353.252603 -282.433617) (xy 353.252024 -282.405836) (xy 353.252532 -282.379949) (xy 353.260631 -282.328811)
			(xy 353.27663 -282.279571) (xy 353.300136 -282.233439) (xy 353.330568 -282.191552) (xy 353.367178 -282.154942)
			(xy 353.409065 -282.12451) (xy 353.455197 -282.101004) (xy 353.504437 -282.085005) (xy 353.555575 -282.076906)
			(xy 353.607349 -282.076906) (xy 353.658487 -282.085005) (xy 353.707727 -282.101004) (xy 353.753859 -282.12451)
			(xy 353.795746 -282.154942) (xy 353.832356 -282.191552) (xy 353.862788 -282.233439) (xy 353.886294 -282.279571)
			(xy 353.902293 -282.328811) (xy 353.910392 -282.379949) (xy 353.9109 -282.405836) (xy 353.910408 -282.431158)
			(xy 353.902672 -282.481209) (xy 353.887373 -282.529487) (xy 353.86487 -282.574858) (xy 353.835693 -282.616254)
			(xy 353.800529 -282.6527) (xy 353.760204 -282.68334) (xy 353.715668 -282.707453) (xy 353.667968 -282.72447)
			(xy 353.643184 -282.729686) (xy 353.620324 -282.734004) (xy 353.415092 -283.089096) (xy 353.422966 -283.111194)
			(xy 353.431602 -283.137539) (xy 353.44092 -283.192188) (xy 353.441508 -283.219906) (xy 353.441 -283.245813)
			(xy 353.432894 -283.29699) (xy 353.416882 -283.346269) (xy 353.393359 -283.392436) (xy 353.362903 -283.434355)
			(xy 353.326265 -283.470993) (xy 353.284346 -283.501449) (xy 353.238179 -283.524972) (xy 353.1889 -283.540984)
			(xy 353.137723 -283.54909) (xy 353.085909 -283.54909) (xy 353.034732 -283.540984) (xy 352.985453 -283.524972)
			(xy 352.939286 -283.501449) (xy 352.897367 -283.470993) (xy 352.860729 -283.434355) (xy 352.830273 -283.392436)
			(xy 352.80675 -283.346269) (xy 352.790738 -283.29699) (xy 352.782632 -283.245813) (xy 352.782124 -283.219906)
			(xy 350.621336 -283.219906) (xy 350.621336 -283.245787) (xy 350.613237 -283.296924) (xy 350.597239 -283.346164)
			(xy 350.573735 -283.392295) (xy 350.543303 -283.434182) (xy 350.506694 -283.470793) (xy 350.464809 -283.501226)
			(xy 350.418679 -283.524733) (xy 350.369439 -283.540734) (xy 350.318303 -283.548835) (xy 350.292416 -283.549344)
			(xy 350.266904 -283.548874) (xy 350.216488 -283.541014) (xy 350.167885 -283.52548) (xy 350.122256 -283.502643)
			(xy 350.080691 -283.473047) (xy 350.044182 -283.437401) (xy 350.02851 -283.417264) (xy 349.616522 -283.417264)
			(xy 349.600826 -283.437381) (xy 349.564322 -283.473028) (xy 349.522762 -283.502625) (xy 349.477138 -283.525464)
			(xy 349.428539 -283.541001) (xy 349.378127 -283.548865) (xy 349.352616 -283.549344) (xy 349.326726 -283.548852)
			(xy 349.275584 -283.540754) (xy 349.226338 -283.524755) (xy 349.180201 -283.501249) (xy 349.13831 -283.470815)
			(xy 349.101695 -283.434203) (xy 349.071259 -283.392313) (xy 349.047751 -283.346177) (xy 349.03175 -283.296932)
			(xy 349.023649 -283.24579) (xy 347.8022 -283.24579) (xy 347.8022 -283.245813) (xy 347.794094 -283.29699)
			(xy 347.778082 -283.346269) (xy 347.754559 -283.392436) (xy 347.724103 -283.434355) (xy 347.687465 -283.470993)
			(xy 347.645546 -283.501449) (xy 347.599379 -283.524972) (xy 347.5501 -283.540984) (xy 347.498923 -283.54909)
			(xy 347.447109 -283.54909) (xy 347.395932 -283.540984) (xy 347.346653 -283.524972) (xy 347.300486 -283.501449)
			(xy 347.258567 -283.470993) (xy 347.221929 -283.434355) (xy 347.191473 -283.392436) (xy 347.16795 -283.346269)
			(xy 347.151938 -283.29699) (xy 347.143832 -283.245813) (xy 347.143324 -283.219906) (xy 344.983308 -283.219906)
			(xy 344.9828 -283.245813) (xy 344.974694 -283.29699) (xy 344.958682 -283.346269) (xy 344.935159 -283.392436)
			(xy 344.904703 -283.434355) (xy 344.868065 -283.470993) (xy 344.826146 -283.501449) (xy 344.779979 -283.524972)
			(xy 344.7307 -283.540984) (xy 344.679523 -283.54909) (xy 344.627709 -283.54909) (xy 344.576532 -283.540984)
			(xy 344.527253 -283.524972) (xy 344.481086 -283.501449) (xy 344.439167 -283.470993) (xy 344.402529 -283.434355)
			(xy 344.372073 -283.392436) (xy 344.34855 -283.346269) (xy 344.332538 -283.29699) (xy 344.324432 -283.245813)
			(xy 344.323924 -283.219906) (xy 344.324518 -283.192189) (xy 344.333841 -283.137542) (xy 344.342466 -283.111194)
			(xy 344.35034 -283.089096) (xy 344.145362 -282.734004) (xy 344.122248 -282.729686) (xy 344.097423 -282.724538)
			(xy 344.049642 -282.707582) (xy 344.005022 -282.683508) (xy 343.964615 -282.652886) (xy 343.929374 -282.616436)
			(xy 343.900131 -282.57502) (xy 343.877575 -282.529614) (xy 343.862239 -282.481289) (xy 343.854484 -282.431186)
			(xy 343.854024 -282.405836) (xy 343.5731 -282.405836) (xy 343.572592 -282.431723) (xy 343.564493 -282.482861)
			(xy 343.548494 -282.532101) (xy 343.524988 -282.578233) (xy 343.494556 -282.62012) (xy 343.457946 -282.65673)
			(xy 343.416059 -282.687162) (xy 343.369927 -282.710668) (xy 343.320687 -282.726667) (xy 343.269549 -282.734766)
			(xy 343.217775 -282.734766) (xy 343.166637 -282.726667) (xy 343.117397 -282.710668) (xy 343.071265 -282.687162)
			(xy 343.029378 -282.65673) (xy 342.992768 -282.62012) (xy 342.962336 -282.578233) (xy 342.93883 -282.532101)
			(xy 342.922831 -282.482861) (xy 342.914732 -282.431723) (xy 342.914224 -282.405836) (xy 341.694008 -282.405836)
			(xy 341.6935 -282.431743) (xy 341.685394 -282.48292) (xy 341.669382 -282.532199) (xy 341.645859 -282.578366)
			(xy 341.615403 -282.620285) (xy 341.578765 -282.656923) (xy 341.536846 -282.687379) (xy 341.490679 -282.710902)
			(xy 341.4414 -282.726914) (xy 341.390223 -282.73502) (xy 341.338409 -282.73502) (xy 341.287232 -282.726914)
			(xy 341.237953 -282.710902) (xy 341.191786 -282.687379) (xy 341.149867 -282.656923) (xy 341.113229 -282.620285)
			(xy 341.082773 -282.578366) (xy 341.05925 -282.532199) (xy 341.043238 -282.48292) (xy 341.035132 -282.431743)
			(xy 341.034624 -282.405836) (xy 339.814408 -282.405836) (xy 339.813997 -282.431202) (xy 339.806243 -282.481337)
			(xy 339.790893 -282.52969) (xy 339.768309 -282.575118) (xy 339.739027 -282.616545) (xy 339.703739 -282.652993)
			(xy 339.663279 -282.683598) (xy 339.618605 -282.707637) (xy 339.570773 -282.724541) (xy 339.54593 -282.729686)
			(xy 339.52307 -282.734004) (xy 339.318092 -283.089096) (xy 339.325712 -283.11094) (xy 339.33426 -283.137236)
			(xy 339.343458 -283.191753) (xy 339.344 -283.219398) (xy 339.344 -283.219906) (xy 339.343492 -283.245785)
			(xy 340.565275 -283.245785) (xy 340.565275 -283.194015) (xy 340.573373 -283.142882) (xy 340.58937 -283.093646)
			(xy 340.612872 -283.047517) (xy 340.643299 -283.005633) (xy 340.679904 -282.969024) (xy 340.721785 -282.938592)
			(xy 340.76791 -282.915085) (xy 340.817145 -282.899082) (xy 340.868277 -282.890978) (xy 340.894162 -282.890468)
			(xy 340.919672 -282.890989) (xy 340.970084 -282.898843) (xy 341.018684 -282.914369) (xy 341.064312 -282.937197)
			(xy 341.105879 -282.966782) (xy 341.142392 -283.002417) (xy 341.158068 -283.022548) (xy 341.570056 -283.022548)
			(xy 341.585741 -283.002422) (xy 341.62225 -282.96678) (xy 341.663813 -282.937187) (xy 341.709439 -282.91435)
			(xy 341.758039 -282.898813) (xy 341.808451 -282.890948) (xy 341.833962 -282.890468) (xy 341.859854 -282.890934)
			(xy 341.911001 -282.89903) (xy 341.960252 -282.915027) (xy 342.006393 -282.938533) (xy 342.048289 -282.968968)
			(xy 342.084908 -283.005582) (xy 342.115347 -283.047475) (xy 342.138858 -283.093613) (xy 342.154861 -283.142862)
			(xy 342.162963 -283.194008) (xy 342.162963 -283.245792) (xy 342.154861 -283.296938) (xy 342.138858 -283.346187)
			(xy 342.115347 -283.392325) (xy 342.084908 -283.434218) (xy 342.048289 -283.470832) (xy 342.006393 -283.501267)
			(xy 341.960252 -283.524773) (xy 341.911001 -283.54077) (xy 341.859854 -283.548866) (xy 341.833962 -283.549344)
			(xy 341.808448 -283.548913) (xy 341.75803 -283.541045) (xy 341.709427 -283.525503) (xy 341.663798 -283.502658)
			(xy 341.622234 -283.473056) (xy 341.585727 -283.437404) (xy 341.570056 -283.417264) (xy 341.158068 -283.417264)
			(xy 341.142404 -283.437407) (xy 341.105893 -283.473052) (xy 341.064326 -283.502646) (xy 341.018696 -283.525481)
			(xy 340.970092 -283.541013) (xy 340.919675 -283.548869) (xy 340.894162 -283.549344) (xy 340.868277 -283.548822)
			(xy 340.817145 -283.540718) (xy 340.76791 -283.524715) (xy 340.721785 -283.501208) (xy 340.679904 -283.470776)
			(xy 340.643299 -283.434167) (xy 340.612872 -283.392283) (xy 340.58937 -283.346154) (xy 340.573373 -283.296918)
			(xy 340.565275 -283.245785) (xy 339.343492 -283.245785) (xy 339.343492 -283.245793) (xy 339.335393 -283.296931)
			(xy 339.319394 -283.346171) (xy 339.295888 -283.392303) (xy 339.265456 -283.43419) (xy 339.228846 -283.4708)
			(xy 339.186959 -283.501232) (xy 339.140827 -283.524738) (xy 339.091587 -283.540737) (xy 339.040449 -283.548836)
			(xy 338.988675 -283.548836) (xy 338.937537 -283.540737) (xy 338.888297 -283.524738) (xy 338.842165 -283.501232)
			(xy 338.800278 -283.4708) (xy 338.763668 -283.43419) (xy 338.733236 -283.392303) (xy 338.70973 -283.346171)
			(xy 338.693731 -283.296931) (xy 338.685632 -283.245793) (xy 338.685124 -283.219906) (xy 336.5246 -283.219906)
			(xy 336.524092 -283.245793) (xy 336.515993 -283.296931) (xy 336.499994 -283.346171) (xy 336.476488 -283.392303)
			(xy 336.446056 -283.43419) (xy 336.409446 -283.4708) (xy 336.367559 -283.501232) (xy 336.321427 -283.524738)
			(xy 336.272187 -283.540737) (xy 336.221049 -283.548836) (xy 336.169275 -283.548836) (xy 336.118137 -283.540737)
			(xy 336.068897 -283.524738) (xy 336.022765 -283.501232) (xy 335.980878 -283.4708) (xy 335.944268 -283.43419)
			(xy 335.913836 -283.392303) (xy 335.89033 -283.346171) (xy 335.874331 -283.296931) (xy 335.866232 -283.245793)
			(xy 335.865724 -283.219906) (xy 335.866254 -283.192198) (xy 335.875449 -283.137551) (xy 335.884012 -283.111194)
			(xy 335.891886 -283.089096) (xy 335.686654 -282.734004) (xy 335.663794 -282.729686) (xy 335.639001 -282.724454)
			(xy 335.591266 -282.707468) (xy 335.546691 -282.683379) (xy 335.506327 -282.652753) (xy 335.471124 -282.616312)
			(xy 335.441911 -282.574914) (xy 335.419375 -282.529534) (xy 335.404048 -282.48124) (xy 335.396291 -282.43117)
			(xy 335.395824 -282.405836) (xy 335.115408 -282.405836) (xy 335.1149 -282.431743) (xy 335.106794 -282.48292)
			(xy 335.090782 -282.532199) (xy 335.067259 -282.578366) (xy 335.036803 -282.620285) (xy 335.000165 -282.656923)
			(xy 334.958246 -282.687379) (xy 334.912079 -282.710902) (xy 334.8628 -282.726914) (xy 334.811623 -282.73502)
			(xy 334.759809 -282.73502) (xy 334.708632 -282.726914) (xy 334.659353 -282.710902) (xy 334.613186 -282.687379)
			(xy 334.571267 -282.656923) (xy 334.534629 -282.620285) (xy 334.504173 -282.578366) (xy 334.48065 -282.532199)
			(xy 334.464638 -282.48292) (xy 334.456532 -282.431743) (xy 334.456024 -282.405836) (xy 106.910632 -282.405836)
			(xy 106.910124 -282.431723) (xy 106.902025 -282.482861) (xy 106.886026 -282.532101) (xy 106.86252 -282.578233)
			(xy 106.832088 -282.62012) (xy 106.795478 -282.65673) (xy 106.753591 -282.687162) (xy 106.707459 -282.710668)
			(xy 106.658219 -282.726667) (xy 106.607081 -282.734766) (xy 106.555307 -282.734766) (xy 106.504169 -282.726667)
			(xy 106.454929 -282.710668) (xy 106.408797 -282.687162) (xy 106.36691 -282.65673) (xy 106.3303 -282.62012)
			(xy 106.299868 -282.578233) (xy 106.276362 -282.532101) (xy 106.260363 -282.482861) (xy 106.252264 -282.431723)
			(xy 106.251756 -282.405836) (xy 106.252296 -282.378128) (xy 106.261484 -282.323482) (xy 106.270044 -282.297124)
			(xy 106.277918 -282.275026) (xy 106.07294 -281.920188) (xy 106.05008 -281.91587) (xy 106.025256 -281.910713)
			(xy 105.977474 -281.893761) (xy 105.932853 -281.86969) (xy 105.892445 -281.839069) (xy 105.857203 -281.802621)
			(xy 105.827959 -281.761205) (xy 105.805403 -281.715799) (xy 105.790068 -281.667474) (xy 105.782315 -281.61737)
			(xy 105.781856 -281.59202) (xy 104.56164 -281.59202) (xy 104.561132 -281.617927) (xy 104.553026 -281.669104)
			(xy 104.537014 -281.718383) (xy 104.513491 -281.76455) (xy 104.483035 -281.806469) (xy 104.446397 -281.843107)
			(xy 104.404478 -281.873563) (xy 104.358311 -281.897086) (xy 104.309032 -281.913098) (xy 104.257855 -281.921204)
			(xy 104.206041 -281.921204) (xy 104.154864 -281.913098) (xy 104.105585 -281.897086) (xy 104.059418 -281.873563)
			(xy 104.017499 -281.843107) (xy 103.980861 -281.806469) (xy 103.950405 -281.76455) (xy 103.926882 -281.718383)
			(xy 103.91087 -281.669104) (xy 103.902764 -281.617927) (xy 103.902256 -281.59202) (xy 103.902852 -281.564303)
			(xy 103.912174 -281.509656) (xy 103.920798 -281.483308) (xy 103.928672 -281.46121) (xy 103.723694 -281.106372)
			(xy 103.700834 -281.102054) (xy 103.676009 -281.096858) (xy 103.628203 -281.079927) (xy 103.583555 -281.055874)
			(xy 103.543117 -281.025267) (xy 103.507844 -280.988827) (xy 103.478568 -280.947415) (xy 103.45598 -280.902007)
			(xy 103.440613 -280.853676) (xy 103.43283 -280.803562) (xy 103.432356 -280.778204) (xy 101.271832 -280.778204)
			(xy 101.271832 -280.778712) (xy 101.271241 -280.806228) (xy 101.262055 -280.860489) (xy 101.253544 -280.886662)
			(xy 101.245924 -280.908506) (xy 101.451156 -281.263852) (xy 101.474016 -281.26817) (xy 101.498826 -281.273386)
			(xy 101.546603 -281.290334) (xy 101.591222 -281.314398) (xy 101.631628 -281.345012) (xy 101.66687 -281.381453)
			(xy 101.696116 -281.422861) (xy 101.718675 -281.468259) (xy 101.734016 -281.516576) (xy 101.741776 -281.566673)
			(xy 101.74224 -281.59202) (xy 101.741732 -281.617927) (xy 101.733626 -281.669104) (xy 101.717614 -281.718383)
			(xy 101.694091 -281.76455) (xy 101.663635 -281.806469) (xy 101.626997 -281.843107) (xy 101.585078 -281.873563)
			(xy 101.538911 -281.897086) (xy 101.489632 -281.913098) (xy 101.438455 -281.921204) (xy 101.386641 -281.921204)
			(xy 101.335464 -281.913098) (xy 101.286185 -281.897086) (xy 101.240018 -281.873563) (xy 101.198099 -281.843107)
			(xy 101.161461 -281.806469) (xy 101.131005 -281.76455) (xy 101.107482 -281.718383) (xy 101.09147 -281.669104)
			(xy 101.083364 -281.617927) (xy 101.082856 -281.59202) (xy 101.083452 -281.564303) (xy 101.092774 -281.509656)
			(xy 101.101398 -281.483308) (xy 101.109272 -281.46121) (xy 100.904294 -281.106372) (xy 100.881434 -281.102054)
			(xy 100.856609 -281.096858) (xy 100.808803 -281.079927) (xy 100.764155 -281.055874) (xy 100.723717 -281.025267)
			(xy 100.688444 -280.988827) (xy 100.659168 -280.947415) (xy 100.63658 -280.902007) (xy 100.621213 -280.853676)
			(xy 100.61343 -280.803562) (xy 100.612956 -280.778204) (xy 98.452432 -280.778204) (xy 98.451927 -280.803537)
			(xy 98.444175 -280.853607) (xy 98.428854 -280.901902) (xy 98.406324 -280.947284) (xy 98.377117 -280.988685)
			(xy 98.34192 -281.025131) (xy 98.301561 -281.055762) (xy 98.256992 -281.079859) (xy 98.20926 -281.096853)
			(xy 98.184462 -281.102054) (xy 98.161602 -281.106372) (xy 97.956624 -281.46121) (xy 97.964498 -281.483308)
			(xy 97.973138 -281.509652) (xy 97.982453 -281.564301) (xy 97.98304 -281.59202) (xy 97.982532 -281.61791)
			(xy 99.20371 -281.61791) (xy 99.20371 -281.56609) (xy 99.211817 -281.514907) (xy 99.227832 -281.465624)
			(xy 99.25136 -281.419452) (xy 99.281822 -281.37753) (xy 99.318467 -281.34089) (xy 99.360393 -281.310435)
			(xy 99.406568 -281.286913) (xy 99.455854 -281.270906) (xy 99.507038 -281.262806) (xy 99.532948 -281.262328)
			(xy 99.558462 -281.262762) (xy 99.608879 -281.270631) (xy 99.657482 -281.286173) (xy 99.70311 -281.309017)
			(xy 99.744675 -281.338618) (xy 99.781182 -281.374269) (xy 99.796854 -281.394408) (xy 100.208842 -281.394408)
			(xy 100.224493 -281.374254) (xy 100.261007 -281.338611) (xy 100.302577 -281.309019) (xy 100.34821 -281.286186)
			(xy 100.396816 -281.270657) (xy 100.447235 -281.262802) (xy 100.472748 -281.262328) (xy 100.498654 -281.2628)
			(xy 100.549829 -281.270912) (xy 100.599104 -281.286928) (xy 100.645267 -281.310456) (xy 100.687182 -281.340914)
			(xy 100.723817 -281.377554) (xy 100.754269 -281.419474) (xy 100.77779 -281.465641) (xy 100.7938 -281.514918)
			(xy 100.801904 -281.566093) (xy 100.801904 -281.617907) (xy 100.7938 -281.669082) (xy 100.77779 -281.718359)
			(xy 100.754269 -281.764526) (xy 100.723817 -281.806446) (xy 100.687182 -281.843086) (xy 100.645267 -281.873544)
			(xy 100.599104 -281.897072) (xy 100.549829 -281.913088) (xy 100.498654 -281.9212) (xy 100.472748 -281.921712)
			(xy 100.447238 -281.921192) (xy 100.396825 -281.913339) (xy 100.348225 -281.897813) (xy 100.302596 -281.874985)
			(xy 100.26103 -281.8454) (xy 100.224517 -281.809764) (xy 100.208842 -281.789632) (xy 99.796854 -281.789632)
			(xy 99.781158 -281.809749) (xy 99.744652 -281.845392) (xy 99.703091 -281.874987) (xy 99.657467 -281.897826)
			(xy 99.60887 -281.913365) (xy 99.558459 -281.921231) (xy 99.532948 -281.921712) (xy 99.507038 -281.921194)
			(xy 99.455854 -281.913094) (xy 99.406568 -281.897087) (xy 99.360393 -281.873565) (xy 99.318467 -281.84311)
			(xy 99.281822 -281.80647) (xy 99.25136 -281.764548) (xy 99.227832 -281.718376) (xy 99.211817 -281.669093)
			(xy 99.20371 -281.61791) (xy 97.982532 -281.61791) (xy 97.982532 -281.617927) (xy 97.974426 -281.669104)
			(xy 97.958414 -281.718383) (xy 97.934891 -281.76455) (xy 97.904435 -281.806469) (xy 97.867797 -281.843107)
			(xy 97.825878 -281.873563) (xy 97.779711 -281.897086) (xy 97.730432 -281.913098) (xy 97.679255 -281.921204)
			(xy 97.627441 -281.921204) (xy 97.576264 -281.913098) (xy 97.526985 -281.897086) (xy 97.480818 -281.873563)
			(xy 97.438899 -281.843107) (xy 97.402261 -281.806469) (xy 97.371805 -281.76455) (xy 97.348282 -281.718383)
			(xy 97.33227 -281.669104) (xy 97.324164 -281.617927) (xy 97.323656 -281.59202) (xy 96.10344 -281.59202)
			(xy 96.103032 -281.617397) (xy 96.095259 -281.667553) (xy 96.079885 -281.715923) (xy 96.057273 -281.761362)
			(xy 96.027958 -281.802795) (xy 95.992635 -281.839241) (xy 95.95214 -281.869837) (xy 95.907431 -281.89386)
			(xy 95.859566 -281.910741) (xy 95.834708 -281.91587) (xy 95.811848 -281.920188) (xy 95.60687 -282.275026)
			(xy 95.614744 -282.297124) (xy 95.623311 -282.32348) (xy 95.632506 -282.378127) (xy 95.633032 -282.405836)
			(xy 95.913956 -282.405836) (xy 95.914464 -282.379949) (xy 95.922563 -282.328811) (xy 95.938562 -282.279571)
			(xy 95.962068 -282.233439) (xy 95.9925 -282.191552) (xy 96.02911 -282.154942) (xy 96.070997 -282.12451)
			(xy 96.117129 -282.101004) (xy 96.166369 -282.085005) (xy 96.217507 -282.076906) (xy 96.269281 -282.076906)
			(xy 96.320419 -282.085005) (xy 96.369659 -282.101004) (xy 96.415791 -282.12451) (xy 96.457678 -282.154942)
			(xy 96.494288 -282.191552) (xy 96.52472 -282.233439) (xy 96.548226 -282.279571) (xy 96.564225 -282.328811)
			(xy 96.572324 -282.379949) (xy 96.572832 -282.405836) (xy 96.572832 -282.406344) (xy 96.572295 -282.431704)
			(xy 96.854052 -282.431704) (xy 96.854052 -282.379896) (xy 96.862157 -282.328725) (xy 96.878166 -282.279453)
			(xy 96.901687 -282.233291) (xy 96.932138 -282.191377) (xy 96.968772 -282.154742) (xy 97.010686 -282.12429)
			(xy 97.056847 -282.100769) (xy 97.106119 -282.084758) (xy 97.15729 -282.076653) (xy 97.183194 -282.076144)
			(xy 97.208707 -282.076611) (xy 97.259122 -282.084472) (xy 97.307725 -282.100007) (xy 97.353354 -282.122845)
			(xy 97.394919 -282.152441) (xy 97.431427 -282.188087) (xy 97.4471 -282.208224) (xy 97.859088 -282.208224)
			(xy 97.874775 -282.188099) (xy 97.911281 -282.152454) (xy 97.952843 -282.122858) (xy 97.998469 -282.10002)
			(xy 98.047069 -282.084484) (xy 98.097483 -282.076622) (xy 98.122994 -282.076144) (xy 98.148907 -282.076553)
			(xy 98.200094 -282.08466) (xy 98.249383 -282.100674) (xy 98.295559 -282.124201) (xy 98.337487 -282.154663)
			(xy 98.374133 -282.191308) (xy 98.404596 -282.233235) (xy 98.428124 -282.279412) (xy 98.444139 -282.3287)
			(xy 98.452246 -282.379887) (xy 98.452246 -282.431713) (xy 98.444139 -282.4829) (xy 98.428124 -282.532188)
			(xy 98.404596 -282.578365) (xy 98.374133 -282.620292) (xy 98.337487 -282.656937) (xy 98.295559 -282.687399)
			(xy 98.249383 -282.710926) (xy 98.200094 -282.72694) (xy 98.148907 -282.735047) (xy 98.122994 -282.735528)
			(xy 98.097483 -282.735041) (xy 98.047069 -282.72718) (xy 97.998468 -282.711647) (xy 97.95284 -282.688813)
			(xy 97.911274 -282.659222) (xy 97.874762 -282.623582) (xy 97.859088 -282.603448) (xy 97.4471 -282.603448)
			(xy 97.43144 -282.623594) (xy 97.394926 -282.659235) (xy 97.353357 -282.688826) (xy 97.307726 -282.71166)
			(xy 97.259123 -282.727192) (xy 97.208707 -282.735052) (xy 97.183194 -282.735528) (xy 97.15729 -282.734947)
			(xy 97.106119 -282.726842) (xy 97.056847 -282.710831) (xy 97.010686 -282.68731) (xy 96.968772 -282.656858)
			(xy 96.932138 -282.620223) (xy 96.901687 -282.578309) (xy 96.878166 -282.532147) (xy 96.862157 -282.482875)
			(xy 96.854052 -282.431704) (xy 96.572295 -282.431704) (xy 96.572249 -282.43386) (xy 96.563058 -282.488121)
			(xy 96.554544 -282.514294) (xy 96.546924 -282.536392) (xy 96.752156 -282.891738) (xy 96.775016 -282.896056)
			(xy 96.799823 -282.901285) (xy 96.847599 -282.918232) (xy 96.892217 -282.942295) (xy 96.932623 -282.972907)
			(xy 96.967865 -283.009346) (xy 96.997111 -283.050752) (xy 97.019671 -283.096149) (xy 97.035013 -283.144464)
			(xy 97.042775 -283.194559) (xy 97.04324 -283.219906) (xy 99.203256 -283.219906) (xy 99.203737 -283.19456)
			(xy 99.21151 -283.144468) (xy 99.226857 -283.096156) (xy 99.249417 -283.050761) (xy 99.278659 -283.009354)
			(xy 99.313894 -282.97291) (xy 99.354291 -282.942288) (xy 99.398899 -282.918209) (xy 99.446666 -282.901241)
			(xy 99.47148 -282.896056) (xy 99.49434 -282.891738) (xy 99.699318 -282.5369) (xy 99.691698 -282.514802)
			(xy 99.683062 -282.488391) (xy 99.673735 -282.433617) (xy 99.673156 -282.405836) (xy 99.673664 -282.379949)
			(xy 99.681763 -282.328811) (xy 99.697762 -282.279571) (xy 99.721268 -282.233439) (xy 99.7517 -282.191552)
			(xy 99.78831 -282.154942) (xy 99.830197 -282.12451) (xy 99.876329 -282.101004) (xy 99.925569 -282.085005)
			(xy 99.976707 -282.076906) (xy 100.028481 -282.076906) (xy 100.079619 -282.085005) (xy 100.128859 -282.101004)
			(xy 100.174991 -282.12451) (xy 100.216878 -282.154942) (xy 100.253488 -282.191552) (xy 100.28392 -282.233439)
			(xy 100.307426 -282.279571) (xy 100.323425 -282.328811) (xy 100.331524 -282.379949) (xy 100.332032 -282.405836)
			(xy 101.552756 -282.405836) (xy 101.553216 -282.380501) (xy 101.560977 -282.33043) (xy 101.576305 -282.282135)
			(xy 101.598841 -282.236753) (xy 101.628054 -282.195352) (xy 101.663256 -282.158908) (xy 101.703619 -282.128277)
			(xy 101.748192 -282.104181) (xy 101.795927 -282.087187) (xy 101.820726 -282.081986) (xy 101.843586 -282.077668)
			(xy 102.048818 -281.722322) (xy 102.041198 -281.700478) (xy 102.03257 -281.674197) (xy 102.023258 -281.619675)
			(xy 102.022656 -281.59202) (xy 102.023164 -281.566113) (xy 102.03127 -281.514936) (xy 102.047282 -281.465657)
			(xy 102.070805 -281.41949) (xy 102.101261 -281.377571) (xy 102.137899 -281.340933) (xy 102.179818 -281.310477)
			(xy 102.225985 -281.286954) (xy 102.275264 -281.270942) (xy 102.326441 -281.262836) (xy 102.378255 -281.262836)
			(xy 102.429432 -281.270942) (xy 102.478711 -281.286954) (xy 102.524878 -281.310477) (xy 102.566797 -281.340933)
			(xy 102.603435 -281.377571) (xy 102.633891 -281.41949) (xy 102.657414 -281.465657) (xy 102.673426 -281.514936)
			(xy 102.681532 -281.566113) (xy 102.68204 -281.59202) (xy 102.681632 -281.617397) (xy 102.673859 -281.667553)
			(xy 102.658485 -281.715923) (xy 102.635873 -281.761362) (xy 102.606558 -281.802795) (xy 102.571235 -281.839241)
			(xy 102.53074 -281.869837) (xy 102.486031 -281.89386) (xy 102.438166 -281.910741) (xy 102.413308 -281.91587)
			(xy 102.390448 -281.920188) (xy 102.18547 -282.275026) (xy 102.193344 -282.297124) (xy 102.201911 -282.32348)
			(xy 102.211106 -282.378127) (xy 102.211632 -282.405836) (xy 102.211124 -282.431704) (xy 103.432652 -282.431704)
			(xy 103.432652 -282.379896) (xy 103.440757 -282.328725) (xy 103.456766 -282.279453) (xy 103.480287 -282.233291)
			(xy 103.510738 -282.191377) (xy 103.547372 -282.154742) (xy 103.589286 -282.12429) (xy 103.635447 -282.100769)
			(xy 103.684719 -282.084758) (xy 103.73589 -282.076653) (xy 103.761794 -282.076144) (xy 103.787307 -282.076611)
			(xy 103.837722 -282.084472) (xy 103.886325 -282.100007) (xy 103.931954 -282.122845) (xy 103.973519 -282.152441)
			(xy 104.010027 -282.188087) (xy 104.0257 -282.208224) (xy 104.437688 -282.208224) (xy 104.453375 -282.188099)
			(xy 104.489881 -282.152454) (xy 104.531443 -282.122858) (xy 104.577069 -282.10002) (xy 104.625669 -282.084484)
			(xy 104.676083 -282.076622) (xy 104.701594 -282.076144) (xy 104.727507 -282.076553) (xy 104.778694 -282.08466)
			(xy 104.827983 -282.100674) (xy 104.874159 -282.124201) (xy 104.916087 -282.154663) (xy 104.952733 -282.191308)
			(xy 104.983196 -282.233235) (xy 105.006724 -282.279412) (xy 105.022739 -282.3287) (xy 105.030846 -282.379887)
			(xy 105.030846 -282.431713) (xy 105.022739 -282.4829) (xy 105.006724 -282.532188) (xy 104.983196 -282.578365)
			(xy 104.952733 -282.620292) (xy 104.916087 -282.656937) (xy 104.874159 -282.687399) (xy 104.827983 -282.710926)
			(xy 104.778694 -282.72694) (xy 104.727507 -282.735047) (xy 104.701594 -282.735528) (xy 104.676083 -282.735041)
			(xy 104.625669 -282.72718) (xy 104.577068 -282.711647) (xy 104.53144 -282.688813) (xy 104.489874 -282.659222)
			(xy 104.453362 -282.623582) (xy 104.437688 -282.603448) (xy 104.0257 -282.603448) (xy 104.01004 -282.623594)
			(xy 103.973526 -282.659235) (xy 103.931957 -282.688826) (xy 103.886326 -282.71166) (xy 103.837723 -282.727192)
			(xy 103.787307 -282.735052) (xy 103.761794 -282.735528) (xy 103.73589 -282.734947) (xy 103.684719 -282.726842)
			(xy 103.635447 -282.710831) (xy 103.589286 -282.68731) (xy 103.547372 -282.656858) (xy 103.510738 -282.620223)
			(xy 103.480287 -282.578309) (xy 103.456766 -282.532147) (xy 103.440757 -282.482875) (xy 103.432652 -282.431704)
			(xy 102.211124 -282.431704) (xy 102.211124 -282.431723) (xy 102.203025 -282.482861) (xy 102.187026 -282.532101)
			(xy 102.16352 -282.578233) (xy 102.133088 -282.62012) (xy 102.096478 -282.65673) (xy 102.054591 -282.687162)
			(xy 102.008459 -282.710668) (xy 101.959219 -282.726667) (xy 101.908081 -282.734766) (xy 101.856307 -282.734766)
			(xy 101.805169 -282.726667) (xy 101.755929 -282.710668) (xy 101.709797 -282.687162) (xy 101.66791 -282.65673)
			(xy 101.6313 -282.62012) (xy 101.600868 -282.578233) (xy 101.577362 -282.532101) (xy 101.561363 -282.482861)
			(xy 101.553264 -282.431723) (xy 101.552756 -282.405836) (xy 100.332032 -282.405836) (xy 100.331594 -282.431161)
			(xy 100.323857 -282.481217) (xy 100.308554 -282.5295) (xy 100.286046 -282.574874) (xy 100.256862 -282.616272)
			(xy 100.22169 -282.652718) (xy 100.181356 -282.683356) (xy 100.136812 -282.707464) (xy 100.089103 -282.724474)
			(xy 100.064316 -282.729686) (xy 100.041456 -282.734004) (xy 99.836224 -283.089096) (xy 99.844098 -283.111194)
			(xy 99.852735 -283.137539) (xy 99.862052 -283.192188) (xy 99.86264 -283.219906) (xy 99.862132 -283.245791)
			(xy 101.083549 -283.245791) (xy 101.083549 -283.194009) (xy 101.091651 -283.142863) (xy 101.107654 -283.093616)
			(xy 101.131165 -283.047478) (xy 101.161604 -283.005586) (xy 101.198223 -282.968973) (xy 101.240119 -282.93854)
			(xy 101.28626 -282.915036) (xy 101.33551 -282.89904) (xy 101.386657 -282.890946) (xy 101.412548 -282.890468)
			(xy 101.43806 -282.890926) (xy 101.488475 -282.898793) (xy 101.537077 -282.914332) (xy 101.582705 -282.937172)
			(xy 101.62427 -282.966767) (xy 101.66078 -283.002412) (xy 101.676454 -283.022548) (xy 102.088442 -283.022548)
			(xy 102.104077 -283.002381) (xy 102.140596 -282.966741) (xy 102.18217 -282.937153) (xy 102.227806 -282.914323)
			(xy 102.276414 -282.898795) (xy 102.326834 -282.890941) (xy 102.352348 -282.890468) (xy 102.378233 -282.890967)
			(xy 102.429366 -282.899073) (xy 102.478601 -282.915077) (xy 102.524727 -282.938585) (xy 102.566608 -282.969019)
			(xy 102.603213 -283.005629) (xy 102.63364 -283.047514) (xy 102.657142 -283.093643) (xy 102.673139 -283.142881)
			(xy 102.681237 -283.194015) (xy 102.681237 -283.219906) (xy 104.842056 -283.219906) (xy 104.842537 -283.19456)
			(xy 104.85031 -283.144468) (xy 104.865657 -283.096156) (xy 104.888217 -283.050761) (xy 104.917459 -283.009354)
			(xy 104.952694 -282.97291) (xy 104.993091 -282.942288) (xy 105.037699 -282.918209) (xy 105.085466 -282.901241)
			(xy 105.11028 -282.896056) (xy 105.13314 -282.891738) (xy 105.338118 -282.5369) (xy 105.330498 -282.514802)
			(xy 105.321862 -282.488391) (xy 105.312535 -282.433617) (xy 105.311956 -282.405836) (xy 105.312464 -282.379949)
			(xy 105.320563 -282.328811) (xy 105.336562 -282.279571) (xy 105.360068 -282.233439) (xy 105.3905 -282.191552)
			(xy 105.42711 -282.154942) (xy 105.468997 -282.12451) (xy 105.515129 -282.101004) (xy 105.564369 -282.085005)
			(xy 105.615507 -282.076906) (xy 105.667281 -282.076906) (xy 105.718419 -282.085005) (xy 105.767659 -282.101004)
			(xy 105.813791 -282.12451) (xy 105.855678 -282.154942) (xy 105.892288 -282.191552) (xy 105.92272 -282.233439)
			(xy 105.946226 -282.279571) (xy 105.962225 -282.328811) (xy 105.970324 -282.379949) (xy 105.970832 -282.405836)
			(xy 105.970394 -282.431161) (xy 105.962657 -282.481217) (xy 105.947354 -282.5295) (xy 105.924846 -282.574874)
			(xy 105.895662 -282.616272) (xy 105.86049 -282.652718) (xy 105.820156 -282.683356) (xy 105.775612 -282.707464)
			(xy 105.727903 -282.724474) (xy 105.703116 -282.729686) (xy 105.680256 -282.734004) (xy 105.475024 -283.089096)
			(xy 105.482898 -283.111194) (xy 105.491535 -283.137539) (xy 105.500852 -283.192188) (xy 105.50144 -283.219906)
			(xy 105.500932 -283.245813) (xy 105.492826 -283.29699) (xy 105.476814 -283.346269) (xy 105.453291 -283.392436)
			(xy 105.422835 -283.434355) (xy 105.386197 -283.470993) (xy 105.344278 -283.501449) (xy 105.298111 -283.524972)
			(xy 105.248832 -283.540984) (xy 105.197655 -283.54909) (xy 105.145841 -283.54909) (xy 105.094664 -283.540984)
			(xy 105.045385 -283.524972) (xy 104.999218 -283.501449) (xy 104.957299 -283.470993) (xy 104.920661 -283.434355)
			(xy 104.890205 -283.392436) (xy 104.866682 -283.346269) (xy 104.85067 -283.29699) (xy 104.842564 -283.245813)
			(xy 104.842056 -283.219906) (xy 102.681237 -283.219906) (xy 102.681237 -283.245785) (xy 102.673139 -283.296919)
			(xy 102.657142 -283.346157) (xy 102.63364 -283.392286) (xy 102.603213 -283.434171) (xy 102.566608 -283.470781)
			(xy 102.524727 -283.501215) (xy 102.478601 -283.524723) (xy 102.429366 -283.540727) (xy 102.378233 -283.548833)
			(xy 102.352348 -283.549344) (xy 102.326836 -283.548851) (xy 102.276422 -283.540996) (xy 102.227819 -283.525467)
			(xy 102.18219 -283.502633) (xy 102.140624 -283.473042) (xy 102.104115 -283.437399) (xy 102.088442 -283.417264)
			(xy 101.676454 -283.417264) (xy 101.660739 -283.437366) (xy 101.624239 -283.473014) (xy 101.582683 -283.502612)
			(xy 101.537062 -283.525454) (xy 101.488467 -283.540995) (xy 101.438058 -283.548863) (xy 101.412548 -283.549344)
			(xy 101.386657 -283.548854) (xy 101.33551 -283.54076) (xy 101.28626 -283.524764) (xy 101.240119 -283.50126)
			(xy 101.198223 -283.470827) (xy 101.161604 -283.434214) (xy 101.131165 -283.392322) (xy 101.107654 -283.346184)
			(xy 101.091651 -283.296937) (xy 101.083549 -283.245791) (xy 99.862132 -283.245791) (xy 99.862132 -283.245813)
			(xy 99.854026 -283.29699) (xy 99.838014 -283.346269) (xy 99.814491 -283.392436) (xy 99.784035 -283.434355)
			(xy 99.747397 -283.470993) (xy 99.705478 -283.501449) (xy 99.659311 -283.524972) (xy 99.610032 -283.540984)
			(xy 99.558855 -283.54909) (xy 99.507041 -283.54909) (xy 99.455864 -283.540984) (xy 99.406585 -283.524972)
			(xy 99.360418 -283.501449) (xy 99.318499 -283.470993) (xy 99.281861 -283.434355) (xy 99.251405 -283.392436)
			(xy 99.227882 -283.346269) (xy 99.21187 -283.29699) (xy 99.203764 -283.245813) (xy 99.203256 -283.219906)
			(xy 97.04324 -283.219906) (xy 97.042732 -283.245813) (xy 97.034626 -283.29699) (xy 97.018614 -283.346269)
			(xy 96.995091 -283.392436) (xy 96.964635 -283.434355) (xy 96.927997 -283.470993) (xy 96.886078 -283.501449)
			(xy 96.839911 -283.524972) (xy 96.790632 -283.540984) (xy 96.739455 -283.54909) (xy 96.687641 -283.54909)
			(xy 96.636464 -283.540984) (xy 96.587185 -283.524972) (xy 96.541018 -283.501449) (xy 96.499099 -283.470993)
			(xy 96.462461 -283.434355) (xy 96.432005 -283.392436) (xy 96.408482 -283.346269) (xy 96.39247 -283.29699)
			(xy 96.384364 -283.245813) (xy 96.383856 -283.219906) (xy 96.384448 -283.192189) (xy 96.393773 -283.137542)
			(xy 96.402398 -283.111194) (xy 96.410272 -283.089096) (xy 96.205294 -282.734004) (xy 96.18218 -282.729686)
			(xy 96.15736 -282.724514) (xy 96.109579 -282.707563) (xy 96.064958 -282.683494) (xy 96.024551 -282.652875)
			(xy 95.989309 -282.616428) (xy 95.960065 -282.575014) (xy 95.937508 -282.52961) (xy 95.922171 -282.481287)
			(xy 95.914416 -282.431185) (xy 95.913956 -282.405836) (xy 95.633032 -282.405836) (xy 95.632524 -282.431723)
			(xy 95.624425 -282.482861) (xy 95.608426 -282.532101) (xy 95.58492 -282.578233) (xy 95.554488 -282.62012)
			(xy 95.517878 -282.65673) (xy 95.475991 -282.687162) (xy 95.429859 -282.710668) (xy 95.380619 -282.726667)
			(xy 95.329481 -282.734766) (xy 95.277707 -282.734766) (xy 95.226569 -282.726667) (xy 95.177329 -282.710668)
			(xy 95.131197 -282.687162) (xy 95.08931 -282.65673) (xy 95.0527 -282.62012) (xy 95.022268 -282.578233)
			(xy 94.998762 -282.532101) (xy 94.982763 -282.482861) (xy 94.974664 -282.431723) (xy 94.974156 -282.405836)
			(xy 93.75394 -282.405836) (xy 93.753432 -282.431743) (xy 93.745326 -282.48292) (xy 93.729314 -282.532199)
			(xy 93.705791 -282.578366) (xy 93.675335 -282.620285) (xy 93.638697 -282.656923) (xy 93.596778 -282.687379)
			(xy 93.550611 -282.710902) (xy 93.501332 -282.726914) (xy 93.450155 -282.73502) (xy 93.398341 -282.73502)
			(xy 93.347164 -282.726914) (xy 93.297885 -282.710902) (xy 93.251718 -282.687379) (xy 93.209799 -282.656923)
			(xy 93.173161 -282.620285) (xy 93.142705 -282.578366) (xy 93.119182 -282.532199) (xy 93.10317 -282.48292)
			(xy 93.095064 -282.431743) (xy 93.094556 -282.405836) (xy 91.87434 -282.405836) (xy 91.873903 -282.431201)
			(xy 91.86615 -282.481333) (xy 91.850801 -282.529685) (xy 91.828221 -282.575111) (xy 91.798942 -282.616537)
			(xy 91.763657 -282.652984) (xy 91.723202 -282.683591) (xy 91.678531 -282.707632) (xy 91.630703 -282.724539)
			(xy 91.605862 -282.729686) (xy 91.583002 -282.734004) (xy 91.378024 -283.089096) (xy 91.385644 -283.11094)
			(xy 91.394193 -283.137235) (xy 91.40339 -283.191753) (xy 91.403932 -283.219398) (xy 91.403932 -283.219906)
			(xy 91.403424 -283.245787) (xy 92.625176 -283.245787) (xy 92.625176 -283.194013) (xy 92.633275 -283.142878)
			(xy 92.649273 -283.093638) (xy 92.672778 -283.047508) (xy 92.703209 -283.005622) (xy 92.739818 -282.969013)
			(xy 92.781703 -282.938581) (xy 92.827833 -282.915076) (xy 92.877072 -282.899076) (xy 92.928207 -282.890976)
			(xy 92.954094 -282.890468) (xy 92.979605 -282.890965) (xy 93.030018 -282.898824) (xy 93.078619 -282.914355)
			(xy 93.124247 -282.937187) (xy 93.165813 -282.966776) (xy 93.202325 -283.002415) (xy 93.218 -283.022548)
			(xy 93.629988 -283.022548) (xy 93.645654 -283.002407) (xy 93.682167 -282.966766) (xy 93.723734 -282.937174)
			(xy 93.769364 -282.91434) (xy 93.817967 -282.898806) (xy 93.868382 -282.890945) (xy 93.893894 -282.890468)
			(xy 93.919784 -282.890937) (xy 93.970927 -282.899036) (xy 94.020174 -282.915037) (xy 94.066311 -282.938544)
			(xy 94.108202 -282.968979) (xy 94.144817 -283.005593) (xy 94.175253 -283.047484) (xy 94.198761 -283.093621)
			(xy 94.214762 -283.142867) (xy 94.222863 -283.19401) (xy 94.222863 -283.24579) (xy 94.214762 -283.296933)
			(xy 94.198761 -283.346179) (xy 94.175253 -283.392316) (xy 94.144817 -283.434207) (xy 94.108202 -283.470821)
			(xy 94.066311 -283.501256) (xy 94.020174 -283.524763) (xy 93.970927 -283.540764) (xy 93.919784 -283.548863)
			(xy 93.893894 -283.549344) (xy 93.868381 -283.54889) (xy 93.817964 -283.541027) (xy 93.769361 -283.52549)
			(xy 93.723732 -283.502649) (xy 93.682168 -283.473051) (xy 93.64566 -283.437402) (xy 93.629988 -283.417264)
			(xy 93.218 -283.417264) (xy 93.202317 -283.437392) (xy 93.16581 -283.473038) (xy 93.124247 -283.502633)
			(xy 93.078621 -283.525471) (xy 93.03002 -283.541006) (xy 92.979606 -283.548867) (xy 92.954094 -283.549344)
			(xy 92.928207 -283.548824) (xy 92.877072 -283.540724) (xy 92.827833 -283.524724) (xy 92.781703 -283.501219)
			(xy 92.739818 -283.470787) (xy 92.703209 -283.434178) (xy 92.672778 -283.392292) (xy 92.649273 -283.346162)
			(xy 92.633275 -283.296922) (xy 92.625176 -283.245787) (xy 91.403424 -283.245787) (xy 91.403424 -283.245793)
			(xy 91.395325 -283.296931) (xy 91.379326 -283.346171) (xy 91.35582 -283.392303) (xy 91.325388 -283.43419)
			(xy 91.288778 -283.4708) (xy 91.246891 -283.501232) (xy 91.200759 -283.524738) (xy 91.151519 -283.540737)
			(xy 91.100381 -283.548836) (xy 91.048607 -283.548836) (xy 90.997469 -283.540737) (xy 90.948229 -283.524738)
			(xy 90.902097 -283.501232) (xy 90.86021 -283.4708) (xy 90.8236 -283.43419) (xy 90.793168 -283.392303)
			(xy 90.769662 -283.346171) (xy 90.753663 -283.296931) (xy 90.745564 -283.245793) (xy 90.745056 -283.219906)
			(xy 88.584532 -283.219906) (xy 88.584024 -283.245793) (xy 88.575925 -283.296931) (xy 88.559926 -283.346171)
			(xy 88.53642 -283.392303) (xy 88.505988 -283.43419) (xy 88.469378 -283.4708) (xy 88.427491 -283.501232)
			(xy 88.381359 -283.524738) (xy 88.332119 -283.540737) (xy 88.280981 -283.548836) (xy 88.229207 -283.548836)
			(xy 88.178069 -283.540737) (xy 88.128829 -283.524738) (xy 88.082697 -283.501232) (xy 88.04081 -283.4708)
			(xy 88.0042 -283.43419) (xy 87.973768 -283.392303) (xy 87.950262 -283.346171) (xy 87.934263 -283.296931)
			(xy 87.926164 -283.245793) (xy 87.925656 -283.219906) (xy 87.926189 -283.192198) (xy 87.935382 -283.137551)
			(xy 87.943944 -283.111194) (xy 87.951818 -283.089096) (xy 87.746586 -282.734004) (xy 87.723726 -282.729686)
			(xy 87.698938 -282.724431) (xy 87.651203 -282.70745) (xy 87.606628 -282.683364) (xy 87.566263 -282.652742)
			(xy 87.531059 -282.616304) (xy 87.501844 -282.574908) (xy 87.479308 -282.52953) (xy 87.463981 -282.481238)
			(xy 87.456223 -282.431169) (xy 87.455756 -282.405836) (xy 87.17534 -282.405836) (xy 87.174832 -282.431743)
			(xy 87.166726 -282.48292) (xy 87.150714 -282.532199) (xy 87.127191 -282.578366) (xy 87.096735 -282.620285)
			(xy 87.060097 -282.656923) (xy 87.018178 -282.687379) (xy 86.972011 -282.710902) (xy 86.922732 -282.726914)
			(xy 86.871555 -282.73502) (xy 86.819741 -282.73502) (xy 86.768564 -282.726914) (xy 86.719285 -282.710902)
			(xy 86.673118 -282.687379) (xy 86.631199 -282.656923) (xy 86.594561 -282.620285) (xy 86.564105 -282.578366)
			(xy 86.540582 -282.532199) (xy 86.52457 -282.48292) (xy 86.516464 -282.431743) (xy 86.515956 -282.405836)
			(xy 2.509012 -282.405836) (xy 2.509012 -284.033722) (xy 86.515956 -284.033722) (xy 86.516464 -284.007815)
			(xy 86.52457 -283.956638) (xy 86.540582 -283.907359) (xy 86.564105 -283.861192) (xy 86.594561 -283.819273)
			(xy 86.631199 -283.782635) (xy 86.673118 -283.752179) (xy 86.719285 -283.728656) (xy 86.768564 -283.712644)
			(xy 86.819741 -283.704538) (xy 86.871555 -283.704538) (xy 86.922732 -283.712644) (xy 86.972011 -283.728656)
			(xy 87.018178 -283.752179) (xy 87.060097 -283.782635) (xy 87.096735 -283.819273) (xy 87.127191 -283.861192)
			(xy 87.150714 -283.907359) (xy 87.166726 -283.956638) (xy 87.174832 -284.007815) (xy 87.17534 -284.033722)
			(xy 334.456024 -284.033722) (xy 334.456532 -284.007815) (xy 334.464638 -283.956638) (xy 334.48065 -283.907359)
			(xy 334.504173 -283.861192) (xy 334.534629 -283.819273) (xy 334.571267 -283.782635) (xy 334.613186 -283.752179)
			(xy 334.659353 -283.728656) (xy 334.708632 -283.712644) (xy 334.759809 -283.704538) (xy 334.811623 -283.704538)
			(xy 334.8628 -283.712644) (xy 334.912079 -283.728656) (xy 334.958246 -283.752179) (xy 335.000165 -283.782635)
			(xy 335.036803 -283.819273) (xy 335.067259 -283.861192) (xy 335.090782 -283.907359) (xy 335.106794 -283.956638)
			(xy 335.1149 -284.007815) (xy 335.115408 -284.033722) (xy 335.114819 -284.06144) (xy 335.105492 -284.116086)
			(xy 335.096866 -284.142434) (xy 335.088992 -284.164532) (xy 335.29397 -284.51937) (xy 335.31683 -284.523688)
			(xy 335.341643 -284.528833) (xy 335.389384 -284.545828) (xy 335.433962 -284.569927) (xy 335.474328 -284.600564)
			(xy 335.50953 -284.637016) (xy 335.538741 -284.678425) (xy 335.561271 -284.723817) (xy 335.576591 -284.772121)
			(xy 335.584339 -284.8222) (xy 335.5848 -284.847538) (xy 335.584292 -284.873425) (xy 335.576193 -284.924563)
			(xy 335.560194 -284.973803) (xy 335.536688 -285.019935) (xy 335.506256 -285.061822) (xy 335.469646 -285.098432)
			(xy 335.427759 -285.128864) (xy 335.381627 -285.15237) (xy 335.332387 -285.168369) (xy 335.281249 -285.176468)
			(xy 335.229475 -285.176468) (xy 335.178337 -285.168369) (xy 335.129097 -285.15237) (xy 335.082965 -285.128864)
			(xy 335.041078 -285.098432) (xy 335.004468 -285.061822) (xy 334.974036 -285.019935) (xy 334.95053 -284.973803)
			(xy 334.934531 -284.924563) (xy 334.926432 -284.873425) (xy 334.925924 -284.847538) (xy 334.926462 -284.81983)
			(xy 334.935651 -284.765183) (xy 334.944212 -284.738826) (xy 334.952086 -284.716728) (xy 334.747108 -284.36189)
			(xy 334.724248 -284.357572) (xy 334.699419 -284.352437) (xy 334.651638 -284.33548) (xy 334.607017 -284.311405)
			(xy 334.56661 -284.280781) (xy 334.531369 -284.24433) (xy 334.502126 -284.202912) (xy 334.479571 -284.157504)
			(xy 334.464236 -284.109178) (xy 334.456483 -284.059073) (xy 334.456024 -284.033722) (xy 87.17534 -284.033722)
			(xy 87.174755 -284.06144) (xy 87.165426 -284.116086) (xy 87.156798 -284.142434) (xy 87.148924 -284.164532)
			(xy 87.353902 -284.51937) (xy 87.376762 -284.523688) (xy 87.401564 -284.528882) (xy 87.449305 -284.545867)
			(xy 87.493884 -284.569958) (xy 87.534252 -284.600587) (xy 87.569457 -284.637033) (xy 87.598669 -284.678438)
			(xy 87.621201 -284.723825) (xy 87.636522 -284.772125) (xy 87.644271 -284.822202) (xy 87.644732 -284.847538)
			(xy 87.644224 -284.873425) (xy 87.636125 -284.924563) (xy 87.620126 -284.973803) (xy 87.59662 -285.019935)
			(xy 87.566188 -285.061822) (xy 87.529578 -285.098432) (xy 87.487691 -285.128864) (xy 87.441559 -285.15237)
			(xy 87.392319 -285.168369) (xy 87.341181 -285.176468) (xy 87.289407 -285.176468) (xy 87.238269 -285.168369)
			(xy 87.189029 -285.15237) (xy 87.142897 -285.128864) (xy 87.10101 -285.098432) (xy 87.0644 -285.061822)
			(xy 87.033968 -285.019935) (xy 87.010462 -284.973803) (xy 86.994463 -284.924563) (xy 86.986364 -284.873425)
			(xy 86.985856 -284.847538) (xy 86.986397 -284.81983) (xy 86.995584 -284.765184) (xy 87.004144 -284.738826)
			(xy 87.012018 -284.716728) (xy 86.80704 -284.36189) (xy 86.78418 -284.357572) (xy 86.759356 -284.352414)
			(xy 86.711575 -284.335461) (xy 86.666954 -284.311391) (xy 86.626545 -284.28077) (xy 86.591303 -284.244322)
			(xy 86.56206 -284.202906) (xy 86.539504 -284.1575) (xy 86.524169 -284.109175) (xy 86.516415 -284.059072)
			(xy 86.515956 -284.033722) (xy 2.509012 -284.033722) (xy 2.509012 -284.873384) (xy 85.106807 -284.873384)
			(xy 85.106807 -284.821616) (xy 85.114906 -284.770485) (xy 85.130903 -284.72125) (xy 85.154405 -284.675125)
			(xy 85.184833 -284.633243) (xy 85.221438 -284.596637) (xy 85.263319 -284.566208) (xy 85.309445 -284.542705)
			(xy 85.358679 -284.526707) (xy 85.40981 -284.518608) (xy 85.435694 -284.5181) (xy 85.461187 -284.518588)
			(xy 85.511565 -284.526449) (xy 85.560127 -284.541983) (xy 85.605714 -284.564818) (xy 85.647235 -284.594409)
			(xy 85.683698 -284.630049) (xy 85.699346 -284.65018) (xy 86.111842 -284.65018) (xy 86.127489 -284.630047)
			(xy 86.163951 -284.594407) (xy 86.205472 -284.564814) (xy 86.251059 -284.541976) (xy 86.299622 -284.526441)
			(xy 86.35 -284.518579) (xy 86.375494 -284.5181) (xy 86.401387 -284.518505) (xy 86.452535 -284.526605)
			(xy 86.501786 -284.542607) (xy 86.547927 -284.566116) (xy 86.589823 -284.596555) (xy 86.626441 -284.633172)
			(xy 86.65688 -284.675067) (xy 86.680391 -284.721208) (xy 86.696394 -284.770459) (xy 86.704495 -284.821607)
			(xy 86.704495 -284.873393) (xy 86.696394 -284.924541) (xy 86.680391 -284.973792) (xy 86.65688 -285.019933)
			(xy 86.626441 -285.061828) (xy 86.589823 -285.098445) (xy 86.547927 -285.128884) (xy 86.501786 -285.152393)
			(xy 86.452535 -285.168395) (xy 86.401387 -285.176495) (xy 86.375494 -285.176976) (xy 86.35 -285.176506)
			(xy 86.299621 -285.168643) (xy 86.251058 -285.153106) (xy 86.205471 -285.130267) (xy 86.16395 -285.100672)
			(xy 86.127489 -285.065029) (xy 86.111842 -285.044896) (xy 85.699346 -285.044896) (xy 85.683699 -285.065029)
			(xy 85.647238 -285.100671) (xy 85.605717 -285.130265) (xy 85.56013 -285.153102) (xy 85.511566 -285.168637)
			(xy 85.461188 -285.176498) (xy 85.435694 -285.176976) (xy 85.40981 -285.176392) (xy 85.358679 -285.168293)
			(xy 85.309445 -285.152295) (xy 85.263319 -285.128792) (xy 85.221438 -285.098363) (xy 85.184833 -285.061757)
			(xy 85.154405 -285.019875) (xy 85.130903 -284.97375) (xy 85.114906 -284.924515) (xy 85.106807 -284.873384)
			(xy 2.509012 -284.873384) (xy 2.509012 -285.661354) (xy 87.455756 -285.661354) (xy 87.456232 -285.63602)
			(xy 87.46399 -285.585949) (xy 87.479317 -285.537654) (xy 87.50185 -285.492273) (xy 87.531061 -285.450872)
			(xy 87.566261 -285.414427) (xy 87.606622 -285.383796) (xy 87.651194 -285.3597) (xy 87.698927 -285.342705)
			(xy 87.723726 -285.337504) (xy 87.746586 -285.333186) (xy 87.951564 -284.978094) (xy 87.943944 -284.95625)
			(xy 87.935376 -284.929894) (xy 87.926181 -284.875247) (xy 87.925656 -284.847538) (xy 87.926164 -284.821651)
			(xy 87.934263 -284.770513) (xy 87.950262 -284.721273) (xy 87.973768 -284.675141) (xy 88.0042 -284.633254)
			(xy 88.04081 -284.596644) (xy 88.082697 -284.566212) (xy 88.128829 -284.542706) (xy 88.178069 -284.526707)
			(xy 88.229207 -284.518608) (xy 88.280981 -284.518608) (xy 88.332119 -284.526707) (xy 88.381359 -284.542706)
			(xy 88.427491 -284.566212) (xy 88.469378 -284.596644) (xy 88.505988 -284.633254) (xy 88.53642 -284.675141)
			(xy 88.559926 -284.721273) (xy 88.575925 -284.770513) (xy 88.584024 -284.821651) (xy 88.584532 -284.847538)
			(xy 88.584058 -284.872872) (xy 88.576301 -284.922944) (xy 88.560975 -284.971239) (xy 88.538441 -285.016622)
			(xy 88.50923 -285.058022) (xy 88.47403 -285.094467) (xy 88.433668 -285.125098) (xy 88.389095 -285.149194)
			(xy 88.341361 -285.166187) (xy 88.316562 -285.171388) (xy 88.293702 -285.175706) (xy 88.088724 -285.530798)
			(xy 88.096344 -285.552642) (xy 88.104909 -285.578999) (xy 88.114106 -285.633646) (xy 88.114632 -285.661354)
			(xy 89.335356 -285.661354) (xy 89.335864 -285.635467) (xy 89.343963 -285.584329) (xy 89.359962 -285.535089)
			(xy 89.383468 -285.488957) (xy 89.4139 -285.44707) (xy 89.45051 -285.41046) (xy 89.492397 -285.380028)
			(xy 89.538529 -285.356522) (xy 89.587769 -285.340523) (xy 89.638907 -285.332424) (xy 89.690681 -285.332424)
			(xy 89.741819 -285.340523) (xy 89.791059 -285.356522) (xy 89.837191 -285.380028) (xy 89.879078 -285.41046)
			(xy 89.915688 -285.44707) (xy 89.94612 -285.488957) (xy 89.969626 -285.535089) (xy 89.985625 -285.584329)
			(xy 89.993724 -285.635467) (xy 89.994232 -285.661354) (xy 90.275156 -285.661354) (xy 90.27559 -285.636007)
			(xy 90.28337 -285.585913) (xy 90.298725 -285.537599) (xy 90.321292 -285.492204) (xy 90.35054 -285.450798)
			(xy 90.385779 -285.414354) (xy 90.426181 -285.383733) (xy 90.470793 -285.359656) (xy 90.518564 -285.342688)
			(xy 90.54338 -285.337504) (xy 90.56624 -285.333186) (xy 90.771218 -284.978348) (xy 90.763344 -284.956504)
			(xy 90.754767 -284.930085) (xy 90.745569 -284.87531) (xy 90.745056 -284.847538) (xy 90.745564 -284.821651)
			(xy 90.753663 -284.770513) (xy 90.769662 -284.721273) (xy 90.793168 -284.675141) (xy 90.8236 -284.633254)
			(xy 90.86021 -284.596644) (xy 90.902097 -284.566212) (xy 90.948229 -284.542706) (xy 90.997469 -284.526707)
			(xy 91.048607 -284.518608) (xy 91.100381 -284.518608) (xy 91.151519 -284.526707) (xy 91.200759 -284.542706)
			(xy 91.246891 -284.566212) (xy 91.288778 -284.596644) (xy 91.325388 -284.633254) (xy 91.35582 -284.675141)
			(xy 91.379326 -284.721273) (xy 91.395325 -284.770513) (xy 91.403424 -284.821651) (xy 91.403932 -284.847538)
			(xy 91.403458 -284.872872) (xy 91.395701 -284.922944) (xy 91.380375 -284.971239) (xy 91.357841 -285.016622)
			(xy 91.32863 -285.058022) (xy 91.29343 -285.094467) (xy 91.253068 -285.125098) (xy 91.208495 -285.149194)
			(xy 91.160761 -285.166187) (xy 91.135962 -285.171388) (xy 91.113102 -285.175706) (xy 90.908124 -285.530544)
			(xy 90.915998 -285.552642) (xy 90.924622 -285.57899) (xy 90.933948 -285.633636) (xy 90.93454 -285.661354)
			(xy 91.214956 -285.661354) (xy 91.215464 -285.635447) (xy 91.22357 -285.58427) (xy 91.239582 -285.534991)
			(xy 91.263105 -285.488824) (xy 91.293561 -285.446905) (xy 91.330199 -285.410267) (xy 91.372118 -285.379811)
			(xy 91.418285 -285.356288) (xy 91.467564 -285.340276) (xy 91.518741 -285.33217) (xy 91.570555 -285.33217)
			(xy 91.621732 -285.340276) (xy 91.671011 -285.356288) (xy 91.717178 -285.379811) (xy 91.759097 -285.410267)
			(xy 91.795735 -285.446905) (xy 91.826191 -285.488824) (xy 91.849714 -285.534991) (xy 91.865726 -285.58427)
			(xy 91.873832 -285.635447) (xy 91.87434 -285.661354) (xy 92.154756 -285.661354) (xy 92.155232 -285.63602)
			(xy 92.16299 -285.585949) (xy 92.178317 -285.537654) (xy 92.20085 -285.492273) (xy 92.230061 -285.450872)
			(xy 92.265261 -285.414427) (xy 92.305622 -285.383796) (xy 92.350194 -285.3597) (xy 92.397927 -285.342705)
			(xy 92.422726 -285.337504) (xy 92.445586 -285.333186) (xy 92.650818 -284.97784) (xy 92.643198 -284.955996)
			(xy 92.634574 -284.929714) (xy 92.625259 -284.875193) (xy 92.624656 -284.847538) (xy 92.625164 -284.821631)
			(xy 92.63327 -284.770454) (xy 92.649282 -284.721175) (xy 92.672805 -284.675008) (xy 92.703261 -284.633089)
			(xy 92.739899 -284.596451) (xy 92.781818 -284.565995) (xy 92.827985 -284.542472) (xy 92.877264 -284.52646)
			(xy 92.928441 -284.518354) (xy 92.980255 -284.518354) (xy 93.031432 -284.52646) (xy 93.080711 -284.542472)
			(xy 93.126878 -284.565995) (xy 93.168797 -284.596451) (xy 93.205435 -284.633089) (xy 93.235891 -284.675008)
			(xy 93.259414 -284.721175) (xy 93.275426 -284.770454) (xy 93.283532 -284.821631) (xy 93.28404 -284.847538)
			(xy 93.283648 -284.872916) (xy 93.275873 -284.923072) (xy 93.260496 -284.971442) (xy 93.237881 -285.016882)
			(xy 93.208565 -285.058314) (xy 93.17324 -285.09476) (xy 93.132743 -285.125356) (xy 93.088033 -285.149379)
			(xy 93.040166 -285.166259) (xy 93.015308 -285.171388) (xy 92.992448 -285.175706) (xy 92.78747 -285.530544)
			(xy 92.795344 -285.552642) (xy 92.803916 -285.578997) (xy 92.813107 -285.633645) (xy 92.813632 -285.661354)
			(xy 93.094556 -285.661354) (xy 93.095064 -285.635467) (xy 93.103163 -285.584329) (xy 93.119162 -285.535089)
			(xy 93.142668 -285.488957) (xy 93.1731 -285.44707) (xy 93.20971 -285.41046) (xy 93.251597 -285.380028)
			(xy 93.297729 -285.356522) (xy 93.346969 -285.340523) (xy 93.398107 -285.332424) (xy 93.449881 -285.332424)
			(xy 93.501019 -285.340523) (xy 93.550259 -285.356522) (xy 93.596391 -285.380028) (xy 93.638278 -285.41046)
			(xy 93.674888 -285.44707) (xy 93.70532 -285.488957) (xy 93.728826 -285.535089) (xy 93.744825 -285.584329)
			(xy 93.752924 -285.635467) (xy 93.753432 -285.661354) (xy 94.034356 -285.661354) (xy 94.034832 -285.63602)
			(xy 94.04259 -285.585949) (xy 94.057917 -285.537654) (xy 94.08045 -285.492273) (xy 94.109661 -285.450872)
			(xy 94.144861 -285.414427) (xy 94.185222 -285.383796) (xy 94.229794 -285.3597) (xy 94.277527 -285.342705)
			(xy 94.302326 -285.337504) (xy 94.325186 -285.333186) (xy 94.530418 -284.97784) (xy 94.522798 -284.955996)
			(xy 94.514174 -284.929714) (xy 94.504859 -284.875193) (xy 94.504256 -284.847538) (xy 94.504764 -284.821631)
			(xy 94.51287 -284.770454) (xy 94.528882 -284.721175) (xy 94.552405 -284.675008) (xy 94.582861 -284.633089)
			(xy 94.619499 -284.596451) (xy 94.661418 -284.565995) (xy 94.707585 -284.542472) (xy 94.756864 -284.52646)
			(xy 94.808041 -284.518354) (xy 94.859855 -284.518354) (xy 94.911032 -284.52646) (xy 94.960311 -284.542472)
			(xy 95.006478 -284.565995) (xy 95.048397 -284.596451) (xy 95.085035 -284.633089) (xy 95.115491 -284.675008)
			(xy 95.139014 -284.721175) (xy 95.155026 -284.770454) (xy 95.163132 -284.821631) (xy 95.16364 -284.847538)
			(xy 95.163248 -284.872916) (xy 95.155473 -284.923072) (xy 95.140096 -284.971442) (xy 95.117481 -285.016882)
			(xy 95.088165 -285.058314) (xy 95.05284 -285.09476) (xy 95.012343 -285.125356) (xy 94.967633 -285.149379)
			(xy 94.919766 -285.166259) (xy 94.894908 -285.171388) (xy 94.872048 -285.175706) (xy 94.66707 -285.530544)
			(xy 94.674944 -285.552642) (xy 94.683516 -285.578997) (xy 94.692707 -285.633645) (xy 94.693232 -285.661354)
			(xy 94.974156 -285.661354) (xy 94.974664 -285.635467) (xy 94.982763 -285.584329) (xy 94.998762 -285.535089)
			(xy 95.022268 -285.488957) (xy 95.0527 -285.44707) (xy 95.08931 -285.41046) (xy 95.131197 -285.380028)
			(xy 95.177329 -285.356522) (xy 95.226569 -285.340523) (xy 95.277707 -285.332424) (xy 95.329481 -285.332424)
			(xy 95.380619 -285.340523) (xy 95.429859 -285.356522) (xy 95.475991 -285.380028) (xy 95.517878 -285.41046)
			(xy 95.554488 -285.44707) (xy 95.58492 -285.488957) (xy 95.608426 -285.535089) (xy 95.624425 -285.584329)
			(xy 95.632524 -285.635467) (xy 95.633032 -285.661354) (xy 95.913956 -285.661354) (xy 95.914432 -285.63602)
			(xy 95.92219 -285.585949) (xy 95.937517 -285.537654) (xy 95.96005 -285.492273) (xy 95.989261 -285.450872)
			(xy 96.024461 -285.414427) (xy 96.064822 -285.383796) (xy 96.109394 -285.3597) (xy 96.157127 -285.342705)
			(xy 96.181926 -285.337504) (xy 96.204786 -285.333186) (xy 96.410018 -284.97784) (xy 96.402398 -284.955996)
			(xy 96.393774 -284.929714) (xy 96.384459 -284.875193) (xy 96.383856 -284.847538) (xy 96.384364 -284.821631)
			(xy 96.39247 -284.770454) (xy 96.408482 -284.721175) (xy 96.432005 -284.675008) (xy 96.462461 -284.633089)
			(xy 96.499099 -284.596451) (xy 96.541018 -284.565995) (xy 96.587185 -284.542472) (xy 96.636464 -284.52646)
			(xy 96.687641 -284.518354) (xy 96.739455 -284.518354) (xy 96.790632 -284.52646) (xy 96.839911 -284.542472)
			(xy 96.886078 -284.565995) (xy 96.927997 -284.596451) (xy 96.964635 -284.633089) (xy 96.995091 -284.675008)
			(xy 97.018614 -284.721175) (xy 97.034626 -284.770454) (xy 97.042732 -284.821631) (xy 97.04324 -284.847538)
			(xy 97.042848 -284.872916) (xy 97.035073 -284.923072) (xy 97.019696 -284.971442) (xy 96.997081 -285.016882)
			(xy 96.967765 -285.058314) (xy 96.93244 -285.09476) (xy 96.891943 -285.125356) (xy 96.847233 -285.149379)
			(xy 96.799366 -285.166259) (xy 96.774508 -285.171388) (xy 96.751648 -285.175706) (xy 96.54667 -285.530544)
			(xy 96.554544 -285.552642) (xy 96.563116 -285.578997) (xy 96.572307 -285.633645) (xy 96.572832 -285.661354)
			(xy 96.853756 -285.661354) (xy 96.854264 -285.635467) (xy 96.862363 -285.584329) (xy 96.878362 -285.535089)
			(xy 96.901868 -285.488957) (xy 96.9323 -285.44707) (xy 96.96891 -285.41046) (xy 97.010797 -285.380028)
			(xy 97.056929 -285.356522) (xy 97.106169 -285.340523) (xy 97.157307 -285.332424) (xy 97.209081 -285.332424)
			(xy 97.260219 -285.340523) (xy 97.309459 -285.356522) (xy 97.355591 -285.380028) (xy 97.397478 -285.41046)
			(xy 97.434088 -285.44707) (xy 97.46452 -285.488957) (xy 97.488026 -285.535089) (xy 97.504025 -285.584329)
			(xy 97.512124 -285.635467) (xy 97.512632 -285.661354) (xy 97.793556 -285.661354) (xy 97.794032 -285.63602)
			(xy 97.80179 -285.585949) (xy 97.817117 -285.537654) (xy 97.83965 -285.492273) (xy 97.868861 -285.450872)
			(xy 97.904061 -285.414427) (xy 97.944422 -285.383796) (xy 97.988994 -285.3597) (xy 98.036727 -285.342705)
			(xy 98.061526 -285.337504) (xy 98.084386 -285.333186) (xy 98.289618 -284.97784) (xy 98.281998 -284.955996)
			(xy 98.273374 -284.929714) (xy 98.264059 -284.875193) (xy 98.263456 -284.847538) (xy 98.263964 -284.821631)
			(xy 98.27207 -284.770454) (xy 98.288082 -284.721175) (xy 98.311605 -284.675008) (xy 98.342061 -284.633089)
			(xy 98.378699 -284.596451) (xy 98.420618 -284.565995) (xy 98.466785 -284.542472) (xy 98.516064 -284.52646)
			(xy 98.567241 -284.518354) (xy 98.619055 -284.518354) (xy 98.670232 -284.52646) (xy 98.719511 -284.542472)
			(xy 98.765678 -284.565995) (xy 98.807597 -284.596451) (xy 98.844235 -284.633089) (xy 98.874691 -284.675008)
			(xy 98.898214 -284.721175) (xy 98.914226 -284.770454) (xy 98.922332 -284.821631) (xy 98.92284 -284.847538)
			(xy 98.922448 -284.872916) (xy 98.914673 -284.923072) (xy 98.899296 -284.971442) (xy 98.876681 -285.016882)
			(xy 98.847365 -285.058314) (xy 98.81204 -285.09476) (xy 98.771543 -285.125356) (xy 98.726833 -285.149379)
			(xy 98.678966 -285.166259) (xy 98.654108 -285.171388) (xy 98.631248 -285.175706) (xy 98.42627 -285.530544)
			(xy 98.434144 -285.552642) (xy 98.442716 -285.578997) (xy 98.451907 -285.633645) (xy 98.452432 -285.661354)
			(xy 98.733356 -285.661354) (xy 98.733864 -285.635467) (xy 98.741963 -285.584329) (xy 98.757962 -285.535089)
			(xy 98.781468 -285.488957) (xy 98.8119 -285.44707) (xy 98.84851 -285.41046) (xy 98.890397 -285.380028)
			(xy 98.936529 -285.356522) (xy 98.985769 -285.340523) (xy 99.036907 -285.332424) (xy 99.088681 -285.332424)
			(xy 99.139819 -285.340523) (xy 99.189059 -285.356522) (xy 99.235191 -285.380028) (xy 99.277078 -285.41046)
			(xy 99.313688 -285.44707) (xy 99.34412 -285.488957) (xy 99.367626 -285.535089) (xy 99.383625 -285.584329)
			(xy 99.391724 -285.635467) (xy 99.392232 -285.661354) (xy 99.673156 -285.661354) (xy 99.673632 -285.63602)
			(xy 99.68139 -285.585949) (xy 99.696717 -285.537654) (xy 99.71925 -285.492273) (xy 99.748461 -285.450872)
			(xy 99.783661 -285.414427) (xy 99.824022 -285.383796) (xy 99.868594 -285.3597) (xy 99.916327 -285.342705)
			(xy 99.941126 -285.337504) (xy 99.963986 -285.333186) (xy 100.169218 -284.97784) (xy 100.161598 -284.955996)
			(xy 100.152974 -284.929714) (xy 100.143659 -284.875193) (xy 100.143056 -284.847538) (xy 100.143564 -284.821631)
			(xy 100.15167 -284.770454) (xy 100.167682 -284.721175) (xy 100.191205 -284.675008) (xy 100.221661 -284.633089)
			(xy 100.258299 -284.596451) (xy 100.300218 -284.565995) (xy 100.346385 -284.542472) (xy 100.395664 -284.52646)
			(xy 100.446841 -284.518354) (xy 100.498655 -284.518354) (xy 100.549832 -284.52646) (xy 100.599111 -284.542472)
			(xy 100.645278 -284.565995) (xy 100.687197 -284.596451) (xy 100.723835 -284.633089) (xy 100.754291 -284.675008)
			(xy 100.777814 -284.721175) (xy 100.793826 -284.770454) (xy 100.801932 -284.821631) (xy 100.80244 -284.847538)
			(xy 100.802048 -284.872916) (xy 100.794273 -284.923072) (xy 100.778896 -284.971442) (xy 100.756281 -285.016882)
			(xy 100.726965 -285.058314) (xy 100.69164 -285.09476) (xy 100.651143 -285.125356) (xy 100.606433 -285.149379)
			(xy 100.558566 -285.166259) (xy 100.533708 -285.171388) (xy 100.510848 -285.175706) (xy 100.30587 -285.530544)
			(xy 100.313744 -285.552642) (xy 100.322316 -285.578997) (xy 100.331507 -285.633645) (xy 100.332032 -285.661354)
			(xy 100.612956 -285.661354) (xy 100.613464 -285.635467) (xy 100.621563 -285.584329) (xy 100.637562 -285.535089)
			(xy 100.661068 -285.488957) (xy 100.6915 -285.44707) (xy 100.72811 -285.41046) (xy 100.769997 -285.380028)
			(xy 100.816129 -285.356522) (xy 100.865369 -285.340523) (xy 100.916507 -285.332424) (xy 100.968281 -285.332424)
			(xy 101.019419 -285.340523) (xy 101.068659 -285.356522) (xy 101.114791 -285.380028) (xy 101.156678 -285.41046)
			(xy 101.193288 -285.44707) (xy 101.22372 -285.488957) (xy 101.247226 -285.535089) (xy 101.263225 -285.584329)
			(xy 101.271324 -285.635467) (xy 101.271832 -285.661354) (xy 101.552756 -285.661354) (xy 101.553232 -285.63602)
			(xy 101.56099 -285.585949) (xy 101.576317 -285.537654) (xy 101.59885 -285.492273) (xy 101.628061 -285.450872)
			(xy 101.663261 -285.414427) (xy 101.703622 -285.383796) (xy 101.748194 -285.3597) (xy 101.795927 -285.342705)
			(xy 101.820726 -285.337504) (xy 101.843586 -285.333186) (xy 102.048818 -284.97784) (xy 102.041198 -284.955996)
			(xy 102.032574 -284.929714) (xy 102.023259 -284.875193) (xy 102.022656 -284.847538) (xy 102.023164 -284.821631)
			(xy 102.03127 -284.770454) (xy 102.047282 -284.721175) (xy 102.070805 -284.675008) (xy 102.101261 -284.633089)
			(xy 102.137899 -284.596451) (xy 102.179818 -284.565995) (xy 102.225985 -284.542472) (xy 102.275264 -284.52646)
			(xy 102.326441 -284.518354) (xy 102.378255 -284.518354) (xy 102.429432 -284.52646) (xy 102.478711 -284.542472)
			(xy 102.524878 -284.565995) (xy 102.566797 -284.596451) (xy 102.603435 -284.633089) (xy 102.633891 -284.675008)
			(xy 102.657414 -284.721175) (xy 102.673426 -284.770454) (xy 102.681532 -284.821631) (xy 102.68204 -284.847538)
			(xy 102.681648 -284.872916) (xy 102.673873 -284.923072) (xy 102.658496 -284.971442) (xy 102.635881 -285.016882)
			(xy 102.606565 -285.058314) (xy 102.57124 -285.09476) (xy 102.530743 -285.125356) (xy 102.486033 -285.149379)
			(xy 102.438166 -285.166259) (xy 102.413308 -285.171388) (xy 102.390448 -285.175706) (xy 102.18547 -285.530544)
			(xy 102.193344 -285.552642) (xy 102.201916 -285.578997) (xy 102.211107 -285.633645) (xy 102.211632 -285.661354)
			(xy 102.492556 -285.661354) (xy 102.493064 -285.635467) (xy 102.501163 -285.584329) (xy 102.517162 -285.535089)
			(xy 102.540668 -285.488957) (xy 102.5711 -285.44707) (xy 102.60771 -285.41046) (xy 102.649597 -285.380028)
			(xy 102.695729 -285.356522) (xy 102.744969 -285.340523) (xy 102.796107 -285.332424) (xy 102.847881 -285.332424)
			(xy 102.899019 -285.340523) (xy 102.948259 -285.356522) (xy 102.994391 -285.380028) (xy 103.036278 -285.41046)
			(xy 103.072888 -285.44707) (xy 103.10332 -285.488957) (xy 103.126826 -285.535089) (xy 103.142825 -285.584329)
			(xy 103.150924 -285.635467) (xy 103.151432 -285.661354) (xy 103.432356 -285.661354) (xy 103.432832 -285.63602)
			(xy 103.44059 -285.585949) (xy 103.455917 -285.537654) (xy 103.47845 -285.492273) (xy 103.507661 -285.450872)
			(xy 103.542861 -285.414427) (xy 103.583222 -285.383796) (xy 103.627794 -285.3597) (xy 103.675527 -285.342705)
			(xy 103.700326 -285.337504) (xy 103.723186 -285.333186) (xy 103.928418 -284.97784) (xy 103.920798 -284.955996)
			(xy 103.912174 -284.929714) (xy 103.902859 -284.875193) (xy 103.902256 -284.847538) (xy 103.902764 -284.821631)
			(xy 103.91087 -284.770454) (xy 103.926882 -284.721175) (xy 103.950405 -284.675008) (xy 103.980861 -284.633089)
			(xy 104.017499 -284.596451) (xy 104.059418 -284.565995) (xy 104.105585 -284.542472) (xy 104.154864 -284.52646)
			(xy 104.206041 -284.518354) (xy 104.257855 -284.518354) (xy 104.309032 -284.52646) (xy 104.358311 -284.542472)
			(xy 104.404478 -284.565995) (xy 104.446397 -284.596451) (xy 104.483035 -284.633089) (xy 104.513491 -284.675008)
			(xy 104.537014 -284.721175) (xy 104.553026 -284.770454) (xy 104.561132 -284.821631) (xy 104.56164 -284.847538)
			(xy 118.939056 -284.847538) (xy 118.939564 -284.821631) (xy 118.94767 -284.770454) (xy 118.963682 -284.721175)
			(xy 118.987205 -284.675008) (xy 119.017661 -284.633089) (xy 119.054299 -284.596451) (xy 119.096218 -284.565995)
			(xy 119.142385 -284.542472) (xy 119.191664 -284.52646) (xy 119.242841 -284.518354) (xy 119.294655 -284.518354)
			(xy 119.345832 -284.52646) (xy 119.395111 -284.542472) (xy 119.441278 -284.565995) (xy 119.483197 -284.596451)
			(xy 119.519835 -284.633089) (xy 119.550291 -284.675008) (xy 119.573814 -284.721175) (xy 119.589826 -284.770454)
			(xy 119.597932 -284.821631) (xy 119.59844 -284.847538) (xy 120.818656 -284.847538) (xy 120.819164 -284.821631)
			(xy 120.82727 -284.770454) (xy 120.843282 -284.721175) (xy 120.866805 -284.675008) (xy 120.897261 -284.633089)
			(xy 120.933899 -284.596451) (xy 120.975818 -284.565995) (xy 121.021985 -284.542472) (xy 121.071264 -284.52646)
			(xy 121.122441 -284.518354) (xy 121.174255 -284.518354) (xy 121.225432 -284.52646) (xy 121.274711 -284.542472)
			(xy 121.320878 -284.565995) (xy 121.362797 -284.596451) (xy 121.399435 -284.633089) (xy 121.429891 -284.675008)
			(xy 121.453414 -284.721175) (xy 121.469426 -284.770454) (xy 121.477532 -284.821631) (xy 121.47804 -284.847538)
			(xy 122.698256 -284.847538) (xy 122.698764 -284.821631) (xy 122.70687 -284.770454) (xy 122.722882 -284.721175)
			(xy 122.746405 -284.675008) (xy 122.776861 -284.633089) (xy 122.813499 -284.596451) (xy 122.855418 -284.565995)
			(xy 122.901585 -284.542472) (xy 122.950864 -284.52646) (xy 123.002041 -284.518354) (xy 123.053855 -284.518354)
			(xy 123.105032 -284.52646) (xy 123.154311 -284.542472) (xy 123.200478 -284.565995) (xy 123.242397 -284.596451)
			(xy 123.279035 -284.633089) (xy 123.309491 -284.675008) (xy 123.333014 -284.721175) (xy 123.349026 -284.770454)
			(xy 123.357132 -284.821631) (xy 123.35764 -284.847538) (xy 124.577856 -284.847538) (xy 124.578364 -284.821631)
			(xy 124.58647 -284.770454) (xy 124.602482 -284.721175) (xy 124.626005 -284.675008) (xy 124.656461 -284.633089)
			(xy 124.693099 -284.596451) (xy 124.735018 -284.565995) (xy 124.781185 -284.542472) (xy 124.830464 -284.52646)
			(xy 124.881641 -284.518354) (xy 124.933455 -284.518354) (xy 124.984632 -284.52646) (xy 125.033911 -284.542472)
			(xy 125.080078 -284.565995) (xy 125.121997 -284.596451) (xy 125.158635 -284.633089) (xy 125.189091 -284.675008)
			(xy 125.212614 -284.721175) (xy 125.228626 -284.770454) (xy 125.236732 -284.821631) (xy 125.23724 -284.847538)
			(xy 126.457456 -284.847538) (xy 126.457964 -284.821631) (xy 126.46607 -284.770454) (xy 126.482082 -284.721175)
			(xy 126.505605 -284.675008) (xy 126.536061 -284.633089) (xy 126.572699 -284.596451) (xy 126.614618 -284.565995)
			(xy 126.660785 -284.542472) (xy 126.710064 -284.52646) (xy 126.761241 -284.518354) (xy 126.813055 -284.518354)
			(xy 126.864232 -284.52646) (xy 126.913511 -284.542472) (xy 126.959678 -284.565995) (xy 127.001597 -284.596451)
			(xy 127.038235 -284.633089) (xy 127.068691 -284.675008) (xy 127.092214 -284.721175) (xy 127.108226 -284.770454)
			(xy 127.116332 -284.821631) (xy 127.11684 -284.847538) (xy 128.337056 -284.847538) (xy 128.337564 -284.821631)
			(xy 128.34567 -284.770454) (xy 128.361682 -284.721175) (xy 128.385205 -284.675008) (xy 128.415661 -284.633089)
			(xy 128.452299 -284.596451) (xy 128.494218 -284.565995) (xy 128.540385 -284.542472) (xy 128.589664 -284.52646)
			(xy 128.640841 -284.518354) (xy 128.692655 -284.518354) (xy 128.743832 -284.52646) (xy 128.793111 -284.542472)
			(xy 128.839278 -284.565995) (xy 128.881197 -284.596451) (xy 128.917835 -284.633089) (xy 128.948291 -284.675008)
			(xy 128.971814 -284.721175) (xy 128.987826 -284.770454) (xy 128.995932 -284.821631) (xy 128.99644 -284.847538)
			(xy 130.216656 -284.847538) (xy 130.217164 -284.821631) (xy 130.22527 -284.770454) (xy 130.241282 -284.721175)
			(xy 130.264805 -284.675008) (xy 130.295261 -284.633089) (xy 130.331899 -284.596451) (xy 130.373818 -284.565995)
			(xy 130.419985 -284.542472) (xy 130.469264 -284.52646) (xy 130.520441 -284.518354) (xy 130.572255 -284.518354)
			(xy 130.623432 -284.52646) (xy 130.672711 -284.542472) (xy 130.718878 -284.565995) (xy 130.760797 -284.596451)
			(xy 130.797435 -284.633089) (xy 130.827891 -284.675008) (xy 130.851414 -284.721175) (xy 130.867426 -284.770454)
			(xy 130.875532 -284.821631) (xy 130.87604 -284.847538) (xy 132.096256 -284.847538) (xy 132.096764 -284.821631)
			(xy 132.10487 -284.770454) (xy 132.120882 -284.721175) (xy 132.144405 -284.675008) (xy 132.174861 -284.633089)
			(xy 132.211499 -284.596451) (xy 132.253418 -284.565995) (xy 132.299585 -284.542472) (xy 132.348864 -284.52646)
			(xy 132.400041 -284.518354) (xy 132.451855 -284.518354) (xy 132.503032 -284.52646) (xy 132.552311 -284.542472)
			(xy 132.598478 -284.565995) (xy 132.640397 -284.596451) (xy 132.677035 -284.633089) (xy 132.707491 -284.675008)
			(xy 132.731014 -284.721175) (xy 132.747026 -284.770454) (xy 132.755132 -284.821631) (xy 132.75564 -284.847538)
			(xy 132.755075 -284.873383) (xy 333.046907 -284.873383) (xy 333.046907 -284.821618) (xy 333.055005 -284.77049)
			(xy 333.071 -284.721258) (xy 333.094499 -284.675134) (xy 333.124924 -284.633254) (xy 333.161525 -284.596648)
			(xy 333.203402 -284.566219) (xy 333.249523 -284.542714) (xy 333.298753 -284.526713) (xy 333.34988 -284.51861)
			(xy 333.375762 -284.5181) (xy 333.401254 -284.518612) (xy 333.451631 -284.526467) (xy 333.500193 -284.541996)
			(xy 333.54578 -284.564827) (xy 333.587302 -284.594415) (xy 333.623765 -284.63005) (xy 333.639414 -284.65018)
			(xy 334.05191 -284.65018) (xy 334.067576 -284.630063) (xy 334.104034 -284.594421) (xy 334.145551 -284.564826)
			(xy 334.191135 -284.541986) (xy 334.239694 -284.526447) (xy 334.290069 -284.518581) (xy 334.315562 -284.5181)
			(xy 334.341456 -284.518502) (xy 334.392608 -284.526599) (xy 334.441864 -284.542598) (xy 334.48801 -284.566106)
			(xy 334.52991 -284.596543) (xy 334.566532 -284.633161) (xy 334.596975 -284.675058) (xy 334.620488 -284.721201)
			(xy 334.636492 -284.770455) (xy 334.644595 -284.821606) (xy 334.644595 -284.873394) (xy 334.636492 -284.924545)
			(xy 334.620488 -284.973799) (xy 334.596975 -285.019942) (xy 334.566532 -285.061839) (xy 334.52991 -285.098457)
			(xy 334.48801 -285.128894) (xy 334.441864 -285.152402) (xy 334.392608 -285.168401) (xy 334.341456 -285.176498)
			(xy 334.315562 -285.176976) (xy 334.290067 -285.176529) (xy 334.239687 -285.168661) (xy 334.191123 -285.15312)
			(xy 334.145536 -285.130277) (xy 334.104016 -285.100678) (xy 334.067557 -285.065031) (xy 334.05191 -285.044896)
			(xy 333.639414 -285.044896) (xy 333.623786 -285.065045) (xy 333.587321 -285.100686) (xy 333.545796 -285.130277)
			(xy 333.500205 -285.153112) (xy 333.451638 -285.168644) (xy 333.401257 -285.176501) (xy 333.375762 -285.176976)
			(xy 333.34988 -285.17639) (xy 333.298753 -285.168287) (xy 333.249523 -285.152286) (xy 333.203402 -285.128781)
			(xy 333.161525 -285.098352) (xy 333.124924 -285.061746) (xy 333.094499 -285.019866) (xy 333.071 -284.973742)
			(xy 333.055005 -284.92451) (xy 333.046907 -284.873383) (xy 132.755075 -284.873383) (xy 132.755034 -284.875255)
			(xy 132.745719 -284.929901) (xy 132.737098 -284.95625) (xy 132.729224 -284.978348) (xy 132.934202 -285.333186)
			(xy 132.957062 -285.337504) (xy 132.981868 -285.342683) (xy 133.02961 -285.359669) (xy 133.07419 -285.383762)
			(xy 133.114558 -285.414393) (xy 133.149763 -285.450841) (xy 133.178975 -285.492247) (xy 133.201506 -285.537636)
			(xy 133.216825 -285.585939) (xy 133.224572 -285.636017) (xy 133.225032 -285.661354) (xy 133.224524 -285.687241)
			(xy 133.216425 -285.738379) (xy 133.200426 -285.787619) (xy 133.17692 -285.833751) (xy 133.146488 -285.875638)
			(xy 133.109878 -285.912248) (xy 133.067991 -285.94268) (xy 133.021859 -285.966186) (xy 132.972619 -285.982185)
			(xy 132.921481 -285.990284) (xy 132.869707 -285.990284) (xy 132.818569 -285.982185) (xy 132.769329 -285.966186)
			(xy 132.723197 -285.94268) (xy 132.68131 -285.912248) (xy 132.6447 -285.875638) (xy 132.614268 -285.833751)
			(xy 132.590762 -285.787619) (xy 132.574763 -285.738379) (xy 132.566664 -285.687241) (xy 132.566156 -285.661354)
			(xy 132.566701 -285.633647) (xy 132.575886 -285.579) (xy 132.584444 -285.552642) (xy 132.592318 -285.530544)
			(xy 132.38734 -285.175706) (xy 132.36448 -285.171388) (xy 132.33966 -285.166215) (xy 132.29188 -285.149263)
			(xy 132.247259 -285.125194) (xy 132.206851 -285.094575) (xy 132.171609 -285.058129) (xy 132.142365 -285.016715)
			(xy 132.119809 -284.971312) (xy 132.104472 -284.922989) (xy 132.096717 -284.872887) (xy 132.096256 -284.847538)
			(xy 130.87604 -284.847538) (xy 130.875434 -284.875255) (xy 130.866119 -284.929901) (xy 130.857498 -284.95625)
			(xy 130.849624 -284.978348) (xy 131.054602 -285.333186) (xy 131.077462 -285.337504) (xy 131.102268 -285.342683)
			(xy 131.15001 -285.359669) (xy 131.19459 -285.383762) (xy 131.234958 -285.414393) (xy 131.270163 -285.450841)
			(xy 131.299375 -285.492247) (xy 131.321906 -285.537636) (xy 131.337225 -285.585939) (xy 131.344972 -285.636017)
			(xy 131.345432 -285.661354) (xy 131.344924 -285.687241) (xy 131.336825 -285.738379) (xy 131.320826 -285.787619)
			(xy 131.29732 -285.833751) (xy 131.266888 -285.875638) (xy 131.230278 -285.912248) (xy 131.188391 -285.94268)
			(xy 131.142259 -285.966186) (xy 131.093019 -285.982185) (xy 131.041881 -285.990284) (xy 130.990107 -285.990284)
			(xy 130.938969 -285.982185) (xy 130.889729 -285.966186) (xy 130.843597 -285.94268) (xy 130.80171 -285.912248)
			(xy 130.7651 -285.875638) (xy 130.734668 -285.833751) (xy 130.711162 -285.787619) (xy 130.695163 -285.738379)
			(xy 130.687064 -285.687241) (xy 130.686556 -285.661354) (xy 130.687101 -285.633647) (xy 130.696286 -285.579)
			(xy 130.704844 -285.552642) (xy 130.712718 -285.530544) (xy 130.50774 -285.175706) (xy 130.48488 -285.171388)
			(xy 130.46006 -285.166215) (xy 130.41228 -285.149263) (xy 130.367659 -285.125194) (xy 130.327251 -285.094575)
			(xy 130.292009 -285.058129) (xy 130.262765 -285.016715) (xy 130.240209 -284.971312) (xy 130.224872 -284.922989)
			(xy 130.217117 -284.872887) (xy 130.216656 -284.847538) (xy 128.99644 -284.847538) (xy 128.995834 -284.875255)
			(xy 128.986519 -284.929901) (xy 128.977898 -284.95625) (xy 128.970024 -284.978348) (xy 129.175002 -285.333186)
			(xy 129.197862 -285.337504) (xy 129.222668 -285.342683) (xy 129.27041 -285.359669) (xy 129.31499 -285.383762)
			(xy 129.355358 -285.414393) (xy 129.390563 -285.450841) (xy 129.419775 -285.492247) (xy 129.442306 -285.537636)
			(xy 129.457625 -285.585939) (xy 129.465372 -285.636017) (xy 129.465832 -285.661354) (xy 129.465324 -285.687241)
			(xy 129.457225 -285.738379) (xy 129.441226 -285.787619) (xy 129.41772 -285.833751) (xy 129.387288 -285.875638)
			(xy 129.350678 -285.912248) (xy 129.308791 -285.94268) (xy 129.262659 -285.966186) (xy 129.213419 -285.982185)
			(xy 129.162281 -285.990284) (xy 129.110507 -285.990284) (xy 129.059369 -285.982185) (xy 129.010129 -285.966186)
			(xy 128.963997 -285.94268) (xy 128.92211 -285.912248) (xy 128.8855 -285.875638) (xy 128.855068 -285.833751)
			(xy 128.831562 -285.787619) (xy 128.815563 -285.738379) (xy 128.807464 -285.687241) (xy 128.806956 -285.661354)
			(xy 128.807501 -285.633647) (xy 128.816686 -285.579) (xy 128.825244 -285.552642) (xy 128.833118 -285.530544)
			(xy 128.62814 -285.175706) (xy 128.60528 -285.171388) (xy 128.58046 -285.166215) (xy 128.53268 -285.149263)
			(xy 128.488059 -285.125194) (xy 128.447651 -285.094575) (xy 128.412409 -285.058129) (xy 128.383165 -285.016715)
			(xy 128.360609 -284.971312) (xy 128.345272 -284.922989) (xy 128.337517 -284.872887) (xy 128.337056 -284.847538)
			(xy 127.11684 -284.847538) (xy 127.116234 -284.875255) (xy 127.106919 -284.929901) (xy 127.098298 -284.95625)
			(xy 127.090424 -284.978348) (xy 127.295402 -285.333186) (xy 127.318262 -285.337504) (xy 127.343068 -285.342683)
			(xy 127.39081 -285.359669) (xy 127.43539 -285.383762) (xy 127.475758 -285.414393) (xy 127.510963 -285.450841)
			(xy 127.540175 -285.492247) (xy 127.562706 -285.537636) (xy 127.578025 -285.585939) (xy 127.585772 -285.636017)
			(xy 127.586232 -285.661354) (xy 127.585724 -285.687241) (xy 127.577625 -285.738379) (xy 127.561626 -285.787619)
			(xy 127.53812 -285.833751) (xy 127.507688 -285.875638) (xy 127.471078 -285.912248) (xy 127.429191 -285.94268)
			(xy 127.383059 -285.966186) (xy 127.333819 -285.982185) (xy 127.282681 -285.990284) (xy 127.230907 -285.990284)
			(xy 127.179769 -285.982185) (xy 127.130529 -285.966186) (xy 127.084397 -285.94268) (xy 127.04251 -285.912248)
			(xy 127.0059 -285.875638) (xy 126.975468 -285.833751) (xy 126.951962 -285.787619) (xy 126.935963 -285.738379)
			(xy 126.927864 -285.687241) (xy 126.927356 -285.661354) (xy 126.927901 -285.633647) (xy 126.937086 -285.579)
			(xy 126.945644 -285.552642) (xy 126.953518 -285.530544) (xy 126.74854 -285.175706) (xy 126.72568 -285.171388)
			(xy 126.70086 -285.166215) (xy 126.65308 -285.149263) (xy 126.608459 -285.125194) (xy 126.568051 -285.094575)
			(xy 126.532809 -285.058129) (xy 126.503565 -285.016715) (xy 126.481009 -284.971312) (xy 126.465672 -284.922989)
			(xy 126.457917 -284.872887) (xy 126.457456 -284.847538) (xy 125.23724 -284.847538) (xy 125.236634 -284.875255)
			(xy 125.227319 -284.929901) (xy 125.218698 -284.95625) (xy 125.210824 -284.978348) (xy 125.415802 -285.333186)
			(xy 125.438662 -285.337504) (xy 125.463468 -285.342683) (xy 125.51121 -285.359669) (xy 125.55579 -285.383762)
			(xy 125.596158 -285.414393) (xy 125.631363 -285.450841) (xy 125.660575 -285.492247) (xy 125.683106 -285.537636)
			(xy 125.698425 -285.585939) (xy 125.706172 -285.636017) (xy 125.706632 -285.661354) (xy 125.706124 -285.687241)
			(xy 125.698025 -285.738379) (xy 125.682026 -285.787619) (xy 125.65852 -285.833751) (xy 125.628088 -285.875638)
			(xy 125.591478 -285.912248) (xy 125.549591 -285.94268) (xy 125.503459 -285.966186) (xy 125.454219 -285.982185)
			(xy 125.403081 -285.990284) (xy 125.351307 -285.990284) (xy 125.300169 -285.982185) (xy 125.250929 -285.966186)
			(xy 125.204797 -285.94268) (xy 125.16291 -285.912248) (xy 125.1263 -285.875638) (xy 125.095868 -285.833751)
			(xy 125.072362 -285.787619) (xy 125.056363 -285.738379) (xy 125.048264 -285.687241) (xy 125.047756 -285.661354)
			(xy 125.048301 -285.633647) (xy 125.057486 -285.579) (xy 125.066044 -285.552642) (xy 125.073918 -285.530544)
			(xy 124.86894 -285.175706) (xy 124.84608 -285.171388) (xy 124.82126 -285.166215) (xy 124.77348 -285.149263)
			(xy 124.728859 -285.125194) (xy 124.688451 -285.094575) (xy 124.653209 -285.058129) (xy 124.623965 -285.016715)
			(xy 124.601409 -284.971312) (xy 124.586072 -284.922989) (xy 124.578317 -284.872887) (xy 124.577856 -284.847538)
			(xy 123.35764 -284.847538) (xy 123.357034 -284.875255) (xy 123.347719 -284.929901) (xy 123.339098 -284.95625)
			(xy 123.331224 -284.978348) (xy 123.536202 -285.333186) (xy 123.559062 -285.337504) (xy 123.583868 -285.342683)
			(xy 123.63161 -285.359669) (xy 123.67619 -285.383762) (xy 123.716558 -285.414393) (xy 123.751763 -285.450841)
			(xy 123.780975 -285.492247) (xy 123.803506 -285.537636) (xy 123.818825 -285.585939) (xy 123.826572 -285.636017)
			(xy 123.827032 -285.661354) (xy 123.826524 -285.687241) (xy 123.818425 -285.738379) (xy 123.802426 -285.787619)
			(xy 123.77892 -285.833751) (xy 123.748488 -285.875638) (xy 123.711878 -285.912248) (xy 123.669991 -285.94268)
			(xy 123.623859 -285.966186) (xy 123.574619 -285.982185) (xy 123.523481 -285.990284) (xy 123.471707 -285.990284)
			(xy 123.420569 -285.982185) (xy 123.371329 -285.966186) (xy 123.325197 -285.94268) (xy 123.28331 -285.912248)
			(xy 123.2467 -285.875638) (xy 123.216268 -285.833751) (xy 123.192762 -285.787619) (xy 123.176763 -285.738379)
			(xy 123.168664 -285.687241) (xy 123.168156 -285.661354) (xy 123.168701 -285.633647) (xy 123.177886 -285.579)
			(xy 123.186444 -285.552642) (xy 123.194318 -285.530544) (xy 122.98934 -285.175706) (xy 122.96648 -285.171388)
			(xy 122.94166 -285.166215) (xy 122.89388 -285.149263) (xy 122.849259 -285.125194) (xy 122.808851 -285.094575)
			(xy 122.773609 -285.058129) (xy 122.744365 -285.016715) (xy 122.721809 -284.971312) (xy 122.706472 -284.922989)
			(xy 122.698717 -284.872887) (xy 122.698256 -284.847538) (xy 121.47804 -284.847538) (xy 121.477434 -284.875255)
			(xy 121.468119 -284.929901) (xy 121.459498 -284.95625) (xy 121.451624 -284.978348) (xy 121.656602 -285.333186)
			(xy 121.679462 -285.337504) (xy 121.704268 -285.342683) (xy 121.75201 -285.359669) (xy 121.79659 -285.383762)
			(xy 121.836958 -285.414393) (xy 121.872163 -285.450841) (xy 121.901375 -285.492247) (xy 121.923906 -285.537636)
			(xy 121.939225 -285.585939) (xy 121.946972 -285.636017) (xy 121.947432 -285.661354) (xy 121.946924 -285.687241)
			(xy 121.938825 -285.738379) (xy 121.922826 -285.787619) (xy 121.89932 -285.833751) (xy 121.868888 -285.875638)
			(xy 121.832278 -285.912248) (xy 121.790391 -285.94268) (xy 121.744259 -285.966186) (xy 121.695019 -285.982185)
			(xy 121.643881 -285.990284) (xy 121.592107 -285.990284) (xy 121.540969 -285.982185) (xy 121.491729 -285.966186)
			(xy 121.445597 -285.94268) (xy 121.40371 -285.912248) (xy 121.3671 -285.875638) (xy 121.336668 -285.833751)
			(xy 121.313162 -285.787619) (xy 121.297163 -285.738379) (xy 121.289064 -285.687241) (xy 121.288556 -285.661354)
			(xy 121.289101 -285.633647) (xy 121.298286 -285.579) (xy 121.306844 -285.552642) (xy 121.314718 -285.530544)
			(xy 121.10974 -285.175706) (xy 121.08688 -285.171388) (xy 121.06206 -285.166215) (xy 121.01428 -285.149263)
			(xy 120.969659 -285.125194) (xy 120.929251 -285.094575) (xy 120.894009 -285.058129) (xy 120.864765 -285.016715)
			(xy 120.842209 -284.971312) (xy 120.826872 -284.922989) (xy 120.819117 -284.872887) (xy 120.818656 -284.847538)
			(xy 119.59844 -284.847538) (xy 119.597834 -284.875255) (xy 119.588519 -284.929901) (xy 119.579898 -284.95625)
			(xy 119.572024 -284.978348) (xy 119.777002 -285.333186) (xy 119.799862 -285.337504) (xy 119.824668 -285.342683)
			(xy 119.87241 -285.359669) (xy 119.91699 -285.383762) (xy 119.957358 -285.414393) (xy 119.992563 -285.450841)
			(xy 120.021775 -285.492247) (xy 120.044306 -285.537636) (xy 120.059625 -285.585939) (xy 120.067372 -285.636017)
			(xy 120.067832 -285.661354) (xy 120.067324 -285.687241) (xy 120.059225 -285.738379) (xy 120.043226 -285.787619)
			(xy 120.01972 -285.833751) (xy 119.989288 -285.875638) (xy 119.952678 -285.912248) (xy 119.910791 -285.94268)
			(xy 119.864659 -285.966186) (xy 119.815419 -285.982185) (xy 119.764281 -285.990284) (xy 119.712507 -285.990284)
			(xy 119.661369 -285.982185) (xy 119.612129 -285.966186) (xy 119.565997 -285.94268) (xy 119.52411 -285.912248)
			(xy 119.4875 -285.875638) (xy 119.457068 -285.833751) (xy 119.433562 -285.787619) (xy 119.417563 -285.738379)
			(xy 119.409464 -285.687241) (xy 119.408956 -285.661354) (xy 119.409501 -285.633647) (xy 119.418686 -285.579)
			(xy 119.427244 -285.552642) (xy 119.435118 -285.530544) (xy 119.23014 -285.175706) (xy 119.20728 -285.171388)
			(xy 119.18246 -285.166215) (xy 119.13468 -285.149263) (xy 119.090059 -285.125194) (xy 119.049651 -285.094575)
			(xy 119.014409 -285.058129) (xy 118.985165 -285.016715) (xy 118.962609 -284.971312) (xy 118.947272 -284.922989)
			(xy 118.939517 -284.872887) (xy 118.939056 -284.847538) (xy 104.56164 -284.847538) (xy 104.561248 -284.872916)
			(xy 104.553473 -284.923072) (xy 104.538096 -284.971442) (xy 104.515481 -285.016882) (xy 104.486165 -285.058314)
			(xy 104.45084 -285.09476) (xy 104.410343 -285.125356) (xy 104.365633 -285.149379) (xy 104.317766 -285.166259)
			(xy 104.292908 -285.171388) (xy 104.270048 -285.175706) (xy 104.06507 -285.530544) (xy 104.072944 -285.552642)
			(xy 104.081516 -285.578997) (xy 104.090707 -285.633645) (xy 104.091232 -285.661354) (xy 104.090724 -285.687241)
			(xy 104.082625 -285.738379) (xy 104.066626 -285.787619) (xy 104.04312 -285.833751) (xy 104.012688 -285.875638)
			(xy 103.976078 -285.912248) (xy 103.934191 -285.94268) (xy 103.888059 -285.966186) (xy 103.838819 -285.982185)
			(xy 103.787681 -285.990284) (xy 103.735907 -285.990284) (xy 103.684769 -285.982185) (xy 103.635529 -285.966186)
			(xy 103.589397 -285.94268) (xy 103.54751 -285.912248) (xy 103.5109 -285.875638) (xy 103.480468 -285.833751)
			(xy 103.456962 -285.787619) (xy 103.440963 -285.738379) (xy 103.432864 -285.687241) (xy 103.432356 -285.661354)
			(xy 103.151432 -285.661354) (xy 103.151432 -285.661862) (xy 103.150853 -285.689379) (xy 103.141659 -285.74364)
			(xy 103.133144 -285.769812) (xy 103.125524 -285.79191) (xy 103.330756 -286.147256) (xy 103.353616 -286.151574)
			(xy 103.378427 -286.156786) (xy 103.426204 -286.173734) (xy 103.470823 -286.197799) (xy 103.51123 -286.228413)
			(xy 103.546472 -286.264855) (xy 103.575717 -286.306263) (xy 103.598276 -286.351662) (xy 103.613617 -286.399979)
			(xy 103.621377 -286.450077) (xy 103.62184 -286.475424) (xy 119.878856 -286.475424) (xy 119.879354 -286.450079)
			(xy 119.887123 -286.399987) (xy 119.902468 -286.351675) (xy 119.925026 -286.306281) (xy 119.954266 -286.264873)
			(xy 119.989499 -286.228429) (xy 120.029894 -286.197807) (xy 120.0745 -286.173728) (xy 120.122266 -286.156759)
			(xy 120.14708 -286.151574) (xy 120.16994 -286.147256) (xy 120.374918 -285.792164) (xy 120.367044 -285.77032)
			(xy 120.358471 -285.743899) (xy 120.34927 -285.689126) (xy 120.348756 -285.661354) (xy 120.349264 -285.635467)
			(xy 120.357363 -285.584329) (xy 120.373362 -285.535089) (xy 120.396868 -285.488957) (xy 120.4273 -285.44707)
			(xy 120.46391 -285.41046) (xy 120.505797 -285.380028) (xy 120.551929 -285.356522) (xy 120.601169 -285.340523)
			(xy 120.652307 -285.332424) (xy 120.704081 -285.332424) (xy 120.755219 -285.340523) (xy 120.804459 -285.356522)
			(xy 120.850591 -285.380028) (xy 120.892478 -285.41046) (xy 120.929088 -285.44707) (xy 120.95952 -285.488957)
			(xy 120.983026 -285.535089) (xy 120.999025 -285.584329) (xy 121.007124 -285.635467) (xy 121.007632 -285.661354)
			(xy 121.007172 -285.686689) (xy 120.999413 -285.736761) (xy 120.984085 -285.785057) (xy 120.961549 -285.830439)
			(xy 120.932336 -285.87184) (xy 120.897134 -285.908285) (xy 120.856771 -285.938915) (xy 120.812197 -285.963011)
			(xy 120.764462 -285.980004) (xy 120.739662 -285.985204) (xy 120.716802 -285.989522) (xy 120.511824 -286.344614)
			(xy 120.519698 -286.366458) (xy 120.528349 -286.392865) (xy 120.537666 -286.447642) (xy 120.53824 -286.475424)
			(xy 121.758456 -286.475424) (xy 121.758954 -286.450079) (xy 121.766723 -286.399987) (xy 121.782068 -286.351675)
			(xy 121.804626 -286.306281) (xy 121.833866 -286.264873) (xy 121.869099 -286.228429) (xy 121.909494 -286.197807)
			(xy 121.9541 -286.173728) (xy 122.001866 -286.156759) (xy 122.02668 -286.151574) (xy 122.04954 -286.147256)
			(xy 122.254518 -285.792164) (xy 122.246644 -285.77032) (xy 122.238071 -285.743899) (xy 122.22887 -285.689126)
			(xy 122.228356 -285.661354) (xy 122.228864 -285.635467) (xy 122.236963 -285.584329) (xy 122.252962 -285.535089)
			(xy 122.276468 -285.488957) (xy 122.3069 -285.44707) (xy 122.34351 -285.41046) (xy 122.385397 -285.380028)
			(xy 122.431529 -285.356522) (xy 122.480769 -285.340523) (xy 122.531907 -285.332424) (xy 122.583681 -285.332424)
			(xy 122.634819 -285.340523) (xy 122.684059 -285.356522) (xy 122.730191 -285.380028) (xy 122.772078 -285.41046)
			(xy 122.808688 -285.44707) (xy 122.83912 -285.488957) (xy 122.862626 -285.535089) (xy 122.878625 -285.584329)
			(xy 122.886724 -285.635467) (xy 122.887232 -285.661354) (xy 122.886772 -285.686689) (xy 122.879013 -285.736761)
			(xy 122.863685 -285.785057) (xy 122.841149 -285.830439) (xy 122.811936 -285.87184) (xy 122.776734 -285.908285)
			(xy 122.736371 -285.938915) (xy 122.691797 -285.963011) (xy 122.644062 -285.980004) (xy 122.619262 -285.985204)
			(xy 122.596402 -285.989522) (xy 122.391424 -286.344614) (xy 122.399298 -286.366458) (xy 122.407949 -286.392865)
			(xy 122.417266 -286.447642) (xy 122.41784 -286.475424) (xy 123.638056 -286.475424) (xy 123.638554 -286.450079)
			(xy 123.646323 -286.399987) (xy 123.661668 -286.351675) (xy 123.684226 -286.306281) (xy 123.713466 -286.264873)
			(xy 123.748699 -286.228429) (xy 123.789094 -286.197807) (xy 123.8337 -286.173728) (xy 123.881466 -286.156759)
			(xy 123.90628 -286.151574) (xy 123.92914 -286.147256) (xy 124.134118 -285.792164) (xy 124.126244 -285.77032)
			(xy 124.117671 -285.743899) (xy 124.10847 -285.689126) (xy 124.107956 -285.661354) (xy 124.108464 -285.635467)
			(xy 124.116563 -285.584329) (xy 124.132562 -285.535089) (xy 124.156068 -285.488957) (xy 124.1865 -285.44707)
			(xy 124.22311 -285.41046) (xy 124.264997 -285.380028) (xy 124.311129 -285.356522) (xy 124.360369 -285.340523)
			(xy 124.411507 -285.332424) (xy 124.463281 -285.332424) (xy 124.514419 -285.340523) (xy 124.563659 -285.356522)
			(xy 124.609791 -285.380028) (xy 124.651678 -285.41046) (xy 124.688288 -285.44707) (xy 124.71872 -285.488957)
			(xy 124.742226 -285.535089) (xy 124.758225 -285.584329) (xy 124.766324 -285.635467) (xy 124.766832 -285.661354)
			(xy 124.766372 -285.686689) (xy 124.758613 -285.736761) (xy 124.743285 -285.785057) (xy 124.720749 -285.830439)
			(xy 124.691536 -285.87184) (xy 124.656334 -285.908285) (xy 124.615971 -285.938915) (xy 124.571397 -285.963011)
			(xy 124.523662 -285.980004) (xy 124.498862 -285.985204) (xy 124.476002 -285.989522) (xy 124.271024 -286.344614)
			(xy 124.278898 -286.366458) (xy 124.287549 -286.392865) (xy 124.296866 -286.447642) (xy 124.29744 -286.475424)
			(xy 125.517656 -286.475424) (xy 125.518154 -286.450079) (xy 125.525923 -286.399987) (xy 125.541268 -286.351675)
			(xy 125.563826 -286.306281) (xy 125.593066 -286.264873) (xy 125.628299 -286.228429) (xy 125.668694 -286.197807)
			(xy 125.7133 -286.173728) (xy 125.761066 -286.156759) (xy 125.78588 -286.151574) (xy 125.80874 -286.147256)
			(xy 126.013718 -285.792164) (xy 126.005844 -285.77032) (xy 125.997271 -285.743899) (xy 125.98807 -285.689126)
			(xy 125.987556 -285.661354) (xy 125.988064 -285.635467) (xy 125.996163 -285.584329) (xy 126.012162 -285.535089)
			(xy 126.035668 -285.488957) (xy 126.0661 -285.44707) (xy 126.10271 -285.41046) (xy 126.144597 -285.380028)
			(xy 126.190729 -285.356522) (xy 126.239969 -285.340523) (xy 126.291107 -285.332424) (xy 126.342881 -285.332424)
			(xy 126.394019 -285.340523) (xy 126.443259 -285.356522) (xy 126.489391 -285.380028) (xy 126.531278 -285.41046)
			(xy 126.567888 -285.44707) (xy 126.59832 -285.488957) (xy 126.621826 -285.535089) (xy 126.637825 -285.584329)
			(xy 126.645924 -285.635467) (xy 126.646432 -285.661354) (xy 126.645972 -285.686689) (xy 126.638213 -285.736761)
			(xy 126.622885 -285.785057) (xy 126.600349 -285.830439) (xy 126.571136 -285.87184) (xy 126.535934 -285.908285)
			(xy 126.495571 -285.938915) (xy 126.450997 -285.963011) (xy 126.403262 -285.980004) (xy 126.378462 -285.985204)
			(xy 126.355602 -285.989522) (xy 126.150624 -286.344614) (xy 126.158498 -286.366458) (xy 126.167149 -286.392865)
			(xy 126.176466 -286.447642) (xy 126.17704 -286.475424) (xy 127.397256 -286.475424) (xy 127.397754 -286.450079)
			(xy 127.405523 -286.399987) (xy 127.420868 -286.351675) (xy 127.443426 -286.306281) (xy 127.472666 -286.264873)
			(xy 127.507899 -286.228429) (xy 127.548294 -286.197807) (xy 127.5929 -286.173728) (xy 127.640666 -286.156759)
			(xy 127.66548 -286.151574) (xy 127.68834 -286.147256) (xy 127.893318 -285.792164) (xy 127.885444 -285.77032)
			(xy 127.876871 -285.743899) (xy 127.86767 -285.689126) (xy 127.867156 -285.661354) (xy 127.867664 -285.635467)
			(xy 127.875763 -285.584329) (xy 127.891762 -285.535089) (xy 127.915268 -285.488957) (xy 127.9457 -285.44707)
			(xy 127.98231 -285.41046) (xy 128.024197 -285.380028) (xy 128.070329 -285.356522) (xy 128.119569 -285.340523)
			(xy 128.170707 -285.332424) (xy 128.222481 -285.332424) (xy 128.273619 -285.340523) (xy 128.322859 -285.356522)
			(xy 128.368991 -285.380028) (xy 128.410878 -285.41046) (xy 128.447488 -285.44707) (xy 128.47792 -285.488957)
			(xy 128.501426 -285.535089) (xy 128.517425 -285.584329) (xy 128.525524 -285.635467) (xy 128.526032 -285.661354)
			(xy 128.525572 -285.686689) (xy 128.517813 -285.736761) (xy 128.502485 -285.785057) (xy 128.479949 -285.830439)
			(xy 128.450736 -285.87184) (xy 128.415534 -285.908285) (xy 128.375171 -285.938915) (xy 128.330597 -285.963011)
			(xy 128.282862 -285.980004) (xy 128.258062 -285.985204) (xy 128.235202 -285.989522) (xy 128.030224 -286.344614)
			(xy 128.038098 -286.366458) (xy 128.046749 -286.392865) (xy 128.056066 -286.447642) (xy 128.05664 -286.475424)
			(xy 129.276856 -286.475424) (xy 129.277354 -286.450079) (xy 129.285123 -286.399987) (xy 129.300468 -286.351675)
			(xy 129.323026 -286.306281) (xy 129.352266 -286.264873) (xy 129.387499 -286.228429) (xy 129.427894 -286.197807)
			(xy 129.4725 -286.173728) (xy 129.520266 -286.156759) (xy 129.54508 -286.151574) (xy 129.56794 -286.147256)
			(xy 129.772918 -285.792164) (xy 129.765044 -285.77032) (xy 129.756471 -285.743899) (xy 129.74727 -285.689126)
			(xy 129.746756 -285.661354) (xy 129.747264 -285.635467) (xy 129.755363 -285.584329) (xy 129.771362 -285.535089)
			(xy 129.794868 -285.488957) (xy 129.8253 -285.44707) (xy 129.86191 -285.41046) (xy 129.903797 -285.380028)
			(xy 129.949929 -285.356522) (xy 129.999169 -285.340523) (xy 130.050307 -285.332424) (xy 130.102081 -285.332424)
			(xy 130.153219 -285.340523) (xy 130.202459 -285.356522) (xy 130.248591 -285.380028) (xy 130.290478 -285.41046)
			(xy 130.327088 -285.44707) (xy 130.35752 -285.488957) (xy 130.381026 -285.535089) (xy 130.397025 -285.584329)
			(xy 130.405124 -285.635467) (xy 130.405632 -285.661354) (xy 130.405172 -285.686689) (xy 130.397413 -285.736761)
			(xy 130.382085 -285.785057) (xy 130.359549 -285.830439) (xy 130.330336 -285.87184) (xy 130.295134 -285.908285)
			(xy 130.254771 -285.938915) (xy 130.210197 -285.963011) (xy 130.162462 -285.980004) (xy 130.137662 -285.985204)
			(xy 130.114802 -285.989522) (xy 129.909824 -286.344614) (xy 129.917698 -286.366458) (xy 129.926349 -286.392865)
			(xy 129.935666 -286.447642) (xy 129.93624 -286.475424) (xy 131.156456 -286.475424) (xy 131.156954 -286.450079)
			(xy 131.164723 -286.399987) (xy 131.180068 -286.351675) (xy 131.202626 -286.306281) (xy 131.231866 -286.264873)
			(xy 131.267099 -286.228429) (xy 131.307494 -286.197807) (xy 131.3521 -286.173728) (xy 131.399866 -286.156759)
			(xy 131.42468 -286.151574) (xy 131.44754 -286.147256) (xy 131.652518 -285.792164) (xy 131.644644 -285.77032)
			(xy 131.636071 -285.743899) (xy 131.62687 -285.689126) (xy 131.626356 -285.661354) (xy 131.626864 -285.635467)
			(xy 131.634963 -285.584329) (xy 131.650962 -285.535089) (xy 131.674468 -285.488957) (xy 131.7049 -285.44707)
			(xy 131.74151 -285.41046) (xy 131.783397 -285.380028) (xy 131.829529 -285.356522) (xy 131.878769 -285.340523)
			(xy 131.929907 -285.332424) (xy 131.981681 -285.332424) (xy 132.032819 -285.340523) (xy 132.082059 -285.356522)
			(xy 132.128191 -285.380028) (xy 132.170078 -285.41046) (xy 132.206688 -285.44707) (xy 132.23712 -285.488957)
			(xy 132.260626 -285.535089) (xy 132.276625 -285.584329) (xy 132.284724 -285.635467) (xy 132.285232 -285.661354)
			(xy 132.284772 -285.686689) (xy 132.277013 -285.736761) (xy 132.261685 -285.785057) (xy 132.239149 -285.830439)
			(xy 132.209936 -285.87184) (xy 132.174734 -285.908285) (xy 132.134371 -285.938915) (xy 132.089797 -285.963011)
			(xy 132.042062 -285.980004) (xy 132.017262 -285.985204) (xy 131.994402 -285.989522) (xy 131.789424 -286.344614)
			(xy 131.797298 -286.366458) (xy 131.805949 -286.392865) (xy 131.815266 -286.447642) (xy 131.81584 -286.475424)
			(xy 133.036056 -286.475424) (xy 133.036554 -286.450079) (xy 133.044323 -286.399987) (xy 133.059668 -286.351675)
			(xy 133.082226 -286.306281) (xy 133.111466 -286.264873) (xy 133.146699 -286.228429) (xy 133.187094 -286.197807)
			(xy 133.2317 -286.173728) (xy 133.279466 -286.156759) (xy 133.30428 -286.151574) (xy 133.32714 -286.147256)
			(xy 133.532118 -285.792164) (xy 133.524244 -285.77032) (xy 133.515671 -285.743899) (xy 133.50647 -285.689126)
			(xy 133.505956 -285.661354) (xy 133.506464 -285.635467) (xy 133.514563 -285.584329) (xy 133.530562 -285.535089)
			(xy 133.554068 -285.488957) (xy 133.5845 -285.44707) (xy 133.62111 -285.41046) (xy 133.662997 -285.380028)
			(xy 133.709129 -285.356522) (xy 133.758369 -285.340523) (xy 133.809507 -285.332424) (xy 133.861281 -285.332424)
			(xy 133.912419 -285.340523) (xy 133.961659 -285.356522) (xy 134.007791 -285.380028) (xy 134.049678 -285.41046)
			(xy 134.086288 -285.44707) (xy 134.11672 -285.488957) (xy 134.140226 -285.535089) (xy 134.156225 -285.584329)
			(xy 134.164324 -285.635467) (xy 134.164832 -285.661354) (xy 335.395824 -285.661354) (xy 335.396245 -285.636017)
			(xy 335.404005 -285.585941) (xy 335.419335 -285.537642) (xy 335.441875 -285.492257) (xy 335.471092 -285.450854)
			(xy 335.5063 -285.41441) (xy 335.54667 -285.383781) (xy 335.59125 -285.359689) (xy 335.638992 -285.342701)
			(xy 335.663794 -285.337504) (xy 335.686654 -285.333186) (xy 335.891632 -284.978094) (xy 335.884012 -284.95625)
			(xy 335.875447 -284.929893) (xy 335.86625 -284.875247) (xy 335.865724 -284.847538) (xy 335.866232 -284.821651)
			(xy 335.874331 -284.770513) (xy 335.89033 -284.721273) (xy 335.913836 -284.675141) (xy 335.944268 -284.633254)
			(xy 335.980878 -284.596644) (xy 336.022765 -284.566212) (xy 336.068897 -284.542706) (xy 336.118137 -284.526707)
			(xy 336.169275 -284.518608) (xy 336.221049 -284.518608) (xy 336.272187 -284.526707) (xy 336.321427 -284.542706)
			(xy 336.367559 -284.566212) (xy 336.409446 -284.596644) (xy 336.446056 -284.633254) (xy 336.476488 -284.675141)
			(xy 336.499994 -284.721273) (xy 336.515993 -284.770513) (xy 336.524092 -284.821651) (xy 336.5246 -284.847538)
			(xy 336.524152 -284.872874) (xy 336.516394 -284.922948) (xy 336.501066 -284.971245) (xy 336.47853 -285.016629)
			(xy 336.449316 -285.058031) (xy 336.414111 -285.094476) (xy 336.373746 -285.125106) (xy 336.329169 -285.149199)
			(xy 336.281431 -285.16619) (xy 336.25663 -285.171388) (xy 336.23377 -285.175706) (xy 336.028792 -285.530798)
			(xy 336.036412 -285.552642) (xy 336.044976 -285.578999) (xy 336.054174 -285.633646) (xy 336.0547 -285.661354)
			(xy 337.275424 -285.661354) (xy 337.275932 -285.635467) (xy 337.284031 -285.584329) (xy 337.30003 -285.535089)
			(xy 337.323536 -285.488957) (xy 337.353968 -285.44707) (xy 337.390578 -285.41046) (xy 337.432465 -285.380028)
			(xy 337.478597 -285.356522) (xy 337.527837 -285.340523) (xy 337.578975 -285.332424) (xy 337.630749 -285.332424)
			(xy 337.681887 -285.340523) (xy 337.731127 -285.356522) (xy 337.777259 -285.380028) (xy 337.819146 -285.41046)
			(xy 337.855756 -285.44707) (xy 337.886188 -285.488957) (xy 337.909694 -285.535089) (xy 337.925693 -285.584329)
			(xy 337.933792 -285.635467) (xy 337.9343 -285.661354) (xy 338.215224 -285.661354) (xy 338.215684 -285.636008)
			(xy 338.223463 -285.585916) (xy 338.238816 -285.537605) (xy 338.26138 -285.492212) (xy 338.290625 -285.450806)
			(xy 338.325861 -285.414363) (xy 338.366259 -285.383741) (xy 338.410867 -285.359661) (xy 338.458634 -285.34269)
			(xy 338.483448 -285.337504) (xy 338.506308 -285.333186) (xy 338.711286 -284.978348) (xy 338.703412 -284.956504)
			(xy 338.694834 -284.930085) (xy 338.685636 -284.87531) (xy 338.685124 -284.847538) (xy 338.685632 -284.821651)
			(xy 338.693731 -284.770513) (xy 338.70973 -284.721273) (xy 338.733236 -284.675141) (xy 338.763668 -284.633254)
			(xy 338.800278 -284.596644) (xy 338.842165 -284.566212) (xy 338.888297 -284.542706) (xy 338.937537 -284.526707)
			(xy 338.988675 -284.518608) (xy 339.040449 -284.518608) (xy 339.091587 -284.526707) (xy 339.140827 -284.542706)
			(xy 339.186959 -284.566212) (xy 339.228846 -284.596644) (xy 339.265456 -284.633254) (xy 339.295888 -284.675141)
			(xy 339.319394 -284.721273) (xy 339.335393 -284.770513) (xy 339.343492 -284.821651) (xy 339.344 -284.847538)
			(xy 339.343552 -284.872874) (xy 339.335794 -284.922948) (xy 339.320466 -284.971245) (xy 339.29793 -285.016629)
			(xy 339.268716 -285.058031) (xy 339.233511 -285.094476) (xy 339.193146 -285.125106) (xy 339.148569 -285.149199)
			(xy 339.100831 -285.16619) (xy 339.07603 -285.171388) (xy 339.05317 -285.175706) (xy 338.848192 -285.530544)
			(xy 338.856066 -285.552642) (xy 338.86469 -285.578991) (xy 338.874015 -285.633637) (xy 338.874608 -285.661354)
			(xy 339.155024 -285.661354) (xy 339.155532 -285.635447) (xy 339.163638 -285.58427) (xy 339.17965 -285.534991)
			(xy 339.203173 -285.488824) (xy 339.233629 -285.446905) (xy 339.270267 -285.410267) (xy 339.312186 -285.379811)
			(xy 339.358353 -285.356288) (xy 339.407632 -285.340276) (xy 339.458809 -285.33217) (xy 339.510623 -285.33217)
			(xy 339.5618 -285.340276) (xy 339.611079 -285.356288) (xy 339.657246 -285.379811) (xy 339.699165 -285.410267)
			(xy 339.735803 -285.446905) (xy 339.766259 -285.488824) (xy 339.789782 -285.534991) (xy 339.805794 -285.58427)
			(xy 339.8139 -285.635447) (xy 339.814408 -285.661354) (xy 340.094824 -285.661354) (xy 340.095245 -285.636017)
			(xy 340.103005 -285.585941) (xy 340.118335 -285.537642) (xy 340.140875 -285.492257) (xy 340.170092 -285.450854)
			(xy 340.2053 -285.41441) (xy 340.24567 -285.383781) (xy 340.29025 -285.359689) (xy 340.337992 -285.342701)
			(xy 340.362794 -285.337504) (xy 340.385654 -285.333186) (xy 340.590886 -284.97784) (xy 340.583266 -284.955996)
			(xy 340.574644 -284.929713) (xy 340.565327 -284.875193) (xy 340.564724 -284.847538) (xy 340.565232 -284.821631)
			(xy 340.573338 -284.770454) (xy 340.58935 -284.721175) (xy 340.612873 -284.675008) (xy 340.643329 -284.633089)
			(xy 340.679967 -284.596451) (xy 340.721886 -284.565995) (xy 340.768053 -284.542472) (xy 340.817332 -284.52646)
			(xy 340.868509 -284.518354) (xy 340.920323 -284.518354) (xy 340.9715 -284.52646) (xy 341.020779 -284.542472)
			(xy 341.066946 -284.565995) (xy 341.108865 -284.596451) (xy 341.145503 -284.633089) (xy 341.175959 -284.675008)
			(xy 341.199482 -284.721175) (xy 341.215494 -284.770454) (xy 341.2236 -284.821631) (xy 341.224108 -284.847538)
			(xy 341.223661 -284.872913) (xy 341.215887 -284.923064) (xy 341.200514 -284.97143) (xy 341.177905 -285.016866)
			(xy 341.148596 -285.058297) (xy 341.113279 -285.094742) (xy 341.072791 -285.125341) (xy 341.028089 -285.149367)
			(xy 340.980231 -285.166254) (xy 340.955376 -285.171388) (xy 340.932516 -285.175706) (xy 340.727538 -285.530544)
			(xy 340.735412 -285.552642) (xy 340.743983 -285.578997) (xy 340.753175 -285.633645) (xy 340.7537 -285.661354)
			(xy 341.034624 -285.661354) (xy 341.035132 -285.635467) (xy 341.043231 -285.584329) (xy 341.05923 -285.535089)
			(xy 341.082736 -285.488957) (xy 341.113168 -285.44707) (xy 341.149778 -285.41046) (xy 341.191665 -285.380028)
			(xy 341.237797 -285.356522) (xy 341.287037 -285.340523) (xy 341.338175 -285.332424) (xy 341.389949 -285.332424)
			(xy 341.441087 -285.340523) (xy 341.490327 -285.356522) (xy 341.536459 -285.380028) (xy 341.578346 -285.41046)
			(xy 341.614956 -285.44707) (xy 341.645388 -285.488957) (xy 341.668894 -285.535089) (xy 341.684893 -285.584329)
			(xy 341.692992 -285.635467) (xy 341.6935 -285.661354) (xy 341.974424 -285.661354) (xy 341.974845 -285.636017)
			(xy 341.982605 -285.585941) (xy 341.997935 -285.537642) (xy 342.020475 -285.492257) (xy 342.049692 -285.450854)
			(xy 342.0849 -285.41441) (xy 342.12527 -285.383781) (xy 342.16985 -285.359689) (xy 342.217592 -285.342701)
			(xy 342.242394 -285.337504) (xy 342.265254 -285.333186) (xy 342.470486 -284.97784) (xy 342.462866 -284.955996)
			(xy 342.454244 -284.929713) (xy 342.444927 -284.875193) (xy 342.444324 -284.847538) (xy 342.444832 -284.821631)
			(xy 342.452938 -284.770454) (xy 342.46895 -284.721175) (xy 342.492473 -284.675008) (xy 342.522929 -284.633089)
			(xy 342.559567 -284.596451) (xy 342.601486 -284.565995) (xy 342.647653 -284.542472) (xy 342.696932 -284.52646)
			(xy 342.748109 -284.518354) (xy 342.799923 -284.518354) (xy 342.8511 -284.52646) (xy 342.900379 -284.542472)
			(xy 342.946546 -284.565995) (xy 342.988465 -284.596451) (xy 343.025103 -284.633089) (xy 343.055559 -284.675008)
			(xy 343.079082 -284.721175) (xy 343.095094 -284.770454) (xy 343.1032 -284.821631) (xy 343.103708 -284.847538)
			(xy 343.103261 -284.872913) (xy 343.095487 -284.923064) (xy 343.080114 -284.97143) (xy 343.057505 -285.016866)
			(xy 343.028196 -285.058297) (xy 342.992879 -285.094742) (xy 342.952391 -285.125341) (xy 342.907689 -285.149367)
			(xy 342.859831 -285.166254) (xy 342.834976 -285.171388) (xy 342.812116 -285.175706) (xy 342.607138 -285.530544)
			(xy 342.615012 -285.552642) (xy 342.623583 -285.578997) (xy 342.632775 -285.633645) (xy 342.6333 -285.661354)
			(xy 342.914224 -285.661354) (xy 342.914732 -285.635467) (xy 342.922831 -285.584329) (xy 342.93883 -285.535089)
			(xy 342.962336 -285.488957) (xy 342.992768 -285.44707) (xy 343.029378 -285.41046) (xy 343.071265 -285.380028)
			(xy 343.117397 -285.356522) (xy 343.166637 -285.340523) (xy 343.217775 -285.332424) (xy 343.269549 -285.332424)
			(xy 343.320687 -285.340523) (xy 343.369927 -285.356522) (xy 343.416059 -285.380028) (xy 343.457946 -285.41046)
			(xy 343.494556 -285.44707) (xy 343.524988 -285.488957) (xy 343.548494 -285.535089) (xy 343.564493 -285.584329)
			(xy 343.572592 -285.635467) (xy 343.5731 -285.661354) (xy 343.854024 -285.661354) (xy 343.854445 -285.636017)
			(xy 343.862205 -285.585941) (xy 343.877535 -285.537642) (xy 343.900075 -285.492257) (xy 343.929292 -285.450854)
			(xy 343.9645 -285.41441) (xy 344.00487 -285.383781) (xy 344.04945 -285.359689) (xy 344.097192 -285.342701)
			(xy 344.121994 -285.337504) (xy 344.144854 -285.333186) (xy 344.350086 -284.97784) (xy 344.342466 -284.955996)
			(xy 344.333844 -284.929713) (xy 344.324527 -284.875193) (xy 344.323924 -284.847538) (xy 344.324432 -284.821631)
			(xy 344.332538 -284.770454) (xy 344.34855 -284.721175) (xy 344.372073 -284.675008) (xy 344.402529 -284.633089)
			(xy 344.439167 -284.596451) (xy 344.481086 -284.565995) (xy 344.527253 -284.542472) (xy 344.576532 -284.52646)
			(xy 344.627709 -284.518354) (xy 344.679523 -284.518354) (xy 344.7307 -284.52646) (xy 344.779979 -284.542472)
			(xy 344.826146 -284.565995) (xy 344.868065 -284.596451) (xy 344.904703 -284.633089) (xy 344.935159 -284.675008)
			(xy 344.958682 -284.721175) (xy 344.974694 -284.770454) (xy 344.9828 -284.821631) (xy 344.983308 -284.847538)
			(xy 344.982861 -284.872913) (xy 344.975087 -284.923064) (xy 344.959714 -284.97143) (xy 344.937105 -285.016866)
			(xy 344.907796 -285.058297) (xy 344.872479 -285.094742) (xy 344.831991 -285.125341) (xy 344.787289 -285.149367)
			(xy 344.739431 -285.166254) (xy 344.714576 -285.171388) (xy 344.691716 -285.175706) (xy 344.486738 -285.530544)
			(xy 344.494612 -285.552642) (xy 344.503183 -285.578997) (xy 344.512375 -285.633645) (xy 344.5129 -285.661354)
			(xy 344.793824 -285.661354) (xy 344.794332 -285.635467) (xy 344.802431 -285.584329) (xy 344.81843 -285.535089)
			(xy 344.841936 -285.488957) (xy 344.872368 -285.44707) (xy 344.908978 -285.41046) (xy 344.950865 -285.380028)
			(xy 344.996997 -285.356522) (xy 345.046237 -285.340523) (xy 345.097375 -285.332424) (xy 345.149149 -285.332424)
			(xy 345.200287 -285.340523) (xy 345.249527 -285.356522) (xy 345.295659 -285.380028) (xy 345.337546 -285.41046)
			(xy 345.374156 -285.44707) (xy 345.404588 -285.488957) (xy 345.428094 -285.535089) (xy 345.444093 -285.584329)
			(xy 345.452192 -285.635467) (xy 345.4527 -285.661354) (xy 345.733624 -285.661354) (xy 345.734045 -285.636017)
			(xy 345.741805 -285.585941) (xy 345.757135 -285.537642) (xy 345.779675 -285.492257) (xy 345.808892 -285.450854)
			(xy 345.8441 -285.41441) (xy 345.88447 -285.383781) (xy 345.92905 -285.359689) (xy 345.976792 -285.342701)
			(xy 346.001594 -285.337504) (xy 346.024454 -285.333186) (xy 346.229686 -284.97784) (xy 346.222066 -284.955996)
			(xy 346.213444 -284.929713) (xy 346.204127 -284.875193) (xy 346.203524 -284.847538) (xy 346.204032 -284.821631)
			(xy 346.212138 -284.770454) (xy 346.22815 -284.721175) (xy 346.251673 -284.675008) (xy 346.282129 -284.633089)
			(xy 346.318767 -284.596451) (xy 346.360686 -284.565995) (xy 346.406853 -284.542472) (xy 346.456132 -284.52646)
			(xy 346.507309 -284.518354) (xy 346.559123 -284.518354) (xy 346.6103 -284.52646) (xy 346.659579 -284.542472)
			(xy 346.705746 -284.565995) (xy 346.747665 -284.596451) (xy 346.784303 -284.633089) (xy 346.814759 -284.675008)
			(xy 346.838282 -284.721175) (xy 346.854294 -284.770454) (xy 346.8624 -284.821631) (xy 346.862908 -284.847538)
			(xy 346.862461 -284.872913) (xy 346.854687 -284.923064) (xy 346.839314 -284.97143) (xy 346.816705 -285.016866)
			(xy 346.787396 -285.058297) (xy 346.752079 -285.094742) (xy 346.711591 -285.125341) (xy 346.666889 -285.149367)
			(xy 346.619031 -285.166254) (xy 346.594176 -285.171388) (xy 346.571316 -285.175706) (xy 346.366338 -285.530544)
			(xy 346.374212 -285.552642) (xy 346.382783 -285.578997) (xy 346.391975 -285.633645) (xy 346.3925 -285.661354)
			(xy 346.673424 -285.661354) (xy 346.673932 -285.635467) (xy 346.682031 -285.584329) (xy 346.69803 -285.535089)
			(xy 346.721536 -285.488957) (xy 346.751968 -285.44707) (xy 346.788578 -285.41046) (xy 346.830465 -285.380028)
			(xy 346.876597 -285.356522) (xy 346.925837 -285.340523) (xy 346.976975 -285.332424) (xy 347.028749 -285.332424)
			(xy 347.079887 -285.340523) (xy 347.129127 -285.356522) (xy 347.175259 -285.380028) (xy 347.217146 -285.41046)
			(xy 347.253756 -285.44707) (xy 347.284188 -285.488957) (xy 347.307694 -285.535089) (xy 347.323693 -285.584329)
			(xy 347.331792 -285.635467) (xy 347.3323 -285.661354) (xy 347.613224 -285.661354) (xy 347.613645 -285.636017)
			(xy 347.621405 -285.585941) (xy 347.636735 -285.537642) (xy 347.659275 -285.492257) (xy 347.688492 -285.450854)
			(xy 347.7237 -285.41441) (xy 347.76407 -285.383781) (xy 347.80865 -285.359689) (xy 347.856392 -285.342701)
			(xy 347.881194 -285.337504) (xy 347.904054 -285.333186) (xy 348.109286 -284.97784) (xy 348.101666 -284.955996)
			(xy 348.093044 -284.929713) (xy 348.083727 -284.875193) (xy 348.083124 -284.847538) (xy 348.083632 -284.821631)
			(xy 348.091738 -284.770454) (xy 348.10775 -284.721175) (xy 348.131273 -284.675008) (xy 348.161729 -284.633089)
			(xy 348.198367 -284.596451) (xy 348.240286 -284.565995) (xy 348.286453 -284.542472) (xy 348.335732 -284.52646)
			(xy 348.386909 -284.518354) (xy 348.438723 -284.518354) (xy 348.4899 -284.52646) (xy 348.539179 -284.542472)
			(xy 348.585346 -284.565995) (xy 348.627265 -284.596451) (xy 348.663903 -284.633089) (xy 348.694359 -284.675008)
			(xy 348.717882 -284.721175) (xy 348.733894 -284.770454) (xy 348.742 -284.821631) (xy 348.742508 -284.847538)
			(xy 348.742061 -284.872913) (xy 348.734287 -284.923064) (xy 348.718914 -284.97143) (xy 348.696305 -285.016866)
			(xy 348.666996 -285.058297) (xy 348.631679 -285.094742) (xy 348.591191 -285.125341) (xy 348.546489 -285.149367)
			(xy 348.498631 -285.166254) (xy 348.473776 -285.171388) (xy 348.450916 -285.175706) (xy 348.245938 -285.530544)
			(xy 348.253812 -285.552642) (xy 348.262383 -285.578997) (xy 348.271575 -285.633645) (xy 348.2721 -285.661354)
			(xy 348.553024 -285.661354) (xy 348.553532 -285.635467) (xy 348.561631 -285.584329) (xy 348.57763 -285.535089)
			(xy 348.601136 -285.488957) (xy 348.631568 -285.44707) (xy 348.668178 -285.41046) (xy 348.710065 -285.380028)
			(xy 348.756197 -285.356522) (xy 348.805437 -285.340523) (xy 348.856575 -285.332424) (xy 348.908349 -285.332424)
			(xy 348.959487 -285.340523) (xy 349.008727 -285.356522) (xy 349.054859 -285.380028) (xy 349.096746 -285.41046)
			(xy 349.133356 -285.44707) (xy 349.163788 -285.488957) (xy 349.187294 -285.535089) (xy 349.203293 -285.584329)
			(xy 349.211392 -285.635467) (xy 349.2119 -285.661354) (xy 349.492824 -285.661354) (xy 349.493245 -285.636017)
			(xy 349.501005 -285.585941) (xy 349.516335 -285.537642) (xy 349.538875 -285.492257) (xy 349.568092 -285.450854)
			(xy 349.6033 -285.41441) (xy 349.64367 -285.383781) (xy 349.68825 -285.359689) (xy 349.735992 -285.342701)
			(xy 349.760794 -285.337504) (xy 349.783654 -285.333186) (xy 349.988886 -284.97784) (xy 349.981266 -284.955996)
			(xy 349.972644 -284.929713) (xy 349.963327 -284.875193) (xy 349.962724 -284.847538) (xy 349.963232 -284.821631)
			(xy 349.971338 -284.770454) (xy 349.98735 -284.721175) (xy 350.010873 -284.675008) (xy 350.041329 -284.633089)
			(xy 350.077967 -284.596451) (xy 350.119886 -284.565995) (xy 350.166053 -284.542472) (xy 350.215332 -284.52646)
			(xy 350.266509 -284.518354) (xy 350.318323 -284.518354) (xy 350.3695 -284.52646) (xy 350.418779 -284.542472)
			(xy 350.464946 -284.565995) (xy 350.506865 -284.596451) (xy 350.543503 -284.633089) (xy 350.573959 -284.675008)
			(xy 350.597482 -284.721175) (xy 350.613494 -284.770454) (xy 350.6216 -284.821631) (xy 350.622108 -284.847538)
			(xy 350.621661 -284.872913) (xy 350.613887 -284.923064) (xy 350.598514 -284.97143) (xy 350.575905 -285.016866)
			(xy 350.546596 -285.058297) (xy 350.511279 -285.094742) (xy 350.470791 -285.125341) (xy 350.426089 -285.149367)
			(xy 350.378231 -285.166254) (xy 350.353376 -285.171388) (xy 350.330516 -285.175706) (xy 350.125538 -285.530544)
			(xy 350.133412 -285.552642) (xy 350.141983 -285.578997) (xy 350.151175 -285.633645) (xy 350.1517 -285.661354)
			(xy 350.432624 -285.661354) (xy 350.433132 -285.635467) (xy 350.441231 -285.584329) (xy 350.45723 -285.535089)
			(xy 350.480736 -285.488957) (xy 350.511168 -285.44707) (xy 350.547778 -285.41046) (xy 350.589665 -285.380028)
			(xy 350.635797 -285.356522) (xy 350.685037 -285.340523) (xy 350.736175 -285.332424) (xy 350.787949 -285.332424)
			(xy 350.839087 -285.340523) (xy 350.888327 -285.356522) (xy 350.934459 -285.380028) (xy 350.976346 -285.41046)
			(xy 351.012956 -285.44707) (xy 351.043388 -285.488957) (xy 351.066894 -285.535089) (xy 351.082893 -285.584329)
			(xy 351.090992 -285.635467) (xy 351.0915 -285.661354) (xy 351.372424 -285.661354) (xy 351.372845 -285.636017)
			(xy 351.380605 -285.585941) (xy 351.395935 -285.537642) (xy 351.418475 -285.492257) (xy 351.447692 -285.450854)
			(xy 351.4829 -285.41441) (xy 351.52327 -285.383781) (xy 351.56785 -285.359689) (xy 351.615592 -285.342701)
			(xy 351.640394 -285.337504) (xy 351.663254 -285.333186) (xy 351.868486 -284.97784) (xy 351.860866 -284.955996)
			(xy 351.852244 -284.929713) (xy 351.842927 -284.875193) (xy 351.842324 -284.847538) (xy 351.842832 -284.821631)
			(xy 351.850938 -284.770454) (xy 351.86695 -284.721175) (xy 351.890473 -284.675008) (xy 351.920929 -284.633089)
			(xy 351.957567 -284.596451) (xy 351.999486 -284.565995) (xy 352.045653 -284.542472) (xy 352.094932 -284.52646)
			(xy 352.146109 -284.518354) (xy 352.197923 -284.518354) (xy 352.2491 -284.52646) (xy 352.298379 -284.542472)
			(xy 352.344546 -284.565995) (xy 352.386465 -284.596451) (xy 352.423103 -284.633089) (xy 352.453559 -284.675008)
			(xy 352.477082 -284.721175) (xy 352.493094 -284.770454) (xy 352.5012 -284.821631) (xy 352.501708 -284.847538)
			(xy 366.879124 -284.847538) (xy 366.879632 -284.821631) (xy 366.887738 -284.770454) (xy 366.90375 -284.721175)
			(xy 366.927273 -284.675008) (xy 366.957729 -284.633089) (xy 366.994367 -284.596451) (xy 367.036286 -284.565995)
			(xy 367.082453 -284.542472) (xy 367.131732 -284.52646) (xy 367.182909 -284.518354) (xy 367.234723 -284.518354)
			(xy 367.2859 -284.52646) (xy 367.335179 -284.542472) (xy 367.381346 -284.565995) (xy 367.423265 -284.596451)
			(xy 367.459903 -284.633089) (xy 367.490359 -284.675008) (xy 367.513882 -284.721175) (xy 367.529894 -284.770454)
			(xy 367.538 -284.821631) (xy 367.538508 -284.847538) (xy 368.758724 -284.847538) (xy 368.759232 -284.821631)
			(xy 368.767338 -284.770454) (xy 368.78335 -284.721175) (xy 368.806873 -284.675008) (xy 368.837329 -284.633089)
			(xy 368.873967 -284.596451) (xy 368.915886 -284.565995) (xy 368.962053 -284.542472) (xy 369.011332 -284.52646)
			(xy 369.062509 -284.518354) (xy 369.114323 -284.518354) (xy 369.1655 -284.52646) (xy 369.214779 -284.542472)
			(xy 369.260946 -284.565995) (xy 369.302865 -284.596451) (xy 369.339503 -284.633089) (xy 369.369959 -284.675008)
			(xy 369.393482 -284.721175) (xy 369.409494 -284.770454) (xy 369.4176 -284.821631) (xy 369.418108 -284.847538)
			(xy 370.638324 -284.847538) (xy 370.638832 -284.821631) (xy 370.646938 -284.770454) (xy 370.66295 -284.721175)
			(xy 370.686473 -284.675008) (xy 370.716929 -284.633089) (xy 370.753567 -284.596451) (xy 370.795486 -284.565995)
			(xy 370.841653 -284.542472) (xy 370.890932 -284.52646) (xy 370.942109 -284.518354) (xy 370.993923 -284.518354)
			(xy 371.0451 -284.52646) (xy 371.094379 -284.542472) (xy 371.140546 -284.565995) (xy 371.182465 -284.596451)
			(xy 371.219103 -284.633089) (xy 371.249559 -284.675008) (xy 371.273082 -284.721175) (xy 371.289094 -284.770454)
			(xy 371.2972 -284.821631) (xy 371.297708 -284.847538) (xy 372.517924 -284.847538) (xy 372.518432 -284.821631)
			(xy 372.526538 -284.770454) (xy 372.54255 -284.721175) (xy 372.566073 -284.675008) (xy 372.596529 -284.633089)
			(xy 372.633167 -284.596451) (xy 372.675086 -284.565995) (xy 372.721253 -284.542472) (xy 372.770532 -284.52646)
			(xy 372.821709 -284.518354) (xy 372.873523 -284.518354) (xy 372.9247 -284.52646) (xy 372.973979 -284.542472)
			(xy 373.020146 -284.565995) (xy 373.062065 -284.596451) (xy 373.098703 -284.633089) (xy 373.129159 -284.675008)
			(xy 373.152682 -284.721175) (xy 373.168694 -284.770454) (xy 373.1768 -284.821631) (xy 373.177308 -284.847538)
			(xy 374.397524 -284.847538) (xy 374.398032 -284.821631) (xy 374.406138 -284.770454) (xy 374.42215 -284.721175)
			(xy 374.445673 -284.675008) (xy 374.476129 -284.633089) (xy 374.512767 -284.596451) (xy 374.554686 -284.565995)
			(xy 374.600853 -284.542472) (xy 374.650132 -284.52646) (xy 374.701309 -284.518354) (xy 374.753123 -284.518354)
			(xy 374.8043 -284.52646) (xy 374.853579 -284.542472) (xy 374.899746 -284.565995) (xy 374.941665 -284.596451)
			(xy 374.978303 -284.633089) (xy 375.008759 -284.675008) (xy 375.032282 -284.721175) (xy 375.048294 -284.770454)
			(xy 375.0564 -284.821631) (xy 375.056908 -284.847538) (xy 376.277124 -284.847538) (xy 376.277632 -284.821631)
			(xy 376.285738 -284.770454) (xy 376.30175 -284.721175) (xy 376.325273 -284.675008) (xy 376.355729 -284.633089)
			(xy 376.392367 -284.596451) (xy 376.434286 -284.565995) (xy 376.480453 -284.542472) (xy 376.529732 -284.52646)
			(xy 376.580909 -284.518354) (xy 376.632723 -284.518354) (xy 376.6839 -284.52646) (xy 376.733179 -284.542472)
			(xy 376.779346 -284.565995) (xy 376.821265 -284.596451) (xy 376.857903 -284.633089) (xy 376.888359 -284.675008)
			(xy 376.911882 -284.721175) (xy 376.927894 -284.770454) (xy 376.936 -284.821631) (xy 376.936508 -284.847538)
			(xy 378.156724 -284.847538) (xy 378.157232 -284.821631) (xy 378.165338 -284.770454) (xy 378.18135 -284.721175)
			(xy 378.204873 -284.675008) (xy 378.235329 -284.633089) (xy 378.271967 -284.596451) (xy 378.313886 -284.565995)
			(xy 378.360053 -284.542472) (xy 378.409332 -284.52646) (xy 378.460509 -284.518354) (xy 378.512323 -284.518354)
			(xy 378.5635 -284.52646) (xy 378.612779 -284.542472) (xy 378.658946 -284.565995) (xy 378.700865 -284.596451)
			(xy 378.737503 -284.633089) (xy 378.767959 -284.675008) (xy 378.791482 -284.721175) (xy 378.807494 -284.770454)
			(xy 378.8156 -284.821631) (xy 378.816108 -284.847538) (xy 380.036324 -284.847538) (xy 380.036832 -284.821631)
			(xy 380.044938 -284.770454) (xy 380.06095 -284.721175) (xy 380.084473 -284.675008) (xy 380.114929 -284.633089)
			(xy 380.151567 -284.596451) (xy 380.193486 -284.565995) (xy 380.239653 -284.542472) (xy 380.288932 -284.52646)
			(xy 380.340109 -284.518354) (xy 380.391923 -284.518354) (xy 380.4431 -284.52646) (xy 380.492379 -284.542472)
			(xy 380.538546 -284.565995) (xy 380.580465 -284.596451) (xy 380.617103 -284.633089) (xy 380.647559 -284.675008)
			(xy 380.671082 -284.721175) (xy 380.687094 -284.770454) (xy 380.6952 -284.821631) (xy 380.695708 -284.847538)
			(xy 380.695098 -284.875255) (xy 380.685785 -284.929901) (xy 380.677166 -284.95625) (xy 380.669292 -284.978348)
			(xy 380.87427 -285.333186) (xy 380.89713 -285.337504) (xy 380.921947 -285.342634) (xy 380.969689 -285.35963)
			(xy 381.014267 -285.383731) (xy 381.054634 -285.414369) (xy 381.089836 -285.450823) (xy 381.119046 -285.492235)
			(xy 381.141576 -285.537628) (xy 381.156894 -285.585934) (xy 381.16464 -285.636016) (xy 381.1651 -285.661354)
			(xy 381.164592 -285.687241) (xy 381.156493 -285.738379) (xy 381.140494 -285.787619) (xy 381.116988 -285.833751)
			(xy 381.086556 -285.875638) (xy 381.049946 -285.912248) (xy 381.008059 -285.94268) (xy 380.961927 -285.966186)
			(xy 380.912687 -285.982185) (xy 380.861549 -285.990284) (xy 380.809775 -285.990284) (xy 380.758637 -285.982185)
			(xy 380.709397 -285.966186) (xy 380.663265 -285.94268) (xy 380.621378 -285.912248) (xy 380.584768 -285.875638)
			(xy 380.554336 -285.833751) (xy 380.53083 -285.787619) (xy 380.514831 -285.738379) (xy 380.506732 -285.687241)
			(xy 380.506224 -285.661354) (xy 380.506766 -285.633646) (xy 380.515953 -285.579) (xy 380.524512 -285.552642)
			(xy 380.532386 -285.530544) (xy 380.327408 -285.175706) (xy 380.304548 -285.171388) (xy 380.279723 -285.166238)
			(xy 380.231943 -285.149282) (xy 380.187323 -285.125209) (xy 380.146916 -285.094586) (xy 380.111675 -285.058137)
			(xy 380.082431 -285.016721) (xy 380.059876 -284.971315) (xy 380.044539 -284.922991) (xy 380.036785 -284.872888)
			(xy 380.036324 -284.847538) (xy 378.816108 -284.847538) (xy 378.815498 -284.875255) (xy 378.806185 -284.929901)
			(xy 378.797566 -284.95625) (xy 378.789692 -284.978348) (xy 378.99467 -285.333186) (xy 379.01753 -285.337504)
			(xy 379.042347 -285.342634) (xy 379.090089 -285.35963) (xy 379.134667 -285.383731) (xy 379.175034 -285.414369)
			(xy 379.210236 -285.450823) (xy 379.239446 -285.492235) (xy 379.261976 -285.537628) (xy 379.277294 -285.585934)
			(xy 379.28504 -285.636016) (xy 379.2855 -285.661354) (xy 379.284992 -285.687241) (xy 379.276893 -285.738379)
			(xy 379.260894 -285.787619) (xy 379.237388 -285.833751) (xy 379.206956 -285.875638) (xy 379.170346 -285.912248)
			(xy 379.128459 -285.94268) (xy 379.082327 -285.966186) (xy 379.033087 -285.982185) (xy 378.981949 -285.990284)
			(xy 378.930175 -285.990284) (xy 378.879037 -285.982185) (xy 378.829797 -285.966186) (xy 378.783665 -285.94268)
			(xy 378.741778 -285.912248) (xy 378.705168 -285.875638) (xy 378.674736 -285.833751) (xy 378.65123 -285.787619)
			(xy 378.635231 -285.738379) (xy 378.627132 -285.687241) (xy 378.626624 -285.661354) (xy 378.627166 -285.633646)
			(xy 378.636353 -285.579) (xy 378.644912 -285.552642) (xy 378.652786 -285.530544) (xy 378.447808 -285.175706)
			(xy 378.424948 -285.171388) (xy 378.400123 -285.166238) (xy 378.352343 -285.149282) (xy 378.307723 -285.125209)
			(xy 378.267316 -285.094586) (xy 378.232075 -285.058137) (xy 378.202831 -285.016721) (xy 378.180276 -284.971315)
			(xy 378.164939 -284.922991) (xy 378.157185 -284.872888) (xy 378.156724 -284.847538) (xy 376.936508 -284.847538)
			(xy 376.935898 -284.875255) (xy 376.926585 -284.929901) (xy 376.917966 -284.95625) (xy 376.910092 -284.978348)
			(xy 377.11507 -285.333186) (xy 377.13793 -285.337504) (xy 377.162747 -285.342634) (xy 377.210489 -285.35963)
			(xy 377.255067 -285.383731) (xy 377.295434 -285.414369) (xy 377.330636 -285.450823) (xy 377.359846 -285.492235)
			(xy 377.382376 -285.537628) (xy 377.397694 -285.585934) (xy 377.40544 -285.636016) (xy 377.4059 -285.661354)
			(xy 377.405392 -285.687241) (xy 377.397293 -285.738379) (xy 377.381294 -285.787619) (xy 377.357788 -285.833751)
			(xy 377.327356 -285.875638) (xy 377.290746 -285.912248) (xy 377.248859 -285.94268) (xy 377.202727 -285.966186)
			(xy 377.153487 -285.982185) (xy 377.102349 -285.990284) (xy 377.050575 -285.990284) (xy 376.999437 -285.982185)
			(xy 376.950197 -285.966186) (xy 376.904065 -285.94268) (xy 376.862178 -285.912248) (xy 376.825568 -285.875638)
			(xy 376.795136 -285.833751) (xy 376.77163 -285.787619) (xy 376.755631 -285.738379) (xy 376.747532 -285.687241)
			(xy 376.747024 -285.661354) (xy 376.747566 -285.633646) (xy 376.756753 -285.579) (xy 376.765312 -285.552642)
			(xy 376.773186 -285.530544) (xy 376.568208 -285.175706) (xy 376.545348 -285.171388) (xy 376.520523 -285.166238)
			(xy 376.472743 -285.149282) (xy 376.428123 -285.125209) (xy 376.387716 -285.094586) (xy 376.352475 -285.058137)
			(xy 376.323231 -285.016721) (xy 376.300676 -284.971315) (xy 376.285339 -284.922991) (xy 376.277585 -284.872888)
			(xy 376.277124 -284.847538) (xy 375.056908 -284.847538) (xy 375.056298 -284.875255) (xy 375.046985 -284.929901)
			(xy 375.038366 -284.95625) (xy 375.030492 -284.978348) (xy 375.23547 -285.333186) (xy 375.25833 -285.337504)
			(xy 375.283147 -285.342634) (xy 375.330889 -285.35963) (xy 375.375467 -285.383731) (xy 375.415834 -285.414369)
			(xy 375.451036 -285.450823) (xy 375.480246 -285.492235) (xy 375.502776 -285.537628) (xy 375.518094 -285.585934)
			(xy 375.52584 -285.636016) (xy 375.5263 -285.661354) (xy 375.525792 -285.687241) (xy 375.517693 -285.738379)
			(xy 375.501694 -285.787619) (xy 375.478188 -285.833751) (xy 375.447756 -285.875638) (xy 375.411146 -285.912248)
			(xy 375.369259 -285.94268) (xy 375.323127 -285.966186) (xy 375.273887 -285.982185) (xy 375.222749 -285.990284)
			(xy 375.170975 -285.990284) (xy 375.119837 -285.982185) (xy 375.070597 -285.966186) (xy 375.024465 -285.94268)
			(xy 374.982578 -285.912248) (xy 374.945968 -285.875638) (xy 374.915536 -285.833751) (xy 374.89203 -285.787619)
			(xy 374.876031 -285.738379) (xy 374.867932 -285.687241) (xy 374.867424 -285.661354) (xy 374.867966 -285.633646)
			(xy 374.877153 -285.579) (xy 374.885712 -285.552642) (xy 374.893586 -285.530544) (xy 374.688608 -285.175706)
			(xy 374.665748 -285.171388) (xy 374.640923 -285.166238) (xy 374.593143 -285.149282) (xy 374.548523 -285.125209)
			(xy 374.508116 -285.094586) (xy 374.472875 -285.058137) (xy 374.443631 -285.016721) (xy 374.421076 -284.971315)
			(xy 374.405739 -284.922991) (xy 374.397985 -284.872888) (xy 374.397524 -284.847538) (xy 373.177308 -284.847538)
			(xy 373.176698 -284.875255) (xy 373.167385 -284.929901) (xy 373.158766 -284.95625) (xy 373.150892 -284.978348)
			(xy 373.35587 -285.333186) (xy 373.37873 -285.337504) (xy 373.403547 -285.342634) (xy 373.451289 -285.35963)
			(xy 373.495867 -285.383731) (xy 373.536234 -285.414369) (xy 373.571436 -285.450823) (xy 373.600646 -285.492235)
			(xy 373.623176 -285.537628) (xy 373.638494 -285.585934) (xy 373.64624 -285.636016) (xy 373.6467 -285.661354)
			(xy 373.646192 -285.687241) (xy 373.638093 -285.738379) (xy 373.622094 -285.787619) (xy 373.598588 -285.833751)
			(xy 373.568156 -285.875638) (xy 373.531546 -285.912248) (xy 373.489659 -285.94268) (xy 373.443527 -285.966186)
			(xy 373.394287 -285.982185) (xy 373.343149 -285.990284) (xy 373.291375 -285.990284) (xy 373.240237 -285.982185)
			(xy 373.190997 -285.966186) (xy 373.144865 -285.94268) (xy 373.102978 -285.912248) (xy 373.066368 -285.875638)
			(xy 373.035936 -285.833751) (xy 373.01243 -285.787619) (xy 372.996431 -285.738379) (xy 372.988332 -285.687241)
			(xy 372.987824 -285.661354) (xy 372.988366 -285.633646) (xy 372.997553 -285.579) (xy 373.006112 -285.552642)
			(xy 373.013986 -285.530544) (xy 372.809008 -285.175706) (xy 372.786148 -285.171388) (xy 372.761323 -285.166238)
			(xy 372.713543 -285.149282) (xy 372.668923 -285.125209) (xy 372.628516 -285.094586) (xy 372.593275 -285.058137)
			(xy 372.564031 -285.016721) (xy 372.541476 -284.971315) (xy 372.526139 -284.922991) (xy 372.518385 -284.872888)
			(xy 372.517924 -284.847538) (xy 371.297708 -284.847538) (xy 371.297098 -284.875255) (xy 371.287785 -284.929901)
			(xy 371.279166 -284.95625) (xy 371.271292 -284.978348) (xy 371.47627 -285.333186) (xy 371.49913 -285.337504)
			(xy 371.523947 -285.342634) (xy 371.571689 -285.35963) (xy 371.616267 -285.383731) (xy 371.656634 -285.414369)
			(xy 371.691836 -285.450823) (xy 371.721046 -285.492235) (xy 371.743576 -285.537628) (xy 371.758894 -285.585934)
			(xy 371.76664 -285.636016) (xy 371.7671 -285.661354) (xy 371.766592 -285.687241) (xy 371.758493 -285.738379)
			(xy 371.742494 -285.787619) (xy 371.718988 -285.833751) (xy 371.688556 -285.875638) (xy 371.651946 -285.912248)
			(xy 371.610059 -285.94268) (xy 371.563927 -285.966186) (xy 371.514687 -285.982185) (xy 371.463549 -285.990284)
			(xy 371.411775 -285.990284) (xy 371.360637 -285.982185) (xy 371.311397 -285.966186) (xy 371.265265 -285.94268)
			(xy 371.223378 -285.912248) (xy 371.186768 -285.875638) (xy 371.156336 -285.833751) (xy 371.13283 -285.787619)
			(xy 371.116831 -285.738379) (xy 371.108732 -285.687241) (xy 371.108224 -285.661354) (xy 371.108766 -285.633646)
			(xy 371.117953 -285.579) (xy 371.126512 -285.552642) (xy 371.134386 -285.530544) (xy 370.929408 -285.175706)
			(xy 370.906548 -285.171388) (xy 370.881723 -285.166238) (xy 370.833943 -285.149282) (xy 370.789323 -285.125209)
			(xy 370.748916 -285.094586) (xy 370.713675 -285.058137) (xy 370.684431 -285.016721) (xy 370.661876 -284.971315)
			(xy 370.646539 -284.922991) (xy 370.638785 -284.872888) (xy 370.638324 -284.847538) (xy 369.418108 -284.847538)
			(xy 369.417498 -284.875255) (xy 369.408185 -284.929901) (xy 369.399566 -284.95625) (xy 369.391692 -284.978348)
			(xy 369.59667 -285.333186) (xy 369.61953 -285.337504) (xy 369.644347 -285.342634) (xy 369.692089 -285.35963)
			(xy 369.736667 -285.383731) (xy 369.777034 -285.414369) (xy 369.812236 -285.450823) (xy 369.841446 -285.492235)
			(xy 369.863976 -285.537628) (xy 369.879294 -285.585934) (xy 369.88704 -285.636016) (xy 369.8875 -285.661354)
			(xy 369.886992 -285.687241) (xy 369.878893 -285.738379) (xy 369.862894 -285.787619) (xy 369.839388 -285.833751)
			(xy 369.808956 -285.875638) (xy 369.772346 -285.912248) (xy 369.730459 -285.94268) (xy 369.684327 -285.966186)
			(xy 369.635087 -285.982185) (xy 369.583949 -285.990284) (xy 369.532175 -285.990284) (xy 369.481037 -285.982185)
			(xy 369.431797 -285.966186) (xy 369.385665 -285.94268) (xy 369.343778 -285.912248) (xy 369.307168 -285.875638)
			(xy 369.276736 -285.833751) (xy 369.25323 -285.787619) (xy 369.237231 -285.738379) (xy 369.229132 -285.687241)
			(xy 369.228624 -285.661354) (xy 369.229166 -285.633646) (xy 369.238353 -285.579) (xy 369.246912 -285.552642)
			(xy 369.254786 -285.530544) (xy 369.049808 -285.175706) (xy 369.026948 -285.171388) (xy 369.002123 -285.166238)
			(xy 368.954343 -285.149282) (xy 368.909723 -285.125209) (xy 368.869316 -285.094586) (xy 368.834075 -285.058137)
			(xy 368.804831 -285.016721) (xy 368.782276 -284.971315) (xy 368.766939 -284.922991) (xy 368.759185 -284.872888)
			(xy 368.758724 -284.847538) (xy 367.538508 -284.847538) (xy 367.537898 -284.875255) (xy 367.528585 -284.929901)
			(xy 367.519966 -284.95625) (xy 367.512092 -284.978348) (xy 367.71707 -285.333186) (xy 367.73993 -285.337504)
			(xy 367.764747 -285.342634) (xy 367.812489 -285.35963) (xy 367.857067 -285.383731) (xy 367.897434 -285.414369)
			(xy 367.932636 -285.450823) (xy 367.961846 -285.492235) (xy 367.984376 -285.537628) (xy 367.999694 -285.585934)
			(xy 368.00744 -285.636016) (xy 368.0079 -285.661354) (xy 368.007392 -285.687241) (xy 367.999293 -285.738379)
			(xy 367.983294 -285.787619) (xy 367.959788 -285.833751) (xy 367.929356 -285.875638) (xy 367.892746 -285.912248)
			(xy 367.850859 -285.94268) (xy 367.804727 -285.966186) (xy 367.755487 -285.982185) (xy 367.704349 -285.990284)
			(xy 367.652575 -285.990284) (xy 367.601437 -285.982185) (xy 367.552197 -285.966186) (xy 367.506065 -285.94268)
			(xy 367.464178 -285.912248) (xy 367.427568 -285.875638) (xy 367.397136 -285.833751) (xy 367.37363 -285.787619)
			(xy 367.357631 -285.738379) (xy 367.349532 -285.687241) (xy 367.349024 -285.661354) (xy 367.349566 -285.633646)
			(xy 367.358753 -285.579) (xy 367.367312 -285.552642) (xy 367.375186 -285.530544) (xy 367.170208 -285.175706)
			(xy 367.147348 -285.171388) (xy 367.122523 -285.166238) (xy 367.074743 -285.149282) (xy 367.030123 -285.125209)
			(xy 366.989716 -285.094586) (xy 366.954475 -285.058137) (xy 366.925231 -285.016721) (xy 366.902676 -284.971315)
			(xy 366.887339 -284.922991) (xy 366.879585 -284.872888) (xy 366.879124 -284.847538) (xy 352.501708 -284.847538)
			(xy 352.501261 -284.872913) (xy 352.493487 -284.923064) (xy 352.478114 -284.97143) (xy 352.455505 -285.016866)
			(xy 352.426196 -285.058297) (xy 352.390879 -285.094742) (xy 352.350391 -285.125341) (xy 352.305689 -285.149367)
			(xy 352.257831 -285.166254) (xy 352.232976 -285.171388) (xy 352.210116 -285.175706) (xy 352.005138 -285.530544)
			(xy 352.013012 -285.552642) (xy 352.021583 -285.578997) (xy 352.030775 -285.633645) (xy 352.0313 -285.661354)
			(xy 352.030792 -285.687241) (xy 352.022693 -285.738379) (xy 352.006694 -285.787619) (xy 351.983188 -285.833751)
			(xy 351.952756 -285.875638) (xy 351.916146 -285.912248) (xy 351.874259 -285.94268) (xy 351.828127 -285.966186)
			(xy 351.778887 -285.982185) (xy 351.727749 -285.990284) (xy 351.675975 -285.990284) (xy 351.624837 -285.982185)
			(xy 351.575597 -285.966186) (xy 351.529465 -285.94268) (xy 351.487578 -285.912248) (xy 351.450968 -285.875638)
			(xy 351.420536 -285.833751) (xy 351.39703 -285.787619) (xy 351.381031 -285.738379) (xy 351.372932 -285.687241)
			(xy 351.372424 -285.661354) (xy 351.0915 -285.661354) (xy 351.0915 -285.661862) (xy 351.090923 -285.689379)
			(xy 351.081728 -285.74364) (xy 351.073212 -285.769812) (xy 351.065592 -285.79191) (xy 351.270824 -286.147256)
			(xy 351.293684 -286.151574) (xy 351.318506 -286.156737) (xy 351.366283 -286.173695) (xy 351.410901 -286.197768)
			(xy 351.451306 -286.22839) (xy 351.486546 -286.264837) (xy 351.515789 -286.30625) (xy 351.538346 -286.351653)
			(xy 351.553685 -286.399975) (xy 351.561445 -286.450075) (xy 351.561908 -286.475424) (xy 367.818924 -286.475424)
			(xy 367.819448 -286.45008) (xy 367.827216 -286.399991) (xy 367.842559 -286.351681) (xy 367.865115 -286.306288)
			(xy 367.894351 -286.264882) (xy 367.92958 -286.228438) (xy 367.969972 -286.197814) (xy 368.014574 -286.173733)
			(xy 368.062336 -286.156761) (xy 368.087148 -286.151574) (xy 368.110008 -286.147256) (xy 368.314986 -285.792164)
			(xy 368.307112 -285.77032) (xy 368.298538 -285.7439) (xy 368.289338 -285.689126) (xy 368.288824 -285.661354)
			(xy 368.289332 -285.635467) (xy 368.297431 -285.584329) (xy 368.31343 -285.535089) (xy 368.336936 -285.488957)
			(xy 368.367368 -285.44707) (xy 368.403978 -285.41046) (xy 368.445865 -285.380028) (xy 368.491997 -285.356522)
			(xy 368.541237 -285.340523) (xy 368.592375 -285.332424) (xy 368.644149 -285.332424) (xy 368.695287 -285.340523)
			(xy 368.744527 -285.356522) (xy 368.790659 -285.380028) (xy 368.832546 -285.41046) (xy 368.869156 -285.44707)
			(xy 368.899588 -285.488957) (xy 368.923094 -285.535089) (xy 368.939093 -285.584329) (xy 368.947192 -285.635467)
			(xy 368.9477 -285.661354) (xy 368.947266 -285.68669) (xy 368.939506 -285.736765) (xy 368.924176 -285.785062)
			(xy 368.901638 -285.830446) (xy 368.872422 -285.871848) (xy 368.837216 -285.908293) (xy 368.796849 -285.938922)
			(xy 368.752271 -285.963016) (xy 368.704531 -285.980006) (xy 368.67973 -285.985204) (xy 368.65687 -285.989522)
			(xy 368.451892 -286.344614) (xy 368.459766 -286.366458) (xy 368.468419 -286.392864) (xy 368.477734 -286.447642)
			(xy 368.478308 -286.475424) (xy 369.698524 -286.475424) (xy 369.699048 -286.45008) (xy 369.706816 -286.399991)
			(xy 369.722159 -286.351681) (xy 369.744715 -286.306288) (xy 369.773951 -286.264882) (xy 369.80918 -286.228438)
			(xy 369.849572 -286.197814) (xy 369.894174 -286.173733) (xy 369.941936 -286.156761) (xy 369.966748 -286.151574)
			(xy 369.989608 -286.147256) (xy 370.194586 -285.792164) (xy 370.186712 -285.77032) (xy 370.178138 -285.7439)
			(xy 370.168938 -285.689126) (xy 370.168424 -285.661354) (xy 370.168932 -285.635467) (xy 370.177031 -285.584329)
			(xy 370.19303 -285.535089) (xy 370.216536 -285.488957) (xy 370.246968 -285.44707) (xy 370.283578 -285.41046)
			(xy 370.325465 -285.380028) (xy 370.371597 -285.356522) (xy 370.420837 -285.340523) (xy 370.471975 -285.332424)
			(xy 370.523749 -285.332424) (xy 370.574887 -285.340523) (xy 370.624127 -285.356522) (xy 370.670259 -285.380028)
			(xy 370.712146 -285.41046) (xy 370.748756 -285.44707) (xy 370.779188 -285.488957) (xy 370.802694 -285.535089)
			(xy 370.818693 -285.584329) (xy 370.826792 -285.635467) (xy 370.8273 -285.661354) (xy 370.826866 -285.68669)
			(xy 370.819106 -285.736765) (xy 370.803776 -285.785062) (xy 370.781238 -285.830446) (xy 370.752022 -285.871848)
			(xy 370.716816 -285.908293) (xy 370.676449 -285.938922) (xy 370.631871 -285.963016) (xy 370.584131 -285.980006)
			(xy 370.55933 -285.985204) (xy 370.53647 -285.989522) (xy 370.331492 -286.344614) (xy 370.339366 -286.366458)
			(xy 370.348019 -286.392864) (xy 370.357334 -286.447642) (xy 370.357908 -286.475424) (xy 371.578124 -286.475424)
			(xy 371.578648 -286.45008) (xy 371.586416 -286.399991) (xy 371.601759 -286.351681) (xy 371.624315 -286.306288)
			(xy 371.653551 -286.264882) (xy 371.68878 -286.228438) (xy 371.729172 -286.197814) (xy 371.773774 -286.173733)
			(xy 371.821536 -286.156761) (xy 371.846348 -286.151574) (xy 371.869208 -286.147256) (xy 372.074186 -285.792164)
			(xy 372.066312 -285.77032) (xy 372.057738 -285.7439) (xy 372.048538 -285.689126) (xy 372.048024 -285.661354)
			(xy 372.048532 -285.635467) (xy 372.056631 -285.584329) (xy 372.07263 -285.535089) (xy 372.096136 -285.488957)
			(xy 372.126568 -285.44707) (xy 372.163178 -285.41046) (xy 372.205065 -285.380028) (xy 372.251197 -285.356522)
			(xy 372.300437 -285.340523) (xy 372.351575 -285.332424) (xy 372.403349 -285.332424) (xy 372.454487 -285.340523)
			(xy 372.503727 -285.356522) (xy 372.549859 -285.380028) (xy 372.591746 -285.41046) (xy 372.628356 -285.44707)
			(xy 372.658788 -285.488957) (xy 372.682294 -285.535089) (xy 372.698293 -285.584329) (xy 372.706392 -285.635467)
			(xy 372.7069 -285.661354) (xy 372.706466 -285.68669) (xy 372.698706 -285.736765) (xy 372.683376 -285.785062)
			(xy 372.660838 -285.830446) (xy 372.631622 -285.871848) (xy 372.596416 -285.908293) (xy 372.556049 -285.938922)
			(xy 372.511471 -285.963016) (xy 372.463731 -285.980006) (xy 372.43893 -285.985204) (xy 372.41607 -285.989522)
			(xy 372.211092 -286.344614) (xy 372.218966 -286.366458) (xy 372.227619 -286.392864) (xy 372.236934 -286.447642)
			(xy 372.237508 -286.475424) (xy 373.457724 -286.475424) (xy 373.458248 -286.45008) (xy 373.466016 -286.399991)
			(xy 373.481359 -286.351681) (xy 373.503915 -286.306288) (xy 373.533151 -286.264882) (xy 373.56838 -286.228438)
			(xy 373.608772 -286.197814) (xy 373.653374 -286.173733) (xy 373.701136 -286.156761) (xy 373.725948 -286.151574)
			(xy 373.748808 -286.147256) (xy 373.953786 -285.792164) (xy 373.945912 -285.77032) (xy 373.937338 -285.7439)
			(xy 373.928138 -285.689126) (xy 373.927624 -285.661354) (xy 373.928132 -285.635467) (xy 373.936231 -285.584329)
			(xy 373.95223 -285.535089) (xy 373.975736 -285.488957) (xy 374.006168 -285.44707) (xy 374.042778 -285.41046)
			(xy 374.084665 -285.380028) (xy 374.130797 -285.356522) (xy 374.180037 -285.340523) (xy 374.231175 -285.332424)
			(xy 374.282949 -285.332424) (xy 374.334087 -285.340523) (xy 374.383327 -285.356522) (xy 374.429459 -285.380028)
			(xy 374.471346 -285.41046) (xy 374.507956 -285.44707) (xy 374.538388 -285.488957) (xy 374.561894 -285.535089)
			(xy 374.577893 -285.584329) (xy 374.585992 -285.635467) (xy 374.5865 -285.661354) (xy 374.586066 -285.68669)
			(xy 374.578306 -285.736765) (xy 374.562976 -285.785062) (xy 374.540438 -285.830446) (xy 374.511222 -285.871848)
			(xy 374.476016 -285.908293) (xy 374.435649 -285.938922) (xy 374.391071 -285.963016) (xy 374.343331 -285.980006)
			(xy 374.31853 -285.985204) (xy 374.29567 -285.989522) (xy 374.090692 -286.344614) (xy 374.098566 -286.366458)
			(xy 374.107219 -286.392864) (xy 374.116534 -286.447642) (xy 374.117108 -286.475424) (xy 375.337324 -286.475424)
			(xy 375.337848 -286.45008) (xy 375.345616 -286.399991) (xy 375.360959 -286.351681) (xy 375.383515 -286.306288)
			(xy 375.412751 -286.264882) (xy 375.44798 -286.228438) (xy 375.488372 -286.197814) (xy 375.532974 -286.173733)
			(xy 375.580736 -286.156761) (xy 375.605548 -286.151574) (xy 375.628408 -286.147256) (xy 375.833386 -285.792164)
			(xy 375.825512 -285.77032) (xy 375.816938 -285.7439) (xy 375.807738 -285.689126) (xy 375.807224 -285.661354)
			(xy 375.807732 -285.635467) (xy 375.815831 -285.584329) (xy 375.83183 -285.535089) (xy 375.855336 -285.488957)
			(xy 375.885768 -285.44707) (xy 375.922378 -285.41046) (xy 375.964265 -285.380028) (xy 376.010397 -285.356522)
			(xy 376.059637 -285.340523) (xy 376.110775 -285.332424) (xy 376.162549 -285.332424) (xy 376.213687 -285.340523)
			(xy 376.262927 -285.356522) (xy 376.309059 -285.380028) (xy 376.350946 -285.41046) (xy 376.387556 -285.44707)
			(xy 376.417988 -285.488957) (xy 376.441494 -285.535089) (xy 376.457493 -285.584329) (xy 376.465592 -285.635467)
			(xy 376.4661 -285.661354) (xy 376.465666 -285.68669) (xy 376.457906 -285.736765) (xy 376.442576 -285.785062)
			(xy 376.420038 -285.830446) (xy 376.390822 -285.871848) (xy 376.355616 -285.908293) (xy 376.315249 -285.938922)
			(xy 376.270671 -285.963016) (xy 376.222931 -285.980006) (xy 376.19813 -285.985204) (xy 376.17527 -285.989522)
			(xy 375.970292 -286.344614) (xy 375.978166 -286.366458) (xy 375.986819 -286.392864) (xy 375.996134 -286.447642)
			(xy 375.996708 -286.475424) (xy 377.216924 -286.475424) (xy 377.217448 -286.45008) (xy 377.225216 -286.399991)
			(xy 377.240559 -286.351681) (xy 377.263115 -286.306288) (xy 377.292351 -286.264882) (xy 377.32758 -286.228438)
			(xy 377.367972 -286.197814) (xy 377.412574 -286.173733) (xy 377.460336 -286.156761) (xy 377.485148 -286.151574)
			(xy 377.508008 -286.147256) (xy 377.712986 -285.792164) (xy 377.705112 -285.77032) (xy 377.696538 -285.7439)
			(xy 377.687338 -285.689126) (xy 377.686824 -285.661354) (xy 377.687332 -285.635467) (xy 377.695431 -285.584329)
			(xy 377.71143 -285.535089) (xy 377.734936 -285.488957) (xy 377.765368 -285.44707) (xy 377.801978 -285.41046)
			(xy 377.843865 -285.380028) (xy 377.889997 -285.356522) (xy 377.939237 -285.340523) (xy 377.990375 -285.332424)
			(xy 378.042149 -285.332424) (xy 378.093287 -285.340523) (xy 378.142527 -285.356522) (xy 378.188659 -285.380028)
			(xy 378.230546 -285.41046) (xy 378.267156 -285.44707) (xy 378.297588 -285.488957) (xy 378.321094 -285.535089)
			(xy 378.337093 -285.584329) (xy 378.345192 -285.635467) (xy 378.3457 -285.661354) (xy 378.345266 -285.68669)
			(xy 378.337506 -285.736765) (xy 378.322176 -285.785062) (xy 378.299638 -285.830446) (xy 378.270422 -285.871848)
			(xy 378.235216 -285.908293) (xy 378.194849 -285.938922) (xy 378.150271 -285.963016) (xy 378.102531 -285.980006)
			(xy 378.07773 -285.985204) (xy 378.05487 -285.989522) (xy 377.849892 -286.344614) (xy 377.857766 -286.366458)
			(xy 377.866419 -286.392864) (xy 377.875734 -286.447642) (xy 377.876308 -286.475424) (xy 379.096524 -286.475424)
			(xy 379.097048 -286.45008) (xy 379.104816 -286.399991) (xy 379.120159 -286.351681) (xy 379.142715 -286.306288)
			(xy 379.171951 -286.264882) (xy 379.20718 -286.228438) (xy 379.247572 -286.197814) (xy 379.292174 -286.173733)
			(xy 379.339936 -286.156761) (xy 379.364748 -286.151574) (xy 379.387608 -286.147256) (xy 379.592586 -285.792164)
			(xy 379.584712 -285.77032) (xy 379.576138 -285.7439) (xy 379.566938 -285.689126) (xy 379.566424 -285.661354)
			(xy 379.566932 -285.635467) (xy 379.575031 -285.584329) (xy 379.59103 -285.535089) (xy 379.614536 -285.488957)
			(xy 379.644968 -285.44707) (xy 379.681578 -285.41046) (xy 379.723465 -285.380028) (xy 379.769597 -285.356522)
			(xy 379.818837 -285.340523) (xy 379.869975 -285.332424) (xy 379.921749 -285.332424) (xy 379.972887 -285.340523)
			(xy 380.022127 -285.356522) (xy 380.068259 -285.380028) (xy 380.110146 -285.41046) (xy 380.146756 -285.44707)
			(xy 380.177188 -285.488957) (xy 380.200694 -285.535089) (xy 380.216693 -285.584329) (xy 380.224792 -285.635467)
			(xy 380.2253 -285.661354) (xy 380.224866 -285.68669) (xy 380.217106 -285.736765) (xy 380.201776 -285.785062)
			(xy 380.179238 -285.830446) (xy 380.150022 -285.871848) (xy 380.114816 -285.908293) (xy 380.074449 -285.938922)
			(xy 380.029871 -285.963016) (xy 379.982131 -285.980006) (xy 379.95733 -285.985204) (xy 379.93447 -285.989522)
			(xy 379.729492 -286.344614) (xy 379.737366 -286.366458) (xy 379.746019 -286.392864) (xy 379.755334 -286.447642)
			(xy 379.755908 -286.475424) (xy 380.976124 -286.475424) (xy 380.976648 -286.45008) (xy 380.984416 -286.399991)
			(xy 380.999759 -286.351681) (xy 381.022315 -286.306288) (xy 381.051551 -286.264882) (xy 381.08678 -286.228438)
			(xy 381.127172 -286.197814) (xy 381.171774 -286.173733) (xy 381.219536 -286.156761) (xy 381.244348 -286.151574)
			(xy 381.267208 -286.147256) (xy 381.472186 -285.792164) (xy 381.464312 -285.77032) (xy 381.455738 -285.7439)
			(xy 381.446538 -285.689126) (xy 381.446024 -285.661354) (xy 381.446532 -285.635467) (xy 381.454631 -285.584329)
			(xy 381.47063 -285.535089) (xy 381.494136 -285.488957) (xy 381.524568 -285.44707) (xy 381.561178 -285.41046)
			(xy 381.603065 -285.380028) (xy 381.649197 -285.356522) (xy 381.698437 -285.340523) (xy 381.749575 -285.332424)
			(xy 381.801349 -285.332424) (xy 381.852487 -285.340523) (xy 381.901727 -285.356522) (xy 381.947859 -285.380028)
			(xy 381.989746 -285.41046) (xy 382.026356 -285.44707) (xy 382.056788 -285.488957) (xy 382.080294 -285.535089)
			(xy 382.096293 -285.584329) (xy 382.104392 -285.635467) (xy 382.1049 -285.661354) (xy 382.104466 -285.68669)
			(xy 382.096706 -285.736765) (xy 382.081376 -285.785062) (xy 382.058838 -285.830446) (xy 382.029622 -285.871848)
			(xy 381.994416 -285.908293) (xy 381.954049 -285.938922) (xy 381.909471 -285.963016) (xy 381.861731 -285.980006)
			(xy 381.83693 -285.985204) (xy 381.81407 -285.989522) (xy 381.609092 -286.344614) (xy 381.616966 -286.366458)
			(xy 381.625619 -286.392864) (xy 381.634934 -286.447642) (xy 381.635508 -286.475424) (xy 381.635 -286.501331)
			(xy 381.626894 -286.552508) (xy 381.610882 -286.601787) (xy 381.587359 -286.647954) (xy 381.556903 -286.689873)
			(xy 381.520265 -286.726511) (xy 381.478346 -286.756967) (xy 381.432179 -286.78049) (xy 381.3829 -286.796502)
			(xy 381.331723 -286.804608) (xy 381.279909 -286.804608) (xy 381.228732 -286.796502) (xy 381.179453 -286.78049)
			(xy 381.133286 -286.756967) (xy 381.091367 -286.726511) (xy 381.054729 -286.689873) (xy 381.024273 -286.647954)
			(xy 381.00075 -286.601787) (xy 380.984738 -286.552508) (xy 380.976632 -286.501331) (xy 380.976124 -286.475424)
			(xy 379.755908 -286.475424) (xy 379.7554 -286.501331) (xy 379.747294 -286.552508) (xy 379.731282 -286.601787)
			(xy 379.707759 -286.647954) (xy 379.677303 -286.689873) (xy 379.640665 -286.726511) (xy 379.598746 -286.756967)
			(xy 379.552579 -286.78049) (xy 379.5033 -286.796502) (xy 379.452123 -286.804608) (xy 379.400309 -286.804608)
			(xy 379.349132 -286.796502) (xy 379.299853 -286.78049) (xy 379.253686 -286.756967) (xy 379.211767 -286.726511)
			(xy 379.175129 -286.689873) (xy 379.144673 -286.647954) (xy 379.12115 -286.601787) (xy 379.105138 -286.552508)
			(xy 379.097032 -286.501331) (xy 379.096524 -286.475424) (xy 377.876308 -286.475424) (xy 377.8758 -286.501331)
			(xy 377.867694 -286.552508) (xy 377.851682 -286.601787) (xy 377.828159 -286.647954) (xy 377.797703 -286.689873)
			(xy 377.761065 -286.726511) (xy 377.719146 -286.756967) (xy 377.672979 -286.78049) (xy 377.6237 -286.796502)
			(xy 377.572523 -286.804608) (xy 377.520709 -286.804608) (xy 377.469532 -286.796502) (xy 377.420253 -286.78049)
			(xy 377.374086 -286.756967) (xy 377.332167 -286.726511) (xy 377.295529 -286.689873) (xy 377.265073 -286.647954)
			(xy 377.24155 -286.601787) (xy 377.225538 -286.552508) (xy 377.217432 -286.501331) (xy 377.216924 -286.475424)
			(xy 375.996708 -286.475424) (xy 375.9962 -286.501331) (xy 375.988094 -286.552508) (xy 375.972082 -286.601787)
			(xy 375.948559 -286.647954) (xy 375.918103 -286.689873) (xy 375.881465 -286.726511) (xy 375.839546 -286.756967)
			(xy 375.793379 -286.78049) (xy 375.7441 -286.796502) (xy 375.692923 -286.804608) (xy 375.641109 -286.804608)
			(xy 375.589932 -286.796502) (xy 375.540653 -286.78049) (xy 375.494486 -286.756967) (xy 375.452567 -286.726511)
			(xy 375.415929 -286.689873) (xy 375.385473 -286.647954) (xy 375.36195 -286.601787) (xy 375.345938 -286.552508)
			(xy 375.337832 -286.501331) (xy 375.337324 -286.475424) (xy 374.117108 -286.475424) (xy 374.1166 -286.501331)
			(xy 374.108494 -286.552508) (xy 374.092482 -286.601787) (xy 374.068959 -286.647954) (xy 374.038503 -286.689873)
			(xy 374.001865 -286.726511) (xy 373.959946 -286.756967) (xy 373.913779 -286.78049) (xy 373.8645 -286.796502)
			(xy 373.813323 -286.804608) (xy 373.761509 -286.804608) (xy 373.710332 -286.796502) (xy 373.661053 -286.78049)
			(xy 373.614886 -286.756967) (xy 373.572967 -286.726511) (xy 373.536329 -286.689873) (xy 373.505873 -286.647954)
			(xy 373.48235 -286.601787) (xy 373.466338 -286.552508) (xy 373.458232 -286.501331) (xy 373.457724 -286.475424)
			(xy 372.237508 -286.475424) (xy 372.237 -286.501331) (xy 372.228894 -286.552508) (xy 372.212882 -286.601787)
			(xy 372.189359 -286.647954) (xy 372.158903 -286.689873) (xy 372.122265 -286.726511) (xy 372.080346 -286.756967)
			(xy 372.034179 -286.78049) (xy 371.9849 -286.796502) (xy 371.933723 -286.804608) (xy 371.881909 -286.804608)
			(xy 371.830732 -286.796502) (xy 371.781453 -286.78049) (xy 371.735286 -286.756967) (xy 371.693367 -286.726511)
			(xy 371.656729 -286.689873) (xy 371.626273 -286.647954) (xy 371.60275 -286.601787) (xy 371.586738 -286.552508)
			(xy 371.578632 -286.501331) (xy 371.578124 -286.475424) (xy 370.357908 -286.475424) (xy 370.3574 -286.501331)
			(xy 370.349294 -286.552508) (xy 370.333282 -286.601787) (xy 370.309759 -286.647954) (xy 370.279303 -286.689873)
			(xy 370.242665 -286.726511) (xy 370.200746 -286.756967) (xy 370.154579 -286.78049) (xy 370.1053 -286.796502)
			(xy 370.054123 -286.804608) (xy 370.002309 -286.804608) (xy 369.951132 -286.796502) (xy 369.901853 -286.78049)
			(xy 369.855686 -286.756967) (xy 369.813767 -286.726511) (xy 369.777129 -286.689873) (xy 369.746673 -286.647954)
			(xy 369.72315 -286.601787) (xy 369.707138 -286.552508) (xy 369.699032 -286.501331) (xy 369.698524 -286.475424)
			(xy 368.478308 -286.475424) (xy 368.4778 -286.501331) (xy 368.469694 -286.552508) (xy 368.453682 -286.601787)
			(xy 368.430159 -286.647954) (xy 368.399703 -286.689873) (xy 368.363065 -286.726511) (xy 368.321146 -286.756967)
			(xy 368.274979 -286.78049) (xy 368.2257 -286.796502) (xy 368.174523 -286.804608) (xy 368.122709 -286.804608)
			(xy 368.071532 -286.796502) (xy 368.022253 -286.78049) (xy 367.976086 -286.756967) (xy 367.934167 -286.726511)
			(xy 367.897529 -286.689873) (xy 367.867073 -286.647954) (xy 367.84355 -286.601787) (xy 367.827538 -286.552508)
			(xy 367.819432 -286.501331) (xy 367.818924 -286.475424) (xy 351.561908 -286.475424) (xy 351.5614 -286.501331)
			(xy 351.553294 -286.552508) (xy 351.537282 -286.601787) (xy 351.513759 -286.647954) (xy 351.483303 -286.689873)
			(xy 351.446665 -286.726511) (xy 351.404746 -286.756967) (xy 351.358579 -286.78049) (xy 351.3093 -286.796502)
			(xy 351.258123 -286.804608) (xy 351.206309 -286.804608) (xy 351.155132 -286.796502) (xy 351.105853 -286.78049)
			(xy 351.059686 -286.756967) (xy 351.017767 -286.726511) (xy 350.981129 -286.689873) (xy 350.950673 -286.647954)
			(xy 350.92715 -286.601787) (xy 350.911138 -286.552508) (xy 350.903032 -286.501331) (xy 350.902524 -286.475424)
			(xy 350.903123 -286.447707) (xy 350.912443 -286.39306) (xy 350.921066 -286.366712) (xy 350.92894 -286.344614)
			(xy 350.723962 -285.989522) (xy 350.700848 -285.985204) (xy 350.676027 -285.980039) (xy 350.628247 -285.963084)
			(xy 350.583628 -285.939012) (xy 350.543222 -285.908392) (xy 350.507981 -285.871945) (xy 350.478737 -285.830531)
			(xy 350.45618 -285.785127) (xy 350.440843 -285.736804) (xy 350.433086 -285.686703) (xy 350.432624 -285.661354)
			(xy 350.1517 -285.661354) (xy 350.151192 -285.687241) (xy 350.143093 -285.738379) (xy 350.127094 -285.787619)
			(xy 350.103588 -285.833751) (xy 350.073156 -285.875638) (xy 350.036546 -285.912248) (xy 349.994659 -285.94268)
			(xy 349.948527 -285.966186) (xy 349.899287 -285.982185) (xy 349.848149 -285.990284) (xy 349.796375 -285.990284)
			(xy 349.745237 -285.982185) (xy 349.695997 -285.966186) (xy 349.649865 -285.94268) (xy 349.607978 -285.912248)
			(xy 349.571368 -285.875638) (xy 349.540936 -285.833751) (xy 349.51743 -285.787619) (xy 349.501431 -285.738379)
			(xy 349.493332 -285.687241) (xy 349.492824 -285.661354) (xy 349.2119 -285.661354) (xy 349.2119 -285.661862)
			(xy 349.211323 -285.689379) (xy 349.202128 -285.74364) (xy 349.193612 -285.769812) (xy 349.185992 -285.79191)
			(xy 349.391224 -286.147256) (xy 349.414084 -286.151574) (xy 349.438906 -286.156737) (xy 349.486683 -286.173695)
			(xy 349.531301 -286.197768) (xy 349.571706 -286.22839) (xy 349.606946 -286.264837) (xy 349.636189 -286.30625)
			(xy 349.658746 -286.351653) (xy 349.674085 -286.399975) (xy 349.681845 -286.450075) (xy 349.682308 -286.475424)
			(xy 349.6818 -286.501331) (xy 349.673694 -286.552508) (xy 349.657682 -286.601787) (xy 349.634159 -286.647954)
			(xy 349.603703 -286.689873) (xy 349.567065 -286.726511) (xy 349.525146 -286.756967) (xy 349.478979 -286.78049)
			(xy 349.4297 -286.796502) (xy 349.378523 -286.804608) (xy 349.326709 -286.804608) (xy 349.275532 -286.796502)
			(xy 349.226253 -286.78049) (xy 349.180086 -286.756967) (xy 349.138167 -286.726511) (xy 349.101529 -286.689873)
			(xy 349.071073 -286.647954) (xy 349.04755 -286.601787) (xy 349.031538 -286.552508) (xy 349.023432 -286.501331)
			(xy 349.022924 -286.475424) (xy 349.023523 -286.447707) (xy 349.032843 -286.39306) (xy 349.041466 -286.366712)
			(xy 349.04934 -286.344614) (xy 348.844362 -285.989522) (xy 348.821248 -285.985204) (xy 348.796427 -285.980039)
			(xy 348.748647 -285.963084) (xy 348.704028 -285.939012) (xy 348.663622 -285.908392) (xy 348.628381 -285.871945)
			(xy 348.599137 -285.830531) (xy 348.57658 -285.785127) (xy 348.561243 -285.736804) (xy 348.553486 -285.686703)
			(xy 348.553024 -285.661354) (xy 348.2721 -285.661354) (xy 348.271592 -285.687241) (xy 348.263493 -285.738379)
			(xy 348.247494 -285.787619) (xy 348.223988 -285.833751) (xy 348.193556 -285.875638) (xy 348.156946 -285.912248)
			(xy 348.115059 -285.94268) (xy 348.068927 -285.966186) (xy 348.019687 -285.982185) (xy 347.968549 -285.990284)
			(xy 347.916775 -285.990284) (xy 347.865637 -285.982185) (xy 347.816397 -285.966186) (xy 347.770265 -285.94268)
			(xy 347.728378 -285.912248) (xy 347.691768 -285.875638) (xy 347.661336 -285.833751) (xy 347.63783 -285.787619)
			(xy 347.621831 -285.738379) (xy 347.613732 -285.687241) (xy 347.613224 -285.661354) (xy 347.3323 -285.661354)
			(xy 347.3323 -285.661862) (xy 347.331723 -285.689379) (xy 347.322528 -285.74364) (xy 347.314012 -285.769812)
			(xy 347.306392 -285.79191) (xy 347.511624 -286.147256) (xy 347.534484 -286.151574) (xy 347.559306 -286.156737)
			(xy 347.607083 -286.173695) (xy 347.651701 -286.197768) (xy 347.692106 -286.22839) (xy 347.727346 -286.264837)
			(xy 347.756589 -286.30625) (xy 347.779146 -286.351653) (xy 347.794485 -286.399975) (xy 347.802245 -286.450075)
			(xy 347.802708 -286.475424) (xy 347.8022 -286.501331) (xy 347.794094 -286.552508) (xy 347.778082 -286.601787)
			(xy 347.754559 -286.647954) (xy 347.724103 -286.689873) (xy 347.687465 -286.726511) (xy 347.645546 -286.756967)
			(xy 347.599379 -286.78049) (xy 347.5501 -286.796502) (xy 347.498923 -286.804608) (xy 347.447109 -286.804608)
			(xy 347.395932 -286.796502) (xy 347.346653 -286.78049) (xy 347.300486 -286.756967) (xy 347.258567 -286.726511)
			(xy 347.221929 -286.689873) (xy 347.191473 -286.647954) (xy 347.16795 -286.601787) (xy 347.151938 -286.552508)
			(xy 347.143832 -286.501331) (xy 347.143324 -286.475424) (xy 347.143923 -286.447707) (xy 347.153243 -286.39306)
			(xy 347.161866 -286.366712) (xy 347.16974 -286.344614) (xy 346.964762 -285.989522) (xy 346.941648 -285.985204)
			(xy 346.916827 -285.980039) (xy 346.869047 -285.963084) (xy 346.824428 -285.939012) (xy 346.784022 -285.908392)
			(xy 346.748781 -285.871945) (xy 346.719537 -285.830531) (xy 346.69698 -285.785127) (xy 346.681643 -285.736804)
			(xy 346.673886 -285.686703) (xy 346.673424 -285.661354) (xy 346.3925 -285.661354) (xy 346.391992 -285.687241)
			(xy 346.383893 -285.738379) (xy 346.367894 -285.787619) (xy 346.344388 -285.833751) (xy 346.313956 -285.875638)
			(xy 346.277346 -285.912248) (xy 346.235459 -285.94268) (xy 346.189327 -285.966186) (xy 346.140087 -285.982185)
			(xy 346.088949 -285.990284) (xy 346.037175 -285.990284) (xy 345.986037 -285.982185) (xy 345.936797 -285.966186)
			(xy 345.890665 -285.94268) (xy 345.848778 -285.912248) (xy 345.812168 -285.875638) (xy 345.781736 -285.833751)
			(xy 345.75823 -285.787619) (xy 345.742231 -285.738379) (xy 345.734132 -285.687241) (xy 345.733624 -285.661354)
			(xy 345.4527 -285.661354) (xy 345.4527 -285.661862) (xy 345.452123 -285.689379) (xy 345.442928 -285.74364)
			(xy 345.434412 -285.769812) (xy 345.426792 -285.79191) (xy 345.632024 -286.147256) (xy 345.654884 -286.151574)
			(xy 345.679706 -286.156737) (xy 345.727483 -286.173695) (xy 345.772101 -286.197768) (xy 345.812506 -286.22839)
			(xy 345.847746 -286.264837) (xy 345.876989 -286.30625) (xy 345.899546 -286.351653) (xy 345.914885 -286.399975)
			(xy 345.922645 -286.450075) (xy 345.923108 -286.475424) (xy 345.9226 -286.501331) (xy 345.914494 -286.552508)
			(xy 345.898482 -286.601787) (xy 345.874959 -286.647954) (xy 345.844503 -286.689873) (xy 345.807865 -286.726511)
			(xy 345.765946 -286.756967) (xy 345.719779 -286.78049) (xy 345.6705 -286.796502) (xy 345.619323 -286.804608)
			(xy 345.567509 -286.804608) (xy 345.516332 -286.796502) (xy 345.467053 -286.78049) (xy 345.420886 -286.756967)
			(xy 345.378967 -286.726511) (xy 345.342329 -286.689873) (xy 345.311873 -286.647954) (xy 345.28835 -286.601787)
			(xy 345.272338 -286.552508) (xy 345.264232 -286.501331) (xy 345.263724 -286.475424) (xy 345.264323 -286.447707)
			(xy 345.273643 -286.39306) (xy 345.282266 -286.366712) (xy 345.29014 -286.344614) (xy 345.085162 -285.989522)
			(xy 345.062048 -285.985204) (xy 345.037227 -285.980039) (xy 344.989447 -285.963084) (xy 344.944828 -285.939012)
			(xy 344.904422 -285.908392) (xy 344.869181 -285.871945) (xy 344.839937 -285.830531) (xy 344.81738 -285.785127)
			(xy 344.802043 -285.736804) (xy 344.794286 -285.686703) (xy 344.793824 -285.661354) (xy 344.5129 -285.661354)
			(xy 344.512392 -285.687241) (xy 344.504293 -285.738379) (xy 344.488294 -285.787619) (xy 344.464788 -285.833751)
			(xy 344.434356 -285.875638) (xy 344.397746 -285.912248) (xy 344.355859 -285.94268) (xy 344.309727 -285.966186)
			(xy 344.260487 -285.982185) (xy 344.209349 -285.990284) (xy 344.157575 -285.990284) (xy 344.106437 -285.982185)
			(xy 344.057197 -285.966186) (xy 344.011065 -285.94268) (xy 343.969178 -285.912248) (xy 343.932568 -285.875638)
			(xy 343.902136 -285.833751) (xy 343.87863 -285.787619) (xy 343.862631 -285.738379) (xy 343.854532 -285.687241)
			(xy 343.854024 -285.661354) (xy 343.5731 -285.661354) (xy 343.5731 -285.661862) (xy 343.572523 -285.689379)
			(xy 343.563328 -285.74364) (xy 343.554812 -285.769812) (xy 343.547192 -285.79191) (xy 343.752424 -286.147256)
			(xy 343.775284 -286.151574) (xy 343.800106 -286.156737) (xy 343.847883 -286.173695) (xy 343.892501 -286.197768)
			(xy 343.932906 -286.22839) (xy 343.968146 -286.264837) (xy 343.997389 -286.30625) (xy 344.019946 -286.351653)
			(xy 344.035285 -286.399975) (xy 344.043045 -286.450075) (xy 344.043508 -286.475424) (xy 344.043 -286.501331)
			(xy 344.034894 -286.552508) (xy 344.018882 -286.601787) (xy 343.995359 -286.647954) (xy 343.964903 -286.689873)
			(xy 343.928265 -286.726511) (xy 343.886346 -286.756967) (xy 343.840179 -286.78049) (xy 343.7909 -286.796502)
			(xy 343.739723 -286.804608) (xy 343.687909 -286.804608) (xy 343.636732 -286.796502) (xy 343.587453 -286.78049)
			(xy 343.541286 -286.756967) (xy 343.499367 -286.726511) (xy 343.462729 -286.689873) (xy 343.432273 -286.647954)
			(xy 343.40875 -286.601787) (xy 343.392738 -286.552508) (xy 343.384632 -286.501331) (xy 343.384124 -286.475424)
			(xy 343.384723 -286.447707) (xy 343.394043 -286.39306) (xy 343.402666 -286.366712) (xy 343.41054 -286.344614)
			(xy 343.205562 -285.989522) (xy 343.182448 -285.985204) (xy 343.157627 -285.980039) (xy 343.109847 -285.963084)
			(xy 343.065228 -285.939012) (xy 343.024822 -285.908392) (xy 342.989581 -285.871945) (xy 342.960337 -285.830531)
			(xy 342.93778 -285.785127) (xy 342.922443 -285.736804) (xy 342.914686 -285.686703) (xy 342.914224 -285.661354)
			(xy 342.6333 -285.661354) (xy 342.632792 -285.687241) (xy 342.624693 -285.738379) (xy 342.608694 -285.787619)
			(xy 342.585188 -285.833751) (xy 342.554756 -285.875638) (xy 342.518146 -285.912248) (xy 342.476259 -285.94268)
			(xy 342.430127 -285.966186) (xy 342.380887 -285.982185) (xy 342.329749 -285.990284) (xy 342.277975 -285.990284)
			(xy 342.226837 -285.982185) (xy 342.177597 -285.966186) (xy 342.131465 -285.94268) (xy 342.089578 -285.912248)
			(xy 342.052968 -285.875638) (xy 342.022536 -285.833751) (xy 341.99903 -285.787619) (xy 341.983031 -285.738379)
			(xy 341.974932 -285.687241) (xy 341.974424 -285.661354) (xy 341.6935 -285.661354) (xy 341.6935 -285.661862)
			(xy 341.692923 -285.689379) (xy 341.683728 -285.74364) (xy 341.675212 -285.769812) (xy 341.667592 -285.79191)
			(xy 341.872824 -286.147256) (xy 341.895684 -286.151574) (xy 341.920506 -286.156737) (xy 341.968283 -286.173695)
			(xy 342.012901 -286.197768) (xy 342.053306 -286.22839) (xy 342.088546 -286.264837) (xy 342.117789 -286.30625)
			(xy 342.140346 -286.351653) (xy 342.155685 -286.399975) (xy 342.163445 -286.450075) (xy 342.163908 -286.475424)
			(xy 342.1634 -286.501331) (xy 342.155294 -286.552508) (xy 342.139282 -286.601787) (xy 342.115759 -286.647954)
			(xy 342.085303 -286.689873) (xy 342.048665 -286.726511) (xy 342.006746 -286.756967) (xy 341.960579 -286.78049)
			(xy 341.9113 -286.796502) (xy 341.860123 -286.804608) (xy 341.808309 -286.804608) (xy 341.757132 -286.796502)
			(xy 341.707853 -286.78049) (xy 341.661686 -286.756967) (xy 341.619767 -286.726511) (xy 341.583129 -286.689873)
			(xy 341.552673 -286.647954) (xy 341.52915 -286.601787) (xy 341.513138 -286.552508) (xy 341.505032 -286.501331)
			(xy 341.504524 -286.475424) (xy 341.505123 -286.447707) (xy 341.514443 -286.39306) (xy 341.523066 -286.366712)
			(xy 341.53094 -286.344614) (xy 341.325962 -285.989522) (xy 341.302848 -285.985204) (xy 341.278027 -285.980039)
			(xy 341.230247 -285.963084) (xy 341.185628 -285.939012) (xy 341.145222 -285.908392) (xy 341.109981 -285.871945)
			(xy 341.080737 -285.830531) (xy 341.05818 -285.785127) (xy 341.042843 -285.736804) (xy 341.035086 -285.686703)
			(xy 341.034624 -285.661354) (xy 340.7537 -285.661354) (xy 340.753192 -285.687241) (xy 340.745093 -285.738379)
			(xy 340.729094 -285.787619) (xy 340.705588 -285.833751) (xy 340.675156 -285.875638) (xy 340.638546 -285.912248)
			(xy 340.596659 -285.94268) (xy 340.550527 -285.966186) (xy 340.501287 -285.982185) (xy 340.450149 -285.990284)
			(xy 340.398375 -285.990284) (xy 340.347237 -285.982185) (xy 340.297997 -285.966186) (xy 340.251865 -285.94268)
			(xy 340.209978 -285.912248) (xy 340.173368 -285.875638) (xy 340.142936 -285.833751) (xy 340.11943 -285.787619)
			(xy 340.103431 -285.738379) (xy 340.095332 -285.687241) (xy 340.094824 -285.661354) (xy 339.814408 -285.661354)
			(xy 339.813802 -285.689071) (xy 339.804487 -285.743717) (xy 339.795866 -285.770066) (xy 339.787992 -285.792164)
			(xy 339.993224 -286.147256) (xy 340.016084 -286.151574) (xy 340.040906 -286.156737) (xy 340.088683 -286.173695)
			(xy 340.133301 -286.197768) (xy 340.173706 -286.22839) (xy 340.208946 -286.264837) (xy 340.238189 -286.30625)
			(xy 340.260746 -286.351653) (xy 340.276085 -286.399975) (xy 340.283845 -286.450075) (xy 340.284308 -286.475424)
			(xy 340.2838 -286.501331) (xy 340.275694 -286.552508) (xy 340.259682 -286.601787) (xy 340.236159 -286.647954)
			(xy 340.205703 -286.689873) (xy 340.169065 -286.726511) (xy 340.127146 -286.756967) (xy 340.080979 -286.78049)
			(xy 340.0317 -286.796502) (xy 339.980523 -286.804608) (xy 339.928709 -286.804608) (xy 339.877532 -286.796502)
			(xy 339.828253 -286.78049) (xy 339.782086 -286.756967) (xy 339.740167 -286.726511) (xy 339.703529 -286.689873)
			(xy 339.673073 -286.647954) (xy 339.64955 -286.601787) (xy 339.633538 -286.552508) (xy 339.625432 -286.501331)
			(xy 339.624924 -286.475424) (xy 339.625523 -286.447707) (xy 339.634843 -286.39306) (xy 339.643466 -286.366712)
			(xy 339.65134 -286.344614) (xy 339.446108 -285.989522) (xy 339.423248 -285.985204) (xy 339.398427 -285.980039)
			(xy 339.350647 -285.963084) (xy 339.306028 -285.939012) (xy 339.265622 -285.908392) (xy 339.230381 -285.871945)
			(xy 339.201137 -285.830531) (xy 339.17858 -285.785127) (xy 339.163243 -285.736804) (xy 339.155486 -285.686703)
			(xy 339.155024 -285.661354) (xy 338.874608 -285.661354) (xy 338.8741 -285.687261) (xy 338.865994 -285.738438)
			(xy 338.849982 -285.787717) (xy 338.826459 -285.833884) (xy 338.796003 -285.875803) (xy 338.759365 -285.912441)
			(xy 338.717446 -285.942897) (xy 338.671279 -285.96642) (xy 338.622 -285.982432) (xy 338.570823 -285.990538)
			(xy 338.519009 -285.990538) (xy 338.467832 -285.982432) (xy 338.418553 -285.96642) (xy 338.372386 -285.942897)
			(xy 338.330467 -285.912441) (xy 338.293829 -285.875803) (xy 338.263373 -285.833884) (xy 338.23985 -285.787717)
			(xy 338.223838 -285.738438) (xy 338.215732 -285.687261) (xy 338.215224 -285.661354) (xy 337.9343 -285.661354)
			(xy 337.933759 -285.689062) (xy 337.924571 -285.743708) (xy 337.916012 -285.770066) (xy 337.908138 -285.792164)
			(xy 338.11337 -286.147256) (xy 338.13623 -286.151574) (xy 338.16104 -286.156732) (xy 338.20878 -286.173726)
			(xy 338.253357 -286.197824) (xy 338.293722 -286.228459) (xy 338.328925 -286.264909) (xy 338.358136 -286.306317)
			(xy 338.380667 -286.351707) (xy 338.395988 -286.400009) (xy 338.403738 -286.450087) (xy 338.4042 -286.475424)
			(xy 338.403692 -286.501311) (xy 338.395593 -286.552449) (xy 338.379594 -286.601689) (xy 338.356088 -286.647821)
			(xy 338.325656 -286.689708) (xy 338.289046 -286.726318) (xy 338.247159 -286.75675) (xy 338.201027 -286.780256)
			(xy 338.151787 -286.796255) (xy 338.100649 -286.804354) (xy 338.048875 -286.804354) (xy 337.997737 -286.796255)
			(xy 337.948497 -286.780256) (xy 337.902365 -286.75675) (xy 337.860478 -286.726318) (xy 337.823868 -286.689708)
			(xy 337.793436 -286.647821) (xy 337.76993 -286.601689) (xy 337.753931 -286.552449) (xy 337.745832 -286.501311)
			(xy 337.745324 -286.475424) (xy 337.745858 -286.447716) (xy 337.75505 -286.393069) (xy 337.763612 -286.366712)
			(xy 337.771486 -286.344614) (xy 337.566254 -285.989522) (xy 337.543394 -285.985204) (xy 337.518583 -285.980049)
			(xy 337.470842 -285.963057) (xy 337.426263 -285.93896) (xy 337.385896 -285.908325) (xy 337.350693 -285.871874)
			(xy 337.321482 -285.830466) (xy 337.298951 -285.785075) (xy 337.283632 -285.736771) (xy 337.275885 -285.686692)
			(xy 337.275424 -285.661354) (xy 336.0547 -285.661354) (xy 336.054192 -285.687241) (xy 336.046093 -285.738379)
			(xy 336.030094 -285.787619) (xy 336.006588 -285.833751) (xy 335.976156 -285.875638) (xy 335.939546 -285.912248)
			(xy 335.897659 -285.94268) (xy 335.851527 -285.966186) (xy 335.802287 -285.982185) (xy 335.751149 -285.990284)
			(xy 335.699375 -285.990284) (xy 335.648237 -285.982185) (xy 335.598997 -285.966186) (xy 335.552865 -285.94268)
			(xy 335.510978 -285.912248) (xy 335.474368 -285.875638) (xy 335.443936 -285.833751) (xy 335.42043 -285.787619)
			(xy 335.404431 -285.738379) (xy 335.396332 -285.687241) (xy 335.395824 -285.661354) (xy 134.164832 -285.661354)
			(xy 134.164372 -285.686689) (xy 134.156613 -285.736761) (xy 134.141285 -285.785057) (xy 134.118749 -285.830439)
			(xy 134.089536 -285.87184) (xy 134.054334 -285.908285) (xy 134.013971 -285.938915) (xy 133.969397 -285.963011)
			(xy 133.921662 -285.980004) (xy 133.896862 -285.985204) (xy 133.874002 -285.989522) (xy 133.669024 -286.344614)
			(xy 133.676898 -286.366458) (xy 133.685549 -286.392865) (xy 133.694866 -286.447642) (xy 133.69544 -286.475424)
			(xy 333.986124 -286.475424) (xy 333.986632 -286.449537) (xy 333.994731 -286.398399) (xy 334.01073 -286.349159)
			(xy 334.034236 -286.303027) (xy 334.064668 -286.26114) (xy 334.101278 -286.22453) (xy 334.143165 -286.194098)
			(xy 334.189297 -286.170592) (xy 334.238537 -286.154593) (xy 334.289675 -286.146494) (xy 334.341449 -286.146494)
			(xy 334.392587 -286.154593) (xy 334.441827 -286.170592) (xy 334.487959 -286.194098) (xy 334.529846 -286.22453)
			(xy 334.566456 -286.26114) (xy 334.596888 -286.303027) (xy 334.620394 -286.349159) (xy 334.636393 -286.398399)
			(xy 334.644492 -286.449537) (xy 334.645 -286.475424) (xy 334.644511 -286.501304) (xy 334.92624 -286.501304)
			(xy 334.92624 -286.449496) (xy 334.934344 -286.398327) (xy 334.950352 -286.349055) (xy 334.97387 -286.302894)
			(xy 335.00432 -286.26098) (xy 335.040951 -286.224345) (xy 335.082862 -286.19389) (xy 335.12902 -286.170367)
			(xy 335.17829 -286.154353) (xy 335.229459 -286.146243) (xy 335.255362 -286.145732) (xy 335.280855 -286.146231)
			(xy 335.331232 -286.154087) (xy 335.379796 -286.169618) (xy 335.425383 -286.192452) (xy 335.466904 -286.222042)
			(xy 335.503366 -286.257681) (xy 335.519014 -286.277812) (xy 335.93151 -286.277812) (xy 335.947185 -286.257701)
			(xy 335.98364 -286.222058) (xy 336.025155 -286.192461) (xy 336.070737 -286.16962) (xy 336.119296 -286.15408)
			(xy 336.16967 -286.146213) (xy 336.195162 -286.145732) (xy 336.221075 -286.146163) (xy 336.272264 -286.154265)
			(xy 336.321556 -286.170276) (xy 336.367735 -286.193801) (xy 336.409666 -286.22426) (xy 336.446315 -286.260905)
			(xy 336.47678 -286.302832) (xy 336.50031 -286.349009) (xy 336.516326 -286.398299) (xy 336.524434 -286.449487)
			(xy 336.524434 -286.501313) (xy 336.516326 -286.552501) (xy 336.50031 -286.601791) (xy 336.47678 -286.647968)
			(xy 336.446315 -286.689895) (xy 336.409666 -286.72654) (xy 336.367735 -286.756999) (xy 336.321556 -286.780524)
			(xy 336.272264 -286.796535) (xy 336.221075 -286.804637) (xy 336.195162 -286.805116) (xy 336.169668 -286.804653)
			(xy 336.11929 -286.796786) (xy 336.070727 -286.781247) (xy 336.02514 -286.758407) (xy 335.98362 -286.728811)
			(xy 335.947158 -286.693169) (xy 335.93151 -286.673036) (xy 335.519014 -286.673036) (xy 335.503397 -286.693193)
			(xy 335.466928 -286.728832) (xy 335.425401 -286.758421) (xy 335.379808 -286.781254) (xy 335.33124 -286.796785)
			(xy 335.280857 -286.804641) (xy 335.255362 -286.805116) (xy 335.229459 -286.804557) (xy 335.17829 -286.796447)
			(xy 335.12902 -286.780433) (xy 335.082862 -286.75691) (xy 335.040951 -286.726455) (xy 335.00432 -286.68982)
			(xy 334.97387 -286.647906) (xy 334.950352 -286.601745) (xy 334.934344 -286.552473) (xy 334.92624 -286.501304)
			(xy 334.644511 -286.501304) (xy 334.644476 -286.503132) (xy 334.635277 -286.557779) (xy 334.626712 -286.584136)
			(xy 334.619092 -286.60598) (xy 334.82407 -286.961072) (xy 334.84693 -286.96539) (xy 334.871744 -286.970533)
			(xy 334.919484 -286.987528) (xy 334.964063 -287.011628) (xy 335.004428 -287.042264) (xy 335.039631 -287.078717)
			(xy 335.068841 -287.120126) (xy 335.091372 -287.165518) (xy 335.106691 -287.213822) (xy 335.114439 -287.263902)
			(xy 335.1149 -287.28924) (xy 335.114392 -287.315127) (xy 335.106293 -287.366265) (xy 335.090294 -287.415505)
			(xy 335.066788 -287.461637) (xy 335.036356 -287.503524) (xy 334.999746 -287.540134) (xy 334.957859 -287.570566)
			(xy 334.911727 -287.594072) (xy 334.862487 -287.610071) (xy 334.811349 -287.61817) (xy 334.759575 -287.61817)
			(xy 334.708437 -287.610071) (xy 334.659197 -287.594072) (xy 334.613065 -287.570566) (xy 334.571178 -287.540134)
			(xy 334.534568 -287.503524) (xy 334.504136 -287.461637) (xy 334.48063 -287.415505) (xy 334.464631 -287.366265)
			(xy 334.456532 -287.315127) (xy 334.456024 -287.28924) (xy 334.456562 -287.261532) (xy 334.465751 -287.206885)
			(xy 334.474312 -287.180528) (xy 334.481932 -287.158684) (xy 334.276954 -286.803592) (xy 334.254094 -286.799274)
			(xy 334.229299 -286.794053) (xy 334.181562 -286.777067) (xy 334.136987 -286.752976) (xy 334.096622 -286.722349)
			(xy 334.061419 -286.685906) (xy 334.032206 -286.644507) (xy 334.009672 -286.599125) (xy 333.994346 -286.55083)
			(xy 333.98659 -286.500758) (xy 333.986124 -286.475424) (xy 133.69544 -286.475424) (xy 133.694932 -286.501331)
			(xy 133.686826 -286.552508) (xy 133.670814 -286.601787) (xy 133.647291 -286.647954) (xy 133.616835 -286.689873)
			(xy 133.580197 -286.726511) (xy 133.538278 -286.756967) (xy 133.492111 -286.78049) (xy 133.442832 -286.796502)
			(xy 133.391655 -286.804608) (xy 133.339841 -286.804608) (xy 133.288664 -286.796502) (xy 133.239385 -286.78049)
			(xy 133.193218 -286.756967) (xy 133.151299 -286.726511) (xy 133.114661 -286.689873) (xy 133.084205 -286.647954)
			(xy 133.060682 -286.601787) (xy 133.04467 -286.552508) (xy 133.036564 -286.501331) (xy 133.036056 -286.475424)
			(xy 131.81584 -286.475424) (xy 131.815332 -286.501331) (xy 131.807226 -286.552508) (xy 131.791214 -286.601787)
			(xy 131.767691 -286.647954) (xy 131.737235 -286.689873) (xy 131.700597 -286.726511) (xy 131.658678 -286.756967)
			(xy 131.612511 -286.78049) (xy 131.563232 -286.796502) (xy 131.512055 -286.804608) (xy 131.460241 -286.804608)
			(xy 131.409064 -286.796502) (xy 131.359785 -286.78049) (xy 131.313618 -286.756967) (xy 131.271699 -286.726511)
			(xy 131.235061 -286.689873) (xy 131.204605 -286.647954) (xy 131.181082 -286.601787) (xy 131.16507 -286.552508)
			(xy 131.156964 -286.501331) (xy 131.156456 -286.475424) (xy 129.93624 -286.475424) (xy 129.935732 -286.501331)
			(xy 129.927626 -286.552508) (xy 129.911614 -286.601787) (xy 129.888091 -286.647954) (xy 129.857635 -286.689873)
			(xy 129.820997 -286.726511) (xy 129.779078 -286.756967) (xy 129.732911 -286.78049) (xy 129.683632 -286.796502)
			(xy 129.632455 -286.804608) (xy 129.580641 -286.804608) (xy 129.529464 -286.796502) (xy 129.480185 -286.78049)
			(xy 129.434018 -286.756967) (xy 129.392099 -286.726511) (xy 129.355461 -286.689873) (xy 129.325005 -286.647954)
			(xy 129.301482 -286.601787) (xy 129.28547 -286.552508) (xy 129.277364 -286.501331) (xy 129.276856 -286.475424)
			(xy 128.05664 -286.475424) (xy 128.056132 -286.501331) (xy 128.048026 -286.552508) (xy 128.032014 -286.601787)
			(xy 128.008491 -286.647954) (xy 127.978035 -286.689873) (xy 127.941397 -286.726511) (xy 127.899478 -286.756967)
			(xy 127.853311 -286.78049) (xy 127.804032 -286.796502) (xy 127.752855 -286.804608) (xy 127.701041 -286.804608)
			(xy 127.649864 -286.796502) (xy 127.600585 -286.78049) (xy 127.554418 -286.756967) (xy 127.512499 -286.726511)
			(xy 127.475861 -286.689873) (xy 127.445405 -286.647954) (xy 127.421882 -286.601787) (xy 127.40587 -286.552508)
			(xy 127.397764 -286.501331) (xy 127.397256 -286.475424) (xy 126.17704 -286.475424) (xy 126.176532 -286.501331)
			(xy 126.168426 -286.552508) (xy 126.152414 -286.601787) (xy 126.128891 -286.647954) (xy 126.098435 -286.689873)
			(xy 126.061797 -286.726511) (xy 126.019878 -286.756967) (xy 125.973711 -286.78049) (xy 125.924432 -286.796502)
			(xy 125.873255 -286.804608) (xy 125.821441 -286.804608) (xy 125.770264 -286.796502) (xy 125.720985 -286.78049)
			(xy 125.674818 -286.756967) (xy 125.632899 -286.726511) (xy 125.596261 -286.689873) (xy 125.565805 -286.647954)
			(xy 125.542282 -286.601787) (xy 125.52627 -286.552508) (xy 125.518164 -286.501331) (xy 125.517656 -286.475424)
			(xy 124.29744 -286.475424) (xy 124.296932 -286.501331) (xy 124.288826 -286.552508) (xy 124.272814 -286.601787)
			(xy 124.249291 -286.647954) (xy 124.218835 -286.689873) (xy 124.182197 -286.726511) (xy 124.140278 -286.756967)
			(xy 124.094111 -286.78049) (xy 124.044832 -286.796502) (xy 123.993655 -286.804608) (xy 123.941841 -286.804608)
			(xy 123.890664 -286.796502) (xy 123.841385 -286.78049) (xy 123.795218 -286.756967) (xy 123.753299 -286.726511)
			(xy 123.716661 -286.689873) (xy 123.686205 -286.647954) (xy 123.662682 -286.601787) (xy 123.64667 -286.552508)
			(xy 123.638564 -286.501331) (xy 123.638056 -286.475424) (xy 122.41784 -286.475424) (xy 122.417332 -286.501331)
			(xy 122.409226 -286.552508) (xy 122.393214 -286.601787) (xy 122.369691 -286.647954) (xy 122.339235 -286.689873)
			(xy 122.302597 -286.726511) (xy 122.260678 -286.756967) (xy 122.214511 -286.78049) (xy 122.165232 -286.796502)
			(xy 122.114055 -286.804608) (xy 122.062241 -286.804608) (xy 122.011064 -286.796502) (xy 121.961785 -286.78049)
			(xy 121.915618 -286.756967) (xy 121.873699 -286.726511) (xy 121.837061 -286.689873) (xy 121.806605 -286.647954)
			(xy 121.783082 -286.601787) (xy 121.76707 -286.552508) (xy 121.758964 -286.501331) (xy 121.758456 -286.475424)
			(xy 120.53824 -286.475424) (xy 120.537732 -286.501331) (xy 120.529626 -286.552508) (xy 120.513614 -286.601787)
			(xy 120.490091 -286.647954) (xy 120.459635 -286.689873) (xy 120.422997 -286.726511) (xy 120.381078 -286.756967)
			(xy 120.334911 -286.78049) (xy 120.285632 -286.796502) (xy 120.234455 -286.804608) (xy 120.182641 -286.804608)
			(xy 120.131464 -286.796502) (xy 120.082185 -286.78049) (xy 120.036018 -286.756967) (xy 119.994099 -286.726511)
			(xy 119.957461 -286.689873) (xy 119.927005 -286.647954) (xy 119.903482 -286.601787) (xy 119.88747 -286.552508)
			(xy 119.879364 -286.501331) (xy 119.878856 -286.475424) (xy 103.62184 -286.475424) (xy 103.621332 -286.501331)
			(xy 103.613226 -286.552508) (xy 103.597214 -286.601787) (xy 103.573691 -286.647954) (xy 103.543235 -286.689873)
			(xy 103.506597 -286.726511) (xy 103.464678 -286.756967) (xy 103.418511 -286.78049) (xy 103.369232 -286.796502)
			(xy 103.318055 -286.804608) (xy 103.266241 -286.804608) (xy 103.215064 -286.796502) (xy 103.165785 -286.78049)
			(xy 103.119618 -286.756967) (xy 103.077699 -286.726511) (xy 103.041061 -286.689873) (xy 103.010605 -286.647954)
			(xy 102.987082 -286.601787) (xy 102.97107 -286.552508) (xy 102.962964 -286.501331) (xy 102.962456 -286.475424)
			(xy 102.963053 -286.447707) (xy 102.972374 -286.39306) (xy 102.980998 -286.366712) (xy 102.988872 -286.344614)
			(xy 102.783894 -285.989522) (xy 102.76078 -285.985204) (xy 102.735964 -285.980016) (xy 102.688184 -285.963065)
			(xy 102.643565 -285.938998) (xy 102.603157 -285.908381) (xy 102.567916 -285.871936) (xy 102.538671 -285.830525)
			(xy 102.516113 -285.785123) (xy 102.500775 -285.736802) (xy 102.493018 -285.686702) (xy 102.492556 -285.661354)
			(xy 102.211632 -285.661354) (xy 102.211124 -285.687241) (xy 102.203025 -285.738379) (xy 102.187026 -285.787619)
			(xy 102.16352 -285.833751) (xy 102.133088 -285.875638) (xy 102.096478 -285.912248) (xy 102.054591 -285.94268)
			(xy 102.008459 -285.966186) (xy 101.959219 -285.982185) (xy 101.908081 -285.990284) (xy 101.856307 -285.990284)
			(xy 101.805169 -285.982185) (xy 101.755929 -285.966186) (xy 101.709797 -285.94268) (xy 101.66791 -285.912248)
			(xy 101.6313 -285.875638) (xy 101.600868 -285.833751) (xy 101.577362 -285.787619) (xy 101.561363 -285.738379)
			(xy 101.553264 -285.687241) (xy 101.552756 -285.661354) (xy 101.271832 -285.661354) (xy 101.271832 -285.661862)
			(xy 101.271253 -285.689379) (xy 101.262059 -285.74364) (xy 101.253544 -285.769812) (xy 101.245924 -285.79191)
			(xy 101.451156 -286.147256) (xy 101.474016 -286.151574) (xy 101.498827 -286.156786) (xy 101.546604 -286.173734)
			(xy 101.591223 -286.197799) (xy 101.63163 -286.228413) (xy 101.666872 -286.264855) (xy 101.696117 -286.306263)
			(xy 101.718676 -286.351662) (xy 101.734017 -286.399979) (xy 101.741777 -286.450077) (xy 101.74224 -286.475424)
			(xy 101.741732 -286.501331) (xy 101.733626 -286.552508) (xy 101.717614 -286.601787) (xy 101.694091 -286.647954)
			(xy 101.663635 -286.689873) (xy 101.626997 -286.726511) (xy 101.585078 -286.756967) (xy 101.538911 -286.78049)
			(xy 101.489632 -286.796502) (xy 101.438455 -286.804608) (xy 101.386641 -286.804608) (xy 101.335464 -286.796502)
			(xy 101.286185 -286.78049) (xy 101.240018 -286.756967) (xy 101.198099 -286.726511) (xy 101.161461 -286.689873)
			(xy 101.131005 -286.647954) (xy 101.107482 -286.601787) (xy 101.09147 -286.552508) (xy 101.083364 -286.501331)
			(xy 101.082856 -286.475424) (xy 101.083453 -286.447707) (xy 101.092774 -286.39306) (xy 101.101398 -286.366712)
			(xy 101.109272 -286.344614) (xy 100.904294 -285.989522) (xy 100.88118 -285.985204) (xy 100.856364 -285.980016)
			(xy 100.808584 -285.963065) (xy 100.763965 -285.938998) (xy 100.723557 -285.908381) (xy 100.688316 -285.871936)
			(xy 100.659071 -285.830525) (xy 100.636513 -285.785123) (xy 100.621175 -285.736802) (xy 100.613418 -285.686702)
			(xy 100.612956 -285.661354) (xy 100.332032 -285.661354) (xy 100.331524 -285.687241) (xy 100.323425 -285.738379)
			(xy 100.307426 -285.787619) (xy 100.28392 -285.833751) (xy 100.253488 -285.875638) (xy 100.216878 -285.912248)
			(xy 100.174991 -285.94268) (xy 100.128859 -285.966186) (xy 100.079619 -285.982185) (xy 100.028481 -285.990284)
			(xy 99.976707 -285.990284) (xy 99.925569 -285.982185) (xy 99.876329 -285.966186) (xy 99.830197 -285.94268)
			(xy 99.78831 -285.912248) (xy 99.7517 -285.875638) (xy 99.721268 -285.833751) (xy 99.697762 -285.787619)
			(xy 99.681763 -285.738379) (xy 99.673664 -285.687241) (xy 99.673156 -285.661354) (xy 99.392232 -285.661354)
			(xy 99.392232 -285.661862) (xy 99.391653 -285.689379) (xy 99.382459 -285.74364) (xy 99.373944 -285.769812)
			(xy 99.366324 -285.79191) (xy 99.571556 -286.147256) (xy 99.594416 -286.151574) (xy 99.619227 -286.156786)
			(xy 99.667004 -286.173734) (xy 99.711623 -286.197799) (xy 99.75203 -286.228413) (xy 99.787272 -286.264855)
			(xy 99.816517 -286.306263) (xy 99.839076 -286.351662) (xy 99.854417 -286.399979) (xy 99.862177 -286.450077)
			(xy 99.86264 -286.475424) (xy 99.862132 -286.501331) (xy 99.854026 -286.552508) (xy 99.838014 -286.601787)
			(xy 99.814491 -286.647954) (xy 99.784035 -286.689873) (xy 99.747397 -286.726511) (xy 99.705478 -286.756967)
			(xy 99.659311 -286.78049) (xy 99.610032 -286.796502) (xy 99.558855 -286.804608) (xy 99.507041 -286.804608)
			(xy 99.455864 -286.796502) (xy 99.406585 -286.78049) (xy 99.360418 -286.756967) (xy 99.318499 -286.726511)
			(xy 99.281861 -286.689873) (xy 99.251405 -286.647954) (xy 99.227882 -286.601787) (xy 99.21187 -286.552508)
			(xy 99.203764 -286.501331) (xy 99.203256 -286.475424) (xy 99.203853 -286.447707) (xy 99.213174 -286.39306)
			(xy 99.221798 -286.366712) (xy 99.229672 -286.344614) (xy 99.024694 -285.989522) (xy 99.00158 -285.985204)
			(xy 98.976764 -285.980016) (xy 98.928984 -285.963065) (xy 98.884365 -285.938998) (xy 98.843957 -285.908381)
			(xy 98.808716 -285.871936) (xy 98.779471 -285.830525) (xy 98.756913 -285.785123) (xy 98.741575 -285.736802)
			(xy 98.733818 -285.686702) (xy 98.733356 -285.661354) (xy 98.452432 -285.661354) (xy 98.451924 -285.687241)
			(xy 98.443825 -285.738379) (xy 98.427826 -285.787619) (xy 98.40432 -285.833751) (xy 98.373888 -285.875638)
			(xy 98.337278 -285.912248) (xy 98.295391 -285.94268) (xy 98.249259 -285.966186) (xy 98.200019 -285.982185)
			(xy 98.148881 -285.990284) (xy 98.097107 -285.990284) (xy 98.045969 -285.982185) (xy 97.996729 -285.966186)
			(xy 97.950597 -285.94268) (xy 97.90871 -285.912248) (xy 97.8721 -285.875638) (xy 97.841668 -285.833751)
			(xy 97.818162 -285.787619) (xy 97.802163 -285.738379) (xy 97.794064 -285.687241) (xy 97.793556 -285.661354)
			(xy 97.512632 -285.661354) (xy 97.512632 -285.661862) (xy 97.512053 -285.689379) (xy 97.502859 -285.74364)
			(xy 97.494344 -285.769812) (xy 97.486724 -285.79191) (xy 97.691956 -286.147256) (xy 97.714816 -286.151574)
			(xy 97.739627 -286.156786) (xy 97.787404 -286.173734) (xy 97.832023 -286.197799) (xy 97.87243 -286.228413)
			(xy 97.907672 -286.264855) (xy 97.936917 -286.306263) (xy 97.959476 -286.351662) (xy 97.974817 -286.399979)
			(xy 97.982577 -286.450077) (xy 97.98304 -286.475424) (xy 97.982532 -286.501331) (xy 97.974426 -286.552508)
			(xy 97.958414 -286.601787) (xy 97.934891 -286.647954) (xy 97.904435 -286.689873) (xy 97.867797 -286.726511)
			(xy 97.825878 -286.756967) (xy 97.779711 -286.78049) (xy 97.730432 -286.796502) (xy 97.679255 -286.804608)
			(xy 97.627441 -286.804608) (xy 97.576264 -286.796502) (xy 97.526985 -286.78049) (xy 97.480818 -286.756967)
			(xy 97.438899 -286.726511) (xy 97.402261 -286.689873) (xy 97.371805 -286.647954) (xy 97.348282 -286.601787)
			(xy 97.33227 -286.552508) (xy 97.324164 -286.501331) (xy 97.323656 -286.475424) (xy 97.324253 -286.447707)
			(xy 97.333574 -286.39306) (xy 97.342198 -286.366712) (xy 97.350072 -286.344614) (xy 97.145094 -285.989522)
			(xy 97.12198 -285.985204) (xy 97.097164 -285.980016) (xy 97.049384 -285.963065) (xy 97.004765 -285.938998)
			(xy 96.964357 -285.908381) (xy 96.929116 -285.871936) (xy 96.899871 -285.830525) (xy 96.877313 -285.785123)
			(xy 96.861975 -285.736802) (xy 96.854218 -285.686702) (xy 96.853756 -285.661354) (xy 96.572832 -285.661354)
			(xy 96.572324 -285.687241) (xy 96.564225 -285.738379) (xy 96.548226 -285.787619) (xy 96.52472 -285.833751)
			(xy 96.494288 -285.875638) (xy 96.457678 -285.912248) (xy 96.415791 -285.94268) (xy 96.369659 -285.966186)
			(xy 96.320419 -285.982185) (xy 96.269281 -285.990284) (xy 96.217507 -285.990284) (xy 96.166369 -285.982185)
			(xy 96.117129 -285.966186) (xy 96.070997 -285.94268) (xy 96.02911 -285.912248) (xy 95.9925 -285.875638)
			(xy 95.962068 -285.833751) (xy 95.938562 -285.787619) (xy 95.922563 -285.738379) (xy 95.914464 -285.687241)
			(xy 95.913956 -285.661354) (xy 95.633032 -285.661354) (xy 95.633032 -285.661862) (xy 95.632453 -285.689379)
			(xy 95.623259 -285.74364) (xy 95.614744 -285.769812) (xy 95.607124 -285.79191) (xy 95.812356 -286.147256)
			(xy 95.835216 -286.151574) (xy 95.860027 -286.156786) (xy 95.907804 -286.173734) (xy 95.952423 -286.197799)
			(xy 95.99283 -286.228413) (xy 96.028072 -286.264855) (xy 96.057317 -286.306263) (xy 96.079876 -286.351662)
			(xy 96.095217 -286.399979) (xy 96.102977 -286.450077) (xy 96.10344 -286.475424) (xy 96.102932 -286.501331)
			(xy 96.094826 -286.552508) (xy 96.078814 -286.601787) (xy 96.055291 -286.647954) (xy 96.024835 -286.689873)
			(xy 95.988197 -286.726511) (xy 95.946278 -286.756967) (xy 95.900111 -286.78049) (xy 95.850832 -286.796502)
			(xy 95.799655 -286.804608) (xy 95.747841 -286.804608) (xy 95.696664 -286.796502) (xy 95.647385 -286.78049)
			(xy 95.601218 -286.756967) (xy 95.559299 -286.726511) (xy 95.522661 -286.689873) (xy 95.492205 -286.647954)
			(xy 95.468682 -286.601787) (xy 95.45267 -286.552508) (xy 95.444564 -286.501331) (xy 95.444056 -286.475424)
			(xy 95.444653 -286.447707) (xy 95.453974 -286.39306) (xy 95.462598 -286.366712) (xy 95.470472 -286.344614)
			(xy 95.265494 -285.989522) (xy 95.24238 -285.985204) (xy 95.217564 -285.980016) (xy 95.169784 -285.963065)
			(xy 95.125165 -285.938998) (xy 95.084757 -285.908381) (xy 95.049516 -285.871936) (xy 95.020271 -285.830525)
			(xy 94.997713 -285.785123) (xy 94.982375 -285.736802) (xy 94.974618 -285.686702) (xy 94.974156 -285.661354)
			(xy 94.693232 -285.661354) (xy 94.692724 -285.687241) (xy 94.684625 -285.738379) (xy 94.668626 -285.787619)
			(xy 94.64512 -285.833751) (xy 94.614688 -285.875638) (xy 94.578078 -285.912248) (xy 94.536191 -285.94268)
			(xy 94.490059 -285.966186) (xy 94.440819 -285.982185) (xy 94.389681 -285.990284) (xy 94.337907 -285.990284)
			(xy 94.286769 -285.982185) (xy 94.237529 -285.966186) (xy 94.191397 -285.94268) (xy 94.14951 -285.912248)
			(xy 94.1129 -285.875638) (xy 94.082468 -285.833751) (xy 94.058962 -285.787619) (xy 94.042963 -285.738379)
			(xy 94.034864 -285.687241) (xy 94.034356 -285.661354) (xy 93.753432 -285.661354) (xy 93.753432 -285.661862)
			(xy 93.752853 -285.689379) (xy 93.743659 -285.74364) (xy 93.735144 -285.769812) (xy 93.727524 -285.79191)
			(xy 93.932756 -286.147256) (xy 93.955616 -286.151574) (xy 93.980427 -286.156786) (xy 94.028204 -286.173734)
			(xy 94.072823 -286.197799) (xy 94.11323 -286.228413) (xy 94.148472 -286.264855) (xy 94.177717 -286.306263)
			(xy 94.200276 -286.351662) (xy 94.215617 -286.399979) (xy 94.223377 -286.450077) (xy 94.22384 -286.475424)
			(xy 94.223332 -286.501331) (xy 94.215226 -286.552508) (xy 94.199214 -286.601787) (xy 94.175691 -286.647954)
			(xy 94.145235 -286.689873) (xy 94.108597 -286.726511) (xy 94.066678 -286.756967) (xy 94.020511 -286.78049)
			(xy 93.971232 -286.796502) (xy 93.920055 -286.804608) (xy 93.868241 -286.804608) (xy 93.817064 -286.796502)
			(xy 93.767785 -286.78049) (xy 93.721618 -286.756967) (xy 93.679699 -286.726511) (xy 93.643061 -286.689873)
			(xy 93.612605 -286.647954) (xy 93.589082 -286.601787) (xy 93.57307 -286.552508) (xy 93.564964 -286.501331)
			(xy 93.564456 -286.475424) (xy 93.565053 -286.447707) (xy 93.574374 -286.39306) (xy 93.582998 -286.366712)
			(xy 93.590872 -286.344614) (xy 93.385894 -285.989522) (xy 93.36278 -285.985204) (xy 93.337964 -285.980016)
			(xy 93.290184 -285.963065) (xy 93.245565 -285.938998) (xy 93.205157 -285.908381) (xy 93.169916 -285.871936)
			(xy 93.140671 -285.830525) (xy 93.118113 -285.785123) (xy 93.102775 -285.736802) (xy 93.095018 -285.686702)
			(xy 93.094556 -285.661354) (xy 92.813632 -285.661354) (xy 92.813124 -285.687241) (xy 92.805025 -285.738379)
			(xy 92.789026 -285.787619) (xy 92.76552 -285.833751) (xy 92.735088 -285.875638) (xy 92.698478 -285.912248)
			(xy 92.656591 -285.94268) (xy 92.610459 -285.966186) (xy 92.561219 -285.982185) (xy 92.510081 -285.990284)
			(xy 92.458307 -285.990284) (xy 92.407169 -285.982185) (xy 92.357929 -285.966186) (xy 92.311797 -285.94268)
			(xy 92.26991 -285.912248) (xy 92.2333 -285.875638) (xy 92.202868 -285.833751) (xy 92.179362 -285.787619)
			(xy 92.163363 -285.738379) (xy 92.155264 -285.687241) (xy 92.154756 -285.661354) (xy 91.87434 -285.661354)
			(xy 91.873738 -285.689071) (xy 91.86442 -285.743718) (xy 91.855798 -285.770066) (xy 91.847924 -285.792164)
			(xy 92.053156 -286.147256) (xy 92.076016 -286.151574) (xy 92.100827 -286.156786) (xy 92.148604 -286.173734)
			(xy 92.193223 -286.197799) (xy 92.23363 -286.228413) (xy 92.268872 -286.264855) (xy 92.298117 -286.306263)
			(xy 92.320676 -286.351662) (xy 92.336017 -286.399979) (xy 92.343777 -286.450077) (xy 92.34424 -286.475424)
			(xy 92.343732 -286.501331) (xy 92.335626 -286.552508) (xy 92.319614 -286.601787) (xy 92.296091 -286.647954)
			(xy 92.265635 -286.689873) (xy 92.228997 -286.726511) (xy 92.187078 -286.756967) (xy 92.140911 -286.78049)
			(xy 92.091632 -286.796502) (xy 92.040455 -286.804608) (xy 91.988641 -286.804608) (xy 91.937464 -286.796502)
			(xy 91.888185 -286.78049) (xy 91.842018 -286.756967) (xy 91.800099 -286.726511) (xy 91.763461 -286.689873)
			(xy 91.733005 -286.647954) (xy 91.709482 -286.601787) (xy 91.69347 -286.552508) (xy 91.685364 -286.501331)
			(xy 91.684856 -286.475424) (xy 91.685453 -286.447707) (xy 91.694774 -286.39306) (xy 91.703398 -286.366712)
			(xy 91.711272 -286.344614) (xy 91.50604 -285.989522) (xy 91.48318 -285.985204) (xy 91.458364 -285.980016)
			(xy 91.410584 -285.963065) (xy 91.365965 -285.938998) (xy 91.325557 -285.908381) (xy 91.290316 -285.871936)
			(xy 91.261071 -285.830525) (xy 91.238513 -285.785123) (xy 91.223175 -285.736802) (xy 91.215418 -285.686702)
			(xy 91.214956 -285.661354) (xy 90.93454 -285.661354) (xy 90.934032 -285.687261) (xy 90.925926 -285.738438)
			(xy 90.909914 -285.787717) (xy 90.886391 -285.833884) (xy 90.855935 -285.875803) (xy 90.819297 -285.912441)
			(xy 90.777378 -285.942897) (xy 90.731211 -285.96642) (xy 90.681932 -285.982432) (xy 90.630755 -285.990538)
			(xy 90.578941 -285.990538) (xy 90.527764 -285.982432) (xy 90.478485 -285.96642) (xy 90.432318 -285.942897)
			(xy 90.390399 -285.912441) (xy 90.353761 -285.875803) (xy 90.323305 -285.833884) (xy 90.299782 -285.787717)
			(xy 90.28377 -285.738438) (xy 90.275664 -285.687261) (xy 90.275156 -285.661354) (xy 89.994232 -285.661354)
			(xy 89.993689 -285.689062) (xy 89.984503 -285.743708) (xy 89.975944 -285.770066) (xy 89.96807 -285.792164)
			(xy 90.173302 -286.147256) (xy 90.196162 -286.151574) (xy 90.220961 -286.156781) (xy 90.268701 -286.173765)
			(xy 90.31328 -286.197855) (xy 90.353647 -286.228483) (xy 90.388851 -286.264927) (xy 90.418064 -286.30633)
			(xy 90.440597 -286.351715) (xy 90.455919 -286.400014) (xy 90.46367 -286.450088) (xy 90.464132 -286.475424)
			(xy 90.463624 -286.501311) (xy 90.455525 -286.552449) (xy 90.439526 -286.601689) (xy 90.41602 -286.647821)
			(xy 90.385588 -286.689708) (xy 90.348978 -286.726318) (xy 90.307091 -286.75675) (xy 90.260959 -286.780256)
			(xy 90.211719 -286.796255) (xy 90.160581 -286.804354) (xy 90.108807 -286.804354) (xy 90.057669 -286.796255)
			(xy 90.008429 -286.780256) (xy 89.962297 -286.75675) (xy 89.92041 -286.726318) (xy 89.8838 -286.689708)
			(xy 89.853368 -286.647821) (xy 89.829862 -286.601689) (xy 89.813863 -286.552449) (xy 89.805764 -286.501311)
			(xy 89.805256 -286.475424) (xy 89.805793 -286.447716) (xy 89.814983 -286.393069) (xy 89.823544 -286.366712)
			(xy 89.831418 -286.344614) (xy 89.626186 -285.989522) (xy 89.603326 -285.985204) (xy 89.57852 -285.980026)
			(xy 89.530779 -285.963039) (xy 89.486199 -285.938946) (xy 89.445832 -285.908314) (xy 89.410627 -285.871866)
			(xy 89.381416 -285.83046) (xy 89.358884 -285.785071) (xy 89.343564 -285.736769) (xy 89.335817 -285.686691)
			(xy 89.335356 -285.661354) (xy 88.114632 -285.661354) (xy 88.114124 -285.687241) (xy 88.106025 -285.738379)
			(xy 88.090026 -285.787619) (xy 88.06652 -285.833751) (xy 88.036088 -285.875638) (xy 87.999478 -285.912248)
			(xy 87.957591 -285.94268) (xy 87.911459 -285.966186) (xy 87.862219 -285.982185) (xy 87.811081 -285.990284)
			(xy 87.759307 -285.990284) (xy 87.708169 -285.982185) (xy 87.658929 -285.966186) (xy 87.612797 -285.94268)
			(xy 87.57091 -285.912248) (xy 87.5343 -285.875638) (xy 87.503868 -285.833751) (xy 87.480362 -285.787619)
			(xy 87.464363 -285.738379) (xy 87.456264 -285.687241) (xy 87.455756 -285.661354) (xy 2.509012 -285.661354)
			(xy 2.509012 -286.475424) (xy 86.046056 -286.475424) (xy 86.046564 -286.449537) (xy 86.054663 -286.398399)
			(xy 86.070662 -286.349159) (xy 86.094168 -286.303027) (xy 86.1246 -286.26114) (xy 86.16121 -286.22453)
			(xy 86.203097 -286.194098) (xy 86.249229 -286.170592) (xy 86.298469 -286.154593) (xy 86.349607 -286.146494)
			(xy 86.401381 -286.146494) (xy 86.452519 -286.154593) (xy 86.501759 -286.170592) (xy 86.547891 -286.194098)
			(xy 86.589778 -286.22453) (xy 86.626388 -286.26114) (xy 86.65682 -286.303027) (xy 86.680326 -286.349159)
			(xy 86.696325 -286.398399) (xy 86.704424 -286.449537) (xy 86.704932 -286.475424) (xy 86.704442 -286.501305)
			(xy 86.98614 -286.501305) (xy 86.98614 -286.449495) (xy 86.994245 -286.398322) (xy 87.010255 -286.349048)
			(xy 87.033776 -286.302885) (xy 87.064229 -286.260969) (xy 87.100864 -286.224333) (xy 87.142779 -286.193879)
			(xy 87.188942 -286.170357) (xy 87.238217 -286.154347) (xy 87.289389 -286.146241) (xy 87.315294 -286.145732)
			(xy 87.340788 -286.146208) (xy 87.391166 -286.154069) (xy 87.43973 -286.169604) (xy 87.485317 -286.192442)
			(xy 87.526838 -286.222037) (xy 87.563299 -286.257679) (xy 87.578946 -286.277812) (xy 87.991442 -286.277812)
			(xy 88.007098 -286.257686) (xy 88.043557 -286.222043) (xy 88.085076 -286.192449) (xy 88.130661 -286.16961)
			(xy 88.179224 -286.154073) (xy 88.229601 -286.146211) (xy 88.255094 -286.145732) (xy 88.281006 -286.146165)
			(xy 88.332191 -286.154271) (xy 88.381478 -286.170285) (xy 88.427653 -286.193811) (xy 88.469579 -286.224272)
			(xy 88.506224 -286.260916) (xy 88.536685 -286.302842) (xy 88.560213 -286.349016) (xy 88.576227 -286.398303)
			(xy 88.584334 -286.449488) (xy 88.584334 -286.501312) (xy 88.576227 -286.552497) (xy 88.560213 -286.601784)
			(xy 88.536685 -286.647958) (xy 88.506224 -286.689884) (xy 88.469579 -286.726528) (xy 88.427653 -286.756989)
			(xy 88.381478 -286.780515) (xy 88.332191 -286.796529) (xy 88.281006 -286.804635) (xy 88.255094 -286.805116)
			(xy 88.229601 -286.80463) (xy 88.179224 -286.796768) (xy 88.130661 -286.781233) (xy 88.085074 -286.758397)
			(xy 88.043553 -286.728806) (xy 88.007091 -286.693167) (xy 87.991442 -286.673036) (xy 87.578946 -286.673036)
			(xy 87.56331 -286.693178) (xy 87.526845 -286.728817) (xy 87.485322 -286.758409) (xy 87.439733 -286.781244)
			(xy 87.391168 -286.796778) (xy 87.340788 -286.804638) (xy 87.315294 -286.805116) (xy 87.289389 -286.804559)
			(xy 87.238217 -286.796453) (xy 87.188942 -286.780443) (xy 87.142779 -286.756921) (xy 87.100864 -286.726467)
			(xy 87.064229 -286.689831) (xy 87.033776 -286.647915) (xy 87.010255 -286.601752) (xy 86.994245 -286.552478)
			(xy 86.98614 -286.501305) (xy 86.704442 -286.501305) (xy 86.704407 -286.503132) (xy 86.695209 -286.557779)
			(xy 86.686644 -286.584136) (xy 86.679024 -286.60598) (xy 86.884002 -286.961072) (xy 86.906862 -286.96539)
			(xy 86.931665 -286.970582) (xy 86.979406 -286.987567) (xy 87.023985 -287.011659) (xy 87.064353 -287.042288)
			(xy 87.099557 -287.078734) (xy 87.12877 -287.120139) (xy 87.151302 -287.165526) (xy 87.166622 -287.213827)
			(xy 87.174371 -287.263904) (xy 87.174832 -287.28924) (xy 87.174324 -287.315127) (xy 87.166225 -287.366265)
			(xy 87.150226 -287.415505) (xy 87.12672 -287.461637) (xy 87.096288 -287.503524) (xy 87.059678 -287.540134)
			(xy 87.017791 -287.570566) (xy 86.971659 -287.594072) (xy 86.922419 -287.610071) (xy 86.871281 -287.61817)
			(xy 86.819507 -287.61817) (xy 86.768369 -287.610071) (xy 86.719129 -287.594072) (xy 86.672997 -287.570566)
			(xy 86.63111 -287.540134) (xy 86.5945 -287.503524) (xy 86.564068 -287.461637) (xy 86.540562 -287.415505)
			(xy 86.524563 -287.366265) (xy 86.516464 -287.315127) (xy 86.515956 -287.28924) (xy 86.516497 -287.261532)
			(xy 86.525685 -287.206886) (xy 86.534244 -287.180528) (xy 86.541864 -287.158684) (xy 86.336886 -286.803592)
			(xy 86.314026 -286.799274) (xy 86.289236 -286.79403) (xy 86.241499 -286.777048) (xy 86.196923 -286.752961)
			(xy 86.156558 -286.722338) (xy 86.121354 -286.685898) (xy 86.09214 -286.644501) (xy 86.069605 -286.599121)
			(xy 86.054278 -286.550828) (xy 86.046522 -286.500758) (xy 86.046056 -286.475424) (xy 2.509012 -286.475424)
			(xy 2.509012 -288.917126) (xy 88.395556 -288.917126) (xy 88.396056 -288.891781) (xy 88.403825 -288.84169)
			(xy 88.419169 -288.793377) (xy 88.441727 -288.747983) (xy 88.470967 -288.706576) (xy 88.506199 -288.670131)
			(xy 88.546595 -288.639509) (xy 88.591201 -288.61543) (xy 88.638966 -288.598461) (xy 88.66378 -288.593276)
			(xy 88.68664 -288.588958) (xy 88.891618 -288.233866) (xy 88.883744 -288.212022) (xy 88.875171 -288.185601)
			(xy 88.86597 -288.130828) (xy 88.865456 -288.103056) (xy 88.865964 -288.077169) (xy 88.874063 -288.026031)
			(xy 88.890062 -287.976791) (xy 88.913568 -287.930659) (xy 88.944 -287.888772) (xy 88.98061 -287.852162)
			(xy 89.022497 -287.82173) (xy 89.068629 -287.798224) (xy 89.117869 -287.782225) (xy 89.169007 -287.774126)
			(xy 89.220781 -287.774126) (xy 89.271919 -287.782225) (xy 89.321159 -287.798224) (xy 89.367291 -287.82173)
			(xy 89.409178 -287.852162) (xy 89.445788 -287.888772) (xy 89.47622 -287.930659) (xy 89.499726 -287.976791)
			(xy 89.515725 -288.026031) (xy 89.523824 -288.077169) (xy 89.524332 -288.103056) (xy 89.523874 -288.128391)
			(xy 89.516115 -288.178463) (xy 89.500786 -288.226759) (xy 89.47825 -288.272141) (xy 89.449037 -288.313542)
			(xy 89.413835 -288.349987) (xy 89.373471 -288.380617) (xy 89.328897 -288.404713) (xy 89.281162 -288.421706)
			(xy 89.256362 -288.426906) (xy 89.233502 -288.431224) (xy 89.028524 -288.786316) (xy 89.036398 -288.80816)
			(xy 89.045049 -288.834567) (xy 89.054366 -288.889344) (xy 89.05494 -288.917126) (xy 90.275156 -288.917126)
			(xy 90.275656 -288.891781) (xy 90.283425 -288.84169) (xy 90.298769 -288.793377) (xy 90.321327 -288.747983)
			(xy 90.350567 -288.706576) (xy 90.385799 -288.670131) (xy 90.426195 -288.639509) (xy 90.470801 -288.61543)
			(xy 90.518566 -288.598461) (xy 90.54338 -288.593276) (xy 90.56624 -288.588958) (xy 90.771218 -288.233866)
			(xy 90.763344 -288.212022) (xy 90.754771 -288.185601) (xy 90.74557 -288.130828) (xy 90.745056 -288.103056)
			(xy 90.745564 -288.077169) (xy 90.753663 -288.026031) (xy 90.769662 -287.976791) (xy 90.793168 -287.930659)
			(xy 90.8236 -287.888772) (xy 90.86021 -287.852162) (xy 90.902097 -287.82173) (xy 90.948229 -287.798224)
			(xy 90.997469 -287.782225) (xy 91.048607 -287.774126) (xy 91.100381 -287.774126) (xy 91.151519 -287.782225)
			(xy 91.200759 -287.798224) (xy 91.246891 -287.82173) (xy 91.288778 -287.852162) (xy 91.325388 -287.888772)
			(xy 91.35582 -287.930659) (xy 91.379326 -287.976791) (xy 91.395325 -288.026031) (xy 91.403424 -288.077169)
			(xy 91.403932 -288.103056) (xy 91.403474 -288.128391) (xy 91.395715 -288.178463) (xy 91.380386 -288.226759)
			(xy 91.35785 -288.272141) (xy 91.328637 -288.313542) (xy 91.293435 -288.349987) (xy 91.253071 -288.380617)
			(xy 91.208497 -288.404713) (xy 91.160762 -288.421706) (xy 91.135962 -288.426906) (xy 91.113102 -288.431224)
			(xy 90.908124 -288.786316) (xy 90.915998 -288.80816) (xy 90.924649 -288.834567) (xy 90.933966 -288.889344)
			(xy 90.93454 -288.917126) (xy 91.214956 -288.917126) (xy 91.215464 -288.891219) (xy 91.22357 -288.840042)
			(xy 91.239582 -288.790763) (xy 91.263105 -288.744596) (xy 91.293561 -288.702677) (xy 91.330199 -288.666039)
			(xy 91.372118 -288.635583) (xy 91.418285 -288.61206) (xy 91.467564 -288.596048) (xy 91.518741 -288.587942)
			(xy 91.570555 -288.587942) (xy 91.621732 -288.596048) (xy 91.671011 -288.61206) (xy 91.717178 -288.635583)
			(xy 91.759097 -288.666039) (xy 91.795735 -288.702677) (xy 91.826191 -288.744596) (xy 91.849714 -288.790763)
			(xy 91.865726 -288.840042) (xy 91.873832 -288.891219) (xy 91.87434 -288.917126) (xy 92.154756 -288.917126)
			(xy 92.155256 -288.891781) (xy 92.163025 -288.84169) (xy 92.178369 -288.793377) (xy 92.200927 -288.747983)
			(xy 92.230167 -288.706576) (xy 92.265399 -288.670131) (xy 92.305795 -288.639509) (xy 92.350401 -288.61543)
			(xy 92.398166 -288.598461) (xy 92.42298 -288.593276) (xy 92.44584 -288.588958) (xy 92.651072 -288.233866)
			(xy 92.643198 -288.211768) (xy 92.634576 -288.185419) (xy 92.625249 -288.130773) (xy 92.624656 -288.103056)
			(xy 92.625164 -288.077149) (xy 92.63327 -288.025972) (xy 92.649282 -287.976693) (xy 92.672805 -287.930526)
			(xy 92.703261 -287.888607) (xy 92.739899 -287.851969) (xy 92.781818 -287.821513) (xy 92.827985 -287.79799)
			(xy 92.877264 -287.781978) (xy 92.928441 -287.773872) (xy 92.980255 -287.773872) (xy 93.031432 -287.781978)
			(xy 93.080711 -287.79799) (xy 93.126878 -287.821513) (xy 93.168797 -287.851969) (xy 93.205435 -287.888607)
			(xy 93.235891 -287.930526) (xy 93.259414 -287.976693) (xy 93.275426 -288.025972) (xy 93.283532 -288.077149)
			(xy 93.28404 -288.103056) (xy 93.283618 -288.128404) (xy 93.275836 -288.178499) (xy 93.26048 -288.226813)
			(xy 93.237912 -288.272208) (xy 93.208662 -288.313614) (xy 93.173421 -288.350057) (xy 93.133018 -288.380678)
			(xy 93.088405 -288.404755) (xy 93.040632 -288.421722) (xy 93.015816 -288.426906) (xy 92.992956 -288.431224)
			(xy 92.787724 -288.786316) (xy 92.795598 -288.808414) (xy 92.80424 -288.834757) (xy 92.813554 -288.889407)
			(xy 92.81414 -288.917126) (xy 93.094556 -288.917126) (xy 93.095064 -288.891219) (xy 93.10317 -288.840042)
			(xy 93.119182 -288.790763) (xy 93.142705 -288.744596) (xy 93.173161 -288.702677) (xy 93.209799 -288.666039)
			(xy 93.251718 -288.635583) (xy 93.297885 -288.61206) (xy 93.347164 -288.596048) (xy 93.398341 -288.587942)
			(xy 93.450155 -288.587942) (xy 93.501332 -288.596048) (xy 93.550611 -288.61206) (xy 93.596778 -288.635583)
			(xy 93.638697 -288.666039) (xy 93.675335 -288.702677) (xy 93.705791 -288.744596) (xy 93.729314 -288.790763)
			(xy 93.745326 -288.840042) (xy 93.753432 -288.891219) (xy 93.75394 -288.917126) (xy 94.034356 -288.917126)
			(xy 94.034856 -288.891781) (xy 94.042625 -288.84169) (xy 94.057969 -288.793377) (xy 94.080527 -288.747983)
			(xy 94.109767 -288.706576) (xy 94.144999 -288.670131) (xy 94.185395 -288.639509) (xy 94.230001 -288.61543)
			(xy 94.277766 -288.598461) (xy 94.30258 -288.593276) (xy 94.32544 -288.588958) (xy 94.530672 -288.233866)
			(xy 94.522798 -288.211768) (xy 94.514176 -288.185419) (xy 94.504849 -288.130773) (xy 94.504256 -288.103056)
			(xy 94.504764 -288.077149) (xy 94.51287 -288.025972) (xy 94.528882 -287.976693) (xy 94.552405 -287.930526)
			(xy 94.582861 -287.888607) (xy 94.619499 -287.851969) (xy 94.661418 -287.821513) (xy 94.707585 -287.79799)
			(xy 94.756864 -287.781978) (xy 94.808041 -287.773872) (xy 94.859855 -287.773872) (xy 94.911032 -287.781978)
			(xy 94.960311 -287.79799) (xy 95.006478 -287.821513) (xy 95.048397 -287.851969) (xy 95.085035 -287.888607)
			(xy 95.115491 -287.930526) (xy 95.139014 -287.976693) (xy 95.155026 -288.025972) (xy 95.163132 -288.077149)
			(xy 95.16364 -288.103056) (xy 95.163218 -288.128404) (xy 95.155436 -288.178499) (xy 95.14008 -288.226813)
			(xy 95.117512 -288.272208) (xy 95.088262 -288.313614) (xy 95.053021 -288.350057) (xy 95.012618 -288.380678)
			(xy 94.968005 -288.404755) (xy 94.920232 -288.421722) (xy 94.895416 -288.426906) (xy 94.872556 -288.431224)
			(xy 94.667324 -288.786316) (xy 94.675198 -288.808414) (xy 94.68384 -288.834757) (xy 94.693154 -288.889407)
			(xy 94.69374 -288.917126) (xy 94.974156 -288.917126) (xy 94.974664 -288.891219) (xy 94.98277 -288.840042)
			(xy 94.998782 -288.790763) (xy 95.022305 -288.744596) (xy 95.052761 -288.702677) (xy 95.089399 -288.666039)
			(xy 95.131318 -288.635583) (xy 95.177485 -288.61206) (xy 95.226764 -288.596048) (xy 95.277941 -288.587942)
			(xy 95.329755 -288.587942) (xy 95.380932 -288.596048) (xy 95.430211 -288.61206) (xy 95.476378 -288.635583)
			(xy 95.518297 -288.666039) (xy 95.554935 -288.702677) (xy 95.585391 -288.744596) (xy 95.608914 -288.790763)
			(xy 95.624926 -288.840042) (xy 95.633032 -288.891219) (xy 95.63354 -288.917126) (xy 95.913956 -288.917126)
			(xy 95.914456 -288.891781) (xy 95.922225 -288.84169) (xy 95.937569 -288.793377) (xy 95.960127 -288.747983)
			(xy 95.989367 -288.706576) (xy 96.024599 -288.670131) (xy 96.064995 -288.639509) (xy 96.109601 -288.61543)
			(xy 96.157366 -288.598461) (xy 96.18218 -288.593276) (xy 96.20504 -288.588958) (xy 96.410272 -288.233866)
			(xy 96.402398 -288.211768) (xy 96.393776 -288.185419) (xy 96.384449 -288.130773) (xy 96.383856 -288.103056)
			(xy 96.384364 -288.077149) (xy 96.39247 -288.025972) (xy 96.408482 -287.976693) (xy 96.432005 -287.930526)
			(xy 96.462461 -287.888607) (xy 96.499099 -287.851969) (xy 96.541018 -287.821513) (xy 96.587185 -287.79799)
			(xy 96.636464 -287.781978) (xy 96.687641 -287.773872) (xy 96.739455 -287.773872) (xy 96.790632 -287.781978)
			(xy 96.839911 -287.79799) (xy 96.886078 -287.821513) (xy 96.927997 -287.851969) (xy 96.964635 -287.888607)
			(xy 96.995091 -287.930526) (xy 97.018614 -287.976693) (xy 97.034626 -288.025972) (xy 97.042732 -288.077149)
			(xy 97.04324 -288.103056) (xy 97.042818 -288.128404) (xy 97.035036 -288.178499) (xy 97.01968 -288.226813)
			(xy 96.997112 -288.272208) (xy 96.967862 -288.313614) (xy 96.932621 -288.350057) (xy 96.892218 -288.380678)
			(xy 96.847605 -288.404755) (xy 96.799832 -288.421722) (xy 96.775016 -288.426906) (xy 96.752156 -288.431224)
			(xy 96.546924 -288.786316) (xy 96.554798 -288.808414) (xy 96.56344 -288.834757) (xy 96.572754 -288.889407)
			(xy 96.57334 -288.917126) (xy 96.853756 -288.917126) (xy 96.854264 -288.891219) (xy 96.86237 -288.840042)
			(xy 96.878382 -288.790763) (xy 96.901905 -288.744596) (xy 96.932361 -288.702677) (xy 96.968999 -288.666039)
			(xy 97.010918 -288.635583) (xy 97.057085 -288.61206) (xy 97.106364 -288.596048) (xy 97.157541 -288.587942)
			(xy 97.209355 -288.587942) (xy 97.260532 -288.596048) (xy 97.309811 -288.61206) (xy 97.355978 -288.635583)
			(xy 97.397897 -288.666039) (xy 97.434535 -288.702677) (xy 97.464991 -288.744596) (xy 97.488514 -288.790763)
			(xy 97.504526 -288.840042) (xy 97.512632 -288.891219) (xy 97.51314 -288.917126) (xy 97.793556 -288.917126)
			(xy 97.794056 -288.891781) (xy 97.801825 -288.84169) (xy 97.817169 -288.793377) (xy 97.839727 -288.747983)
			(xy 97.868967 -288.706576) (xy 97.904199 -288.670131) (xy 97.944595 -288.639509) (xy 97.989201 -288.61543)
			(xy 98.036966 -288.598461) (xy 98.06178 -288.593276) (xy 98.08464 -288.588958) (xy 98.289872 -288.233866)
			(xy 98.281998 -288.211768) (xy 98.273376 -288.185419) (xy 98.264049 -288.130773) (xy 98.263456 -288.103056)
			(xy 98.263964 -288.077149) (xy 98.27207 -288.025972) (xy 98.288082 -287.976693) (xy 98.311605 -287.930526)
			(xy 98.342061 -287.888607) (xy 98.378699 -287.851969) (xy 98.420618 -287.821513) (xy 98.466785 -287.79799)
			(xy 98.516064 -287.781978) (xy 98.567241 -287.773872) (xy 98.619055 -287.773872) (xy 98.670232 -287.781978)
			(xy 98.719511 -287.79799) (xy 98.765678 -287.821513) (xy 98.807597 -287.851969) (xy 98.844235 -287.888607)
			(xy 98.874691 -287.930526) (xy 98.898214 -287.976693) (xy 98.914226 -288.025972) (xy 98.922332 -288.077149)
			(xy 98.92284 -288.103056) (xy 98.922418 -288.128404) (xy 98.914636 -288.178499) (xy 98.89928 -288.226813)
			(xy 98.876712 -288.272208) (xy 98.847462 -288.313614) (xy 98.812221 -288.350057) (xy 98.771818 -288.380678)
			(xy 98.727205 -288.404755) (xy 98.679432 -288.421722) (xy 98.654616 -288.426906) (xy 98.631756 -288.431224)
			(xy 98.426524 -288.786316) (xy 98.434398 -288.808414) (xy 98.44304 -288.834757) (xy 98.452354 -288.889407)
			(xy 98.45294 -288.917126) (xy 98.733356 -288.917126) (xy 98.733864 -288.891219) (xy 98.74197 -288.840042)
			(xy 98.757982 -288.790763) (xy 98.781505 -288.744596) (xy 98.811961 -288.702677) (xy 98.848599 -288.666039)
			(xy 98.890518 -288.635583) (xy 98.936685 -288.61206) (xy 98.985964 -288.596048) (xy 99.037141 -288.587942)
			(xy 99.088955 -288.587942) (xy 99.140132 -288.596048) (xy 99.189411 -288.61206) (xy 99.235578 -288.635583)
			(xy 99.277497 -288.666039) (xy 99.314135 -288.702677) (xy 99.344591 -288.744596) (xy 99.368114 -288.790763)
			(xy 99.384126 -288.840042) (xy 99.392232 -288.891219) (xy 99.39274 -288.917126) (xy 99.673156 -288.917126)
			(xy 99.673656 -288.891781) (xy 99.681425 -288.84169) (xy 99.696769 -288.793377) (xy 99.719327 -288.747983)
			(xy 99.748567 -288.706576) (xy 99.783799 -288.670131) (xy 99.824195 -288.639509) (xy 99.868801 -288.61543)
			(xy 99.916566 -288.598461) (xy 99.94138 -288.593276) (xy 99.96424 -288.588958) (xy 100.169472 -288.233866)
			(xy 100.161598 -288.211768) (xy 100.152976 -288.185419) (xy 100.143649 -288.130773) (xy 100.143056 -288.103056)
			(xy 100.143564 -288.077149) (xy 100.15167 -288.025972) (xy 100.167682 -287.976693) (xy 100.191205 -287.930526)
			(xy 100.221661 -287.888607) (xy 100.258299 -287.851969) (xy 100.300218 -287.821513) (xy 100.346385 -287.79799)
			(xy 100.395664 -287.781978) (xy 100.446841 -287.773872) (xy 100.498655 -287.773872) (xy 100.549832 -287.781978)
			(xy 100.599111 -287.79799) (xy 100.645278 -287.821513) (xy 100.687197 -287.851969) (xy 100.723835 -287.888607)
			(xy 100.754291 -287.930526) (xy 100.777814 -287.976693) (xy 100.793826 -288.025972) (xy 100.801932 -288.077149)
			(xy 100.80244 -288.103056) (xy 100.802018 -288.128404) (xy 100.794236 -288.178499) (xy 100.77888 -288.226813)
			(xy 100.756312 -288.272208) (xy 100.727062 -288.313614) (xy 100.691821 -288.350057) (xy 100.651418 -288.380678)
			(xy 100.606805 -288.404755) (xy 100.559032 -288.421722) (xy 100.534216 -288.426906) (xy 100.511356 -288.431224)
			(xy 100.306124 -288.786316) (xy 100.313998 -288.808414) (xy 100.32264 -288.834757) (xy 100.331954 -288.889407)
			(xy 100.33254 -288.917126) (xy 100.612956 -288.917126) (xy 100.613464 -288.891219) (xy 100.62157 -288.840042)
			(xy 100.637582 -288.790763) (xy 100.661105 -288.744596) (xy 100.691561 -288.702677) (xy 100.728199 -288.666039)
			(xy 100.770118 -288.635583) (xy 100.816285 -288.61206) (xy 100.865564 -288.596048) (xy 100.916741 -288.587942)
			(xy 100.968555 -288.587942) (xy 101.019732 -288.596048) (xy 101.069011 -288.61206) (xy 101.115178 -288.635583)
			(xy 101.157097 -288.666039) (xy 101.193735 -288.702677) (xy 101.224191 -288.744596) (xy 101.247714 -288.790763)
			(xy 101.263726 -288.840042) (xy 101.271832 -288.891219) (xy 101.27234 -288.917126) (xy 101.552756 -288.917126)
			(xy 101.553256 -288.891781) (xy 101.561025 -288.84169) (xy 101.576369 -288.793377) (xy 101.598927 -288.747983)
			(xy 101.628167 -288.706576) (xy 101.663399 -288.670131) (xy 101.703795 -288.639509) (xy 101.748401 -288.61543)
			(xy 101.796166 -288.598461) (xy 101.82098 -288.593276) (xy 101.84384 -288.588958) (xy 102.049072 -288.233866)
			(xy 102.041198 -288.211768) (xy 102.032576 -288.185419) (xy 102.023249 -288.130773) (xy 102.022656 -288.103056)
			(xy 102.023164 -288.077149) (xy 102.03127 -288.025972) (xy 102.047282 -287.976693) (xy 102.070805 -287.930526)
			(xy 102.101261 -287.888607) (xy 102.137899 -287.851969) (xy 102.179818 -287.821513) (xy 102.225985 -287.79799)
			(xy 102.275264 -287.781978) (xy 102.326441 -287.773872) (xy 102.378255 -287.773872) (xy 102.429432 -287.781978)
			(xy 102.478711 -287.79799) (xy 102.524878 -287.821513) (xy 102.566797 -287.851969) (xy 102.603435 -287.888607)
			(xy 102.633891 -287.930526) (xy 102.657414 -287.976693) (xy 102.673426 -288.025972) (xy 102.681532 -288.077149)
			(xy 102.68204 -288.103056) (xy 102.681618 -288.128404) (xy 102.673836 -288.178499) (xy 102.65848 -288.226813)
			(xy 102.635912 -288.272208) (xy 102.606662 -288.313614) (xy 102.571421 -288.350057) (xy 102.531018 -288.380678)
			(xy 102.486405 -288.404755) (xy 102.438632 -288.421722) (xy 102.413816 -288.426906) (xy 102.390956 -288.431224)
			(xy 102.185724 -288.786316) (xy 102.193598 -288.808414) (xy 102.20224 -288.834757) (xy 102.211554 -288.889407)
			(xy 102.21214 -288.917126) (xy 102.492556 -288.917126) (xy 102.493064 -288.891219) (xy 102.50117 -288.840042)
			(xy 102.517182 -288.790763) (xy 102.540705 -288.744596) (xy 102.571161 -288.702677) (xy 102.607799 -288.666039)
			(xy 102.649718 -288.635583) (xy 102.695885 -288.61206) (xy 102.745164 -288.596048) (xy 102.796341 -288.587942)
			(xy 102.848155 -288.587942) (xy 102.899332 -288.596048) (xy 102.948611 -288.61206) (xy 102.994778 -288.635583)
			(xy 103.036697 -288.666039) (xy 103.073335 -288.702677) (xy 103.103791 -288.744596) (xy 103.127314 -288.790763)
			(xy 103.143326 -288.840042) (xy 103.151432 -288.891219) (xy 103.15194 -288.917126) (xy 103.432356 -288.917126)
			(xy 103.432856 -288.891781) (xy 103.440625 -288.84169) (xy 103.455969 -288.793377) (xy 103.478527 -288.747983)
			(xy 103.507767 -288.706576) (xy 103.542999 -288.670131) (xy 103.583395 -288.639509) (xy 103.628001 -288.61543)
			(xy 103.675766 -288.598461) (xy 103.70058 -288.593276) (xy 103.72344 -288.588958) (xy 103.928672 -288.233866)
			(xy 103.920798 -288.211768) (xy 103.912176 -288.185419) (xy 103.902849 -288.130773) (xy 103.902256 -288.103056)
			(xy 103.902764 -288.077149) (xy 103.91087 -288.025972) (xy 103.926882 -287.976693) (xy 103.950405 -287.930526)
			(xy 103.980861 -287.888607) (xy 104.017499 -287.851969) (xy 104.059418 -287.821513) (xy 104.105585 -287.79799)
			(xy 104.154864 -287.781978) (xy 104.206041 -287.773872) (xy 104.257855 -287.773872) (xy 104.309032 -287.781978)
			(xy 104.358311 -287.79799) (xy 104.404478 -287.821513) (xy 104.446397 -287.851969) (xy 104.483035 -287.888607)
			(xy 104.513491 -287.930526) (xy 104.537014 -287.976693) (xy 104.553026 -288.025972) (xy 104.561132 -288.077149)
			(xy 104.56164 -288.103056) (xy 120.818656 -288.103056) (xy 120.819164 -288.077149) (xy 120.82727 -288.025972)
			(xy 120.843282 -287.976693) (xy 120.866805 -287.930526) (xy 120.897261 -287.888607) (xy 120.933899 -287.851969)
			(xy 120.975818 -287.821513) (xy 121.021985 -287.79799) (xy 121.071264 -287.781978) (xy 121.122441 -287.773872)
			(xy 121.174255 -287.773872) (xy 121.225432 -287.781978) (xy 121.274711 -287.79799) (xy 121.320878 -287.821513)
			(xy 121.362797 -287.851969) (xy 121.399435 -287.888607) (xy 121.429891 -287.930526) (xy 121.453414 -287.976693)
			(xy 121.469426 -288.025972) (xy 121.477532 -288.077149) (xy 121.47804 -288.103056) (xy 122.698256 -288.103056)
			(xy 122.698764 -288.077149) (xy 122.70687 -288.025972) (xy 122.722882 -287.976693) (xy 122.746405 -287.930526)
			(xy 122.776861 -287.888607) (xy 122.813499 -287.851969) (xy 122.855418 -287.821513) (xy 122.901585 -287.79799)
			(xy 122.950864 -287.781978) (xy 123.002041 -287.773872) (xy 123.053855 -287.773872) (xy 123.105032 -287.781978)
			(xy 123.154311 -287.79799) (xy 123.200478 -287.821513) (xy 123.242397 -287.851969) (xy 123.279035 -287.888607)
			(xy 123.309491 -287.930526) (xy 123.333014 -287.976693) (xy 123.349026 -288.025972) (xy 123.357132 -288.077149)
			(xy 123.35764 -288.103056) (xy 124.577856 -288.103056) (xy 124.578364 -288.077149) (xy 124.58647 -288.025972)
			(xy 124.602482 -287.976693) (xy 124.626005 -287.930526) (xy 124.656461 -287.888607) (xy 124.693099 -287.851969)
			(xy 124.735018 -287.821513) (xy 124.781185 -287.79799) (xy 124.830464 -287.781978) (xy 124.881641 -287.773872)
			(xy 124.933455 -287.773872) (xy 124.984632 -287.781978) (xy 125.033911 -287.79799) (xy 125.080078 -287.821513)
			(xy 125.121997 -287.851969) (xy 125.158635 -287.888607) (xy 125.189091 -287.930526) (xy 125.212614 -287.976693)
			(xy 125.228626 -288.025972) (xy 125.236732 -288.077149) (xy 125.23724 -288.103056) (xy 126.457456 -288.103056)
			(xy 126.457964 -288.077149) (xy 126.46607 -288.025972) (xy 126.482082 -287.976693) (xy 126.505605 -287.930526)
			(xy 126.536061 -287.888607) (xy 126.572699 -287.851969) (xy 126.614618 -287.821513) (xy 126.660785 -287.79799)
			(xy 126.710064 -287.781978) (xy 126.761241 -287.773872) (xy 126.813055 -287.773872) (xy 126.864232 -287.781978)
			(xy 126.913511 -287.79799) (xy 126.959678 -287.821513) (xy 127.001597 -287.851969) (xy 127.038235 -287.888607)
			(xy 127.068691 -287.930526) (xy 127.092214 -287.976693) (xy 127.108226 -288.025972) (xy 127.116332 -288.077149)
			(xy 127.11684 -288.103056) (xy 128.337056 -288.103056) (xy 128.337564 -288.077149) (xy 128.34567 -288.025972)
			(xy 128.361682 -287.976693) (xy 128.385205 -287.930526) (xy 128.415661 -287.888607) (xy 128.452299 -287.851969)
			(xy 128.494218 -287.821513) (xy 128.540385 -287.79799) (xy 128.589664 -287.781978) (xy 128.640841 -287.773872)
			(xy 128.692655 -287.773872) (xy 128.743832 -287.781978) (xy 128.793111 -287.79799) (xy 128.839278 -287.821513)
			(xy 128.881197 -287.851969) (xy 128.917835 -287.888607) (xy 128.948291 -287.930526) (xy 128.971814 -287.976693)
			(xy 128.987826 -288.025972) (xy 128.995932 -288.077149) (xy 128.99644 -288.103056) (xy 130.216656 -288.103056)
			(xy 130.217164 -288.077149) (xy 130.22527 -288.025972) (xy 130.241282 -287.976693) (xy 130.264805 -287.930526)
			(xy 130.295261 -287.888607) (xy 130.331899 -287.851969) (xy 130.373818 -287.821513) (xy 130.419985 -287.79799)
			(xy 130.469264 -287.781978) (xy 130.520441 -287.773872) (xy 130.572255 -287.773872) (xy 130.623432 -287.781978)
			(xy 130.672711 -287.79799) (xy 130.718878 -287.821513) (xy 130.760797 -287.851969) (xy 130.797435 -287.888607)
			(xy 130.827891 -287.930526) (xy 130.851414 -287.976693) (xy 130.867426 -288.025972) (xy 130.875532 -288.077149)
			(xy 130.87604 -288.103056) (xy 132.096256 -288.103056) (xy 132.096764 -288.077149) (xy 132.10487 -288.025972)
			(xy 132.120882 -287.976693) (xy 132.144405 -287.930526) (xy 132.174861 -287.888607) (xy 132.211499 -287.851969)
			(xy 132.253418 -287.821513) (xy 132.299585 -287.79799) (xy 132.348864 -287.781978) (xy 132.400041 -287.773872)
			(xy 132.451855 -287.773872) (xy 132.503032 -287.781978) (xy 132.552311 -287.79799) (xy 132.598478 -287.821513)
			(xy 132.640397 -287.851969) (xy 132.677035 -287.888607) (xy 132.707491 -287.930526) (xy 132.731014 -287.976693)
			(xy 132.747026 -288.025972) (xy 132.755132 -288.077149) (xy 132.75564 -288.103056) (xy 134.915656 -288.103056)
			(xy 134.916164 -288.077149) (xy 134.92427 -288.025972) (xy 134.940282 -287.976693) (xy 134.963805 -287.930526)
			(xy 134.994261 -287.888607) (xy 135.030899 -287.851969) (xy 135.072818 -287.821513) (xy 135.118985 -287.79799)
			(xy 135.168264 -287.781978) (xy 135.219441 -287.773872) (xy 135.271255 -287.773872) (xy 135.322432 -287.781978)
			(xy 135.371711 -287.79799) (xy 135.417878 -287.821513) (xy 135.459797 -287.851969) (xy 135.496435 -287.888607)
			(xy 135.526891 -287.930526) (xy 135.550414 -287.976693) (xy 135.566426 -288.025972) (xy 135.574532 -288.077149)
			(xy 135.57504 -288.103056) (xy 135.574438 -288.130773) (xy 135.56512 -288.18542) (xy 135.556498 -288.211768)
			(xy 135.548624 -288.233866) (xy 135.753856 -288.588958) (xy 135.776716 -288.593276) (xy 135.801527 -288.598486)
			(xy 135.849305 -288.615434) (xy 135.893924 -288.6395) (xy 135.934331 -288.670114) (xy 135.969573 -288.706556)
			(xy 135.998818 -288.747964) (xy 136.021377 -288.793363) (xy 136.036717 -288.841681) (xy 136.044477 -288.891779)
			(xy 136.04494 -288.917126) (xy 336.335624 -288.917126) (xy 336.336149 -288.891782) (xy 336.343918 -288.841693)
			(xy 336.359261 -288.793383) (xy 336.381816 -288.74799) (xy 336.411052 -288.706584) (xy 336.446281 -288.67014)
			(xy 336.486672 -288.639516) (xy 336.531274 -288.615435) (xy 336.579036 -288.598463) (xy 336.603848 -288.593276)
			(xy 336.626708 -288.588958) (xy 336.831686 -288.233866) (xy 336.823812 -288.212022) (xy 336.815238 -288.185602)
			(xy 336.806038 -288.130828) (xy 336.805524 -288.103056) (xy 336.806032 -288.077169) (xy 336.814131 -288.026031)
			(xy 336.83013 -287.976791) (xy 336.853636 -287.930659) (xy 336.884068 -287.888772) (xy 336.920678 -287.852162)
			(xy 336.962565 -287.82173) (xy 337.008697 -287.798224) (xy 337.057937 -287.782225) (xy 337.109075 -287.774126)
			(xy 337.160849 -287.774126) (xy 337.211987 -287.782225) (xy 337.261227 -287.798224) (xy 337.307359 -287.82173)
			(xy 337.349246 -287.852162) (xy 337.385856 -287.888772) (xy 337.416288 -287.930659) (xy 337.439794 -287.976791)
			(xy 337.455793 -288.026031) (xy 337.463892 -288.077169) (xy 337.4644 -288.103056) (xy 337.463968 -288.128392)
			(xy 337.456207 -288.178467) (xy 337.440877 -288.226765) (xy 337.418339 -288.272149) (xy 337.389123 -288.31355)
			(xy 337.353916 -288.349995) (xy 337.313549 -288.380624) (xy 337.268971 -288.404718) (xy 337.221232 -288.421708)
			(xy 337.19643 -288.426906) (xy 337.17357 -288.431224) (xy 336.968592 -288.786316) (xy 336.976466 -288.80816)
			(xy 336.985119 -288.834566) (xy 336.994435 -288.889344) (xy 336.995008 -288.917126) (xy 338.215224 -288.917126)
			(xy 338.215749 -288.891782) (xy 338.223518 -288.841693) (xy 338.238861 -288.793383) (xy 338.261416 -288.74799)
			(xy 338.290652 -288.706584) (xy 338.325881 -288.67014) (xy 338.366272 -288.639516) (xy 338.410874 -288.615435)
			(xy 338.458636 -288.598463) (xy 338.483448 -288.593276) (xy 338.506308 -288.588958) (xy 338.711286 -288.233866)
			(xy 338.703412 -288.212022) (xy 338.694838 -288.185602) (xy 338.685638 -288.130828) (xy 338.685124 -288.103056)
			(xy 338.685632 -288.077169) (xy 338.693731 -288.026031) (xy 338.70973 -287.976791) (xy 338.733236 -287.930659)
			(xy 338.763668 -287.888772) (xy 338.800278 -287.852162) (xy 338.842165 -287.82173) (xy 338.888297 -287.798224)
			(xy 338.937537 -287.782225) (xy 338.988675 -287.774126) (xy 339.040449 -287.774126) (xy 339.091587 -287.782225)
			(xy 339.140827 -287.798224) (xy 339.186959 -287.82173) (xy 339.228846 -287.852162) (xy 339.265456 -287.888772)
			(xy 339.295888 -287.930659) (xy 339.319394 -287.976791) (xy 339.335393 -288.026031) (xy 339.343492 -288.077169)
			(xy 339.344 -288.103056) (xy 339.343568 -288.128392) (xy 339.335807 -288.178467) (xy 339.320477 -288.226765)
			(xy 339.297939 -288.272149) (xy 339.268723 -288.31355) (xy 339.233516 -288.349995) (xy 339.193149 -288.380624)
			(xy 339.148571 -288.404718) (xy 339.100832 -288.421708) (xy 339.07603 -288.426906) (xy 339.05317 -288.431224)
			(xy 338.848192 -288.786316) (xy 338.856066 -288.80816) (xy 338.864719 -288.834566) (xy 338.874035 -288.889344)
			(xy 338.874608 -288.917126) (xy 339.155024 -288.917126) (xy 339.155532 -288.891219) (xy 339.163638 -288.840042)
			(xy 339.17965 -288.790763) (xy 339.203173 -288.744596) (xy 339.233629 -288.702677) (xy 339.270267 -288.666039)
			(xy 339.312186 -288.635583) (xy 339.358353 -288.61206) (xy 339.407632 -288.596048) (xy 339.458809 -288.587942)
			(xy 339.510623 -288.587942) (xy 339.5618 -288.596048) (xy 339.611079 -288.61206) (xy 339.657246 -288.635583)
			(xy 339.699165 -288.666039) (xy 339.735803 -288.702677) (xy 339.766259 -288.744596) (xy 339.789782 -288.790763)
			(xy 339.805794 -288.840042) (xy 339.8139 -288.891219) (xy 339.814408 -288.917126) (xy 340.094824 -288.917126)
			(xy 340.095349 -288.891782) (xy 340.103118 -288.841693) (xy 340.118461 -288.793383) (xy 340.141016 -288.74799)
			(xy 340.170252 -288.706584) (xy 340.205481 -288.67014) (xy 340.245872 -288.639516) (xy 340.290474 -288.615435)
			(xy 340.338236 -288.598463) (xy 340.363048 -288.593276) (xy 340.385908 -288.588958) (xy 340.59114 -288.233866)
			(xy 340.583266 -288.211768) (xy 340.574642 -288.185419) (xy 340.565317 -288.130773) (xy 340.564724 -288.103056)
			(xy 340.565232 -288.077149) (xy 340.573338 -288.025972) (xy 340.58935 -287.976693) (xy 340.612873 -287.930526)
			(xy 340.643329 -287.888607) (xy 340.679967 -287.851969) (xy 340.721886 -287.821513) (xy 340.768053 -287.79799)
			(xy 340.817332 -287.781978) (xy 340.868509 -287.773872) (xy 340.920323 -287.773872) (xy 340.9715 -287.781978)
			(xy 341.020779 -287.79799) (xy 341.066946 -287.821513) (xy 341.108865 -287.851969) (xy 341.145503 -287.888607)
			(xy 341.175959 -287.930526) (xy 341.199482 -287.976693) (xy 341.215494 -288.025972) (xy 341.2236 -288.077149)
			(xy 341.224108 -288.103056) (xy 341.223631 -288.128401) (xy 341.215851 -288.178491) (xy 341.200499 -288.2268)
			(xy 341.177936 -288.272192) (xy 341.148694 -288.313597) (xy 341.11346 -288.35004) (xy 341.073065 -288.380663)
			(xy 341.028461 -288.404744) (xy 340.980697 -288.421718) (xy 340.955884 -288.426906) (xy 340.933024 -288.431224)
			(xy 340.727792 -288.786316) (xy 340.735666 -288.808414) (xy 340.744307 -288.834758) (xy 340.753621 -288.889407)
			(xy 340.754208 -288.917126) (xy 341.034624 -288.917126) (xy 341.035132 -288.891219) (xy 341.043238 -288.840042)
			(xy 341.05925 -288.790763) (xy 341.082773 -288.744596) (xy 341.113229 -288.702677) (xy 341.149867 -288.666039)
			(xy 341.191786 -288.635583) (xy 341.237953 -288.61206) (xy 341.287232 -288.596048) (xy 341.338409 -288.587942)
			(xy 341.390223 -288.587942) (xy 341.4414 -288.596048) (xy 341.490679 -288.61206) (xy 341.536846 -288.635583)
			(xy 341.578765 -288.666039) (xy 341.615403 -288.702677) (xy 341.645859 -288.744596) (xy 341.669382 -288.790763)
			(xy 341.685394 -288.840042) (xy 341.6935 -288.891219) (xy 341.694008 -288.917126) (xy 341.974424 -288.917126)
			(xy 341.974949 -288.891782) (xy 341.982718 -288.841693) (xy 341.998061 -288.793383) (xy 342.020616 -288.74799)
			(xy 342.049852 -288.706584) (xy 342.085081 -288.67014) (xy 342.125472 -288.639516) (xy 342.170074 -288.615435)
			(xy 342.217836 -288.598463) (xy 342.242648 -288.593276) (xy 342.265508 -288.588958) (xy 342.47074 -288.233866)
			(xy 342.462866 -288.211768) (xy 342.454242 -288.185419) (xy 342.444917 -288.130773) (xy 342.444324 -288.103056)
			(xy 342.444832 -288.077149) (xy 342.452938 -288.025972) (xy 342.46895 -287.976693) (xy 342.492473 -287.930526)
			(xy 342.522929 -287.888607) (xy 342.559567 -287.851969) (xy 342.601486 -287.821513) (xy 342.647653 -287.79799)
			(xy 342.696932 -287.781978) (xy 342.748109 -287.773872) (xy 342.799923 -287.773872) (xy 342.8511 -287.781978)
			(xy 342.900379 -287.79799) (xy 342.946546 -287.821513) (xy 342.988465 -287.851969) (xy 343.025103 -287.888607)
			(xy 343.055559 -287.930526) (xy 343.079082 -287.976693) (xy 343.095094 -288.025972) (xy 343.1032 -288.077149)
			(xy 343.103708 -288.103056) (xy 343.103231 -288.128401) (xy 343.095451 -288.178491) (xy 343.080099 -288.2268)
			(xy 343.057536 -288.272192) (xy 343.028294 -288.313597) (xy 342.99306 -288.35004) (xy 342.952665 -288.380663)
			(xy 342.908061 -288.404744) (xy 342.860297 -288.421718) (xy 342.835484 -288.426906) (xy 342.812624 -288.431224)
			(xy 342.607392 -288.786316) (xy 342.615266 -288.808414) (xy 342.623907 -288.834758) (xy 342.633221 -288.889407)
			(xy 342.633808 -288.917126) (xy 342.914224 -288.917126) (xy 342.914732 -288.891219) (xy 342.922838 -288.840042)
			(xy 342.93885 -288.790763) (xy 342.962373 -288.744596) (xy 342.992829 -288.702677) (xy 343.029467 -288.666039)
			(xy 343.071386 -288.635583) (xy 343.117553 -288.61206) (xy 343.166832 -288.596048) (xy 343.218009 -288.587942)
			(xy 343.269823 -288.587942) (xy 343.321 -288.596048) (xy 343.370279 -288.61206) (xy 343.416446 -288.635583)
			(xy 343.458365 -288.666039) (xy 343.495003 -288.702677) (xy 343.525459 -288.744596) (xy 343.548982 -288.790763)
			(xy 343.564994 -288.840042) (xy 343.5731 -288.891219) (xy 343.573608 -288.917126) (xy 343.854024 -288.917126)
			(xy 343.854549 -288.891782) (xy 343.862318 -288.841693) (xy 343.877661 -288.793383) (xy 343.900216 -288.74799)
			(xy 343.929452 -288.706584) (xy 343.964681 -288.67014) (xy 344.005072 -288.639516) (xy 344.049674 -288.615435)
			(xy 344.097436 -288.598463) (xy 344.122248 -288.593276) (xy 344.145108 -288.588958) (xy 344.35034 -288.233866)
			(xy 344.342466 -288.211768) (xy 344.333842 -288.185419) (xy 344.324517 -288.130773) (xy 344.323924 -288.103056)
			(xy 344.324432 -288.077149) (xy 344.332538 -288.025972) (xy 344.34855 -287.976693) (xy 344.372073 -287.930526)
			(xy 344.402529 -287.888607) (xy 344.439167 -287.851969) (xy 344.481086 -287.821513) (xy 344.527253 -287.79799)
			(xy 344.576532 -287.781978) (xy 344.627709 -287.773872) (xy 344.679523 -287.773872) (xy 344.7307 -287.781978)
			(xy 344.779979 -287.79799) (xy 344.826146 -287.821513) (xy 344.868065 -287.851969) (xy 344.904703 -287.888607)
			(xy 344.935159 -287.930526) (xy 344.958682 -287.976693) (xy 344.974694 -288.025972) (xy 344.9828 -288.077149)
			(xy 344.983308 -288.103056) (xy 344.982831 -288.128401) (xy 344.975051 -288.178491) (xy 344.959699 -288.2268)
			(xy 344.937136 -288.272192) (xy 344.907894 -288.313597) (xy 344.87266 -288.35004) (xy 344.832265 -288.380663)
			(xy 344.787661 -288.404744) (xy 344.739897 -288.421718) (xy 344.715084 -288.426906) (xy 344.692224 -288.431224)
			(xy 344.486992 -288.786316) (xy 344.494866 -288.808414) (xy 344.503507 -288.834758) (xy 344.512821 -288.889407)
			(xy 344.513408 -288.917126) (xy 344.793824 -288.917126) (xy 344.794332 -288.891219) (xy 344.802438 -288.840042)
			(xy 344.81845 -288.790763) (xy 344.841973 -288.744596) (xy 344.872429 -288.702677) (xy 344.909067 -288.666039)
			(xy 344.950986 -288.635583) (xy 344.997153 -288.61206) (xy 345.046432 -288.596048) (xy 345.097609 -288.587942)
			(xy 345.149423 -288.587942) (xy 345.2006 -288.596048) (xy 345.249879 -288.61206) (xy 345.296046 -288.635583)
			(xy 345.337965 -288.666039) (xy 345.374603 -288.702677) (xy 345.405059 -288.744596) (xy 345.428582 -288.790763)
			(xy 345.444594 -288.840042) (xy 345.4527 -288.891219) (xy 345.453208 -288.917126) (xy 345.733624 -288.917126)
			(xy 345.734149 -288.891782) (xy 345.741918 -288.841693) (xy 345.757261 -288.793383) (xy 345.779816 -288.74799)
			(xy 345.809052 -288.706584) (xy 345.844281 -288.67014) (xy 345.884672 -288.639516) (xy 345.929274 -288.615435)
			(xy 345.977036 -288.598463) (xy 346.001848 -288.593276) (xy 346.024708 -288.588958) (xy 346.22994 -288.233866)
			(xy 346.222066 -288.211768) (xy 346.213442 -288.185419) (xy 346.204117 -288.130773) (xy 346.203524 -288.103056)
			(xy 346.204032 -288.077149) (xy 346.212138 -288.025972) (xy 346.22815 -287.976693) (xy 346.251673 -287.930526)
			(xy 346.282129 -287.888607) (xy 346.318767 -287.851969) (xy 346.360686 -287.821513) (xy 346.406853 -287.79799)
			(xy 346.456132 -287.781978) (xy 346.507309 -287.773872) (xy 346.559123 -287.773872) (xy 346.6103 -287.781978)
			(xy 346.659579 -287.79799) (xy 346.705746 -287.821513) (xy 346.747665 -287.851969) (xy 346.784303 -287.888607)
			(xy 346.814759 -287.930526) (xy 346.838282 -287.976693) (xy 346.854294 -288.025972) (xy 346.8624 -288.077149)
			(xy 346.862908 -288.103056) (xy 346.862431 -288.128401) (xy 346.854651 -288.178491) (xy 346.839299 -288.2268)
			(xy 346.816736 -288.272192) (xy 346.787494 -288.313597) (xy 346.75226 -288.35004) (xy 346.711865 -288.380663)
			(xy 346.667261 -288.404744) (xy 346.619497 -288.421718) (xy 346.594684 -288.426906) (xy 346.571824 -288.431224)
			(xy 346.366592 -288.786316) (xy 346.374466 -288.808414) (xy 346.383107 -288.834758) (xy 346.392421 -288.889407)
			(xy 346.393008 -288.917126) (xy 346.673424 -288.917126) (xy 346.673932 -288.891219) (xy 346.682038 -288.840042)
			(xy 346.69805 -288.790763) (xy 346.721573 -288.744596) (xy 346.752029 -288.702677) (xy 346.788667 -288.666039)
			(xy 346.830586 -288.635583) (xy 346.876753 -288.61206) (xy 346.926032 -288.596048) (xy 346.977209 -288.587942)
			(xy 347.029023 -288.587942) (xy 347.0802 -288.596048) (xy 347.129479 -288.61206) (xy 347.175646 -288.635583)
			(xy 347.217565 -288.666039) (xy 347.254203 -288.702677) (xy 347.284659 -288.744596) (xy 347.308182 -288.790763)
			(xy 347.324194 -288.840042) (xy 347.3323 -288.891219) (xy 347.332808 -288.917126) (xy 347.613224 -288.917126)
			(xy 347.613749 -288.891782) (xy 347.621518 -288.841693) (xy 347.636861 -288.793383) (xy 347.659416 -288.74799)
			(xy 347.688652 -288.706584) (xy 347.723881 -288.67014) (xy 347.764272 -288.639516) (xy 347.808874 -288.615435)
			(xy 347.856636 -288.598463) (xy 347.881448 -288.593276) (xy 347.904308 -288.588958) (xy 348.10954 -288.233866)
			(xy 348.101666 -288.211768) (xy 348.093042 -288.185419) (xy 348.083717 -288.130773) (xy 348.083124 -288.103056)
			(xy 348.083632 -288.077149) (xy 348.091738 -288.025972) (xy 348.10775 -287.976693) (xy 348.131273 -287.930526)
			(xy 348.161729 -287.888607) (xy 348.198367 -287.851969) (xy 348.240286 -287.821513) (xy 348.286453 -287.79799)
			(xy 348.335732 -287.781978) (xy 348.386909 -287.773872) (xy 348.438723 -287.773872) (xy 348.4899 -287.781978)
			(xy 348.539179 -287.79799) (xy 348.585346 -287.821513) (xy 348.627265 -287.851969) (xy 348.663903 -287.888607)
			(xy 348.694359 -287.930526) (xy 348.717882 -287.976693) (xy 348.733894 -288.025972) (xy 348.742 -288.077149)
			(xy 348.742508 -288.103056) (xy 348.742031 -288.128401) (xy 348.734251 -288.178491) (xy 348.718899 -288.2268)
			(xy 348.696336 -288.272192) (xy 348.667094 -288.313597) (xy 348.63186 -288.35004) (xy 348.591465 -288.380663)
			(xy 348.546861 -288.404744) (xy 348.499097 -288.421718) (xy 348.474284 -288.426906) (xy 348.451424 -288.431224)
			(xy 348.246192 -288.786316) (xy 348.254066 -288.808414) (xy 348.262707 -288.834758) (xy 348.272021 -288.889407)
			(xy 348.272608 -288.917126) (xy 348.553024 -288.917126) (xy 348.553532 -288.891219) (xy 348.561638 -288.840042)
			(xy 348.57765 -288.790763) (xy 348.601173 -288.744596) (xy 348.631629 -288.702677) (xy 348.668267 -288.666039)
			(xy 348.710186 -288.635583) (xy 348.756353 -288.61206) (xy 348.805632 -288.596048) (xy 348.856809 -288.587942)
			(xy 348.908623 -288.587942) (xy 348.9598 -288.596048) (xy 349.009079 -288.61206) (xy 349.055246 -288.635583)
			(xy 349.097165 -288.666039) (xy 349.133803 -288.702677) (xy 349.164259 -288.744596) (xy 349.187782 -288.790763)
			(xy 349.203794 -288.840042) (xy 349.2119 -288.891219) (xy 349.212408 -288.917126) (xy 349.492824 -288.917126)
			(xy 349.493349 -288.891782) (xy 349.501118 -288.841693) (xy 349.516461 -288.793383) (xy 349.539016 -288.74799)
			(xy 349.568252 -288.706584) (xy 349.603481 -288.67014) (xy 349.643872 -288.639516) (xy 349.688474 -288.615435)
			(xy 349.736236 -288.598463) (xy 349.761048 -288.593276) (xy 349.783908 -288.588958) (xy 349.98914 -288.233866)
			(xy 349.981266 -288.211768) (xy 349.972642 -288.185419) (xy 349.963317 -288.130773) (xy 349.962724 -288.103056)
			(xy 349.963232 -288.077149) (xy 349.971338 -288.025972) (xy 349.98735 -287.976693) (xy 350.010873 -287.930526)
			(xy 350.041329 -287.888607) (xy 350.077967 -287.851969) (xy 350.119886 -287.821513) (xy 350.166053 -287.79799)
			(xy 350.215332 -287.781978) (xy 350.266509 -287.773872) (xy 350.318323 -287.773872) (xy 350.3695 -287.781978)
			(xy 350.418779 -287.79799) (xy 350.464946 -287.821513) (xy 350.506865 -287.851969) (xy 350.543503 -287.888607)
			(xy 350.573959 -287.930526) (xy 350.597482 -287.976693) (xy 350.613494 -288.025972) (xy 350.6216 -288.077149)
			(xy 350.622108 -288.103056) (xy 350.621631 -288.128401) (xy 350.613851 -288.178491) (xy 350.598499 -288.2268)
			(xy 350.575936 -288.272192) (xy 350.546694 -288.313597) (xy 350.51146 -288.35004) (xy 350.471065 -288.380663)
			(xy 350.426461 -288.404744) (xy 350.378697 -288.421718) (xy 350.353884 -288.426906) (xy 350.331024 -288.431224)
			(xy 350.125792 -288.786316) (xy 350.133666 -288.808414) (xy 350.142307 -288.834758) (xy 350.151621 -288.889407)
			(xy 350.152208 -288.917126) (xy 350.432624 -288.917126) (xy 350.433132 -288.891219) (xy 350.441238 -288.840042)
			(xy 350.45725 -288.790763) (xy 350.480773 -288.744596) (xy 350.511229 -288.702677) (xy 350.547867 -288.666039)
			(xy 350.589786 -288.635583) (xy 350.635953 -288.61206) (xy 350.685232 -288.596048) (xy 350.736409 -288.587942)
			(xy 350.788223 -288.587942) (xy 350.8394 -288.596048) (xy 350.888679 -288.61206) (xy 350.934846 -288.635583)
			(xy 350.976765 -288.666039) (xy 351.013403 -288.702677) (xy 351.043859 -288.744596) (xy 351.067382 -288.790763)
			(xy 351.083394 -288.840042) (xy 351.0915 -288.891219) (xy 351.092008 -288.917126) (xy 351.372424 -288.917126)
			(xy 351.372949 -288.891782) (xy 351.380718 -288.841693) (xy 351.396061 -288.793383) (xy 351.418616 -288.74799)
			(xy 351.447852 -288.706584) (xy 351.483081 -288.67014) (xy 351.523472 -288.639516) (xy 351.568074 -288.615435)
			(xy 351.615836 -288.598463) (xy 351.640648 -288.593276) (xy 351.663508 -288.588958) (xy 351.86874 -288.233866)
			(xy 351.860866 -288.211768) (xy 351.852242 -288.185419) (xy 351.842917 -288.130773) (xy 351.842324 -288.103056)
			(xy 351.842832 -288.077149) (xy 351.850938 -288.025972) (xy 351.86695 -287.976693) (xy 351.890473 -287.930526)
			(xy 351.920929 -287.888607) (xy 351.957567 -287.851969) (xy 351.999486 -287.821513) (xy 352.045653 -287.79799)
			(xy 352.094932 -287.781978) (xy 352.146109 -287.773872) (xy 352.197923 -287.773872) (xy 352.2491 -287.781978)
			(xy 352.298379 -287.79799) (xy 352.344546 -287.821513) (xy 352.386465 -287.851969) (xy 352.423103 -287.888607)
			(xy 352.453559 -287.930526) (xy 352.477082 -287.976693) (xy 352.493094 -288.025972) (xy 352.5012 -288.077149)
			(xy 352.501708 -288.103056) (xy 368.758724 -288.103056) (xy 368.759232 -288.077149) (xy 368.767338 -288.025972)
			(xy 368.78335 -287.976693) (xy 368.806873 -287.930526) (xy 368.837329 -287.888607) (xy 368.873967 -287.851969)
			(xy 368.915886 -287.821513) (xy 368.962053 -287.79799) (xy 369.011332 -287.781978) (xy 369.062509 -287.773872)
			(xy 369.114323 -287.773872) (xy 369.1655 -287.781978) (xy 369.214779 -287.79799) (xy 369.260946 -287.821513)
			(xy 369.302865 -287.851969) (xy 369.339503 -287.888607) (xy 369.369959 -287.930526) (xy 369.393482 -287.976693)
			(xy 369.409494 -288.025972) (xy 369.4176 -288.077149) (xy 369.418108 -288.103056) (xy 370.638324 -288.103056)
			(xy 370.638832 -288.077149) (xy 370.646938 -288.025972) (xy 370.66295 -287.976693) (xy 370.686473 -287.930526)
			(xy 370.716929 -287.888607) (xy 370.753567 -287.851969) (xy 370.795486 -287.821513) (xy 370.841653 -287.79799)
			(xy 370.890932 -287.781978) (xy 370.942109 -287.773872) (xy 370.993923 -287.773872) (xy 371.0451 -287.781978)
			(xy 371.094379 -287.79799) (xy 371.140546 -287.821513) (xy 371.182465 -287.851969) (xy 371.219103 -287.888607)
			(xy 371.249559 -287.930526) (xy 371.273082 -287.976693) (xy 371.289094 -288.025972) (xy 371.2972 -288.077149)
			(xy 371.297708 -288.103056) (xy 372.517924 -288.103056) (xy 372.518432 -288.077149) (xy 372.526538 -288.025972)
			(xy 372.54255 -287.976693) (xy 372.566073 -287.930526) (xy 372.596529 -287.888607) (xy 372.633167 -287.851969)
			(xy 372.675086 -287.821513) (xy 372.721253 -287.79799) (xy 372.770532 -287.781978) (xy 372.821709 -287.773872)
			(xy 372.873523 -287.773872) (xy 372.9247 -287.781978) (xy 372.973979 -287.79799) (xy 373.020146 -287.821513)
			(xy 373.062065 -287.851969) (xy 373.098703 -287.888607) (xy 373.129159 -287.930526) (xy 373.152682 -287.976693)
			(xy 373.168694 -288.025972) (xy 373.1768 -288.077149) (xy 373.177308 -288.103056) (xy 374.397524 -288.103056)
			(xy 374.398032 -288.077149) (xy 374.406138 -288.025972) (xy 374.42215 -287.976693) (xy 374.445673 -287.930526)
			(xy 374.476129 -287.888607) (xy 374.512767 -287.851969) (xy 374.554686 -287.821513) (xy 374.600853 -287.79799)
			(xy 374.650132 -287.781978) (xy 374.701309 -287.773872) (xy 374.753123 -287.773872) (xy 374.8043 -287.781978)
			(xy 374.853579 -287.79799) (xy 374.899746 -287.821513) (xy 374.941665 -287.851969) (xy 374.978303 -287.888607)
			(xy 375.008759 -287.930526) (xy 375.032282 -287.976693) (xy 375.048294 -288.025972) (xy 375.0564 -288.077149)
			(xy 375.056908 -288.103056) (xy 376.277124 -288.103056) (xy 376.277632 -288.077149) (xy 376.285738 -288.025972)
			(xy 376.30175 -287.976693) (xy 376.325273 -287.930526) (xy 376.355729 -287.888607) (xy 376.392367 -287.851969)
			(xy 376.434286 -287.821513) (xy 376.480453 -287.79799) (xy 376.529732 -287.781978) (xy 376.580909 -287.773872)
			(xy 376.632723 -287.773872) (xy 376.6839 -287.781978) (xy 376.733179 -287.79799) (xy 376.779346 -287.821513)
			(xy 376.821265 -287.851969) (xy 376.857903 -287.888607) (xy 376.888359 -287.930526) (xy 376.911882 -287.976693)
			(xy 376.927894 -288.025972) (xy 376.936 -288.077149) (xy 376.936508 -288.103056) (xy 378.156724 -288.103056)
			(xy 378.157232 -288.077149) (xy 378.165338 -288.025972) (xy 378.18135 -287.976693) (xy 378.204873 -287.930526)
			(xy 378.235329 -287.888607) (xy 378.271967 -287.851969) (xy 378.313886 -287.821513) (xy 378.360053 -287.79799)
			(xy 378.409332 -287.781978) (xy 378.460509 -287.773872) (xy 378.512323 -287.773872) (xy 378.5635 -287.781978)
			(xy 378.612779 -287.79799) (xy 378.658946 -287.821513) (xy 378.700865 -287.851969) (xy 378.737503 -287.888607)
			(xy 378.767959 -287.930526) (xy 378.791482 -287.976693) (xy 378.807494 -288.025972) (xy 378.8156 -288.077149)
			(xy 378.816108 -288.103056) (xy 380.036324 -288.103056) (xy 380.036832 -288.077149) (xy 380.044938 -288.025972)
			(xy 380.06095 -287.976693) (xy 380.084473 -287.930526) (xy 380.114929 -287.888607) (xy 380.151567 -287.851969)
			(xy 380.193486 -287.821513) (xy 380.239653 -287.79799) (xy 380.288932 -287.781978) (xy 380.340109 -287.773872)
			(xy 380.391923 -287.773872) (xy 380.4431 -287.781978) (xy 380.492379 -287.79799) (xy 380.538546 -287.821513)
			(xy 380.580465 -287.851969) (xy 380.617103 -287.888607) (xy 380.647559 -287.930526) (xy 380.671082 -287.976693)
			(xy 380.687094 -288.025972) (xy 380.6952 -288.077149) (xy 380.695708 -288.103056) (xy 382.855724 -288.103056)
			(xy 382.856232 -288.077149) (xy 382.864338 -288.025972) (xy 382.88035 -287.976693) (xy 382.903873 -287.930526)
			(xy 382.934329 -287.888607) (xy 382.970967 -287.851969) (xy 383.012886 -287.821513) (xy 383.059053 -287.79799)
			(xy 383.108332 -287.781978) (xy 383.159509 -287.773872) (xy 383.211323 -287.773872) (xy 383.2625 -287.781978)
			(xy 383.311779 -287.79799) (xy 383.357946 -287.821513) (xy 383.399865 -287.851969) (xy 383.436503 -287.888607)
			(xy 383.466959 -287.930526) (xy 383.490482 -287.976693) (xy 383.506494 -288.025972) (xy 383.5146 -288.077149)
			(xy 383.515108 -288.103056) (xy 383.514503 -288.130773) (xy 383.505187 -288.185419) (xy 383.496566 -288.211768)
			(xy 383.488692 -288.233866) (xy 383.693924 -288.588958) (xy 383.716784 -288.593276) (xy 383.741606 -288.598437)
			(xy 383.789384 -288.615395) (xy 383.834001 -288.639469) (xy 383.874406 -288.67009) (xy 383.909646 -288.706538)
			(xy 383.93889 -288.747952) (xy 383.961447 -288.793355) (xy 383.976786 -288.841676) (xy 383.984545 -288.891777)
			(xy 383.985008 -288.917126) (xy 383.9845 -288.943033) (xy 383.976394 -288.99421) (xy 383.960382 -289.043489)
			(xy 383.936859 -289.089656) (xy 383.906403 -289.131575) (xy 383.869765 -289.168213) (xy 383.827846 -289.198669)
			(xy 383.781679 -289.222192) (xy 383.7324 -289.238204) (xy 383.681223 -289.24631) (xy 383.629409 -289.24631)
			(xy 383.578232 -289.238204) (xy 383.528953 -289.222192) (xy 383.482786 -289.198669) (xy 383.440867 -289.168213)
			(xy 383.404229 -289.131575) (xy 383.373773 -289.089656) (xy 383.35025 -289.043489) (xy 383.334238 -288.99421)
			(xy 383.326132 -288.943033) (xy 383.325624 -288.917126) (xy 383.326223 -288.889409) (xy 383.335543 -288.834762)
			(xy 383.344166 -288.808414) (xy 383.35204 -288.786316) (xy 383.146808 -288.431224) (xy 383.123948 -288.426906)
			(xy 383.099127 -288.421739) (xy 383.051348 -288.404784) (xy 383.006729 -288.380713) (xy 382.966322 -288.350092)
			(xy 382.931082 -288.313646) (xy 382.901838 -288.272232) (xy 382.879281 -288.226828) (xy 382.863943 -288.178506)
			(xy 382.856186 -288.128405) (xy 382.855724 -288.103056) (xy 380.695708 -288.103056) (xy 380.695103 -288.130773)
			(xy 380.685787 -288.185419) (xy 380.677166 -288.211768) (xy 380.669546 -288.233866) (xy 380.874524 -288.588958)
			(xy 380.897384 -288.593276) (xy 380.922206 -288.598437) (xy 380.969984 -288.615395) (xy 381.014601 -288.639469)
			(xy 381.055006 -288.67009) (xy 381.090246 -288.706538) (xy 381.11949 -288.747952) (xy 381.142047 -288.793355)
			(xy 381.157386 -288.841676) (xy 381.165145 -288.891777) (xy 381.165608 -288.917126) (xy 381.1651 -288.943033)
			(xy 381.156994 -288.99421) (xy 381.140982 -289.043489) (xy 381.117459 -289.089656) (xy 381.087003 -289.131575)
			(xy 381.050365 -289.168213) (xy 381.008446 -289.198669) (xy 380.962279 -289.222192) (xy 380.913 -289.238204)
			(xy 380.861823 -289.24631) (xy 380.810009 -289.24631) (xy 380.758832 -289.238204) (xy 380.709553 -289.222192)
			(xy 380.663386 -289.198669) (xy 380.621467 -289.168213) (xy 380.584829 -289.131575) (xy 380.554373 -289.089656)
			(xy 380.53085 -289.043489) (xy 380.514838 -288.99421) (xy 380.506732 -288.943033) (xy 380.506224 -288.917126)
			(xy 380.506823 -288.889409) (xy 380.516143 -288.834762) (xy 380.524766 -288.808414) (xy 380.53264 -288.786316)
			(xy 380.327662 -288.431224) (xy 380.304802 -288.426906) (xy 380.279961 -288.421779) (xy 380.232152 -288.40484)
			(xy 380.187502 -288.380778) (xy 380.147063 -288.350162) (xy 380.111791 -288.313713) (xy 380.082517 -288.272293)
			(xy 380.059933 -288.226877) (xy 380.044571 -288.178538) (xy 380.036794 -288.128417) (xy 380.036324 -288.103056)
			(xy 378.816108 -288.103056) (xy 378.815503 -288.130773) (xy 378.806187 -288.185419) (xy 378.797566 -288.211768)
			(xy 378.789946 -288.233866) (xy 378.994924 -288.588958) (xy 379.017784 -288.593276) (xy 379.042606 -288.598437)
			(xy 379.090384 -288.615395) (xy 379.135001 -288.639469) (xy 379.175406 -288.67009) (xy 379.210646 -288.706538)
			(xy 379.23989 -288.747952) (xy 379.262447 -288.793355) (xy 379.277786 -288.841676) (xy 379.285545 -288.891777)
			(xy 379.286008 -288.917126) (xy 379.2855 -288.943033) (xy 379.277394 -288.99421) (xy 379.261382 -289.043489)
			(xy 379.237859 -289.089656) (xy 379.207403 -289.131575) (xy 379.170765 -289.168213) (xy 379.128846 -289.198669)
			(xy 379.082679 -289.222192) (xy 379.0334 -289.238204) (xy 378.982223 -289.24631) (xy 378.930409 -289.24631)
			(xy 378.879232 -289.238204) (xy 378.829953 -289.222192) (xy 378.783786 -289.198669) (xy 378.741867 -289.168213)
			(xy 378.705229 -289.131575) (xy 378.674773 -289.089656) (xy 378.65125 -289.043489) (xy 378.635238 -288.99421)
			(xy 378.627132 -288.943033) (xy 378.626624 -288.917126) (xy 378.627223 -288.889409) (xy 378.636543 -288.834762)
			(xy 378.645166 -288.808414) (xy 378.65304 -288.786316) (xy 378.448062 -288.431224) (xy 378.425202 -288.426906)
			(xy 378.400361 -288.421779) (xy 378.352552 -288.40484) (xy 378.307902 -288.380778) (xy 378.267463 -288.350162)
			(xy 378.232191 -288.313713) (xy 378.202917 -288.272293) (xy 378.180333 -288.226877) (xy 378.164971 -288.178538)
			(xy 378.157194 -288.128417) (xy 378.156724 -288.103056) (xy 376.936508 -288.103056) (xy 376.935903 -288.130773)
			(xy 376.926587 -288.185419) (xy 376.917966 -288.211768) (xy 376.910346 -288.233866) (xy 377.115324 -288.588958)
			(xy 377.138184 -288.593276) (xy 377.163006 -288.598437) (xy 377.210784 -288.615395) (xy 377.255401 -288.639469)
			(xy 377.295806 -288.67009) (xy 377.331046 -288.706538) (xy 377.36029 -288.747952) (xy 377.382847 -288.793355)
			(xy 377.398186 -288.841676) (xy 377.405945 -288.891777) (xy 377.406408 -288.917126) (xy 377.4059 -288.943033)
			(xy 377.397794 -288.99421) (xy 377.381782 -289.043489) (xy 377.358259 -289.089656) (xy 377.327803 -289.131575)
			(xy 377.291165 -289.168213) (xy 377.249246 -289.198669) (xy 377.203079 -289.222192) (xy 377.1538 -289.238204)
			(xy 377.102623 -289.24631) (xy 377.050809 -289.24631) (xy 376.999632 -289.238204) (xy 376.950353 -289.222192)
			(xy 376.904186 -289.198669) (xy 376.862267 -289.168213) (xy 376.825629 -289.131575) (xy 376.795173 -289.089656)
			(xy 376.77165 -289.043489) (xy 376.755638 -288.99421) (xy 376.747532 -288.943033) (xy 376.747024 -288.917126)
			(xy 376.747623 -288.889409) (xy 376.756943 -288.834762) (xy 376.765566 -288.808414) (xy 376.77344 -288.786316)
			(xy 376.568462 -288.431224) (xy 376.545602 -288.426906) (xy 376.520761 -288.421779) (xy 376.472952 -288.40484)
			(xy 376.428302 -288.380778) (xy 376.387863 -288.350162) (xy 376.352591 -288.313713) (xy 376.323317 -288.272293)
			(xy 376.300733 -288.226877) (xy 376.285371 -288.178538) (xy 376.277594 -288.128417) (xy 376.277124 -288.103056)
			(xy 375.056908 -288.103056) (xy 375.056303 -288.130773) (xy 375.046987 -288.185419) (xy 375.038366 -288.211768)
			(xy 375.030746 -288.233866) (xy 375.235724 -288.588958) (xy 375.258584 -288.593276) (xy 375.283406 -288.598437)
			(xy 375.331184 -288.615395) (xy 375.375801 -288.639469) (xy 375.416206 -288.67009) (xy 375.451446 -288.706538)
			(xy 375.48069 -288.747952) (xy 375.503247 -288.793355) (xy 375.518586 -288.841676) (xy 375.526345 -288.891777)
			(xy 375.526808 -288.917126) (xy 375.5263 -288.943033) (xy 375.518194 -288.99421) (xy 375.502182 -289.043489)
			(xy 375.478659 -289.089656) (xy 375.448203 -289.131575) (xy 375.411565 -289.168213) (xy 375.369646 -289.198669)
			(xy 375.323479 -289.222192) (xy 375.2742 -289.238204) (xy 375.223023 -289.24631) (xy 375.171209 -289.24631)
			(xy 375.120032 -289.238204) (xy 375.070753 -289.222192) (xy 375.024586 -289.198669) (xy 374.982667 -289.168213)
			(xy 374.946029 -289.131575) (xy 374.915573 -289.089656) (xy 374.89205 -289.043489) (xy 374.876038 -288.99421)
			(xy 374.867932 -288.943033) (xy 374.867424 -288.917126) (xy 374.868023 -288.889409) (xy 374.877343 -288.834762)
			(xy 374.885966 -288.808414) (xy 374.89384 -288.786316) (xy 374.688862 -288.431224) (xy 374.666002 -288.426906)
			(xy 374.641161 -288.421779) (xy 374.593352 -288.40484) (xy 374.548702 -288.380778) (xy 374.508263 -288.350162)
			(xy 374.472991 -288.313713) (xy 374.443717 -288.272293) (xy 374.421133 -288.226877) (xy 374.405771 -288.178538)
			(xy 374.397994 -288.128417) (xy 374.397524 -288.103056) (xy 373.177308 -288.103056) (xy 373.176703 -288.130773)
			(xy 373.167387 -288.185419) (xy 373.158766 -288.211768) (xy 373.151146 -288.233866) (xy 373.356124 -288.588958)
			(xy 373.378984 -288.593276) (xy 373.403806 -288.598437) (xy 373.451584 -288.615395) (xy 373.496201 -288.639469)
			(xy 373.536606 -288.67009) (xy 373.571846 -288.706538) (xy 373.60109 -288.747952) (xy 373.623647 -288.793355)
			(xy 373.638986 -288.841676) (xy 373.646745 -288.891777) (xy 373.647208 -288.917126) (xy 373.6467 -288.943033)
			(xy 373.638594 -288.99421) (xy 373.622582 -289.043489) (xy 373.599059 -289.089656) (xy 373.568603 -289.131575)
			(xy 373.531965 -289.168213) (xy 373.490046 -289.198669) (xy 373.443879 -289.222192) (xy 373.3946 -289.238204)
			(xy 373.343423 -289.24631) (xy 373.291609 -289.24631) (xy 373.240432 -289.238204) (xy 373.191153 -289.222192)
			(xy 373.144986 -289.198669) (xy 373.103067 -289.168213) (xy 373.066429 -289.131575) (xy 373.035973 -289.089656)
			(xy 373.01245 -289.043489) (xy 372.996438 -288.99421) (xy 372.988332 -288.943033) (xy 372.987824 -288.917126)
			(xy 372.988423 -288.889409) (xy 372.997743 -288.834762) (xy 373.006366 -288.808414) (xy 373.01424 -288.786316)
			(xy 372.809262 -288.431224) (xy 372.786402 -288.426906) (xy 372.761561 -288.421779) (xy 372.713752 -288.40484)
			(xy 372.669102 -288.380778) (xy 372.628663 -288.350162) (xy 372.593391 -288.313713) (xy 372.564117 -288.272293)
			(xy 372.541533 -288.226877) (xy 372.526171 -288.178538) (xy 372.518394 -288.128417) (xy 372.517924 -288.103056)
			(xy 371.297708 -288.103056) (xy 371.297103 -288.130773) (xy 371.287787 -288.185419) (xy 371.279166 -288.211768)
			(xy 371.271546 -288.233866) (xy 371.476524 -288.588958) (xy 371.499384 -288.593276) (xy 371.524206 -288.598437)
			(xy 371.571984 -288.615395) (xy 371.616601 -288.639469) (xy 371.657006 -288.67009) (xy 371.692246 -288.706538)
			(xy 371.72149 -288.747952) (xy 371.744047 -288.793355) (xy 371.759386 -288.841676) (xy 371.767145 -288.891777)
			(xy 371.767608 -288.917126) (xy 371.7671 -288.943033) (xy 371.758994 -288.99421) (xy 371.742982 -289.043489)
			(xy 371.719459 -289.089656) (xy 371.689003 -289.131575) (xy 371.652365 -289.168213) (xy 371.610446 -289.198669)
			(xy 371.564279 -289.222192) (xy 371.515 -289.238204) (xy 371.463823 -289.24631) (xy 371.412009 -289.24631)
			(xy 371.360832 -289.238204) (xy 371.311553 -289.222192) (xy 371.265386 -289.198669) (xy 371.223467 -289.168213)
			(xy 371.186829 -289.131575) (xy 371.156373 -289.089656) (xy 371.13285 -289.043489) (xy 371.116838 -288.99421)
			(xy 371.108732 -288.943033) (xy 371.108224 -288.917126) (xy 371.108823 -288.889409) (xy 371.118143 -288.834762)
			(xy 371.126766 -288.808414) (xy 371.13464 -288.786316) (xy 370.929662 -288.431224) (xy 370.906802 -288.426906)
			(xy 370.881961 -288.421779) (xy 370.834152 -288.40484) (xy 370.789502 -288.380778) (xy 370.749063 -288.350162)
			(xy 370.713791 -288.313713) (xy 370.684517 -288.272293) (xy 370.661933 -288.226877) (xy 370.646571 -288.178538)
			(xy 370.638794 -288.128417) (xy 370.638324 -288.103056) (xy 369.418108 -288.103056) (xy 369.417503 -288.130773)
			(xy 369.408187 -288.185419) (xy 369.399566 -288.211768) (xy 369.391692 -288.233866) (xy 369.596924 -288.588958)
			(xy 369.619784 -288.593276) (xy 369.644606 -288.598437) (xy 369.692384 -288.615395) (xy 369.737001 -288.639469)
			(xy 369.777406 -288.67009) (xy 369.812646 -288.706538) (xy 369.84189 -288.747952) (xy 369.864447 -288.793355)
			(xy 369.879786 -288.841676) (xy 369.887545 -288.891777) (xy 369.888008 -288.917126) (xy 369.8875 -288.943033)
			(xy 369.879394 -288.99421) (xy 369.863382 -289.043489) (xy 369.839859 -289.089656) (xy 369.809403 -289.131575)
			(xy 369.772765 -289.168213) (xy 369.730846 -289.198669) (xy 369.684679 -289.222192) (xy 369.6354 -289.238204)
			(xy 369.584223 -289.24631) (xy 369.532409 -289.24631) (xy 369.481232 -289.238204) (xy 369.431953 -289.222192)
			(xy 369.385786 -289.198669) (xy 369.343867 -289.168213) (xy 369.307229 -289.131575) (xy 369.276773 -289.089656)
			(xy 369.25325 -289.043489) (xy 369.237238 -288.99421) (xy 369.229132 -288.943033) (xy 369.228624 -288.917126)
			(xy 369.229223 -288.889409) (xy 369.238543 -288.834762) (xy 369.247166 -288.808414) (xy 369.25504 -288.786316)
			(xy 369.049808 -288.431224) (xy 369.026948 -288.426906) (xy 369.002127 -288.421739) (xy 368.954348 -288.404784)
			(xy 368.909729 -288.380713) (xy 368.869322 -288.350092) (xy 368.834082 -288.313646) (xy 368.804838 -288.272232)
			(xy 368.782281 -288.226828) (xy 368.766943 -288.178506) (xy 368.759186 -288.128405) (xy 368.758724 -288.103056)
			(xy 352.501708 -288.103056) (xy 352.501231 -288.128401) (xy 352.493451 -288.178491) (xy 352.478099 -288.2268)
			(xy 352.455536 -288.272192) (xy 352.426294 -288.313597) (xy 352.39106 -288.35004) (xy 352.350665 -288.380663)
			(xy 352.306061 -288.404744) (xy 352.258297 -288.421718) (xy 352.233484 -288.426906) (xy 352.210624 -288.431224)
			(xy 352.005392 -288.786316) (xy 352.013266 -288.808414) (xy 352.021907 -288.834758) (xy 352.031221 -288.889407)
			(xy 352.031808 -288.917126) (xy 352.0313 -288.943033) (xy 352.023194 -288.99421) (xy 352.007182 -289.043489)
			(xy 351.983659 -289.089656) (xy 351.953203 -289.131575) (xy 351.916565 -289.168213) (xy 351.874646 -289.198669)
			(xy 351.828479 -289.222192) (xy 351.7792 -289.238204) (xy 351.728023 -289.24631) (xy 351.676209 -289.24631)
			(xy 351.625032 -289.238204) (xy 351.575753 -289.222192) (xy 351.529586 -289.198669) (xy 351.487667 -289.168213)
			(xy 351.451029 -289.131575) (xy 351.420573 -289.089656) (xy 351.39705 -289.043489) (xy 351.381038 -288.99421)
			(xy 351.372932 -288.943033) (xy 351.372424 -288.917126) (xy 351.092008 -288.917126) (xy 351.091589 -288.940067)
			(xy 351.08516 -288.985498) (xy 351.072513 -289.029604) (xy 351.06356 -289.05073) (xy 351.053654 -289.073336)
			(xy 351.267522 -289.478466) (xy 351.291652 -289.483038) (xy 351.316573 -289.488138) (xy 351.364584 -289.504939)
			(xy 351.409443 -289.528919) (xy 351.450084 -289.559507) (xy 351.485541 -289.595978) (xy 351.514973 -289.637465)
			(xy 351.537679 -289.682981) (xy 351.553121 -289.731446) (xy 351.560931 -289.781709) (xy 351.5614 -289.807142)
			(xy 367.818924 -289.807142) (xy 367.819411 -289.781712) (xy 367.827244 -289.73146) (xy 367.842699 -289.683005)
			(xy 367.86541 -289.637498) (xy 367.894839 -289.596018) (xy 367.930287 -289.559547) (xy 367.970914 -289.528951)
			(xy 368.015757 -289.504956) (xy 368.063753 -289.48813) (xy 368.088672 -289.483038) (xy 368.112802 -289.478466)
			(xy 368.327178 -289.073082) (xy 368.317272 -289.050476) (xy 368.308309 -289.029398) (xy 368.295664 -288.985377)
			(xy 368.289249 -288.940026) (xy 368.288824 -288.917126) (xy 368.289332 -288.891219) (xy 368.297438 -288.840042)
			(xy 368.31345 -288.790763) (xy 368.336973 -288.744596) (xy 368.367429 -288.702677) (xy 368.404067 -288.666039)
			(xy 368.445986 -288.635583) (xy 368.492153 -288.61206) (xy 368.541432 -288.596048) (xy 368.592609 -288.587942)
			(xy 368.644423 -288.587942) (xy 368.6956 -288.596048) (xy 368.744879 -288.61206) (xy 368.791046 -288.635583)
			(xy 368.832965 -288.666039) (xy 368.869603 -288.702677) (xy 368.900059 -288.744596) (xy 368.923582 -288.790763)
			(xy 368.939594 -288.840042) (xy 368.9477 -288.891219) (xy 368.948208 -288.917126) (xy 368.947753 -288.942575)
			(xy 368.939949 -288.992871) (xy 368.924499 -289.041367) (xy 368.901771 -289.086909) (xy 368.872307 -289.128411)
			(xy 368.836809 -289.164887) (xy 368.796121 -289.195466) (xy 368.751213 -289.21942) (xy 368.703153 -289.23618)
			(xy 368.678206 -289.24123) (xy 368.654076 -289.245802) (xy 368.4397 -289.651186) (xy 368.449606 -289.673792)
			(xy 368.458528 -289.694877) (xy 368.471078 -289.738907) (xy 368.47741 -289.78425) (xy 368.4778 -289.807142)
			(xy 369.698524 -289.807142) (xy 369.699011 -289.781712) (xy 369.706844 -289.73146) (xy 369.722299 -289.683005)
			(xy 369.74501 -289.637498) (xy 369.774439 -289.596018) (xy 369.809887 -289.559547) (xy 369.850514 -289.528951)
			(xy 369.895357 -289.504956) (xy 369.943353 -289.48813) (xy 369.968272 -289.483038) (xy 369.992402 -289.478466)
			(xy 370.206778 -289.073082) (xy 370.196872 -289.050476) (xy 370.187909 -289.029398) (xy 370.175264 -288.985377)
			(xy 370.168849 -288.940026) (xy 370.168424 -288.917126) (xy 370.168932 -288.891219) (xy 370.177038 -288.840042)
			(xy 370.19305 -288.790763) (xy 370.216573 -288.744596) (xy 370.247029 -288.702677) (xy 370.283667 -288.666039)
			(xy 370.325586 -288.635583) (xy 370.371753 -288.61206) (xy 370.421032 -288.596048) (xy 370.472209 -288.587942)
			(xy 370.524023 -288.587942) (xy 370.5752 -288.596048) (xy 370.624479 -288.61206) (xy 370.670646 -288.635583)
			(xy 370.712565 -288.666039) (xy 370.749203 -288.702677) (xy 370.779659 -288.744596) (xy 370.803182 -288.790763)
			(xy 370.819194 -288.840042) (xy 370.8273 -288.891219) (xy 370.827808 -288.917126) (xy 370.827353 -288.942575)
			(xy 370.819549 -288.992871) (xy 370.804099 -289.041367) (xy 370.781371 -289.086909) (xy 370.751907 -289.128411)
			(xy 370.716409 -289.164887) (xy 370.675721 -289.195466) (xy 370.630813 -289.21942) (xy 370.582753 -289.23618)
			(xy 370.557806 -289.24123) (xy 370.533676 -289.245802) (xy 370.3193 -289.651186) (xy 370.329206 -289.673792)
			(xy 370.338128 -289.694877) (xy 370.350678 -289.738907) (xy 370.35701 -289.78425) (xy 370.3574 -289.807142)
			(xy 371.578124 -289.807142) (xy 371.578611 -289.781712) (xy 371.586444 -289.73146) (xy 371.601899 -289.683005)
			(xy 371.62461 -289.637498) (xy 371.654039 -289.596018) (xy 371.689487 -289.559547) (xy 371.730114 -289.528951)
			(xy 371.774957 -289.504956) (xy 371.822953 -289.48813) (xy 371.847872 -289.483038) (xy 371.872002 -289.478466)
			(xy 372.086378 -289.073082) (xy 372.076472 -289.050476) (xy 372.067509 -289.029398) (xy 372.054864 -288.985377)
			(xy 372.048449 -288.940026) (xy 372.048024 -288.917126) (xy 372.048532 -288.891219) (xy 372.056638 -288.840042)
			(xy 372.07265 -288.790763) (xy 372.096173 -288.744596) (xy 372.126629 -288.702677) (xy 372.163267 -288.666039)
			(xy 372.205186 -288.635583) (xy 372.251353 -288.61206) (xy 372.300632 -288.596048) (xy 372.351809 -288.587942)
			(xy 372.403623 -288.587942) (xy 372.4548 -288.596048) (xy 372.504079 -288.61206) (xy 372.550246 -288.635583)
			(xy 372.592165 -288.666039) (xy 372.628803 -288.702677) (xy 372.659259 -288.744596) (xy 372.682782 -288.790763)
			(xy 372.698794 -288.840042) (xy 372.7069 -288.891219) (xy 372.707408 -288.917126) (xy 372.706953 -288.942575)
			(xy 372.699149 -288.992871) (xy 372.683699 -289.041367) (xy 372.660971 -289.086909) (xy 372.631507 -289.128411)
			(xy 372.596009 -289.164887) (xy 372.555321 -289.195466) (xy 372.510413 -289.21942) (xy 372.462353 -289.23618)
			(xy 372.437406 -289.24123) (xy 372.413276 -289.245802) (xy 372.1989 -289.651186) (xy 372.208806 -289.673792)
			(xy 372.217728 -289.694877) (xy 372.230278 -289.738907) (xy 372.23661 -289.78425) (xy 372.237 -289.807142)
			(xy 373.457724 -289.807142) (xy 373.458211 -289.781712) (xy 373.466044 -289.73146) (xy 373.481499 -289.683005)
			(xy 373.50421 -289.637498) (xy 373.533639 -289.596018) (xy 373.569087 -289.559547) (xy 373.609714 -289.528951)
			(xy 373.654557 -289.504956) (xy 373.702553 -289.48813) (xy 373.727472 -289.483038) (xy 373.751602 -289.478466)
			(xy 373.965978 -289.073082) (xy 373.956072 -289.050476) (xy 373.947109 -289.029398) (xy 373.934464 -288.985377)
			(xy 373.928049 -288.940026) (xy 373.927624 -288.917126) (xy 373.928132 -288.891219) (xy 373.936238 -288.840042)
			(xy 373.95225 -288.790763) (xy 373.975773 -288.744596) (xy 374.006229 -288.702677) (xy 374.042867 -288.666039)
			(xy 374.084786 -288.635583) (xy 374.130953 -288.61206) (xy 374.180232 -288.596048) (xy 374.231409 -288.587942)
			(xy 374.283223 -288.587942) (xy 374.3344 -288.596048) (xy 374.383679 -288.61206) (xy 374.429846 -288.635583)
			(xy 374.471765 -288.666039) (xy 374.508403 -288.702677) (xy 374.538859 -288.744596) (xy 374.562382 -288.790763)
			(xy 374.578394 -288.840042) (xy 374.5865 -288.891219) (xy 374.587008 -288.917126) (xy 374.586553 -288.942575)
			(xy 374.578749 -288.992871) (xy 374.563299 -289.041367) (xy 374.540571 -289.086909) (xy 374.511107 -289.128411)
			(xy 374.475609 -289.164887) (xy 374.434921 -289.195466) (xy 374.390013 -289.21942) (xy 374.341953 -289.23618)
			(xy 374.317006 -289.24123) (xy 374.292876 -289.245802) (xy 374.0785 -289.651186) (xy 374.088406 -289.673792)
			(xy 374.097328 -289.694877) (xy 374.109878 -289.738907) (xy 374.11621 -289.78425) (xy 374.1166 -289.807142)
			(xy 375.337324 -289.807142) (xy 375.337811 -289.781712) (xy 375.345644 -289.73146) (xy 375.361099 -289.683005)
			(xy 375.38381 -289.637498) (xy 375.413239 -289.596018) (xy 375.448687 -289.559547) (xy 375.489314 -289.528951)
			(xy 375.534157 -289.504956) (xy 375.582153 -289.48813) (xy 375.607072 -289.483038) (xy 375.631202 -289.478466)
			(xy 375.845578 -289.073082) (xy 375.835672 -289.050476) (xy 375.826709 -289.029398) (xy 375.814064 -288.985377)
			(xy 375.807649 -288.940026) (xy 375.807224 -288.917126) (xy 375.807732 -288.891219) (xy 375.815838 -288.840042)
			(xy 375.83185 -288.790763) (xy 375.855373 -288.744596) (xy 375.885829 -288.702677) (xy 375.922467 -288.666039)
			(xy 375.964386 -288.635583) (xy 376.010553 -288.61206) (xy 376.059832 -288.596048) (xy 376.111009 -288.587942)
			(xy 376.162823 -288.587942) (xy 376.214 -288.596048) (xy 376.263279 -288.61206) (xy 376.309446 -288.635583)
			(xy 376.351365 -288.666039) (xy 376.388003 -288.702677) (xy 376.418459 -288.744596) (xy 376.441982 -288.790763)
			(xy 376.457994 -288.840042) (xy 376.4661 -288.891219) (xy 376.466608 -288.917126) (xy 376.466153 -288.942575)
			(xy 376.458349 -288.992871) (xy 376.442899 -289.041367) (xy 376.420171 -289.086909) (xy 376.390707 -289.128411)
			(xy 376.355209 -289.164887) (xy 376.314521 -289.195466) (xy 376.269613 -289.21942) (xy 376.221553 -289.23618)
			(xy 376.196606 -289.24123) (xy 376.172476 -289.245802) (xy 375.9581 -289.651186) (xy 375.968006 -289.673792)
			(xy 375.976928 -289.694877) (xy 375.989478 -289.738907) (xy 375.99581 -289.78425) (xy 375.9962 -289.807142)
			(xy 377.216924 -289.807142) (xy 377.217411 -289.781712) (xy 377.225244 -289.73146) (xy 377.240699 -289.683005)
			(xy 377.26341 -289.637498) (xy 377.292839 -289.596018) (xy 377.328287 -289.559547) (xy 377.368914 -289.528951)
			(xy 377.413757 -289.504956) (xy 377.461753 -289.48813) (xy 377.486672 -289.483038) (xy 377.510802 -289.478466)
			(xy 377.725178 -289.073082) (xy 377.715272 -289.050476) (xy 377.706309 -289.029398) (xy 377.693664 -288.985377)
			(xy 377.687249 -288.940026) (xy 377.686824 -288.917126) (xy 377.687332 -288.891219) (xy 377.695438 -288.840042)
			(xy 377.71145 -288.790763) (xy 377.734973 -288.744596) (xy 377.765429 -288.702677) (xy 377.802067 -288.666039)
			(xy 377.843986 -288.635583) (xy 377.890153 -288.61206) (xy 377.939432 -288.596048) (xy 377.990609 -288.587942)
			(xy 378.042423 -288.587942) (xy 378.0936 -288.596048) (xy 378.142879 -288.61206) (xy 378.189046 -288.635583)
			(xy 378.230965 -288.666039) (xy 378.267603 -288.702677) (xy 378.298059 -288.744596) (xy 378.321582 -288.790763)
			(xy 378.337594 -288.840042) (xy 378.3457 -288.891219) (xy 378.346208 -288.917126) (xy 378.345753 -288.942575)
			(xy 378.337949 -288.992871) (xy 378.322499 -289.041367) (xy 378.299771 -289.086909) (xy 378.270307 -289.128411)
			(xy 378.234809 -289.164887) (xy 378.194121 -289.195466) (xy 378.149213 -289.21942) (xy 378.101153 -289.23618)
			(xy 378.076206 -289.24123) (xy 378.052076 -289.245802) (xy 377.8377 -289.651186) (xy 377.847606 -289.673792)
			(xy 377.856528 -289.694877) (xy 377.869078 -289.738907) (xy 377.87541 -289.78425) (xy 377.8758 -289.807142)
			(xy 379.096524 -289.807142) (xy 379.097011 -289.781712) (xy 379.104844 -289.73146) (xy 379.120299 -289.683005)
			(xy 379.14301 -289.637498) (xy 379.172439 -289.596018) (xy 379.207887 -289.559547) (xy 379.248514 -289.528951)
			(xy 379.293357 -289.504956) (xy 379.341353 -289.48813) (xy 379.366272 -289.483038) (xy 379.390402 -289.478466)
			(xy 379.604778 -289.073082) (xy 379.594872 -289.050476) (xy 379.585909 -289.029398) (xy 379.573264 -288.985377)
			(xy 379.566849 -288.940026) (xy 379.566424 -288.917126) (xy 379.566932 -288.891219) (xy 379.575038 -288.840042)
			(xy 379.59105 -288.790763) (xy 379.614573 -288.744596) (xy 379.645029 -288.702677) (xy 379.681667 -288.666039)
			(xy 379.723586 -288.635583) (xy 379.769753 -288.61206) (xy 379.819032 -288.596048) (xy 379.870209 -288.587942)
			(xy 379.922023 -288.587942) (xy 379.9732 -288.596048) (xy 380.022479 -288.61206) (xy 380.068646 -288.635583)
			(xy 380.110565 -288.666039) (xy 380.147203 -288.702677) (xy 380.177659 -288.744596) (xy 380.201182 -288.790763)
			(xy 380.217194 -288.840042) (xy 380.2253 -288.891219) (xy 380.225808 -288.917126) (xy 380.225353 -288.942575)
			(xy 380.217549 -288.992871) (xy 380.202099 -289.041367) (xy 380.179371 -289.086909) (xy 380.149907 -289.128411)
			(xy 380.114409 -289.164887) (xy 380.073721 -289.195466) (xy 380.028813 -289.21942) (xy 379.980753 -289.23618)
			(xy 379.955806 -289.24123) (xy 379.931676 -289.245802) (xy 379.7173 -289.651186) (xy 379.727206 -289.673792)
			(xy 379.736128 -289.694877) (xy 379.748678 -289.738907) (xy 379.75501 -289.78425) (xy 379.7554 -289.807142)
			(xy 380.976124 -289.807142) (xy 380.976611 -289.781712) (xy 380.984444 -289.73146) (xy 380.999899 -289.683005)
			(xy 381.02261 -289.637498) (xy 381.052039 -289.596018) (xy 381.087487 -289.559547) (xy 381.128114 -289.528951)
			(xy 381.172957 -289.504956) (xy 381.220953 -289.48813) (xy 381.245872 -289.483038) (xy 381.270002 -289.478466)
			(xy 381.484378 -289.073082) (xy 381.474472 -289.050476) (xy 381.465509 -289.029398) (xy 381.452864 -288.985377)
			(xy 381.446449 -288.940026) (xy 381.446024 -288.917126) (xy 381.446532 -288.891219) (xy 381.454638 -288.840042)
			(xy 381.47065 -288.790763) (xy 381.494173 -288.744596) (xy 381.524629 -288.702677) (xy 381.561267 -288.666039)
			(xy 381.603186 -288.635583) (xy 381.649353 -288.61206) (xy 381.698632 -288.596048) (xy 381.749809 -288.587942)
			(xy 381.801623 -288.587942) (xy 381.8528 -288.596048) (xy 381.902079 -288.61206) (xy 381.948246 -288.635583)
			(xy 381.990165 -288.666039) (xy 382.026803 -288.702677) (xy 382.057259 -288.744596) (xy 382.080782 -288.790763)
			(xy 382.096794 -288.840042) (xy 382.1049 -288.891219) (xy 382.105408 -288.917126) (xy 382.104953 -288.942575)
			(xy 382.097149 -288.992871) (xy 382.081699 -289.041367) (xy 382.058971 -289.086909) (xy 382.029507 -289.128411)
			(xy 381.994009 -289.164887) (xy 381.953321 -289.195466) (xy 381.908413 -289.21942) (xy 381.860353 -289.23618)
			(xy 381.835406 -289.24123) (xy 381.811276 -289.245802) (xy 381.5969 -289.651186) (xy 381.606806 -289.673792)
			(xy 381.615728 -289.694877) (xy 381.628278 -289.738907) (xy 381.63461 -289.78425) (xy 381.635 -289.807142)
			(xy 381.634492 -289.833029) (xy 381.626393 -289.884167) (xy 381.610394 -289.933407) (xy 381.586888 -289.979539)
			(xy 381.556456 -290.021426) (xy 381.519846 -290.058036) (xy 381.477959 -290.088468) (xy 381.431827 -290.111974)
			(xy 381.382587 -290.127973) (xy 381.331449 -290.136072) (xy 381.279675 -290.136072) (xy 381.228537 -290.127973)
			(xy 381.179297 -290.111974) (xy 381.133165 -290.088468) (xy 381.091278 -290.058036) (xy 381.054668 -290.021426)
			(xy 381.024236 -289.979539) (xy 381.00073 -289.933407) (xy 380.984731 -289.884167) (xy 380.976632 -289.833029)
			(xy 380.976124 -289.807142) (xy 379.7554 -289.807142) (xy 379.754892 -289.833029) (xy 379.746793 -289.884167)
			(xy 379.730794 -289.933407) (xy 379.707288 -289.979539) (xy 379.676856 -290.021426) (xy 379.640246 -290.058036)
			(xy 379.598359 -290.088468) (xy 379.552227 -290.111974) (xy 379.502987 -290.127973) (xy 379.451849 -290.136072)
			(xy 379.400075 -290.136072) (xy 379.348937 -290.127973) (xy 379.299697 -290.111974) (xy 379.253565 -290.088468)
			(xy 379.211678 -290.058036) (xy 379.175068 -290.021426) (xy 379.144636 -289.979539) (xy 379.12113 -289.933407)
			(xy 379.105131 -289.884167) (xy 379.097032 -289.833029) (xy 379.096524 -289.807142) (xy 377.8758 -289.807142)
			(xy 377.875292 -289.833029) (xy 377.867193 -289.884167) (xy 377.851194 -289.933407) (xy 377.827688 -289.979539)
			(xy 377.797256 -290.021426) (xy 377.760646 -290.058036) (xy 377.718759 -290.088468) (xy 377.672627 -290.111974)
			(xy 377.623387 -290.127973) (xy 377.572249 -290.136072) (xy 377.520475 -290.136072) (xy 377.469337 -290.127973)
			(xy 377.420097 -290.111974) (xy 377.373965 -290.088468) (xy 377.332078 -290.058036) (xy 377.295468 -290.021426)
			(xy 377.265036 -289.979539) (xy 377.24153 -289.933407) (xy 377.225531 -289.884167) (xy 377.217432 -289.833029)
			(xy 377.216924 -289.807142) (xy 375.9962 -289.807142) (xy 375.995692 -289.833029) (xy 375.987593 -289.884167)
			(xy 375.971594 -289.933407) (xy 375.948088 -289.979539) (xy 375.917656 -290.021426) (xy 375.881046 -290.058036)
			(xy 375.839159 -290.088468) (xy 375.793027 -290.111974) (xy 375.743787 -290.127973) (xy 375.692649 -290.136072)
			(xy 375.640875 -290.136072) (xy 375.589737 -290.127973) (xy 375.540497 -290.111974) (xy 375.494365 -290.088468)
			(xy 375.452478 -290.058036) (xy 375.415868 -290.021426) (xy 375.385436 -289.979539) (xy 375.36193 -289.933407)
			(xy 375.345931 -289.884167) (xy 375.337832 -289.833029) (xy 375.337324 -289.807142) (xy 374.1166 -289.807142)
			(xy 374.116092 -289.833029) (xy 374.107993 -289.884167) (xy 374.091994 -289.933407) (xy 374.068488 -289.979539)
			(xy 374.038056 -290.021426) (xy 374.001446 -290.058036) (xy 373.959559 -290.088468) (xy 373.913427 -290.111974)
			(xy 373.864187 -290.127973) (xy 373.813049 -290.136072) (xy 373.761275 -290.136072) (xy 373.710137 -290.127973)
			(xy 373.660897 -290.111974) (xy 373.614765 -290.088468) (xy 373.572878 -290.058036) (xy 373.536268 -290.021426)
			(xy 373.505836 -289.979539) (xy 373.48233 -289.933407) (xy 373.466331 -289.884167) (xy 373.458232 -289.833029)
			(xy 373.457724 -289.807142) (xy 372.237 -289.807142) (xy 372.236492 -289.833029) (xy 372.228393 -289.884167)
			(xy 372.212394 -289.933407) (xy 372.188888 -289.979539) (xy 372.158456 -290.021426) (xy 372.121846 -290.058036)
			(xy 372.079959 -290.088468) (xy 372.033827 -290.111974) (xy 371.984587 -290.127973) (xy 371.933449 -290.136072)
			(xy 371.881675 -290.136072) (xy 371.830537 -290.127973) (xy 371.781297 -290.111974) (xy 371.735165 -290.088468)
			(xy 371.693278 -290.058036) (xy 371.656668 -290.021426) (xy 371.626236 -289.979539) (xy 371.60273 -289.933407)
			(xy 371.586731 -289.884167) (xy 371.578632 -289.833029) (xy 371.578124 -289.807142) (xy 370.3574 -289.807142)
			(xy 370.356892 -289.833029) (xy 370.348793 -289.884167) (xy 370.332794 -289.933407) (xy 370.309288 -289.979539)
			(xy 370.278856 -290.021426) (xy 370.242246 -290.058036) (xy 370.200359 -290.088468) (xy 370.154227 -290.111974)
			(xy 370.104987 -290.127973) (xy 370.053849 -290.136072) (xy 370.002075 -290.136072) (xy 369.950937 -290.127973)
			(xy 369.901697 -290.111974) (xy 369.855565 -290.088468) (xy 369.813678 -290.058036) (xy 369.777068 -290.021426)
			(xy 369.746636 -289.979539) (xy 369.72313 -289.933407) (xy 369.707131 -289.884167) (xy 369.699032 -289.833029)
			(xy 369.698524 -289.807142) (xy 368.4778 -289.807142) (xy 368.477292 -289.833029) (xy 368.469193 -289.884167)
			(xy 368.453194 -289.933407) (xy 368.429688 -289.979539) (xy 368.399256 -290.021426) (xy 368.362646 -290.058036)
			(xy 368.320759 -290.088468) (xy 368.274627 -290.111974) (xy 368.225387 -290.127973) (xy 368.174249 -290.136072)
			(xy 368.122475 -290.136072) (xy 368.071337 -290.127973) (xy 368.022097 -290.111974) (xy 367.975965 -290.088468)
			(xy 367.934078 -290.058036) (xy 367.897468 -290.021426) (xy 367.867036 -289.979539) (xy 367.84353 -289.933407)
			(xy 367.827531 -289.884167) (xy 367.819432 -289.833029) (xy 367.818924 -289.807142) (xy 351.5614 -289.807142)
			(xy 351.560892 -289.833029) (xy 351.552793 -289.884167) (xy 351.536794 -289.933407) (xy 351.513288 -289.979539)
			(xy 351.482856 -290.021426) (xy 351.446246 -290.058036) (xy 351.404359 -290.088468) (xy 351.358227 -290.111974)
			(xy 351.308987 -290.127973) (xy 351.257849 -290.136072) (xy 351.206075 -290.136072) (xy 351.154937 -290.127973)
			(xy 351.105697 -290.111974) (xy 351.059565 -290.088468) (xy 351.017678 -290.058036) (xy 350.981068 -290.021426)
			(xy 350.950636 -289.979539) (xy 350.92713 -289.933407) (xy 350.911131 -289.884167) (xy 350.903032 -289.833029)
			(xy 350.902524 -289.807142) (xy 350.902524 -289.806634) (xy 350.902922 -289.783785) (xy 350.909275 -289.738531)
			(xy 350.921824 -289.694589) (xy 350.930718 -289.673538) (xy 350.940624 -289.650932) (xy 350.726756 -289.245802)
			(xy 350.702626 -289.24123) (xy 350.677682 -289.236182) (xy 350.629639 -289.219398) (xy 350.584746 -289.195428)
			(xy 350.544072 -289.164843) (xy 350.508582 -289.128369) (xy 350.479121 -289.086873) (xy 350.456389 -289.041341)
			(xy 350.440925 -288.992857) (xy 350.433099 -288.942571) (xy 350.432624 -288.917126) (xy 350.152208 -288.917126)
			(xy 350.1517 -288.943033) (xy 350.143594 -288.99421) (xy 350.127582 -289.043489) (xy 350.104059 -289.089656)
			(xy 350.073603 -289.131575) (xy 350.036965 -289.168213) (xy 349.995046 -289.198669) (xy 349.948879 -289.222192)
			(xy 349.8996 -289.238204) (xy 349.848423 -289.24631) (xy 349.796609 -289.24631) (xy 349.745432 -289.238204)
			(xy 349.696153 -289.222192) (xy 349.649986 -289.198669) (xy 349.608067 -289.168213) (xy 349.571429 -289.131575)
			(xy 349.540973 -289.089656) (xy 349.51745 -289.043489) (xy 349.501438 -288.99421) (xy 349.493332 -288.943033)
			(xy 349.492824 -288.917126) (xy 349.212408 -288.917126) (xy 349.211989 -288.940067) (xy 349.20556 -288.985498)
			(xy 349.192913 -289.029604) (xy 349.18396 -289.05073) (xy 349.174054 -289.073336) (xy 349.387922 -289.478466)
			(xy 349.412052 -289.483038) (xy 349.436973 -289.488138) (xy 349.484984 -289.504939) (xy 349.529843 -289.528919)
			(xy 349.570484 -289.559507) (xy 349.605941 -289.595978) (xy 349.635373 -289.637465) (xy 349.658079 -289.682981)
			(xy 349.673521 -289.731446) (xy 349.681331 -289.781709) (xy 349.6818 -289.807142) (xy 349.681292 -289.833029)
			(xy 349.673193 -289.884167) (xy 349.657194 -289.933407) (xy 349.633688 -289.979539) (xy 349.603256 -290.021426)
			(xy 349.566646 -290.058036) (xy 349.524759 -290.088468) (xy 349.478627 -290.111974) (xy 349.429387 -290.127973)
			(xy 349.378249 -290.136072) (xy 349.326475 -290.136072) (xy 349.275337 -290.127973) (xy 349.226097 -290.111974)
			(xy 349.179965 -290.088468) (xy 349.138078 -290.058036) (xy 349.101468 -290.021426) (xy 349.071036 -289.979539)
			(xy 349.04753 -289.933407) (xy 349.031531 -289.884167) (xy 349.023432 -289.833029) (xy 349.022924 -289.807142)
			(xy 349.022924 -289.806634) (xy 349.023322 -289.783785) (xy 349.029675 -289.738531) (xy 349.042224 -289.694589)
			(xy 349.051118 -289.673538) (xy 349.061024 -289.650932) (xy 348.847156 -289.245802) (xy 348.823026 -289.24123)
			(xy 348.798082 -289.236182) (xy 348.750039 -289.219398) (xy 348.705146 -289.195428) (xy 348.664472 -289.164843)
			(xy 348.628982 -289.128369) (xy 348.599521 -289.086873) (xy 348.576789 -289.041341) (xy 348.561325 -288.992857)
			(xy 348.553499 -288.942571) (xy 348.553024 -288.917126) (xy 348.272608 -288.917126) (xy 348.2721 -288.943033)
			(xy 348.263994 -288.99421) (xy 348.247982 -289.043489) (xy 348.224459 -289.089656) (xy 348.194003 -289.131575)
			(xy 348.157365 -289.168213) (xy 348.115446 -289.198669) (xy 348.069279 -289.222192) (xy 348.02 -289.238204)
			(xy 347.968823 -289.24631) (xy 347.917009 -289.24631) (xy 347.865832 -289.238204) (xy 347.816553 -289.222192)
			(xy 347.770386 -289.198669) (xy 347.728467 -289.168213) (xy 347.691829 -289.131575) (xy 347.661373 -289.089656)
			(xy 347.63785 -289.043489) (xy 347.621838 -288.99421) (xy 347.613732 -288.943033) (xy 347.613224 -288.917126)
			(xy 347.332808 -288.917126) (xy 347.332389 -288.940067) (xy 347.32596 -288.985498) (xy 347.313313 -289.029604)
			(xy 347.30436 -289.05073) (xy 347.294454 -289.073336) (xy 347.508322 -289.478466) (xy 347.532452 -289.483038)
			(xy 347.557373 -289.488138) (xy 347.605384 -289.504939) (xy 347.650243 -289.528919) (xy 347.690884 -289.559507)
			(xy 347.726341 -289.595978) (xy 347.755773 -289.637465) (xy 347.778479 -289.682981) (xy 347.793921 -289.731446)
			(xy 347.801731 -289.781709) (xy 347.8022 -289.807142) (xy 347.801692 -289.833029) (xy 347.793593 -289.884167)
			(xy 347.777594 -289.933407) (xy 347.754088 -289.979539) (xy 347.723656 -290.021426) (xy 347.687046 -290.058036)
			(xy 347.645159 -290.088468) (xy 347.599027 -290.111974) (xy 347.549787 -290.127973) (xy 347.498649 -290.136072)
			(xy 347.446875 -290.136072) (xy 347.395737 -290.127973) (xy 347.346497 -290.111974) (xy 347.300365 -290.088468)
			(xy 347.258478 -290.058036) (xy 347.221868 -290.021426) (xy 347.191436 -289.979539) (xy 347.16793 -289.933407)
			(xy 347.151931 -289.884167) (xy 347.143832 -289.833029) (xy 347.143324 -289.807142) (xy 347.143324 -289.806634)
			(xy 347.143722 -289.783785) (xy 347.150075 -289.738531) (xy 347.162624 -289.694589) (xy 347.171518 -289.673538)
			(xy 347.181424 -289.650932) (xy 346.967556 -289.245802) (xy 346.943426 -289.24123) (xy 346.918482 -289.236182)
			(xy 346.870439 -289.219398) (xy 346.825546 -289.195428) (xy 346.784872 -289.164843) (xy 346.749382 -289.128369)
			(xy 346.719921 -289.086873) (xy 346.697189 -289.041341) (xy 346.681725 -288.992857) (xy 346.673899 -288.942571)
			(xy 346.673424 -288.917126) (xy 346.393008 -288.917126) (xy 346.3925 -288.943033) (xy 346.384394 -288.99421)
			(xy 346.368382 -289.043489) (xy 346.344859 -289.089656) (xy 346.314403 -289.131575) (xy 346.277765 -289.168213)
			(xy 346.235846 -289.198669) (xy 346.189679 -289.222192) (xy 346.1404 -289.238204) (xy 346.089223 -289.24631)
			(xy 346.037409 -289.24631) (xy 345.986232 -289.238204) (xy 345.936953 -289.222192) (xy 345.890786 -289.198669)
			(xy 345.848867 -289.168213) (xy 345.812229 -289.131575) (xy 345.781773 -289.089656) (xy 345.75825 -289.043489)
			(xy 345.742238 -288.99421) (xy 345.734132 -288.943033) (xy 345.733624 -288.917126) (xy 345.453208 -288.917126)
			(xy 345.452789 -288.940067) (xy 345.44636 -288.985498) (xy 345.433713 -289.029604) (xy 345.42476 -289.05073)
			(xy 345.414854 -289.073336) (xy 345.628722 -289.478466) (xy 345.652852 -289.483038) (xy 345.677773 -289.488138)
			(xy 345.725784 -289.504939) (xy 345.770643 -289.528919) (xy 345.811284 -289.559507) (xy 345.846741 -289.595978)
			(xy 345.876173 -289.637465) (xy 345.898879 -289.682981) (xy 345.914321 -289.731446) (xy 345.922131 -289.781709)
			(xy 345.9226 -289.807142) (xy 345.922092 -289.833029) (xy 345.913993 -289.884167) (xy 345.897994 -289.933407)
			(xy 345.874488 -289.979539) (xy 345.844056 -290.021426) (xy 345.807446 -290.058036) (xy 345.765559 -290.088468)
			(xy 345.719427 -290.111974) (xy 345.670187 -290.127973) (xy 345.619049 -290.136072) (xy 345.567275 -290.136072)
			(xy 345.516137 -290.127973) (xy 345.466897 -290.111974) (xy 345.420765 -290.088468) (xy 345.378878 -290.058036)
			(xy 345.342268 -290.021426) (xy 345.311836 -289.979539) (xy 345.28833 -289.933407) (xy 345.272331 -289.884167)
			(xy 345.264232 -289.833029) (xy 345.263724 -289.807142) (xy 345.263724 -289.806634) (xy 345.264122 -289.783785)
			(xy 345.270475 -289.738531) (xy 345.283024 -289.694589) (xy 345.291918 -289.673538) (xy 345.301824 -289.650932)
			(xy 345.087956 -289.245802) (xy 345.063826 -289.24123) (xy 345.038882 -289.236182) (xy 344.990839 -289.219398)
			(xy 344.945946 -289.195428) (xy 344.905272 -289.164843) (xy 344.869782 -289.128369) (xy 344.840321 -289.086873)
			(xy 344.817589 -289.041341) (xy 344.802125 -288.992857) (xy 344.794299 -288.942571) (xy 344.793824 -288.917126)
			(xy 344.513408 -288.917126) (xy 344.5129 -288.943033) (xy 344.504794 -288.99421) (xy 344.488782 -289.043489)
			(xy 344.465259 -289.089656) (xy 344.434803 -289.131575) (xy 344.398165 -289.168213) (xy 344.356246 -289.198669)
			(xy 344.310079 -289.222192) (xy 344.2608 -289.238204) (xy 344.209623 -289.24631) (xy 344.157809 -289.24631)
			(xy 344.106632 -289.238204) (xy 344.057353 -289.222192) (xy 344.011186 -289.198669) (xy 343.969267 -289.168213)
			(xy 343.932629 -289.131575) (xy 343.902173 -289.089656) (xy 343.87865 -289.043489) (xy 343.862638 -288.99421)
			(xy 343.854532 -288.943033) (xy 343.854024 -288.917126) (xy 343.573608 -288.917126) (xy 343.573189 -288.940067)
			(xy 343.56676 -288.985498) (xy 343.554113 -289.029604) (xy 343.54516 -289.05073) (xy 343.535254 -289.073336)
			(xy 343.749122 -289.478466) (xy 343.773252 -289.483038) (xy 343.798173 -289.488138) (xy 343.846184 -289.504939)
			(xy 343.891043 -289.528919) (xy 343.931684 -289.559507) (xy 343.967141 -289.595978) (xy 343.996573 -289.637465)
			(xy 344.019279 -289.682981) (xy 344.034721 -289.731446) (xy 344.042531 -289.781709) (xy 344.043 -289.807142)
			(xy 344.042492 -289.833029) (xy 344.034393 -289.884167) (xy 344.018394 -289.933407) (xy 343.994888 -289.979539)
			(xy 343.964456 -290.021426) (xy 343.927846 -290.058036) (xy 343.885959 -290.088468) (xy 343.839827 -290.111974)
			(xy 343.790587 -290.127973) (xy 343.739449 -290.136072) (xy 343.687675 -290.136072) (xy 343.636537 -290.127973)
			(xy 343.587297 -290.111974) (xy 343.541165 -290.088468) (xy 343.499278 -290.058036) (xy 343.462668 -290.021426)
			(xy 343.432236 -289.979539) (xy 343.40873 -289.933407) (xy 343.392731 -289.884167) (xy 343.384632 -289.833029)
			(xy 343.384124 -289.807142) (xy 343.384124 -289.806634) (xy 343.384522 -289.783785) (xy 343.390875 -289.738531)
			(xy 343.403424 -289.694589) (xy 343.412318 -289.673538) (xy 343.422224 -289.650932) (xy 343.208356 -289.245802)
			(xy 343.184226 -289.24123) (xy 343.159282 -289.236182) (xy 343.111239 -289.219398) (xy 343.066346 -289.195428)
			(xy 343.025672 -289.164843) (xy 342.990182 -289.128369) (xy 342.960721 -289.086873) (xy 342.937989 -289.041341)
			(xy 342.922525 -288.992857) (xy 342.914699 -288.942571) (xy 342.914224 -288.917126) (xy 342.633808 -288.917126)
			(xy 342.6333 -288.943033) (xy 342.625194 -288.99421) (xy 342.609182 -289.043489) (xy 342.585659 -289.089656)
			(xy 342.555203 -289.131575) (xy 342.518565 -289.168213) (xy 342.476646 -289.198669) (xy 342.430479 -289.222192)
			(xy 342.3812 -289.238204) (xy 342.330023 -289.24631) (xy 342.278209 -289.24631) (xy 342.227032 -289.238204)
			(xy 342.177753 -289.222192) (xy 342.131586 -289.198669) (xy 342.089667 -289.168213) (xy 342.053029 -289.131575)
			(xy 342.022573 -289.089656) (xy 341.99905 -289.043489) (xy 341.983038 -288.99421) (xy 341.974932 -288.943033)
			(xy 341.974424 -288.917126) (xy 341.694008 -288.917126) (xy 341.693589 -288.940067) (xy 341.68716 -288.985498)
			(xy 341.674513 -289.029604) (xy 341.66556 -289.05073) (xy 341.655654 -289.073336) (xy 341.869522 -289.478466)
			(xy 341.893652 -289.483038) (xy 341.918573 -289.488138) (xy 341.966584 -289.504939) (xy 342.011443 -289.528919)
			(xy 342.052084 -289.559507) (xy 342.087541 -289.595978) (xy 342.116973 -289.637465) (xy 342.139679 -289.682981)
			(xy 342.155121 -289.731446) (xy 342.162931 -289.781709) (xy 342.1634 -289.807142) (xy 342.162892 -289.833029)
			(xy 342.154793 -289.884167) (xy 342.138794 -289.933407) (xy 342.115288 -289.979539) (xy 342.084856 -290.021426)
			(xy 342.048246 -290.058036) (xy 342.006359 -290.088468) (xy 341.960227 -290.111974) (xy 341.910987 -290.127973)
			(xy 341.859849 -290.136072) (xy 341.808075 -290.136072) (xy 341.756937 -290.127973) (xy 341.707697 -290.111974)
			(xy 341.661565 -290.088468) (xy 341.619678 -290.058036) (xy 341.583068 -290.021426) (xy 341.552636 -289.979539)
			(xy 341.52913 -289.933407) (xy 341.513131 -289.884167) (xy 341.505032 -289.833029) (xy 341.504524 -289.807142)
			(xy 341.504524 -289.806634) (xy 341.504922 -289.783785) (xy 341.511275 -289.738531) (xy 341.523824 -289.694589)
			(xy 341.532718 -289.673538) (xy 341.542624 -289.650932) (xy 341.328756 -289.245802) (xy 341.304626 -289.24123)
			(xy 341.279682 -289.236182) (xy 341.231639 -289.219398) (xy 341.186746 -289.195428) (xy 341.146072 -289.164843)
			(xy 341.110582 -289.128369) (xy 341.081121 -289.086873) (xy 341.058389 -289.041341) (xy 341.042925 -288.992857)
			(xy 341.035099 -288.942571) (xy 341.034624 -288.917126) (xy 340.754208 -288.917126) (xy 340.7537 -288.943033)
			(xy 340.745594 -288.99421) (xy 340.729582 -289.043489) (xy 340.706059 -289.089656) (xy 340.675603 -289.131575)
			(xy 340.638965 -289.168213) (xy 340.597046 -289.198669) (xy 340.550879 -289.222192) (xy 340.5016 -289.238204)
			(xy 340.450423 -289.24631) (xy 340.398609 -289.24631) (xy 340.347432 -289.238204) (xy 340.298153 -289.222192)
			(xy 340.251986 -289.198669) (xy 340.210067 -289.168213) (xy 340.173429 -289.131575) (xy 340.142973 -289.089656)
			(xy 340.11945 -289.043489) (xy 340.103438 -288.99421) (xy 340.095332 -288.943033) (xy 340.094824 -288.917126)
			(xy 339.814408 -288.917126) (xy 339.813989 -288.940067) (xy 339.80756 -288.985498) (xy 339.794913 -289.029604)
			(xy 339.78596 -289.05073) (xy 339.776054 -289.073336) (xy 339.989922 -289.478466) (xy 340.014052 -289.483038)
			(xy 340.038973 -289.488138) (xy 340.086984 -289.504939) (xy 340.131843 -289.528919) (xy 340.172484 -289.559507)
			(xy 340.207941 -289.595978) (xy 340.237373 -289.637465) (xy 340.260079 -289.682981) (xy 340.275521 -289.731446)
			(xy 340.283331 -289.781709) (xy 340.2838 -289.807142) (xy 340.283292 -289.833029) (xy 340.275193 -289.884167)
			(xy 340.259194 -289.933407) (xy 340.235688 -289.979539) (xy 340.205256 -290.021426) (xy 340.168646 -290.058036)
			(xy 340.126759 -290.088468) (xy 340.080627 -290.111974) (xy 340.031387 -290.127973) (xy 339.980249 -290.136072)
			(xy 339.928475 -290.136072) (xy 339.877337 -290.127973) (xy 339.828097 -290.111974) (xy 339.781965 -290.088468)
			(xy 339.740078 -290.058036) (xy 339.703468 -290.021426) (xy 339.673036 -289.979539) (xy 339.64953 -289.933407)
			(xy 339.633531 -289.884167) (xy 339.625432 -289.833029) (xy 339.624924 -289.807142) (xy 339.624924 -289.806634)
			(xy 339.625322 -289.783785) (xy 339.631675 -289.738531) (xy 339.644224 -289.694589) (xy 339.653118 -289.673538)
			(xy 339.663024 -289.650932) (xy 339.449156 -289.245802) (xy 339.425026 -289.24123) (xy 339.400082 -289.236182)
			(xy 339.352039 -289.219398) (xy 339.307146 -289.195428) (xy 339.266472 -289.164843) (xy 339.230982 -289.128369)
			(xy 339.201521 -289.086873) (xy 339.178789 -289.041341) (xy 339.163325 -288.992857) (xy 339.155499 -288.942571)
			(xy 339.155024 -288.917126) (xy 338.874608 -288.917126) (xy 338.8741 -288.943033) (xy 338.865994 -288.99421)
			(xy 338.849982 -289.043489) (xy 338.826459 -289.089656) (xy 338.796003 -289.131575) (xy 338.759365 -289.168213)
			(xy 338.717446 -289.198669) (xy 338.671279 -289.222192) (xy 338.622 -289.238204) (xy 338.570823 -289.24631)
			(xy 338.519009 -289.24631) (xy 338.467832 -289.238204) (xy 338.418553 -289.222192) (xy 338.372386 -289.198669)
			(xy 338.330467 -289.168213) (xy 338.293829 -289.131575) (xy 338.263373 -289.089656) (xy 338.23985 -289.043489)
			(xy 338.223838 -288.99421) (xy 338.215732 -288.943033) (xy 338.215224 -288.917126) (xy 336.995008 -288.917126)
			(xy 336.9945 -288.943033) (xy 336.986394 -288.99421) (xy 336.970382 -289.043489) (xy 336.946859 -289.089656)
			(xy 336.916403 -289.131575) (xy 336.879765 -289.168213) (xy 336.837846 -289.198669) (xy 336.791679 -289.222192)
			(xy 336.7424 -289.238204) (xy 336.691223 -289.24631) (xy 336.639409 -289.24631) (xy 336.588232 -289.238204)
			(xy 336.538953 -289.222192) (xy 336.492786 -289.198669) (xy 336.450867 -289.168213) (xy 336.414229 -289.131575)
			(xy 336.383773 -289.089656) (xy 336.36025 -289.043489) (xy 336.344238 -288.99421) (xy 336.336132 -288.943033)
			(xy 336.335624 -288.917126) (xy 136.04494 -288.917126) (xy 136.044432 -288.943033) (xy 136.036326 -288.99421)
			(xy 136.020314 -289.043489) (xy 135.996791 -289.089656) (xy 135.966335 -289.131575) (xy 135.929697 -289.168213)
			(xy 135.887778 -289.198669) (xy 135.841611 -289.222192) (xy 135.792332 -289.238204) (xy 135.741155 -289.24631)
			(xy 135.689341 -289.24631) (xy 135.638164 -289.238204) (xy 135.588885 -289.222192) (xy 135.542718 -289.198669)
			(xy 135.500799 -289.168213) (xy 135.464161 -289.131575) (xy 135.433705 -289.089656) (xy 135.410182 -289.043489)
			(xy 135.39417 -288.99421) (xy 135.386064 -288.943033) (xy 135.385556 -288.917126) (xy 135.386153 -288.889409)
			(xy 135.395474 -288.834762) (xy 135.404098 -288.808414) (xy 135.411972 -288.786316) (xy 135.20674 -288.431224)
			(xy 135.18388 -288.426906) (xy 135.159064 -288.421716) (xy 135.111285 -288.404766) (xy 135.066665 -288.380698)
			(xy 135.026258 -288.350081) (xy 134.991016 -288.313637) (xy 134.961772 -288.272226) (xy 134.939214 -288.226825)
			(xy 134.923875 -288.178504) (xy 134.916118 -288.128404) (xy 134.915656 -288.103056) (xy 132.75564 -288.103056)
			(xy 132.755038 -288.130773) (xy 132.74572 -288.18542) (xy 132.737098 -288.211768) (xy 132.729478 -288.233866)
			(xy 132.934456 -288.588958) (xy 132.957316 -288.593276) (xy 132.982127 -288.598486) (xy 133.029905 -288.615434)
			(xy 133.074524 -288.6395) (xy 133.114931 -288.670114) (xy 133.150173 -288.706556) (xy 133.179418 -288.747964)
			(xy 133.201977 -288.793363) (xy 133.217317 -288.841681) (xy 133.225077 -288.891779) (xy 133.22554 -288.917126)
			(xy 133.225032 -288.943033) (xy 133.216926 -288.99421) (xy 133.200914 -289.043489) (xy 133.177391 -289.089656)
			(xy 133.146935 -289.131575) (xy 133.110297 -289.168213) (xy 133.068378 -289.198669) (xy 133.022211 -289.222192)
			(xy 132.972932 -289.238204) (xy 132.921755 -289.24631) (xy 132.869941 -289.24631) (xy 132.818764 -289.238204)
			(xy 132.769485 -289.222192) (xy 132.723318 -289.198669) (xy 132.681399 -289.168213) (xy 132.644761 -289.131575)
			(xy 132.614305 -289.089656) (xy 132.590782 -289.043489) (xy 132.57477 -288.99421) (xy 132.566664 -288.943033)
			(xy 132.566156 -288.917126) (xy 132.566753 -288.889409) (xy 132.576074 -288.834762) (xy 132.584698 -288.808414)
			(xy 132.592572 -288.786316) (xy 132.387594 -288.431224) (xy 132.364734 -288.426906) (xy 132.339899 -288.421756)
			(xy 132.292089 -288.404821) (xy 132.247438 -288.380764) (xy 132.206999 -288.350151) (xy 132.171726 -288.313705)
			(xy 132.142451 -288.272287) (xy 132.119866 -288.226873) (xy 132.104504 -288.178536) (xy 132.096726 -288.128416)
			(xy 132.096256 -288.103056) (xy 130.87604 -288.103056) (xy 130.875438 -288.130773) (xy 130.86612 -288.18542)
			(xy 130.857498 -288.211768) (xy 130.849878 -288.233866) (xy 131.054856 -288.588958) (xy 131.077716 -288.593276)
			(xy 131.102527 -288.598486) (xy 131.150305 -288.615434) (xy 131.194924 -288.6395) (xy 131.235331 -288.670114)
			(xy 131.270573 -288.706556) (xy 131.299818 -288.747964) (xy 131.322377 -288.793363) (xy 131.337717 -288.841681)
			(xy 131.345477 -288.891779) (xy 131.34594 -288.917126) (xy 131.345432 -288.943033) (xy 131.337326 -288.99421)
			(xy 131.321314 -289.043489) (xy 131.297791 -289.089656) (xy 131.267335 -289.131575) (xy 131.230697 -289.168213)
			(xy 131.188778 -289.198669) (xy 131.142611 -289.222192) (xy 131.093332 -289.238204) (xy 131.042155 -289.24631)
			(xy 130.990341 -289.24631) (xy 130.939164 -289.238204) (xy 130.889885 -289.222192) (xy 130.843718 -289.198669)
			(xy 130.801799 -289.168213) (xy 130.765161 -289.131575) (xy 130.734705 -289.089656) (xy 130.711182 -289.043489)
			(xy 130.69517 -288.99421) (xy 130.687064 -288.943033) (xy 130.686556 -288.917126) (xy 130.687153 -288.889409)
			(xy 130.696474 -288.834762) (xy 130.705098 -288.808414) (xy 130.712972 -288.786316) (xy 130.507994 -288.431224)
			(xy 130.485134 -288.426906) (xy 130.460299 -288.421756) (xy 130.412489 -288.404821) (xy 130.367838 -288.380764)
			(xy 130.327399 -288.350151) (xy 130.292126 -288.313705) (xy 130.262851 -288.272287) (xy 130.240266 -288.226873)
			(xy 130.224904 -288.178536) (xy 130.217126 -288.128416) (xy 130.216656 -288.103056) (xy 128.99644 -288.103056)
			(xy 128.995838 -288.130773) (xy 128.98652 -288.18542) (xy 128.977898 -288.211768) (xy 128.970278 -288.233866)
			(xy 129.175256 -288.588958) (xy 129.198116 -288.593276) (xy 129.222927 -288.598486) (xy 129.270705 -288.615434)
			(xy 129.315324 -288.6395) (xy 129.355731 -288.670114) (xy 129.390973 -288.706556) (xy 129.420218 -288.747964)
			(xy 129.442777 -288.793363) (xy 129.458117 -288.841681) (xy 129.465877 -288.891779) (xy 129.46634 -288.917126)
			(xy 129.465832 -288.943033) (xy 129.457726 -288.99421) (xy 129.441714 -289.043489) (xy 129.418191 -289.089656)
			(xy 129.387735 -289.131575) (xy 129.351097 -289.168213) (xy 129.309178 -289.198669) (xy 129.263011 -289.222192)
			(xy 129.213732 -289.238204) (xy 129.162555 -289.24631) (xy 129.110741 -289.24631) (xy 129.059564 -289.238204)
			(xy 129.010285 -289.222192) (xy 128.964118 -289.198669) (xy 128.922199 -289.168213) (xy 128.885561 -289.131575)
			(xy 128.855105 -289.089656) (xy 128.831582 -289.043489) (xy 128.81557 -288.99421) (xy 128.807464 -288.943033)
			(xy 128.806956 -288.917126) (xy 128.807553 -288.889409) (xy 128.816874 -288.834762) (xy 128.825498 -288.808414)
			(xy 128.833372 -288.786316) (xy 128.628394 -288.431224) (xy 128.605534 -288.426906) (xy 128.580699 -288.421756)
			(xy 128.532889 -288.404821) (xy 128.488238 -288.380764) (xy 128.447799 -288.350151) (xy 128.412526 -288.313705)
			(xy 128.383251 -288.272287) (xy 128.360666 -288.226873) (xy 128.345304 -288.178536) (xy 128.337526 -288.128416)
			(xy 128.337056 -288.103056) (xy 127.11684 -288.103056) (xy 127.116238 -288.130773) (xy 127.10692 -288.18542)
			(xy 127.098298 -288.211768) (xy 127.090678 -288.233866) (xy 127.295656 -288.588958) (xy 127.318516 -288.593276)
			(xy 127.343327 -288.598486) (xy 127.391105 -288.615434) (xy 127.435724 -288.6395) (xy 127.476131 -288.670114)
			(xy 127.511373 -288.706556) (xy 127.540618 -288.747964) (xy 127.563177 -288.793363) (xy 127.578517 -288.841681)
			(xy 127.586277 -288.891779) (xy 127.58674 -288.917126) (xy 127.586232 -288.943033) (xy 127.578126 -288.99421)
			(xy 127.562114 -289.043489) (xy 127.538591 -289.089656) (xy 127.508135 -289.131575) (xy 127.471497 -289.168213)
			(xy 127.429578 -289.198669) (xy 127.383411 -289.222192) (xy 127.334132 -289.238204) (xy 127.282955 -289.24631)
			(xy 127.231141 -289.24631) (xy 127.179964 -289.238204) (xy 127.130685 -289.222192) (xy 127.084518 -289.198669)
			(xy 127.042599 -289.168213) (xy 127.005961 -289.131575) (xy 126.975505 -289.089656) (xy 126.951982 -289.043489)
			(xy 126.93597 -288.99421) (xy 126.927864 -288.943033) (xy 126.927356 -288.917126) (xy 126.927953 -288.889409)
			(xy 126.937274 -288.834762) (xy 126.945898 -288.808414) (xy 126.953772 -288.786316) (xy 126.748794 -288.431224)
			(xy 126.725934 -288.426906) (xy 126.701099 -288.421756) (xy 126.653289 -288.404821) (xy 126.608638 -288.380764)
			(xy 126.568199 -288.350151) (xy 126.532926 -288.313705) (xy 126.503651 -288.272287) (xy 126.481066 -288.226873)
			(xy 126.465704 -288.178536) (xy 126.457926 -288.128416) (xy 126.457456 -288.103056) (xy 125.23724 -288.103056)
			(xy 125.236638 -288.130773) (xy 125.22732 -288.18542) (xy 125.218698 -288.211768) (xy 125.211078 -288.233866)
			(xy 125.416056 -288.588958) (xy 125.438916 -288.593276) (xy 125.463727 -288.598486) (xy 125.511505 -288.615434)
			(xy 125.556124 -288.6395) (xy 125.596531 -288.670114) (xy 125.631773 -288.706556) (xy 125.661018 -288.747964)
			(xy 125.683577 -288.793363) (xy 125.698917 -288.841681) (xy 125.706677 -288.891779) (xy 125.70714 -288.917126)
			(xy 125.706632 -288.943033) (xy 125.698526 -288.99421) (xy 125.682514 -289.043489) (xy 125.658991 -289.089656)
			(xy 125.628535 -289.131575) (xy 125.591897 -289.168213) (xy 125.549978 -289.198669) (xy 125.503811 -289.222192)
			(xy 125.454532 -289.238204) (xy 125.403355 -289.24631) (xy 125.351541 -289.24631) (xy 125.300364 -289.238204)
			(xy 125.251085 -289.222192) (xy 125.204918 -289.198669) (xy 125.162999 -289.168213) (xy 125.126361 -289.131575)
			(xy 125.095905 -289.089656) (xy 125.072382 -289.043489) (xy 125.05637 -288.99421) (xy 125.048264 -288.943033)
			(xy 125.047756 -288.917126) (xy 125.048353 -288.889409) (xy 125.057674 -288.834762) (xy 125.066298 -288.808414)
			(xy 125.074172 -288.786316) (xy 124.869194 -288.431224) (xy 124.846334 -288.426906) (xy 124.821499 -288.421756)
			(xy 124.773689 -288.404821) (xy 124.729038 -288.380764) (xy 124.688599 -288.350151) (xy 124.653326 -288.313705)
			(xy 124.624051 -288.272287) (xy 124.601466 -288.226873) (xy 124.586104 -288.178536) (xy 124.578326 -288.128416)
			(xy 124.577856 -288.103056) (xy 123.35764 -288.103056) (xy 123.357038 -288.130773) (xy 123.34772 -288.18542)
			(xy 123.339098 -288.211768) (xy 123.331478 -288.233866) (xy 123.536456 -288.588958) (xy 123.559316 -288.593276)
			(xy 123.584127 -288.598486) (xy 123.631905 -288.615434) (xy 123.676524 -288.6395) (xy 123.716931 -288.670114)
			(xy 123.752173 -288.706556) (xy 123.781418 -288.747964) (xy 123.803977 -288.793363) (xy 123.819317 -288.841681)
			(xy 123.827077 -288.891779) (xy 123.82754 -288.917126) (xy 123.827032 -288.943033) (xy 123.818926 -288.99421)
			(xy 123.802914 -289.043489) (xy 123.779391 -289.089656) (xy 123.748935 -289.131575) (xy 123.712297 -289.168213)
			(xy 123.670378 -289.198669) (xy 123.624211 -289.222192) (xy 123.574932 -289.238204) (xy 123.523755 -289.24631)
			(xy 123.471941 -289.24631) (xy 123.420764 -289.238204) (xy 123.371485 -289.222192) (xy 123.325318 -289.198669)
			(xy 123.283399 -289.168213) (xy 123.246761 -289.131575) (xy 123.216305 -289.089656) (xy 123.192782 -289.043489)
			(xy 123.17677 -288.99421) (xy 123.168664 -288.943033) (xy 123.168156 -288.917126) (xy 123.168753 -288.889409)
			(xy 123.178074 -288.834762) (xy 123.186698 -288.808414) (xy 123.194572 -288.786316) (xy 122.989594 -288.431224)
			(xy 122.966734 -288.426906) (xy 122.941899 -288.421756) (xy 122.894089 -288.404821) (xy 122.849438 -288.380764)
			(xy 122.808999 -288.350151) (xy 122.773726 -288.313705) (xy 122.744451 -288.272287) (xy 122.721866 -288.226873)
			(xy 122.706504 -288.178536) (xy 122.698726 -288.128416) (xy 122.698256 -288.103056) (xy 121.47804 -288.103056)
			(xy 121.477438 -288.130773) (xy 121.46812 -288.18542) (xy 121.459498 -288.211768) (xy 121.451624 -288.233866)
			(xy 121.656856 -288.588958) (xy 121.679716 -288.593276) (xy 121.704527 -288.598486) (xy 121.752305 -288.615434)
			(xy 121.796924 -288.6395) (xy 121.837331 -288.670114) (xy 121.872573 -288.706556) (xy 121.901818 -288.747964)
			(xy 121.924377 -288.793363) (xy 121.939717 -288.841681) (xy 121.947477 -288.891779) (xy 121.94794 -288.917126)
			(xy 121.947432 -288.943033) (xy 121.939326 -288.99421) (xy 121.923314 -289.043489) (xy 121.899791 -289.089656)
			(xy 121.869335 -289.131575) (xy 121.832697 -289.168213) (xy 121.790778 -289.198669) (xy 121.744611 -289.222192)
			(xy 121.695332 -289.238204) (xy 121.644155 -289.24631) (xy 121.592341 -289.24631) (xy 121.541164 -289.238204)
			(xy 121.491885 -289.222192) (xy 121.445718 -289.198669) (xy 121.403799 -289.168213) (xy 121.367161 -289.131575)
			(xy 121.336705 -289.089656) (xy 121.313182 -289.043489) (xy 121.29717 -288.99421) (xy 121.289064 -288.943033)
			(xy 121.288556 -288.917126) (xy 121.289153 -288.889409) (xy 121.298474 -288.834762) (xy 121.307098 -288.808414)
			(xy 121.314972 -288.786316) (xy 121.10974 -288.431224) (xy 121.08688 -288.426906) (xy 121.062064 -288.421716)
			(xy 121.014285 -288.404766) (xy 120.969665 -288.380698) (xy 120.929258 -288.350081) (xy 120.894016 -288.313637)
			(xy 120.864772 -288.272226) (xy 120.842214 -288.226825) (xy 120.826875 -288.178504) (xy 120.819118 -288.128404)
			(xy 120.818656 -288.103056) (xy 104.56164 -288.103056) (xy 104.561218 -288.128404) (xy 104.553436 -288.178499)
			(xy 104.53808 -288.226813) (xy 104.515512 -288.272208) (xy 104.486262 -288.313614) (xy 104.451021 -288.350057)
			(xy 104.410618 -288.380678) (xy 104.366005 -288.404755) (xy 104.318232 -288.421722) (xy 104.293416 -288.426906)
			(xy 104.270556 -288.431224) (xy 104.065324 -288.786316) (xy 104.073198 -288.808414) (xy 104.08184 -288.834757)
			(xy 104.091154 -288.889407) (xy 104.09174 -288.917126) (xy 104.091232 -288.943033) (xy 104.083126 -288.99421)
			(xy 104.067114 -289.043489) (xy 104.043591 -289.089656) (xy 104.013135 -289.131575) (xy 103.976497 -289.168213)
			(xy 103.934578 -289.198669) (xy 103.888411 -289.222192) (xy 103.839132 -289.238204) (xy 103.787955 -289.24631)
			(xy 103.736141 -289.24631) (xy 103.684964 -289.238204) (xy 103.635685 -289.222192) (xy 103.589518 -289.198669)
			(xy 103.547599 -289.168213) (xy 103.510961 -289.131575) (xy 103.480505 -289.089656) (xy 103.456982 -289.043489)
			(xy 103.44097 -288.99421) (xy 103.432864 -288.943033) (xy 103.432356 -288.917126) (xy 103.15194 -288.917126)
			(xy 103.151518 -288.940067) (xy 103.14509 -288.985498) (xy 103.132444 -289.029604) (xy 103.123492 -289.05073)
			(xy 103.113586 -289.073336) (xy 103.327454 -289.478466) (xy 103.351584 -289.483038) (xy 103.37651 -289.488115)
			(xy 103.424521 -289.50492) (xy 103.469379 -289.528904) (xy 103.510019 -289.559496) (xy 103.545476 -289.59597)
			(xy 103.574906 -289.637459) (xy 103.597612 -289.682977) (xy 103.613053 -289.731444) (xy 103.620863 -289.781708)
			(xy 103.621332 -289.807142) (xy 119.878856 -289.807142) (xy 119.879399 -289.781715) (xy 119.887229 -289.731468)
			(xy 119.90268 -289.683018) (xy 119.925386 -289.637514) (xy 119.954808 -289.596036) (xy 119.990248 -289.559565)
			(xy 120.030867 -289.528967) (xy 120.075701 -289.504967) (xy 120.123688 -289.488134) (xy 120.148604 -289.483038)
			(xy 120.172734 -289.478466) (xy 120.38711 -289.073082) (xy 120.377204 -289.050476) (xy 120.368243 -289.029398)
			(xy 120.355596 -288.985377) (xy 120.349182 -288.940026) (xy 120.348756 -288.917126) (xy 120.349264 -288.891219)
			(xy 120.35737 -288.840042) (xy 120.373382 -288.790763) (xy 120.396905 -288.744596) (xy 120.427361 -288.702677)
			(xy 120.463999 -288.666039) (xy 120.505918 -288.635583) (xy 120.552085 -288.61206) (xy 120.601364 -288.596048)
			(xy 120.652541 -288.587942) (xy 120.704355 -288.587942) (xy 120.755532 -288.596048) (xy 120.804811 -288.61206)
			(xy 120.850978 -288.635583) (xy 120.892897 -288.666039) (xy 120.929535 -288.702677) (xy 120.959991 -288.744596)
			(xy 120.983514 -288.790763) (xy 120.999526 -288.840042) (xy 121.007632 -288.891219) (xy 121.00814 -288.917126)
			(xy 121.007659 -288.942574) (xy 120.999856 -288.992867) (xy 120.984408 -289.041361) (xy 120.961683 -289.086901)
			(xy 120.932222 -289.128403) (xy 120.896727 -289.164878) (xy 120.856043 -289.195458) (xy 120.811139 -289.219415)
			(xy 120.763084 -289.236178) (xy 120.738138 -289.24123) (xy 120.714008 -289.245802) (xy 120.499632 -289.651186)
			(xy 120.509538 -289.673792) (xy 120.518456 -289.694878) (xy 120.531008 -289.738907) (xy 120.537342 -289.78425)
			(xy 120.537732 -289.807142) (xy 121.758456 -289.807142) (xy 121.758999 -289.781715) (xy 121.766829 -289.731468)
			(xy 121.78228 -289.683018) (xy 121.804986 -289.637514) (xy 121.834408 -289.596036) (xy 121.869848 -289.559565)
			(xy 121.910467 -289.528967) (xy 121.955301 -289.504967) (xy 122.003288 -289.488134) (xy 122.028204 -289.483038)
			(xy 122.052334 -289.478466) (xy 122.26671 -289.073082) (xy 122.256804 -289.050476) (xy 122.247843 -289.029398)
			(xy 122.235196 -288.985377) (xy 122.228782 -288.940026) (xy 122.228356 -288.917126) (xy 122.228864 -288.891219)
			(xy 122.23697 -288.840042) (xy 122.252982 -288.790763) (xy 122.276505 -288.744596) (xy 122.306961 -288.702677)
			(xy 122.343599 -288.666039) (xy 122.385518 -288.635583) (xy 122.431685 -288.61206) (xy 122.480964 -288.596048)
			(xy 122.532141 -288.587942) (xy 122.583955 -288.587942) (xy 122.635132 -288.596048) (xy 122.684411 -288.61206)
			(xy 122.730578 -288.635583) (xy 122.772497 -288.666039) (xy 122.809135 -288.702677) (xy 122.839591 -288.744596)
			(xy 122.863114 -288.790763) (xy 122.879126 -288.840042) (xy 122.887232 -288.891219) (xy 122.88774 -288.917126)
			(xy 122.887259 -288.942574) (xy 122.879456 -288.992867) (xy 122.864008 -289.041361) (xy 122.841283 -289.086901)
			(xy 122.811822 -289.128403) (xy 122.776327 -289.164878) (xy 122.735643 -289.195458) (xy 122.690739 -289.219415)
			(xy 122.642684 -289.236178) (xy 122.617738 -289.24123) (xy 122.593608 -289.245802) (xy 122.379232 -289.651186)
			(xy 122.389138 -289.673792) (xy 122.398056 -289.694878) (xy 122.410608 -289.738907) (xy 122.416942 -289.78425)
			(xy 122.417332 -289.807142) (xy 123.638056 -289.807142) (xy 123.638599 -289.781715) (xy 123.646429 -289.731468)
			(xy 123.66188 -289.683018) (xy 123.684586 -289.637514) (xy 123.714008 -289.596036) (xy 123.749448 -289.559565)
			(xy 123.790067 -289.528967) (xy 123.834901 -289.504967) (xy 123.882888 -289.488134) (xy 123.907804 -289.483038)
			(xy 123.931934 -289.478466) (xy 124.14631 -289.073082) (xy 124.136404 -289.050476) (xy 124.127443 -289.029398)
			(xy 124.114796 -288.985377) (xy 124.108382 -288.940026) (xy 124.107956 -288.917126) (xy 124.108464 -288.891219)
			(xy 124.11657 -288.840042) (xy 124.132582 -288.790763) (xy 124.156105 -288.744596) (xy 124.186561 -288.702677)
			(xy 124.223199 -288.666039) (xy 124.265118 -288.635583) (xy 124.311285 -288.61206) (xy 124.360564 -288.596048)
			(xy 124.411741 -288.587942) (xy 124.463555 -288.587942) (xy 124.514732 -288.596048) (xy 124.564011 -288.61206)
			(xy 124.610178 -288.635583) (xy 124.652097 -288.666039) (xy 124.688735 -288.702677) (xy 124.719191 -288.744596)
			(xy 124.742714 -288.790763) (xy 124.758726 -288.840042) (xy 124.766832 -288.891219) (xy 124.76734 -288.917126)
			(xy 124.766859 -288.942574) (xy 124.759056 -288.992867) (xy 124.743608 -289.041361) (xy 124.720883 -289.086901)
			(xy 124.691422 -289.128403) (xy 124.655927 -289.164878) (xy 124.615243 -289.195458) (xy 124.570339 -289.219415)
			(xy 124.522284 -289.236178) (xy 124.497338 -289.24123) (xy 124.473208 -289.245802) (xy 124.258832 -289.651186)
			(xy 124.268738 -289.673792) (xy 124.277656 -289.694878) (xy 124.290208 -289.738907) (xy 124.296542 -289.78425)
			(xy 124.296932 -289.807142) (xy 125.517656 -289.807142) (xy 125.518199 -289.781715) (xy 125.526029 -289.731468)
			(xy 125.54148 -289.683018) (xy 125.564186 -289.637514) (xy 125.593608 -289.596036) (xy 125.629048 -289.559565)
			(xy 125.669667 -289.528967) (xy 125.714501 -289.504967) (xy 125.762488 -289.488134) (xy 125.787404 -289.483038)
			(xy 125.811534 -289.478466) (xy 126.02591 -289.073082) (xy 126.016004 -289.050476) (xy 126.007043 -289.029398)
			(xy 125.994396 -288.985377) (xy 125.987982 -288.940026) (xy 125.987556 -288.917126) (xy 125.988064 -288.891219)
			(xy 125.99617 -288.840042) (xy 126.012182 -288.790763) (xy 126.035705 -288.744596) (xy 126.066161 -288.702677)
			(xy 126.102799 -288.666039) (xy 126.144718 -288.635583) (xy 126.190885 -288.61206) (xy 126.240164 -288.596048)
			(xy 126.291341 -288.587942) (xy 126.343155 -288.587942) (xy 126.394332 -288.596048) (xy 126.443611 -288.61206)
			(xy 126.489778 -288.635583) (xy 126.531697 -288.666039) (xy 126.568335 -288.702677) (xy 126.598791 -288.744596)
			(xy 126.622314 -288.790763) (xy 126.638326 -288.840042) (xy 126.646432 -288.891219) (xy 126.64694 -288.917126)
			(xy 126.646459 -288.942574) (xy 126.638656 -288.992867) (xy 126.623208 -289.041361) (xy 126.600483 -289.086901)
			(xy 126.571022 -289.128403) (xy 126.535527 -289.164878) (xy 126.494843 -289.195458) (xy 126.449939 -289.219415)
			(xy 126.401884 -289.236178) (xy 126.376938 -289.24123) (xy 126.352808 -289.245802) (xy 126.138432 -289.651186)
			(xy 126.148338 -289.673792) (xy 126.157256 -289.694878) (xy 126.169808 -289.738907) (xy 126.176142 -289.78425)
			(xy 126.176532 -289.807142) (xy 127.397256 -289.807142) (xy 127.397799 -289.781715) (xy 127.405629 -289.731468)
			(xy 127.42108 -289.683018) (xy 127.443786 -289.637514) (xy 127.473208 -289.596036) (xy 127.508648 -289.559565)
			(xy 127.549267 -289.528967) (xy 127.594101 -289.504967) (xy 127.642088 -289.488134) (xy 127.667004 -289.483038)
			(xy 127.691134 -289.478466) (xy 127.90551 -289.073082) (xy 127.895604 -289.050476) (xy 127.886643 -289.029398)
			(xy 127.873996 -288.985377) (xy 127.867582 -288.940026) (xy 127.867156 -288.917126) (xy 127.867664 -288.891219)
			(xy 127.87577 -288.840042) (xy 127.891782 -288.790763) (xy 127.915305 -288.744596) (xy 127.945761 -288.702677)
			(xy 127.982399 -288.666039) (xy 128.024318 -288.635583) (xy 128.070485 -288.61206) (xy 128.119764 -288.596048)
			(xy 128.170941 -288.587942) (xy 128.222755 -288.587942) (xy 128.273932 -288.596048) (xy 128.323211 -288.61206)
			(xy 128.369378 -288.635583) (xy 128.411297 -288.666039) (xy 128.447935 -288.702677) (xy 128.478391 -288.744596)
			(xy 128.501914 -288.790763) (xy 128.517926 -288.840042) (xy 128.526032 -288.891219) (xy 128.52654 -288.917126)
			(xy 128.526059 -288.942574) (xy 128.518256 -288.992867) (xy 128.502808 -289.041361) (xy 128.480083 -289.086901)
			(xy 128.450622 -289.128403) (xy 128.415127 -289.164878) (xy 128.374443 -289.195458) (xy 128.329539 -289.219415)
			(xy 128.281484 -289.236178) (xy 128.256538 -289.24123) (xy 128.232408 -289.245802) (xy 128.018032 -289.651186)
			(xy 128.027938 -289.673792) (xy 128.036856 -289.694878) (xy 128.049408 -289.738907) (xy 128.055742 -289.78425)
			(xy 128.056132 -289.807142) (xy 129.276856 -289.807142) (xy 129.277399 -289.781715) (xy 129.285229 -289.731468)
			(xy 129.30068 -289.683018) (xy 129.323386 -289.637514) (xy 129.352808 -289.596036) (xy 129.388248 -289.559565)
			(xy 129.428867 -289.528967) (xy 129.473701 -289.504967) (xy 129.521688 -289.488134) (xy 129.546604 -289.483038)
			(xy 129.570734 -289.478466) (xy 129.78511 -289.073082) (xy 129.775204 -289.050476) (xy 129.766243 -289.029398)
			(xy 129.753596 -288.985377) (xy 129.747182 -288.940026) (xy 129.746756 -288.917126) (xy 129.747264 -288.891219)
			(xy 129.75537 -288.840042) (xy 129.771382 -288.790763) (xy 129.794905 -288.744596) (xy 129.825361 -288.702677)
			(xy 129.861999 -288.666039) (xy 129.903918 -288.635583) (xy 129.950085 -288.61206) (xy 129.999364 -288.596048)
			(xy 130.050541 -288.587942) (xy 130.102355 -288.587942) (xy 130.153532 -288.596048) (xy 130.202811 -288.61206)
			(xy 130.248978 -288.635583) (xy 130.290897 -288.666039) (xy 130.327535 -288.702677) (xy 130.357991 -288.744596)
			(xy 130.381514 -288.790763) (xy 130.397526 -288.840042) (xy 130.405632 -288.891219) (xy 130.40614 -288.917126)
			(xy 130.405659 -288.942574) (xy 130.397856 -288.992867) (xy 130.382408 -289.041361) (xy 130.359683 -289.086901)
			(xy 130.330222 -289.128403) (xy 130.294727 -289.164878) (xy 130.254043 -289.195458) (xy 130.209139 -289.219415)
			(xy 130.161084 -289.236178) (xy 130.136138 -289.24123) (xy 130.112008 -289.245802) (xy 129.897632 -289.651186)
			(xy 129.907538 -289.673792) (xy 129.916456 -289.694878) (xy 129.929008 -289.738907) (xy 129.935342 -289.78425)
			(xy 129.935732 -289.807142) (xy 131.156456 -289.807142) (xy 131.156999 -289.781715) (xy 131.164829 -289.731468)
			(xy 131.18028 -289.683018) (xy 131.202986 -289.637514) (xy 131.232408 -289.596036) (xy 131.267848 -289.559565)
			(xy 131.308467 -289.528967) (xy 131.353301 -289.504967) (xy 131.401288 -289.488134) (xy 131.426204 -289.483038)
			(xy 131.450334 -289.478466) (xy 131.66471 -289.073082) (xy 131.654804 -289.050476) (xy 131.645843 -289.029398)
			(xy 131.633196 -288.985377) (xy 131.626782 -288.940026) (xy 131.626356 -288.917126) (xy 131.626864 -288.891219)
			(xy 131.63497 -288.840042) (xy 131.650982 -288.790763) (xy 131.674505 -288.744596) (xy 131.704961 -288.702677)
			(xy 131.741599 -288.666039) (xy 131.783518 -288.635583) (xy 131.829685 -288.61206) (xy 131.878964 -288.596048)
			(xy 131.930141 -288.587942) (xy 131.981955 -288.587942) (xy 132.033132 -288.596048) (xy 132.082411 -288.61206)
			(xy 132.128578 -288.635583) (xy 132.170497 -288.666039) (xy 132.207135 -288.702677) (xy 132.237591 -288.744596)
			(xy 132.261114 -288.790763) (xy 132.277126 -288.840042) (xy 132.285232 -288.891219) (xy 132.28574 -288.917126)
			(xy 132.285259 -288.942574) (xy 132.277456 -288.992867) (xy 132.262008 -289.041361) (xy 132.239283 -289.086901)
			(xy 132.209822 -289.128403) (xy 132.174327 -289.164878) (xy 132.133643 -289.195458) (xy 132.088739 -289.219415)
			(xy 132.040684 -289.236178) (xy 132.015738 -289.24123) (xy 131.991608 -289.245802) (xy 131.777232 -289.651186)
			(xy 131.787138 -289.673792) (xy 131.796056 -289.694878) (xy 131.808608 -289.738907) (xy 131.814942 -289.78425)
			(xy 131.815332 -289.807142) (xy 133.036056 -289.807142) (xy 133.036599 -289.781715) (xy 133.044429 -289.731468)
			(xy 133.05988 -289.683018) (xy 133.082586 -289.637514) (xy 133.112008 -289.596036) (xy 133.147448 -289.559565)
			(xy 133.188067 -289.528967) (xy 133.232901 -289.504967) (xy 133.280888 -289.488134) (xy 133.305804 -289.483038)
			(xy 133.329934 -289.478466) (xy 133.54431 -289.073082) (xy 133.534404 -289.050476) (xy 133.525443 -289.029398)
			(xy 133.512796 -288.985377) (xy 133.506382 -288.940026) (xy 133.505956 -288.917126) (xy 133.506464 -288.891219)
			(xy 133.51457 -288.840042) (xy 133.530582 -288.790763) (xy 133.554105 -288.744596) (xy 133.584561 -288.702677)
			(xy 133.621199 -288.666039) (xy 133.663118 -288.635583) (xy 133.709285 -288.61206) (xy 133.758564 -288.596048)
			(xy 133.809741 -288.587942) (xy 133.861555 -288.587942) (xy 133.912732 -288.596048) (xy 133.962011 -288.61206)
			(xy 134.008178 -288.635583) (xy 134.050097 -288.666039) (xy 134.086735 -288.702677) (xy 134.117191 -288.744596)
			(xy 134.140714 -288.790763) (xy 134.156726 -288.840042) (xy 134.164832 -288.891219) (xy 134.16534 -288.917126)
			(xy 134.164859 -288.942574) (xy 134.157056 -288.992867) (xy 134.141608 -289.041361) (xy 134.118883 -289.086901)
			(xy 134.089422 -289.128403) (xy 134.053927 -289.164878) (xy 134.013243 -289.195458) (xy 133.968339 -289.219415)
			(xy 133.920284 -289.236178) (xy 133.895338 -289.24123) (xy 133.871208 -289.245802) (xy 133.656832 -289.651186)
			(xy 133.666738 -289.673792) (xy 133.675656 -289.694878) (xy 133.688208 -289.738907) (xy 133.694542 -289.78425)
			(xy 133.694932 -289.807142) (xy 133.694424 -289.833029) (xy 133.686325 -289.884167) (xy 133.670326 -289.933407)
			(xy 133.64682 -289.979539) (xy 133.616388 -290.021426) (xy 133.579778 -290.058036) (xy 133.537891 -290.088468)
			(xy 133.491759 -290.111974) (xy 133.442519 -290.127973) (xy 133.391381 -290.136072) (xy 133.339607 -290.136072)
			(xy 133.288469 -290.127973) (xy 133.239229 -290.111974) (xy 133.193097 -290.088468) (xy 133.15121 -290.058036)
			(xy 133.1146 -290.021426) (xy 133.084168 -289.979539) (xy 133.060662 -289.933407) (xy 133.044663 -289.884167)
			(xy 133.036564 -289.833029) (xy 133.036056 -289.807142) (xy 131.815332 -289.807142) (xy 131.814824 -289.833029)
			(xy 131.806725 -289.884167) (xy 131.790726 -289.933407) (xy 131.76722 -289.979539) (xy 131.736788 -290.021426)
			(xy 131.700178 -290.058036) (xy 131.658291 -290.088468) (xy 131.612159 -290.111974) (xy 131.562919 -290.127973)
			(xy 131.511781 -290.136072) (xy 131.460007 -290.136072) (xy 131.408869 -290.127973) (xy 131.359629 -290.111974)
			(xy 131.313497 -290.088468) (xy 131.27161 -290.058036) (xy 131.235 -290.021426) (xy 131.204568 -289.979539)
			(xy 131.181062 -289.933407) (xy 131.165063 -289.884167) (xy 131.156964 -289.833029) (xy 131.156456 -289.807142)
			(xy 129.935732 -289.807142) (xy 129.935224 -289.833029) (xy 129.927125 -289.884167) (xy 129.911126 -289.933407)
			(xy 129.88762 -289.979539) (xy 129.857188 -290.021426) (xy 129.820578 -290.058036) (xy 129.778691 -290.088468)
			(xy 129.732559 -290.111974) (xy 129.683319 -290.127973) (xy 129.632181 -290.136072) (xy 129.580407 -290.136072)
			(xy 129.529269 -290.127973) (xy 129.480029 -290.111974) (xy 129.433897 -290.088468) (xy 129.39201 -290.058036)
			(xy 129.3554 -290.021426) (xy 129.324968 -289.979539) (xy 129.301462 -289.933407) (xy 129.285463 -289.884167)
			(xy 129.277364 -289.833029) (xy 129.276856 -289.807142) (xy 128.056132 -289.807142) (xy 128.055624 -289.833029)
			(xy 128.047525 -289.884167) (xy 128.031526 -289.933407) (xy 128.00802 -289.979539) (xy 127.977588 -290.021426)
			(xy 127.940978 -290.058036) (xy 127.899091 -290.088468) (xy 127.852959 -290.111974) (xy 127.803719 -290.127973)
			(xy 127.752581 -290.136072) (xy 127.700807 -290.136072) (xy 127.649669 -290.127973) (xy 127.600429 -290.111974)
			(xy 127.554297 -290.088468) (xy 127.51241 -290.058036) (xy 127.4758 -290.021426) (xy 127.445368 -289.979539)
			(xy 127.421862 -289.933407) (xy 127.405863 -289.884167) (xy 127.397764 -289.833029) (xy 127.397256 -289.807142)
			(xy 126.176532 -289.807142) (xy 126.176024 -289.833029) (xy 126.167925 -289.884167) (xy 126.151926 -289.933407)
			(xy 126.12842 -289.979539) (xy 126.097988 -290.021426) (xy 126.061378 -290.058036) (xy 126.019491 -290.088468)
			(xy 125.973359 -290.111974) (xy 125.924119 -290.127973) (xy 125.872981 -290.136072) (xy 125.821207 -290.136072)
			(xy 125.770069 -290.127973) (xy 125.720829 -290.111974) (xy 125.674697 -290.088468) (xy 125.63281 -290.058036)
			(xy 125.5962 -290.021426) (xy 125.565768 -289.979539) (xy 125.542262 -289.933407) (xy 125.526263 -289.884167)
			(xy 125.518164 -289.833029) (xy 125.517656 -289.807142) (xy 124.296932 -289.807142) (xy 124.296424 -289.833029)
			(xy 124.288325 -289.884167) (xy 124.272326 -289.933407) (xy 124.24882 -289.979539) (xy 124.218388 -290.021426)
			(xy 124.181778 -290.058036) (xy 124.139891 -290.088468) (xy 124.093759 -290.111974) (xy 124.044519 -290.127973)
			(xy 123.993381 -290.136072) (xy 123.941607 -290.136072) (xy 123.890469 -290.127973) (xy 123.841229 -290.111974)
			(xy 123.795097 -290.088468) (xy 123.75321 -290.058036) (xy 123.7166 -290.021426) (xy 123.686168 -289.979539)
			(xy 123.662662 -289.933407) (xy 123.646663 -289.884167) (xy 123.638564 -289.833029) (xy 123.638056 -289.807142)
			(xy 122.417332 -289.807142) (xy 122.416824 -289.833029) (xy 122.408725 -289.884167) (xy 122.392726 -289.933407)
			(xy 122.36922 -289.979539) (xy 122.338788 -290.021426) (xy 122.302178 -290.058036) (xy 122.260291 -290.088468)
			(xy 122.214159 -290.111974) (xy 122.164919 -290.127973) (xy 122.113781 -290.136072) (xy 122.062007 -290.136072)
			(xy 122.010869 -290.127973) (xy 121.961629 -290.111974) (xy 121.915497 -290.088468) (xy 121.87361 -290.058036)
			(xy 121.837 -290.021426) (xy 121.806568 -289.979539) (xy 121.783062 -289.933407) (xy 121.767063 -289.884167)
			(xy 121.758964 -289.833029) (xy 121.758456 -289.807142) (xy 120.537732 -289.807142) (xy 120.537224 -289.833029)
			(xy 120.529125 -289.884167) (xy 120.513126 -289.933407) (xy 120.48962 -289.979539) (xy 120.459188 -290.021426)
			(xy 120.422578 -290.058036) (xy 120.380691 -290.088468) (xy 120.334559 -290.111974) (xy 120.285319 -290.127973)
			(xy 120.234181 -290.136072) (xy 120.182407 -290.136072) (xy 120.131269 -290.127973) (xy 120.082029 -290.111974)
			(xy 120.035897 -290.088468) (xy 119.99401 -290.058036) (xy 119.9574 -290.021426) (xy 119.926968 -289.979539)
			(xy 119.903462 -289.933407) (xy 119.887463 -289.884167) (xy 119.879364 -289.833029) (xy 119.878856 -289.807142)
			(xy 103.621332 -289.807142) (xy 103.620824 -289.833029) (xy 103.612725 -289.884167) (xy 103.596726 -289.933407)
			(xy 103.57322 -289.979539) (xy 103.542788 -290.021426) (xy 103.506178 -290.058036) (xy 103.464291 -290.088468)
			(xy 103.418159 -290.111974) (xy 103.368919 -290.127973) (xy 103.317781 -290.136072) (xy 103.266007 -290.136072)
			(xy 103.214869 -290.127973) (xy 103.165629 -290.111974) (xy 103.119497 -290.088468) (xy 103.07761 -290.058036)
			(xy 103.041 -290.021426) (xy 103.010568 -289.979539) (xy 102.987062 -289.933407) (xy 102.971063 -289.884167)
			(xy 102.962964 -289.833029) (xy 102.962456 -289.807142) (xy 102.962456 -289.806634) (xy 102.962859 -289.783785)
			(xy 102.969212 -289.738531) (xy 102.981758 -289.694589) (xy 102.99065 -289.673538) (xy 103.000556 -289.650932)
			(xy 102.786688 -289.245802) (xy 102.762558 -289.24123) (xy 102.737619 -289.236158) (xy 102.689576 -289.219379)
			(xy 102.644683 -289.195414) (xy 102.604007 -289.164832) (xy 102.568517 -289.12836) (xy 102.539055 -289.086867)
			(xy 102.516322 -289.041337) (xy 102.500858 -288.992854) (xy 102.493031 -288.942571) (xy 102.492556 -288.917126)
			(xy 102.21214 -288.917126) (xy 102.211632 -288.943033) (xy 102.203526 -288.99421) (xy 102.187514 -289.043489)
			(xy 102.163991 -289.089656) (xy 102.133535 -289.131575) (xy 102.096897 -289.168213) (xy 102.054978 -289.198669)
			(xy 102.008811 -289.222192) (xy 101.959532 -289.238204) (xy 101.908355 -289.24631) (xy 101.856541 -289.24631)
			(xy 101.805364 -289.238204) (xy 101.756085 -289.222192) (xy 101.709918 -289.198669) (xy 101.667999 -289.168213)
			(xy 101.631361 -289.131575) (xy 101.600905 -289.089656) (xy 101.577382 -289.043489) (xy 101.56137 -288.99421)
			(xy 101.553264 -288.943033) (xy 101.552756 -288.917126) (xy 101.27234 -288.917126) (xy 101.271918 -288.940067)
			(xy 101.26549 -288.985498) (xy 101.252844 -289.029604) (xy 101.243892 -289.05073) (xy 101.233986 -289.073336)
			(xy 101.447854 -289.478466) (xy 101.471984 -289.483038) (xy 101.49691 -289.488115) (xy 101.544921 -289.50492)
			(xy 101.589779 -289.528904) (xy 101.630419 -289.559496) (xy 101.665876 -289.59597) (xy 101.695306 -289.637459)
			(xy 101.718012 -289.682977) (xy 101.733453 -289.731444) (xy 101.741263 -289.781708) (xy 101.741732 -289.807142)
			(xy 101.741224 -289.833029) (xy 101.733125 -289.884167) (xy 101.717126 -289.933407) (xy 101.69362 -289.979539)
			(xy 101.663188 -290.021426) (xy 101.626578 -290.058036) (xy 101.584691 -290.088468) (xy 101.538559 -290.111974)
			(xy 101.489319 -290.127973) (xy 101.438181 -290.136072) (xy 101.386407 -290.136072) (xy 101.335269 -290.127973)
			(xy 101.286029 -290.111974) (xy 101.239897 -290.088468) (xy 101.19801 -290.058036) (xy 101.1614 -290.021426)
			(xy 101.130968 -289.979539) (xy 101.107462 -289.933407) (xy 101.091463 -289.884167) (xy 101.083364 -289.833029)
			(xy 101.082856 -289.807142) (xy 101.082856 -289.806634) (xy 101.083259 -289.783785) (xy 101.089612 -289.738531)
			(xy 101.102158 -289.694589) (xy 101.11105 -289.673538) (xy 101.120956 -289.650932) (xy 100.907088 -289.245802)
			(xy 100.882958 -289.24123) (xy 100.858019 -289.236158) (xy 100.809976 -289.219379) (xy 100.765083 -289.195414)
			(xy 100.724407 -289.164832) (xy 100.688917 -289.12836) (xy 100.659455 -289.086867) (xy 100.636722 -289.041337)
			(xy 100.621258 -288.992854) (xy 100.613431 -288.942571) (xy 100.612956 -288.917126) (xy 100.33254 -288.917126)
			(xy 100.332032 -288.943033) (xy 100.323926 -288.99421) (xy 100.307914 -289.043489) (xy 100.284391 -289.089656)
			(xy 100.253935 -289.131575) (xy 100.217297 -289.168213) (xy 100.175378 -289.198669) (xy 100.129211 -289.222192)
			(xy 100.079932 -289.238204) (xy 100.028755 -289.24631) (xy 99.976941 -289.24631) (xy 99.925764 -289.238204)
			(xy 99.876485 -289.222192) (xy 99.830318 -289.198669) (xy 99.788399 -289.168213) (xy 99.751761 -289.131575)
			(xy 99.721305 -289.089656) (xy 99.697782 -289.043489) (xy 99.68177 -288.99421) (xy 99.673664 -288.943033)
			(xy 99.673156 -288.917126) (xy 99.39274 -288.917126) (xy 99.392318 -288.940067) (xy 99.38589 -288.985498)
			(xy 99.373244 -289.029604) (xy 99.364292 -289.05073) (xy 99.354386 -289.073336) (xy 99.568254 -289.478466)
			(xy 99.592384 -289.483038) (xy 99.61731 -289.488115) (xy 99.665321 -289.50492) (xy 99.710179 -289.528904)
			(xy 99.750819 -289.559496) (xy 99.786276 -289.59597) (xy 99.815706 -289.637459) (xy 99.838412 -289.682977)
			(xy 99.853853 -289.731444) (xy 99.861663 -289.781708) (xy 99.862132 -289.807142) (xy 99.861624 -289.833029)
			(xy 99.853525 -289.884167) (xy 99.837526 -289.933407) (xy 99.81402 -289.979539) (xy 99.783588 -290.021426)
			(xy 99.746978 -290.058036) (xy 99.705091 -290.088468) (xy 99.658959 -290.111974) (xy 99.609719 -290.127973)
			(xy 99.558581 -290.136072) (xy 99.506807 -290.136072) (xy 99.455669 -290.127973) (xy 99.406429 -290.111974)
			(xy 99.360297 -290.088468) (xy 99.31841 -290.058036) (xy 99.2818 -290.021426) (xy 99.251368 -289.979539)
			(xy 99.227862 -289.933407) (xy 99.211863 -289.884167) (xy 99.203764 -289.833029) (xy 99.203256 -289.807142)
			(xy 99.203256 -289.806634) (xy 99.203659 -289.783785) (xy 99.210012 -289.738531) (xy 99.222558 -289.694589)
			(xy 99.23145 -289.673538) (xy 99.241356 -289.650932) (xy 99.027488 -289.245802) (xy 99.003358 -289.24123)
			(xy 98.978419 -289.236158) (xy 98.930376 -289.219379) (xy 98.885483 -289.195414) (xy 98.844807 -289.164832)
			(xy 98.809317 -289.12836) (xy 98.779855 -289.086867) (xy 98.757122 -289.041337) (xy 98.741658 -288.992854)
			(xy 98.733831 -288.942571) (xy 98.733356 -288.917126) (xy 98.45294 -288.917126) (xy 98.452432 -288.943033)
			(xy 98.444326 -288.99421) (xy 98.428314 -289.043489) (xy 98.404791 -289.089656) (xy 98.374335 -289.131575)
			(xy 98.337697 -289.168213) (xy 98.295778 -289.198669) (xy 98.249611 -289.222192) (xy 98.200332 -289.238204)
			(xy 98.149155 -289.24631) (xy 98.097341 -289.24631) (xy 98.046164 -289.238204) (xy 97.996885 -289.222192)
			(xy 97.950718 -289.198669) (xy 97.908799 -289.168213) (xy 97.872161 -289.131575) (xy 97.841705 -289.089656)
			(xy 97.818182 -289.043489) (xy 97.80217 -288.99421) (xy 97.794064 -288.943033) (xy 97.793556 -288.917126)
			(xy 97.51314 -288.917126) (xy 97.512718 -288.940067) (xy 97.50629 -288.985498) (xy 97.493644 -289.029604)
			(xy 97.484692 -289.05073) (xy 97.474786 -289.073336) (xy 97.688654 -289.478466) (xy 97.712784 -289.483038)
			(xy 97.73771 -289.488115) (xy 97.785721 -289.50492) (xy 97.830579 -289.528904) (xy 97.871219 -289.559496)
			(xy 97.906676 -289.59597) (xy 97.936106 -289.637459) (xy 97.958812 -289.682977) (xy 97.974253 -289.731444)
			(xy 97.982063 -289.781708) (xy 97.982532 -289.807142) (xy 97.982024 -289.833029) (xy 97.973925 -289.884167)
			(xy 97.957926 -289.933407) (xy 97.93442 -289.979539) (xy 97.903988 -290.021426) (xy 97.867378 -290.058036)
			(xy 97.825491 -290.088468) (xy 97.779359 -290.111974) (xy 97.730119 -290.127973) (xy 97.678981 -290.136072)
			(xy 97.627207 -290.136072) (xy 97.576069 -290.127973) (xy 97.526829 -290.111974) (xy 97.480697 -290.088468)
			(xy 97.43881 -290.058036) (xy 97.4022 -290.021426) (xy 97.371768 -289.979539) (xy 97.348262 -289.933407)
			(xy 97.332263 -289.884167) (xy 97.324164 -289.833029) (xy 97.323656 -289.807142) (xy 97.323656 -289.806634)
			(xy 97.324059 -289.783785) (xy 97.330412 -289.738531) (xy 97.342958 -289.694589) (xy 97.35185 -289.673538)
			(xy 97.361756 -289.650932) (xy 97.147888 -289.245802) (xy 97.123758 -289.24123) (xy 97.098819 -289.236158)
			(xy 97.050776 -289.219379) (xy 97.005883 -289.195414) (xy 96.965207 -289.164832) (xy 96.929717 -289.12836)
			(xy 96.900255 -289.086867) (xy 96.877522 -289.041337) (xy 96.862058 -288.992854) (xy 96.854231 -288.942571)
			(xy 96.853756 -288.917126) (xy 96.57334 -288.917126) (xy 96.572832 -288.943033) (xy 96.564726 -288.99421)
			(xy 96.548714 -289.043489) (xy 96.525191 -289.089656) (xy 96.494735 -289.131575) (xy 96.458097 -289.168213)
			(xy 96.416178 -289.198669) (xy 96.370011 -289.222192) (xy 96.320732 -289.238204) (xy 96.269555 -289.24631)
			(xy 96.217741 -289.24631) (xy 96.166564 -289.238204) (xy 96.117285 -289.222192) (xy 96.071118 -289.198669)
			(xy 96.029199 -289.168213) (xy 95.992561 -289.131575) (xy 95.962105 -289.089656) (xy 95.938582 -289.043489)
			(xy 95.92257 -288.99421) (xy 95.914464 -288.943033) (xy 95.913956 -288.917126) (xy 95.63354 -288.917126)
			(xy 95.633118 -288.940067) (xy 95.62669 -288.985498) (xy 95.614044 -289.029604) (xy 95.605092 -289.05073)
			(xy 95.595186 -289.073336) (xy 95.809054 -289.478466) (xy 95.833184 -289.483038) (xy 95.85811 -289.488115)
			(xy 95.906121 -289.50492) (xy 95.950979 -289.528904) (xy 95.991619 -289.559496) (xy 96.027076 -289.59597)
			(xy 96.056506 -289.637459) (xy 96.079212 -289.682977) (xy 96.094653 -289.731444) (xy 96.102463 -289.781708)
			(xy 96.102932 -289.807142) (xy 96.102424 -289.833029) (xy 96.094325 -289.884167) (xy 96.078326 -289.933407)
			(xy 96.05482 -289.979539) (xy 96.024388 -290.021426) (xy 95.987778 -290.058036) (xy 95.945891 -290.088468)
			(xy 95.899759 -290.111974) (xy 95.850519 -290.127973) (xy 95.799381 -290.136072) (xy 95.747607 -290.136072)
			(xy 95.696469 -290.127973) (xy 95.647229 -290.111974) (xy 95.601097 -290.088468) (xy 95.55921 -290.058036)
			(xy 95.5226 -290.021426) (xy 95.492168 -289.979539) (xy 95.468662 -289.933407) (xy 95.452663 -289.884167)
			(xy 95.444564 -289.833029) (xy 95.444056 -289.807142) (xy 95.444056 -289.806634) (xy 95.444459 -289.783785)
			(xy 95.450812 -289.738531) (xy 95.463358 -289.694589) (xy 95.47225 -289.673538) (xy 95.482156 -289.650932)
			(xy 95.268288 -289.245802) (xy 95.244158 -289.24123) (xy 95.219219 -289.236158) (xy 95.171176 -289.219379)
			(xy 95.126283 -289.195414) (xy 95.085607 -289.164832) (xy 95.050117 -289.12836) (xy 95.020655 -289.086867)
			(xy 94.997922 -289.041337) (xy 94.982458 -288.992854) (xy 94.974631 -288.942571) (xy 94.974156 -288.917126)
			(xy 94.69374 -288.917126) (xy 94.693232 -288.943033) (xy 94.685126 -288.99421) (xy 94.669114 -289.043489)
			(xy 94.645591 -289.089656) (xy 94.615135 -289.131575) (xy 94.578497 -289.168213) (xy 94.536578 -289.198669)
			(xy 94.490411 -289.222192) (xy 94.441132 -289.238204) (xy 94.389955 -289.24631) (xy 94.338141 -289.24631)
			(xy 94.286964 -289.238204) (xy 94.237685 -289.222192) (xy 94.191518 -289.198669) (xy 94.149599 -289.168213)
			(xy 94.112961 -289.131575) (xy 94.082505 -289.089656) (xy 94.058982 -289.043489) (xy 94.04297 -288.99421)
			(xy 94.034864 -288.943033) (xy 94.034356 -288.917126) (xy 93.75394 -288.917126) (xy 93.753518 -288.940067)
			(xy 93.74709 -288.985498) (xy 93.734444 -289.029604) (xy 93.725492 -289.05073) (xy 93.715586 -289.073336)
			(xy 93.929454 -289.478466) (xy 93.953584 -289.483038) (xy 93.97851 -289.488115) (xy 94.026521 -289.50492)
			(xy 94.071379 -289.528904) (xy 94.112019 -289.559496) (xy 94.147476 -289.59597) (xy 94.176906 -289.637459)
			(xy 94.199612 -289.682977) (xy 94.215053 -289.731444) (xy 94.222863 -289.781708) (xy 94.223332 -289.807142)
			(xy 94.222824 -289.833029) (xy 94.214725 -289.884167) (xy 94.198726 -289.933407) (xy 94.17522 -289.979539)
			(xy 94.144788 -290.021426) (xy 94.108178 -290.058036) (xy 94.066291 -290.088468) (xy 94.020159 -290.111974)
			(xy 93.970919 -290.127973) (xy 93.919781 -290.136072) (xy 93.868007 -290.136072) (xy 93.816869 -290.127973)
			(xy 93.767629 -290.111974) (xy 93.721497 -290.088468) (xy 93.67961 -290.058036) (xy 93.643 -290.021426)
			(xy 93.612568 -289.979539) (xy 93.589062 -289.933407) (xy 93.573063 -289.884167) (xy 93.564964 -289.833029)
			(xy 93.564456 -289.807142) (xy 93.564456 -289.806634) (xy 93.564859 -289.783785) (xy 93.571212 -289.738531)
			(xy 93.583758 -289.694589) (xy 93.59265 -289.673538) (xy 93.602556 -289.650932) (xy 93.388688 -289.245802)
			(xy 93.364558 -289.24123) (xy 93.339619 -289.236158) (xy 93.291576 -289.219379) (xy 93.246683 -289.195414)
			(xy 93.206007 -289.164832) (xy 93.170517 -289.12836) (xy 93.141055 -289.086867) (xy 93.118322 -289.041337)
			(xy 93.102858 -288.992854) (xy 93.095031 -288.942571) (xy 93.094556 -288.917126) (xy 92.81414 -288.917126)
			(xy 92.813632 -288.943033) (xy 92.805526 -288.99421) (xy 92.789514 -289.043489) (xy 92.765991 -289.089656)
			(xy 92.735535 -289.131575) (xy 92.698897 -289.168213) (xy 92.656978 -289.198669) (xy 92.610811 -289.222192)
			(xy 92.561532 -289.238204) (xy 92.510355 -289.24631) (xy 92.458541 -289.24631) (xy 92.407364 -289.238204)
			(xy 92.358085 -289.222192) (xy 92.311918 -289.198669) (xy 92.269999 -289.168213) (xy 92.233361 -289.131575)
			(xy 92.202905 -289.089656) (xy 92.179382 -289.043489) (xy 92.16337 -288.99421) (xy 92.155264 -288.943033)
			(xy 92.154756 -288.917126) (xy 91.87434 -288.917126) (xy 91.873918 -288.940067) (xy 91.86749 -288.985498)
			(xy 91.854844 -289.029604) (xy 91.845892 -289.05073) (xy 91.835986 -289.073336) (xy 92.049854 -289.478466)
			(xy 92.073984 -289.483038) (xy 92.09891 -289.488115) (xy 92.146921 -289.50492) (xy 92.191779 -289.528904)
			(xy 92.232419 -289.559496) (xy 92.267876 -289.59597) (xy 92.297306 -289.637459) (xy 92.320012 -289.682977)
			(xy 92.335453 -289.731444) (xy 92.343263 -289.781708) (xy 92.343732 -289.807142) (xy 92.343224 -289.833029)
			(xy 92.335125 -289.884167) (xy 92.319126 -289.933407) (xy 92.29562 -289.979539) (xy 92.265188 -290.021426)
			(xy 92.228578 -290.058036) (xy 92.186691 -290.088468) (xy 92.140559 -290.111974) (xy 92.091319 -290.127973)
			(xy 92.040181 -290.136072) (xy 91.988407 -290.136072) (xy 91.937269 -290.127973) (xy 91.888029 -290.111974)
			(xy 91.841897 -290.088468) (xy 91.80001 -290.058036) (xy 91.7634 -290.021426) (xy 91.732968 -289.979539)
			(xy 91.709462 -289.933407) (xy 91.693463 -289.884167) (xy 91.685364 -289.833029) (xy 91.684856 -289.807142)
			(xy 91.684856 -289.806634) (xy 91.685259 -289.783785) (xy 91.691612 -289.738531) (xy 91.704158 -289.694589)
			(xy 91.71305 -289.673538) (xy 91.722956 -289.650932) (xy 91.509088 -289.245802) (xy 91.484958 -289.24123)
			(xy 91.460019 -289.236158) (xy 91.411976 -289.219379) (xy 91.367083 -289.195414) (xy 91.326407 -289.164832)
			(xy 91.290917 -289.12836) (xy 91.261455 -289.086867) (xy 91.238722 -289.041337) (xy 91.223258 -288.992854)
			(xy 91.215431 -288.942571) (xy 91.214956 -288.917126) (xy 90.93454 -288.917126) (xy 90.934032 -288.943033)
			(xy 90.925926 -288.99421) (xy 90.909914 -289.043489) (xy 90.886391 -289.089656) (xy 90.855935 -289.131575)
			(xy 90.819297 -289.168213) (xy 90.777378 -289.198669) (xy 90.731211 -289.222192) (xy 90.681932 -289.238204)
			(xy 90.630755 -289.24631) (xy 90.578941 -289.24631) (xy 90.527764 -289.238204) (xy 90.478485 -289.222192)
			(xy 90.432318 -289.198669) (xy 90.390399 -289.168213) (xy 90.353761 -289.131575) (xy 90.323305 -289.089656)
			(xy 90.299782 -289.043489) (xy 90.28377 -288.99421) (xy 90.275664 -288.943033) (xy 90.275156 -288.917126)
			(xy 89.05494 -288.917126) (xy 89.054432 -288.943033) (xy 89.046326 -288.99421) (xy 89.030314 -289.043489)
			(xy 89.006791 -289.089656) (xy 88.976335 -289.131575) (xy 88.939697 -289.168213) (xy 88.897778 -289.198669)
			(xy 88.851611 -289.222192) (xy 88.802332 -289.238204) (xy 88.751155 -289.24631) (xy 88.699341 -289.24631)
			(xy 88.648164 -289.238204) (xy 88.598885 -289.222192) (xy 88.552718 -289.198669) (xy 88.510799 -289.168213)
			(xy 88.474161 -289.131575) (xy 88.443705 -289.089656) (xy 88.420182 -289.043489) (xy 88.40417 -288.99421)
			(xy 88.396064 -288.943033) (xy 88.395556 -288.917126) (xy 2.509012 -288.917126) (xy 2.509012 -297.515026)
			(xy 88.21548 -297.515026) (xy 88.219461 -297.382006) (xy 88.23139 -297.249461) (xy 88.251225 -297.117868)
			(xy 88.278894 -296.987696) (xy 88.314298 -296.859411) (xy 88.357311 -296.733474) (xy 88.407778 -296.610335)
			(xy 88.465519 -296.490434) (xy 88.530328 -296.374201) (xy 88.601972 -296.262051) (xy 88.680194 -296.154387)
			(xy 88.764715 -296.051594) (xy 88.855233 -295.954039) (xy 88.951422 -295.862073) (xy 89.05294 -295.776023)
			(xy 89.159421 -295.696199) (xy 89.270486 -295.622886) (xy 89.385737 -295.556346) (xy 89.504761 -295.496817)
			(xy 89.627132 -295.444513) (xy 89.752411 -295.399621) (xy 89.880152 -295.362302) (xy 90.009895 -295.332689)
			(xy 90.141177 -295.310888) (xy 90.273528 -295.296978) (xy 90.406474 -295.291007) (xy 90.539539 -295.292998)
			(xy 90.672247 -295.302943) (xy 90.804123 -295.320807) (xy 90.934694 -295.346525) (xy 91.063494 -295.380006)
			(xy 91.19006 -295.42113) (xy 91.313941 -295.46975) (xy 91.434692 -295.525691) (xy 91.551882 -295.588753)
			(xy 91.665091 -295.658711) (xy 91.773913 -295.735315) (xy 91.877959 -295.818289) (xy 91.976857 -295.907337)
			(xy 92.070252 -296.00214) (xy 92.15781 -296.102358) (xy 92.239219 -296.207634) (xy 92.314185 -296.31759)
			(xy 92.382442 -296.431832) (xy 92.443744 -296.549952) (xy 92.497873 -296.671527) (xy 92.544634 -296.796121)
			(xy 92.58386 -296.923289) (xy 92.61541 -297.052575) (xy 92.639173 -297.183516) (xy 92.655062 -297.315644)
			(xy 92.66302 -297.448486) (xy 92.663518 -297.515026) (xy 131.195582 -297.515026) (xy 131.199563 -297.382006)
			(xy 131.211492 -297.249461) (xy 131.231327 -297.117868) (xy 131.258996 -296.987696) (xy 131.2944 -296.859411)
			(xy 131.337413 -296.733474) (xy 131.38788 -296.610335) (xy 131.445621 -296.490434) (xy 131.51043 -296.374201)
			(xy 131.582074 -296.262051) (xy 131.660296 -296.154387) (xy 131.744817 -296.051594) (xy 131.835335 -295.954039)
			(xy 131.931524 -295.862073) (xy 132.033042 -295.776023) (xy 132.139523 -295.696199) (xy 132.250588 -295.622886)
			(xy 132.365839 -295.556346) (xy 132.484863 -295.496817) (xy 132.607234 -295.444513) (xy 132.732513 -295.399621)
			(xy 132.860254 -295.362302) (xy 132.989997 -295.332689) (xy 133.121279 -295.310888) (xy 133.25363 -295.296978)
			(xy 133.386576 -295.291007) (xy 133.519641 -295.292998) (xy 133.652349 -295.302943) (xy 133.784225 -295.320807)
			(xy 133.914796 -295.346525) (xy 134.043596 -295.380006) (xy 134.170162 -295.42113) (xy 134.294043 -295.46975)
			(xy 134.414794 -295.525691) (xy 134.531984 -295.588753) (xy 134.645193 -295.658711) (xy 134.754015 -295.735315)
			(xy 134.858061 -295.818289) (xy 134.956959 -295.907337) (xy 135.050354 -296.00214) (xy 135.137912 -296.102358)
			(xy 135.219321 -296.207634) (xy 135.294287 -296.31759) (xy 135.362544 -296.431832) (xy 135.423846 -296.549952)
			(xy 135.477975 -296.671527) (xy 135.524736 -296.796121) (xy 135.563962 -296.923289) (xy 135.595512 -297.052575)
			(xy 135.619275 -297.183516) (xy 135.635164 -297.315644) (xy 135.643122 -297.448486) (xy 135.64362 -297.515026)
			(xy 336.155548 -297.515026) (xy 336.159529 -297.382006) (xy 336.171458 -297.249461) (xy 336.191293 -297.117868)
			(xy 336.218962 -296.987696) (xy 336.254366 -296.859411) (xy 336.297379 -296.733474) (xy 336.347846 -296.610335)
			(xy 336.405587 -296.490434) (xy 336.470396 -296.374201) (xy 336.54204 -296.262051) (xy 336.620262 -296.154387)
			(xy 336.704783 -296.051594) (xy 336.795301 -295.954039) (xy 336.89149 -295.862073) (xy 336.993008 -295.776023)
			(xy 337.099489 -295.696199) (xy 337.210554 -295.622886) (xy 337.325805 -295.556346) (xy 337.444829 -295.496817)
			(xy 337.5672 -295.444513) (xy 337.692479 -295.399621) (xy 337.82022 -295.362302) (xy 337.949963 -295.332689)
			(xy 338.081245 -295.310888) (xy 338.213596 -295.296978) (xy 338.346542 -295.291007) (xy 338.479607 -295.292998)
			(xy 338.612315 -295.302943) (xy 338.744191 -295.320807) (xy 338.874762 -295.346525) (xy 339.003562 -295.380006)
			(xy 339.130128 -295.42113) (xy 339.254009 -295.46975) (xy 339.37476 -295.525691) (xy 339.49195 -295.588753)
			(xy 339.605159 -295.658711) (xy 339.713981 -295.735315) (xy 339.818027 -295.818289) (xy 339.916925 -295.907337)
			(xy 340.01032 -296.00214) (xy 340.097878 -296.102358) (xy 340.179287 -296.207634) (xy 340.254253 -296.31759)
			(xy 340.32251 -296.431832) (xy 340.383812 -296.549952) (xy 340.437941 -296.671527) (xy 340.484702 -296.796121)
			(xy 340.523928 -296.923289) (xy 340.555478 -297.052575) (xy 340.579241 -297.183516) (xy 340.59513 -297.315644)
			(xy 340.603088 -297.448486) (xy 340.603586 -297.515026) (xy 379.13565 -297.515026) (xy 379.139631 -297.382006)
			(xy 379.15156 -297.249461) (xy 379.171395 -297.117868) (xy 379.199064 -296.987696) (xy 379.234468 -296.859411)
			(xy 379.277481 -296.733474) (xy 379.327948 -296.610335) (xy 379.385689 -296.490434) (xy 379.450498 -296.374201)
			(xy 379.522142 -296.262051) (xy 379.600364 -296.154387) (xy 379.684885 -296.051594) (xy 379.775403 -295.954039)
			(xy 379.871592 -295.862073) (xy 379.97311 -295.776023) (xy 380.079591 -295.696199) (xy 380.190656 -295.622886)
			(xy 380.305907 -295.556346) (xy 380.424931 -295.496817) (xy 380.547302 -295.444513) (xy 380.672581 -295.399621)
			(xy 380.800322 -295.362302) (xy 380.930065 -295.332689) (xy 381.061347 -295.310888) (xy 381.193698 -295.296978)
			(xy 381.326644 -295.291007) (xy 381.459709 -295.292998) (xy 381.592417 -295.302943) (xy 381.724293 -295.320807)
			(xy 381.854864 -295.346525) (xy 381.983664 -295.380006) (xy 382.11023 -295.42113) (xy 382.234111 -295.46975)
			(xy 382.354862 -295.525691) (xy 382.472052 -295.588753) (xy 382.585261 -295.658711) (xy 382.694083 -295.735315)
			(xy 382.798129 -295.818289) (xy 382.897027 -295.907337) (xy 382.990422 -296.00214) (xy 383.07798 -296.102358)
			(xy 383.159389 -296.207634) (xy 383.234355 -296.31759) (xy 383.302612 -296.431832) (xy 383.363914 -296.549952)
			(xy 383.418043 -296.671527) (xy 383.464804 -296.796121) (xy 383.50403 -296.923289) (xy 383.53558 -297.052575)
			(xy 383.559343 -297.183516) (xy 383.575232 -297.315644) (xy 383.58319 -297.448486) (xy 383.583688 -297.515026)
			(xy 383.58319 -297.581566) (xy 383.575232 -297.714408) (xy 383.559343 -297.846536) (xy 383.53558 -297.977477)
			(xy 383.50403 -298.106763) (xy 383.464804 -298.233931) (xy 383.418043 -298.358525) (xy 383.363914 -298.4801)
			(xy 383.302612 -298.59822) (xy 383.234355 -298.712462) (xy 383.159389 -298.822418) (xy 383.07798 -298.927694)
			(xy 382.990422 -299.027912) (xy 382.897027 -299.122715) (xy 382.798129 -299.211763) (xy 382.694083 -299.294737)
			(xy 382.585261 -299.371341) (xy 382.472052 -299.441299) (xy 382.354862 -299.504361) (xy 382.234111 -299.560302)
			(xy 382.11023 -299.608922) (xy 381.983664 -299.650046) (xy 381.854864 -299.683527) (xy 381.724293 -299.709245)
			(xy 381.592417 -299.727109) (xy 381.459709 -299.737054) (xy 381.326644 -299.739045) (xy 381.193698 -299.733074)
			(xy 381.061347 -299.719164) (xy 380.930065 -299.697363) (xy 380.800322 -299.66775) (xy 380.672581 -299.630431)
			(xy 380.547302 -299.585539) (xy 380.424931 -299.533235) (xy 380.305907 -299.473706) (xy 380.190656 -299.407166)
			(xy 380.079591 -299.333853) (xy 379.97311 -299.254029) (xy 379.871592 -299.167979) (xy 379.775403 -299.076013)
			(xy 379.684885 -298.978458) (xy 379.600364 -298.875665) (xy 379.522142 -298.768001) (xy 379.450498 -298.655851)
			(xy 379.385689 -298.539618) (xy 379.327948 -298.419717) (xy 379.277481 -298.296578) (xy 379.234468 -298.170641)
			(xy 379.199064 -298.042356) (xy 379.171395 -297.912184) (xy 379.15156 -297.780591) (xy 379.139631 -297.648046)
			(xy 379.13565 -297.515026) (xy 340.603586 -297.515026) (xy 340.603088 -297.581566) (xy 340.59513 -297.714408)
			(xy 340.579241 -297.846536) (xy 340.555478 -297.977477) (xy 340.523928 -298.106763) (xy 340.484702 -298.233931)
			(xy 340.437941 -298.358525) (xy 340.383812 -298.4801) (xy 340.32251 -298.59822) (xy 340.254253 -298.712462)
			(xy 340.179287 -298.822418) (xy 340.097878 -298.927694) (xy 340.01032 -299.027912) (xy 339.916925 -299.122715)
			(xy 339.818027 -299.211763) (xy 339.713981 -299.294737) (xy 339.605159 -299.371341) (xy 339.49195 -299.441299)
			(xy 339.37476 -299.504361) (xy 339.254009 -299.560302) (xy 339.130128 -299.608922) (xy 339.003562 -299.650046)
			(xy 338.874762 -299.683527) (xy 338.744191 -299.709245) (xy 338.612315 -299.727109) (xy 338.479607 -299.737054)
			(xy 338.346542 -299.739045) (xy 338.213596 -299.733074) (xy 338.081245 -299.719164) (xy 337.949963 -299.697363)
			(xy 337.82022 -299.66775) (xy 337.692479 -299.630431) (xy 337.5672 -299.585539) (xy 337.444829 -299.533235)
			(xy 337.325805 -299.473706) (xy 337.210554 -299.407166) (xy 337.099489 -299.333853) (xy 336.993008 -299.254029)
			(xy 336.89149 -299.167979) (xy 336.795301 -299.076013) (xy 336.704783 -298.978458) (xy 336.620262 -298.875665)
			(xy 336.54204 -298.768001) (xy 336.470396 -298.655851) (xy 336.405587 -298.539618) (xy 336.347846 -298.419717)
			(xy 336.297379 -298.296578) (xy 336.254366 -298.170641) (xy 336.218962 -298.042356) (xy 336.191293 -297.912184)
			(xy 336.171458 -297.780591) (xy 336.159529 -297.648046) (xy 336.155548 -297.515026) (xy 135.64362 -297.515026)
			(xy 135.643122 -297.581566) (xy 135.635164 -297.714408) (xy 135.619275 -297.846536) (xy 135.595512 -297.977477)
			(xy 135.563962 -298.106763) (xy 135.524736 -298.233931) (xy 135.477975 -298.358525) (xy 135.423846 -298.4801)
			(xy 135.362544 -298.59822) (xy 135.294287 -298.712462) (xy 135.219321 -298.822418) (xy 135.137912 -298.927694)
			(xy 135.050354 -299.027912) (xy 134.956959 -299.122715) (xy 134.858061 -299.211763) (xy 134.754015 -299.294737)
			(xy 134.645193 -299.371341) (xy 134.531984 -299.441299) (xy 134.414794 -299.504361) (xy 134.294043 -299.560302)
			(xy 134.170162 -299.608922) (xy 134.043596 -299.650046) (xy 133.914796 -299.683527) (xy 133.784225 -299.709245)
			(xy 133.652349 -299.727109) (xy 133.519641 -299.737054) (xy 133.386576 -299.739045) (xy 133.25363 -299.733074)
			(xy 133.121279 -299.719164) (xy 132.989997 -299.697363) (xy 132.860254 -299.66775) (xy 132.732513 -299.630431)
			(xy 132.607234 -299.585539) (xy 132.484863 -299.533235) (xy 132.365839 -299.473706) (xy 132.250588 -299.407166)
			(xy 132.139523 -299.333853) (xy 132.033042 -299.254029) (xy 131.931524 -299.167979) (xy 131.835335 -299.076013)
			(xy 131.744817 -298.978458) (xy 131.660296 -298.875665) (xy 131.582074 -298.768001) (xy 131.51043 -298.655851)
			(xy 131.445621 -298.539618) (xy 131.38788 -298.419717) (xy 131.337413 -298.296578) (xy 131.2944 -298.170641)
			(xy 131.258996 -298.042356) (xy 131.231327 -297.912184) (xy 131.211492 -297.780591) (xy 131.199563 -297.648046)
			(xy 131.195582 -297.515026) (xy 92.663518 -297.515026) (xy 92.66302 -297.581566) (xy 92.655062 -297.714408)
			(xy 92.639173 -297.846536) (xy 92.61541 -297.977477) (xy 92.58386 -298.106763) (xy 92.544634 -298.233931)
			(xy 92.497873 -298.358525) (xy 92.443744 -298.4801) (xy 92.382442 -298.59822) (xy 92.314185 -298.712462)
			(xy 92.239219 -298.822418) (xy 92.15781 -298.927694) (xy 92.070252 -299.027912) (xy 91.976857 -299.122715)
			(xy 91.877959 -299.211763) (xy 91.773913 -299.294737) (xy 91.665091 -299.371341) (xy 91.551882 -299.441299)
			(xy 91.434692 -299.504361) (xy 91.313941 -299.560302) (xy 91.19006 -299.608922) (xy 91.063494 -299.650046)
			(xy 90.934694 -299.683527) (xy 90.804123 -299.709245) (xy 90.672247 -299.727109) (xy 90.539539 -299.737054)
			(xy 90.406474 -299.739045) (xy 90.273528 -299.733074) (xy 90.141177 -299.719164) (xy 90.009895 -299.697363)
			(xy 89.880152 -299.66775) (xy 89.752411 -299.630431) (xy 89.627132 -299.585539) (xy 89.504761 -299.533235)
			(xy 89.385737 -299.473706) (xy 89.270486 -299.407166) (xy 89.159421 -299.333853) (xy 89.05294 -299.254029)
			(xy 88.951422 -299.167979) (xy 88.855233 -299.076013) (xy 88.764715 -298.978458) (xy 88.680194 -298.875665)
			(xy 88.601972 -298.768001) (xy 88.530328 -298.655851) (xy 88.465519 -298.539618) (xy 88.407778 -298.419717)
			(xy 88.357311 -298.296578) (xy 88.314298 -298.170641) (xy 88.278894 -298.042356) (xy 88.251225 -297.912184)
			(xy 88.23139 -297.780591) (xy 88.219461 -297.648046) (xy 88.21548 -297.515026) (xy 2.509012 -297.515026)
			(xy 2.509012 -360.76382) (xy 4.226823 -360.76382) (xy 4.230819 -360.553934) (xy 4.242804 -360.344352)
			(xy 4.262758 -360.135378) (xy 4.290654 -359.927316) (xy 4.326451 -359.720466) (xy 4.370096 -359.515129)
			(xy 4.421528 -359.311603) (xy 4.48067 -359.110182) (xy 4.547438 -358.911159) (xy 4.621734 -358.714822)
			(xy 4.703452 -358.521456) (xy 4.792471 -358.331341) (xy 4.888664 -358.144753) (xy 4.991891 -357.961962)
			(xy 5.102002 -357.783234) (xy 5.218837 -357.608827) (xy 5.342227 -357.438995) (xy 5.471994 -357.273983)
			(xy 5.607948 -357.114032) (xy 5.749894 -356.959372) (xy 5.897624 -356.810228) (xy 6.050926 -356.666817)
			(xy 6.209576 -356.529346) (xy 6.373345 -356.398014) (xy 6.541995 -356.273013) (xy 6.715281 -356.154522)
			(xy 6.892953 -356.042715) (xy 7.074753 -355.937753) (xy 7.260417 -355.839788) (xy 7.449675 -355.748963)
			(xy 7.642255 -355.665409) (xy 7.837876 -355.589246) (xy 8.036254 -355.520587) (xy 8.237103 -355.45953)
			(xy 8.44013 -355.406163) (xy 8.645043 -355.360565) (xy 8.851542 -355.3228) (xy 9.059329 -355.292925)
			(xy 9.268104 -355.270982) (xy 9.477562 -355.257003) (xy 9.687401 -355.251008) (xy 9.897315 -355.253007)
			(xy 10.107002 -355.262995) (xy 10.316156 -355.28096) (xy 10.524474 -355.306874) (xy 10.731655 -355.340699)
			(xy 10.937399 -355.382388) (xy 11.141405 -355.43188) (xy 11.34338 -355.489102) (xy 11.54303 -355.553972)
			(xy 11.740065 -355.626396) (xy 11.934201 -355.706269) (xy 12.125154 -355.793475) (xy 12.31265 -355.887887)
			(xy 12.496415 -355.989369) (xy 12.676183 -356.097773) (xy 12.851694 -356.212943) (xy 13.022693 -356.334711)
			(xy 13.188933 -356.4629) (xy 13.350172 -356.597326) (xy 13.506176 -356.737793) (xy 13.656719 -356.884097)
			(xy 13.801583 -357.036026) (xy 13.940558 -357.19336) (xy 14.073443 -357.355871) (xy 14.200044 -357.523324)
			(xy 14.320179 -357.695474) (xy 14.433673 -357.872074) (xy 14.540361 -358.052866) (xy 14.640088 -358.237589)
			(xy 14.732711 -358.425975) (xy 14.818095 -358.61775) (xy 14.896116 -358.812637) (xy 14.966661 -359.010353)
			(xy 15.029628 -359.210611) (xy 15.084925 -359.413121) (xy 15.132472 -359.61759) (xy 15.1722 -359.823721)
			(xy 15.204052 -360.031214) (xy 15.227982 -360.23977) (xy 15.243954 -360.449086) (xy 15.251946 -360.658858)
			(xy 15.252446 -360.76382) (xy 15.251946 -360.868782) (xy 15.243954 -361.078554) (xy 15.239789 -361.133136)
			(xy 121.446286 -361.133136) (xy 121.450375 -361.077254) (xy 121.462558 -361.022564) (xy 121.482574 -360.97023)
			(xy 121.509997 -360.921368) (xy 121.544242 -360.87702) (xy 121.584578 -360.83813) (xy 121.630148 -360.805528)
			(xy 121.679979 -360.779909) (xy 121.733009 -360.761817) (xy 121.788107 -360.75164) (xy 121.844101 -360.749594)
			(xy 121.899796 -360.755722) (xy 121.930771 -360.76382) (xy 211.161635 -360.76382) (xy 211.16566 -360.621628)
			(xy 211.177723 -360.479892) (xy 211.197786 -360.339066) (xy 211.225784 -360.1996) (xy 211.261628 -360.061941)
			(xy 211.305202 -359.926531) (xy 211.356367 -359.793803) (xy 211.41496 -359.664182) (xy 211.480791 -359.538084)
			(xy 211.553652 -359.415912) (xy 211.633307 -359.298058) (xy 211.719503 -359.184899) (xy 211.811962 -359.076797)
			(xy 211.91039 -358.9741) (xy 212.014469 -358.877136) (xy 212.123868 -358.786216) (xy 212.238236 -358.70163)
			(xy 212.357205 -358.62365) (xy 212.480396 -358.552526) (xy 212.607413 -358.488485) (xy 212.73785 -358.431733)
			(xy 212.871289 -358.382451) (xy 213.007302 -358.340797) (xy 213.145454 -358.306905) (xy 213.285303 -358.280884)
			(xy 213.426399 -358.262816) (xy 213.568291 -358.252759) (xy 213.710526 -358.250746) (xy 213.852646 -358.256783)
			(xy 213.994197 -358.270851) (xy 214.134726 -358.292905) (xy 214.273781 -358.322874) (xy 214.410919 -358.360662)
			(xy 214.545699 -358.406148) (xy 214.67769 -358.459186) (xy 214.806469 -358.519607) (xy 214.931623 -358.587216)
			(xy 215.052751 -358.661798) (xy 215.169467 -358.743114) (xy 215.281395 -358.830902) (xy 215.388177 -358.924882)
			(xy 215.489471 -359.024752) (xy 215.584952 -359.130194) (xy 215.674316 -359.240868) (xy 215.757274 -359.356421)
			(xy 215.833563 -359.476482) (xy 215.902937 -359.600667) (xy 215.965174 -359.728578) (xy 216.020075 -359.859805)
			(xy 216.067463 -359.993928) (xy 216.107188 -360.130517) (xy 216.139121 -360.269135) (xy 216.163162 -360.409337)
			(xy 216.179231 -360.550675) (xy 216.187279 -360.692696) (xy 216.187782 -360.76382) (xy 255.611635 -360.76382)
			(xy 255.61566 -360.621628) (xy 255.627723 -360.479892) (xy 255.647786 -360.339066) (xy 255.675784 -360.1996)
			(xy 255.711628 -360.061941) (xy 255.755202 -359.926531) (xy 255.806367 -359.793803) (xy 255.86496 -359.664182)
			(xy 255.930791 -359.538084) (xy 256.003652 -359.415912) (xy 256.083307 -359.298058) (xy 256.169503 -359.184899)
			(xy 256.261962 -359.076797) (xy 256.36039 -358.9741) (xy 256.464469 -358.877136) (xy 256.573868 -358.786216)
			(xy 256.688236 -358.70163) (xy 256.807205 -358.62365) (xy 256.930396 -358.552526) (xy 257.057413 -358.488485)
			(xy 257.18785 -358.431733) (xy 257.321289 -358.382451) (xy 257.457302 -358.340797) (xy 257.595454 -358.306905)
			(xy 257.735303 -358.280884) (xy 257.876399 -358.262816) (xy 258.018291 -358.252759) (xy 258.160526 -358.250746)
			(xy 258.302646 -358.256783) (xy 258.444197 -358.270851) (xy 258.584726 -358.292905) (xy 258.723781 -358.322874)
			(xy 258.860919 -358.360662) (xy 258.995699 -358.406148) (xy 259.12769 -358.459186) (xy 259.256469 -358.519607)
			(xy 259.381623 -358.587216) (xy 259.502751 -358.661798) (xy 259.619467 -358.743114) (xy 259.731395 -358.830902)
			(xy 259.838177 -358.924882) (xy 259.939471 -359.024752) (xy 260.034952 -359.130194) (xy 260.124316 -359.240868)
			(xy 260.207274 -359.356421) (xy 260.283563 -359.476482) (xy 260.352937 -359.600667) (xy 260.415174 -359.728578)
			(xy 260.470075 -359.859805) (xy 260.517463 -359.993928) (xy 260.557188 -360.130517) (xy 260.589121 -360.269135)
			(xy 260.613162 -360.409337) (xy 260.629231 -360.550675) (xy 260.637279 -360.692696) (xy 260.637782 -360.76382)
			(xy 260.637279 -360.834944) (xy 260.629231 -360.976965) (xy 260.613162 -361.118303) (xy 260.610619 -361.133136)
			(xy 369.3861 -361.133136) (xy 369.390189 -361.077254) (xy 369.402372 -361.022564) (xy 369.422388 -360.97023)
			(xy 369.449811 -360.921368) (xy 369.484056 -360.87702) (xy 369.524392 -360.83813) (xy 369.569962 -360.805528)
			(xy 369.619793 -360.779909) (xy 369.672823 -360.761817) (xy 369.727921 -360.75164) (xy 369.783915 -360.749594)
			(xy 369.83961 -360.755722) (xy 369.870585 -360.76382) (xy 456.565771 -360.76382) (xy 456.569767 -360.553934)
			(xy 456.581752 -360.344352) (xy 456.601706 -360.135378) (xy 456.629602 -359.927316) (xy 456.665399 -359.720466)
			(xy 456.709044 -359.515129) (xy 456.760476 -359.311603) (xy 456.819618 -359.110182) (xy 456.886386 -358.911159)
			(xy 456.960682 -358.714822) (xy 457.0424 -358.521456) (xy 457.131419 -358.331341) (xy 457.227612 -358.144753)
			(xy 457.330839 -357.961962) (xy 457.44095 -357.783234) (xy 457.557785 -357.608827) (xy 457.681175 -357.438995)
			(xy 457.810942 -357.273983) (xy 457.946896 -357.114032) (xy 458.088842 -356.959372) (xy 458.236572 -356.810228)
			(xy 458.389874 -356.666817) (xy 458.548524 -356.529346) (xy 458.712293 -356.398014) (xy 458.880943 -356.273013)
			(xy 459.054229 -356.154522) (xy 459.231901 -356.042715) (xy 459.413701 -355.937753) (xy 459.599365 -355.839788)
			(xy 459.788623 -355.748963) (xy 459.981203 -355.665409) (xy 460.176824 -355.589246) (xy 460.375202 -355.520587)
			(xy 460.576051 -355.45953) (xy 460.779078 -355.406163) (xy 460.983991 -355.360565) (xy 461.19049 -355.3228)
			(xy 461.398277 -355.292925) (xy 461.607052 -355.270982) (xy 461.81651 -355.257003) (xy 462.026349 -355.251008)
			(xy 462.236263 -355.253007) (xy 462.44595 -355.262995) (xy 462.655104 -355.28096) (xy 462.863422 -355.306874)
			(xy 463.070603 -355.340699) (xy 463.276347 -355.382388) (xy 463.480353 -355.43188) (xy 463.682328 -355.489102)
			(xy 463.881978 -355.553972) (xy 464.079013 -355.626396) (xy 464.273149 -355.706269) (xy 464.464102 -355.793475)
			(xy 464.651598 -355.887887) (xy 464.835363 -355.989369) (xy 465.015131 -356.097773) (xy 465.190642 -356.212943)
			(xy 465.361641 -356.334711) (xy 465.527881 -356.4629) (xy 465.68912 -356.597326) (xy 465.845124 -356.737793)
			(xy 465.995667 -356.884097) (xy 466.140531 -357.036026) (xy 466.279506 -357.19336) (xy 466.412391 -357.355871)
			(xy 466.538992 -357.523324) (xy 466.659127 -357.695474) (xy 466.772621 -357.872074) (xy 466.879309 -358.052866)
			(xy 466.979036 -358.237589) (xy 467.071659 -358.425975) (xy 467.157043 -358.61775) (xy 467.235064 -358.812637)
			(xy 467.305609 -359.010353) (xy 467.368576 -359.210611) (xy 467.423873 -359.413121) (xy 467.47142 -359.61759)
			(xy 467.511148 -359.823721) (xy 467.543 -360.031214) (xy 467.56693 -360.23977) (xy 467.582902 -360.449086)
			(xy 467.590894 -360.658858) (xy 467.591394 -360.76382) (xy 467.590894 -360.868782) (xy 467.582902 -361.078554)
			(xy 467.56693 -361.28787) (xy 467.543 -361.496426) (xy 467.511148 -361.703919) (xy 467.47142 -361.91005)
			(xy 467.423873 -362.114519) (xy 467.368576 -362.317029) (xy 467.305609 -362.517287) (xy 467.235064 -362.715003)
			(xy 467.157043 -362.90989) (xy 467.071659 -363.101665) (xy 466.979036 -363.290051) (xy 466.879309 -363.474774)
			(xy 466.772621 -363.655566) (xy 466.659127 -363.832166) (xy 466.538992 -364.004316) (xy 466.412391 -364.171769)
			(xy 466.279506 -364.33428) (xy 466.140531 -364.491614) (xy 465.995667 -364.643543) (xy 465.845124 -364.789847)
			(xy 465.68912 -364.930314) (xy 465.527881 -365.06474) (xy 465.361641 -365.192929) (xy 465.190642 -365.314697)
			(xy 465.015131 -365.429867) (xy 464.835363 -365.538271) (xy 464.651598 -365.639753) (xy 464.464102 -365.734165)
			(xy 464.273149 -365.821371) (xy 464.079013 -365.901244) (xy 463.881978 -365.973668) (xy 463.682328 -366.038538)
			(xy 463.480353 -366.09576) (xy 463.276347 -366.145252) (xy 463.070603 -366.186941) (xy 462.863422 -366.220766)
			(xy 462.655104 -366.24668) (xy 462.44595 -366.264645) (xy 462.236263 -366.274633) (xy 462.026349 -366.276632)
			(xy 461.81651 -366.270637) (xy 461.607052 -366.256658) (xy 461.398277 -366.234715) (xy 461.19049 -366.20484)
			(xy 460.983991 -366.167075) (xy 460.779078 -366.121477) (xy 460.576051 -366.06811) (xy 460.375202 -366.007053)
			(xy 460.176824 -365.938394) (xy 459.981203 -365.862231) (xy 459.788623 -365.778677) (xy 459.599365 -365.687852)
			(xy 459.413701 -365.589887) (xy 459.231901 -365.484925) (xy 459.054229 -365.373118) (xy 458.880943 -365.254627)
			(xy 458.712293 -365.129626) (xy 458.548524 -364.998294) (xy 458.389874 -364.860823) (xy 458.236572 -364.717412)
			(xy 458.088842 -364.568268) (xy 457.946896 -364.413608) (xy 457.810942 -364.253657) (xy 457.681175 -364.088645)
			(xy 457.557785 -363.918813) (xy 457.44095 -363.744406) (xy 457.330839 -363.565678) (xy 457.227612 -363.382887)
			(xy 457.131419 -363.196299) (xy 457.0424 -363.006184) (xy 456.960682 -362.812818) (xy 456.886386 -362.616481)
			(xy 456.819618 -362.417458) (xy 456.760476 -362.216037) (xy 456.709044 -362.012511) (xy 456.665399 -361.807174)
			(xy 456.629602 -361.600324) (xy 456.601706 -361.392262) (xy 456.581752 -361.183288) (xy 456.569767 -360.973706)
			(xy 456.565771 -360.76382) (xy 369.870585 -360.76382) (xy 369.893819 -360.769894) (xy 369.945387 -360.791808)
			(xy 369.993215 -360.820997) (xy 370.036283 -360.856838) (xy 370.073673 -360.898568) (xy 370.104589 -360.945298)
			(xy 370.128372 -360.996031) (xy 370.144514 -361.049687) (xy 370.152673 -361.105121) (xy 370.153184 -361.133136)
			(xy 370.152673 -361.161151) (xy 370.144514 -361.216585) (xy 370.128372 -361.270241) (xy 370.104589 -361.320974)
			(xy 370.073673 -361.367704) (xy 370.036283 -361.409434) (xy 369.993215 -361.445275) (xy 369.945387 -361.474464)
			(xy 369.893819 -361.496378) (xy 369.83961 -361.51055) (xy 369.783915 -361.516678) (xy 369.727921 -361.514632)
			(xy 369.672823 -361.504455) (xy 369.619793 -361.486363) (xy 369.569962 -361.460744) (xy 369.524392 -361.428142)
			(xy 369.484056 -361.389252) (xy 369.449811 -361.344904) (xy 369.422388 -361.296042) (xy 369.402372 -361.243708)
			(xy 369.390189 -361.189018) (xy 369.3861 -361.133136) (xy 260.610619 -361.133136) (xy 260.589121 -361.258505)
			(xy 260.557188 -361.397123) (xy 260.517463 -361.533712) (xy 260.470075 -361.667835) (xy 260.415174 -361.799062)
			(xy 260.352937 -361.926973) (xy 260.283563 -362.051158) (xy 260.207274 -362.171219) (xy 260.124316 -362.286772)
			(xy 260.034952 -362.397446) (xy 259.939471 -362.502888) (xy 259.838177 -362.602758) (xy 259.731395 -362.696738)
			(xy 259.619467 -362.784526) (xy 259.502751 -362.865842) (xy 259.381623 -362.940424) (xy 259.256469 -363.008033)
			(xy 259.12769 -363.068454) (xy 258.995699 -363.121492) (xy 258.860919 -363.166978) (xy 258.723781 -363.204766)
			(xy 258.584726 -363.234735) (xy 258.444197 -363.256789) (xy 258.302646 -363.270857) (xy 258.160526 -363.276894)
			(xy 258.018291 -363.274881) (xy 257.876399 -363.264824) (xy 257.735303 -363.246756) (xy 257.595454 -363.220735)
			(xy 257.457302 -363.186843) (xy 257.321289 -363.145189) (xy 257.18785 -363.095907) (xy 257.057413 -363.039155)
			(xy 256.930396 -362.975114) (xy 256.807205 -362.90399) (xy 256.688236 -362.82601) (xy 256.573868 -362.741424)
			(xy 256.464469 -362.650504) (xy 256.36039 -362.55354) (xy 256.261962 -362.450843) (xy 256.169503 -362.342741)
			(xy 256.083307 -362.229582) (xy 256.003652 -362.111728) (xy 255.930791 -361.989556) (xy 255.86496 -361.863458)
			(xy 255.806367 -361.733837) (xy 255.755202 -361.601109) (xy 255.711628 -361.465699) (xy 255.675784 -361.32804)
			(xy 255.647786 -361.188574) (xy 255.627723 -361.047748) (xy 255.61566 -360.906012) (xy 255.611635 -360.76382)
			(xy 216.187782 -360.76382) (xy 216.187279 -360.834944) (xy 216.179231 -360.976965) (xy 216.163162 -361.118303)
			(xy 216.139121 -361.258505) (xy 216.107188 -361.397123) (xy 216.067463 -361.533712) (xy 216.020075 -361.667835)
			(xy 215.965174 -361.799062) (xy 215.902937 -361.926973) (xy 215.833563 -362.051158) (xy 215.757274 -362.171219)
			(xy 215.674316 -362.286772) (xy 215.584952 -362.397446) (xy 215.489471 -362.502888) (xy 215.388177 -362.602758)
			(xy 215.281395 -362.696738) (xy 215.169467 -362.784526) (xy 215.052751 -362.865842) (xy 214.931623 -362.940424)
			(xy 214.806469 -363.008033) (xy 214.67769 -363.068454) (xy 214.545699 -363.121492) (xy 214.410919 -363.166978)
			(xy 214.273781 -363.204766) (xy 214.134726 -363.234735) (xy 213.994197 -363.256789) (xy 213.852646 -363.270857)
			(xy 213.710526 -363.276894) (xy 213.568291 -363.274881) (xy 213.426399 -363.264824) (xy 213.285303 -363.246756)
			(xy 213.145454 -363.220735) (xy 213.007302 -363.186843) (xy 212.871289 -363.145189) (xy 212.73785 -363.095907)
			(xy 212.607413 -363.039155) (xy 212.480396 -362.975114) (xy 212.357205 -362.90399) (xy 212.238236 -362.82601)
			(xy 212.123868 -362.741424) (xy 212.014469 -362.650504) (xy 211.91039 -362.55354) (xy 211.811962 -362.450843)
			(xy 211.719503 -362.342741) (xy 211.633307 -362.229582) (xy 211.553652 -362.111728) (xy 211.480791 -361.989556)
			(xy 211.41496 -361.863458) (xy 211.356367 -361.733837) (xy 211.305202 -361.601109) (xy 211.261628 -361.465699)
			(xy 211.225784 -361.32804) (xy 211.197786 -361.188574) (xy 211.177723 -361.047748) (xy 211.16566 -360.906012)
			(xy 211.161635 -360.76382) (xy 121.930771 -360.76382) (xy 121.954005 -360.769894) (xy 122.005573 -360.791808)
			(xy 122.053401 -360.820997) (xy 122.096469 -360.856838) (xy 122.133859 -360.898568) (xy 122.164775 -360.945298)
			(xy 122.188558 -360.996031) (xy 122.2047 -361.049687) (xy 122.212859 -361.105121) (xy 122.21337 -361.133136)
			(xy 122.212859 -361.161151) (xy 122.2047 -361.216585) (xy 122.188558 -361.270241) (xy 122.164775 -361.320974)
			(xy 122.133859 -361.367704) (xy 122.096469 -361.409434) (xy 122.053401 -361.445275) (xy 122.005573 -361.474464)
			(xy 121.954005 -361.496378) (xy 121.899796 -361.51055) (xy 121.844101 -361.516678) (xy 121.788107 -361.514632)
			(xy 121.733009 -361.504455) (xy 121.679979 -361.486363) (xy 121.630148 -361.460744) (xy 121.584578 -361.428142)
			(xy 121.544242 -361.389252) (xy 121.509997 -361.344904) (xy 121.482574 -361.296042) (xy 121.462558 -361.243708)
			(xy 121.450375 -361.189018) (xy 121.446286 -361.133136) (xy 15.239789 -361.133136) (xy 15.227982 -361.28787)
			(xy 15.204052 -361.496426) (xy 15.1722 -361.703919) (xy 15.132472 -361.91005) (xy 15.084925 -362.114519)
			(xy 15.029628 -362.317029) (xy 14.966661 -362.517287) (xy 14.896116 -362.715003) (xy 14.818095 -362.90989)
			(xy 14.732711 -363.101665) (xy 14.640088 -363.290051) (xy 14.540361 -363.474774) (xy 14.433673 -363.655566)
			(xy 14.320179 -363.832166) (xy 14.200044 -364.004316) (xy 14.073443 -364.171769) (xy 13.940558 -364.33428)
			(xy 13.801583 -364.491614) (xy 13.656719 -364.643543) (xy 13.506176 -364.789847) (xy 13.350172 -364.930314)
			(xy 13.188933 -365.06474) (xy 13.022693 -365.192929) (xy 12.851694 -365.314697) (xy 12.676183 -365.429867)
			(xy 12.496415 -365.538271) (xy 12.31265 -365.639753) (xy 12.125154 -365.734165) (xy 11.934201 -365.821371)
			(xy 11.740065 -365.901244) (xy 11.54303 -365.973668) (xy 11.34338 -366.038538) (xy 11.141405 -366.09576)
			(xy 10.937399 -366.145252) (xy 10.731655 -366.186941) (xy 10.524474 -366.220766) (xy 10.316156 -366.24668)
			(xy 10.107002 -366.264645) (xy 9.897315 -366.274633) (xy 9.687401 -366.276632) (xy 9.477562 -366.270637)
			(xy 9.268104 -366.256658) (xy 9.059329 -366.234715) (xy 8.851542 -366.20484) (xy 8.645043 -366.167075)
			(xy 8.44013 -366.121477) (xy 8.237103 -366.06811) (xy 8.036254 -366.007053) (xy 7.837876 -365.938394)
			(xy 7.642255 -365.862231) (xy 7.449675 -365.778677) (xy 7.260417 -365.687852) (xy 7.074753 -365.589887)
			(xy 6.892953 -365.484925) (xy 6.715281 -365.373118) (xy 6.541995 -365.254627) (xy 6.373345 -365.129626)
			(xy 6.209576 -364.998294) (xy 6.050926 -364.860823) (xy 5.897624 -364.717412) (xy 5.749894 -364.568268)
			(xy 5.607948 -364.413608) (xy 5.471994 -364.253657) (xy 5.342227 -364.088645) (xy 5.218837 -363.918813)
			(xy 5.102002 -363.744406) (xy 4.991891 -363.565678) (xy 4.888664 -363.382887) (xy 4.792471 -363.196299)
			(xy 4.703452 -363.006184) (xy 4.621734 -362.812818) (xy 4.547438 -362.616481) (xy 4.48067 -362.417458)
			(xy 4.421528 -362.216037) (xy 4.370096 -362.012511) (xy 4.326451 -361.807174) (xy 4.290654 -361.600324)
			(xy 4.262758 -361.392262) (xy 4.242804 -361.183288) (xy 4.230819 -360.973706) (xy 4.226823 -360.76382)
			(xy 2.509012 -360.76382) (xy 2.509012 -383.932484) (xy 8.539215 -383.932484) (xy 8.539215 -383.803344)
			(xy 8.547165 -383.674449) (xy 8.563035 -383.546289) (xy 8.586764 -383.419348) (xy 8.618263 -383.294109)
			(xy 8.657412 -383.171046) (xy 8.704063 -383.050627) (xy 8.758038 -382.933308) (xy 8.819133 -382.819534)
			(xy 8.887116 -382.709737) (xy 8.96173 -382.604334) (xy 9.042691 -382.503724) (xy 9.129691 -382.408289)
			(xy 9.222402 -382.31839) (xy 9.320472 -382.234369) (xy 9.423527 -382.156545) (xy 9.531178 -382.085213)
			(xy 9.643017 -382.020643) (xy 9.758618 -381.963081) (xy 9.877543 -381.912744) (xy 9.999342 -381.869824)
			(xy 10.123552 -381.834483) (xy 10.249701 -381.806856) (xy 10.377313 -381.787047) (xy 10.505902 -381.775131)
			(xy 10.63498 -381.771155) (xy 10.764058 -381.775131) (xy 10.892647 -381.787047) (xy 11.020259 -381.806856)
			(xy 11.146408 -381.834483) (xy 11.270618 -381.869824) (xy 11.392417 -381.912744) (xy 11.511342 -381.963081)
			(xy 11.626943 -382.020643) (xy 11.738782 -382.085213) (xy 11.846433 -382.156545) (xy 11.949488 -382.234369)
			(xy 12.047558 -382.31839) (xy 12.140269 -382.408289) (xy 12.227269 -382.503724) (xy 12.30823 -382.604334)
			(xy 12.382844 -382.709737) (xy 12.450827 -382.819534) (xy 12.505341 -382.921052) (xy 19.016679 -382.921052)
			(xy 19.016679 -382.866548) (xy 19.024437 -382.812598) (xy 19.039793 -382.760301) (xy 19.062436 -382.710722)
			(xy 19.091904 -382.664871) (xy 19.127599 -382.62368) (xy 19.168792 -382.587989) (xy 19.214645 -382.558523)
			(xy 19.264226 -382.535884) (xy 19.316523 -382.520531) (xy 19.370474 -382.512778) (xy 19.397726 -382.512316)
			(xy 20.261326 -382.512316) (xy 20.288578 -382.512756) (xy 20.342526 -382.520516) (xy 20.394821 -382.535874)
			(xy 20.444398 -382.558518) (xy 20.490248 -382.587987) (xy 20.531438 -382.623681) (xy 20.567129 -382.664873)
			(xy 20.596594 -382.710725) (xy 20.619235 -382.760303) (xy 20.63459 -382.812599) (xy 20.642346 -382.866548)
			(xy 20.642346 -382.921052) (xy 20.636681 -382.960459) (xy 22.291788 -382.960459) (xy 22.291788 -382.905921)
			(xy 22.29955 -382.851938) (xy 22.314915 -382.79961) (xy 22.337571 -382.75) (xy 22.367056 -382.70412)
			(xy 22.40277 -382.662903) (xy 22.443987 -382.627188) (xy 22.489867 -382.597702) (xy 22.539476 -382.575046)
			(xy 22.591804 -382.559681) (xy 22.645787 -382.551919) (xy 22.673056 -382.551432) (xy 23.536656 -382.551432)
			(xy 23.563927 -382.551887) (xy 23.617915 -382.559649) (xy 23.670249 -382.575015) (xy 23.719863 -382.597673)
			(xy 23.765748 -382.62716) (xy 23.806969 -382.662878) (xy 23.842687 -382.704099) (xy 23.872175 -382.749983)
			(xy 23.894834 -382.799597) (xy 23.9102 -382.851931) (xy 23.917962 -382.905919) (xy 23.917962 -382.960461)
			(xy 23.9102 -383.014449) (xy 23.894834 -383.066783) (xy 23.872175 -383.116397) (xy 23.842687 -383.162281)
			(xy 23.806969 -383.203502) (xy 23.765748 -383.23922) (xy 23.719863 -383.268707) (xy 23.670249 -383.291365)
			(xy 23.617915 -383.306731) (xy 23.563927 -383.314493) (xy 23.536656 -383.314956) (xy 22.673056 -383.314956)
			(xy 22.645787 -383.314461) (xy 22.591804 -383.306699) (xy 22.539476 -383.291334) (xy 22.489867 -383.268678)
			(xy 22.443987 -383.239192) (xy 22.40277 -383.203477) (xy 22.367056 -383.16226) (xy 22.337571 -383.11638)
			(xy 22.314915 -383.06677) (xy 22.29955 -383.014442) (xy 22.291788 -382.960459) (xy 20.636681 -382.960459)
			(xy 20.63459 -382.975001) (xy 20.619235 -383.027297) (xy 20.596594 -383.076875) (xy 20.567129 -383.122727)
			(xy 20.531438 -383.163919) (xy 20.490248 -383.199613) (xy 20.444398 -383.229082) (xy 20.394821 -383.251726)
			(xy 20.342526 -383.267084) (xy 20.288578 -383.274844) (xy 20.261326 -383.275332) (xy 19.397726 -383.275332)
			(xy 19.370474 -383.274822) (xy 19.316523 -383.267069) (xy 19.264226 -383.251716) (xy 19.214645 -383.229077)
			(xy 19.168792 -383.199611) (xy 19.127599 -383.16392) (xy 19.091904 -383.122729) (xy 19.062436 -383.076878)
			(xy 19.039793 -383.027299) (xy 19.024437 -382.975002) (xy 19.016679 -382.921052) (xy 12.505341 -382.921052)
			(xy 12.511922 -382.933308) (xy 12.565897 -383.050627) (xy 12.612548 -383.171046) (xy 12.651697 -383.294109)
			(xy 12.683196 -383.419348) (xy 12.706925 -383.546289) (xy 12.722795 -383.674449) (xy 12.730745 -383.803344)
			(xy 12.731242 -383.867914) (xy 12.730745 -383.932484) (xy 12.722795 -384.061379) (xy 12.706925 -384.189539)
			(xy 12.683196 -384.31648) (xy 12.651697 -384.441719) (xy 12.612548 -384.564782) (xy 12.565897 -384.685201)
			(xy 12.511922 -384.80252) (xy 12.450827 -384.916294) (xy 12.382844 -385.026091) (xy 12.30823 -385.131494)
			(xy 12.227269 -385.232104) (xy 12.140269 -385.327539) (xy 12.047558 -385.417438) (xy 11.949488 -385.501459)
			(xy 11.846433 -385.579283) (xy 11.738782 -385.650615) (xy 11.626943 -385.715185) (xy 11.511342 -385.772747)
			(xy 11.483943 -385.784344) (xy 19.460972 -385.784344) (xy 19.460972 -384.920744) (xy 19.461458 -384.893493)
			(xy 19.469214 -384.839545) (xy 19.484569 -384.78725) (xy 19.507211 -384.737673) (xy 19.536677 -384.691823)
			(xy 19.572368 -384.650632) (xy 19.613559 -384.614941) (xy 19.659409 -384.585475) (xy 19.708986 -384.562833)
			(xy 19.761281 -384.547478) (xy 19.815229 -384.539722) (xy 19.869731 -384.539722) (xy 19.923679 -384.547478)
			(xy 19.975974 -384.562833) (xy 20.025551 -384.585475) (xy 20.071401 -384.614941) (xy 20.112592 -384.650632)
			(xy 20.148283 -384.691823) (xy 20.177749 -384.737673) (xy 20.200391 -384.78725) (xy 20.215746 -384.839545)
			(xy 20.223502 -384.893493) (xy 20.223988 -384.920744) (xy 20.223988 -385.784344) (xy 20.22353 -385.809998)
			(xy 22.731984 -385.809998) (xy 22.731984 -384.946398) (xy 22.73247 -384.919147) (xy 22.740226 -384.865199)
			(xy 22.755581 -384.812904) (xy 22.778223 -384.763327) (xy 22.807689 -384.717477) (xy 22.84338 -384.676286)
			(xy 22.884571 -384.640595) (xy 22.930421 -384.611129) (xy 22.979998 -384.588487) (xy 23.032293 -384.573132)
			(xy 23.086241 -384.565376) (xy 23.140743 -384.565376) (xy 23.194691 -384.573132) (xy 23.246986 -384.588487)
			(xy 23.296563 -384.611129) (xy 23.342413 -384.640595) (xy 23.383604 -384.676286) (xy 23.419295 -384.717477)
			(xy 23.448761 -384.763327) (xy 23.471403 -384.812904) (xy 23.486758 -384.865199) (xy 23.494514 -384.919147)
			(xy 23.495 -384.946398) (xy 23.495 -385.440249) (xy 36.585674 -385.440249) (xy 36.585674 -385.385751)
			(xy 36.593429 -385.331807) (xy 36.608782 -385.279515) (xy 36.63142 -385.229941) (xy 36.660882 -385.184092)
			(xy 36.696569 -385.142903) (xy 36.737753 -385.107211) (xy 36.783598 -385.077743) (xy 36.83317 -385.055099)
			(xy 36.88546 -385.039739) (xy 36.939403 -385.031977) (xy 36.966652 -385.031488) (xy 37.830252 -385.031488)
			(xy 37.857507 -385.031956) (xy 37.911462 -385.039707) (xy 37.963765 -385.055059) (xy 38.013351 -385.077699)
			(xy 38.05921 -385.107165) (xy 38.100408 -385.142858) (xy 38.136106 -385.184052) (xy 38.165578 -385.229907)
			(xy 38.188224 -385.27949) (xy 38.203582 -385.331791) (xy 38.211341 -385.385745) (xy 38.211341 -385.440255)
			(xy 38.203582 -385.494209) (xy 38.188224 -385.54651) (xy 38.165578 -385.596093) (xy 38.16123 -385.602858)
			(xy 41.455211 -385.602858) (xy 41.455211 -385.548342) (xy 41.46297 -385.494381) (xy 41.47833 -385.442074)
			(xy 41.500978 -385.392486) (xy 41.530453 -385.346625) (xy 41.566155 -385.305427) (xy 41.607357 -385.269729)
			(xy 41.653221 -385.240259) (xy 41.702812 -385.217616) (xy 41.755121 -385.202261) (xy 41.809082 -385.194508)
			(xy 41.83634 -385.194048) (xy 42.69994 -385.194048) (xy 42.727186 -385.194625) (xy 42.781123 -385.202385)
			(xy 42.833407 -385.217742) (xy 42.882974 -385.240383) (xy 42.928814 -385.269847) (xy 42.969994 -385.305534)
			(xy 43.005677 -385.346718) (xy 43.035136 -385.392562) (xy 43.057772 -385.44213) (xy 43.073123 -385.494416)
			(xy 43.080878 -385.548354) (xy 43.080878 -385.602846) (xy 43.073123 -385.656784) (xy 43.057772 -385.70907)
			(xy 43.035136 -385.758638) (xy 43.005677 -385.804482) (xy 42.969994 -385.845666) (xy 42.928814 -385.881353)
			(xy 42.882974 -385.910817) (xy 42.833407 -385.933458) (xy 42.781123 -385.948815) (xy 42.727186 -385.956575)
			(xy 42.69994 -385.957064) (xy 41.83634 -385.957064) (xy 41.809082 -385.956692) (xy 41.755121 -385.948939)
			(xy 41.702812 -385.933584) (xy 41.653221 -385.910941) (xy 41.607357 -385.881471) (xy 41.566155 -385.845773)
			(xy 41.530453 -385.804575) (xy 41.500978 -385.758714) (xy 41.47833 -385.709126) (xy 41.46297 -385.656819)
			(xy 41.455211 -385.602858) (xy 38.16123 -385.602858) (xy 38.136106 -385.641948) (xy 38.100408 -385.683142)
			(xy 38.05921 -385.718835) (xy 38.013351 -385.748301) (xy 37.963765 -385.770941) (xy 37.911462 -385.786293)
			(xy 37.857507 -385.794044) (xy 37.830252 -385.794504) (xy 36.966652 -385.794504) (xy 36.939403 -385.794023)
			(xy 36.88546 -385.786261) (xy 36.83317 -385.770901) (xy 36.783598 -385.748257) (xy 36.737753 -385.718789)
			(xy 36.696569 -385.683097) (xy 36.660882 -385.641908) (xy 36.63142 -385.596059) (xy 36.608782 -385.546485)
			(xy 36.593429 -385.494193) (xy 36.585674 -385.440249) (xy 23.495 -385.440249) (xy 23.495 -385.809998)
			(xy 23.494514 -385.837249) (xy 23.486758 -385.891197) (xy 23.471403 -385.943492) (xy 23.448761 -385.993069)
			(xy 23.419295 -386.038919) (xy 23.383604 -386.08011) (xy 23.342413 -386.115801) (xy 23.296563 -386.145267)
			(xy 23.246986 -386.167909) (xy 23.194691 -386.183264) (xy 23.140743 -386.19102) (xy 23.086241 -386.19102)
			(xy 23.032293 -386.183264) (xy 22.979998 -386.167909) (xy 22.930421 -386.145267) (xy 22.884571 -386.115801)
			(xy 22.84338 -386.08011) (xy 22.807689 -386.038919) (xy 22.778223 -385.993069) (xy 22.755581 -385.943492)
			(xy 22.740226 -385.891197) (xy 22.73247 -385.837249) (xy 22.731984 -385.809998) (xy 20.22353 -385.809998)
			(xy 20.223502 -385.811595) (xy 20.215746 -385.865543) (xy 20.200391 -385.917838) (xy 20.177749 -385.967415)
			(xy 20.148283 -386.013265) (xy 20.112592 -386.054456) (xy 20.071401 -386.090147) (xy 20.025551 -386.119613)
			(xy 19.975974 -386.142255) (xy 19.923679 -386.15761) (xy 19.869731 -386.165366) (xy 19.815229 -386.165366)
			(xy 19.761281 -386.15761) (xy 19.708986 -386.142255) (xy 19.659409 -386.119613) (xy 19.613559 -386.090147)
			(xy 19.572368 -386.054456) (xy 19.536677 -386.013265) (xy 19.507211 -385.967415) (xy 19.484569 -385.917838)
			(xy 19.469214 -385.865543) (xy 19.461458 -385.811595) (xy 19.460972 -385.784344) (xy 11.483943 -385.784344)
			(xy 11.392417 -385.823084) (xy 11.270618 -385.866004) (xy 11.146408 -385.901345) (xy 11.020259 -385.928972)
			(xy 10.892647 -385.948781) (xy 10.764058 -385.960697) (xy 10.63498 -385.964674) (xy 10.505902 -385.960697)
			(xy 10.377313 -385.948781) (xy 10.249701 -385.928972) (xy 10.123552 -385.901345) (xy 9.999342 -385.866004)
			(xy 9.877543 -385.823084) (xy 9.758618 -385.772747) (xy 9.643017 -385.715185) (xy 9.531178 -385.650615)
			(xy 9.423527 -385.579283) (xy 9.320472 -385.501459) (xy 9.222402 -385.417438) (xy 9.129691 -385.327539)
			(xy 9.042691 -385.232104) (xy 8.96173 -385.131494) (xy 8.887116 -385.026091) (xy 8.819133 -384.916294)
			(xy 8.758038 -384.80252) (xy 8.704063 -384.685201) (xy 8.657412 -384.564782) (xy 8.618263 -384.441719)
			(xy 8.586764 -384.31648) (xy 8.563035 -384.189539) (xy 8.547165 -384.061379) (xy 8.539215 -383.932484)
			(xy 2.509012 -383.932484) (xy 2.509012 -389.402275) (xy 286.566098 -389.402275) (xy 286.566098 -389.317529)
			(xy 286.574154 -389.233168) (xy 286.590192 -389.149954) (xy 286.614067 -389.068641) (xy 286.645564 -388.989966)
			(xy 286.684397 -388.914642) (xy 286.730213 -388.843349) (xy 286.7826 -388.776735) (xy 286.84108 -388.715402)
			(xy 286.905127 -388.659906) (xy 286.974158 -388.610748) (xy 287.04755 -388.568376) (xy 287.124637 -388.533171)
			(xy 287.204721 -388.505454) (xy 287.287078 -388.485474) (xy 287.370961 -388.473414) (xy 287.45561 -388.469382)
			(xy 287.540259 -388.473414) (xy 287.624142 -388.485474) (xy 287.706499 -388.505454) (xy 287.786583 -388.533171)
			(xy 287.86367 -388.568376) (xy 287.937062 -388.610748) (xy 288.006093 -388.659906) (xy 288.07014 -388.715402)
			(xy 288.12862 -388.776735) (xy 288.181007 -388.843349) (xy 288.226823 -388.914642) (xy 288.265656 -388.989966)
			(xy 288.297153 -389.068641) (xy 288.321028 -389.149954) (xy 288.337066 -389.233168) (xy 288.345122 -389.317529)
			(xy 288.345626 -389.359902) (xy 288.345122 -389.402275) (xy 297.615098 -389.402275) (xy 297.615098 -389.317529)
			(xy 297.623154 -389.233168) (xy 297.639192 -389.149954) (xy 297.663067 -389.068641) (xy 297.694564 -388.989966)
			(xy 297.733397 -388.914642) (xy 297.779213 -388.843349) (xy 297.8316 -388.776735) (xy 297.89008 -388.715402)
			(xy 297.954127 -388.659906) (xy 298.023158 -388.610748) (xy 298.09655 -388.568376) (xy 298.173637 -388.533171)
			(xy 298.253721 -388.505454) (xy 298.336078 -388.485474) (xy 298.419961 -388.473414) (xy 298.50461 -388.469382)
			(xy 298.589259 -388.473414) (xy 298.673142 -388.485474) (xy 298.755499 -388.505454) (xy 298.835583 -388.533171)
			(xy 298.91267 -388.568376) (xy 298.986062 -388.610748) (xy 299.055093 -388.659906) (xy 299.11914 -388.715402)
			(xy 299.17762 -388.776735) (xy 299.230007 -388.843349) (xy 299.275823 -388.914642) (xy 299.314656 -388.989966)
			(xy 299.346153 -389.068641) (xy 299.370028 -389.149954) (xy 299.386066 -389.233168) (xy 299.394122 -389.317529)
			(xy 299.394626 -389.359902) (xy 299.394122 -389.402275) (xy 299.386066 -389.486636) (xy 299.370028 -389.56985)
			(xy 299.346153 -389.651163) (xy 299.314656 -389.729838) (xy 299.275823 -389.805162) (xy 299.230007 -389.876455)
			(xy 299.17762 -389.943069) (xy 299.11914 -390.004402) (xy 299.055093 -390.059898) (xy 298.986062 -390.109056)
			(xy 298.91267 -390.151428) (xy 298.835583 -390.186633) (xy 298.755499 -390.21435) (xy 298.673142 -390.23433)
			(xy 298.589259 -390.24639) (xy 298.50461 -390.250423) (xy 298.419961 -390.24639) (xy 298.336078 -390.23433)
			(xy 298.253721 -390.21435) (xy 298.173637 -390.186633) (xy 298.09655 -390.151428) (xy 298.023158 -390.109056)
			(xy 297.954127 -390.059898) (xy 297.89008 -390.004402) (xy 297.8316 -389.943069) (xy 297.779213 -389.876455)
			(xy 297.733397 -389.805162) (xy 297.694564 -389.729838) (xy 297.663067 -389.651163) (xy 297.639192 -389.56985)
			(xy 297.623154 -389.486636) (xy 297.615098 -389.402275) (xy 288.345122 -389.402275) (xy 288.337066 -389.486636)
			(xy 288.321028 -389.56985) (xy 288.297153 -389.651163) (xy 288.265656 -389.729838) (xy 288.226823 -389.805162)
			(xy 288.181007 -389.876455) (xy 288.12862 -389.943069) (xy 288.07014 -390.004402) (xy 288.006093 -390.059898)
			(xy 287.937062 -390.109056) (xy 287.86367 -390.151428) (xy 287.786583 -390.186633) (xy 287.706499 -390.21435)
			(xy 287.624142 -390.23433) (xy 287.540259 -390.24639) (xy 287.45561 -390.250423) (xy 287.370961 -390.24639)
			(xy 287.287078 -390.23433) (xy 287.204721 -390.21435) (xy 287.124637 -390.186633) (xy 287.04755 -390.151428)
			(xy 286.974158 -390.109056) (xy 286.905127 -390.059898) (xy 286.84108 -390.004402) (xy 286.7826 -389.943069)
			(xy 286.730213 -389.876455) (xy 286.684397 -389.805162) (xy 286.645564 -389.729838) (xy 286.614067 -389.651163)
			(xy 286.590192 -389.56985) (xy 286.574154 -389.486636) (xy 286.566098 -389.402275) (xy 2.509012 -389.402275)
			(xy 2.509012 -390.74852) (xy 289.828732 -390.74852) (xy 289.829157 -390.717787) (xy 289.836564 -390.656768)
			(xy 289.851272 -390.597088) (xy 289.873068 -390.539615) (xy 289.901633 -390.485189) (xy 289.93655 -390.434604)
			(xy 289.97731 -390.388596) (xy 290.023319 -390.347837) (xy 290.073907 -390.312922) (xy 290.128334 -390.28436)
			(xy 290.185807 -390.262566) (xy 290.245488 -390.24786) (xy 290.306507 -390.240455) (xy 290.33724 -390.240012)
			(xy 290.369283 -390.240508) (xy 290.432859 -390.248584) (xy 290.494917 -390.264579) (xy 290.554476 -390.288239)
			(xy 290.610594 -390.31919) (xy 290.662381 -390.356941) (xy 290.709019 -390.400896) (xy 290.749768 -390.450359)
			(xy 290.783985 -390.504546) (xy 290.811128 -390.562601) (xy 290.830767 -390.623604) (xy 290.842591 -390.686591)
			(xy 290.844986 -390.718548) (xy 290.846452 -390.733661) (xy 290.857061 -390.762093) (xy 290.875562 -390.786147)
			(xy 290.900318 -390.803698) (xy 290.929141 -390.813192) (xy 290.9443 -390.814052) (xy 290.977155 -390.815239)
			(xy 291.042167 -390.825028) (xy 291.105376 -390.843112) (xy 291.165728 -390.86919) (xy 291.222216 -390.902827)
			(xy 291.2739 -390.943462) (xy 291.319917 -390.990417) (xy 291.359501 -391.04291) (xy 291.391992 -391.100065)
			(xy 291.416847 -391.160931) (xy 291.433653 -391.224491) (xy 291.442129 -391.289688) (xy 291.442648 -391.32256)
			(xy 291.442106 -391.353289) (xy 291.434703 -391.414298) (xy 291.42 -391.473971) (xy 291.398212 -391.531436)
			(xy 291.369656 -391.585856) (xy 291.334748 -391.636437) (xy 291.293998 -391.682441) (xy 291.248 -391.723199)
			(xy 291.197424 -391.758114) (xy 291.143009 -391.786679) (xy 291.085547 -391.808477) (xy 291.025877 -391.823189)
			(xy 290.964869 -391.830602) (xy 290.93414 -391.831068) (xy 290.902098 -391.830516) (xy 290.838523 -391.822449)
			(xy 290.776465 -391.806463) (xy 290.716905 -391.78281) (xy 290.660787 -391.751866) (xy 290.608999 -391.71412)
			(xy 290.56236 -391.670169) (xy 290.521609 -391.620711) (xy 290.487392 -391.566526) (xy 290.460249 -391.508474)
			(xy 290.440611 -391.447473) (xy 290.428788 -391.384488) (xy 290.426394 -391.352532) (xy 290.424962 -391.337414)
			(xy 290.414346 -391.308979) (xy 290.395837 -391.284924) (xy 290.371072 -391.267376) (xy 290.342242 -391.257886)
			(xy 290.32708 -391.257028) (xy 290.294229 -391.25578) (xy 290.229223 -391.24599) (xy 290.166019 -391.227907)
			(xy 290.105673 -391.201832) (xy 290.049188 -391.1682) (xy 289.997507 -391.127571) (xy 289.95149 -391.080623)
			(xy 289.911906 -391.028137) (xy 289.879413 -390.97099) (xy 289.854553 -390.910132) (xy 289.837741 -390.846579)
			(xy 289.829256 -390.78139) (xy 289.828732 -390.74852) (xy 2.509012 -390.74852) (xy 2.509012 -394.8085)
			(xy 243.179528 -394.8085) (xy 243.183558 -394.723892) (xy 243.195613 -394.640051) (xy 243.215583 -394.557735)
			(xy 243.243287 -394.47769) (xy 243.278475 -394.400641) (xy 243.320827 -394.327286) (xy 243.36996 -394.258289)
			(xy 243.42543 -394.194274) (xy 243.486733 -394.135823) (xy 243.553315 -394.083463) (xy 243.624573 -394.03767)
			(xy 243.699861 -393.998857) (xy 243.778498 -393.967377) (xy 243.859771 -393.943515) (xy 243.942944 -393.927486)
			(xy 244.027264 -393.919435) (xy 244.069616 -393.918948) (xy 244.11084 -393.919417) (xy 244.192933 -393.927053)
			(xy 244.273968 -393.94225) (xy 244.35325 -393.964876) (xy 244.430099 -393.994739) (xy 244.503857 -394.031582)
			(xy 244.573891 -394.075088) (xy 244.639601 -394.124886) (xy 244.670326 -394.152374) (xy 244.677558 -394.158461)
			(xy 244.695171 -394.165287) (xy 244.714061 -394.165287) (xy 244.731674 -394.158461) (xy 244.738906 -394.152374)
			(xy 244.769639 -394.124894) (xy 244.835341 -394.075085) (xy 244.905371 -394.03157) (xy 244.979128 -393.994723)
			(xy 245.055977 -393.964858) (xy 245.13526 -393.942233) (xy 245.216297 -393.927041) (xy 245.298392 -393.919413)
			(xy 245.339616 -393.918948) (xy 245.380184 -393.919416) (xy 245.460981 -393.926807) (xy 245.54077 -393.941524)
			(xy 245.618888 -393.963447) (xy 245.694684 -393.992392) (xy 245.767529 -394.02812) (xy 245.836818 -394.070333)
			(xy 245.901975 -394.118681) (xy 245.962458 -394.172761) (xy 246.017765 -394.232125) (xy 246.067436 -394.296278)
			(xy 246.111059 -394.364689) (xy 246.130064 -394.400532) (xy 246.157157 -394.401367) (xy 246.21073 -394.409598)
			(xy 246.262601 -394.42532) (xy 246.31173 -394.448214) (xy 246.357129 -394.477824) (xy 246.397887 -394.513553)
			(xy 246.433186 -394.554684) (xy 246.462317 -394.600391) (xy 246.484695 -394.649758) (xy 246.499871 -394.701791)
			(xy 246.507539 -394.755447) (xy 246.508016 -394.782548) (xy 246.507582 -394.8085) (xy 249.114543 -394.8085)
			(xy 249.118574 -394.723896) (xy 249.130628 -394.640058) (xy 249.150596 -394.557746) (xy 249.178298 -394.477704)
			(xy 249.213483 -394.400658) (xy 249.255833 -394.327305) (xy 249.304963 -394.25831) (xy 249.360429 -394.194298)
			(xy 249.421729 -394.135847) (xy 249.488307 -394.083488) (xy 249.55956 -394.037695) (xy 249.634844 -393.998882)
			(xy 249.713476 -393.967401) (xy 249.794745 -393.943537) (xy 249.877914 -393.927506) (xy 249.96223 -393.919453)
			(xy 250.00458 -393.918948) (xy 250.045803 -393.919439) (xy 250.127896 -393.927072) (xy 250.20893 -393.942266)
			(xy 250.288212 -393.964889) (xy 250.365061 -393.994749) (xy 250.438819 -394.031588) (xy 250.508854 -394.075092)
			(xy 250.574564 -394.124887) (xy 250.60529 -394.152374) (xy 250.612522 -394.158461) (xy 250.630135 -394.165287)
			(xy 250.649025 -394.165287) (xy 250.666638 -394.158461) (xy 250.67387 -394.152374) (xy 250.704576 -394.124863)
			(xy 250.770283 -394.075057) (xy 250.840317 -394.031545) (xy 250.914078 -393.994701) (xy 250.990931 -393.96484)
			(xy 251.070218 -393.942219) (xy 251.151257 -393.927032) (xy 251.233355 -393.91941) (xy 251.27458 -393.918948)
			(xy 251.315219 -393.919386) (xy 251.396157 -393.926808) (xy 251.47608 -393.941582) (xy 251.554323 -393.963585)
			(xy 251.630232 -393.992634) (xy 251.703174 -394.028487) (xy 251.772542 -394.070844) (xy 251.837756 -394.119353)
			(xy 251.898274 -394.173608) (xy 251.95359 -394.233158) (xy 252.003243 -394.297505) (xy 252.046819 -394.366114)
			(xy 252.06579 -394.402056) (xy 252.086364 -394.401548) (xy 252.113582 -394.401996) (xy 252.167464 -394.409739)
			(xy 252.219695 -394.425073) (xy 252.269213 -394.447684) (xy 252.315007 -394.477114) (xy 252.356147 -394.512762)
			(xy 252.391793 -394.553902) (xy 252.421221 -394.599698) (xy 252.443832 -394.649216) (xy 252.459163 -394.701448)
			(xy 252.466905 -394.75533) (xy 252.467364 -394.782548) (xy 252.466916 -394.8085) (xy 255.049428 -394.8085)
			(xy 255.053459 -394.723891) (xy 255.065514 -394.640048) (xy 255.085484 -394.55773) (xy 255.11319 -394.477684)
			(xy 255.148379 -394.400634) (xy 255.190732 -394.327277) (xy 255.239868 -394.258279) (xy 255.295339 -394.194265)
			(xy 255.356645 -394.135813) (xy 255.423229 -394.083453) (xy 255.494489 -394.03766) (xy 255.56978 -393.998849)
			(xy 255.648419 -393.96737) (xy 255.729694 -393.943509) (xy 255.812869 -393.927482) (xy 255.897191 -393.919434)
			(xy 255.939544 -393.918948) (xy 255.980768 -393.919399) (xy 256.062862 -393.927038) (xy 256.143897 -393.942237)
			(xy 256.223179 -393.964866) (xy 256.300029 -393.994731) (xy 256.373786 -394.031576) (xy 256.44382 -394.075085)
			(xy 256.509529 -394.124885) (xy 256.540254 -394.152374) (xy 256.547486 -394.158461) (xy 256.565099 -394.165287)
			(xy 256.583989 -394.165287) (xy 256.601602 -394.158461) (xy 256.608834 -394.152374) (xy 256.639555 -394.12488)
			(xy 256.70526 -394.075073) (xy 256.775292 -394.031559) (xy 256.849049 -393.994713) (xy 256.925901 -393.96485)
			(xy 257.005185 -393.942227) (xy 257.086223 -393.927037) (xy 257.168319 -393.919412) (xy 257.209544 -393.918948)
			(xy 257.250365 -393.919407) (xy 257.331665 -393.926876) (xy 257.411938 -393.941765) (xy 257.490509 -393.963948)
			(xy 257.566715 -393.993239) (xy 257.639917 -394.029392) (xy 257.709496 -394.072102) (xy 257.774868 -394.121009)
			(xy 257.835483 -394.175702) (xy 257.890829 -394.235721) (xy 257.940442 -394.300559) (xy 257.983902 -394.369672)
			(xy 258.002786 -394.405866) (xy 258.01873 -394.403337) (xy 258.050905 -394.400664) (xy 258.067048 -394.400532)
			(xy 258.094337 -394.400926) (xy 258.148358 -394.408699) (xy 258.200723 -394.424081) (xy 258.250366 -394.446758)
			(xy 258.296278 -394.476268) (xy 258.337522 -394.512012) (xy 258.37326 -394.553261) (xy 258.402765 -394.599176)
			(xy 258.425436 -394.648822) (xy 258.440811 -394.701189) (xy 258.448577 -394.755211) (xy 258.448577 -394.8085)
			(xy 260.984428 -394.8085) (xy 260.988458 -394.723893) (xy 261.000513 -394.640052) (xy 261.020483 -394.557736)
			(xy 261.048186 -394.477692) (xy 261.083374 -394.400643) (xy 261.125725 -394.327288) (xy 261.174858 -394.258291)
			(xy 261.230327 -394.194277) (xy 261.29163 -394.135826) (xy 261.358212 -394.083466) (xy 261.429469 -394.037672)
			(xy 261.504756 -393.99886) (xy 261.583392 -393.967379) (xy 261.664664 -393.943516) (xy 261.747837 -393.927487)
			(xy 261.832156 -393.919436) (xy 261.874508 -393.918948) (xy 261.915732 -393.919422) (xy 261.997825 -393.927057)
			(xy 262.078859 -393.942253) (xy 262.158141 -393.964879) (xy 262.234991 -393.994741) (xy 262.308749 -394.031583)
			(xy 262.378783 -394.075089) (xy 262.444493 -394.124886) (xy 262.475218 -394.152374) (xy 262.48245 -394.158461)
			(xy 262.500063 -394.165287) (xy 262.518953 -394.165287) (xy 262.536566 -394.158461) (xy 262.543798 -394.152374)
			(xy 262.574534 -394.124897) (xy 262.640236 -394.075089) (xy 262.710266 -394.031574) (xy 262.784021 -393.994725)
			(xy 262.86087 -393.96486) (xy 262.940153 -393.942234) (xy 263.021189 -393.927042) (xy 263.103284 -393.919413)
			(xy 263.144508 -393.918948) (xy 263.185239 -393.919443) (xy 263.26636 -393.9269) (xy 263.346458 -393.941743)
			(xy 263.424865 -393.963847) (xy 263.500922 -393.993026) (xy 263.573993 -394.029037) (xy 263.643465 -394.071577)
			(xy 263.708758 -394.120291) (xy 263.769323 -394.174771) (xy 263.824654 -394.234559) (xy 263.874287 -394.299155)
			(xy 263.917806 -394.368019) (xy 263.936734 -394.404088) (xy 263.947933 -394.402872) (xy 263.970427 -394.401601)
			(xy 263.981692 -394.401548) (xy 264.008912 -394.401914) (xy 264.062799 -394.409661) (xy 264.115035 -394.424998)
			(xy 264.164556 -394.447612) (xy 264.210355 -394.477045) (xy 264.251499 -394.512695) (xy 264.287151 -394.553838)
			(xy 264.316584 -394.599637) (xy 264.3392 -394.649158) (xy 264.354537 -394.701393) (xy 264.362285 -394.75528)
			(xy 264.362285 -394.8085) (xy 266.919443 -394.8085) (xy 266.923474 -394.723896) (xy 266.935527 -394.640059)
			(xy 266.955496 -394.557747) (xy 266.983198 -394.477706) (xy 267.018382 -394.40066) (xy 267.060731 -394.327308)
			(xy 267.109861 -394.258313) (xy 267.165326 -394.194301) (xy 267.226625 -394.13585) (xy 267.293203 -394.083491)
			(xy 267.364456 -394.037698) (xy 267.439739 -393.998885) (xy 267.51837 -393.967403) (xy 267.599638 -393.943538)
			(xy 267.682807 -393.927507) (xy 267.767122 -393.919453) (xy 267.809472 -393.918948) (xy 267.850695 -393.919444)
			(xy 267.932787 -393.927077) (xy 268.013822 -393.942269) (xy 268.093103 -393.964892) (xy 268.169953 -393.994751)
			(xy 268.243711 -394.03159) (xy 268.313746 -394.075093) (xy 268.379456 -394.124888) (xy 268.410182 -394.152374)
			(xy 268.417414 -394.158461) (xy 268.435027 -394.165287) (xy 268.453917 -394.165287) (xy 268.47153 -394.158461)
			(xy 268.478762 -394.152374) (xy 268.509471 -394.124866) (xy 268.575178 -394.07506) (xy 268.645212 -394.031548)
			(xy 268.718971 -393.994703) (xy 268.795824 -393.964842) (xy 268.87511 -393.942221) (xy 268.95615 -393.927033)
			(xy 269.038247 -393.91941) (xy 269.079472 -393.918948) (xy 269.120039 -393.919454) (xy 269.200835 -393.92684)
			(xy 269.280624 -393.941554) (xy 269.35874 -393.963472) (xy 269.434536 -393.992414) (xy 269.507381 -394.028138)
			(xy 269.576671 -394.070348) (xy 269.641828 -394.118693) (xy 269.702312 -394.17277) (xy 269.757619 -394.232131)
			(xy 269.807291 -394.296282) (xy 269.850914 -394.36469) (xy 269.86992 -394.400532) (xy 269.897015 -394.401316)
			(xy 269.95059 -394.409555) (xy 270.002462 -394.425283) (xy 270.051591 -394.448184) (xy 270.096989 -394.477799)
			(xy 270.137747 -394.513533) (xy 270.173045 -394.554669) (xy 270.202175 -394.60038) (xy 270.224552 -394.64975)
			(xy 270.239727 -394.701787) (xy 270.247395 -394.755446) (xy 270.247872 -394.782548) (xy 270.24739 -394.8085)
			(xy 272.854328 -394.8085) (xy 272.858359 -394.723891) (xy 272.870414 -394.640048) (xy 272.890384 -394.557731)
			(xy 272.918089 -394.477686) (xy 272.953277 -394.400636) (xy 272.995631 -394.32728) (xy 273.044766 -394.258282)
			(xy 273.100237 -394.194267) (xy 273.161542 -394.135816) (xy 273.228125 -394.083456) (xy 273.299385 -394.037663)
			(xy 273.374675 -393.998851) (xy 273.453313 -393.967372) (xy 273.534587 -393.943511) (xy 273.617762 -393.927483)
			(xy 273.702084 -393.919434) (xy 273.744436 -393.918948) (xy 273.78566 -393.919404) (xy 273.867754 -393.927042)
			(xy 273.948789 -393.942241) (xy 274.028071 -393.964869) (xy 274.10492 -393.994734) (xy 274.178678 -394.031578)
			(xy 274.248712 -394.075086) (xy 274.314421 -394.124886) (xy 274.345146 -394.152374) (xy 274.352378 -394.158461)
			(xy 274.369991 -394.165287) (xy 274.388881 -394.165287) (xy 274.406494 -394.158461) (xy 274.413726 -394.152374)
			(xy 274.44445 -394.124884) (xy 274.510154 -394.075076) (xy 274.580186 -394.031562) (xy 274.653943 -393.994716)
			(xy 274.730794 -393.964852) (xy 274.810078 -393.942228) (xy 274.891116 -393.927038) (xy 274.973211 -393.919412)
			(xy 275.014436 -393.918948) (xy 275.055004 -393.9194) (xy 275.135802 -393.926792) (xy 275.215592 -393.941511)
			(xy 275.293709 -393.963435) (xy 275.369506 -393.992382) (xy 275.442351 -394.028112) (xy 275.51164 -394.070326)
			(xy 275.576797 -394.118675) (xy 275.63728 -394.172757) (xy 275.692586 -394.232122) (xy 275.742257 -394.296277)
			(xy 275.785879 -394.364688) (xy 275.804884 -394.400532) (xy 275.831978 -394.401349) (xy 275.885551 -394.409583)
			(xy 275.937423 -394.425306) (xy 275.986552 -394.448204) (xy 276.031951 -394.477815) (xy 276.072709 -394.513546)
			(xy 276.108007 -394.554678) (xy 276.137138 -394.600387) (xy 276.159515 -394.649755) (xy 276.174691 -394.70179)
			(xy 276.182359 -394.755447) (xy 276.182836 -394.782548) (xy 276.182385 -394.808456) (xy 278.916892 -394.808456)
			(xy 278.917356 -394.766262) (xy 278.925335 -394.682252) (xy 278.941234 -394.599376) (xy 278.964912 -394.518378)
			(xy 278.996156 -394.439987) (xy 279.034684 -394.364908) (xy 279.08015 -394.293815) (xy 279.132146 -394.227349)
			(xy 279.190203 -394.166106) (xy 279.2538 -394.110638) (xy 279.322365 -394.061443) (xy 279.395282 -394.018964)
			(xy 279.471894 -393.983582) (xy 279.551513 -393.955615) (xy 279.633423 -393.935316) (xy 279.675082 -393.9286)
			(xy 279.689459 -393.925944) (xy 279.715949 -393.913606) (xy 279.737852 -393.894262) (xy 279.753368 -393.869499)
			(xy 279.761223 -393.841352) (xy 279.760772 -393.812133) (xy 279.75687 -393.798044) (xy 279.744165 -393.755179)
			(xy 279.726399 -393.667554) (xy 279.717507 -393.578589) (xy 279.716992 -393.533884) (xy 279.717496 -393.491536)
			(xy 279.725547 -393.407222) (xy 279.741576 -393.324056) (xy 279.765437 -393.242789) (xy 279.796916 -393.164159)
			(xy 279.835727 -393.088878) (xy 279.881517 -393.017626) (xy 279.933873 -392.95105) (xy 279.992321 -392.889752)
			(xy 280.056331 -392.834287) (xy 280.125323 -392.785158) (xy 280.198673 -392.742809) (xy 280.275716 -392.707625)
			(xy 280.355755 -392.679923) (xy 280.438064 -392.659955) (xy 280.521899 -392.647902) (xy 280.6065 -392.643872)
			(xy 280.691101 -392.647902) (xy 280.774936 -392.659955) (xy 280.857245 -392.679923) (xy 280.937284 -392.707625)
			(xy 281.014327 -392.742809) (xy 281.087677 -392.785158) (xy 281.156669 -392.834287) (xy 281.220679 -392.889752)
			(xy 281.279127 -392.95105) (xy 281.331483 -393.017626) (xy 281.377273 -393.088878) (xy 281.416084 -393.164159)
			(xy 281.447563 -393.242789) (xy 281.471424 -393.324056) (xy 281.487453 -393.407222) (xy 281.495504 -393.491536)
			(xy 281.496008 -393.533884) (xy 281.495487 -393.576077) (xy 281.487514 -393.660085) (xy 281.47162 -393.74296)
			(xy 281.461756 -393.776708) (xy 289.471608 -393.776708) (xy 289.471608 -393.776454) (xy 289.47211 -393.744493)
			(xy 289.480121 -393.681075) (xy 289.496018 -393.619161) (xy 289.51955 -393.559728) (xy 289.550344 -393.503713)
			(xy 289.587917 -393.451998) (xy 289.631674 -393.405401) (xy 289.680927 -393.364656) (xy 289.734898 -393.330405)
			(xy 289.792737 -393.303188) (xy 289.85353 -393.283435) (xy 289.91632 -393.271457) (xy 289.980116 -393.267444)
			(xy 290.043912 -393.271457) (xy 290.106702 -393.283435) (xy 290.167495 -393.303188) (xy 290.225334 -393.330405)
			(xy 290.279305 -393.364656) (xy 290.328558 -393.405401) (xy 290.372315 -393.451998) (xy 290.409888 -393.503713)
			(xy 290.440682 -393.559728) (xy 290.464214 -393.619161) (xy 290.480111 -393.681075) (xy 290.488122 -393.744493)
			(xy 290.488624 -393.776454) (xy 290.488624 -393.7765) (xy 291.470768 -393.7765) (xy 291.474784 -393.712663)
			(xy 291.48677 -393.649832) (xy 291.506536 -393.589) (xy 291.533771 -393.531124) (xy 291.568045 -393.477118)
			(xy 291.608817 -393.427834) (xy 291.655445 -393.384049) (xy 291.707193 -393.346453) (xy 291.763245 -393.315639)
			(xy 291.822717 -393.292094) (xy 291.884671 -393.276188) (xy 291.94813 -393.268172) (xy 291.980112 -393.267692)
			(xy 292.010658 -393.268138) (xy 292.071311 -393.275449) (xy 292.13065 -393.289975) (xy 292.187822 -393.311508)
			(xy 292.242001 -393.339737) (xy 292.292406 -393.374254) (xy 292.338312 -393.414564) (xy 292.379057 -393.460084)
			(xy 292.396926 -393.484862) (xy 292.405296 -393.496027) (xy 292.426903 -393.51367) (xy 292.452477 -393.52481)
			(xy 292.480111 -393.528618) (xy 292.507745 -393.52481) (xy 292.533319 -393.51367) (xy 292.554926 -393.496027)
			(xy 292.563296 -393.484862) (xy 292.582389 -393.458454) (xy 292.626241 -393.410247) (xy 292.675892 -393.368039)
			(xy 292.730528 -393.332518) (xy 292.789254 -393.304269) (xy 292.851108 -393.283754) (xy 292.915076 -393.271309)
			(xy 292.98011 -393.267138) (xy 293.045144 -393.271309) (xy 293.109112 -393.283754) (xy 293.170966 -393.304269)
			(xy 293.229692 -393.332518) (xy 293.284328 -393.368039) (xy 293.333979 -393.410247) (xy 293.377831 -393.458454)
			(xy 293.396924 -393.484862) (xy 293.405294 -393.496027) (xy 293.426901 -393.51367) (xy 293.452475 -393.52481)
			(xy 293.480109 -393.528618) (xy 293.507743 -393.52481) (xy 293.533317 -393.51367) (xy 293.554924 -393.496027)
			(xy 293.563294 -393.484862) (xy 293.582387 -393.458454) (xy 293.626239 -393.410247) (xy 293.67589 -393.368039)
			(xy 293.730526 -393.332518) (xy 293.789252 -393.304269) (xy 293.851106 -393.283754) (xy 293.915074 -393.271309)
			(xy 293.980108 -393.267138) (xy 294.045142 -393.271309) (xy 294.10911 -393.283754) (xy 294.170964 -393.304269)
			(xy 294.22969 -393.332518) (xy 294.284326 -393.368039) (xy 294.333977 -393.410247) (xy 294.377829 -393.458454)
			(xy 294.396922 -393.484862) (xy 294.405292 -393.496027) (xy 294.426899 -393.51367) (xy 294.452473 -393.52481)
			(xy 294.480107 -393.528618) (xy 294.507741 -393.52481) (xy 294.533315 -393.51367) (xy 294.554922 -393.496027)
			(xy 294.563292 -393.484862) (xy 294.582385 -393.458454) (xy 294.626237 -393.410247) (xy 294.675888 -393.368039)
			(xy 294.730524 -393.332518) (xy 294.78925 -393.304269) (xy 294.851104 -393.283754) (xy 294.915072 -393.271309)
			(xy 294.980106 -393.267138) (xy 295.04514 -393.271309) (xy 295.109108 -393.283754) (xy 295.170962 -393.304269)
			(xy 295.229688 -393.332518) (xy 295.284324 -393.368039) (xy 295.333975 -393.410247) (xy 295.377827 -393.458454)
			(xy 295.39692 -393.484862) (xy 295.40529 -393.496027) (xy 295.426897 -393.51367) (xy 295.452471 -393.52481)
			(xy 295.480105 -393.528618) (xy 295.507739 -393.52481) (xy 295.533313 -393.51367) (xy 295.55492 -393.496027)
			(xy 295.56329 -393.484862) (xy 295.582383 -393.458454) (xy 295.626235 -393.410247) (xy 295.675886 -393.368039)
			(xy 295.730522 -393.332518) (xy 295.789248 -393.304269) (xy 295.851102 -393.283754) (xy 295.91507 -393.271309)
			(xy 295.980104 -393.267138) (xy 296.045138 -393.271309) (xy 296.109106 -393.283754) (xy 296.17096 -393.304269)
			(xy 296.229686 -393.332518) (xy 296.284322 -393.368039) (xy 296.333973 -393.410247) (xy 296.377825 -393.458454)
			(xy 296.396918 -393.484862) (xy 296.405288 -393.496027) (xy 296.426895 -393.51367) (xy 296.452469 -393.52481)
			(xy 296.480103 -393.528618) (xy 296.507737 -393.52481) (xy 296.533311 -393.51367) (xy 296.554918 -393.496027)
			(xy 296.563288 -393.484862) (xy 296.581151 -393.46008) (xy 296.621903 -393.414568) (xy 296.667813 -393.374265)
			(xy 296.71822 -393.339752) (xy 296.772399 -393.311525) (xy 296.829568 -393.289992) (xy 296.888906 -393.275462)
			(xy 296.949557 -393.268144) (xy 296.980102 -393.267692) (xy 297.012076 -393.268286) (xy 297.07552 -393.276301)
			(xy 297.137459 -393.292204) (xy 297.196916 -393.315745) (xy 297.252954 -393.346553) (xy 297.304689 -393.384141)
			(xy 297.351305 -393.427916) (xy 297.392067 -393.477189) (xy 297.426332 -393.531182) (xy 297.45356 -393.589044)
			(xy 297.473321 -393.649863) (xy 297.485304 -393.712678) (xy 297.489319 -393.7765) (xy 297.485304 -393.840322)
			(xy 297.473321 -393.903137) (xy 297.45356 -393.963956) (xy 297.426332 -394.021818) (xy 297.392067 -394.075811)
			(xy 297.351305 -394.125084) (xy 297.304689 -394.168859) (xy 297.252954 -394.206447) (xy 297.196916 -394.237255)
			(xy 297.137459 -394.260796) (xy 297.07552 -394.276699) (xy 297.012076 -394.284714) (xy 296.980102 -394.285216)
			(xy 296.949556 -394.284756) (xy 296.888904 -394.277447) (xy 296.829565 -394.262922) (xy 296.772394 -394.241392)
			(xy 296.718215 -394.213165) (xy 296.667809 -394.178649) (xy 296.621903 -394.138341) (xy 296.581158 -394.092823)
			(xy 296.563288 -394.068046) (xy 296.554946 -394.056837) (xy 296.53336 -394.03911) (xy 296.507771 -394.027912)
			(xy 296.480103 -394.024083) (xy 296.452435 -394.027912) (xy 296.426846 -394.03911) (xy 296.40526 -394.056837)
			(xy 296.396918 -394.068046) (xy 296.377825 -394.094454) (xy 296.333973 -394.142661) (xy 296.284322 -394.184869)
			(xy 296.229686 -394.22039) (xy 296.17096 -394.248639) (xy 296.109106 -394.269154) (xy 296.045138 -394.281599)
			(xy 295.980104 -394.28577) (xy 295.91507 -394.281599) (xy 295.851102 -394.269154) (xy 295.789248 -394.248639)
			(xy 295.730522 -394.22039) (xy 295.675886 -394.184869) (xy 295.626235 -394.142661) (xy 295.582383 -394.094454)
			(xy 295.56329 -394.068046) (xy 295.554948 -394.056837) (xy 295.533362 -394.03911) (xy 295.507773 -394.027912)
			(xy 295.480105 -394.024083) (xy 295.452437 -394.027912) (xy 295.426848 -394.03911) (xy 295.405262 -394.056837)
			(xy 295.39692 -394.068046) (xy 295.377827 -394.094454) (xy 295.333975 -394.142661) (xy 295.284324 -394.184869)
			(xy 295.229688 -394.22039) (xy 295.170962 -394.248639) (xy 295.109108 -394.269154) (xy 295.04514 -394.281599)
			(xy 294.980106 -394.28577) (xy 294.915072 -394.281599) (xy 294.851104 -394.269154) (xy 294.78925 -394.248639)
			(xy 294.730524 -394.22039) (xy 294.675888 -394.184869) (xy 294.626237 -394.142661) (xy 294.582385 -394.094454)
			(xy 294.563292 -394.068046) (xy 294.55495 -394.056837) (xy 294.533364 -394.03911) (xy 294.507775 -394.027912)
			(xy 294.480107 -394.024083) (xy 294.452439 -394.027912) (xy 294.42685 -394.03911) (xy 294.405264 -394.056837)
			(xy 294.396922 -394.068046) (xy 294.377829 -394.094454) (xy 294.333977 -394.142661) (xy 294.284326 -394.184869)
			(xy 294.22969 -394.22039) (xy 294.170964 -394.248639) (xy 294.10911 -394.269154) (xy 294.045142 -394.281599)
			(xy 293.980108 -394.28577) (xy 293.915074 -394.281599) (xy 293.851106 -394.269154) (xy 293.789252 -394.248639)
			(xy 293.730526 -394.22039) (xy 293.67589 -394.184869) (xy 293.626239 -394.142661) (xy 293.582387 -394.094454)
			(xy 293.563294 -394.068046) (xy 293.554952 -394.056837) (xy 293.533366 -394.03911) (xy 293.507777 -394.027912)
			(xy 293.480109 -394.024083) (xy 293.452441 -394.027912) (xy 293.426852 -394.03911) (xy 293.405266 -394.056837)
			(xy 293.396924 -394.068046) (xy 293.377831 -394.094454) (xy 293.333979 -394.142661) (xy 293.284328 -394.184869)
			(xy 293.229692 -394.22039) (xy 293.170966 -394.248639) (xy 293.109112 -394.269154) (xy 293.045144 -394.281599)
			(xy 292.98011 -394.28577) (xy 292.915076 -394.281599) (xy 292.851108 -394.269154) (xy 292.789254 -394.248639)
			(xy 292.730528 -394.22039) (xy 292.675892 -394.184869) (xy 292.626241 -394.142661) (xy 292.582389 -394.094454)
			(xy 292.563296 -394.068046) (xy 292.554954 -394.056837) (xy 292.533368 -394.03911) (xy 292.507779 -394.027912)
			(xy 292.480111 -394.024083) (xy 292.452443 -394.027912) (xy 292.426854 -394.03911) (xy 292.405268 -394.056837)
			(xy 292.396926 -394.068046) (xy 292.379057 -394.092823) (xy 292.338306 -394.138335) (xy 292.292396 -394.178638)
			(xy 292.24199 -394.213151) (xy 292.187812 -394.241378) (xy 292.130644 -394.262913) (xy 292.071307 -394.277444)
			(xy 292.010657 -394.284763) (xy 291.980112 -394.285216) (xy 291.94813 -394.284828) (xy 291.884671 -394.276812)
			(xy 291.822717 -394.260906) (xy 291.763245 -394.237361) (xy 291.707193 -394.206547) (xy 291.655445 -394.168951)
			(xy 291.608817 -394.125166) (xy 291.568045 -394.075882) (xy 291.533771 -394.021876) (xy 291.506536 -393.964)
			(xy 291.48677 -393.903168) (xy 291.474784 -393.840337) (xy 291.470768 -393.7765) (xy 290.488624 -393.7765)
			(xy 290.488624 -393.776962) (xy 290.488202 -393.806564) (xy 290.481324 -393.865367) (xy 290.467658 -393.922971)
			(xy 290.447389 -393.978597) (xy 290.420792 -394.03149) (xy 290.388226 -394.080932) (xy 290.369498 -394.10386)
			(xy 290.389588 -394.127178) (xy 290.424612 -394.17779) (xy 290.453267 -394.232263) (xy 290.475133 -394.289797)
			(xy 290.48989 -394.349552) (xy 290.497321 -394.410651) (xy 290.497768 -394.441426) (xy 290.497768 -394.44168)
			(xy 290.497266 -394.473641) (xy 290.489255 -394.537059) (xy 290.473358 -394.598973) (xy 290.449826 -394.658406)
			(xy 290.419032 -394.714421) (xy 290.381459 -394.766136) (xy 290.337702 -394.812733) (xy 290.288449 -394.853478)
			(xy 290.234478 -394.887729) (xy 290.176639 -394.914946) (xy 290.115846 -394.934699) (xy 290.053056 -394.946677)
			(xy 289.98926 -394.950691) (xy 289.925464 -394.946677) (xy 289.862674 -394.934699) (xy 289.801881 -394.914946)
			(xy 289.744042 -394.887729) (xy 289.690071 -394.853478) (xy 289.640818 -394.812733) (xy 289.597061 -394.766136)
			(xy 289.559488 -394.714421) (xy 289.528694 -394.658406) (xy 289.505162 -394.598973) (xy 289.489265 -394.537059)
			(xy 289.481254 -394.473641) (xy 289.480752 -394.44168) (xy 289.480752 -394.441172) (xy 289.481141 -394.411569)
			(xy 289.488026 -394.352765) (xy 289.501699 -394.29516) (xy 289.521974 -394.239535) (xy 289.548577 -394.186643)
			(xy 289.581148 -394.137202) (xy 289.599878 -394.114274) (xy 289.579769 -394.090972) (xy 289.544745 -394.040357)
			(xy 289.516091 -393.985882) (xy 289.494228 -393.928344) (xy 289.479476 -393.868586) (xy 289.472051 -393.807484)
			(xy 289.471608 -393.776708) (xy 281.461756 -393.776708) (xy 281.447947 -393.823957) (xy 281.416708 -393.902348)
			(xy 281.378185 -393.977427) (xy 281.332723 -394.04852) (xy 281.280732 -394.114986) (xy 281.222678 -394.176229)
			(xy 281.159084 -394.231698) (xy 281.090523 -394.280894) (xy 281.017609 -394.323374) (xy 280.941 -394.358757)
			(xy 280.861383 -394.386724) (xy 280.779476 -394.407024) (xy 280.737818 -394.41374) (xy 280.72343 -394.416347)
			(xy 280.696933 -394.428691) (xy 280.675026 -394.448046) (xy 280.659511 -394.472819) (xy 280.651661 -394.500977)
			(xy 280.652122 -394.530204) (xy 280.65603 -394.544296) (xy 280.668744 -394.587158) (xy 280.686507 -394.674785)
			(xy 280.695395 -394.763751) (xy 280.695908 -394.808456) (xy 280.695404 -394.850804) (xy 280.687353 -394.935118)
			(xy 280.671324 -395.018284) (xy 280.647463 -395.099551) (xy 280.615984 -395.178181) (xy 280.577173 -395.253462)
			(xy 280.531383 -395.324714) (xy 280.479027 -395.39129) (xy 280.420579 -395.452588) (xy 280.356569 -395.508053)
			(xy 280.287577 -395.557182) (xy 280.214227 -395.599531) (xy 280.137184 -395.634715) (xy 280.057145 -395.662417)
			(xy 279.974836 -395.682385) (xy 279.891001 -395.694438) (xy 279.8064 -395.698469) (xy 279.721799 -395.694438)
			(xy 279.637964 -395.682385) (xy 279.555655 -395.662417) (xy 279.475616 -395.634715) (xy 279.398573 -395.599531)
			(xy 279.325223 -395.557182) (xy 279.256231 -395.508053) (xy 279.192221 -395.452588) (xy 279.133773 -395.39129)
			(xy 279.081417 -395.324714) (xy 279.035627 -395.253462) (xy 278.996816 -395.178181) (xy 278.965337 -395.099551)
			(xy 278.941476 -395.018284) (xy 278.925447 -394.935118) (xy 278.917396 -394.850804) (xy 278.916892 -394.808456)
			(xy 276.182385 -394.808456) (xy 276.182339 -394.81111) (xy 276.173854 -394.867601) (xy 276.157051 -394.922198)
			(xy 276.132304 -394.973684) (xy 276.100165 -395.02091) (xy 276.061351 -395.062822) (xy 276.016728 -395.098487)
			(xy 275.967291 -395.127109) (xy 275.914142 -395.148048) (xy 275.858468 -395.160839) (xy 275.83003 -395.163548)
			(xy 275.812369 -395.202766) (xy 275.770577 -395.277947) (xy 275.721724 -395.348744) (xy 275.666266 -395.414494)
			(xy 275.60472 -395.474584) (xy 275.537661 -395.528453) (xy 275.465716 -395.575598) (xy 275.389556 -395.615578)
			(xy 275.309893 -395.648021) (xy 275.22747 -395.672622) (xy 275.143058 -395.689153) (xy 275.057444 -395.697459)
			(xy 275.014436 -395.697964) (xy 274.973213 -395.69746) (xy 274.891121 -395.689828) (xy 274.810087 -395.674636)
			(xy 274.730806 -395.652015) (xy 274.653956 -395.622157) (xy 274.580198 -395.585319) (xy 274.510163 -395.541817)
			(xy 274.444452 -395.492024) (xy 274.413726 -395.464538) (xy 274.406494 -395.458451) (xy 274.388881 -395.451625)
			(xy 274.369991 -395.451625) (xy 274.352378 -395.458451) (xy 274.345146 -395.464538) (xy 274.314435 -395.492044)
			(xy 274.248729 -395.54185) (xy 274.178695 -395.585362) (xy 274.104936 -395.622207) (xy 274.028083 -395.652068)
			(xy 273.948797 -395.67469) (xy 273.867758 -395.689878) (xy 273.785661 -395.697501) (xy 273.744436 -395.697964)
			(xy 273.702084 -395.697566) (xy 273.617762 -395.689517) (xy 273.534587 -395.673489) (xy 273.453313 -395.649628)
			(xy 273.374675 -395.618149) (xy 273.299385 -395.579337) (xy 273.228125 -395.533544) (xy 273.161542 -395.481184)
			(xy 273.100237 -395.422733) (xy 273.044766 -395.358718) (xy 272.995631 -395.28972) (xy 272.953277 -395.216364)
			(xy 272.918089 -395.139314) (xy 272.890384 -395.059269) (xy 272.870414 -394.976952) (xy 272.858359 -394.893109)
			(xy 272.854328 -394.8085) (xy 270.24739 -394.8085) (xy 270.247342 -394.811109) (xy 270.238858 -394.867596)
			(xy 270.222057 -394.922191) (xy 270.197312 -394.973674) (xy 270.165177 -395.020899) (xy 270.126367 -395.062811)
			(xy 270.081748 -395.098476) (xy 270.032316 -395.127099) (xy 269.979172 -395.148042) (xy 269.923503 -395.160836)
			(xy 269.895066 -395.163548) (xy 269.877376 -395.202752) (xy 269.835586 -395.277933) (xy 269.786736 -395.348729)
			(xy 269.73128 -395.414479) (xy 269.669737 -395.474569) (xy 269.602681 -395.528439) (xy 269.530739 -395.575585)
			(xy 269.454582 -395.615566) (xy 269.374921 -395.648011) (xy 269.292501 -395.672615) (xy 269.208091 -395.689148)
			(xy 269.122479 -395.697457) (xy 269.079472 -395.697964) (xy 269.038248 -395.6975) (xy 268.956155 -395.689862)
			(xy 268.87512 -395.674665) (xy 268.795838 -395.652037) (xy 268.718989 -395.622174) (xy 268.645231 -395.585331)
			(xy 268.575197 -395.541824) (xy 268.509487 -395.492026) (xy 268.478762 -395.464538) (xy 268.47153 -395.458451)
			(xy 268.453917 -395.451625) (xy 268.435027 -395.451625) (xy 268.417414 -395.458451) (xy 268.410182 -395.464538)
			(xy 268.379456 -395.492026) (xy 268.313752 -395.541834) (xy 268.243721 -395.585348) (xy 268.169964 -395.622194)
			(xy 268.093113 -395.652058) (xy 268.013829 -395.674682) (xy 267.932792 -395.689873) (xy 267.850696 -395.6975)
			(xy 267.809472 -395.697964) (xy 267.767122 -395.697547) (xy 267.682807 -395.689493) (xy 267.599638 -395.673462)
			(xy 267.51837 -395.649597) (xy 267.439739 -395.618115) (xy 267.364456 -395.579302) (xy 267.293203 -395.533509)
			(xy 267.226625 -395.48115) (xy 267.165326 -395.422699) (xy 267.109861 -395.358687) (xy 267.060731 -395.289692)
			(xy 267.018382 -395.21634) (xy 266.983198 -395.139294) (xy 266.955496 -395.059253) (xy 266.935527 -394.976941)
			(xy 266.923474 -394.893104) (xy 266.919443 -394.8085) (xy 264.362285 -394.8085) (xy 264.362285 -394.80972)
			(xy 264.354537 -394.863607) (xy 264.3392 -394.915842) (xy 264.316584 -394.965363) (xy 264.287151 -395.011162)
			(xy 264.251499 -395.052305) (xy 264.210355 -395.087955) (xy 264.164556 -395.117388) (xy 264.115035 -395.140002)
			(xy 264.062799 -395.155339) (xy 264.008912 -395.163086) (xy 263.981692 -395.163548) (xy 263.960356 -395.16304)
			(xy 263.942674 -395.202274) (xy 263.9009 -395.277517) (xy 263.852055 -395.348375) (xy 263.796597 -395.414185)
			(xy 263.735042 -395.474332) (xy 263.667968 -395.528254) (xy 263.596 -395.575447) (xy 263.519811 -395.61547)
			(xy 263.440113 -395.647949) (xy 263.357652 -395.67258) (xy 263.273197 -395.689134) (xy 263.187539 -395.697455)
			(xy 263.144508 -395.697964) (xy 263.103285 -395.697477) (xy 263.021192 -395.689843) (xy 262.940158 -395.674649)
			(xy 262.860876 -395.652025) (xy 262.784027 -395.622164) (xy 262.710269 -395.585324) (xy 262.640234 -395.54182)
			(xy 262.574524 -395.492025) (xy 262.543798 -395.464538) (xy 262.536566 -395.458451) (xy 262.518953 -395.451625)
			(xy 262.500063 -395.451625) (xy 262.48245 -395.458451) (xy 262.475218 -395.464538) (xy 262.444477 -395.492009)
			(xy 262.378775 -395.541818) (xy 262.308747 -395.585333) (xy 262.234992 -395.622182) (xy 262.158144 -395.652048)
			(xy 262.078861 -395.674675) (xy 261.997826 -395.689868) (xy 261.915732 -395.697498) (xy 261.874508 -395.697964)
			(xy 261.832156 -395.697564) (xy 261.747837 -395.689513) (xy 261.664664 -395.673484) (xy 261.583392 -395.649621)
			(xy 261.504756 -395.61814) (xy 261.429469 -395.579328) (xy 261.358212 -395.533534) (xy 261.29163 -395.481174)
			(xy 261.230327 -395.422723) (xy 261.174858 -395.358709) (xy 261.125725 -395.289712) (xy 261.083374 -395.216357)
			(xy 261.048186 -395.139308) (xy 261.020483 -395.059264) (xy 261.000513 -394.976948) (xy 260.988458 -394.893107)
			(xy 260.984428 -394.8085) (xy 258.448577 -394.8085) (xy 258.448577 -394.809789) (xy 258.440811 -394.863811)
			(xy 258.425436 -394.916178) (xy 258.402765 -394.965824) (xy 258.37326 -395.011739) (xy 258.337522 -395.052988)
			(xy 258.296278 -395.088732) (xy 258.250366 -395.118242) (xy 258.200723 -395.140919) (xy 258.148358 -395.156301)
			(xy 258.094337 -395.164074) (xy 258.067048 -395.164564) (xy 258.056676 -395.164479) (xy 258.035964 -395.163337)
			(xy 258.025646 -395.162278) (xy 258.008 -395.201564) (xy 257.966267 -395.276906) (xy 257.917448 -395.347861)
			(xy 257.861999 -395.413765) (xy 257.80044 -395.474001) (xy 257.733346 -395.528004) (xy 257.661347 -395.575269)
			(xy 257.585116 -395.615354) (xy 257.505368 -395.647883) (xy 257.422848 -395.672551) (xy 257.338331 -395.689127)
			(xy 257.252608 -395.697456) (xy 257.209544 -395.697964) (xy 257.168321 -395.697455) (xy 257.08623 -395.689824)
			(xy 257.005196 -395.674633) (xy 256.925914 -395.652012) (xy 256.849065 -395.622155) (xy 256.775306 -395.585317)
			(xy 256.705271 -395.541816) (xy 256.63956 -395.492023) (xy 256.608834 -395.464538) (xy 256.601602 -395.458451)
			(xy 256.583989 -395.451625) (xy 256.565099 -395.451625) (xy 256.547486 -395.458451) (xy 256.540254 -395.464538)
			(xy 256.50954 -395.49204) (xy 256.443834 -395.541846) (xy 256.373801 -395.585359) (xy 256.300042 -395.622204)
			(xy 256.22319 -395.652066) (xy 256.143904 -395.674688) (xy 256.062865 -395.689877) (xy 255.980769 -395.697501)
			(xy 255.939544 -395.697964) (xy 255.897191 -395.697566) (xy 255.812869 -395.689518) (xy 255.729694 -395.673491)
			(xy 255.648419 -395.64963) (xy 255.56978 -395.618151) (xy 255.494489 -395.57934) (xy 255.423229 -395.533547)
			(xy 255.356645 -395.481187) (xy 255.295339 -395.422735) (xy 255.239868 -395.358721) (xy 255.190732 -395.289723)
			(xy 255.148379 -395.216366) (xy 255.11319 -395.139316) (xy 255.085484 -395.05927) (xy 255.065514 -394.976952)
			(xy 255.053459 -394.893109) (xy 255.049428 -394.8085) (xy 252.466916 -394.8085) (xy 252.466897 -394.809592)
			(xy 252.459254 -394.863136) (xy 252.444116 -394.915061) (xy 252.421785 -394.964324) (xy 252.392711 -395.009932)
			(xy 252.357479 -395.05097) (xy 252.316797 -395.086613) (xy 252.271483 -395.116143) (xy 252.222447 -395.138967)
			(xy 252.170677 -395.154627) (xy 252.117212 -395.162807) (xy 252.090174 -395.163548) (xy 252.072477 -395.202749)
			(xy 252.030688 -395.27793) (xy 251.981838 -395.348725) (xy 251.926383 -395.414475) (xy 251.864841 -395.474566)
			(xy 251.797785 -395.528436) (xy 251.725844 -395.575582) (xy 251.649687 -395.615564) (xy 251.570027 -395.648009)
			(xy 251.487608 -395.672613) (xy 251.403198 -395.689147) (xy 251.317587 -395.697457) (xy 251.27458 -395.697964)
			(xy 251.233356 -395.697495) (xy 251.151263 -395.689858) (xy 251.070228 -395.674661) (xy 250.990947 -395.652035)
			(xy 250.914097 -395.622172) (xy 250.840339 -395.58533) (xy 250.770305 -395.541823) (xy 250.704595 -395.492026)
			(xy 250.67387 -395.464538) (xy 250.666638 -395.458451) (xy 250.649025 -395.451625) (xy 250.630135 -395.451625)
			(xy 250.612522 -395.458451) (xy 250.60529 -395.464538) (xy 250.574561 -395.492023) (xy 250.508857 -395.54183)
			(xy 250.438827 -395.585344) (xy 250.36507 -395.622192) (xy 250.28822 -395.652056) (xy 250.208936 -395.67468)
			(xy 250.127899 -395.689872) (xy 250.045804 -395.697499) (xy 250.00458 -395.697964) (xy 249.96223 -395.697547)
			(xy 249.877914 -395.689494) (xy 249.794745 -395.673463) (xy 249.713476 -395.649599) (xy 249.634844 -395.618118)
			(xy 249.55956 -395.579305) (xy 249.488307 -395.533512) (xy 249.421729 -395.481153) (xy 249.360429 -395.422702)
			(xy 249.304963 -395.35869) (xy 249.255833 -395.289695) (xy 249.213483 -395.216342) (xy 249.178298 -395.139296)
			(xy 249.150596 -395.059254) (xy 249.130628 -394.976942) (xy 249.118574 -394.893104) (xy 249.114543 -394.8085)
			(xy 246.507582 -394.8085) (xy 246.507538 -394.811111) (xy 246.499052 -394.867604) (xy 246.482248 -394.922202)
			(xy 246.457499 -394.973689) (xy 246.425358 -395.020916) (xy 246.386542 -395.062829) (xy 246.341916 -395.098493)
			(xy 246.292476 -395.127114) (xy 246.239326 -395.148052) (xy 246.183649 -395.16084) (xy 246.15521 -395.163548)
			(xy 246.137565 -395.202774) (xy 246.095772 -395.277955) (xy 246.046918 -395.348752) (xy 245.991458 -395.414502)
			(xy 245.929911 -395.474592) (xy 245.86285 -395.528461) (xy 245.790904 -395.575605) (xy 245.714742 -395.615585)
			(xy 245.635078 -395.648026) (xy 245.552653 -395.672626) (xy 245.46824 -395.689156) (xy 245.382624 -395.69746)
			(xy 245.339616 -395.697964) (xy 245.298393 -395.697472) (xy 245.216301 -395.689839) (xy 245.135266 -395.674645)
			(xy 245.055985 -395.652022) (xy 244.979135 -395.622162) (xy 244.905377 -395.585323) (xy 244.835342 -395.541819)
			(xy 244.769632 -395.492024) (xy 244.738906 -395.464538) (xy 244.731674 -395.458451) (xy 244.714061 -395.451625)
			(xy 244.695171 -395.451625) (xy 244.677558 -395.458451) (xy 244.670326 -395.464538) (xy 244.639624 -395.492053)
			(xy 244.573916 -395.541859) (xy 244.503881 -395.58537) (xy 244.43012 -395.622214) (xy 244.353266 -395.652074)
			(xy 244.273979 -395.674694) (xy 244.192939 -395.68988) (xy 244.110841 -395.697502) (xy 244.069616 -395.697964)
			(xy 244.027264 -395.697565) (xy 243.942944 -395.689514) (xy 243.859771 -395.673485) (xy 243.778498 -395.649623)
			(xy 243.699861 -395.618143) (xy 243.624573 -395.57933) (xy 243.553315 -395.533537) (xy 243.486733 -395.481177)
			(xy 243.42543 -395.422726) (xy 243.36996 -395.358711) (xy 243.320827 -395.289714) (xy 243.278475 -395.216359)
			(xy 243.243287 -395.13931) (xy 243.215583 -395.059265) (xy 243.195613 -394.976949) (xy 243.183558 -394.893108)
			(xy 243.179528 -394.8085) (xy 2.509012 -394.8085) (xy 2.509012 -396.842996) (xy 18.90268 -396.842996)
			(xy 18.90268 -395.979396) (xy 18.903166 -395.952145) (xy 18.910922 -395.898197) (xy 18.926277 -395.845902)
			(xy 18.948919 -395.796325) (xy 18.978385 -395.750475) (xy 19.014076 -395.709284) (xy 19.055267 -395.673593)
			(xy 19.101117 -395.644127) (xy 19.150694 -395.621485) (xy 19.202989 -395.60613) (xy 19.256937 -395.598374)
			(xy 19.311439 -395.598374) (xy 19.365387 -395.60613) (xy 19.417682 -395.621485) (xy 19.467259 -395.644127)
			(xy 19.513109 -395.673593) (xy 19.5543 -395.709284) (xy 19.589991 -395.750475) (xy 19.601933 -395.769057)
			(xy 288.471858 -395.769057) (xy 288.471858 -395.705103) (xy 288.479873 -395.641653) (xy 288.495778 -395.579708)
			(xy 288.519321 -395.520246) (xy 288.550131 -395.464202) (xy 288.587723 -395.412462) (xy 288.631502 -395.365842)
			(xy 288.68078 -395.325076) (xy 288.734778 -395.290808) (xy 288.792645 -395.263577) (xy 288.853469 -395.243814)
			(xy 288.91629 -395.231831) (xy 288.980118 -395.227815) (xy 289.043946 -395.231831) (xy 289.106767 -395.243814)
			(xy 289.167591 -395.263577) (xy 289.225458 -395.290808) (xy 289.279456 -395.325076) (xy 289.328734 -395.365842)
			(xy 289.372513 -395.412462) (xy 289.410105 -395.464202) (xy 289.440915 -395.520246) (xy 289.464458 -395.579708)
			(xy 289.480363 -395.641653) (xy 289.488378 -395.705103) (xy 289.48888 -395.73708) (xy 289.488378 -395.769057)
			(xy 289.480363 -395.832507) (xy 289.464458 -395.894452) (xy 289.440915 -395.953914) (xy 289.410105 -396.009958)
			(xy 289.372513 -396.061698) (xy 289.328734 -396.108318) (xy 289.279456 -396.149084) (xy 289.225458 -396.183352)
			(xy 289.167591 -396.210583) (xy 289.106767 -396.230346) (xy 289.043946 -396.242329) (xy 288.980118 -396.246345)
			(xy 288.91629 -396.242329) (xy 288.853469 -396.230346) (xy 288.792645 -396.210583) (xy 288.734778 -396.183352)
			(xy 288.68078 -396.149084) (xy 288.631502 -396.108318) (xy 288.587723 -396.061698) (xy 288.550131 -396.009958)
			(xy 288.519321 -395.953914) (xy 288.495778 -395.894452) (xy 288.479873 -395.832507) (xy 288.471858 -395.769057)
			(xy 19.601933 -395.769057) (xy 19.619457 -395.796325) (xy 19.642099 -395.845902) (xy 19.657454 -395.898197)
			(xy 19.66521 -395.952145) (xy 19.665696 -395.979396) (xy 19.665696 -396.842996) (xy 19.66521 -396.870247)
			(xy 19.657454 -396.924195) (xy 19.642099 -396.97649) (xy 19.619457 -397.026067) (xy 19.589991 -397.071917)
			(xy 19.5543 -397.113108) (xy 19.513109 -397.148799) (xy 19.467259 -397.178265) (xy 19.417682 -397.200907)
			(xy 19.365387 -397.216262) (xy 19.311439 -397.224018) (xy 19.256937 -397.224018) (xy 19.202989 -397.216262)
			(xy 19.150694 -397.200907) (xy 19.101117 -397.178265) (xy 19.055267 -397.148799) (xy 19.014076 -397.113108)
			(xy 18.978385 -397.071917) (xy 18.948919 -397.026067) (xy 18.926277 -396.97649) (xy 18.910922 -396.924195)
			(xy 18.903166 -396.870247) (xy 18.90268 -396.842996) (xy 2.509012 -396.842996) (xy 2.509012 -397.606012)
			(xy 24.954992 -397.606012) (xy 24.954992 -396.742412) (xy 24.955478 -396.715161) (xy 24.963234 -396.661213)
			(xy 24.978589 -396.608918) (xy 25.001231 -396.559341) (xy 25.030697 -396.513491) (xy 25.066388 -396.4723)
			(xy 25.107579 -396.436609) (xy 25.153429 -396.407143) (xy 25.203006 -396.384501) (xy 25.255301 -396.369146)
			(xy 25.309249 -396.36139) (xy 25.363751 -396.36139) (xy 25.417699 -396.369146) (xy 25.469994 -396.384501)
			(xy 25.519571 -396.407143) (xy 25.565421 -396.436609) (xy 25.606612 -396.4723) (xy 25.642303 -396.513491)
			(xy 25.671769 -396.559341) (xy 25.694411 -396.608918) (xy 25.709766 -396.661213) (xy 25.717522 -396.715161)
			(xy 25.718008 -396.742412) (xy 25.718008 -397.606012) (xy 25.717522 -397.633263) (xy 25.709766 -397.687211)
			(xy 25.694411 -397.739506) (xy 25.671769 -397.789083) (xy 25.642303 -397.834933) (xy 25.606612 -397.876124)
			(xy 25.565421 -397.911815) (xy 25.519571 -397.941281) (xy 25.469994 -397.963923) (xy 25.417699 -397.979278)
			(xy 25.363751 -397.987034) (xy 25.309249 -397.987034) (xy 25.255301 -397.979278) (xy 25.203006 -397.963923)
			(xy 25.153429 -397.941281) (xy 25.107579 -397.911815) (xy 25.066388 -397.876124) (xy 25.030697 -397.834933)
			(xy 25.001231 -397.789083) (xy 24.978589 -397.739506) (xy 24.963234 -397.687211) (xy 24.955478 -397.633263)
			(xy 24.954992 -397.606012) (xy 2.509012 -397.606012) (xy 2.509012 -398.68657) (xy 36.781952 -398.68657)
			(xy 36.781952 -398.63203) (xy 36.789714 -398.578046) (xy 36.805081 -398.525717) (xy 36.827739 -398.476107)
			(xy 36.857227 -398.430227) (xy 36.892945 -398.389011) (xy 36.934165 -398.353298) (xy 36.980049 -398.323816)
			(xy 37.029662 -398.301164) (xy 37.081993 -398.285804) (xy 37.135978 -398.278048) (xy 37.163248 -398.277588)
			(xy 38.026848 -398.277588) (xy 38.054119 -398.277978) (xy 38.108104 -398.285746) (xy 38.160435 -398.301118)
			(xy 38.210045 -398.323779) (xy 38.255926 -398.353271) (xy 38.297144 -398.38899) (xy 38.332858 -398.430212)
			(xy 38.362344 -398.476097) (xy 38.384999 -398.52571) (xy 38.400364 -398.578043) (xy 38.408126 -398.632029)
			(xy 38.408126 -398.686571) (xy 38.400364 -398.740557) (xy 38.384999 -398.79289) (xy 38.38214 -398.799152)
			(xy 42.10455 -398.799152) (xy 42.10455 -398.744648) (xy 42.112306 -398.6907) (xy 42.12766 -398.638404)
			(xy 42.150301 -398.588826) (xy 42.179766 -398.542974) (xy 42.215456 -398.501781) (xy 42.256645 -398.466087)
			(xy 42.302494 -398.436618) (xy 42.35207 -398.413973) (xy 42.404365 -398.398614) (xy 42.458312 -398.390852)
			(xy 42.485564 -398.390364) (xy 43.349164 -398.390364) (xy 43.376417 -398.390881) (xy 43.430367 -398.398633)
			(xy 43.482666 -398.413985) (xy 43.532247 -398.436624) (xy 43.578101 -398.466088) (xy 43.619295 -398.50178)
			(xy 43.65499 -398.54297) (xy 43.684459 -398.588822) (xy 43.707103 -398.638401) (xy 43.722459 -398.690697)
			(xy 43.730217 -398.744648) (xy 43.730217 -398.799152) (xy 43.722459 -398.853103) (xy 43.707103 -398.9054)
			(xy 43.684459 -398.954978) (xy 43.65499 -399.00083) (xy 43.619295 -399.04202) (xy 43.578101 -399.077712)
			(xy 43.532247 -399.107176) (xy 43.482666 -399.129815) (xy 43.430367 -399.145167) (xy 43.376417 -399.152919)
			(xy 43.349164 -399.15338) (xy 42.485564 -399.15338) (xy 42.458312 -399.152948) (xy 42.404365 -399.145186)
			(xy 42.35207 -399.129827) (xy 42.302494 -399.107182) (xy 42.256645 -399.077713) (xy 42.215456 -399.042019)
			(xy 42.179766 -399.000826) (xy 42.150301 -398.954974) (xy 42.12766 -398.905396) (xy 42.112306 -398.8531)
			(xy 42.10455 -398.799152) (xy 38.38214 -398.799152) (xy 38.362344 -398.842503) (xy 38.332858 -398.888388)
			(xy 38.297144 -398.92961) (xy 38.255926 -398.965329) (xy 38.210045 -398.994821) (xy 38.160435 -399.017482)
			(xy 38.108104 -399.032854) (xy 38.054119 -399.040622) (xy 38.026848 -399.041112) (xy 37.163248 -399.041112)
			(xy 37.135978 -399.040552) (xy 37.081993 -399.032796) (xy 37.029662 -399.017436) (xy 36.980049 -398.994784)
			(xy 36.934165 -398.965302) (xy 36.892945 -398.929589) (xy 36.857227 -398.888373) (xy 36.827739 -398.842493)
			(xy 36.805081 -398.792883) (xy 36.789714 -398.740554) (xy 36.781952 -398.68657) (xy 2.509012 -398.68657)
			(xy 2.509012 -399.443249) (xy 18.470394 -399.443249) (xy 18.470394 -399.388751) (xy 18.47815 -399.334808)
			(xy 18.493503 -399.282518) (xy 18.516141 -399.232945) (xy 18.545603 -399.187098) (xy 18.58129 -399.14591)
			(xy 18.622475 -399.11022) (xy 18.66832 -399.080754) (xy 18.717892 -399.058112) (xy 18.770181 -399.042756)
			(xy 18.824123 -399.034996) (xy 18.851372 -399.034508) (xy 19.714972 -399.034508) (xy 19.742227 -399.034937)
			(xy 19.796184 -399.042691) (xy 19.848487 -399.058045) (xy 19.898073 -399.080687) (xy 19.943931 -399.110156)
			(xy 19.985129 -399.145851) (xy 20.020827 -399.187046) (xy 20.050299 -399.232903) (xy 20.072945 -399.282487)
			(xy 20.088303 -399.334789) (xy 20.096061 -399.388745) (xy 20.096061 -399.443255) (xy 20.088303 -399.497211)
			(xy 20.072945 -399.549513) (xy 20.050299 -399.599097) (xy 20.020828 -399.644954) (xy 19.985129 -399.686149)
			(xy 19.943931 -399.721844) (xy 19.898073 -399.751313) (xy 19.848487 -399.773955) (xy 19.796184 -399.789309)
			(xy 19.742227 -399.797063) (xy 19.714972 -399.797524) (xy 18.851372 -399.797524) (xy 18.824123 -399.797004)
			(xy 18.770181 -399.789244) (xy 18.717892 -399.773888) (xy 18.66832 -399.751246) (xy 18.622475 -399.72178)
			(xy 18.58129 -399.68609) (xy 18.545603 -399.644902) (xy 18.516141 -399.599055) (xy 18.493503 -399.549482)
			(xy 18.47815 -399.497192) (xy 18.470394 -399.443249) (xy 2.509012 -399.443249) (xy 2.509012 -400.459248)
			(xy 25.590794 -400.459248) (xy 25.590794 -400.404752) (xy 25.598549 -400.350811) (xy 25.613901 -400.298522)
			(xy 25.636538 -400.24895) (xy 25.665999 -400.203104) (xy 25.701684 -400.161916) (xy 25.742867 -400.126226)
			(xy 25.788709 -400.09676) (xy 25.838279 -400.074117) (xy 25.890566 -400.058759) (xy 25.944506 -400.050997)
			(xy 25.971754 -400.050508) (xy 26.835354 -400.050508) (xy 26.86261 -400.050936) (xy 26.916568 -400.058688)
			(xy 26.968874 -400.07404) (xy 27.018462 -400.096681) (xy 27.064323 -400.126149) (xy 27.105523 -400.161845)
			(xy 27.141223 -400.20304) (xy 27.170697 -400.248897) (xy 27.193343 -400.298483) (xy 27.208702 -400.350787)
			(xy 27.216461 -400.404744) (xy 27.216461 -400.459256) (xy 27.208702 -400.513213) (xy 27.193343 -400.565517)
			(xy 27.170697 -400.615103) (xy 27.141223 -400.66096) (xy 27.105523 -400.702155) (xy 27.064323 -400.737851)
			(xy 27.018462 -400.767319) (xy 26.968874 -400.78996) (xy 26.916568 -400.805312) (xy 26.86261 -400.813064)
			(xy 26.835354 -400.813524) (xy 25.971754 -400.813524) (xy 25.944506 -400.813003) (xy 25.890566 -400.805241)
			(xy 25.838279 -400.789883) (xy 25.788709 -400.76724) (xy 25.742867 -400.737774) (xy 25.701684 -400.702084)
			(xy 25.665999 -400.660896) (xy 25.636538 -400.61505) (xy 25.613901 -400.565478) (xy 25.598549 -400.513189)
			(xy 25.590794 -400.459248) (xy 2.509012 -400.459248) (xy 2.509012 -400.885453) (xy 47.598783 -400.885453)
			(xy 47.598783 -400.830947) (xy 47.606541 -400.776997) (xy 47.621898 -400.7247) (xy 47.644541 -400.675121)
			(xy 47.674011 -400.629269) (xy 47.709706 -400.588079) (xy 47.7509 -400.552388) (xy 47.796754 -400.522923)
			(xy 47.846336 -400.500284) (xy 47.898634 -400.484933) (xy 47.952585 -400.477181) (xy 47.979838 -400.47672)
			(xy 48.843438 -400.47672) (xy 48.870689 -400.477152) (xy 48.924637 -400.484914) (xy 48.976931 -400.500273)
			(xy 49.026507 -400.522918) (xy 49.072356 -400.552388) (xy 49.113545 -400.588082) (xy 49.149235 -400.629274)
			(xy 49.1787 -400.675126) (xy 49.20134 -400.724705) (xy 49.216694 -400.777) (xy 49.22445 -400.830948)
			(xy 49.22445 -400.885448) (xy 50.662106 -400.885448) (xy 50.662106 -400.830952) (xy 50.669862 -400.77701)
			(xy 50.685214 -400.724721) (xy 50.707852 -400.675149) (xy 50.737314 -400.629303) (xy 50.773001 -400.588116)
			(xy 50.814185 -400.552427) (xy 50.86003 -400.522963) (xy 50.9096 -400.500322) (xy 50.961888 -400.484966)
			(xy 51.01583 -400.477208) (xy 51.043078 -400.47672) (xy 51.906678 -400.47672) (xy 51.933934 -400.477125)
			(xy 51.987891 -400.48488) (xy 52.040196 -400.500236) (xy 52.089782 -400.522879) (xy 52.135642 -400.552348)
			(xy 52.17684 -400.588045) (xy 52.212539 -400.629241) (xy 52.242011 -400.675098) (xy 52.264657 -400.724684)
			(xy 52.280015 -400.776987) (xy 52.287773 -400.830944) (xy 52.287773 -400.885452) (xy 53.725283 -400.885452)
			(xy 53.725283 -400.830948) (xy 53.73304 -400.777) (xy 53.748396 -400.724704) (xy 53.771038 -400.675127)
			(xy 53.800506 -400.629276) (xy 53.836199 -400.588086) (xy 53.87739 -400.552395) (xy 53.923242 -400.52293)
			(xy 53.972821 -400.50029) (xy 54.025117 -400.484936) (xy 54.079066 -400.477182) (xy 54.106318 -400.47672)
			(xy 54.969918 -400.47672) (xy 54.99717 -400.477151) (xy 55.05112 -400.48491) (xy 55.103417 -400.500268)
			(xy 55.152995 -400.522912) (xy 55.198847 -400.552381) (xy 55.240038 -400.588075) (xy 55.27573 -400.629268)
			(xy 55.305197 -400.675121) (xy 55.327838 -400.7247) (xy 55.343194 -400.776997) (xy 55.35095 -400.830948)
			(xy 55.35095 -400.885447) (xy 56.788606 -400.885447) (xy 56.788606 -400.830953) (xy 56.796361 -400.777013)
			(xy 56.811713 -400.724725) (xy 56.834349 -400.675154) (xy 56.863809 -400.629309) (xy 56.899494 -400.588123)
			(xy 56.940676 -400.552435) (xy 56.986518 -400.522969) (xy 57.036086 -400.500327) (xy 57.088372 -400.48497)
			(xy 57.142311 -400.477209) (xy 57.169558 -400.47672) (xy 58.033158 -400.47672) (xy 58.060415 -400.477124)
			(xy 58.114374 -400.484877) (xy 58.166681 -400.50023) (xy 58.21627 -400.522872) (xy 58.262132 -400.552341)
			(xy 58.303333 -400.588037) (xy 58.339034 -400.629234) (xy 58.368508 -400.675093) (xy 58.391155 -400.724679)
			(xy 58.406514 -400.776985) (xy 58.414273 -400.830943) (xy 58.414273 -400.885449) (xy 59.851806 -400.885449)
			(xy 59.851806 -400.830951) (xy 59.859562 -400.777007) (xy 59.874916 -400.724717) (xy 59.897555 -400.675143)
			(xy 59.927019 -400.629296) (xy 59.962708 -400.588109) (xy 60.003895 -400.55242) (xy 60.049742 -400.522956)
			(xy 60.099315 -400.500317) (xy 60.151605 -400.484963) (xy 60.205549 -400.477206) (xy 60.232798 -400.47672)
			(xy 61.096398 -400.47672) (xy 61.123653 -400.477127) (xy 61.177608 -400.484884) (xy 61.22991 -400.500241)
			(xy 61.279494 -400.522885) (xy 61.325351 -400.552355) (xy 61.366547 -400.588052) (xy 61.402243 -400.629247)
			(xy 61.431714 -400.675104) (xy 61.454358 -400.724688) (xy 61.469715 -400.77699) (xy 61.477473 -400.830945)
			(xy 61.477473 -400.885453) (xy 62.914983 -400.885453) (xy 62.914983 -400.830947) (xy 62.922741 -400.776997)
			(xy 62.938098 -400.7247) (xy 62.960741 -400.675121) (xy 62.990211 -400.629269) (xy 63.025906 -400.588079)
			(xy 63.0671 -400.552388) (xy 63.112954 -400.522923) (xy 63.162536 -400.500284) (xy 63.214834 -400.484933)
			(xy 63.268785 -400.477181) (xy 63.296038 -400.47672) (xy 64.159638 -400.47672) (xy 64.186889 -400.477152)
			(xy 64.240837 -400.484914) (xy 64.293131 -400.500273) (xy 64.342707 -400.522918) (xy 64.388556 -400.552388)
			(xy 64.429745 -400.588082) (xy 64.465435 -400.629274) (xy 64.4949 -400.675126) (xy 64.51754 -400.724705)
			(xy 64.532894 -400.777) (xy 64.54065 -400.830948) (xy 64.54065 -400.885448) (xy 65.978306 -400.885448)
			(xy 65.978306 -400.830952) (xy 65.986062 -400.77701) (xy 66.001414 -400.724721) (xy 66.024052 -400.675149)
			(xy 66.053514 -400.629303) (xy 66.089201 -400.588116) (xy 66.130385 -400.552427) (xy 66.17623 -400.522963)
			(xy 66.2258 -400.500322) (xy 66.278088 -400.484966) (xy 66.33203 -400.477208) (xy 66.359278 -400.47672)
			(xy 67.222878 -400.47672) (xy 67.250134 -400.477125) (xy 67.304091 -400.48488) (xy 67.356396 -400.500236)
			(xy 67.405982 -400.522879) (xy 67.451842 -400.552348) (xy 67.49304 -400.588045) (xy 67.528739 -400.629241)
			(xy 67.558211 -400.675098) (xy 67.580857 -400.724684) (xy 67.596215 -400.776987) (xy 67.603973 -400.830944)
			(xy 67.603973 -400.885452) (xy 69.041483 -400.885452) (xy 69.041483 -400.830948) (xy 69.04924 -400.777)
			(xy 69.064596 -400.724704) (xy 69.087238 -400.675127) (xy 69.116706 -400.629276) (xy 69.152399 -400.588086)
			(xy 69.19359 -400.552395) (xy 69.239442 -400.52293) (xy 69.289021 -400.50029) (xy 69.341317 -400.484936)
			(xy 69.395266 -400.477182) (xy 69.422518 -400.47672) (xy 70.286118 -400.47672) (xy 70.31337 -400.477151)
			(xy 70.36732 -400.48491) (xy 70.419617 -400.500268) (xy 70.469195 -400.522912) (xy 70.515047 -400.552381)
			(xy 70.556238 -400.588075) (xy 70.59193 -400.629268) (xy 70.621397 -400.675121) (xy 70.644038 -400.7247)
			(xy 70.659394 -400.776997) (xy 70.66715 -400.830948) (xy 70.66715 -400.885447) (xy 72.104806 -400.885447)
			(xy 72.104806 -400.830953) (xy 72.112561 -400.777013) (xy 72.127913 -400.724725) (xy 72.150549 -400.675154)
			(xy 72.180009 -400.629309) (xy 72.215694 -400.588123) (xy 72.256876 -400.552435) (xy 72.302718 -400.522969)
			(xy 72.352286 -400.500327) (xy 72.404572 -400.48497) (xy 72.458511 -400.477209) (xy 72.485758 -400.47672)
			(xy 73.349358 -400.47672) (xy 73.376615 -400.477124) (xy 73.430574 -400.484877) (xy 73.482881 -400.50023)
			(xy 73.53247 -400.522872) (xy 73.578332 -400.552341) (xy 73.619533 -400.588037) (xy 73.655234 -400.629234)
			(xy 73.684708 -400.675093) (xy 73.707355 -400.724679) (xy 73.722714 -400.776985) (xy 73.730473 -400.830943)
			(xy 73.730473 -400.885449) (xy 75.168006 -400.885449) (xy 75.168006 -400.830951) (xy 75.175762 -400.777007)
			(xy 75.191116 -400.724717) (xy 75.213755 -400.675143) (xy 75.243219 -400.629296) (xy 75.278908 -400.588109)
			(xy 75.320095 -400.55242) (xy 75.365942 -400.522956) (xy 75.415515 -400.500317) (xy 75.467805 -400.484963)
			(xy 75.521749 -400.477206) (xy 75.548998 -400.47672) (xy 76.412598 -400.47672) (xy 76.439853 -400.477127)
			(xy 76.493808 -400.484884) (xy 76.54611 -400.500241) (xy 76.595694 -400.522885) (xy 76.641551 -400.552355)
			(xy 76.682747 -400.588052) (xy 76.718443 -400.629247) (xy 76.747914 -400.675104) (xy 76.770558 -400.724688)
			(xy 76.785915 -400.77699) (xy 76.793673 -400.830945) (xy 76.793673 -400.885453) (xy 78.231183 -400.885453)
			(xy 78.231183 -400.830947) (xy 78.238941 -400.776997) (xy 78.254298 -400.7247) (xy 78.276941 -400.675121)
			(xy 78.306411 -400.629269) (xy 78.342106 -400.588079) (xy 78.3833 -400.552388) (xy 78.429154 -400.522923)
			(xy 78.478736 -400.500284) (xy 78.531034 -400.484933) (xy 78.584985 -400.477181) (xy 78.612238 -400.47672)
			(xy 79.475838 -400.47672) (xy 79.503089 -400.477152) (xy 79.557037 -400.484914) (xy 79.609331 -400.500273)
			(xy 79.658907 -400.522918) (xy 79.704756 -400.552388) (xy 79.745945 -400.588082) (xy 79.781635 -400.629274)
			(xy 79.8111 -400.675126) (xy 79.83374 -400.724705) (xy 79.849094 -400.777) (xy 79.85685 -400.830948)
			(xy 79.85685 -400.885448) (xy 81.294506 -400.885448) (xy 81.294506 -400.830952) (xy 81.302262 -400.77701)
			(xy 81.317614 -400.724721) (xy 81.340252 -400.675149) (xy 81.369714 -400.629303) (xy 81.405401 -400.588116)
			(xy 81.446585 -400.552427) (xy 81.49243 -400.522963) (xy 81.542 -400.500322) (xy 81.594288 -400.484966)
			(xy 81.64823 -400.477208) (xy 81.675478 -400.47672) (xy 82.539078 -400.47672) (xy 82.566334 -400.477125)
			(xy 82.620291 -400.48488) (xy 82.672596 -400.500236) (xy 82.722182 -400.522879) (xy 82.768042 -400.552348)
			(xy 82.80924 -400.588045) (xy 82.844939 -400.629241) (xy 82.874411 -400.675098) (xy 82.897057 -400.724684)
			(xy 82.912415 -400.776987) (xy 82.920173 -400.830944) (xy 82.920173 -400.885452) (xy 84.357683 -400.885452)
			(xy 84.357683 -400.830948) (xy 84.36544 -400.777) (xy 84.380796 -400.724704) (xy 84.403438 -400.675127)
			(xy 84.432906 -400.629276) (xy 84.468599 -400.588086) (xy 84.50979 -400.552395) (xy 84.555642 -400.52293)
			(xy 84.605221 -400.50029) (xy 84.657517 -400.484936) (xy 84.711466 -400.477182) (xy 84.738718 -400.47672)
			(xy 85.602318 -400.47672) (xy 85.62957 -400.477151) (xy 85.68352 -400.48491) (xy 85.735817 -400.500268)
			(xy 85.785395 -400.522912) (xy 85.831247 -400.552381) (xy 85.872438 -400.588075) (xy 85.90813 -400.629268)
			(xy 85.937597 -400.675121) (xy 85.960238 -400.7247) (xy 85.975594 -400.776997) (xy 85.98335 -400.830948)
			(xy 85.98335 -400.885447) (xy 87.421006 -400.885447) (xy 87.421006 -400.830953) (xy 87.428761 -400.777013)
			(xy 87.444113 -400.724725) (xy 87.466749 -400.675154) (xy 87.496209 -400.629309) (xy 87.531894 -400.588123)
			(xy 87.573076 -400.552435) (xy 87.618918 -400.522969) (xy 87.668486 -400.500327) (xy 87.720772 -400.48497)
			(xy 87.774711 -400.477209) (xy 87.801958 -400.47672) (xy 88.665558 -400.47672) (xy 88.692815 -400.477124)
			(xy 88.746774 -400.484877) (xy 88.799081 -400.50023) (xy 88.84867 -400.522872) (xy 88.894532 -400.552341)
			(xy 88.935733 -400.588037) (xy 88.971434 -400.629234) (xy 89.000908 -400.675093) (xy 89.023555 -400.724679)
			(xy 89.038914 -400.776985) (xy 89.046673 -400.830943) (xy 89.046673 -400.885449) (xy 90.484206 -400.885449)
			(xy 90.484206 -400.830951) (xy 90.491962 -400.777007) (xy 90.507316 -400.724717) (xy 90.529955 -400.675143)
			(xy 90.559419 -400.629296) (xy 90.595108 -400.588109) (xy 90.636295 -400.55242) (xy 90.682142 -400.522956)
			(xy 90.731715 -400.500317) (xy 90.784005 -400.484963) (xy 90.837949 -400.477206) (xy 90.865198 -400.47672)
			(xy 91.728798 -400.47672) (xy 91.756053 -400.477127) (xy 91.810008 -400.484884) (xy 91.86231 -400.500241)
			(xy 91.911894 -400.522885) (xy 91.957751 -400.552355) (xy 91.998947 -400.588052) (xy 92.034643 -400.629247)
			(xy 92.064114 -400.675104) (xy 92.086758 -400.724688) (xy 92.102115 -400.77699) (xy 92.109873 -400.830945)
			(xy 92.109873 -400.885453) (xy 93.547383 -400.885453) (xy 93.547383 -400.830947) (xy 93.555141 -400.776997)
			(xy 93.570498 -400.7247) (xy 93.593141 -400.675121) (xy 93.622611 -400.629269) (xy 93.658306 -400.588079)
			(xy 93.6995 -400.552388) (xy 93.745354 -400.522923) (xy 93.794936 -400.500284) (xy 93.847234 -400.484933)
			(xy 93.901185 -400.477181) (xy 93.928438 -400.47672) (xy 94.792038 -400.47672) (xy 94.819289 -400.477152)
			(xy 94.873237 -400.484914) (xy 94.925531 -400.500273) (xy 94.975107 -400.522918) (xy 95.020956 -400.552388)
			(xy 95.062145 -400.588082) (xy 95.097835 -400.629274) (xy 95.1273 -400.675126) (xy 95.14994 -400.724705)
			(xy 95.165294 -400.777) (xy 95.17305 -400.830948) (xy 95.17305 -400.885447) (xy 119.774006 -400.885447)
			(xy 119.774006 -400.830953) (xy 119.781761 -400.777013) (xy 119.797112 -400.724726) (xy 119.819749 -400.675156)
			(xy 119.849208 -400.629311) (xy 119.884892 -400.588125) (xy 119.926074 -400.552436) (xy 119.971915 -400.522971)
			(xy 120.021483 -400.500329) (xy 120.073768 -400.484971) (xy 120.127707 -400.477209) (xy 120.154954 -400.47672)
			(xy 121.018554 -400.47672) (xy 121.045811 -400.477124) (xy 121.099771 -400.484876) (xy 121.152078 -400.500229)
			(xy 121.201668 -400.522871) (xy 121.24753 -400.55234) (xy 121.288731 -400.588036) (xy 121.324433 -400.629233)
			(xy 121.353907 -400.675092) (xy 121.376555 -400.724679) (xy 121.391914 -400.776984) (xy 121.399673 -400.830943)
			(xy 121.399673 -400.885449) (xy 122.837206 -400.885449) (xy 122.837206 -400.830951) (xy 122.844962 -400.777008)
			(xy 122.860316 -400.724717) (xy 122.882955 -400.675144) (xy 122.912418 -400.629298) (xy 122.948106 -400.588111)
			(xy 122.989293 -400.552422) (xy 123.035139 -400.522958) (xy 123.084712 -400.500318) (xy 123.137002 -400.484963)
			(xy 123.190945 -400.477207) (xy 123.218194 -400.47672) (xy 124.081794 -400.47672) (xy 124.109049 -400.477127)
			(xy 124.163005 -400.484883) (xy 124.215307 -400.50024) (xy 124.264892 -400.522884) (xy 124.310749 -400.552354)
			(xy 124.351946 -400.58805) (xy 124.387643 -400.629246) (xy 124.417113 -400.675103) (xy 124.439758 -400.724687)
			(xy 124.455115 -400.776989) (xy 124.462873 -400.830945) (xy 124.462873 -400.885452) (xy 125.900383 -400.885452)
			(xy 125.900383 -400.830948) (xy 125.908141 -400.776998) (xy 125.923497 -400.724701) (xy 125.946141 -400.675122)
			(xy 125.97561 -400.629271) (xy 126.011304 -400.58808) (xy 126.052498 -400.552389) (xy 126.098352 -400.522924)
			(xy 126.147933 -400.500285) (xy 126.200231 -400.484933) (xy 126.254182 -400.477181) (xy 126.281434 -400.47672)
			(xy 127.145034 -400.47672) (xy 127.172286 -400.477152) (xy 127.226234 -400.484913) (xy 127.278528 -400.500272)
			(xy 127.328105 -400.522917) (xy 127.373954 -400.552386) (xy 127.415143 -400.588081) (xy 127.450834 -400.629273)
			(xy 127.480299 -400.675125) (xy 127.50294 -400.724704) (xy 127.518294 -400.777) (xy 127.52605 -400.830948)
			(xy 127.52605 -400.885448) (xy 128.963706 -400.885448) (xy 128.963706 -400.830952) (xy 128.971461 -400.777011)
			(xy 128.986814 -400.724722) (xy 129.009452 -400.67515) (xy 129.038913 -400.629304) (xy 129.074599 -400.588118)
			(xy 129.115783 -400.552429) (xy 129.161627 -400.522964) (xy 129.211197 -400.500323) (xy 129.263485 -400.484967)
			(xy 129.317426 -400.477208) (xy 129.344674 -400.47672) (xy 130.208274 -400.47672) (xy 130.23553 -400.477125)
			(xy 130.289488 -400.48488) (xy 130.341793 -400.500235) (xy 130.39138 -400.522877) (xy 130.43724 -400.552347)
			(xy 130.478438 -400.588043) (xy 130.514138 -400.62924) (xy 130.54361 -400.675097) (xy 130.566256 -400.724683)
			(xy 130.581615 -400.776987) (xy 130.589373 -400.830944) (xy 130.589373 -400.885451) (xy 132.026883 -400.885451)
			(xy 132.026883 -400.830949) (xy 132.03464 -400.777) (xy 132.049996 -400.724705) (xy 132.072638 -400.675128)
			(xy 132.102105 -400.629277) (xy 132.137797 -400.588087) (xy 132.178989 -400.552396) (xy 132.22484 -400.522931)
			(xy 132.274418 -400.500291) (xy 132.326714 -400.484937) (xy 132.380662 -400.477182) (xy 132.407914 -400.47672)
			(xy 133.271514 -400.47672) (xy 133.298767 -400.477151) (xy 133.352717 -400.48491) (xy 133.405014 -400.500267)
			(xy 133.454593 -400.522911) (xy 133.500445 -400.552379) (xy 133.541636 -400.588074) (xy 133.577329 -400.629266)
			(xy 133.606796 -400.67512) (xy 133.629438 -400.724699) (xy 133.644793 -400.776997) (xy 133.65255 -400.830947)
			(xy 133.65255 -400.885447) (xy 135.090206 -400.885447) (xy 135.090206 -400.830953) (xy 135.097961 -400.777013)
			(xy 135.113312 -400.724726) (xy 135.135949 -400.675156) (xy 135.165408 -400.629311) (xy 135.201092 -400.588125)
			(xy 135.242274 -400.552436) (xy 135.288115 -400.522971) (xy 135.337683 -400.500329) (xy 135.389968 -400.484971)
			(xy 135.443907 -400.477209) (xy 135.471154 -400.47672) (xy 136.334754 -400.47672) (xy 136.362011 -400.477124)
			(xy 136.415971 -400.484876) (xy 136.468278 -400.500229) (xy 136.517868 -400.522871) (xy 136.56373 -400.55234)
			(xy 136.604931 -400.588036) (xy 136.640633 -400.629233) (xy 136.670107 -400.675092) (xy 136.692755 -400.724679)
			(xy 136.708114 -400.776984) (xy 136.715873 -400.830943) (xy 136.715873 -400.885449) (xy 138.153406 -400.885449)
			(xy 138.153406 -400.830951) (xy 138.161162 -400.777008) (xy 138.176516 -400.724717) (xy 138.199155 -400.675144)
			(xy 138.228618 -400.629298) (xy 138.264306 -400.588111) (xy 138.305493 -400.552422) (xy 138.351339 -400.522958)
			(xy 138.400912 -400.500318) (xy 138.453202 -400.484963) (xy 138.507145 -400.477207) (xy 138.534394 -400.47672)
			(xy 139.397994 -400.47672) (xy 139.425249 -400.477127) (xy 139.479205 -400.484883) (xy 139.531507 -400.50024)
			(xy 139.581092 -400.522884) (xy 139.626949 -400.552354) (xy 139.668146 -400.58805) (xy 139.703843 -400.629246)
			(xy 139.733313 -400.675103) (xy 139.755958 -400.724687) (xy 139.771315 -400.776989) (xy 139.779073 -400.830945)
			(xy 139.779073 -400.885452) (xy 141.216583 -400.885452) (xy 141.216583 -400.830948) (xy 141.224341 -400.776998)
			(xy 141.239697 -400.724701) (xy 141.262341 -400.675122) (xy 141.29181 -400.629271) (xy 141.327504 -400.58808)
			(xy 141.368698 -400.552389) (xy 141.414552 -400.522924) (xy 141.464133 -400.500285) (xy 141.516431 -400.484933)
			(xy 141.570382 -400.477181) (xy 141.597634 -400.47672) (xy 142.461234 -400.47672) (xy 142.488486 -400.477152)
			(xy 142.542434 -400.484913) (xy 142.594728 -400.500272) (xy 142.644305 -400.522917) (xy 142.690154 -400.552386)
			(xy 142.731343 -400.588081) (xy 142.767034 -400.629273) (xy 142.796499 -400.675125) (xy 142.81914 -400.724704)
			(xy 142.834494 -400.777) (xy 142.84225 -400.830948) (xy 142.84225 -400.885448) (xy 144.279906 -400.885448)
			(xy 144.279906 -400.830952) (xy 144.287661 -400.777011) (xy 144.303014 -400.724722) (xy 144.325652 -400.67515)
			(xy 144.355113 -400.629304) (xy 144.390799 -400.588118) (xy 144.431983 -400.552429) (xy 144.477827 -400.522964)
			(xy 144.527397 -400.500323) (xy 144.579685 -400.484967) (xy 144.633626 -400.477208) (xy 144.660874 -400.47672)
			(xy 145.524474 -400.47672) (xy 145.55173 -400.477125) (xy 145.605688 -400.48488) (xy 145.657993 -400.500235)
			(xy 145.70758 -400.522877) (xy 145.75344 -400.552347) (xy 145.794638 -400.588043) (xy 145.830338 -400.62924)
			(xy 145.85981 -400.675097) (xy 145.882456 -400.724683) (xy 145.897815 -400.776987) (xy 145.905573 -400.830944)
			(xy 145.905573 -400.885451) (xy 147.343083 -400.885451) (xy 147.343083 -400.830949) (xy 147.35084 -400.777)
			(xy 147.366196 -400.724705) (xy 147.388838 -400.675128) (xy 147.418305 -400.629277) (xy 147.453997 -400.588087)
			(xy 147.495189 -400.552396) (xy 147.54104 -400.522931) (xy 147.590618 -400.500291) (xy 147.642914 -400.484937)
			(xy 147.696862 -400.477182) (xy 147.724114 -400.47672) (xy 148.587714 -400.47672) (xy 148.614967 -400.477151)
			(xy 148.668917 -400.48491) (xy 148.721214 -400.500267) (xy 148.770793 -400.522911) (xy 148.816645 -400.552379)
			(xy 148.857836 -400.588074) (xy 148.893529 -400.629266) (xy 148.922996 -400.67512) (xy 148.945638 -400.724699)
			(xy 148.960993 -400.776997) (xy 148.96875 -400.830947) (xy 148.96875 -400.885447) (xy 150.406406 -400.885447)
			(xy 150.406406 -400.830953) (xy 150.414161 -400.777013) (xy 150.429512 -400.724726) (xy 150.452149 -400.675156)
			(xy 150.481608 -400.629311) (xy 150.517292 -400.588125) (xy 150.558474 -400.552436) (xy 150.604315 -400.522971)
			(xy 150.653883 -400.500329) (xy 150.706168 -400.484971) (xy 150.760107 -400.477209) (xy 150.787354 -400.47672)
			(xy 151.650954 -400.47672) (xy 151.678211 -400.477124) (xy 151.732171 -400.484876) (xy 151.784478 -400.500229)
			(xy 151.834068 -400.522871) (xy 151.87993 -400.55234) (xy 151.921131 -400.588036) (xy 151.956833 -400.629233)
			(xy 151.986307 -400.675092) (xy 152.008955 -400.724679) (xy 152.024314 -400.776984) (xy 152.032073 -400.830943)
			(xy 152.032073 -400.885449) (xy 153.469606 -400.885449) (xy 153.469606 -400.830951) (xy 153.477362 -400.777008)
			(xy 153.492716 -400.724717) (xy 153.515355 -400.675144) (xy 153.544818 -400.629298) (xy 153.580506 -400.588111)
			(xy 153.621693 -400.552422) (xy 153.667539 -400.522958) (xy 153.717112 -400.500318) (xy 153.769402 -400.484963)
			(xy 153.823345 -400.477207) (xy 153.850594 -400.47672) (xy 154.714194 -400.47672) (xy 154.741449 -400.477127)
			(xy 154.795405 -400.484883) (xy 154.847707 -400.50024) (xy 154.897292 -400.522884) (xy 154.943149 -400.552354)
			(xy 154.984346 -400.58805) (xy 155.020043 -400.629246) (xy 155.049513 -400.675103) (xy 155.072158 -400.724687)
			(xy 155.087515 -400.776989) (xy 155.095273 -400.830945) (xy 155.095273 -400.885452) (xy 156.532783 -400.885452)
			(xy 156.532783 -400.830948) (xy 156.540541 -400.776998) (xy 156.555897 -400.724701) (xy 156.578541 -400.675122)
			(xy 156.60801 -400.629271) (xy 156.643704 -400.58808) (xy 156.684898 -400.552389) (xy 156.730752 -400.522924)
			(xy 156.780333 -400.500285) (xy 156.832631 -400.484933) (xy 156.886582 -400.477181) (xy 156.913834 -400.47672)
			(xy 157.777434 -400.47672) (xy 157.804686 -400.477152) (xy 157.858634 -400.484913) (xy 157.910928 -400.500272)
			(xy 157.960505 -400.522917) (xy 158.006354 -400.552386) (xy 158.047543 -400.588081) (xy 158.083234 -400.629273)
			(xy 158.112699 -400.675125) (xy 158.13534 -400.724704) (xy 158.150694 -400.777) (xy 158.15845 -400.830948)
			(xy 158.15845 -400.885448) (xy 159.596106 -400.885448) (xy 159.596106 -400.830952) (xy 159.603861 -400.777011)
			(xy 159.619214 -400.724722) (xy 159.641852 -400.67515) (xy 159.671313 -400.629304) (xy 159.706999 -400.588118)
			(xy 159.748183 -400.552429) (xy 159.794027 -400.522964) (xy 159.843597 -400.500323) (xy 159.895885 -400.484967)
			(xy 159.949826 -400.477208) (xy 159.977074 -400.47672) (xy 160.840674 -400.47672) (xy 160.86793 -400.477125)
			(xy 160.921888 -400.48488) (xy 160.974193 -400.500235) (xy 161.02378 -400.522877) (xy 161.06964 -400.552347)
			(xy 161.110838 -400.588043) (xy 161.146538 -400.62924) (xy 161.17601 -400.675097) (xy 161.198656 -400.724683)
			(xy 161.214015 -400.776987) (xy 161.221773 -400.830944) (xy 161.221773 -400.885451) (xy 162.659283 -400.885451)
			(xy 162.659283 -400.830949) (xy 162.66704 -400.777) (xy 162.682396 -400.724705) (xy 162.705038 -400.675128)
			(xy 162.734505 -400.629277) (xy 162.770197 -400.588087) (xy 162.811389 -400.552396) (xy 162.85724 -400.522931)
			(xy 162.906818 -400.500291) (xy 162.959114 -400.484937) (xy 163.013062 -400.477182) (xy 163.040314 -400.47672)
			(xy 163.903914 -400.47672) (xy 163.931167 -400.477151) (xy 163.985117 -400.48491) (xy 164.037414 -400.500267)
			(xy 164.086993 -400.522911) (xy 164.132845 -400.552379) (xy 164.174036 -400.588074) (xy 164.209729 -400.629266)
			(xy 164.239196 -400.67512) (xy 164.261838 -400.724699) (xy 164.277193 -400.776997) (xy 164.28495 -400.830947)
			(xy 164.28495 -400.885447) (xy 165.722606 -400.885447) (xy 165.722606 -400.830953) (xy 165.730361 -400.777013)
			(xy 165.745712 -400.724726) (xy 165.768349 -400.675156) (xy 165.797808 -400.629311) (xy 165.833492 -400.588125)
			(xy 165.874674 -400.552436) (xy 165.920515 -400.522971) (xy 165.970083 -400.500329) (xy 166.022368 -400.484971)
			(xy 166.076307 -400.477209) (xy 166.103554 -400.47672) (xy 166.967154 -400.47672) (xy 166.994411 -400.477124)
			(xy 167.048371 -400.484876) (xy 167.100678 -400.500229) (xy 167.150268 -400.522871) (xy 167.19613 -400.55234)
			(xy 167.237331 -400.588036) (xy 167.273033 -400.629233) (xy 167.302507 -400.675092) (xy 167.325155 -400.724679)
			(xy 167.340514 -400.776984) (xy 167.348273 -400.830943) (xy 167.348273 -400.885457) (xy 167.340514 -400.939416)
			(xy 167.325155 -400.991721) (xy 167.302507 -401.041308) (xy 167.273033 -401.087167) (xy 167.237331 -401.128364)
			(xy 167.19613 -401.16406) (xy 167.150268 -401.193529) (xy 167.100678 -401.216171) (xy 167.048371 -401.231524)
			(xy 166.994411 -401.239276) (xy 166.967154 -401.239736) (xy 166.103554 -401.239736) (xy 166.076307 -401.239191)
			(xy 166.022368 -401.231429) (xy 165.970083 -401.216071) (xy 165.920515 -401.193429) (xy 165.874674 -401.163964)
			(xy 165.833492 -401.128275) (xy 165.797808 -401.087089) (xy 165.768349 -401.041244) (xy 165.745712 -400.991674)
			(xy 165.730361 -400.939387) (xy 165.722606 -400.885447) (xy 164.28495 -400.885447) (xy 164.28495 -400.885453)
			(xy 164.277193 -400.939403) (xy 164.261838 -400.991701) (xy 164.239196 -401.04128) (xy 164.209729 -401.087134)
			(xy 164.174036 -401.128326) (xy 164.132845 -401.164021) (xy 164.086993 -401.193489) (xy 164.037414 -401.216133)
			(xy 163.985117 -401.23149) (xy 163.931167 -401.239249) (xy 163.903914 -401.239736) (xy 163.040314 -401.239736)
			(xy 163.013062 -401.239218) (xy 162.959114 -401.231463) (xy 162.906818 -401.216109) (xy 162.85724 -401.193469)
			(xy 162.811389 -401.164004) (xy 162.770197 -401.128313) (xy 162.734505 -401.087123) (xy 162.705038 -401.041272)
			(xy 162.682396 -400.991695) (xy 162.66704 -400.9394) (xy 162.659283 -400.885451) (xy 161.221773 -400.885451)
			(xy 161.221773 -400.885456) (xy 161.214015 -400.939413) (xy 161.198656 -400.991717) (xy 161.17601 -401.041303)
			(xy 161.146538 -401.08716) (xy 161.110838 -401.128357) (xy 161.06964 -401.164053) (xy 161.02378 -401.193523)
			(xy 160.974193 -401.216165) (xy 160.921888 -401.23152) (xy 160.86793 -401.239275) (xy 160.840674 -401.239736)
			(xy 159.977074 -401.239736) (xy 159.949826 -401.239192) (xy 159.895885 -401.231433) (xy 159.843597 -401.216077)
			(xy 159.794027 -401.193436) (xy 159.748183 -401.163971) (xy 159.706999 -401.128282) (xy 159.671313 -401.087096)
			(xy 159.641852 -401.04125) (xy 159.619214 -400.991678) (xy 159.603861 -400.939389) (xy 159.596106 -400.885448)
			(xy 158.15845 -400.885448) (xy 158.15845 -400.885452) (xy 158.150694 -400.9394) (xy 158.13534 -400.991696)
			(xy 158.112699 -401.041275) (xy 158.083234 -401.087127) (xy 158.047543 -401.128319) (xy 158.006354 -401.164014)
			(xy 157.960505 -401.193483) (xy 157.910928 -401.216128) (xy 157.858634 -401.231487) (xy 157.804686 -401.239248)
			(xy 157.777434 -401.239736) (xy 156.913834 -401.239736) (xy 156.886582 -401.239219) (xy 156.832631 -401.231467)
			(xy 156.780333 -401.216115) (xy 156.730752 -401.193476) (xy 156.684898 -401.164011) (xy 156.643704 -401.12832)
			(xy 156.60801 -401.087129) (xy 156.578541 -401.041278) (xy 156.555897 -400.991699) (xy 156.540541 -400.939402)
			(xy 156.532783 -400.885452) (xy 155.095273 -400.885452) (xy 155.095273 -400.885455) (xy 155.087515 -400.939411)
			(xy 155.072158 -400.991713) (xy 155.049513 -401.041297) (xy 155.020043 -401.087154) (xy 154.984346 -401.12835)
			(xy 154.943149 -401.164046) (xy 154.897292 -401.193516) (xy 154.847707 -401.21616) (xy 154.795405 -401.231517)
			(xy 154.741449 -401.239273) (xy 154.714194 -401.239736) (xy 153.850594 -401.239736) (xy 153.823345 -401.239193)
			(xy 153.769402 -401.231437) (xy 153.717112 -401.216082) (xy 153.667539 -401.193442) (xy 153.621693 -401.163978)
			(xy 153.580506 -401.128289) (xy 153.544818 -401.087102) (xy 153.515355 -401.041256) (xy 153.492716 -400.991683)
			(xy 153.477362 -400.939392) (xy 153.469606 -400.885449) (xy 152.032073 -400.885449) (xy 152.032073 -400.885457)
			(xy 152.024314 -400.939416) (xy 152.008955 -400.991721) (xy 151.986307 -401.041308) (xy 151.956833 -401.087167)
			(xy 151.921131 -401.128364) (xy 151.87993 -401.16406) (xy 151.834068 -401.193529) (xy 151.784478 -401.216171)
			(xy 151.732171 -401.231524) (xy 151.678211 -401.239276) (xy 151.650954 -401.239736) (xy 150.787354 -401.239736)
			(xy 150.760107 -401.239191) (xy 150.706168 -401.231429) (xy 150.653883 -401.216071) (xy 150.604315 -401.193429)
			(xy 150.558474 -401.163964) (xy 150.517292 -401.128275) (xy 150.481608 -401.087089) (xy 150.452149 -401.041244)
			(xy 150.429512 -400.991674) (xy 150.414161 -400.939387) (xy 150.406406 -400.885447) (xy 148.96875 -400.885447)
			(xy 148.96875 -400.885453) (xy 148.960993 -400.939403) (xy 148.945638 -400.991701) (xy 148.922996 -401.04128)
			(xy 148.893529 -401.087134) (xy 148.857836 -401.128326) (xy 148.816645 -401.164021) (xy 148.770793 -401.193489)
			(xy 148.721214 -401.216133) (xy 148.668917 -401.23149) (xy 148.614967 -401.239249) (xy 148.587714 -401.239736)
			(xy 147.724114 -401.239736) (xy 147.696862 -401.239218) (xy 147.642914 -401.231463) (xy 147.590618 -401.216109)
			(xy 147.54104 -401.193469) (xy 147.495189 -401.164004) (xy 147.453997 -401.128313) (xy 147.418305 -401.087123)
			(xy 147.388838 -401.041272) (xy 147.366196 -400.991695) (xy 147.35084 -400.9394) (xy 147.343083 -400.885451)
			(xy 145.905573 -400.885451) (xy 145.905573 -400.885456) (xy 145.897815 -400.939413) (xy 145.882456 -400.991717)
			(xy 145.85981 -401.041303) (xy 145.830338 -401.08716) (xy 145.794638 -401.128357) (xy 145.75344 -401.164053)
			(xy 145.70758 -401.193523) (xy 145.657993 -401.216165) (xy 145.605688 -401.23152) (xy 145.55173 -401.239275)
			(xy 145.524474 -401.239736) (xy 144.660874 -401.239736) (xy 144.633626 -401.239192) (xy 144.579685 -401.231433)
			(xy 144.527397 -401.216077) (xy 144.477827 -401.193436) (xy 144.431983 -401.163971) (xy 144.390799 -401.128282)
			(xy 144.355113 -401.087096) (xy 144.325652 -401.04125) (xy 144.303014 -400.991678) (xy 144.287661 -400.939389)
			(xy 144.279906 -400.885448) (xy 142.84225 -400.885448) (xy 142.84225 -400.885452) (xy 142.834494 -400.9394)
			(xy 142.81914 -400.991696) (xy 142.796499 -401.041275) (xy 142.767034 -401.087127) (xy 142.731343 -401.128319)
			(xy 142.690154 -401.164014) (xy 142.644305 -401.193483) (xy 142.594728 -401.216128) (xy 142.542434 -401.231487)
			(xy 142.488486 -401.239248) (xy 142.461234 -401.239736) (xy 141.597634 -401.239736) (xy 141.570382 -401.239219)
			(xy 141.516431 -401.231467) (xy 141.464133 -401.216115) (xy 141.414552 -401.193476) (xy 141.368698 -401.164011)
			(xy 141.327504 -401.12832) (xy 141.29181 -401.087129) (xy 141.262341 -401.041278) (xy 141.239697 -400.991699)
			(xy 141.224341 -400.939402) (xy 141.216583 -400.885452) (xy 139.779073 -400.885452) (xy 139.779073 -400.885455)
			(xy 139.771315 -400.939411) (xy 139.755958 -400.991713) (xy 139.733313 -401.041297) (xy 139.703843 -401.087154)
			(xy 139.668146 -401.12835) (xy 139.626949 -401.164046) (xy 139.581092 -401.193516) (xy 139.531507 -401.21616)
			(xy 139.479205 -401.231517) (xy 139.425249 -401.239273) (xy 139.397994 -401.239736) (xy 138.534394 -401.239736)
			(xy 138.507145 -401.239193) (xy 138.453202 -401.231437) (xy 138.400912 -401.216082) (xy 138.351339 -401.193442)
			(xy 138.305493 -401.163978) (xy 138.264306 -401.128289) (xy 138.228618 -401.087102) (xy 138.199155 -401.041256)
			(xy 138.176516 -400.991683) (xy 138.161162 -400.939392) (xy 138.153406 -400.885449) (xy 136.715873 -400.885449)
			(xy 136.715873 -400.885457) (xy 136.708114 -400.939416) (xy 136.692755 -400.991721) (xy 136.670107 -401.041308)
			(xy 136.640633 -401.087167) (xy 136.604931 -401.128364) (xy 136.56373 -401.16406) (xy 136.517868 -401.193529)
			(xy 136.468278 -401.216171) (xy 136.415971 -401.231524) (xy 136.362011 -401.239276) (xy 136.334754 -401.239736)
			(xy 135.471154 -401.239736) (xy 135.443907 -401.239191) (xy 135.389968 -401.231429) (xy 135.337683 -401.216071)
			(xy 135.288115 -401.193429) (xy 135.242274 -401.163964) (xy 135.201092 -401.128275) (xy 135.165408 -401.087089)
			(xy 135.135949 -401.041244) (xy 135.113312 -400.991674) (xy 135.097961 -400.939387) (xy 135.090206 -400.885447)
			(xy 133.65255 -400.885447) (xy 133.65255 -400.885453) (xy 133.644793 -400.939403) (xy 133.629438 -400.991701)
			(xy 133.606796 -401.04128) (xy 133.577329 -401.087134) (xy 133.541636 -401.128326) (xy 133.500445 -401.164021)
			(xy 133.454593 -401.193489) (xy 133.405014 -401.216133) (xy 133.352717 -401.23149) (xy 133.298767 -401.239249)
			(xy 133.271514 -401.239736) (xy 132.407914 -401.239736) (xy 132.380662 -401.239218) (xy 132.326714 -401.231463)
			(xy 132.274418 -401.216109) (xy 132.22484 -401.193469) (xy 132.178989 -401.164004) (xy 132.137797 -401.128313)
			(xy 132.102105 -401.087123) (xy 132.072638 -401.041272) (xy 132.049996 -400.991695) (xy 132.03464 -400.9394)
			(xy 132.026883 -400.885451) (xy 130.589373 -400.885451) (xy 130.589373 -400.885456) (xy 130.581615 -400.939413)
			(xy 130.566256 -400.991717) (xy 130.54361 -401.041303) (xy 130.514138 -401.08716) (xy 130.478438 -401.128357)
			(xy 130.43724 -401.164053) (xy 130.39138 -401.193523) (xy 130.341793 -401.216165) (xy 130.289488 -401.23152)
			(xy 130.23553 -401.239275) (xy 130.208274 -401.239736) (xy 129.344674 -401.239736) (xy 129.317426 -401.239192)
			(xy 129.263485 -401.231433) (xy 129.211197 -401.216077) (xy 129.161627 -401.193436) (xy 129.115783 -401.163971)
			(xy 129.074599 -401.128282) (xy 129.038913 -401.087096) (xy 129.009452 -401.04125) (xy 128.986814 -400.991678)
			(xy 128.971461 -400.939389) (xy 128.963706 -400.885448) (xy 127.52605 -400.885448) (xy 127.52605 -400.885452)
			(xy 127.518294 -400.9394) (xy 127.50294 -400.991696) (xy 127.480299 -401.041275) (xy 127.450834 -401.087127)
			(xy 127.415143 -401.128319) (xy 127.373954 -401.164014) (xy 127.328105 -401.193483) (xy 127.278528 -401.216128)
			(xy 127.226234 -401.231487) (xy 127.172286 -401.239248) (xy 127.145034 -401.239736) (xy 126.281434 -401.239736)
			(xy 126.254182 -401.239219) (xy 126.200231 -401.231467) (xy 126.147933 -401.216115) (xy 126.098352 -401.193476)
			(xy 126.052498 -401.164011) (xy 126.011304 -401.12832) (xy 125.97561 -401.087129) (xy 125.946141 -401.041278)
			(xy 125.923497 -400.991699) (xy 125.908141 -400.939402) (xy 125.900383 -400.885452) (xy 124.462873 -400.885452)
			(xy 124.462873 -400.885455) (xy 124.455115 -400.939411) (xy 124.439758 -400.991713) (xy 124.417113 -401.041297)
			(xy 124.387643 -401.087154) (xy 124.351946 -401.12835) (xy 124.310749 -401.164046) (xy 124.264892 -401.193516)
			(xy 124.215307 -401.21616) (xy 124.163005 -401.231517) (xy 124.109049 -401.239273) (xy 124.081794 -401.239736)
			(xy 123.218194 -401.239736) (xy 123.190945 -401.239193) (xy 123.137002 -401.231437) (xy 123.084712 -401.216082)
			(xy 123.035139 -401.193442) (xy 122.989293 -401.163978) (xy 122.948106 -401.128289) (xy 122.912418 -401.087102)
			(xy 122.882955 -401.041256) (xy 122.860316 -400.991683) (xy 122.844962 -400.939392) (xy 122.837206 -400.885449)
			(xy 121.399673 -400.885449) (xy 121.399673 -400.885457) (xy 121.391914 -400.939416) (xy 121.376555 -400.991721)
			(xy 121.353907 -401.041308) (xy 121.324433 -401.087167) (xy 121.288731 -401.128364) (xy 121.24753 -401.16406)
			(xy 121.201668 -401.193529) (xy 121.152078 -401.216171) (xy 121.099771 -401.231524) (xy 121.045811 -401.239276)
			(xy 121.018554 -401.239736) (xy 120.154954 -401.239736) (xy 120.127707 -401.239191) (xy 120.073768 -401.231429)
			(xy 120.021483 -401.216071) (xy 119.971915 -401.193429) (xy 119.926074 -401.163964) (xy 119.884892 -401.128275)
			(xy 119.849208 -401.087089) (xy 119.819749 -401.041244) (xy 119.797112 -400.991674) (xy 119.781761 -400.939387)
			(xy 119.774006 -400.885447) (xy 95.17305 -400.885447) (xy 95.17305 -400.885452) (xy 95.165294 -400.9394)
			(xy 95.14994 -400.991695) (xy 95.1273 -401.041274) (xy 95.097835 -401.087126) (xy 95.062145 -401.128318)
			(xy 95.020956 -401.164012) (xy 94.975107 -401.193482) (xy 94.925531 -401.216127) (xy 94.873237 -401.231486)
			(xy 94.819289 -401.239248) (xy 94.792038 -401.239736) (xy 93.928438 -401.239736) (xy 93.901185 -401.239219)
			(xy 93.847234 -401.231467) (xy 93.794936 -401.216116) (xy 93.745354 -401.193477) (xy 93.6995 -401.164012)
			(xy 93.658306 -401.128321) (xy 93.622611 -401.087131) (xy 93.593141 -401.041279) (xy 93.570498 -400.9917)
			(xy 93.555141 -400.939403) (xy 93.547383 -400.885453) (xy 92.109873 -400.885453) (xy 92.109873 -400.885455)
			(xy 92.102115 -400.93941) (xy 92.086758 -400.991712) (xy 92.064114 -401.041296) (xy 92.034643 -401.087153)
			(xy 91.998947 -401.128348) (xy 91.957751 -401.164045) (xy 91.911894 -401.193515) (xy 91.86231 -401.216159)
			(xy 91.810008 -401.231516) (xy 91.756053 -401.239273) (xy 91.728798 -401.239736) (xy 90.865198 -401.239736)
			(xy 90.837949 -401.239194) (xy 90.784005 -401.231437) (xy 90.731715 -401.216083) (xy 90.682142 -401.193444)
			(xy 90.636295 -401.16398) (xy 90.595108 -401.128291) (xy 90.559419 -401.087104) (xy 90.529955 -401.041257)
			(xy 90.507316 -400.991683) (xy 90.491962 -400.939393) (xy 90.484206 -400.885449) (xy 89.046673 -400.885449)
			(xy 89.046673 -400.885457) (xy 89.038914 -400.939415) (xy 89.023555 -400.991721) (xy 89.000908 -401.041307)
			(xy 88.971434 -401.087166) (xy 88.935733 -401.128363) (xy 88.894532 -401.164059) (xy 88.84867 -401.193528)
			(xy 88.799081 -401.21617) (xy 88.746774 -401.231523) (xy 88.692815 -401.239276) (xy 88.665558 -401.239736)
			(xy 87.801958 -401.239736) (xy 87.774711 -401.239191) (xy 87.720772 -401.23143) (xy 87.668486 -401.216073)
			(xy 87.618918 -401.193431) (xy 87.573076 -401.163965) (xy 87.531894 -401.128277) (xy 87.496209 -401.087091)
			(xy 87.466749 -401.041246) (xy 87.444113 -400.991675) (xy 87.428761 -400.939387) (xy 87.421006 -400.885447)
			(xy 85.98335 -400.885447) (xy 85.98335 -400.885452) (xy 85.975594 -400.939403) (xy 85.960238 -400.9917)
			(xy 85.937597 -401.041279) (xy 85.90813 -401.087132) (xy 85.872438 -401.128325) (xy 85.831247 -401.164019)
			(xy 85.785395 -401.193488) (xy 85.735817 -401.216132) (xy 85.68352 -401.23149) (xy 85.62957 -401.239249)
			(xy 85.602318 -401.239736) (xy 84.738718 -401.239736) (xy 84.711466 -401.239218) (xy 84.657517 -401.231464)
			(xy 84.605221 -401.21611) (xy 84.555642 -401.19347) (xy 84.50979 -401.164005) (xy 84.468599 -401.128314)
			(xy 84.432906 -401.087124) (xy 84.403438 -401.041273) (xy 84.380796 -400.991696) (xy 84.36544 -400.9394)
			(xy 84.357683 -400.885452) (xy 82.920173 -400.885452) (xy 82.920173 -400.885456) (xy 82.912415 -400.939413)
			(xy 82.897057 -400.991716) (xy 82.874411 -401.041302) (xy 82.844939 -401.087159) (xy 82.80924 -401.128355)
			(xy 82.768042 -401.164052) (xy 82.722182 -401.193521) (xy 82.672596 -401.216164) (xy 82.620291 -401.23152)
			(xy 82.566334 -401.239275) (xy 82.539078 -401.239736) (xy 81.675478 -401.239736) (xy 81.64823 -401.239192)
			(xy 81.594288 -401.231434) (xy 81.542 -401.216078) (xy 81.49243 -401.193437) (xy 81.446585 -401.163973)
			(xy 81.405401 -401.128284) (xy 81.369714 -401.087097) (xy 81.340252 -401.041251) (xy 81.317614 -400.991679)
			(xy 81.302262 -400.93939) (xy 81.294506 -400.885448) (xy 79.85685 -400.885448) (xy 79.85685 -400.885452)
			(xy 79.849094 -400.9394) (xy 79.83374 -400.991695) (xy 79.8111 -401.041274) (xy 79.781635 -401.087126)
			(xy 79.745945 -401.128318) (xy 79.704756 -401.164012) (xy 79.658907 -401.193482) (xy 79.609331 -401.216127)
			(xy 79.557037 -401.231486) (xy 79.503089 -401.239248) (xy 79.475838 -401.239736) (xy 78.612238 -401.239736)
			(xy 78.584985 -401.239219) (xy 78.531034 -401.231467) (xy 78.478736 -401.216116) (xy 78.429154 -401.193477)
			(xy 78.3833 -401.164012) (xy 78.342106 -401.128321) (xy 78.306411 -401.087131) (xy 78.276941 -401.041279)
			(xy 78.254298 -400.9917) (xy 78.238941 -400.939403) (xy 78.231183 -400.885453) (xy 76.793673 -400.885453)
			(xy 76.793673 -400.885455) (xy 76.785915 -400.93941) (xy 76.770558 -400.991712) (xy 76.747914 -401.041296)
			(xy 76.718443 -401.087153) (xy 76.682747 -401.128348) (xy 76.641551 -401.164045) (xy 76.595694 -401.193515)
			(xy 76.54611 -401.216159) (xy 76.493808 -401.231516) (xy 76.439853 -401.239273) (xy 76.412598 -401.239736)
			(xy 75.548998 -401.239736) (xy 75.521749 -401.239194) (xy 75.467805 -401.231437) (xy 75.415515 -401.216083)
			(xy 75.365942 -401.193444) (xy 75.320095 -401.16398) (xy 75.278908 -401.128291) (xy 75.243219 -401.087104)
			(xy 75.213755 -401.041257) (xy 75.191116 -400.991683) (xy 75.175762 -400.939393) (xy 75.168006 -400.885449)
			(xy 73.730473 -400.885449) (xy 73.730473 -400.885457) (xy 73.722714 -400.939415) (xy 73.707355 -400.991721)
			(xy 73.684708 -401.041307) (xy 73.655234 -401.087166) (xy 73.619533 -401.128363) (xy 73.578332 -401.164059)
			(xy 73.53247 -401.193528) (xy 73.482881 -401.21617) (xy 73.430574 -401.231523) (xy 73.376615 -401.239276)
			(xy 73.349358 -401.239736) (xy 72.485758 -401.239736) (xy 72.458511 -401.239191) (xy 72.404572 -401.23143)
			(xy 72.352286 -401.216073) (xy 72.302718 -401.193431) (xy 72.256876 -401.163965) (xy 72.215694 -401.128277)
			(xy 72.180009 -401.087091) (xy 72.150549 -401.041246) (xy 72.127913 -400.991675) (xy 72.112561 -400.939387)
			(xy 72.104806 -400.885447) (xy 70.66715 -400.885447) (xy 70.66715 -400.885452) (xy 70.659394 -400.939403)
			(xy 70.644038 -400.9917) (xy 70.621397 -401.041279) (xy 70.59193 -401.087132) (xy 70.556238 -401.128325)
			(xy 70.515047 -401.164019) (xy 70.469195 -401.193488) (xy 70.419617 -401.216132) (xy 70.36732 -401.23149)
			(xy 70.31337 -401.239249) (xy 70.286118 -401.239736) (xy 69.422518 -401.239736) (xy 69.395266 -401.239218)
			(xy 69.341317 -401.231464) (xy 69.289021 -401.21611) (xy 69.239442 -401.19347) (xy 69.19359 -401.164005)
			(xy 69.152399 -401.128314) (xy 69.116706 -401.087124) (xy 69.087238 -401.041273) (xy 69.064596 -400.991696)
			(xy 69.04924 -400.9394) (xy 69.041483 -400.885452) (xy 67.603973 -400.885452) (xy 67.603973 -400.885456)
			(xy 67.596215 -400.939413) (xy 67.580857 -400.991716) (xy 67.558211 -401.041302) (xy 67.528739 -401.087159)
			(xy 67.49304 -401.128355) (xy 67.451842 -401.164052) (xy 67.405982 -401.193521) (xy 67.356396 -401.216164)
			(xy 67.304091 -401.23152) (xy 67.250134 -401.239275) (xy 67.222878 -401.239736) (xy 66.359278 -401.239736)
			(xy 66.33203 -401.239192) (xy 66.278088 -401.231434) (xy 66.2258 -401.216078) (xy 66.17623 -401.193437)
			(xy 66.130385 -401.163973) (xy 66.089201 -401.128284) (xy 66.053514 -401.087097) (xy 66.024052 -401.041251)
			(xy 66.001414 -400.991679) (xy 65.986062 -400.93939) (xy 65.978306 -400.885448) (xy 64.54065 -400.885448)
			(xy 64.54065 -400.885452) (xy 64.532894 -400.9394) (xy 64.51754 -400.991695) (xy 64.4949 -401.041274)
			(xy 64.465435 -401.087126) (xy 64.429745 -401.128318) (xy 64.388556 -401.164012) (xy 64.342707 -401.193482)
			(xy 64.293131 -401.216127) (xy 64.240837 -401.231486) (xy 64.186889 -401.239248) (xy 64.159638 -401.239736)
			(xy 63.296038 -401.239736) (xy 63.268785 -401.239219) (xy 63.214834 -401.231467) (xy 63.162536 -401.216116)
			(xy 63.112954 -401.193477) (xy 63.0671 -401.164012) (xy 63.025906 -401.128321) (xy 62.990211 -401.087131)
			(xy 62.960741 -401.041279) (xy 62.938098 -400.9917) (xy 62.922741 -400.939403) (xy 62.914983 -400.885453)
			(xy 61.477473 -400.885453) (xy 61.477473 -400.885455) (xy 61.469715 -400.93941) (xy 61.454358 -400.991712)
			(xy 61.431714 -401.041296) (xy 61.402243 -401.087153) (xy 61.366547 -401.128348) (xy 61.325351 -401.164045)
			(xy 61.279494 -401.193515) (xy 61.22991 -401.216159) (xy 61.177608 -401.231516) (xy 61.123653 -401.239273)
			(xy 61.096398 -401.239736) (xy 60.232798 -401.239736) (xy 60.205549 -401.239194) (xy 60.151605 -401.231437)
			(xy 60.099315 -401.216083) (xy 60.049742 -401.193444) (xy 60.003895 -401.16398) (xy 59.962708 -401.128291)
			(xy 59.927019 -401.087104) (xy 59.897555 -401.041257) (xy 59.874916 -400.991683) (xy 59.859562 -400.939393)
			(xy 59.851806 -400.885449) (xy 58.414273 -400.885449) (xy 58.414273 -400.885457) (xy 58.406514 -400.939415)
			(xy 58.391155 -400.991721) (xy 58.368508 -401.041307) (xy 58.339034 -401.087166) (xy 58.303333 -401.128363)
			(xy 58.262132 -401.164059) (xy 58.21627 -401.193528) (xy 58.166681 -401.21617) (xy 58.114374 -401.231523)
			(xy 58.060415 -401.239276) (xy 58.033158 -401.239736) (xy 57.169558 -401.239736) (xy 57.142311 -401.239191)
			(xy 57.088372 -401.23143) (xy 57.036086 -401.216073) (xy 56.986518 -401.193431) (xy 56.940676 -401.163965)
			(xy 56.899494 -401.128277) (xy 56.863809 -401.087091) (xy 56.834349 -401.041246) (xy 56.811713 -400.991675)
			(xy 56.796361 -400.939387) (xy 56.788606 -400.885447) (xy 55.35095 -400.885447) (xy 55.35095 -400.885452)
			(xy 55.343194 -400.939403) (xy 55.327838 -400.9917) (xy 55.305197 -401.041279) (xy 55.27573 -401.087132)
			(xy 55.240038 -401.128325) (xy 55.198847 -401.164019) (xy 55.152995 -401.193488) (xy 55.103417 -401.216132)
			(xy 55.05112 -401.23149) (xy 54.99717 -401.239249) (xy 54.969918 -401.239736) (xy 54.106318 -401.239736)
			(xy 54.079066 -401.239218) (xy 54.025117 -401.231464) (xy 53.972821 -401.21611) (xy 53.923242 -401.19347)
			(xy 53.87739 -401.164005) (xy 53.836199 -401.128314) (xy 53.800506 -401.087124) (xy 53.771038 -401.041273)
			(xy 53.748396 -400.991696) (xy 53.73304 -400.9394) (xy 53.725283 -400.885452) (xy 52.287773 -400.885452)
			(xy 52.287773 -400.885456) (xy 52.280015 -400.939413) (xy 52.264657 -400.991716) (xy 52.242011 -401.041302)
			(xy 52.212539 -401.087159) (xy 52.17684 -401.128355) (xy 52.135642 -401.164052) (xy 52.089782 -401.193521)
			(xy 52.040196 -401.216164) (xy 51.987891 -401.23152) (xy 51.933934 -401.239275) (xy 51.906678 -401.239736)
			(xy 51.043078 -401.239736) (xy 51.01583 -401.239192) (xy 50.961888 -401.231434) (xy 50.9096 -401.216078)
			(xy 50.86003 -401.193437) (xy 50.814185 -401.163973) (xy 50.773001 -401.128284) (xy 50.737314 -401.087097)
			(xy 50.707852 -401.041251) (xy 50.685214 -400.991679) (xy 50.669862 -400.93939) (xy 50.662106 -400.885448)
			(xy 49.22445 -400.885448) (xy 49.22445 -400.885452) (xy 49.216694 -400.9394) (xy 49.20134 -400.991695)
			(xy 49.1787 -401.041274) (xy 49.149235 -401.087126) (xy 49.113545 -401.128318) (xy 49.072356 -401.164012)
			(xy 49.026507 -401.193482) (xy 48.976931 -401.216127) (xy 48.924637 -401.231486) (xy 48.870689 -401.239248)
			(xy 48.843438 -401.239736) (xy 47.979838 -401.239736) (xy 47.952585 -401.239219) (xy 47.898634 -401.231467)
			(xy 47.846336 -401.216116) (xy 47.796754 -401.193477) (xy 47.7509 -401.164012) (xy 47.709706 -401.128321)
			(xy 47.674011 -401.087131) (xy 47.644541 -401.041279) (xy 47.621898 -400.9917) (xy 47.606541 -400.939403)
			(xy 47.598783 -400.885453) (xy 2.509012 -400.885453) (xy 2.509012 -402.10994) (xy 239.42294 -402.10994)
			(xy 239.42294 -397.53286) (xy 239.423521 -397.5079) (xy 239.433246 -397.458937) (xy 239.452353 -397.412819)
			(xy 239.480105 -397.371324) (xy 239.497362 -397.353282) (xy 239.885982 -396.964662) (xy 239.904032 -396.947415)
			(xy 239.945531 -396.919673) (xy 239.991645 -396.900562) (xy 240.040601 -396.890815) (xy 240.06556 -396.89024)
			(xy 280.24074 -396.89024) (xy 280.2657 -396.890821) (xy 280.314663 -396.900546) (xy 280.360781 -396.919653)
			(xy 280.402276 -396.947405) (xy 280.420318 -396.964662) (xy 280.689558 -397.233902) (xy 280.706818 -397.25194)
			(xy 280.734556 -397.293444) (xy 280.753664 -397.339561) (xy 280.763407 -397.38852) (xy 280.76398 -397.41348)
			(xy 280.76398 -398.65534) (xy 457.185003 -398.65534) (xy 457.185003 -398.5262) (xy 457.192953 -398.397305)
			(xy 457.208823 -398.269145) (xy 457.232552 -398.142204) (xy 457.264051 -398.016965) (xy 457.3032 -397.893902)
			(xy 457.349851 -397.773483) (xy 457.403826 -397.656164) (xy 457.464921 -397.54239) (xy 457.532904 -397.432593)
			(xy 457.607518 -397.32719) (xy 457.688479 -397.22658) (xy 457.775479 -397.131145) (xy 457.86819 -397.041246)
			(xy 457.96626 -396.957225) (xy 458.069315 -396.879401) (xy 458.176966 -396.808069) (xy 458.288805 -396.743499)
			(xy 458.404406 -396.685937) (xy 458.523331 -396.6356) (xy 458.64513 -396.59268) (xy 458.76934 -396.557339)
			(xy 458.895489 -396.529712) (xy 459.023101 -396.509903) (xy 459.15169 -396.497987) (xy 459.280768 -396.494011)
			(xy 459.409846 -396.497987) (xy 459.538435 -396.509903) (xy 459.666047 -396.529712) (xy 459.792196 -396.557339)
			(xy 459.916406 -396.59268) (xy 460.038205 -396.6356) (xy 460.15713 -396.685937) (xy 460.272731 -396.743499)
			(xy 460.38457 -396.808069) (xy 460.492221 -396.879401) (xy 460.595276 -396.957225) (xy 460.693346 -397.041246)
			(xy 460.786057 -397.131145) (xy 460.873057 -397.22658) (xy 460.954018 -397.32719) (xy 461.028632 -397.432593)
			(xy 461.096615 -397.54239) (xy 461.15771 -397.656164) (xy 461.211685 -397.773483) (xy 461.258336 -397.893902)
			(xy 461.297485 -398.016965) (xy 461.328984 -398.142204) (xy 461.352713 -398.269145) (xy 461.368583 -398.397305)
			(xy 461.376533 -398.5262) (xy 461.37703 -398.59077) (xy 461.376533 -398.65534) (xy 461.368583 -398.784235)
			(xy 461.352713 -398.912395) (xy 461.328984 -399.039336) (xy 461.297485 -399.164575) (xy 461.258336 -399.287638)
			(xy 461.211685 -399.408057) (xy 461.15771 -399.525376) (xy 461.096615 -399.63915) (xy 461.028632 -399.748947)
			(xy 460.954018 -399.85435) (xy 460.873057 -399.95496) (xy 460.786057 -400.050395) (xy 460.693346 -400.140294)
			(xy 460.595276 -400.224315) (xy 460.492221 -400.302139) (xy 460.38457 -400.373471) (xy 460.272731 -400.438041)
			(xy 460.15713 -400.495603) (xy 460.038205 -400.54594) (xy 459.916406 -400.58886) (xy 459.792196 -400.624201)
			(xy 459.666047 -400.651828) (xy 459.538435 -400.671637) (xy 459.409846 -400.683553) (xy 459.280768 -400.68753)
			(xy 459.15169 -400.683553) (xy 459.023101 -400.671637) (xy 458.895489 -400.651828) (xy 458.76934 -400.624201)
			(xy 458.64513 -400.58886) (xy 458.523331 -400.54594) (xy 458.404406 -400.495603) (xy 458.288805 -400.438041)
			(xy 458.176966 -400.373471) (xy 458.069315 -400.302139) (xy 457.96626 -400.224315) (xy 457.86819 -400.140294)
			(xy 457.775479 -400.050395) (xy 457.688479 -399.95496) (xy 457.607518 -399.85435) (xy 457.532904 -399.748947)
			(xy 457.464921 -399.63915) (xy 457.403826 -399.525376) (xy 457.349851 -399.408057) (xy 457.3032 -399.287638)
			(xy 457.264051 -399.164575) (xy 457.232552 -399.039336) (xy 457.208823 -398.912395) (xy 457.192953 -398.784235)
			(xy 457.185003 -398.65534) (xy 280.76398 -398.65534) (xy 280.76398 -399.9835) (xy 289.606441 -399.9835)
			(xy 289.610455 -399.919698) (xy 289.622434 -399.856902) (xy 289.642189 -399.796103) (xy 289.669408 -399.73826)
			(xy 289.703662 -399.684283) (xy 289.744411 -399.635026) (xy 289.791013 -399.591264) (xy 289.842731 -399.553688)
			(xy 289.898752 -399.52289) (xy 289.958191 -399.499357) (xy 290.02011 -399.483458) (xy 290.083534 -399.475446)
			(xy 290.115498 -399.474944) (xy 290.115752 -399.474944) (xy 290.147498 -399.475464) (xy 290.210494 -399.483393)
			(xy 290.272014 -399.499096) (xy 290.331102 -399.52233) (xy 290.386842 -399.552733) (xy 290.438367 -399.589834)
			(xy 290.461954 -399.611088) (xy 290.469217 -399.617272) (xy 290.486967 -399.624223) (xy 290.506029 -399.624223)
			(xy 290.523779 -399.617272) (xy 290.531042 -399.611088) (xy 290.554631 -399.589832) (xy 290.60614 -399.5527)
			(xy 290.661874 -399.522276) (xy 290.720965 -399.499035) (xy 290.782492 -399.483338) (xy 290.845495 -399.475431)
			(xy 290.877244 -399.474944) (xy 290.877498 -399.474944) (xy 290.909457 -399.475521) (xy 290.972872 -399.483532)
			(xy 291.034783 -399.499427) (xy 291.094213 -399.522957) (xy 291.150226 -399.55375) (xy 291.201937 -399.591321)
			(xy 291.248532 -399.635076) (xy 291.289276 -399.684326) (xy 291.323525 -399.738295) (xy 291.350741 -399.79613)
			(xy 291.370493 -399.856921) (xy 291.38247 -399.919707) (xy 291.386484 -399.9835) (xy 292.146441 -399.9835)
			(xy 292.150455 -399.919698) (xy 292.162434 -399.856902) (xy 292.182189 -399.796103) (xy 292.209408 -399.73826)
			(xy 292.243662 -399.684283) (xy 292.284411 -399.635026) (xy 292.331013 -399.591264) (xy 292.382731 -399.553688)
			(xy 292.438752 -399.52289) (xy 292.498191 -399.499357) (xy 292.56011 -399.483458) (xy 292.623534 -399.475446)
			(xy 292.655498 -399.474944) (xy 292.655752 -399.474944) (xy 292.687498 -399.475464) (xy 292.750494 -399.483393)
			(xy 292.812014 -399.499096) (xy 292.871102 -399.52233) (xy 292.926842 -399.552733) (xy 292.978367 -399.589834)
			(xy 293.001954 -399.611088) (xy 293.009217 -399.617272) (xy 293.026967 -399.624223) (xy 293.046029 -399.624223)
			(xy 293.063779 -399.617272) (xy 293.071042 -399.611088) (xy 293.094631 -399.589832) (xy 293.14614 -399.5527)
			(xy 293.201874 -399.522276) (xy 293.260965 -399.499035) (xy 293.322492 -399.483338) (xy 293.385495 -399.475431)
			(xy 293.417244 -399.474944) (xy 293.417498 -399.474944) (xy 293.449457 -399.475521) (xy 293.512872 -399.483532)
			(xy 293.574783 -399.499427) (xy 293.634213 -399.522957) (xy 293.690226 -399.55375) (xy 293.741937 -399.591321)
			(xy 293.788532 -399.635076) (xy 293.829276 -399.684326) (xy 293.863525 -399.738295) (xy 293.890741 -399.79613)
			(xy 293.910493 -399.856921) (xy 293.92247 -399.919707) (xy 293.926484 -399.9835) (xy 294.53602 -399.9835)
			(xy 294.540035 -399.919693) (xy 294.552015 -399.856892) (xy 294.571773 -399.796089) (xy 294.598995 -399.738241)
			(xy 294.633253 -399.684261) (xy 294.674007 -399.635001) (xy 294.720613 -399.591237) (xy 294.772338 -399.55366)
			(xy 294.828364 -399.522862) (xy 294.887809 -399.499329) (xy 294.949734 -399.483433) (xy 295.013163 -399.475423)
			(xy 295.04513 -399.474944) (xy 295.045384 -399.474944) (xy 295.077131 -399.475444) (xy 295.140127 -399.483377)
			(xy 295.201647 -399.499084) (xy 295.260736 -399.522322) (xy 295.316476 -399.552728) (xy 295.368 -399.589832)
			(xy 295.391586 -399.611088) (xy 295.398849 -399.617272) (xy 295.416599 -399.624223) (xy 295.435661 -399.624223)
			(xy 295.453411 -399.617272) (xy 295.460674 -399.611088) (xy 295.48425 -399.589817) (xy 295.535761 -399.552686)
			(xy 295.591498 -399.522265) (xy 295.650592 -399.499026) (xy 295.712121 -399.483332) (xy 295.775126 -399.475429)
			(xy 295.806876 -399.474944) (xy 295.80713 -399.474944) (xy 295.839087 -399.475544) (xy 295.902496 -399.483558)
			(xy 295.964401 -399.499455) (xy 296.023825 -399.522986) (xy 296.079832 -399.553779) (xy 296.131538 -399.591348)
			(xy 296.178128 -399.635102) (xy 296.218866 -399.684349) (xy 296.253112 -399.738314) (xy 296.280324 -399.796145)
			(xy 296.300074 -399.856931) (xy 296.312049 -399.919712) (xy 296.316063 -399.9835) (xy 297.07602 -399.9835)
			(xy 297.080035 -399.919693) (xy 297.092015 -399.856892) (xy 297.111773 -399.796089) (xy 297.138995 -399.738241)
			(xy 297.173253 -399.684261) (xy 297.214007 -399.635001) (xy 297.260613 -399.591237) (xy 297.312338 -399.55366)
			(xy 297.368364 -399.522862) (xy 297.427809 -399.499329) (xy 297.489734 -399.483433) (xy 297.553163 -399.475423)
			(xy 297.58513 -399.474944) (xy 297.585384 -399.474944) (xy 297.617131 -399.475444) (xy 297.680127 -399.483377)
			(xy 297.741647 -399.499084) (xy 297.800736 -399.522322) (xy 297.856476 -399.552728) (xy 297.908 -399.589832)
			(xy 297.931586 -399.611088) (xy 297.938849 -399.617272) (xy 297.956599 -399.624223) (xy 297.975661 -399.624223)
			(xy 297.993411 -399.617272) (xy 298.000674 -399.611088) (xy 298.02425 -399.589817) (xy 298.075761 -399.552686)
			(xy 298.131498 -399.522265) (xy 298.190592 -399.499026) (xy 298.252121 -399.483332) (xy 298.315126 -399.475429)
			(xy 298.346876 -399.474944) (xy 298.34713 -399.474944) (xy 298.379087 -399.475544) (xy 298.442496 -399.483558)
			(xy 298.504401 -399.499455) (xy 298.563825 -399.522986) (xy 298.619832 -399.553779) (xy 298.671538 -399.591348)
			(xy 298.718128 -399.635102) (xy 298.758866 -399.684349) (xy 298.793112 -399.738314) (xy 298.820324 -399.796145)
			(xy 298.840074 -399.856931) (xy 298.852049 -399.919712) (xy 298.856063 -399.9835) (xy 298.852049 -400.047288)
			(xy 298.840074 -400.110069) (xy 298.820324 -400.170855) (xy 298.793112 -400.228686) (xy 298.758866 -400.282651)
			(xy 298.718128 -400.331898) (xy 298.671538 -400.375652) (xy 298.619832 -400.413221) (xy 298.563825 -400.444014)
			(xy 298.504401 -400.467545) (xy 298.442496 -400.483442) (xy 298.379087 -400.491456) (xy 298.34713 -400.49196)
			(xy 298.346876 -400.49196) (xy 298.315131 -400.491422) (xy 298.252136 -400.483497) (xy 298.190616 -400.467797)
			(xy 298.131527 -400.444566) (xy 298.075787 -400.414166) (xy 298.024261 -400.377069) (xy 298.000674 -400.355816)
			(xy 297.993411 -400.349632) (xy 297.975661 -400.342681) (xy 297.956599 -400.342681) (xy 297.938849 -400.349632)
			(xy 297.931586 -400.355816) (xy 297.908028 -400.377107) (xy 297.856512 -400.414235) (xy 297.800771 -400.444654)
			(xy 297.741674 -400.467889) (xy 297.680142 -400.483579) (xy 297.617135 -400.491478) (xy 297.585384 -400.49196)
			(xy 297.58513 -400.49196) (xy 297.553163 -400.491577) (xy 297.489734 -400.483567) (xy 297.427809 -400.467671)
			(xy 297.368364 -400.444138) (xy 297.312338 -400.41334) (xy 297.260613 -400.375763) (xy 297.214007 -400.331999)
			(xy 297.173253 -400.282739) (xy 297.138995 -400.228759) (xy 297.111773 -400.170911) (xy 297.092015 -400.110108)
			(xy 297.080035 -400.047307) (xy 297.07602 -399.9835) (xy 296.316063 -399.9835) (xy 296.312049 -400.047288)
			(xy 296.300074 -400.110069) (xy 296.280324 -400.170855) (xy 296.253112 -400.228686) (xy 296.218866 -400.282651)
			(xy 296.178128 -400.331898) (xy 296.131538 -400.375652) (xy 296.079832 -400.413221) (xy 296.023825 -400.444014)
			(xy 295.964401 -400.467545) (xy 295.902496 -400.483442) (xy 295.839087 -400.491456) (xy 295.80713 -400.49196)
			(xy 295.806876 -400.49196) (xy 295.775131 -400.491422) (xy 295.712136 -400.483497) (xy 295.650616 -400.467797)
			(xy 295.591527 -400.444566) (xy 295.535787 -400.414166) (xy 295.484261 -400.377069) (xy 295.460674 -400.355816)
			(xy 295.453411 -400.349632) (xy 295.435661 -400.342681) (xy 295.416599 -400.342681) (xy 295.398849 -400.349632)
			(xy 295.391586 -400.355816) (xy 295.368028 -400.377107) (xy 295.316512 -400.414235) (xy 295.260771 -400.444654)
			(xy 295.201674 -400.467889) (xy 295.140142 -400.483579) (xy 295.077135 -400.491478) (xy 295.045384 -400.49196)
			(xy 295.04513 -400.49196) (xy 295.013163 -400.491577) (xy 294.949734 -400.483567) (xy 294.887809 -400.467671)
			(xy 294.828364 -400.444138) (xy 294.772338 -400.41334) (xy 294.720613 -400.375763) (xy 294.674007 -400.331999)
			(xy 294.633253 -400.282739) (xy 294.598995 -400.228759) (xy 294.571773 -400.170911) (xy 294.552015 -400.110108)
			(xy 294.540035 -400.047307) (xy 294.53602 -399.9835) (xy 293.926484 -399.9835) (xy 293.92247 -400.047293)
			(xy 293.910493 -400.110079) (xy 293.890741 -400.17087) (xy 293.863525 -400.228705) (xy 293.829276 -400.282674)
			(xy 293.788532 -400.331924) (xy 293.741937 -400.375679) (xy 293.690226 -400.41325) (xy 293.634213 -400.444043)
			(xy 293.574783 -400.467573) (xy 293.512872 -400.483468) (xy 293.449457 -400.491479) (xy 293.417498 -400.49196)
			(xy 293.417244 -400.49196) (xy 293.385498 -400.491442) (xy 293.322502 -400.483512) (xy 293.260982 -400.467809)
			(xy 293.201894 -400.444575) (xy 293.146154 -400.414171) (xy 293.094629 -400.37707) (xy 293.071042 -400.355816)
			(xy 293.063779 -400.349632) (xy 293.046029 -400.342681) (xy 293.026967 -400.342681) (xy 293.009217 -400.349632)
			(xy 293.001954 -400.355816) (xy 292.978367 -400.377074) (xy 292.926858 -400.414206) (xy 292.871123 -400.44463)
			(xy 292.812032 -400.467871) (xy 292.750504 -400.483567) (xy 292.687501 -400.491474) (xy 292.655752 -400.49196)
			(xy 292.655498 -400.49196) (xy 292.623534 -400.491554) (xy 292.56011 -400.483542) (xy 292.498191 -400.467643)
			(xy 292.438752 -400.44411) (xy 292.382731 -400.413312) (xy 292.331013 -400.375736) (xy 292.284411 -400.331974)
			(xy 292.243662 -400.282717) (xy 292.209408 -400.22874) (xy 292.182189 -400.170897) (xy 292.162434 -400.110098)
			(xy 292.150455 -400.047302) (xy 292.146441 -399.9835) (xy 291.386484 -399.9835) (xy 291.38247 -400.047293)
			(xy 291.370493 -400.110079) (xy 291.350741 -400.17087) (xy 291.323525 -400.228705) (xy 291.289276 -400.282674)
			(xy 291.248532 -400.331924) (xy 291.201937 -400.375679) (xy 291.150226 -400.41325) (xy 291.094213 -400.444043)
			(xy 291.034783 -400.467573) (xy 290.972872 -400.483468) (xy 290.909457 -400.491479) (xy 290.877498 -400.49196)
			(xy 290.877244 -400.49196) (xy 290.845498 -400.491442) (xy 290.782502 -400.483512) (xy 290.720982 -400.467809)
			(xy 290.661894 -400.444575) (xy 290.606154 -400.414171) (xy 290.554629 -400.37707) (xy 290.531042 -400.355816)
			(xy 290.523779 -400.349632) (xy 290.506029 -400.342681) (xy 290.486967 -400.342681) (xy 290.469217 -400.349632)
			(xy 290.461954 -400.355816) (xy 290.438367 -400.377074) (xy 290.386858 -400.414206) (xy 290.331123 -400.44463)
			(xy 290.272032 -400.467871) (xy 290.210504 -400.483567) (xy 290.147501 -400.491474) (xy 290.115752 -400.49196)
			(xy 290.115498 -400.49196) (xy 290.083534 -400.491554) (xy 290.02011 -400.483542) (xy 289.958191 -400.467643)
			(xy 289.898752 -400.44411) (xy 289.842731 -400.413312) (xy 289.791013 -400.375736) (xy 289.744411 -400.331974)
			(xy 289.703662 -400.282717) (xy 289.669408 -400.22874) (xy 289.642189 -400.170897) (xy 289.622434 -400.110098)
			(xy 289.610455 -400.047302) (xy 289.606441 -399.9835) (xy 280.76398 -399.9835) (xy 280.76398 -400.885449)
			(xy 303.599106 -400.885449) (xy 303.599106 -400.830951) (xy 303.606862 -400.777009) (xy 303.622215 -400.724719)
			(xy 303.644854 -400.675146) (xy 303.674317 -400.6293) (xy 303.710004 -400.588113) (xy 303.75119 -400.552424)
			(xy 303.797036 -400.52296) (xy 303.846608 -400.500319) (xy 303.898897 -400.484964) (xy 303.952839 -400.477207)
			(xy 303.980088 -400.47672) (xy 304.843688 -400.47672) (xy 304.870943 -400.477126) (xy 304.9249 -400.484882)
			(xy 304.977203 -400.500238) (xy 305.026788 -400.522882) (xy 305.072646 -400.552352) (xy 305.113843 -400.588048)
			(xy 305.149541 -400.629244) (xy 305.179012 -400.675101) (xy 305.201657 -400.724686) (xy 305.217015 -400.776989)
			(xy 305.224773 -400.830945) (xy 305.224773 -400.885452) (xy 306.662283 -400.885452) (xy 306.662283 -400.830948)
			(xy 306.67004 -400.776998) (xy 306.685397 -400.724702) (xy 306.70804 -400.675124) (xy 306.737508 -400.629273)
			(xy 306.773202 -400.588082) (xy 306.814395 -400.552391) (xy 306.860248 -400.522926) (xy 306.909828 -400.500287)
			(xy 306.962126 -400.484935) (xy 307.016076 -400.477181) (xy 307.043328 -400.47672) (xy 307.906928 -400.47672)
			(xy 307.93418 -400.477152) (xy 307.988129 -400.484912) (xy 308.040424 -400.500271) (xy 308.090001 -400.522915)
			(xy 308.135851 -400.552384) (xy 308.177041 -400.588079) (xy 308.212732 -400.629271) (xy 308.242198 -400.675123)
			(xy 308.264839 -400.724702) (xy 308.280194 -400.776999) (xy 308.28795 -400.830948) (xy 308.28795 -400.885448)
			(xy 309.725606 -400.885448) (xy 309.725606 -400.830952) (xy 309.733361 -400.777011) (xy 309.748714 -400.724723)
			(xy 309.771351 -400.675152) (xy 309.800812 -400.629306) (xy 309.836497 -400.58812) (xy 309.877681 -400.552431)
			(xy 309.923524 -400.522966) (xy 309.973093 -400.500325) (xy 310.02538 -400.484968) (xy 310.07932 -400.477208)
			(xy 310.106568 -400.47672) (xy 310.970168 -400.47672) (xy 310.997424 -400.477125) (xy 311.051383 -400.484879)
			(xy 311.103688 -400.500233) (xy 311.153276 -400.522875) (xy 311.199137 -400.552345) (xy 311.240336 -400.588041)
			(xy 311.276036 -400.629238) (xy 311.305509 -400.675096) (xy 311.328156 -400.724682) (xy 311.343515 -400.776986)
			(xy 311.351273 -400.830944) (xy 311.351273 -400.885451) (xy 312.788783 -400.885451) (xy 312.788783 -400.830949)
			(xy 312.79654 -400.777001) (xy 312.811895 -400.724706) (xy 312.834537 -400.675129) (xy 312.864003 -400.629279)
			(xy 312.899695 -400.588089) (xy 312.940886 -400.552398) (xy 312.986736 -400.522933) (xy 313.036314 -400.500292)
			(xy 313.088609 -400.484938) (xy 313.142557 -400.477183) (xy 313.169808 -400.47672) (xy 314.033408 -400.47672)
			(xy 314.060661 -400.47715) (xy 314.114612 -400.484908) (xy 314.166909 -400.500265) (xy 314.216489 -400.522909)
			(xy 314.262342 -400.552377) (xy 314.303534 -400.588071) (xy 314.339228 -400.629264) (xy 314.368695 -400.675118)
			(xy 314.391337 -400.724698) (xy 314.406693 -400.776996) (xy 314.41445 -400.830947) (xy 314.41445 -400.885453)
			(xy 315.851983 -400.885453) (xy 315.851983 -400.830947) (xy 315.859741 -400.776996) (xy 315.875098 -400.724698)
			(xy 315.897743 -400.675118) (xy 315.927213 -400.629266) (xy 315.962909 -400.588075) (xy 316.004105 -400.552384)
			(xy 316.04996 -400.52292) (xy 316.099543 -400.500282) (xy 316.151843 -400.484931) (xy 316.205795 -400.47718)
			(xy 316.233048 -400.47672) (xy 317.096648 -400.47672) (xy 317.123899 -400.477153) (xy 317.177846 -400.484916)
			(xy 317.230138 -400.500276) (xy 317.279713 -400.522922) (xy 317.325561 -400.552391) (xy 317.366748 -400.588086)
			(xy 317.402437 -400.629278) (xy 317.431901 -400.675129) (xy 317.454541 -400.724707) (xy 317.469894 -400.777001)
			(xy 317.47765 -400.830949) (xy 317.47765 -400.885449) (xy 318.915306 -400.885449) (xy 318.915306 -400.830951)
			(xy 318.923062 -400.777009) (xy 318.938415 -400.724719) (xy 318.961054 -400.675146) (xy 318.990517 -400.6293)
			(xy 319.026204 -400.588113) (xy 319.06739 -400.552424) (xy 319.113236 -400.52296) (xy 319.162808 -400.500319)
			(xy 319.215097 -400.484964) (xy 319.269039 -400.477207) (xy 319.296288 -400.47672) (xy 320.159888 -400.47672)
			(xy 320.187143 -400.477126) (xy 320.2411 -400.484882) (xy 320.293403 -400.500238) (xy 320.342988 -400.522882)
			(xy 320.388846 -400.552352) (xy 320.430043 -400.588048) (xy 320.465741 -400.629244) (xy 320.495212 -400.675101)
			(xy 320.517857 -400.724686) (xy 320.533215 -400.776989) (xy 320.540973 -400.830945) (xy 320.540973 -400.885452)
			(xy 321.978483 -400.885452) (xy 321.978483 -400.830948) (xy 321.98624 -400.776998) (xy 322.001597 -400.724702)
			(xy 322.02424 -400.675124) (xy 322.053708 -400.629273) (xy 322.089402 -400.588082) (xy 322.130595 -400.552391)
			(xy 322.176448 -400.522926) (xy 322.226028 -400.500287) (xy 322.278326 -400.484935) (xy 322.332276 -400.477181)
			(xy 322.359528 -400.47672) (xy 323.223128 -400.47672) (xy 323.25038 -400.477152) (xy 323.304329 -400.484912)
			(xy 323.356624 -400.500271) (xy 323.406201 -400.522915) (xy 323.452051 -400.552384) (xy 323.493241 -400.588079)
			(xy 323.528932 -400.629271) (xy 323.558398 -400.675123) (xy 323.581039 -400.724702) (xy 323.596394 -400.776999)
			(xy 323.60415 -400.830948) (xy 323.60415 -400.885448) (xy 325.041806 -400.885448) (xy 325.041806 -400.830952)
			(xy 325.049561 -400.777011) (xy 325.064914 -400.724723) (xy 325.087551 -400.675152) (xy 325.117012 -400.629306)
			(xy 325.152697 -400.58812) (xy 325.193881 -400.552431) (xy 325.239724 -400.522966) (xy 325.289293 -400.500325)
			(xy 325.34158 -400.484968) (xy 325.39552 -400.477208) (xy 325.422768 -400.47672) (xy 326.286368 -400.47672)
			(xy 326.313624 -400.477125) (xy 326.367583 -400.484879) (xy 326.419888 -400.500233) (xy 326.469476 -400.522875)
			(xy 326.515337 -400.552345) (xy 326.556536 -400.588041) (xy 326.592236 -400.629238) (xy 326.621709 -400.675096)
			(xy 326.644356 -400.724682) (xy 326.659715 -400.776986) (xy 326.667473 -400.830944) (xy 326.667473 -400.885451)
			(xy 328.104983 -400.885451) (xy 328.104983 -400.830949) (xy 328.11274 -400.777001) (xy 328.128095 -400.724706)
			(xy 328.150737 -400.675129) (xy 328.180203 -400.629279) (xy 328.215895 -400.588089) (xy 328.257086 -400.552398)
			(xy 328.302936 -400.522933) (xy 328.352514 -400.500292) (xy 328.404809 -400.484938) (xy 328.458757 -400.477183)
			(xy 328.486008 -400.47672) (xy 329.349608 -400.47672) (xy 329.376861 -400.47715) (xy 329.430812 -400.484908)
			(xy 329.483109 -400.500265) (xy 329.532689 -400.522909) (xy 329.578542 -400.552377) (xy 329.619734 -400.588071)
			(xy 329.655428 -400.629264) (xy 329.684895 -400.675118) (xy 329.707537 -400.724698) (xy 329.722893 -400.776996)
			(xy 329.73065 -400.830947) (xy 329.73065 -400.885453) (xy 331.168183 -400.885453) (xy 331.168183 -400.830947)
			(xy 331.175941 -400.776996) (xy 331.191298 -400.724698) (xy 331.213943 -400.675118) (xy 331.243413 -400.629266)
			(xy 331.279109 -400.588075) (xy 331.320305 -400.552384) (xy 331.36616 -400.52292) (xy 331.415743 -400.500282)
			(xy 331.468043 -400.484931) (xy 331.521995 -400.47718) (xy 331.549248 -400.47672) (xy 332.412848 -400.47672)
			(xy 332.440099 -400.477153) (xy 332.494046 -400.484916) (xy 332.546338 -400.500276) (xy 332.595913 -400.522922)
			(xy 332.641761 -400.552391) (xy 332.682948 -400.588086) (xy 332.718637 -400.629278) (xy 332.748101 -400.675129)
			(xy 332.770741 -400.724707) (xy 332.786094 -400.777001) (xy 332.79385 -400.830949) (xy 332.79385 -400.885449)
			(xy 334.231506 -400.885449) (xy 334.231506 -400.830951) (xy 334.239262 -400.777009) (xy 334.254615 -400.724719)
			(xy 334.277254 -400.675146) (xy 334.306717 -400.6293) (xy 334.342404 -400.588113) (xy 334.38359 -400.552424)
			(xy 334.429436 -400.52296) (xy 334.479008 -400.500319) (xy 334.531297 -400.484964) (xy 334.585239 -400.477207)
			(xy 334.612488 -400.47672) (xy 335.476088 -400.47672) (xy 335.503343 -400.477126) (xy 335.5573 -400.484882)
			(xy 335.609603 -400.500238) (xy 335.659188 -400.522882) (xy 335.705046 -400.552352) (xy 335.746243 -400.588048)
			(xy 335.781941 -400.629244) (xy 335.811412 -400.675101) (xy 335.834057 -400.724686) (xy 335.849415 -400.776989)
			(xy 335.857173 -400.830945) (xy 335.857173 -400.885452) (xy 337.294683 -400.885452) (xy 337.294683 -400.830948)
			(xy 337.30244 -400.776998) (xy 337.317797 -400.724702) (xy 337.34044 -400.675124) (xy 337.369908 -400.629273)
			(xy 337.405602 -400.588082) (xy 337.446795 -400.552391) (xy 337.492648 -400.522926) (xy 337.542228 -400.500287)
			(xy 337.594526 -400.484935) (xy 337.648476 -400.477181) (xy 337.675728 -400.47672) (xy 338.539328 -400.47672)
			(xy 338.56658 -400.477152) (xy 338.620529 -400.484912) (xy 338.672824 -400.500271) (xy 338.722401 -400.522915)
			(xy 338.768251 -400.552384) (xy 338.809441 -400.588079) (xy 338.845132 -400.629271) (xy 338.874598 -400.675123)
			(xy 338.897239 -400.724702) (xy 338.912594 -400.776999) (xy 338.92035 -400.830948) (xy 338.92035 -400.885448)
			(xy 340.358006 -400.885448) (xy 340.358006 -400.830952) (xy 340.365761 -400.777011) (xy 340.381114 -400.724723)
			(xy 340.403751 -400.675152) (xy 340.433212 -400.629306) (xy 340.468897 -400.58812) (xy 340.510081 -400.552431)
			(xy 340.555924 -400.522966) (xy 340.605493 -400.500325) (xy 340.65778 -400.484968) (xy 340.71172 -400.477208)
			(xy 340.738968 -400.47672) (xy 341.602568 -400.47672) (xy 341.629824 -400.477125) (xy 341.683783 -400.484879)
			(xy 341.736088 -400.500233) (xy 341.785676 -400.522875) (xy 341.831537 -400.552345) (xy 341.872736 -400.588041)
			(xy 341.908436 -400.629238) (xy 341.937909 -400.675096) (xy 341.960556 -400.724682) (xy 341.975915 -400.776986)
			(xy 341.983673 -400.830944) (xy 341.983673 -400.885451) (xy 343.421183 -400.885451) (xy 343.421183 -400.830949)
			(xy 343.42894 -400.777001) (xy 343.444295 -400.724706) (xy 343.466937 -400.675129) (xy 343.496403 -400.629279)
			(xy 343.532095 -400.588089) (xy 343.573286 -400.552398) (xy 343.619136 -400.522933) (xy 343.668714 -400.500292)
			(xy 343.721009 -400.484938) (xy 343.774957 -400.477183) (xy 343.802208 -400.47672) (xy 344.665808 -400.47672)
			(xy 344.693061 -400.47715) (xy 344.747012 -400.484908) (xy 344.799309 -400.500265) (xy 344.848889 -400.522909)
			(xy 344.894742 -400.552377) (xy 344.935934 -400.588071) (xy 344.971628 -400.629264) (xy 345.001095 -400.675118)
			(xy 345.023737 -400.724698) (xy 345.039093 -400.776996) (xy 345.04685 -400.830947) (xy 345.04685 -400.885453)
			(xy 346.484383 -400.885453) (xy 346.484383 -400.830947) (xy 346.492141 -400.776996) (xy 346.507498 -400.724698)
			(xy 346.530143 -400.675118) (xy 346.559613 -400.629266) (xy 346.595309 -400.588075) (xy 346.636505 -400.552384)
			(xy 346.68236 -400.52292) (xy 346.731943 -400.500282) (xy 346.784243 -400.484931) (xy 346.838195 -400.47718)
			(xy 346.865448 -400.47672) (xy 347.729048 -400.47672) (xy 347.756299 -400.477153) (xy 347.810246 -400.484916)
			(xy 347.862538 -400.500276) (xy 347.912113 -400.522922) (xy 347.957961 -400.552391) (xy 347.999148 -400.588086)
			(xy 348.034837 -400.629278) (xy 348.064301 -400.675129) (xy 348.086941 -400.724707) (xy 348.102294 -400.777001)
			(xy 348.11005 -400.830949) (xy 348.11005 -400.885449) (xy 349.547706 -400.885449) (xy 349.547706 -400.830951)
			(xy 349.555462 -400.777009) (xy 349.570815 -400.724719) (xy 349.593454 -400.675146) (xy 349.622917 -400.6293)
			(xy 349.658604 -400.588113) (xy 349.69979 -400.552424) (xy 349.745636 -400.52296) (xy 349.795208 -400.500319)
			(xy 349.847497 -400.484964) (xy 349.901439 -400.477207) (xy 349.928688 -400.47672) (xy 350.792288 -400.47672)
			(xy 350.819543 -400.477126) (xy 350.8735 -400.484882) (xy 350.925803 -400.500238) (xy 350.975388 -400.522882)
			(xy 351.021246 -400.552352) (xy 351.062443 -400.588048) (xy 351.098141 -400.629244) (xy 351.127612 -400.675101)
			(xy 351.150257 -400.724686) (xy 351.165615 -400.776989) (xy 351.173373 -400.830945) (xy 351.173373 -400.885452)
			(xy 371.041883 -400.885452) (xy 371.041883 -400.830948) (xy 371.049641 -400.776998) (xy 371.064997 -400.724702)
			(xy 371.08764 -400.675123) (xy 371.117109 -400.629272) (xy 371.152803 -400.588082) (xy 371.193996 -400.552391)
			(xy 371.23985 -400.522926) (xy 371.28943 -400.500286) (xy 371.341728 -400.484934) (xy 371.395678 -400.477181)
			(xy 371.42293 -400.47672) (xy 372.28653 -400.47672) (xy 372.313782 -400.477152) (xy 372.36773 -400.484912)
			(xy 372.420025 -400.500271) (xy 372.469602 -400.522916) (xy 372.515452 -400.552385) (xy 372.556642 -400.588079)
			(xy 372.592333 -400.629272) (xy 372.621799 -400.675124) (xy 372.644439 -400.724703) (xy 372.659794 -400.776999)
			(xy 372.66755 -400.830948) (xy 372.66755 -400.885448) (xy 374.105206 -400.885448) (xy 374.105206 -400.830952)
			(xy 374.112961 -400.777011) (xy 374.128314 -400.724723) (xy 374.150951 -400.675151) (xy 374.180412 -400.629306)
			(xy 374.216098 -400.588119) (xy 374.257281 -400.55243) (xy 374.303125 -400.522965) (xy 374.352694 -400.500324)
			(xy 374.404982 -400.484968) (xy 374.458922 -400.477208) (xy 374.48617 -400.47672) (xy 375.34977 -400.47672)
			(xy 375.377026 -400.477125) (xy 375.430984 -400.484879) (xy 375.48329 -400.500234) (xy 375.532877 -400.522876)
			(xy 375.578738 -400.552345) (xy 375.619937 -400.588042) (xy 375.655637 -400.629238) (xy 375.68511 -400.675096)
			(xy 375.707756 -400.724682) (xy 375.723115 -400.776986) (xy 375.730873 -400.830944) (xy 375.730873 -400.885451)
			(xy 377.168383 -400.885451) (xy 377.168383 -400.830949) (xy 377.17614 -400.777001) (xy 377.191495 -400.724706)
			(xy 377.214137 -400.675129) (xy 377.243604 -400.629279) (xy 377.279296 -400.588089) (xy 377.320487 -400.552398)
			(xy 377.366338 -400.522932) (xy 377.415915 -400.500292) (xy 377.468211 -400.484938) (xy 377.522159 -400.477183)
			(xy 377.54941 -400.47672) (xy 378.41301 -400.47672) (xy 378.440263 -400.477151) (xy 378.494213 -400.484909)
			(xy 378.546511 -400.500266) (xy 378.59609 -400.522909) (xy 378.641943 -400.552378) (xy 378.683135 -400.588072)
			(xy 378.718828 -400.629265) (xy 378.748296 -400.675118) (xy 378.770938 -400.724699) (xy 378.786293 -400.776996)
			(xy 378.79405 -400.830947) (xy 378.79405 -400.885447) (xy 380.231706 -400.885447) (xy 380.231706 -400.830953)
			(xy 380.239461 -400.777014) (xy 380.254812 -400.724727) (xy 380.277448 -400.675157) (xy 380.306907 -400.629312)
			(xy 380.342591 -400.588126) (xy 380.383772 -400.552437) (xy 380.429613 -400.522972) (xy 380.47918 -400.50033)
			(xy 380.531465 -400.484971) (xy 380.585403 -400.47721) (xy 380.61265 -400.47672) (xy 381.47625 -400.47672)
			(xy 381.503507 -400.477124) (xy 381.557468 -400.484875) (xy 381.609775 -400.500228) (xy 381.659365 -400.522869)
			(xy 381.705228 -400.552338) (xy 381.74643 -400.588035) (xy 381.782132 -400.629232) (xy 381.811607 -400.675091)
			(xy 381.834254 -400.724678) (xy 381.849614 -400.776983) (xy 381.857373 -400.830943) (xy 381.857373 -400.885449)
			(xy 383.294906 -400.885449) (xy 383.294906 -400.830951) (xy 383.302662 -400.777008) (xy 383.318015 -400.724718)
			(xy 383.340654 -400.675145) (xy 383.370117 -400.629299) (xy 383.405805 -400.588112) (xy 383.446991 -400.552423)
			(xy 383.492837 -400.522959) (xy 383.542409 -400.500319) (xy 383.594699 -400.484964) (xy 383.648641 -400.477207)
			(xy 383.67589 -400.47672) (xy 384.53949 -400.47672) (xy 384.566745 -400.477126) (xy 384.620701 -400.484883)
			(xy 384.673004 -400.500239) (xy 384.722589 -400.522883) (xy 384.768447 -400.552352) (xy 384.809644 -400.588049)
			(xy 384.845342 -400.629245) (xy 384.874813 -400.675102) (xy 384.897458 -400.724686) (xy 384.912815 -400.776989)
			(xy 384.920573 -400.830945) (xy 384.920573 -400.885452) (xy 386.358083 -400.885452) (xy 386.358083 -400.830948)
			(xy 386.365841 -400.776998) (xy 386.381197 -400.724702) (xy 386.40384 -400.675123) (xy 386.433309 -400.629272)
			(xy 386.469003 -400.588082) (xy 386.510196 -400.552391) (xy 386.55605 -400.522926) (xy 386.60563 -400.500286)
			(xy 386.657928 -400.484934) (xy 386.711878 -400.477181) (xy 386.73913 -400.47672) (xy 387.60273 -400.47672)
			(xy 387.629982 -400.477152) (xy 387.68393 -400.484912) (xy 387.736225 -400.500271) (xy 387.785802 -400.522916)
			(xy 387.831652 -400.552385) (xy 387.872842 -400.588079) (xy 387.908533 -400.629272) (xy 387.937999 -400.675124)
			(xy 387.960639 -400.724703) (xy 387.975994 -400.776999) (xy 387.98375 -400.830948) (xy 387.98375 -400.885448)
			(xy 389.421406 -400.885448) (xy 389.421406 -400.830952) (xy 389.429161 -400.777011) (xy 389.444514 -400.724723)
			(xy 389.467151 -400.675151) (xy 389.496612 -400.629306) (xy 389.532298 -400.588119) (xy 389.573481 -400.55243)
			(xy 389.619325 -400.522965) (xy 389.668894 -400.500324) (xy 389.721182 -400.484968) (xy 389.775122 -400.477208)
			(xy 389.80237 -400.47672) (xy 390.66597 -400.47672) (xy 390.693226 -400.477125) (xy 390.747184 -400.484879)
			(xy 390.79949 -400.500234) (xy 390.849077 -400.522876) (xy 390.894938 -400.552345) (xy 390.936137 -400.588042)
			(xy 390.971837 -400.629238) (xy 391.00131 -400.675096) (xy 391.023956 -400.724682) (xy 391.039315 -400.776986)
			(xy 391.047073 -400.830944) (xy 391.047073 -400.885451) (xy 392.484583 -400.885451) (xy 392.484583 -400.830949)
			(xy 392.49234 -400.777001) (xy 392.507695 -400.724706) (xy 392.530337 -400.675129) (xy 392.559804 -400.629279)
			(xy 392.595496 -400.588089) (xy 392.636687 -400.552398) (xy 392.682538 -400.522932) (xy 392.732115 -400.500292)
			(xy 392.784411 -400.484938) (xy 392.838359 -400.477183) (xy 392.86561 -400.47672) (xy 393.72921 -400.47672)
			(xy 393.756463 -400.477151) (xy 393.810413 -400.484909) (xy 393.862711 -400.500266) (xy 393.91229 -400.522909)
			(xy 393.958143 -400.552378) (xy 393.999335 -400.588072) (xy 394.035028 -400.629265) (xy 394.064496 -400.675118)
			(xy 394.087138 -400.724699) (xy 394.102493 -400.776996) (xy 394.11025 -400.830947) (xy 394.11025 -400.885447)
			(xy 395.547906 -400.885447) (xy 395.547906 -400.830953) (xy 395.555661 -400.777014) (xy 395.571012 -400.724727)
			(xy 395.593648 -400.675157) (xy 395.623107 -400.629312) (xy 395.658791 -400.588126) (xy 395.699972 -400.552437)
			(xy 395.745813 -400.522972) (xy 395.79538 -400.50033) (xy 395.847665 -400.484971) (xy 395.901603 -400.47721)
			(xy 395.92885 -400.47672) (xy 396.79245 -400.47672) (xy 396.819707 -400.477124) (xy 396.873668 -400.484875)
			(xy 396.925975 -400.500228) (xy 396.975565 -400.522869) (xy 397.021428 -400.552338) (xy 397.06263 -400.588035)
			(xy 397.098332 -400.629232) (xy 397.127807 -400.675091) (xy 397.150454 -400.724678) (xy 397.165814 -400.776983)
			(xy 397.173573 -400.830943) (xy 397.173573 -400.885449) (xy 398.611106 -400.885449) (xy 398.611106 -400.830951)
			(xy 398.618862 -400.777008) (xy 398.634215 -400.724718) (xy 398.656854 -400.675145) (xy 398.686317 -400.629299)
			(xy 398.722005 -400.588112) (xy 398.763191 -400.552423) (xy 398.809037 -400.522959) (xy 398.858609 -400.500319)
			(xy 398.910899 -400.484964) (xy 398.964841 -400.477207) (xy 398.99209 -400.47672) (xy 399.85569 -400.47672)
			(xy 399.882945 -400.477126) (xy 399.936901 -400.484883) (xy 399.989204 -400.500239) (xy 400.038789 -400.522883)
			(xy 400.084647 -400.552352) (xy 400.125844 -400.588049) (xy 400.161542 -400.629245) (xy 400.191013 -400.675102)
			(xy 400.213658 -400.724686) (xy 400.229015 -400.776989) (xy 400.236773 -400.830945) (xy 400.236773 -400.885452)
			(xy 401.674283 -400.885452) (xy 401.674283 -400.830948) (xy 401.682041 -400.776998) (xy 401.697397 -400.724702)
			(xy 401.72004 -400.675123) (xy 401.749509 -400.629272) (xy 401.785203 -400.588082) (xy 401.826396 -400.552391)
			(xy 401.87225 -400.522926) (xy 401.92183 -400.500286) (xy 401.974128 -400.484934) (xy 402.028078 -400.477181)
			(xy 402.05533 -400.47672) (xy 402.91893 -400.47672) (xy 402.946182 -400.477152) (xy 403.00013 -400.484912)
			(xy 403.052425 -400.500271) (xy 403.102002 -400.522916) (xy 403.147852 -400.552385) (xy 403.189042 -400.588079)
			(xy 403.224733 -400.629272) (xy 403.254199 -400.675124) (xy 403.276839 -400.724703) (xy 403.292194 -400.776999)
			(xy 403.29995 -400.830948) (xy 403.29995 -400.885448) (xy 404.737606 -400.885448) (xy 404.737606 -400.830952)
			(xy 404.745361 -400.777011) (xy 404.760714 -400.724723) (xy 404.783351 -400.675151) (xy 404.812812 -400.629306)
			(xy 404.848498 -400.588119) (xy 404.889681 -400.55243) (xy 404.935525 -400.522965) (xy 404.985094 -400.500324)
			(xy 405.037382 -400.484968) (xy 405.091322 -400.477208) (xy 405.11857 -400.47672) (xy 405.98217 -400.47672)
			(xy 406.009426 -400.477125) (xy 406.063384 -400.484879) (xy 406.11569 -400.500234) (xy 406.165277 -400.522876)
			(xy 406.211138 -400.552345) (xy 406.252337 -400.588042) (xy 406.288037 -400.629238) (xy 406.31751 -400.675096)
			(xy 406.340156 -400.724682) (xy 406.355515 -400.776986) (xy 406.363273 -400.830944) (xy 406.363273 -400.885451)
			(xy 407.800783 -400.885451) (xy 407.800783 -400.830949) (xy 407.80854 -400.777001) (xy 407.823895 -400.724706)
			(xy 407.846537 -400.675129) (xy 407.876004 -400.629279) (xy 407.911696 -400.588089) (xy 407.952887 -400.552398)
			(xy 407.998738 -400.522932) (xy 408.048315 -400.500292) (xy 408.100611 -400.484938) (xy 408.154559 -400.477183)
			(xy 408.18181 -400.47672) (xy 409.04541 -400.47672) (xy 409.072663 -400.477151) (xy 409.126613 -400.484909)
			(xy 409.178911 -400.500266) (xy 409.22849 -400.522909) (xy 409.274343 -400.552378) (xy 409.315535 -400.588072)
			(xy 409.351228 -400.629265) (xy 409.380696 -400.675118) (xy 409.403338 -400.724699) (xy 409.418693 -400.776996)
			(xy 409.42645 -400.830947) (xy 409.42645 -400.885447) (xy 410.864106 -400.885447) (xy 410.864106 -400.830953)
			(xy 410.871861 -400.777014) (xy 410.887212 -400.724727) (xy 410.909848 -400.675157) (xy 410.939307 -400.629312)
			(xy 410.974991 -400.588126) (xy 411.016172 -400.552437) (xy 411.062013 -400.522972) (xy 411.11158 -400.50033)
			(xy 411.163865 -400.484971) (xy 411.217803 -400.47721) (xy 411.24505 -400.47672) (xy 412.10865 -400.47672)
			(xy 412.135907 -400.477124) (xy 412.189868 -400.484875) (xy 412.242175 -400.500228) (xy 412.291765 -400.522869)
			(xy 412.337628 -400.552338) (xy 412.37883 -400.588035) (xy 412.414532 -400.629232) (xy 412.444007 -400.675091)
			(xy 412.466654 -400.724678) (xy 412.482014 -400.776983) (xy 412.489773 -400.830943) (xy 412.489773 -400.885449)
			(xy 413.927306 -400.885449) (xy 413.927306 -400.830951) (xy 413.935062 -400.777008) (xy 413.950415 -400.724718)
			(xy 413.973054 -400.675145) (xy 414.002517 -400.629299) (xy 414.038205 -400.588112) (xy 414.079391 -400.552423)
			(xy 414.125237 -400.522959) (xy 414.174809 -400.500319) (xy 414.227099 -400.484964) (xy 414.281041 -400.477207)
			(xy 414.30829 -400.47672) (xy 415.17189 -400.47672) (xy 415.199145 -400.477126) (xy 415.253101 -400.484883)
			(xy 415.305404 -400.500239) (xy 415.354989 -400.522883) (xy 415.400847 -400.552352) (xy 415.442044 -400.588049)
			(xy 415.477742 -400.629245) (xy 415.507213 -400.675102) (xy 415.529858 -400.724686) (xy 415.545215 -400.776989)
			(xy 415.552973 -400.830945) (xy 415.552973 -400.885452) (xy 416.990483 -400.885452) (xy 416.990483 -400.830948)
			(xy 416.998241 -400.776998) (xy 417.013597 -400.724702) (xy 417.03624 -400.675123) (xy 417.065709 -400.629272)
			(xy 417.101403 -400.588082) (xy 417.142596 -400.552391) (xy 417.18845 -400.522926) (xy 417.23803 -400.500286)
			(xy 417.290328 -400.484934) (xy 417.344278 -400.477181) (xy 417.37153 -400.47672) (xy 418.23513 -400.47672)
			(xy 418.262382 -400.477152) (xy 418.31633 -400.484912) (xy 418.368625 -400.500271) (xy 418.418202 -400.522916)
			(xy 418.464052 -400.552385) (xy 418.505242 -400.588079) (xy 418.540933 -400.629272) (xy 418.570399 -400.675124)
			(xy 418.593039 -400.724703) (xy 418.608394 -400.776999) (xy 418.61615 -400.830948) (xy 418.61615 -400.885452)
			(xy 418.608394 -400.939401) (xy 418.593039 -400.991697) (xy 418.570399 -401.041276) (xy 418.540933 -401.087128)
			(xy 418.505242 -401.128321) (xy 418.464052 -401.164015) (xy 418.418202 -401.193484) (xy 418.368625 -401.216129)
			(xy 418.31633 -401.231488) (xy 418.262382 -401.239248) (xy 418.23513 -401.239736) (xy 417.37153 -401.239736)
			(xy 417.344278 -401.239219) (xy 417.290328 -401.231466) (xy 417.23803 -401.216114) (xy 417.18845 -401.193474)
			(xy 417.142596 -401.164009) (xy 417.101403 -401.128318) (xy 417.065709 -401.087128) (xy 417.03624 -401.041277)
			(xy 417.013597 -400.991698) (xy 416.998241 -400.939402) (xy 416.990483 -400.885452) (xy 415.552973 -400.885452)
			(xy 415.552973 -400.885455) (xy 415.545215 -400.939411) (xy 415.529858 -400.991714) (xy 415.507213 -401.041298)
			(xy 415.477742 -401.087155) (xy 415.442044 -401.128351) (xy 415.400847 -401.164048) (xy 415.354989 -401.193517)
			(xy 415.305404 -401.216161) (xy 415.253101 -401.231517) (xy 415.199145 -401.239274) (xy 415.17189 -401.239736)
			(xy 414.30829 -401.239736) (xy 414.281041 -401.239193) (xy 414.227099 -401.231436) (xy 414.174809 -401.216081)
			(xy 414.125237 -401.193441) (xy 414.079391 -401.163977) (xy 414.038205 -401.128288) (xy 414.002517 -401.087101)
			(xy 413.973054 -401.041255) (xy 413.950415 -400.991682) (xy 413.935062 -400.939392) (xy 413.927306 -400.885449)
			(xy 412.489773 -400.885449) (xy 412.489773 -400.885457) (xy 412.482014 -400.939416) (xy 412.466654 -400.991722)
			(xy 412.444007 -401.041309) (xy 412.414532 -401.087168) (xy 412.37883 -401.128365) (xy 412.337628 -401.164062)
			(xy 412.291765 -401.193531) (xy 412.242175 -401.216172) (xy 412.189868 -401.231525) (xy 412.135907 -401.239276)
			(xy 412.10865 -401.239736) (xy 411.24505 -401.239736) (xy 411.217803 -401.23919) (xy 411.163865 -401.231429)
			(xy 411.11158 -401.21607) (xy 411.062013 -401.193428) (xy 411.016172 -401.163963) (xy 410.974991 -401.128274)
			(xy 410.939307 -401.087088) (xy 410.909848 -401.041243) (xy 410.887212 -400.991673) (xy 410.871861 -400.939386)
			(xy 410.864106 -400.885447) (xy 409.42645 -400.885447) (xy 409.42645 -400.885453) (xy 409.418693 -400.939404)
			(xy 409.403338 -400.991701) (xy 409.380696 -401.041282) (xy 409.351228 -401.087135) (xy 409.315535 -401.128328)
			(xy 409.274343 -401.164022) (xy 409.22849 -401.193491) (xy 409.178911 -401.216134) (xy 409.126613 -401.231491)
			(xy 409.072663 -401.239249) (xy 409.04541 -401.239736) (xy 408.18181 -401.239736) (xy 408.154559 -401.239217)
			(xy 408.100611 -401.231462) (xy 408.048315 -401.216108) (xy 407.998738 -401.193468) (xy 407.952887 -401.164002)
			(xy 407.911696 -401.128311) (xy 407.876004 -401.087121) (xy 407.846537 -401.041271) (xy 407.823895 -400.991694)
			(xy 407.80854 -400.939399) (xy 407.800783 -400.885451) (xy 406.363273 -400.885451) (xy 406.363273 -400.885456)
			(xy 406.355515 -400.939414) (xy 406.340156 -400.991718) (xy 406.31751 -401.041304) (xy 406.288037 -401.087162)
			(xy 406.252337 -401.128358) (xy 406.211138 -401.164055) (xy 406.165277 -401.193524) (xy 406.11569 -401.216166)
			(xy 406.063384 -401.231521) (xy 406.009426 -401.239275) (xy 405.98217 -401.239736) (xy 405.11857 -401.239736)
			(xy 405.091322 -401.239192) (xy 405.037382 -401.231432) (xy 404.985094 -401.216076) (xy 404.935525 -401.193435)
			(xy 404.889682 -401.16397) (xy 404.848498 -401.128281) (xy 404.812812 -401.087094) (xy 404.783351 -401.041249)
			(xy 404.760714 -400.991677) (xy 404.745361 -400.939389) (xy 404.737606 -400.885448) (xy 403.29995 -400.885448)
			(xy 403.29995 -400.885452) (xy 403.292194 -400.939401) (xy 403.276839 -400.991697) (xy 403.254199 -401.041276)
			(xy 403.224733 -401.087128) (xy 403.189042 -401.128321) (xy 403.147852 -401.164015) (xy 403.102002 -401.193484)
			(xy 403.052425 -401.216129) (xy 403.00013 -401.231488) (xy 402.946182 -401.239248) (xy 402.91893 -401.239736)
			(xy 402.05533 -401.239736) (xy 402.028078 -401.239219) (xy 401.974128 -401.231466) (xy 401.92183 -401.216114)
			(xy 401.87225 -401.193474) (xy 401.826396 -401.164009) (xy 401.785203 -401.128318) (xy 401.749509 -401.087128)
			(xy 401.72004 -401.041277) (xy 401.697397 -400.991698) (xy 401.682041 -400.939402) (xy 401.674283 -400.885452)
			(xy 400.236773 -400.885452) (xy 400.236773 -400.885455) (xy 400.229015 -400.939411) (xy 400.213658 -400.991714)
			(xy 400.191013 -401.041298) (xy 400.161542 -401.087155) (xy 400.125844 -401.128351) (xy 400.084647 -401.164048)
			(xy 400.038789 -401.193517) (xy 399.989204 -401.216161) (xy 399.936901 -401.231517) (xy 399.882945 -401.239274)
			(xy 399.85569 -401.239736) (xy 398.99209 -401.239736) (xy 398.964841 -401.239193) (xy 398.910899 -401.231436)
			(xy 398.858609 -401.216081) (xy 398.809037 -401.193441) (xy 398.763191 -401.163977) (xy 398.722005 -401.128288)
			(xy 398.686317 -401.087101) (xy 398.656854 -401.041255) (xy 398.634215 -400.991682) (xy 398.618862 -400.939392)
			(xy 398.611106 -400.885449) (xy 397.173573 -400.885449) (xy 397.173573 -400.885457) (xy 397.165814 -400.939416)
			(xy 397.150454 -400.991722) (xy 397.127807 -401.041309) (xy 397.098332 -401.087168) (xy 397.06263 -401.128365)
			(xy 397.021428 -401.164062) (xy 396.975565 -401.193531) (xy 396.925975 -401.216172) (xy 396.873668 -401.231525)
			(xy 396.819707 -401.239276) (xy 396.79245 -401.239736) (xy 395.92885 -401.239736) (xy 395.901603 -401.23919)
			(xy 395.847665 -401.231429) (xy 395.79538 -401.21607) (xy 395.745813 -401.193428) (xy 395.699972 -401.163963)
			(xy 395.658791 -401.128274) (xy 395.623107 -401.087088) (xy 395.593648 -401.041243) (xy 395.571012 -400.991673)
			(xy 395.555661 -400.939386) (xy 395.547906 -400.885447) (xy 394.11025 -400.885447) (xy 394.11025 -400.885453)
			(xy 394.102493 -400.939404) (xy 394.087138 -400.991701) (xy 394.064496 -401.041282) (xy 394.035028 -401.087135)
			(xy 393.999335 -401.128328) (xy 393.958143 -401.164022) (xy 393.91229 -401.193491) (xy 393.862711 -401.216134)
			(xy 393.810413 -401.231491) (xy 393.756463 -401.239249) (xy 393.72921 -401.239736) (xy 392.86561 -401.239736)
			(xy 392.838359 -401.239217) (xy 392.784411 -401.231462) (xy 392.732115 -401.216108) (xy 392.682538 -401.193468)
			(xy 392.636687 -401.164002) (xy 392.595496 -401.128311) (xy 392.559804 -401.087121) (xy 392.530337 -401.041271)
			(xy 392.507695 -400.991694) (xy 392.49234 -400.939399) (xy 392.484583 -400.885451) (xy 391.047073 -400.885451)
			(xy 391.047073 -400.885456) (xy 391.039315 -400.939414) (xy 391.023956 -400.991718) (xy 391.00131 -401.041304)
			(xy 390.971837 -401.087162) (xy 390.936137 -401.128358) (xy 390.894938 -401.164055) (xy 390.849077 -401.193524)
			(xy 390.79949 -401.216166) (xy 390.747184 -401.231521) (xy 390.693226 -401.239275) (xy 390.66597 -401.239736)
			(xy 389.80237 -401.239736) (xy 389.775122 -401.239192) (xy 389.721182 -401.231432) (xy 389.668894 -401.216076)
			(xy 389.619325 -401.193435) (xy 389.573482 -401.16397) (xy 389.532298 -401.128281) (xy 389.496612 -401.087094)
			(xy 389.467151 -401.041249) (xy 389.444514 -400.991677) (xy 389.429161 -400.939389) (xy 389.421406 -400.885448)
			(xy 387.98375 -400.885448) (xy 387.98375 -400.885452) (xy 387.975994 -400.939401) (xy 387.960639 -400.991697)
			(xy 387.937999 -401.041276) (xy 387.908533 -401.087128) (xy 387.872842 -401.128321) (xy 387.831652 -401.164015)
			(xy 387.785802 -401.193484) (xy 387.736225 -401.216129) (xy 387.68393 -401.231488) (xy 387.629982 -401.239248)
			(xy 387.60273 -401.239736) (xy 386.73913 -401.239736) (xy 386.711878 -401.239219) (xy 386.657928 -401.231466)
			(xy 386.60563 -401.216114) (xy 386.55605 -401.193474) (xy 386.510196 -401.164009) (xy 386.469003 -401.128318)
			(xy 386.433309 -401.087128) (xy 386.40384 -401.041277) (xy 386.381197 -400.991698) (xy 386.365841 -400.939402)
			(xy 386.358083 -400.885452) (xy 384.920573 -400.885452) (xy 384.920573 -400.885455) (xy 384.912815 -400.939411)
			(xy 384.897458 -400.991714) (xy 384.874813 -401.041298) (xy 384.845342 -401.087155) (xy 384.809644 -401.128351)
			(xy 384.768447 -401.164048) (xy 384.722589 -401.193517) (xy 384.673004 -401.216161) (xy 384.620701 -401.231517)
			(xy 384.566745 -401.239274) (xy 384.53949 -401.239736) (xy 383.67589 -401.239736) (xy 383.648641 -401.239193)
			(xy 383.594699 -401.231436) (xy 383.542409 -401.216081) (xy 383.492837 -401.193441) (xy 383.446991 -401.163977)
			(xy 383.405805 -401.128288) (xy 383.370117 -401.087101) (xy 383.340654 -401.041255) (xy 383.318015 -400.991682)
			(xy 383.302662 -400.939392) (xy 383.294906 -400.885449) (xy 381.857373 -400.885449) (xy 381.857373 -400.885457)
			(xy 381.849614 -400.939416) (xy 381.834254 -400.991722) (xy 381.811607 -401.041309) (xy 381.782132 -401.087168)
			(xy 381.74643 -401.128365) (xy 381.705228 -401.164062) (xy 381.659365 -401.193531) (xy 381.609775 -401.216172)
			(xy 381.557468 -401.231525) (xy 381.503507 -401.239276) (xy 381.47625 -401.239736) (xy 380.61265 -401.239736)
			(xy 380.585403 -401.23919) (xy 380.531465 -401.231429) (xy 380.47918 -401.21607) (xy 380.429613 -401.193428)
			(xy 380.383772 -401.163963) (xy 380.342591 -401.128274) (xy 380.306907 -401.087088) (xy 380.277448 -401.041243)
			(xy 380.254812 -400.991673) (xy 380.239461 -400.939386) (xy 380.231706 -400.885447) (xy 378.79405 -400.885447)
			(xy 378.79405 -400.885453) (xy 378.786293 -400.939404) (xy 378.770938 -400.991701) (xy 378.748296 -401.041282)
			(xy 378.718828 -401.087135) (xy 378.683135 -401.128328) (xy 378.641943 -401.164022) (xy 378.59609 -401.193491)
			(xy 378.546511 -401.216134) (xy 378.494213 -401.231491) (xy 378.440263 -401.239249) (xy 378.41301 -401.239736)
			(xy 377.54941 -401.239736) (xy 377.522159 -401.239217) (xy 377.468211 -401.231462) (xy 377.415915 -401.216108)
			(xy 377.366338 -401.193468) (xy 377.320487 -401.164002) (xy 377.279296 -401.128311) (xy 377.243604 -401.087121)
			(xy 377.214137 -401.041271) (xy 377.191495 -400.991694) (xy 377.17614 -400.939399) (xy 377.168383 -400.885451)
			(xy 375.730873 -400.885451) (xy 375.730873 -400.885456) (xy 375.723115 -400.939414) (xy 375.707756 -400.991718)
			(xy 375.68511 -401.041304) (xy 375.655637 -401.087162) (xy 375.619937 -401.128358) (xy 375.578738 -401.164055)
			(xy 375.532877 -401.193524) (xy 375.48329 -401.216166) (xy 375.430984 -401.231521) (xy 375.377026 -401.239275)
			(xy 375.34977 -401.239736) (xy 374.48617 -401.239736) (xy 374.458922 -401.239192) (xy 374.404982 -401.231432)
			(xy 374.352694 -401.216076) (xy 374.303125 -401.193435) (xy 374.257282 -401.16397) (xy 374.216098 -401.128281)
			(xy 374.180412 -401.087094) (xy 374.150951 -401.041249) (xy 374.128314 -400.991677) (xy 374.112961 -400.939389)
			(xy 374.105206 -400.885448) (xy 372.66755 -400.885448) (xy 372.66755 -400.885452) (xy 372.659794 -400.939401)
			(xy 372.644439 -400.991697) (xy 372.621799 -401.041276) (xy 372.592333 -401.087128) (xy 372.556642 -401.128321)
			(xy 372.515452 -401.164015) (xy 372.469602 -401.193484) (xy 372.420025 -401.216129) (xy 372.36773 -401.231488)
			(xy 372.313782 -401.239248) (xy 372.28653 -401.239736) (xy 371.42293 -401.239736) (xy 371.395678 -401.239219)
			(xy 371.341728 -401.231466) (xy 371.28943 -401.216114) (xy 371.23985 -401.193474) (xy 371.193996 -401.164009)
			(xy 371.152803 -401.128318) (xy 371.117109 -401.087128) (xy 371.08764 -401.041277) (xy 371.064997 -400.991698)
			(xy 371.049641 -400.939402) (xy 371.041883 -400.885452) (xy 351.173373 -400.885452) (xy 351.173373 -400.885455)
			(xy 351.165615 -400.939411) (xy 351.150257 -400.991714) (xy 351.127612 -401.041299) (xy 351.098141 -401.087156)
			(xy 351.062443 -401.128352) (xy 351.021246 -401.164048) (xy 350.975388 -401.193518) (xy 350.925803 -401.216162)
			(xy 350.8735 -401.231518) (xy 350.819543 -401.239274) (xy 350.792288 -401.239736) (xy 349.928688 -401.239736)
			(xy 349.901439 -401.239193) (xy 349.847497 -401.231436) (xy 349.795208 -401.216081) (xy 349.745636 -401.19344)
			(xy 349.69979 -401.163976) (xy 349.658604 -401.128287) (xy 349.622917 -401.0871) (xy 349.593454 -401.041254)
			(xy 349.570815 -400.991681) (xy 349.555462 -400.939391) (xy 349.547706 -400.885449) (xy 348.11005 -400.885449)
			(xy 348.11005 -400.885451) (xy 348.102294 -400.939399) (xy 348.086941 -400.991693) (xy 348.064301 -401.041271)
			(xy 348.034837 -401.087122) (xy 347.999148 -401.128314) (xy 347.957961 -401.164009) (xy 347.912113 -401.193478)
			(xy 347.862538 -401.216124) (xy 347.810245 -401.231484) (xy 347.756299 -401.239247) (xy 347.729048 -401.239736)
			(xy 346.865448 -401.239736) (xy 346.838195 -401.23922) (xy 346.784243 -401.231469) (xy 346.731943 -401.216118)
			(xy 346.68236 -401.19348) (xy 346.636505 -401.164016) (xy 346.595309 -401.128325) (xy 346.559613 -401.087134)
			(xy 346.530143 -401.041282) (xy 346.507498 -400.991702) (xy 346.492141 -400.939404) (xy 346.484383 -400.885453)
			(xy 345.04685 -400.885453) (xy 345.039093 -400.939404) (xy 345.023737 -400.991702) (xy 345.001095 -401.041282)
			(xy 344.971628 -401.087136) (xy 344.935934 -401.128329) (xy 344.894742 -401.164023) (xy 344.848889 -401.193491)
			(xy 344.799309 -401.216135) (xy 344.747012 -401.231492) (xy 344.693061 -401.23925) (xy 344.665808 -401.239736)
			(xy 343.802208 -401.239736) (xy 343.774957 -401.239217) (xy 343.721009 -401.231462) (xy 343.668714 -401.216108)
			(xy 343.619136 -401.193467) (xy 343.573286 -401.164002) (xy 343.532095 -401.128311) (xy 343.496403 -401.087121)
			(xy 343.466937 -401.041271) (xy 343.444295 -400.991694) (xy 343.42894 -400.939399) (xy 343.421183 -400.885451)
			(xy 341.983673 -400.885451) (xy 341.983673 -400.885456) (xy 341.975915 -400.939414) (xy 341.960556 -400.991718)
			(xy 341.937909 -401.041304) (xy 341.908436 -401.087162) (xy 341.872736 -401.128359) (xy 341.831537 -401.164055)
			(xy 341.785676 -401.193525) (xy 341.736088 -401.216167) (xy 341.683783 -401.231521) (xy 341.629824 -401.239275)
			(xy 341.602568 -401.239736) (xy 340.738968 -401.239736) (xy 340.71172 -401.239192) (xy 340.65778 -401.231432)
			(xy 340.605493 -401.216075) (xy 340.555924 -401.193434) (xy 340.510081 -401.163969) (xy 340.468897 -401.12828)
			(xy 340.433212 -401.087094) (xy 340.403751 -401.041248) (xy 340.381114 -400.991677) (xy 340.365761 -400.939389)
			(xy 340.358006 -400.885448) (xy 338.92035 -400.885448) (xy 338.92035 -400.885452) (xy 338.912594 -400.939401)
			(xy 338.897239 -400.991698) (xy 338.874598 -401.041277) (xy 338.845132 -401.087129) (xy 338.809441 -401.128321)
			(xy 338.768251 -401.164016) (xy 338.722401 -401.193485) (xy 338.672824 -401.216129) (xy 338.620529 -401.231488)
			(xy 338.56658 -401.239248) (xy 338.539328 -401.239736) (xy 337.675728 -401.239736) (xy 337.648476 -401.239219)
			(xy 337.594526 -401.231465) (xy 337.542228 -401.216113) (xy 337.492648 -401.193474) (xy 337.446795 -401.164009)
			(xy 337.405602 -401.128318) (xy 337.369908 -401.087127) (xy 337.34044 -401.041276) (xy 337.317797 -400.991698)
			(xy 337.30244 -400.939402) (xy 337.294683 -400.885452) (xy 335.857173 -400.885452) (xy 335.857173 -400.885455)
			(xy 335.849415 -400.939411) (xy 335.834057 -400.991714) (xy 335.811412 -401.041299) (xy 335.781941 -401.087156)
			(xy 335.746243 -401.128352) (xy 335.705046 -401.164048) (xy 335.659188 -401.193518) (xy 335.609603 -401.216162)
			(xy 335.5573 -401.231518) (xy 335.503343 -401.239274) (xy 335.476088 -401.239736) (xy 334.612488 -401.239736)
			(xy 334.585239 -401.239193) (xy 334.531297 -401.231436) (xy 334.479008 -401.216081) (xy 334.429436 -401.19344)
			(xy 334.38359 -401.163976) (xy 334.342404 -401.128287) (xy 334.306717 -401.0871) (xy 334.277254 -401.041254)
			(xy 334.254615 -400.991681) (xy 334.239262 -400.939391) (xy 334.231506 -400.885449) (xy 332.79385 -400.885449)
			(xy 332.79385 -400.885451) (xy 332.786094 -400.939399) (xy 332.770741 -400.991693) (xy 332.748101 -401.041271)
			(xy 332.718637 -401.087122) (xy 332.682948 -401.128314) (xy 332.641761 -401.164009) (xy 332.595913 -401.193478)
			(xy 332.546338 -401.216124) (xy 332.494045 -401.231484) (xy 332.440099 -401.239247) (xy 332.412848 -401.239736)
			(xy 331.549248 -401.239736) (xy 331.521995 -401.23922) (xy 331.468043 -401.231469) (xy 331.415743 -401.216118)
			(xy 331.36616 -401.19348) (xy 331.320305 -401.164016) (xy 331.279109 -401.128325) (xy 331.243413 -401.087134)
			(xy 331.213943 -401.041282) (xy 331.191298 -400.991702) (xy 331.175941 -400.939404) (xy 331.168183 -400.885453)
			(xy 329.73065 -400.885453) (xy 329.722893 -400.939404) (xy 329.707537 -400.991702) (xy 329.684895 -401.041282)
			(xy 329.655428 -401.087136) (xy 329.619734 -401.128329) (xy 329.578542 -401.164023) (xy 329.532689 -401.193491)
			(xy 329.483109 -401.216135) (xy 329.430812 -401.231492) (xy 329.376861 -401.23925) (xy 329.349608 -401.239736)
			(xy 328.486008 -401.239736) (xy 328.458757 -401.239217) (xy 328.404809 -401.231462) (xy 328.352514 -401.216108)
			(xy 328.302936 -401.193467) (xy 328.257086 -401.164002) (xy 328.215895 -401.128311) (xy 328.180203 -401.087121)
			(xy 328.150737 -401.041271) (xy 328.128095 -400.991694) (xy 328.11274 -400.939399) (xy 328.104983 -400.885451)
			(xy 326.667473 -400.885451) (xy 326.667473 -400.885456) (xy 326.659715 -400.939414) (xy 326.644356 -400.991718)
			(xy 326.621709 -401.041304) (xy 326.592236 -401.087162) (xy 326.556536 -401.128359) (xy 326.515337 -401.164055)
			(xy 326.469476 -401.193525) (xy 326.419888 -401.216167) (xy 326.367583 -401.231521) (xy 326.313624 -401.239275)
			(xy 326.286368 -401.239736) (xy 325.422768 -401.239736) (xy 325.39552 -401.239192) (xy 325.34158 -401.231432)
			(xy 325.289293 -401.216075) (xy 325.239724 -401.193434) (xy 325.193881 -401.163969) (xy 325.152697 -401.12828)
			(xy 325.117012 -401.087094) (xy 325.087551 -401.041248) (xy 325.064914 -400.991677) (xy 325.049561 -400.939389)
			(xy 325.041806 -400.885448) (xy 323.60415 -400.885448) (xy 323.60415 -400.885452) (xy 323.596394 -400.939401)
			(xy 323.581039 -400.991698) (xy 323.558398 -401.041277) (xy 323.528932 -401.087129) (xy 323.493241 -401.128321)
			(xy 323.452051 -401.164016) (xy 323.406201 -401.193485) (xy 323.356624 -401.216129) (xy 323.304329 -401.231488)
			(xy 323.25038 -401.239248) (xy 323.223128 -401.239736) (xy 322.359528 -401.239736) (xy 322.332276 -401.239219)
			(xy 322.278326 -401.231465) (xy 322.226028 -401.216113) (xy 322.176448 -401.193474) (xy 322.130595 -401.164009)
			(xy 322.089402 -401.128318) (xy 322.053708 -401.087127) (xy 322.02424 -401.041276) (xy 322.001597 -400.991698)
			(xy 321.98624 -400.939402) (xy 321.978483 -400.885452) (xy 320.540973 -400.885452) (xy 320.540973 -400.885455)
			(xy 320.533215 -400.939411) (xy 320.517857 -400.991714) (xy 320.495212 -401.041299) (xy 320.465741 -401.087156)
			(xy 320.430043 -401.128352) (xy 320.388846 -401.164048) (xy 320.342988 -401.193518) (xy 320.293403 -401.216162)
			(xy 320.2411 -401.231518) (xy 320.187143 -401.239274) (xy 320.159888 -401.239736) (xy 319.296288 -401.239736)
			(xy 319.269039 -401.239193) (xy 319.215097 -401.231436) (xy 319.162808 -401.216081) (xy 319.113236 -401.19344)
			(xy 319.06739 -401.163976) (xy 319.026204 -401.128287) (xy 318.990517 -401.0871) (xy 318.961054 -401.041254)
			(xy 318.938415 -400.991681) (xy 318.923062 -400.939391) (xy 318.915306 -400.885449) (xy 317.47765 -400.885449)
			(xy 317.47765 -400.885451) (xy 317.469894 -400.939399) (xy 317.454541 -400.991693) (xy 317.431901 -401.041271)
			(xy 317.402437 -401.087122) (xy 317.366748 -401.128314) (xy 317.325561 -401.164009) (xy 317.279713 -401.193478)
			(xy 317.230138 -401.216124) (xy 317.177845 -401.231484) (xy 317.123899 -401.239247) (xy 317.096648 -401.239736)
			(xy 316.233048 -401.239736) (xy 316.205795 -401.23922) (xy 316.151843 -401.231469) (xy 316.099543 -401.216118)
			(xy 316.04996 -401.19348) (xy 316.004105 -401.164016) (xy 315.962909 -401.128325) (xy 315.927213 -401.087134)
			(xy 315.897743 -401.041282) (xy 315.875098 -400.991702) (xy 315.859741 -400.939404) (xy 315.851983 -400.885453)
			(xy 314.41445 -400.885453) (xy 314.406693 -400.939404) (xy 314.391337 -400.991702) (xy 314.368695 -401.041282)
			(xy 314.339228 -401.087136) (xy 314.303534 -401.128329) (xy 314.262342 -401.164023) (xy 314.216489 -401.193491)
			(xy 314.166909 -401.216135) (xy 314.114612 -401.231492) (xy 314.060661 -401.23925) (xy 314.033408 -401.239736)
			(xy 313.169808 -401.239736) (xy 313.142557 -401.239217) (xy 313.088609 -401.231462) (xy 313.036314 -401.216108)
			(xy 312.986736 -401.193467) (xy 312.940886 -401.164002) (xy 312.899695 -401.128311) (xy 312.864003 -401.087121)
			(xy 312.834537 -401.041271) (xy 312.811895 -400.991694) (xy 312.79654 -400.939399) (xy 312.788783 -400.885451)
			(xy 311.351273 -400.885451) (xy 311.351273 -400.885456) (xy 311.343515 -400.939414) (xy 311.328156 -400.991718)
			(xy 311.305509 -401.041304) (xy 311.276036 -401.087162) (xy 311.240336 -401.128359) (xy 311.199137 -401.164055)
			(xy 311.153276 -401.193525) (xy 311.103688 -401.216167) (xy 311.051383 -401.231521) (xy 310.997424 -401.239275)
			(xy 310.970168 -401.239736) (xy 310.106568 -401.239736) (xy 310.07932 -401.239192) (xy 310.02538 -401.231432)
			(xy 309.973093 -401.216075) (xy 309.923524 -401.193434) (xy 309.877681 -401.163969) (xy 309.836497 -401.12828)
			(xy 309.800812 -401.087094) (xy 309.771351 -401.041248) (xy 309.748714 -400.991677) (xy 309.733361 -400.939389)
			(xy 309.725606 -400.885448) (xy 308.28795 -400.885448) (xy 308.28795 -400.885452) (xy 308.280194 -400.939401)
			(xy 308.264839 -400.991698) (xy 308.242198 -401.041277) (xy 308.212732 -401.087129) (xy 308.177041 -401.128321)
			(xy 308.135851 -401.164016) (xy 308.090001 -401.193485) (xy 308.040424 -401.216129) (xy 307.988129 -401.231488)
			(xy 307.93418 -401.239248) (xy 307.906928 -401.239736) (xy 307.043328 -401.239736) (xy 307.016076 -401.239219)
			(xy 306.962126 -401.231465) (xy 306.909828 -401.216113) (xy 306.860248 -401.193474) (xy 306.814395 -401.164009)
			(xy 306.773202 -401.128318) (xy 306.737508 -401.087127) (xy 306.70804 -401.041276) (xy 306.685397 -400.991698)
			(xy 306.67004 -400.939402) (xy 306.662283 -400.885452) (xy 305.224773 -400.885452) (xy 305.224773 -400.885455)
			(xy 305.217015 -400.939411) (xy 305.201657 -400.991714) (xy 305.179012 -401.041299) (xy 305.149541 -401.087156)
			(xy 305.113843 -401.128352) (xy 305.072646 -401.164048) (xy 305.026788 -401.193518) (xy 304.977203 -401.216162)
			(xy 304.9249 -401.231518) (xy 304.870943 -401.239274) (xy 304.843688 -401.239736) (xy 303.980088 -401.239736)
			(xy 303.952839 -401.239193) (xy 303.898897 -401.231436) (xy 303.846608 -401.216081) (xy 303.797036 -401.19344)
			(xy 303.75119 -401.163976) (xy 303.710004 -401.128287) (xy 303.674317 -401.0871) (xy 303.644854 -401.041254)
			(xy 303.622215 -400.991681) (xy 303.606862 -400.939391) (xy 303.599106 -400.885449) (xy 280.76398 -400.885449)
			(xy 280.76398 -402.0155) (xy 287.066441 -402.0155) (xy 287.070455 -401.951698) (xy 287.082434 -401.888902)
			(xy 287.102189 -401.828103) (xy 287.129408 -401.77026) (xy 287.163662 -401.716283) (xy 287.204411 -401.667026)
			(xy 287.251013 -401.623264) (xy 287.302731 -401.585688) (xy 287.358752 -401.55489) (xy 287.418191 -401.531357)
			(xy 287.48011 -401.515458) (xy 287.543534 -401.507446) (xy 287.575498 -401.506944) (xy 287.575752 -401.506944)
			(xy 287.607498 -401.507464) (xy 287.670494 -401.515393) (xy 287.732014 -401.531096) (xy 287.791102 -401.55433)
			(xy 287.846842 -401.584733) (xy 287.898367 -401.621834) (xy 287.921954 -401.643088) (xy 287.929217 -401.649272)
			(xy 287.946967 -401.656223) (xy 287.966029 -401.656223) (xy 287.983779 -401.649272) (xy 287.991042 -401.643088)
			(xy 288.014631 -401.621832) (xy 288.06614 -401.5847) (xy 288.121874 -401.554276) (xy 288.180965 -401.531035)
			(xy 288.242492 -401.515338) (xy 288.305495 -401.507431) (xy 288.337244 -401.506944) (xy 288.337498 -401.506944)
			(xy 288.369457 -401.507521) (xy 288.432872 -401.515532) (xy 288.494783 -401.531427) (xy 288.554213 -401.554957)
			(xy 288.610226 -401.58575) (xy 288.661937 -401.623321) (xy 288.708532 -401.667076) (xy 288.749276 -401.716326)
			(xy 288.783525 -401.770295) (xy 288.810741 -401.82813) (xy 288.830493 -401.888921) (xy 288.84247 -401.951707)
			(xy 288.846484 -402.0155) (xy 289.606441 -402.0155) (xy 289.610455 -401.951698) (xy 289.622434 -401.888902)
			(xy 289.642189 -401.828103) (xy 289.669408 -401.77026) (xy 289.703662 -401.716283) (xy 289.744411 -401.667026)
			(xy 289.791013 -401.623264) (xy 289.842731 -401.585688) (xy 289.898752 -401.55489) (xy 289.958191 -401.531357)
			(xy 290.02011 -401.515458) (xy 290.083534 -401.507446) (xy 290.115498 -401.506944) (xy 290.115752 -401.506944)
			(xy 290.147498 -401.507464) (xy 290.210494 -401.515393) (xy 290.272014 -401.531096) (xy 290.331102 -401.55433)
			(xy 290.386842 -401.584733) (xy 290.438367 -401.621834) (xy 290.461954 -401.643088) (xy 290.469217 -401.649272)
			(xy 290.486967 -401.656223) (xy 290.506029 -401.656223) (xy 290.523779 -401.649272) (xy 290.531042 -401.643088)
			(xy 290.554631 -401.621832) (xy 290.60614 -401.5847) (xy 290.661874 -401.554276) (xy 290.720965 -401.531035)
			(xy 290.782492 -401.515338) (xy 290.845495 -401.507431) (xy 290.877244 -401.506944) (xy 290.877498 -401.506944)
			(xy 290.909457 -401.507521) (xy 290.972872 -401.515532) (xy 291.034783 -401.531427) (xy 291.094213 -401.554957)
			(xy 291.150226 -401.58575) (xy 291.201937 -401.623321) (xy 291.248532 -401.667076) (xy 291.289276 -401.716326)
			(xy 291.323525 -401.770295) (xy 291.350741 -401.82813) (xy 291.370493 -401.888921) (xy 291.38247 -401.951707)
			(xy 291.386484 -402.0155) (xy 292.146441 -402.0155) (xy 292.150455 -401.951698) (xy 292.162434 -401.888902)
			(xy 292.182189 -401.828103) (xy 292.209408 -401.77026) (xy 292.243662 -401.716283) (xy 292.284411 -401.667026)
			(xy 292.331013 -401.623264) (xy 292.382731 -401.585688) (xy 292.438752 -401.55489) (xy 292.498191 -401.531357)
			(xy 292.56011 -401.515458) (xy 292.623534 -401.507446) (xy 292.655498 -401.506944) (xy 292.655752 -401.506944)
			(xy 292.687498 -401.507464) (xy 292.750494 -401.515393) (xy 292.812014 -401.531096) (xy 292.871102 -401.55433)
			(xy 292.926842 -401.584733) (xy 292.978367 -401.621834) (xy 293.001954 -401.643088) (xy 293.009217 -401.649272)
			(xy 293.026967 -401.656223) (xy 293.046029 -401.656223) (xy 293.063779 -401.649272) (xy 293.071042 -401.643088)
			(xy 293.094631 -401.621832) (xy 293.14614 -401.5847) (xy 293.201874 -401.554276) (xy 293.260965 -401.531035)
			(xy 293.322492 -401.515338) (xy 293.385495 -401.507431) (xy 293.417244 -401.506944) (xy 293.417498 -401.506944)
			(xy 293.449457 -401.507521) (xy 293.512872 -401.515532) (xy 293.574783 -401.531427) (xy 293.634213 -401.554957)
			(xy 293.690226 -401.58575) (xy 293.741937 -401.623321) (xy 293.788532 -401.667076) (xy 293.829276 -401.716326)
			(xy 293.863525 -401.770295) (xy 293.890741 -401.82813) (xy 293.910493 -401.888921) (xy 293.92247 -401.951707)
			(xy 293.926484 -402.0155) (xy 294.53602 -402.0155) (xy 294.540035 -401.951693) (xy 294.552015 -401.888892)
			(xy 294.571773 -401.828089) (xy 294.598995 -401.770241) (xy 294.633253 -401.716261) (xy 294.674007 -401.667001)
			(xy 294.720613 -401.623237) (xy 294.772338 -401.58566) (xy 294.828364 -401.554862) (xy 294.887809 -401.531329)
			(xy 294.949734 -401.515433) (xy 295.013163 -401.507423) (xy 295.04513 -401.506944) (xy 295.045384 -401.506944)
			(xy 295.077131 -401.507444) (xy 295.140127 -401.515377) (xy 295.201647 -401.531084) (xy 295.260736 -401.554322)
			(xy 295.316476 -401.584728) (xy 295.368 -401.621832) (xy 295.391586 -401.643088) (xy 295.398849 -401.649272)
			(xy 295.416599 -401.656223) (xy 295.435661 -401.656223) (xy 295.453411 -401.649272) (xy 295.460674 -401.643088)
			(xy 295.48425 -401.621817) (xy 295.535761 -401.584686) (xy 295.591498 -401.554265) (xy 295.650592 -401.531026)
			(xy 295.712121 -401.515332) (xy 295.775126 -401.507429) (xy 295.806876 -401.506944) (xy 295.80713 -401.506944)
			(xy 295.839087 -401.507544) (xy 295.902496 -401.515558) (xy 295.964401 -401.531455) (xy 296.023825 -401.554986)
			(xy 296.079832 -401.585779) (xy 296.131538 -401.623348) (xy 296.178128 -401.667102) (xy 296.218866 -401.716349)
			(xy 296.253112 -401.770314) (xy 296.280324 -401.828145) (xy 296.300074 -401.888931) (xy 296.312049 -401.951712)
			(xy 296.316063 -402.0155) (xy 297.07602 -402.0155) (xy 297.080035 -401.951693) (xy 297.092015 -401.888892)
			(xy 297.111773 -401.828089) (xy 297.138995 -401.770241) (xy 297.173253 -401.716261) (xy 297.214007 -401.667001)
			(xy 297.260613 -401.623237) (xy 297.312338 -401.58566) (xy 297.368364 -401.554862) (xy 297.427809 -401.531329)
			(xy 297.489734 -401.515433) (xy 297.553163 -401.507423) (xy 297.58513 -401.506944) (xy 297.585384 -401.506944)
			(xy 297.617131 -401.507444) (xy 297.680127 -401.515377) (xy 297.741647 -401.531084) (xy 297.800736 -401.554322)
			(xy 297.856476 -401.584728) (xy 297.908 -401.621832) (xy 297.931586 -401.643088) (xy 297.938849 -401.649272)
			(xy 297.956599 -401.656223) (xy 297.975661 -401.656223) (xy 297.993411 -401.649272) (xy 298.000674 -401.643088)
			(xy 298.02425 -401.621817) (xy 298.075761 -401.584686) (xy 298.131498 -401.554265) (xy 298.190592 -401.531026)
			(xy 298.252121 -401.515332) (xy 298.315126 -401.507429) (xy 298.346876 -401.506944) (xy 298.34713 -401.506944)
			(xy 298.379087 -401.507544) (xy 298.442496 -401.515558) (xy 298.504401 -401.531455) (xy 298.563825 -401.554986)
			(xy 298.619832 -401.585779) (xy 298.671538 -401.623348) (xy 298.718128 -401.667102) (xy 298.758866 -401.716349)
			(xy 298.793112 -401.770314) (xy 298.820324 -401.828145) (xy 298.840074 -401.888931) (xy 298.852049 -401.951712)
			(xy 298.856063 -402.0155) (xy 298.852049 -402.079288) (xy 298.840074 -402.142069) (xy 298.820324 -402.202855)
			(xy 298.793112 -402.260686) (xy 298.758866 -402.314651) (xy 298.718128 -402.363898) (xy 298.671538 -402.407652)
			(xy 298.619832 -402.445221) (xy 298.563825 -402.476014) (xy 298.504401 -402.499545) (xy 298.442496 -402.515442)
			(xy 298.379087 -402.523456) (xy 298.34713 -402.52396) (xy 298.346876 -402.52396) (xy 298.315131 -402.523422)
			(xy 298.252136 -402.515497) (xy 298.190616 -402.499797) (xy 298.131527 -402.476566) (xy 298.075787 -402.446166)
			(xy 298.024261 -402.409069) (xy 298.000674 -402.387816) (xy 297.993411 -402.381632) (xy 297.975661 -402.374681)
			(xy 297.956599 -402.374681) (xy 297.938849 -402.381632) (xy 297.931586 -402.387816) (xy 297.908028 -402.409107)
			(xy 297.856512 -402.446235) (xy 297.800771 -402.476654) (xy 297.741674 -402.499889) (xy 297.680142 -402.515579)
			(xy 297.617135 -402.523478) (xy 297.585384 -402.52396) (xy 297.58513 -402.52396) (xy 297.553163 -402.523577)
			(xy 297.489734 -402.515567) (xy 297.427809 -402.499671) (xy 297.368364 -402.476138) (xy 297.312338 -402.44534)
			(xy 297.260613 -402.407763) (xy 297.214007 -402.363999) (xy 297.173253 -402.314739) (xy 297.138995 -402.260759)
			(xy 297.111773 -402.202911) (xy 297.092015 -402.142108) (xy 297.080035 -402.079307) (xy 297.07602 -402.0155)
			(xy 296.316063 -402.0155) (xy 296.312049 -402.079288) (xy 296.300074 -402.142069) (xy 296.280324 -402.202855)
			(xy 296.253112 -402.260686) (xy 296.218866 -402.314651) (xy 296.178128 -402.363898) (xy 296.131538 -402.407652)
			(xy 296.079832 -402.445221) (xy 296.023825 -402.476014) (xy 295.964401 -402.499545) (xy 295.902496 -402.515442)
			(xy 295.839087 -402.523456) (xy 295.80713 -402.52396) (xy 295.806876 -402.52396) (xy 295.775131 -402.523422)
			(xy 295.712136 -402.515497) (xy 295.650616 -402.499797) (xy 295.591527 -402.476566) (xy 295.535787 -402.446166)
			(xy 295.484261 -402.409069) (xy 295.460674 -402.387816) (xy 295.453411 -402.381632) (xy 295.435661 -402.374681)
			(xy 295.416599 -402.374681) (xy 295.398849 -402.381632) (xy 295.391586 -402.387816) (xy 295.368028 -402.409107)
			(xy 295.316512 -402.446235) (xy 295.260771 -402.476654) (xy 295.201674 -402.499889) (xy 295.140142 -402.515579)
			(xy 295.077135 -402.523478) (xy 295.045384 -402.52396) (xy 295.04513 -402.52396) (xy 295.013163 -402.523577)
			(xy 294.949734 -402.515567) (xy 294.887809 -402.499671) (xy 294.828364 -402.476138) (xy 294.772338 -402.44534)
			(xy 294.720613 -402.407763) (xy 294.674007 -402.363999) (xy 294.633253 -402.314739) (xy 294.598995 -402.260759)
			(xy 294.571773 -402.202911) (xy 294.552015 -402.142108) (xy 294.540035 -402.079307) (xy 294.53602 -402.0155)
			(xy 293.926484 -402.0155) (xy 293.92247 -402.079293) (xy 293.910493 -402.142079) (xy 293.890741 -402.20287)
			(xy 293.863525 -402.260705) (xy 293.829276 -402.314674) (xy 293.788532 -402.363924) (xy 293.741937 -402.407679)
			(xy 293.690226 -402.44525) (xy 293.634213 -402.476043) (xy 293.574783 -402.499573) (xy 293.512872 -402.515468)
			(xy 293.449457 -402.523479) (xy 293.417498 -402.52396) (xy 293.417244 -402.52396) (xy 293.385498 -402.523442)
			(xy 293.322502 -402.515512) (xy 293.260982 -402.499809) (xy 293.201894 -402.476575) (xy 293.146154 -402.446171)
			(xy 293.094629 -402.40907) (xy 293.071042 -402.387816) (xy 293.063779 -402.381632) (xy 293.046029 -402.374681)
			(xy 293.026967 -402.374681) (xy 293.009217 -402.381632) (xy 293.001954 -402.387816) (xy 292.978367 -402.409074)
			(xy 292.926858 -402.446206) (xy 292.871123 -402.47663) (xy 292.812032 -402.499871) (xy 292.750504 -402.515567)
			(xy 292.687501 -402.523474) (xy 292.655752 -402.52396) (xy 292.655498 -402.52396) (xy 292.623534 -402.523554)
			(xy 292.56011 -402.515542) (xy 292.498191 -402.499643) (xy 292.438752 -402.47611) (xy 292.382731 -402.445312)
			(xy 292.331013 -402.407736) (xy 292.284411 -402.363974) (xy 292.243662 -402.314717) (xy 292.209408 -402.26074)
			(xy 292.182189 -402.202897) (xy 292.162434 -402.142098) (xy 292.150455 -402.079302) (xy 292.146441 -402.0155)
			(xy 291.386484 -402.0155) (xy 291.38247 -402.079293) (xy 291.370493 -402.142079) (xy 291.350741 -402.20287)
			(xy 291.323525 -402.260705) (xy 291.289276 -402.314674) (xy 291.248532 -402.363924) (xy 291.201937 -402.407679)
			(xy 291.150226 -402.44525) (xy 291.094213 -402.476043) (xy 291.034783 -402.499573) (xy 290.972872 -402.515468)
			(xy 290.909457 -402.523479) (xy 290.877498 -402.52396) (xy 290.877244 -402.52396) (xy 290.845498 -402.523442)
			(xy 290.782502 -402.515512) (xy 290.720982 -402.499809) (xy 290.661894 -402.476575) (xy 290.606154 -402.446171)
			(xy 290.554629 -402.40907) (xy 290.531042 -402.387816) (xy 290.523779 -402.381632) (xy 290.506029 -402.374681)
			(xy 290.486967 -402.374681) (xy 290.469217 -402.381632) (xy 290.461954 -402.387816) (xy 290.438367 -402.409074)
			(xy 290.386858 -402.446206) (xy 290.331123 -402.47663) (xy 290.272032 -402.499871) (xy 290.210504 -402.515567)
			(xy 290.147501 -402.523474) (xy 290.115752 -402.52396) (xy 290.115498 -402.52396) (xy 290.083534 -402.523554)
			(xy 290.02011 -402.515542) (xy 289.958191 -402.499643) (xy 289.898752 -402.47611) (xy 289.842731 -402.445312)
			(xy 289.791013 -402.407736) (xy 289.744411 -402.363974) (xy 289.703662 -402.314717) (xy 289.669408 -402.26074)
			(xy 289.642189 -402.202897) (xy 289.622434 -402.142098) (xy 289.610455 -402.079302) (xy 289.606441 -402.0155)
			(xy 288.846484 -402.0155) (xy 288.84247 -402.079293) (xy 288.830493 -402.142079) (xy 288.810741 -402.20287)
			(xy 288.783525 -402.260705) (xy 288.749276 -402.314674) (xy 288.708532 -402.363924) (xy 288.661937 -402.407679)
			(xy 288.610226 -402.44525) (xy 288.554213 -402.476043) (xy 288.494783 -402.499573) (xy 288.432872 -402.515468)
			(xy 288.369457 -402.523479) (xy 288.337498 -402.52396) (xy 288.337244 -402.52396) (xy 288.305498 -402.523442)
			(xy 288.242502 -402.515512) (xy 288.180982 -402.499809) (xy 288.121894 -402.476575) (xy 288.066154 -402.446171)
			(xy 288.014629 -402.40907) (xy 287.991042 -402.387816) (xy 287.983779 -402.381632) (xy 287.966029 -402.374681)
			(xy 287.946967 -402.374681) (xy 287.929217 -402.381632) (xy 287.921954 -402.387816) (xy 287.898367 -402.409074)
			(xy 287.846858 -402.446206) (xy 287.791123 -402.47663) (xy 287.732032 -402.499871) (xy 287.670504 -402.515567)
			(xy 287.607501 -402.523474) (xy 287.575752 -402.52396) (xy 287.575498 -402.52396) (xy 287.543534 -402.523554)
			(xy 287.48011 -402.515542) (xy 287.418191 -402.499643) (xy 287.358752 -402.47611) (xy 287.302731 -402.445312)
			(xy 287.251013 -402.407736) (xy 287.204411 -402.363974) (xy 287.163662 -402.314717) (xy 287.129408 -402.26074)
			(xy 287.102189 -402.202897) (xy 287.082434 -402.142098) (xy 287.070455 -402.079302) (xy 287.066441 -402.0155)
			(xy 280.76398 -402.0155) (xy 280.76398 -402.1074) (xy 280.76343 -402.132362) (xy 280.753694 -402.181326)
			(xy 280.734578 -402.227444) (xy 280.706818 -402.268937) (xy 280.689558 -402.286978) (xy 280.501598 -402.474938)
			(xy 280.483557 -402.492195) (xy 280.442055 -402.519934) (xy 280.395938 -402.539043) (xy 280.346979 -402.548787)
			(xy 280.32202 -402.54936) (xy 239.86236 -402.54936) (xy 239.8374 -402.548779) (xy 239.788437 -402.539054)
			(xy 239.742319 -402.519947) (xy 239.700824 -402.492195) (xy 239.682782 -402.474938) (xy 239.497362 -402.289518)
			(xy 239.480115 -402.271468) (xy 239.452373 -402.229969) (xy 239.433262 -402.183855) (xy 239.423515 -402.134899)
			(xy 239.42294 -402.10994) (xy 2.509012 -402.10994) (xy 2.509012 -402.656674) (xy 98.152872 -402.656674)
			(xy 98.152872 -402.602126) (xy 98.160635 -402.548133) (xy 98.176003 -402.495795) (xy 98.198664 -402.446176)
			(xy 98.228156 -402.400288) (xy 98.263878 -402.359064) (xy 98.305104 -402.323344) (xy 98.350994 -402.293855)
			(xy 98.400613 -402.271196) (xy 98.452953 -402.255831) (xy 98.506946 -402.24807) (xy 98.53422 -402.247608)
			(xy 99.39782 -402.247608) (xy 99.425086 -402.248156) (xy 99.479063 -402.255919) (xy 99.531387 -402.271285)
			(xy 99.58099 -402.293941) (xy 99.626865 -402.323425) (xy 99.668077 -402.359137) (xy 99.703787 -402.400351)
			(xy 99.733269 -402.446227) (xy 99.755922 -402.495832) (xy 99.771285 -402.548156) (xy 99.779046 -402.602134)
			(xy 99.779046 -402.656666) (xy 99.771285 -402.710644) (xy 99.755922 -402.762968) (xy 99.733269 -402.812573)
			(xy 99.703787 -402.858449) (xy 99.668077 -402.899663) (xy 99.626865 -402.935375) (xy 99.58099 -402.964859)
			(xy 99.531387 -402.987515) (xy 99.479063 -403.002881) (xy 99.425086 -403.010644) (xy 99.39782 -403.011132)
			(xy 98.53422 -403.011132) (xy 98.506946 -403.01073) (xy 98.452953 -403.002969) (xy 98.400613 -402.987604)
			(xy 98.350994 -402.964945) (xy 98.305104 -402.935456) (xy 98.263878 -402.899736) (xy 98.228156 -402.858512)
			(xy 98.198664 -402.812624) (xy 98.176003 -402.763005) (xy 98.160635 -402.710667) (xy 98.152872 -402.656674)
			(xy 2.509012 -402.656674) (xy 2.509012 -403.371812) (xy 2.5095 -403.425034) (xy 2.517117 -403.531207)
			(xy 2.532283 -403.636566) (xy 2.554922 -403.740575) (xy 2.584919 -403.842706) (xy 2.610452 -403.911156)
			(xy 47.598731 -403.911156) (xy 47.598731 -403.856644) (xy 47.606489 -403.802686) (xy 47.621848 -403.750382)
			(xy 47.644495 -403.700796) (xy 47.673969 -403.654938) (xy 47.709669 -403.613742) (xy 47.750868 -403.578046)
			(xy 47.796729 -403.548577) (xy 47.846317 -403.525935) (xy 47.898623 -403.510581) (xy 47.952582 -403.502828)
			(xy 47.979838 -403.502368) (xy 48.843438 -403.502368) (xy 48.870686 -403.502905) (xy 48.924626 -403.510665)
			(xy 48.976913 -403.526023) (xy 49.026482 -403.548665) (xy 49.072325 -403.57813) (xy 49.113508 -403.613819)
			(xy 49.149193 -403.655006) (xy 49.178654 -403.700851) (xy 49.201291 -403.750423) (xy 49.216643 -403.802711)
			(xy 49.224398 -403.856652) (xy 49.224398 -403.911148) (xy 49.224397 -403.911152) (xy 50.662054 -403.911152)
			(xy 50.662054 -403.856648) (xy 50.66981 -403.802699) (xy 50.685165 -403.750403) (xy 50.707806 -403.700824)
			(xy 50.737272 -403.654971) (xy 50.772964 -403.613779) (xy 50.814154 -403.578085) (xy 50.860004 -403.548617)
			(xy 50.909582 -403.525973) (xy 50.961877 -403.510615) (xy 51.015826 -403.502855) (xy 51.043078 -403.502368)
			(xy 51.906678 -403.502368) (xy 51.93393 -403.502878) (xy 51.98788 -403.510632) (xy 52.040177 -403.525985)
			(xy 52.089757 -403.548625) (xy 52.13561 -403.57809) (xy 52.176803 -403.613782) (xy 52.212497 -403.654972)
			(xy 52.241965 -403.700824) (xy 52.264607 -403.750402) (xy 52.279964 -403.802698) (xy 52.287721 -403.856648)
			(xy 52.287721 -403.911152) (xy 52.287721 -403.911155) (xy 53.725231 -403.911155) (xy 53.725231 -403.856645)
			(xy 53.732989 -403.802689) (xy 53.748347 -403.750386) (xy 53.770992 -403.700801) (xy 53.800464 -403.654945)
			(xy 53.836162 -403.613749) (xy 53.877359 -403.578053) (xy 53.923217 -403.548583) (xy 53.972803 -403.525941)
			(xy 54.025106 -403.510585) (xy 54.079063 -403.50283) (xy 54.106318 -403.502368) (xy 54.969918 -403.502368)
			(xy 54.997167 -403.502903) (xy 55.051109 -403.510662) (xy 55.103398 -403.526017) (xy 55.15297 -403.548658)
			(xy 55.198815 -403.578123) (xy 55.240001 -403.613812) (xy 55.275688 -403.654999) (xy 55.305151 -403.700846)
			(xy 55.327789 -403.750419) (xy 55.343142 -403.802709) (xy 55.350898 -403.856651) (xy 55.350898 -403.911149)
			(xy 55.350898 -403.911151) (xy 56.788554 -403.911151) (xy 56.788554 -403.856649) (xy 56.79631 -403.802702)
			(xy 56.811664 -403.750407) (xy 56.834303 -403.700829) (xy 56.863767 -403.654978) (xy 56.899457 -403.613786)
			(xy 56.940644 -403.578093) (xy 56.986492 -403.548623) (xy 57.036067 -403.525978) (xy 57.08836 -403.510619)
			(xy 57.142307 -403.502857) (xy 57.169558 -403.502368) (xy 58.033158 -403.502368) (xy 58.060411 -403.502876)
			(xy 58.114363 -403.510628) (xy 58.166663 -403.525979) (xy 58.216245 -403.548618) (xy 58.262101 -403.578083)
			(xy 58.303296 -403.613775) (xy 58.338992 -403.654966) (xy 58.368462 -403.700818) (xy 58.391106 -403.750398)
			(xy 58.406463 -403.802696) (xy 58.414221 -403.856647) (xy 58.414221 -403.911153) (xy 59.851754 -403.911153)
			(xy 59.851754 -403.856647) (xy 59.859511 -403.802696) (xy 59.874867 -403.750398) (xy 59.897509 -403.700818)
			(xy 59.926977 -403.654965) (xy 59.962671 -403.613772) (xy 60.003863 -403.578078) (xy 60.049716 -403.54861)
			(xy 60.099296 -403.525967) (xy 60.151594 -403.510611) (xy 60.205545 -403.502854) (xy 60.232798 -403.502368)
			(xy 61.096398 -403.502368) (xy 61.123649 -403.502879) (xy 61.177597 -403.510635) (xy 61.229892 -403.52599)
			(xy 61.279469 -403.548631) (xy 61.32532 -403.578097) (xy 61.36651 -403.613789) (xy 61.402201 -403.654979)
			(xy 61.431668 -403.700829) (xy 61.454309 -403.750406) (xy 61.469664 -403.802701) (xy 61.477421 -403.856649)
			(xy 61.477421 -403.911151) (xy 61.47742 -403.911156) (xy 62.914931 -403.911156) (xy 62.914931 -403.856644)
			(xy 62.922689 -403.802686) (xy 62.938048 -403.750382) (xy 62.960695 -403.700796) (xy 62.990169 -403.654938)
			(xy 63.025869 -403.613742) (xy 63.067068 -403.578046) (xy 63.112929 -403.548577) (xy 63.162517 -403.525935)
			(xy 63.214823 -403.510581) (xy 63.268782 -403.502828) (xy 63.296038 -403.502368) (xy 64.159638 -403.502368)
			(xy 64.186886 -403.502905) (xy 64.240826 -403.510665) (xy 64.293113 -403.526023) (xy 64.342682 -403.548665)
			(xy 64.388525 -403.57813) (xy 64.429708 -403.613819) (xy 64.465393 -403.655006) (xy 64.494854 -403.700851)
			(xy 64.517491 -403.750423) (xy 64.532843 -403.802711) (xy 64.540598 -403.856652) (xy 64.540598 -403.911148)
			(xy 64.540597 -403.911152) (xy 65.978254 -403.911152) (xy 65.978254 -403.856648) (xy 65.98601 -403.802699)
			(xy 66.001365 -403.750403) (xy 66.024006 -403.700824) (xy 66.053472 -403.654971) (xy 66.089164 -403.613779)
			(xy 66.130354 -403.578085) (xy 66.176204 -403.548617) (xy 66.225782 -403.525973) (xy 66.278077 -403.510615)
			(xy 66.332026 -403.502855) (xy 66.359278 -403.502368) (xy 67.222878 -403.502368) (xy 67.25013 -403.502878)
			(xy 67.30408 -403.510632) (xy 67.356377 -403.525985) (xy 67.405957 -403.548625) (xy 67.45181 -403.57809)
			(xy 67.493003 -403.613782) (xy 67.528697 -403.654972) (xy 67.558165 -403.700824) (xy 67.580807 -403.750402)
			(xy 67.596164 -403.802698) (xy 67.603921 -403.856648) (xy 67.603921 -403.911152) (xy 67.603921 -403.911155)
			(xy 69.041431 -403.911155) (xy 69.041431 -403.856645) (xy 69.049189 -403.802689) (xy 69.064547 -403.750386)
			(xy 69.087192 -403.700801) (xy 69.116664 -403.654945) (xy 69.152362 -403.613749) (xy 69.193559 -403.578053)
			(xy 69.239417 -403.548583) (xy 69.289003 -403.525941) (xy 69.341306 -403.510585) (xy 69.395263 -403.50283)
			(xy 69.422518 -403.502368) (xy 70.286118 -403.502368) (xy 70.313367 -403.502903) (xy 70.367309 -403.510662)
			(xy 70.419598 -403.526017) (xy 70.46917 -403.548658) (xy 70.515015 -403.578123) (xy 70.556201 -403.613812)
			(xy 70.591888 -403.654999) (xy 70.621351 -403.700846) (xy 70.643989 -403.750419) (xy 70.659342 -403.802709)
			(xy 70.667098 -403.856651) (xy 70.667098 -403.911149) (xy 70.667098 -403.911151) (xy 72.104754 -403.911151)
			(xy 72.104754 -403.856649) (xy 72.11251 -403.802702) (xy 72.127864 -403.750407) (xy 72.150503 -403.700829)
			(xy 72.179967 -403.654978) (xy 72.215657 -403.613786) (xy 72.256844 -403.578093) (xy 72.302692 -403.548623)
			(xy 72.352267 -403.525978) (xy 72.40456 -403.510619) (xy 72.458507 -403.502857) (xy 72.485758 -403.502368)
			(xy 73.349358 -403.502368) (xy 73.376611 -403.502876) (xy 73.430563 -403.510628) (xy 73.482863 -403.525979)
			(xy 73.532445 -403.548618) (xy 73.578301 -403.578083) (xy 73.619496 -403.613775) (xy 73.655192 -403.654966)
			(xy 73.684662 -403.700818) (xy 73.707306 -403.750398) (xy 73.722663 -403.802696) (xy 73.730421 -403.856647)
			(xy 73.730421 -403.911153) (xy 75.167954 -403.911153) (xy 75.167954 -403.856647) (xy 75.175711 -403.802696)
			(xy 75.191067 -403.750398) (xy 75.213709 -403.700818) (xy 75.243177 -403.654965) (xy 75.278871 -403.613772)
			(xy 75.320063 -403.578078) (xy 75.365916 -403.54861) (xy 75.415496 -403.525967) (xy 75.467794 -403.510611)
			(xy 75.521745 -403.502854) (xy 75.548998 -403.502368) (xy 76.412598 -403.502368) (xy 76.439849 -403.502879)
			(xy 76.493797 -403.510635) (xy 76.546092 -403.52599) (xy 76.595669 -403.548631) (xy 76.64152 -403.578097)
			(xy 76.68271 -403.613789) (xy 76.718401 -403.654979) (xy 76.747868 -403.700829) (xy 76.770509 -403.750406)
			(xy 76.785864 -403.802701) (xy 76.793621 -403.856649) (xy 76.793621 -403.911151) (xy 76.79362 -403.911156)
			(xy 78.231131 -403.911156) (xy 78.231131 -403.856644) (xy 78.238889 -403.802686) (xy 78.254248 -403.750382)
			(xy 78.276895 -403.700796) (xy 78.306369 -403.654938) (xy 78.342069 -403.613742) (xy 78.383268 -403.578046)
			(xy 78.429129 -403.548577) (xy 78.478717 -403.525935) (xy 78.531023 -403.510581) (xy 78.584982 -403.502828)
			(xy 78.612238 -403.502368) (xy 79.475838 -403.502368) (xy 79.503086 -403.502905) (xy 79.557026 -403.510665)
			(xy 79.609313 -403.526023) (xy 79.658882 -403.548665) (xy 79.704725 -403.57813) (xy 79.745908 -403.613819)
			(xy 79.781593 -403.655006) (xy 79.811054 -403.700851) (xy 79.833691 -403.750423) (xy 79.849043 -403.802711)
			(xy 79.856798 -403.856652) (xy 79.856798 -403.911148) (xy 79.856797 -403.911152) (xy 81.294454 -403.911152)
			(xy 81.294454 -403.856648) (xy 81.30221 -403.802699) (xy 81.317565 -403.750403) (xy 81.340206 -403.700824)
			(xy 81.369672 -403.654971) (xy 81.405364 -403.613779) (xy 81.446554 -403.578085) (xy 81.492404 -403.548617)
			(xy 81.541982 -403.525973) (xy 81.594277 -403.510615) (xy 81.648226 -403.502855) (xy 81.675478 -403.502368)
			(xy 82.539078 -403.502368) (xy 82.56633 -403.502878) (xy 82.62028 -403.510632) (xy 82.672577 -403.525985)
			(xy 82.722157 -403.548625) (xy 82.76801 -403.57809) (xy 82.809203 -403.613782) (xy 82.844897 -403.654972)
			(xy 82.874365 -403.700824) (xy 82.897007 -403.750402) (xy 82.912364 -403.802698) (xy 82.920121 -403.856648)
			(xy 82.920121 -403.911152) (xy 82.920121 -403.911155) (xy 84.357631 -403.911155) (xy 84.357631 -403.856645)
			(xy 84.365389 -403.802689) (xy 84.380747 -403.750386) (xy 84.403392 -403.700801) (xy 84.432864 -403.654945)
			(xy 84.468562 -403.613749) (xy 84.509759 -403.578053) (xy 84.555617 -403.548583) (xy 84.605203 -403.525941)
			(xy 84.657506 -403.510585) (xy 84.711463 -403.50283) (xy 84.738718 -403.502368) (xy 85.602318 -403.502368)
			(xy 85.629567 -403.502903) (xy 85.683509 -403.510662) (xy 85.735798 -403.526017) (xy 85.78537 -403.548658)
			(xy 85.831215 -403.578123) (xy 85.872401 -403.613812) (xy 85.908088 -403.654999) (xy 85.937551 -403.700846)
			(xy 85.960189 -403.750419) (xy 85.975542 -403.802709) (xy 85.983298 -403.856651) (xy 85.983298 -403.911149)
			(xy 85.983298 -403.911151) (xy 87.420954 -403.911151) (xy 87.420954 -403.856649) (xy 87.42871 -403.802702)
			(xy 87.444064 -403.750407) (xy 87.466703 -403.700829) (xy 87.496167 -403.654978) (xy 87.531857 -403.613786)
			(xy 87.573044 -403.578093) (xy 87.618892 -403.548623) (xy 87.668467 -403.525978) (xy 87.72076 -403.510619)
			(xy 87.774707 -403.502857) (xy 87.801958 -403.502368) (xy 88.665558 -403.502368) (xy 88.692811 -403.502876)
			(xy 88.746763 -403.510628) (xy 88.799063 -403.525979) (xy 88.848645 -403.548618) (xy 88.894501 -403.578083)
			(xy 88.935696 -403.613775) (xy 88.971392 -403.654966) (xy 89.000862 -403.700818) (xy 89.023506 -403.750398)
			(xy 89.038863 -403.802696) (xy 89.046621 -403.856647) (xy 89.046621 -403.911153) (xy 90.484154 -403.911153)
			(xy 90.484154 -403.856647) (xy 90.491911 -403.802696) (xy 90.507267 -403.750398) (xy 90.529909 -403.700818)
			(xy 90.559377 -403.654965) (xy 90.595071 -403.613772) (xy 90.636263 -403.578078) (xy 90.682116 -403.54861)
			(xy 90.731696 -403.525967) (xy 90.783994 -403.510611) (xy 90.837945 -403.502854) (xy 90.865198 -403.502368)
			(xy 91.728798 -403.502368) (xy 91.756049 -403.502879) (xy 91.809997 -403.510635) (xy 91.862292 -403.52599)
			(xy 91.911869 -403.548631) (xy 91.95772 -403.578097) (xy 91.99891 -403.613789) (xy 92.034601 -403.654979)
			(xy 92.064068 -403.700829) (xy 92.086709 -403.750406) (xy 92.102064 -403.802701) (xy 92.109821 -403.856649)
			(xy 92.109821 -403.911151) (xy 92.10982 -403.911156) (xy 93.547331 -403.911156) (xy 93.547331 -403.856644)
			(xy 93.555089 -403.802686) (xy 93.570448 -403.750382) (xy 93.593095 -403.700796) (xy 93.622569 -403.654938)
			(xy 93.658269 -403.613742) (xy 93.699468 -403.578046) (xy 93.745329 -403.548577) (xy 93.794917 -403.525935)
			(xy 93.847223 -403.510581) (xy 93.901182 -403.502828) (xy 93.928438 -403.502368) (xy 94.792038 -403.502368)
			(xy 94.819286 -403.502905) (xy 94.873226 -403.510665) (xy 94.925513 -403.526023) (xy 94.975082 -403.548665)
			(xy 95.020925 -403.57813) (xy 95.062108 -403.613819) (xy 95.097793 -403.655006) (xy 95.127254 -403.700851)
			(xy 95.149891 -403.750423) (xy 95.165243 -403.802711) (xy 95.172998 -403.856652) (xy 95.172998 -403.911148)
			(xy 95.172998 -403.911151) (xy 119.773954 -403.911151) (xy 119.773954 -403.856649) (xy 119.78171 -403.802702)
			(xy 119.797063 -403.750408) (xy 119.819702 -403.70083) (xy 119.849166 -403.654979) (xy 119.884855 -403.613788)
			(xy 119.926042 -403.578094) (xy 119.97189 -403.548625) (xy 120.021465 -403.525979) (xy 120.073757 -403.510619)
			(xy 120.127703 -403.502857) (xy 120.154954 -403.502368) (xy 121.018554 -403.502368) (xy 121.045807 -403.502876)
			(xy 121.09976 -403.510627) (xy 121.15206 -403.525978) (xy 121.201643 -403.548617) (xy 121.247499 -403.578082)
			(xy 121.288694 -403.613773) (xy 121.324391 -403.654964) (xy 121.353861 -403.700817) (xy 121.376506 -403.750397)
			(xy 121.391863 -403.802695) (xy 121.399621 -403.856647) (xy 121.399621 -403.911153) (xy 122.837154 -403.911153)
			(xy 122.837154 -403.856647) (xy 122.844911 -403.802697) (xy 122.860266 -403.750399) (xy 122.882909 -403.700819)
			(xy 122.912376 -403.654966) (xy 122.948069 -403.613774) (xy 122.989261 -403.57808) (xy 123.035114 -403.548611)
			(xy 123.084694 -403.525969) (xy 123.136991 -403.510612) (xy 123.190941 -403.502854) (xy 123.218194 -403.502368)
			(xy 124.081794 -403.502368) (xy 124.109045 -403.502879) (xy 124.162994 -403.510635) (xy 124.215289 -403.525989)
			(xy 124.264867 -403.54863) (xy 124.310718 -403.578096) (xy 124.351908 -403.613787) (xy 124.3876 -403.654978)
			(xy 124.417067 -403.700828) (xy 124.439709 -403.750406) (xy 124.455064 -403.802701) (xy 124.462821 -403.856649)
			(xy 124.462821 -403.911151) (xy 124.46282 -403.911156) (xy 125.900331 -403.911156) (xy 125.900331 -403.856644)
			(xy 125.908089 -403.802686) (xy 125.923448 -403.750383) (xy 125.946095 -403.700797) (xy 125.975568 -403.654939)
			(xy 126.011267 -403.613743) (xy 126.052467 -403.578047) (xy 126.098327 -403.548578) (xy 126.147914 -403.525936)
			(xy 126.20022 -403.510582) (xy 126.254178 -403.502829) (xy 126.281434 -403.502368) (xy 127.145034 -403.502368)
			(xy 127.172282 -403.502905) (xy 127.226223 -403.510664) (xy 127.27851 -403.526022) (xy 127.32808 -403.548663)
			(xy 127.373923 -403.578129) (xy 127.415106 -403.613818) (xy 127.450792 -403.655004) (xy 127.480253 -403.70085)
			(xy 127.50289 -403.750422) (xy 127.518243 -403.802711) (xy 127.525998 -403.856652) (xy 127.525998 -403.911148)
			(xy 127.525997 -403.911152) (xy 128.963654 -403.911152) (xy 128.963654 -403.856648) (xy 128.97141 -403.802699)
			(xy 128.986765 -403.750403) (xy 129.009406 -403.700825) (xy 129.038871 -403.654973) (xy 129.074562 -403.613781)
			(xy 129.115752 -403.578087) (xy 129.161602 -403.548618) (xy 129.211179 -403.525974) (xy 129.263474 -403.510616)
			(xy 129.317422 -403.502856) (xy 129.344674 -403.502368) (xy 130.208274 -403.502368) (xy 130.235526 -403.502878)
			(xy 130.289477 -403.510631) (xy 130.341774 -403.525984) (xy 130.391355 -403.548623) (xy 130.437208 -403.578089)
			(xy 130.478401 -403.61378) (xy 130.514096 -403.654971) (xy 130.543564 -403.700822) (xy 130.566207 -403.750401)
			(xy 130.581563 -403.802698) (xy 130.589321 -403.856648) (xy 130.589321 -403.911152) (xy 130.589321 -403.911155)
			(xy 132.026831 -403.911155) (xy 132.026831 -403.856645) (xy 132.034589 -403.802689) (xy 132.049946 -403.750387)
			(xy 132.072591 -403.700803) (xy 132.102063 -403.654946) (xy 132.13776 -403.61375) (xy 132.178957 -403.578054)
			(xy 132.224815 -403.548585) (xy 132.2744 -403.525942) (xy 132.326703 -403.510586) (xy 132.380659 -403.50283)
			(xy 132.407914 -403.502368) (xy 133.271514 -403.502368) (xy 133.298763 -403.502903) (xy 133.352706 -403.510661)
			(xy 133.404995 -403.526016) (xy 133.454568 -403.548657) (xy 133.500413 -403.578121) (xy 133.541599 -403.613811)
			(xy 133.577287 -403.654998) (xy 133.60675 -403.700845) (xy 133.629389 -403.750418) (xy 133.644742 -403.802708)
			(xy 133.652498 -403.856651) (xy 133.652498 -403.911149) (xy 133.652498 -403.911151) (xy 135.090154 -403.911151)
			(xy 135.090154 -403.856649) (xy 135.09791 -403.802702) (xy 135.113263 -403.750408) (xy 135.135902 -403.70083)
			(xy 135.165366 -403.654979) (xy 135.201055 -403.613788) (xy 135.242242 -403.578094) (xy 135.28809 -403.548625)
			(xy 135.337665 -403.525979) (xy 135.389957 -403.510619) (xy 135.443903 -403.502857) (xy 135.471154 -403.502368)
			(xy 136.334754 -403.502368) (xy 136.362007 -403.502876) (xy 136.41596 -403.510627) (xy 136.46826 -403.525978)
			(xy 136.517843 -403.548617) (xy 136.563699 -403.578082) (xy 136.604894 -403.613773) (xy 136.640591 -403.654964)
			(xy 136.670061 -403.700817) (xy 136.692706 -403.750397) (xy 136.708063 -403.802695) (xy 136.715821 -403.856647)
			(xy 136.715821 -403.911153) (xy 138.153354 -403.911153) (xy 138.153354 -403.856647) (xy 138.161111 -403.802697)
			(xy 138.176466 -403.750399) (xy 138.199109 -403.700819) (xy 138.228576 -403.654966) (xy 138.264269 -403.613774)
			(xy 138.305461 -403.57808) (xy 138.351314 -403.548611) (xy 138.400894 -403.525969) (xy 138.453191 -403.510612)
			(xy 138.507141 -403.502854) (xy 138.534394 -403.502368) (xy 139.397994 -403.502368) (xy 139.425245 -403.502879)
			(xy 139.479194 -403.510635) (xy 139.531489 -403.525989) (xy 139.581067 -403.54863) (xy 139.626918 -403.578096)
			(xy 139.668108 -403.613787) (xy 139.7038 -403.654978) (xy 139.733267 -403.700828) (xy 139.755909 -403.750406)
			(xy 139.771264 -403.802701) (xy 139.779021 -403.856649) (xy 139.779021 -403.911151) (xy 139.77902 -403.911156)
			(xy 141.216531 -403.911156) (xy 141.216531 -403.856644) (xy 141.224289 -403.802686) (xy 141.239648 -403.750383)
			(xy 141.262295 -403.700797) (xy 141.291768 -403.654939) (xy 141.327467 -403.613743) (xy 141.368667 -403.578047)
			(xy 141.414527 -403.548578) (xy 141.464114 -403.525936) (xy 141.51642 -403.510582) (xy 141.570378 -403.502829)
			(xy 141.597634 -403.502368) (xy 142.461234 -403.502368) (xy 142.488482 -403.502905) (xy 142.542423 -403.510664)
			(xy 142.59471 -403.526022) (xy 142.64428 -403.548663) (xy 142.690123 -403.578129) (xy 142.731306 -403.613818)
			(xy 142.766992 -403.655004) (xy 142.796453 -403.70085) (xy 142.81909 -403.750422) (xy 142.834443 -403.802711)
			(xy 142.842198 -403.856652) (xy 142.842198 -403.911148) (xy 142.842197 -403.911152) (xy 144.279854 -403.911152)
			(xy 144.279854 -403.856648) (xy 144.28761 -403.802699) (xy 144.302965 -403.750403) (xy 144.325606 -403.700825)
			(xy 144.355071 -403.654973) (xy 144.390762 -403.613781) (xy 144.431952 -403.578087) (xy 144.477802 -403.548618)
			(xy 144.527379 -403.525974) (xy 144.579674 -403.510616) (xy 144.633622 -403.502856) (xy 144.660874 -403.502368)
			(xy 145.524474 -403.502368) (xy 145.551726 -403.502878) (xy 145.605677 -403.510631) (xy 145.657974 -403.525984)
			(xy 145.707555 -403.548623) (xy 145.753408 -403.578089) (xy 145.794601 -403.61378) (xy 145.830296 -403.654971)
			(xy 145.859764 -403.700822) (xy 145.882407 -403.750401) (xy 145.897763 -403.802698) (xy 145.905521 -403.856648)
			(xy 145.905521 -403.911152) (xy 145.905521 -403.911155) (xy 147.343031 -403.911155) (xy 147.343031 -403.856645)
			(xy 147.350789 -403.802689) (xy 147.366146 -403.750387) (xy 147.388791 -403.700803) (xy 147.418263 -403.654946)
			(xy 147.45396 -403.61375) (xy 147.495157 -403.578054) (xy 147.541015 -403.548585) (xy 147.5906 -403.525942)
			(xy 147.642903 -403.510586) (xy 147.696859 -403.50283) (xy 147.724114 -403.502368) (xy 148.587714 -403.502368)
			(xy 148.614963 -403.502903) (xy 148.668906 -403.510661) (xy 148.721195 -403.526016) (xy 148.770768 -403.548657)
			(xy 148.816613 -403.578121) (xy 148.857799 -403.613811) (xy 148.893487 -403.654998) (xy 148.92295 -403.700845)
			(xy 148.945589 -403.750418) (xy 148.960942 -403.802708) (xy 148.968698 -403.856651) (xy 148.968698 -403.911149)
			(xy 148.968698 -403.911151) (xy 150.406354 -403.911151) (xy 150.406354 -403.856649) (xy 150.41411 -403.802702)
			(xy 150.429463 -403.750408) (xy 150.452102 -403.70083) (xy 150.481566 -403.654979) (xy 150.517255 -403.613788)
			(xy 150.558442 -403.578094) (xy 150.60429 -403.548625) (xy 150.653865 -403.525979) (xy 150.706157 -403.510619)
			(xy 150.760103 -403.502857) (xy 150.787354 -403.502368) (xy 151.650954 -403.502368) (xy 151.678207 -403.502876)
			(xy 151.73216 -403.510627) (xy 151.78446 -403.525978) (xy 151.834043 -403.548617) (xy 151.879899 -403.578082)
			(xy 151.921094 -403.613773) (xy 151.956791 -403.654964) (xy 151.986261 -403.700817) (xy 152.008906 -403.750397)
			(xy 152.024263 -403.802695) (xy 152.032021 -403.856647) (xy 152.032021 -403.911153) (xy 153.469554 -403.911153)
			(xy 153.469554 -403.856647) (xy 153.477311 -403.802697) (xy 153.492666 -403.750399) (xy 153.515309 -403.700819)
			(xy 153.544776 -403.654966) (xy 153.580469 -403.613774) (xy 153.621661 -403.57808) (xy 153.667514 -403.548611)
			(xy 153.717094 -403.525969) (xy 153.769391 -403.510612) (xy 153.823341 -403.502854) (xy 153.850594 -403.502368)
			(xy 154.714194 -403.502368) (xy 154.741445 -403.502879) (xy 154.795394 -403.510635) (xy 154.847689 -403.525989)
			(xy 154.897267 -403.54863) (xy 154.943118 -403.578096) (xy 154.984308 -403.613787) (xy 155.02 -403.654978)
			(xy 155.049467 -403.700828) (xy 155.072109 -403.750406) (xy 155.087464 -403.802701) (xy 155.095221 -403.856649)
			(xy 155.095221 -403.911151) (xy 155.09522 -403.911156) (xy 156.532731 -403.911156) (xy 156.532731 -403.856644)
			(xy 156.540489 -403.802686) (xy 156.555848 -403.750383) (xy 156.578495 -403.700797) (xy 156.607968 -403.654939)
			(xy 156.643667 -403.613743) (xy 156.684867 -403.578047) (xy 156.730727 -403.548578) (xy 156.780314 -403.525936)
			(xy 156.83262 -403.510582) (xy 156.886578 -403.502829) (xy 156.913834 -403.502368) (xy 157.777434 -403.502368)
			(xy 157.804682 -403.502905) (xy 157.858623 -403.510664) (xy 157.91091 -403.526022) (xy 157.96048 -403.548663)
			(xy 158.006323 -403.578129) (xy 158.047506 -403.613818) (xy 158.083192 -403.655004) (xy 158.112653 -403.70085)
			(xy 158.13529 -403.750422) (xy 158.150643 -403.802711) (xy 158.158398 -403.856652) (xy 158.158398 -403.911148)
			(xy 158.158397 -403.911152) (xy 159.596054 -403.911152) (xy 159.596054 -403.856648) (xy 159.60381 -403.802699)
			(xy 159.619165 -403.750403) (xy 159.641806 -403.700825) (xy 159.671271 -403.654973) (xy 159.706962 -403.613781)
			(xy 159.748152 -403.578087) (xy 159.794002 -403.548618) (xy 159.843579 -403.525974) (xy 159.895874 -403.510616)
			(xy 159.949822 -403.502856) (xy 159.977074 -403.502368) (xy 160.840674 -403.502368) (xy 160.867926 -403.502878)
			(xy 160.921877 -403.510631) (xy 160.974174 -403.525984) (xy 161.023755 -403.548623) (xy 161.069608 -403.578089)
			(xy 161.110801 -403.61378) (xy 161.146496 -403.654971) (xy 161.175964 -403.700822) (xy 161.198607 -403.750401)
			(xy 161.213963 -403.802698) (xy 161.221721 -403.856648) (xy 161.221721 -403.911152) (xy 161.221721 -403.911155)
			(xy 162.659231 -403.911155) (xy 162.659231 -403.856645) (xy 162.666989 -403.802689) (xy 162.682346 -403.750387)
			(xy 162.704991 -403.700803) (xy 162.734463 -403.654946) (xy 162.77016 -403.61375) (xy 162.811357 -403.578054)
			(xy 162.857215 -403.548585) (xy 162.9068 -403.525942) (xy 162.959103 -403.510586) (xy 163.013059 -403.50283)
			(xy 163.040314 -403.502368) (xy 163.903914 -403.502368) (xy 163.931163 -403.502903) (xy 163.985106 -403.510661)
			(xy 164.037395 -403.526016) (xy 164.086968 -403.548657) (xy 164.132813 -403.578121) (xy 164.173999 -403.613811)
			(xy 164.209687 -403.654998) (xy 164.23915 -403.700845) (xy 164.261789 -403.750418) (xy 164.277142 -403.802708)
			(xy 164.284898 -403.856651) (xy 164.284898 -403.911149) (xy 164.284898 -403.911151) (xy 165.722554 -403.911151)
			(xy 165.722554 -403.856649) (xy 165.73031 -403.802702) (xy 165.745663 -403.750408) (xy 165.768302 -403.70083)
			(xy 165.797766 -403.654979) (xy 165.833455 -403.613788) (xy 165.874642 -403.578094) (xy 165.92049 -403.548625)
			(xy 165.970065 -403.525979) (xy 166.022357 -403.510619) (xy 166.076303 -403.502857) (xy 166.103554 -403.502368)
			(xy 166.967154 -403.502368) (xy 166.994407 -403.502876) (xy 167.04836 -403.510627) (xy 167.10066 -403.525978)
			(xy 167.150243 -403.548617) (xy 167.196099 -403.578082) (xy 167.237294 -403.613773) (xy 167.272991 -403.654964)
			(xy 167.302461 -403.700817) (xy 167.325106 -403.750397) (xy 167.340463 -403.802695) (xy 167.348221 -403.856647)
			(xy 167.348221 -403.911153) (xy 167.340463 -403.965105) (xy 167.325106 -404.017403) (xy 167.31136 -404.0475)
			(xy 287.066441 -404.0475) (xy 287.070455 -403.983698) (xy 287.082434 -403.920902) (xy 287.102189 -403.860103)
			(xy 287.129408 -403.80226) (xy 287.163662 -403.748283) (xy 287.204411 -403.699026) (xy 287.251013 -403.655264)
			(xy 287.302731 -403.617688) (xy 287.358752 -403.58689) (xy 287.418191 -403.563357) (xy 287.48011 -403.547458)
			(xy 287.543534 -403.539446) (xy 287.575498 -403.538944) (xy 287.575752 -403.538944) (xy 287.607498 -403.539464)
			(xy 287.670494 -403.547393) (xy 287.732014 -403.563096) (xy 287.791102 -403.58633) (xy 287.846842 -403.616733)
			(xy 287.898367 -403.653834) (xy 287.921954 -403.675088) (xy 287.929217 -403.681272) (xy 287.946967 -403.688223)
			(xy 287.966029 -403.688223) (xy 287.983779 -403.681272) (xy 287.991042 -403.675088) (xy 288.014631 -403.653832)
			(xy 288.06614 -403.6167) (xy 288.121874 -403.586276) (xy 288.180965 -403.563035) (xy 288.242492 -403.547338)
			(xy 288.305495 -403.539431) (xy 288.337244 -403.538944) (xy 288.337498 -403.538944) (xy 288.369457 -403.539521)
			(xy 288.432872 -403.547532) (xy 288.494783 -403.563427) (xy 288.554213 -403.586957) (xy 288.610226 -403.61775)
			(xy 288.661937 -403.655321) (xy 288.708532 -403.699076) (xy 288.749276 -403.748326) (xy 288.783525 -403.802295)
			(xy 288.810741 -403.86013) (xy 288.830493 -403.920921) (xy 288.84247 -403.983707) (xy 288.846484 -404.0475)
			(xy 289.606441 -404.0475) (xy 289.610455 -403.983698) (xy 289.622434 -403.920902) (xy 289.642189 -403.860103)
			(xy 289.669408 -403.80226) (xy 289.703662 -403.748283) (xy 289.744411 -403.699026) (xy 289.791013 -403.655264)
			(xy 289.842731 -403.617688) (xy 289.898752 -403.58689) (xy 289.958191 -403.563357) (xy 290.02011 -403.547458)
			(xy 290.083534 -403.539446) (xy 290.115498 -403.538944) (xy 290.115752 -403.538944) (xy 290.147498 -403.539464)
			(xy 290.210494 -403.547393) (xy 290.272014 -403.563096) (xy 290.331102 -403.58633) (xy 290.386842 -403.616733)
			(xy 290.438367 -403.653834) (xy 290.461954 -403.675088) (xy 290.469217 -403.681272) (xy 290.486967 -403.688223)
			(xy 290.506029 -403.688223) (xy 290.523779 -403.681272) (xy 290.531042 -403.675088) (xy 290.554631 -403.653832)
			(xy 290.60614 -403.6167) (xy 290.661874 -403.586276) (xy 290.720965 -403.563035) (xy 290.782492 -403.547338)
			(xy 290.845495 -403.539431) (xy 290.877244 -403.538944) (xy 290.877498 -403.538944) (xy 290.909457 -403.539521)
			(xy 290.972872 -403.547532) (xy 291.034783 -403.563427) (xy 291.094213 -403.586957) (xy 291.150226 -403.61775)
			(xy 291.201937 -403.655321) (xy 291.248532 -403.699076) (xy 291.289276 -403.748326) (xy 291.323525 -403.802295)
			(xy 291.350741 -403.86013) (xy 291.370493 -403.920921) (xy 291.38247 -403.983707) (xy 291.386484 -404.0475)
			(xy 292.146441 -404.0475) (xy 292.150455 -403.983698) (xy 292.162434 -403.920902) (xy 292.182189 -403.860103)
			(xy 292.209408 -403.80226) (xy 292.243662 -403.748283) (xy 292.284411 -403.699026) (xy 292.331013 -403.655264)
			(xy 292.382731 -403.617688) (xy 292.438752 -403.58689) (xy 292.498191 -403.563357) (xy 292.56011 -403.547458)
			(xy 292.623534 -403.539446) (xy 292.655498 -403.538944) (xy 292.655752 -403.538944) (xy 292.687498 -403.539464)
			(xy 292.750494 -403.547393) (xy 292.812014 -403.563096) (xy 292.871102 -403.58633) (xy 292.926842 -403.616733)
			(xy 292.978367 -403.653834) (xy 293.001954 -403.675088) (xy 293.009217 -403.681272) (xy 293.026967 -403.688223)
			(xy 293.046029 -403.688223) (xy 293.063779 -403.681272) (xy 293.071042 -403.675088) (xy 293.094631 -403.653832)
			(xy 293.14614 -403.6167) (xy 293.201874 -403.586276) (xy 293.260965 -403.563035) (xy 293.322492 -403.547338)
			(xy 293.385495 -403.539431) (xy 293.417244 -403.538944) (xy 293.417498 -403.538944) (xy 293.449457 -403.539521)
			(xy 293.512872 -403.547532) (xy 293.574783 -403.563427) (xy 293.634213 -403.586957) (xy 293.690226 -403.61775)
			(xy 293.741937 -403.655321) (xy 293.788532 -403.699076) (xy 293.829276 -403.748326) (xy 293.863525 -403.802295)
			(xy 293.890741 -403.86013) (xy 293.910493 -403.920921) (xy 293.92247 -403.983707) (xy 293.926484 -404.0475)
			(xy 294.53602 -404.0475) (xy 294.540035 -403.983693) (xy 294.552015 -403.920892) (xy 294.571773 -403.860089)
			(xy 294.598995 -403.802241) (xy 294.633253 -403.748261) (xy 294.674007 -403.699001) (xy 294.720613 -403.655237)
			(xy 294.772338 -403.61766) (xy 294.828364 -403.586862) (xy 294.887809 -403.563329) (xy 294.949734 -403.547433)
			(xy 295.013163 -403.539423) (xy 295.04513 -403.538944) (xy 295.045384 -403.538944) (xy 295.077131 -403.539444)
			(xy 295.140127 -403.547377) (xy 295.201647 -403.563084) (xy 295.260736 -403.586322) (xy 295.316476 -403.616728)
			(xy 295.368 -403.653832) (xy 295.391586 -403.675088) (xy 295.398849 -403.681272) (xy 295.416599 -403.688223)
			(xy 295.435661 -403.688223) (xy 295.453411 -403.681272) (xy 295.460674 -403.675088) (xy 295.48425 -403.653817)
			(xy 295.535761 -403.616686) (xy 295.591498 -403.586265) (xy 295.650592 -403.563026) (xy 295.712121 -403.547332)
			(xy 295.775126 -403.539429) (xy 295.806876 -403.538944) (xy 295.80713 -403.538944) (xy 295.839087 -403.539544)
			(xy 295.902496 -403.547558) (xy 295.964401 -403.563455) (xy 296.023825 -403.586986) (xy 296.079832 -403.617779)
			(xy 296.131538 -403.655348) (xy 296.178128 -403.699102) (xy 296.218866 -403.748349) (xy 296.253112 -403.802314)
			(xy 296.280324 -403.860145) (xy 296.300074 -403.920931) (xy 296.312049 -403.983712) (xy 296.316063 -404.0475)
			(xy 297.07602 -404.0475) (xy 297.080035 -403.983693) (xy 297.092015 -403.920892) (xy 297.111773 -403.860089)
			(xy 297.138995 -403.802241) (xy 297.173253 -403.748261) (xy 297.214007 -403.699001) (xy 297.260613 -403.655237)
			(xy 297.312338 -403.61766) (xy 297.368364 -403.586862) (xy 297.427809 -403.563329) (xy 297.489734 -403.547433)
			(xy 297.553163 -403.539423) (xy 297.58513 -403.538944) (xy 297.585384 -403.538944) (xy 297.617131 -403.539444)
			(xy 297.680127 -403.547377) (xy 297.741647 -403.563084) (xy 297.800736 -403.586322) (xy 297.856476 -403.616728)
			(xy 297.908 -403.653832) (xy 297.931586 -403.675088) (xy 297.938849 -403.681272) (xy 297.956599 -403.688223)
			(xy 297.975661 -403.688223) (xy 297.993411 -403.681272) (xy 298.000674 -403.675088) (xy 298.02425 -403.653817)
			(xy 298.075761 -403.616686) (xy 298.131498 -403.586265) (xy 298.190592 -403.563026) (xy 298.252121 -403.547332)
			(xy 298.315126 -403.539429) (xy 298.346876 -403.538944) (xy 298.34713 -403.538944) (xy 298.379087 -403.539544)
			(xy 298.442496 -403.547558) (xy 298.504401 -403.563455) (xy 298.563825 -403.586986) (xy 298.619832 -403.617779)
			(xy 298.671538 -403.655348) (xy 298.718128 -403.699102) (xy 298.758866 -403.748349) (xy 298.793112 -403.802314)
			(xy 298.820324 -403.860145) (xy 298.836897 -403.911152) (xy 303.599054 -403.911152) (xy 303.599054 -403.856648)
			(xy 303.60681 -403.802698) (xy 303.622166 -403.7504) (xy 303.644808 -403.700821) (xy 303.674275 -403.654968)
			(xy 303.709967 -403.613776) (xy 303.751159 -403.578082) (xy 303.79701 -403.548613) (xy 303.846589 -403.52597)
			(xy 303.898886 -403.510613) (xy 303.952836 -403.502855) (xy 303.980088 -403.502368) (xy 304.843688 -403.502368)
			(xy 304.87094 -403.502878) (xy 304.924889 -403.510634) (xy 304.977185 -403.525988) (xy 305.026763 -403.548628)
			(xy 305.072615 -403.578094) (xy 305.113806 -403.613785) (xy 305.149499 -403.654976) (xy 305.178966 -403.700826)
			(xy 305.201608 -403.750404) (xy 305.216964 -403.8027) (xy 305.224721 -403.856648) (xy 305.224721 -403.911152)
			(xy 305.22472 -403.911156) (xy 306.662231 -403.911156) (xy 306.662231 -403.856644) (xy 306.669989 -403.802687)
			(xy 306.685348 -403.750384) (xy 306.707994 -403.700799) (xy 306.737466 -403.654941) (xy 306.773165 -403.613745)
			(xy 306.814364 -403.578049) (xy 306.860223 -403.54858) (xy 306.90981 -403.525938) (xy 306.962115 -403.510583)
			(xy 307.016072 -403.502829) (xy 307.043328 -403.502368) (xy 307.906928 -403.502368) (xy 307.934176 -403.502904)
			(xy 307.988117 -403.510663) (xy 308.040405 -403.52602) (xy 308.089976 -403.548661) (xy 308.13582 -403.578126)
			(xy 308.177004 -403.613816) (xy 308.21269 -403.655002) (xy 308.242152 -403.700849) (xy 308.26479 -403.750421)
			(xy 308.280143 -403.80271) (xy 308.287898 -403.856652) (xy 308.287898 -403.911148) (xy 308.287897 -403.911152)
			(xy 309.725554 -403.911152) (xy 309.725554 -403.856648) (xy 309.73331 -403.8027) (xy 309.748664 -403.750405)
			(xy 309.771305 -403.700826) (xy 309.80077 -403.654975) (xy 309.83646 -403.613783) (xy 309.877649 -403.578089)
			(xy 309.923498 -403.54862) (xy 309.973075 -403.525976) (xy 310.025369 -403.510617) (xy 310.079317 -403.502856)
			(xy 310.106568 -403.502368) (xy 310.970168 -403.502368) (xy 310.997421 -403.502877) (xy 311.051372 -403.51063)
			(xy 311.10367 -403.525982) (xy 311.153251 -403.548621) (xy 311.199105 -403.578087) (xy 311.240299 -403.613778)
			(xy 311.275994 -403.654969) (xy 311.305463 -403.700821) (xy 311.328107 -403.7504) (xy 311.343463 -403.802697)
			(xy 311.351221 -403.856647) (xy 311.351221 -403.911153) (xy 311.351221 -403.911155) (xy 312.788731 -403.911155)
			(xy 312.788731 -403.856645) (xy 312.796489 -403.80269) (xy 312.811846 -403.750388) (xy 312.834491 -403.700804)
			(xy 312.863961 -403.654948) (xy 312.899658 -403.613752) (xy 312.940854 -403.578056) (xy 312.986711 -403.548587)
			(xy 313.036296 -403.525943) (xy 313.088598 -403.510587) (xy 313.142553 -403.50283) (xy 313.169808 -403.502368)
			(xy 314.033408 -403.502368) (xy 314.060657 -403.502903) (xy 314.114601 -403.51066) (xy 314.166891 -403.526015)
			(xy 314.216464 -403.548655) (xy 314.26231 -403.578119) (xy 314.303497 -403.613809) (xy 314.339186 -403.654996)
			(xy 314.368649 -403.700843) (xy 314.391288 -403.750417) (xy 314.406642 -403.802707) (xy 314.414398 -403.856651)
			(xy 314.414398 -403.911149) (xy 314.414397 -403.911157) (xy 315.851931 -403.911157) (xy 315.851931 -403.856643)
			(xy 315.85969 -403.802685) (xy 315.875049 -403.75038) (xy 315.897697 -403.700793) (xy 315.927171 -403.654935)
			(xy 315.962872 -403.613738) (xy 316.004073 -403.578042) (xy 316.049935 -403.548574) (xy 316.099525 -403.525932)
			(xy 316.151832 -403.51058) (xy 316.205791 -403.502828) (xy 316.233048 -403.502368) (xy 317.096648 -403.502368)
			(xy 317.123895 -403.502905) (xy 317.177834 -403.510667) (xy 317.23012 -403.526025) (xy 317.279688 -403.548668)
			(xy 317.325529 -403.578133) (xy 317.366711 -403.613823) (xy 317.402395 -403.655009) (xy 317.431855 -403.700854)
			(xy 317.454491 -403.750425) (xy 317.469843 -403.802713) (xy 317.477598 -403.856653) (xy 317.477598 -403.911147)
			(xy 317.477597 -403.911152) (xy 318.915254 -403.911152) (xy 318.915254 -403.856648) (xy 318.92301 -403.802698)
			(xy 318.938366 -403.7504) (xy 318.961008 -403.700821) (xy 318.990475 -403.654968) (xy 319.026167 -403.613776)
			(xy 319.067359 -403.578082) (xy 319.11321 -403.548613) (xy 319.162789 -403.52597) (xy 319.215086 -403.510613)
			(xy 319.269036 -403.502855) (xy 319.296288 -403.502368) (xy 320.159888 -403.502368) (xy 320.18714 -403.502878)
			(xy 320.241089 -403.510634) (xy 320.293385 -403.525988) (xy 320.342963 -403.548628) (xy 320.388815 -403.578094)
			(xy 320.430006 -403.613785) (xy 320.465699 -403.654976) (xy 320.495166 -403.700826) (xy 320.517808 -403.750404)
			(xy 320.533164 -403.8027) (xy 320.540921 -403.856648) (xy 320.540921 -403.911152) (xy 320.54092 -403.911156)
			(xy 321.978431 -403.911156) (xy 321.978431 -403.856644) (xy 321.986189 -403.802687) (xy 322.001548 -403.750384)
			(xy 322.024194 -403.700799) (xy 322.053666 -403.654941) (xy 322.089365 -403.613745) (xy 322.130564 -403.578049)
			(xy 322.176423 -403.54858) (xy 322.22601 -403.525938) (xy 322.278315 -403.510583) (xy 322.332272 -403.502829)
			(xy 322.359528 -403.502368) (xy 323.223128 -403.502368) (xy 323.250376 -403.502904) (xy 323.304317 -403.510663)
			(xy 323.356605 -403.52602) (xy 323.406176 -403.548661) (xy 323.45202 -403.578126) (xy 323.493204 -403.613816)
			(xy 323.52889 -403.655002) (xy 323.558352 -403.700849) (xy 323.58099 -403.750421) (xy 323.596343 -403.80271)
			(xy 323.604098 -403.856652) (xy 323.604098 -403.911148) (xy 323.604097 -403.911152) (xy 325.041754 -403.911152)
			(xy 325.041754 -403.856648) (xy 325.04951 -403.8027) (xy 325.064864 -403.750405) (xy 325.087505 -403.700826)
			(xy 325.11697 -403.654975) (xy 325.15266 -403.613783) (xy 325.193849 -403.578089) (xy 325.239698 -403.54862)
			(xy 325.289275 -403.525976) (xy 325.341569 -403.510617) (xy 325.395517 -403.502856) (xy 325.422768 -403.502368)
			(xy 326.286368 -403.502368) (xy 326.313621 -403.502877) (xy 326.367572 -403.51063) (xy 326.41987 -403.525982)
			(xy 326.469451 -403.548621) (xy 326.515305 -403.578087) (xy 326.556499 -403.613778) (xy 326.592194 -403.654969)
			(xy 326.621663 -403.700821) (xy 326.644307 -403.7504) (xy 326.659663 -403.802697) (xy 326.667421 -403.856647)
			(xy 326.667421 -403.911153) (xy 326.667421 -403.911155) (xy 328.104931 -403.911155) (xy 328.104931 -403.856645)
			(xy 328.112689 -403.80269) (xy 328.128046 -403.750388) (xy 328.150691 -403.700804) (xy 328.180161 -403.654948)
			(xy 328.215858 -403.613752) (xy 328.257054 -403.578056) (xy 328.302911 -403.548587) (xy 328.352496 -403.525943)
			(xy 328.404798 -403.510587) (xy 328.458753 -403.50283) (xy 328.486008 -403.502368) (xy 329.349608 -403.502368)
			(xy 329.376857 -403.502903) (xy 329.430801 -403.51066) (xy 329.483091 -403.526015) (xy 329.532664 -403.548655)
			(xy 329.57851 -403.578119) (xy 329.619697 -403.613809) (xy 329.655386 -403.654996) (xy 329.684849 -403.700843)
			(xy 329.707488 -403.750417) (xy 329.722842 -403.802707) (xy 329.730598 -403.856651) (xy 329.730598 -403.911149)
			(xy 329.730597 -403.911157) (xy 331.168131 -403.911157) (xy 331.168131 -403.856643) (xy 331.17589 -403.802685)
			(xy 331.191249 -403.75038) (xy 331.213897 -403.700793) (xy 331.243371 -403.654935) (xy 331.279072 -403.613738)
			(xy 331.320273 -403.578042) (xy 331.366135 -403.548574) (xy 331.415725 -403.525932) (xy 331.468032 -403.51058)
			(xy 331.521991 -403.502828) (xy 331.549248 -403.502368) (xy 332.412848 -403.502368) (xy 332.440095 -403.502905)
			(xy 332.494034 -403.510667) (xy 332.54632 -403.526025) (xy 332.595888 -403.548668) (xy 332.641729 -403.578133)
			(xy 332.682911 -403.613823) (xy 332.718595 -403.655009) (xy 332.748055 -403.700854) (xy 332.770691 -403.750425)
			(xy 332.786043 -403.802713) (xy 332.793798 -403.856653) (xy 332.793798 -403.911147) (xy 332.793797 -403.911152)
			(xy 334.231454 -403.911152) (xy 334.231454 -403.856648) (xy 334.23921 -403.802698) (xy 334.254566 -403.7504)
			(xy 334.277208 -403.700821) (xy 334.306675 -403.654968) (xy 334.342367 -403.613776) (xy 334.383559 -403.578082)
			(xy 334.42941 -403.548613) (xy 334.478989 -403.52597) (xy 334.531286 -403.510613) (xy 334.585236 -403.502855)
			(xy 334.612488 -403.502368) (xy 335.476088 -403.502368) (xy 335.50334 -403.502878) (xy 335.557289 -403.510634)
			(xy 335.609585 -403.525988) (xy 335.659163 -403.548628) (xy 335.705015 -403.578094) (xy 335.746206 -403.613785)
			(xy 335.781899 -403.654976) (xy 335.811366 -403.700826) (xy 335.834008 -403.750404) (xy 335.849364 -403.8027)
			(xy 335.857121 -403.856648) (xy 335.857121 -403.911152) (xy 335.85712 -403.911156) (xy 337.294631 -403.911156)
			(xy 337.294631 -403.856644) (xy 337.302389 -403.802687) (xy 337.317748 -403.750384) (xy 337.340394 -403.700799)
			(xy 337.369866 -403.654941) (xy 337.405565 -403.613745) (xy 337.446764 -403.578049) (xy 337.492623 -403.54858)
			(xy 337.54221 -403.525938) (xy 337.594515 -403.510583) (xy 337.648472 -403.502829) (xy 337.675728 -403.502368)
			(xy 338.539328 -403.502368) (xy 338.566576 -403.502904) (xy 338.620517 -403.510663) (xy 338.672805 -403.52602)
			(xy 338.722376 -403.548661) (xy 338.76822 -403.578126) (xy 338.809404 -403.613816) (xy 338.84509 -403.655002)
			(xy 338.874552 -403.700849) (xy 338.89719 -403.750421) (xy 338.912543 -403.80271) (xy 338.920298 -403.856652)
			(xy 338.920298 -403.911148) (xy 338.920297 -403.911152) (xy 340.357954 -403.911152) (xy 340.357954 -403.856648)
			(xy 340.36571 -403.8027) (xy 340.381064 -403.750405) (xy 340.403705 -403.700826) (xy 340.43317 -403.654975)
			(xy 340.46886 -403.613783) (xy 340.510049 -403.578089) (xy 340.555898 -403.54862) (xy 340.605475 -403.525976)
			(xy 340.657769 -403.510617) (xy 340.711717 -403.502856) (xy 340.738968 -403.502368) (xy 341.602568 -403.502368)
			(xy 341.629821 -403.502877) (xy 341.683772 -403.51063) (xy 341.73607 -403.525982) (xy 341.785651 -403.548621)
			(xy 341.831505 -403.578087) (xy 341.872699 -403.613778) (xy 341.908394 -403.654969) (xy 341.937863 -403.700821)
			(xy 341.960507 -403.7504) (xy 341.975863 -403.802697) (xy 341.983621 -403.856647) (xy 341.983621 -403.911153)
			(xy 341.983621 -403.911155) (xy 343.421131 -403.911155) (xy 343.421131 -403.856645) (xy 343.428889 -403.80269)
			(xy 343.444246 -403.750388) (xy 343.466891 -403.700804) (xy 343.496361 -403.654948) (xy 343.532058 -403.613752)
			(xy 343.573254 -403.578056) (xy 343.619111 -403.548587) (xy 343.668696 -403.525943) (xy 343.720998 -403.510587)
			(xy 343.774953 -403.50283) (xy 343.802208 -403.502368) (xy 344.665808 -403.502368) (xy 344.693057 -403.502903)
			(xy 344.747001 -403.51066) (xy 344.799291 -403.526015) (xy 344.848864 -403.548655) (xy 344.89471 -403.578119)
			(xy 344.935897 -403.613809) (xy 344.971586 -403.654996) (xy 345.001049 -403.700843) (xy 345.023688 -403.750417)
			(xy 345.039042 -403.802707) (xy 345.046798 -403.856651) (xy 345.046798 -403.911149) (xy 345.046797 -403.911157)
			(xy 346.484331 -403.911157) (xy 346.484331 -403.856643) (xy 346.49209 -403.802685) (xy 346.507449 -403.75038)
			(xy 346.530097 -403.700793) (xy 346.559571 -403.654935) (xy 346.595272 -403.613738) (xy 346.636473 -403.578042)
			(xy 346.682335 -403.548574) (xy 346.731925 -403.525932) (xy 346.784232 -403.51058) (xy 346.838191 -403.502828)
			(xy 346.865448 -403.502368) (xy 347.729048 -403.502368) (xy 347.756295 -403.502905) (xy 347.810234 -403.510667)
			(xy 347.86252 -403.526025) (xy 347.912088 -403.548668) (xy 347.957929 -403.578133) (xy 347.999111 -403.613823)
			(xy 348.034795 -403.655009) (xy 348.064255 -403.700854) (xy 348.086891 -403.750425) (xy 348.102243 -403.802713)
			(xy 348.109998 -403.856653) (xy 348.109998 -403.911147) (xy 348.109997 -403.911152) (xy 349.547654 -403.911152)
			(xy 349.547654 -403.856648) (xy 349.55541 -403.802698) (xy 349.570766 -403.7504) (xy 349.593408 -403.700821)
			(xy 349.622875 -403.654968) (xy 349.658567 -403.613776) (xy 349.699759 -403.578082) (xy 349.74561 -403.548613)
			(xy 349.795189 -403.52597) (xy 349.847486 -403.510613) (xy 349.901436 -403.502855) (xy 349.928688 -403.502368)
			(xy 350.792288 -403.502368) (xy 350.81954 -403.502878) (xy 350.873489 -403.510634) (xy 350.925785 -403.525988)
			(xy 350.975363 -403.548628) (xy 351.021215 -403.578094) (xy 351.062406 -403.613785) (xy 351.098099 -403.654976)
			(xy 351.127566 -403.700826) (xy 351.150208 -403.750404) (xy 351.165564 -403.8027) (xy 351.173321 -403.856648)
			(xy 351.173321 -403.911152) (xy 351.17332 -403.911156) (xy 371.041831 -403.911156) (xy 371.041831 -403.856644)
			(xy 371.049589 -403.802687) (xy 371.064948 -403.750383) (xy 371.087594 -403.700798) (xy 371.117067 -403.654941)
			(xy 371.152766 -403.613745) (xy 371.193965 -403.578049) (xy 371.239824 -403.54858) (xy 371.289412 -403.525937)
			(xy 371.341716 -403.510583) (xy 371.395674 -403.502829) (xy 371.42293 -403.502368) (xy 372.28653 -403.502368)
			(xy 372.313778 -403.502904) (xy 372.367719 -403.510664) (xy 372.420007 -403.52602) (xy 372.469577 -403.548662)
			(xy 372.515421 -403.578127) (xy 372.556605 -403.613816) (xy 372.592291 -403.655003) (xy 372.621753 -403.700849)
			(xy 372.64439 -403.750421) (xy 372.659743 -403.80271) (xy 372.667498 -403.856652) (xy 372.667498 -403.911148)
			(xy 372.667497 -403.911152) (xy 374.105154 -403.911152) (xy 374.105154 -403.856648) (xy 374.11291 -403.8027)
			(xy 374.128265 -403.750404) (xy 374.150905 -403.700826) (xy 374.18037 -403.654974) (xy 374.216061 -403.613782)
			(xy 374.25725 -403.578088) (xy 374.3031 -403.548619) (xy 374.352676 -403.525975) (xy 374.404971 -403.510616)
			(xy 374.458918 -403.502856) (xy 374.48617 -403.502368) (xy 375.34977 -403.502368) (xy 375.377023 -403.502877)
			(xy 375.430973 -403.51063) (xy 375.483271 -403.525983) (xy 375.532852 -403.548622) (xy 375.578706 -403.578087)
			(xy 375.6199 -403.613779) (xy 375.655595 -403.65497) (xy 375.685064 -403.700821) (xy 375.707707 -403.7504)
			(xy 375.723063 -403.802697) (xy 375.730821 -403.856647) (xy 375.730821 -403.911153) (xy 375.730821 -403.911155)
			(xy 377.168331 -403.911155) (xy 377.168331 -403.856645) (xy 377.176089 -403.80269) (xy 377.191446 -403.750388)
			(xy 377.214091 -403.700804) (xy 377.243562 -403.654947) (xy 377.279259 -403.613752) (xy 377.320455 -403.578056)
			(xy 377.366313 -403.548586) (xy 377.415897 -403.525943) (xy 377.468199 -403.510587) (xy 377.522155 -403.50283)
			(xy 377.54941 -403.502368) (xy 378.41301 -403.502368) (xy 378.440259 -403.502903) (xy 378.494202 -403.51066)
			(xy 378.546492 -403.526015) (xy 378.596065 -403.548655) (xy 378.641911 -403.57812) (xy 378.683098 -403.613809)
			(xy 378.718786 -403.654997) (xy 378.748249 -403.700844) (xy 378.770888 -403.750417) (xy 378.786242 -403.802708)
			(xy 378.793998 -403.856651) (xy 378.793998 -403.911149) (xy 378.793998 -403.911151) (xy 380.231654 -403.911151)
			(xy 380.231654 -403.856649) (xy 380.239409 -403.802703) (xy 380.254763 -403.750409) (xy 380.277402 -403.700832)
			(xy 380.306865 -403.654981) (xy 380.342554 -403.613789) (xy 380.383741 -403.578095) (xy 380.429588 -403.548626)
			(xy 380.479162 -403.52598) (xy 380.531454 -403.51062) (xy 380.585399 -403.502857) (xy 380.61265 -403.502368)
			(xy 381.47625 -403.502368) (xy 381.503503 -403.502876) (xy 381.557456 -403.510627) (xy 381.609757 -403.525977)
			(xy 381.65934 -403.548616) (xy 381.705197 -403.57808) (xy 381.746393 -403.613772) (xy 381.78209 -403.654963)
			(xy 381.81156 -403.700816) (xy 381.834205 -403.750396) (xy 381.849563 -403.802695) (xy 381.857321 -403.856647)
			(xy 381.857321 -403.911153) (xy 383.294854 -403.911153) (xy 383.294854 -403.856647) (xy 383.302611 -403.802697)
			(xy 383.317966 -403.7504) (xy 383.340608 -403.70082) (xy 383.370075 -403.654968) (xy 383.405768 -403.613775)
			(xy 383.44696 -403.578081) (xy 383.492812 -403.548613) (xy 383.542391 -403.52597) (xy 383.594687 -403.510613)
			(xy 383.648638 -403.502855) (xy 383.67589 -403.502368) (xy 384.53949 -403.502368) (xy 384.566742 -403.502879)
			(xy 384.62069 -403.510634) (xy 384.672986 -403.525988) (xy 384.722564 -403.548629) (xy 384.768416 -403.578095)
			(xy 384.809607 -403.613786) (xy 384.845299 -403.654976) (xy 384.874767 -403.700827) (xy 384.897408 -403.750405)
			(xy 384.912764 -403.8027) (xy 384.920521 -403.856648) (xy 384.920521 -403.911152) (xy 384.92052 -403.911156)
			(xy 386.358031 -403.911156) (xy 386.358031 -403.856644) (xy 386.365789 -403.802687) (xy 386.381148 -403.750383)
			(xy 386.403794 -403.700798) (xy 386.433267 -403.654941) (xy 386.468966 -403.613745) (xy 386.510165 -403.578049)
			(xy 386.556024 -403.54858) (xy 386.605612 -403.525937) (xy 386.657916 -403.510583) (xy 386.711874 -403.502829)
			(xy 386.73913 -403.502368) (xy 387.60273 -403.502368) (xy 387.629978 -403.502904) (xy 387.683919 -403.510664)
			(xy 387.736207 -403.52602) (xy 387.785777 -403.548662) (xy 387.831621 -403.578127) (xy 387.872805 -403.613816)
			(xy 387.908491 -403.655003) (xy 387.937953 -403.700849) (xy 387.96059 -403.750421) (xy 387.975943 -403.80271)
			(xy 387.983698 -403.856652) (xy 387.983698 -403.911148) (xy 387.983697 -403.911152) (xy 389.421354 -403.911152)
			(xy 389.421354 -403.856648) (xy 389.42911 -403.8027) (xy 389.444465 -403.750404) (xy 389.467105 -403.700826)
			(xy 389.49657 -403.654974) (xy 389.532261 -403.613782) (xy 389.57345 -403.578088) (xy 389.6193 -403.548619)
			(xy 389.668876 -403.525975) (xy 389.721171 -403.510616) (xy 389.775118 -403.502856) (xy 389.80237 -403.502368)
			(xy 390.66597 -403.502368) (xy 390.693223 -403.502877) (xy 390.747173 -403.51063) (xy 390.799471 -403.525983)
			(xy 390.849052 -403.548622) (xy 390.894906 -403.578087) (xy 390.9361 -403.613779) (xy 390.971795 -403.65497)
			(xy 391.001264 -403.700821) (xy 391.023907 -403.7504) (xy 391.039263 -403.802697) (xy 391.047021 -403.856647)
			(xy 391.047021 -403.911153) (xy 391.047021 -403.911155) (xy 392.484531 -403.911155) (xy 392.484531 -403.856645)
			(xy 392.492289 -403.80269) (xy 392.507646 -403.750388) (xy 392.530291 -403.700804) (xy 392.559762 -403.654947)
			(xy 392.595459 -403.613752) (xy 392.636655 -403.578056) (xy 392.682513 -403.548586) (xy 392.732097 -403.525943)
			(xy 392.784399 -403.510587) (xy 392.838355 -403.50283) (xy 392.86561 -403.502368) (xy 393.72921 -403.502368)
			(xy 393.756459 -403.502903) (xy 393.810402 -403.51066) (xy 393.862692 -403.526015) (xy 393.912265 -403.548655)
			(xy 393.958111 -403.57812) (xy 393.999298 -403.613809) (xy 394.034986 -403.654997) (xy 394.064449 -403.700844)
			(xy 394.087088 -403.750417) (xy 394.102442 -403.802708) (xy 394.110198 -403.856651) (xy 394.110198 -403.911149)
			(xy 394.110198 -403.911151) (xy 395.547854 -403.911151) (xy 395.547854 -403.856649) (xy 395.555609 -403.802703)
			(xy 395.570963 -403.750409) (xy 395.593602 -403.700832) (xy 395.623065 -403.654981) (xy 395.658754 -403.613789)
			(xy 395.699941 -403.578095) (xy 395.745788 -403.548626) (xy 395.795362 -403.52598) (xy 395.847654 -403.51062)
			(xy 395.901599 -403.502857) (xy 395.92885 -403.502368) (xy 396.79245 -403.502368) (xy 396.819703 -403.502876)
			(xy 396.873656 -403.510627) (xy 396.925957 -403.525977) (xy 396.97554 -403.548616) (xy 397.021397 -403.57808)
			(xy 397.062593 -403.613772) (xy 397.09829 -403.654963) (xy 397.12776 -403.700816) (xy 397.150405 -403.750396)
			(xy 397.165763 -403.802695) (xy 397.173521 -403.856647) (xy 397.173521 -403.911153) (xy 398.611054 -403.911153)
			(xy 398.611054 -403.856647) (xy 398.618811 -403.802697) (xy 398.634166 -403.7504) (xy 398.656808 -403.70082)
			(xy 398.686275 -403.654968) (xy 398.721968 -403.613775) (xy 398.76316 -403.578081) (xy 398.809012 -403.548613)
			(xy 398.858591 -403.52597) (xy 398.910887 -403.510613) (xy 398.964838 -403.502855) (xy 398.99209 -403.502368)
			(xy 399.85569 -403.502368) (xy 399.882942 -403.502879) (xy 399.93689 -403.510634) (xy 399.989186 -403.525988)
			(xy 400.038764 -403.548629) (xy 400.084616 -403.578095) (xy 400.125807 -403.613786) (xy 400.161499 -403.654976)
			(xy 400.190967 -403.700827) (xy 400.213608 -403.750405) (xy 400.228964 -403.8027) (xy 400.236721 -403.856648)
			(xy 400.236721 -403.911152) (xy 400.23672 -403.911156) (xy 401.674231 -403.911156) (xy 401.674231 -403.856644)
			(xy 401.681989 -403.802687) (xy 401.697348 -403.750383) (xy 401.719994 -403.700798) (xy 401.749467 -403.654941)
			(xy 401.785166 -403.613745) (xy 401.826365 -403.578049) (xy 401.872224 -403.54858) (xy 401.921812 -403.525937)
			(xy 401.974116 -403.510583) (xy 402.028074 -403.502829) (xy 402.05533 -403.502368) (xy 402.91893 -403.502368)
			(xy 402.946178 -403.502904) (xy 403.000119 -403.510664) (xy 403.052407 -403.52602) (xy 403.101977 -403.548662)
			(xy 403.147821 -403.578127) (xy 403.189005 -403.613816) (xy 403.224691 -403.655003) (xy 403.254153 -403.700849)
			(xy 403.27679 -403.750421) (xy 403.292143 -403.80271) (xy 403.299898 -403.856652) (xy 403.299898 -403.911148)
			(xy 403.299897 -403.911152) (xy 404.737554 -403.911152) (xy 404.737554 -403.856648) (xy 404.74531 -403.8027)
			(xy 404.760665 -403.750404) (xy 404.783305 -403.700826) (xy 404.81277 -403.654974) (xy 404.848461 -403.613782)
			(xy 404.88965 -403.578088) (xy 404.9355 -403.548619) (xy 404.985076 -403.525975) (xy 405.037371 -403.510616)
			(xy 405.091318 -403.502856) (xy 405.11857 -403.502368) (xy 405.98217 -403.502368) (xy 406.009423 -403.502877)
			(xy 406.063373 -403.51063) (xy 406.115671 -403.525983) (xy 406.165252 -403.548622) (xy 406.211106 -403.578087)
			(xy 406.2523 -403.613779) (xy 406.287995 -403.65497) (xy 406.317464 -403.700821) (xy 406.340107 -403.7504)
			(xy 406.355463 -403.802697) (xy 406.363221 -403.856647) (xy 406.363221 -403.911153) (xy 406.363221 -403.911155)
			(xy 407.800731 -403.911155) (xy 407.800731 -403.856645) (xy 407.808489 -403.80269) (xy 407.823846 -403.750388)
			(xy 407.846491 -403.700804) (xy 407.875962 -403.654947) (xy 407.911659 -403.613752) (xy 407.952855 -403.578056)
			(xy 407.998713 -403.548586) (xy 408.048297 -403.525943) (xy 408.100599 -403.510587) (xy 408.154555 -403.50283)
			(xy 408.18181 -403.502368) (xy 409.04541 -403.502368) (xy 409.072659 -403.502903) (xy 409.126602 -403.51066)
			(xy 409.178892 -403.526015) (xy 409.228465 -403.548655) (xy 409.274311 -403.57812) (xy 409.315498 -403.613809)
			(xy 409.351186 -403.654997) (xy 409.380649 -403.700844) (xy 409.403288 -403.750417) (xy 409.418642 -403.802708)
			(xy 409.426398 -403.856651) (xy 409.426398 -403.911149) (xy 409.426398 -403.911151) (xy 410.864054 -403.911151)
			(xy 410.864054 -403.856649) (xy 410.871809 -403.802703) (xy 410.887163 -403.750409) (xy 410.909802 -403.700832)
			(xy 410.939265 -403.654981) (xy 410.974954 -403.613789) (xy 411.016141 -403.578095) (xy 411.061988 -403.548626)
			(xy 411.111562 -403.52598) (xy 411.163854 -403.51062) (xy 411.217799 -403.502857) (xy 411.24505 -403.502368)
			(xy 412.10865 -403.502368) (xy 412.135903 -403.502876) (xy 412.189856 -403.510627) (xy 412.242157 -403.525977)
			(xy 412.29174 -403.548616) (xy 412.337597 -403.57808) (xy 412.378793 -403.613772) (xy 412.41449 -403.654963)
			(xy 412.44396 -403.700816) (xy 412.466605 -403.750396) (xy 412.481963 -403.802695) (xy 412.489721 -403.856647)
			(xy 412.489721 -403.911153) (xy 413.927254 -403.911153) (xy 413.927254 -403.856647) (xy 413.935011 -403.802697)
			(xy 413.950366 -403.7504) (xy 413.973008 -403.70082) (xy 414.002475 -403.654968) (xy 414.038168 -403.613775)
			(xy 414.07936 -403.578081) (xy 414.125212 -403.548613) (xy 414.174791 -403.52597) (xy 414.227087 -403.510613)
			(xy 414.281038 -403.502855) (xy 414.30829 -403.502368) (xy 415.17189 -403.502368) (xy 415.199142 -403.502879)
			(xy 415.25309 -403.510634) (xy 415.305386 -403.525988) (xy 415.354964 -403.548629) (xy 415.400816 -403.578095)
			(xy 415.442007 -403.613786) (xy 415.477699 -403.654976) (xy 415.507167 -403.700827) (xy 415.529808 -403.750405)
			(xy 415.545164 -403.8027) (xy 415.552921 -403.856648) (xy 415.552921 -403.911152) (xy 415.55292 -403.911156)
			(xy 416.990431 -403.911156) (xy 416.990431 -403.856644) (xy 416.998189 -403.802687) (xy 417.013548 -403.750383)
			(xy 417.036194 -403.700798) (xy 417.065667 -403.654941) (xy 417.101366 -403.613745) (xy 417.142565 -403.578049)
			(xy 417.188424 -403.54858) (xy 417.238012 -403.525937) (xy 417.290316 -403.510583) (xy 417.344274 -403.502829)
			(xy 417.37153 -403.502368) (xy 418.23513 -403.502368) (xy 418.262378 -403.502904) (xy 418.316319 -403.510664)
			(xy 418.368607 -403.52602) (xy 418.418177 -403.548662) (xy 418.464021 -403.578127) (xy 418.505205 -403.613816)
			(xy 418.540891 -403.655003) (xy 418.570353 -403.700849) (xy 418.59299 -403.750421) (xy 418.608343 -403.80271)
			(xy 418.616098 -403.856652) (xy 418.616098 -403.911148) (xy 418.608343 -403.96509) (xy 418.59299 -404.017379)
			(xy 418.570353 -404.066951) (xy 418.540891 -404.112797) (xy 418.505205 -404.153984) (xy 418.464021 -404.189673)
			(xy 418.418177 -404.219138) (xy 418.368607 -404.24178) (xy 418.316319 -404.257136) (xy 418.262378 -404.264896)
			(xy 418.23513 -404.265384) (xy 417.37153 -404.265384) (xy 417.344274 -404.264971) (xy 417.290316 -404.257217)
			(xy 417.238012 -404.241863) (xy 417.188424 -404.21922) (xy 417.142565 -404.189751) (xy 417.101366 -404.154055)
			(xy 417.065667 -404.112859) (xy 417.036194 -404.067002) (xy 417.013548 -404.017417) (xy 416.998189 -403.965113)
			(xy 416.990431 -403.911156) (xy 415.55292 -403.911156) (xy 415.545164 -403.9651) (xy 415.529808 -404.017395)
			(xy 415.507167 -404.066973) (xy 415.477699 -404.112824) (xy 415.442007 -404.154014) (xy 415.400816 -404.189705)
			(xy 415.354964 -404.219171) (xy 415.305386 -404.241812) (xy 415.25309 -404.257166) (xy 415.199142 -404.264921)
			(xy 415.17189 -404.265384) (xy 414.30829 -404.265384) (xy 414.281038 -404.264945) (xy 414.227087 -404.257187)
			(xy 414.174791 -404.24183) (xy 414.125212 -404.219187) (xy 414.07936 -404.189719) (xy 414.038168 -404.154025)
			(xy 414.002475 -404.112832) (xy 413.973008 -404.06698) (xy 413.950366 -404.0174) (xy 413.935011 -403.965103)
			(xy 413.927254 -403.911153) (xy 412.489721 -403.911153) (xy 412.481963 -403.965105) (xy 412.466605 -404.017404)
			(xy 412.44396 -404.066984) (xy 412.41449 -404.112837) (xy 412.378793 -404.154028) (xy 412.337597 -404.18972)
			(xy 412.29174 -404.219184) (xy 412.242157 -404.241823) (xy 412.189856 -404.257173) (xy 412.135903 -404.264924)
			(xy 412.10865 -404.265384) (xy 411.24505 -404.265384) (xy 411.217799 -404.264943) (xy 411.163854 -404.25718)
			(xy 411.111562 -404.24182) (xy 411.061988 -404.219174) (xy 411.016141 -404.189705) (xy 410.974954 -404.154011)
			(xy 410.939265 -404.112819) (xy 410.909802 -404.066968) (xy 410.887163 -404.017391) (xy 410.871809 -403.965097)
			(xy 410.864054 -403.911151) (xy 409.426398 -403.911151) (xy 409.418642 -403.965092) (xy 409.403288 -404.017383)
			(xy 409.380649 -404.066956) (xy 409.351186 -404.112803) (xy 409.315498 -404.153991) (xy 409.274311 -404.18968)
			(xy 409.228465 -404.219145) (xy 409.178892 -404.241785) (xy 409.126602 -404.25714) (xy 409.072659 -404.264897)
			(xy 409.04541 -404.265384) (xy 408.18181 -404.265384) (xy 408.154555 -404.26497) (xy 408.100599 -404.257213)
			(xy 408.048297 -404.241857) (xy 407.998713 -404.219214) (xy 407.952855 -404.189744) (xy 407.911659 -404.154048)
			(xy 407.875962 -404.112853) (xy 407.846491 -404.066996) (xy 407.823846 -404.017412) (xy 407.808489 -403.96511)
			(xy 407.800731 -403.911155) (xy 406.363221 -403.911155) (xy 406.355463 -403.965103) (xy 406.340107 -404.0174)
			(xy 406.317464 -404.066979) (xy 406.287995 -404.11283) (xy 406.2523 -404.154021) (xy 406.211106 -404.189713)
			(xy 406.165252 -404.219178) (xy 406.115671 -404.241817) (xy 406.063373 -404.25717) (xy 406.009423 -404.264923)
			(xy 405.98217 -404.265384) (xy 405.11857 -404.265384) (xy 405.091318 -404.264944) (xy 405.037371 -404.257184)
			(xy 404.985076 -404.241825) (xy 404.9355 -404.219181) (xy 404.88965 -404.189712) (xy 404.848461 -404.154018)
			(xy 404.81277 -404.112826) (xy 404.783305 -404.066974) (xy 404.760665 -404.017396) (xy 404.74531 -403.9651)
			(xy 404.737554 -403.911152) (xy 403.299897 -403.911152) (xy 403.292143 -403.96509) (xy 403.27679 -404.017379)
			(xy 403.254153 -404.066951) (xy 403.224691 -404.112797) (xy 403.189005 -404.153984) (xy 403.147821 -404.189673)
			(xy 403.101977 -404.219138) (xy 403.052407 -404.24178) (xy 403.000119 -404.257136) (xy 402.946178 -404.264896)
			(xy 402.91893 -404.265384) (xy 402.05533 -404.265384) (xy 402.028074 -404.264971) (xy 401.974116 -404.257217)
			(xy 401.921812 -404.241863) (xy 401.872224 -404.21922) (xy 401.826365 -404.189751) (xy 401.785166 -404.154055)
			(xy 401.749467 -404.112859) (xy 401.719994 -404.067002) (xy 401.697348 -404.017417) (xy 401.681989 -403.965113)
			(xy 401.674231 -403.911156) (xy 400.23672 -403.911156) (xy 400.228964 -403.9651) (xy 400.213608 -404.017395)
			(xy 400.190967 -404.066973) (xy 400.161499 -404.112824) (xy 400.125807 -404.154014) (xy 400.084616 -404.189705)
			(xy 400.038764 -404.219171) (xy 399.989186 -404.241812) (xy 399.93689 -404.257166) (xy 399.882942 -404.264921)
			(xy 399.85569 -404.265384) (xy 398.99209 -404.265384) (xy 398.964838 -404.264945) (xy 398.910887 -404.257187)
			(xy 398.858591 -404.24183) (xy 398.809012 -404.219187) (xy 398.76316 -404.189719) (xy 398.721968 -404.154025)
			(xy 398.686275 -404.112832) (xy 398.656808 -404.06698) (xy 398.634166 -404.0174) (xy 398.618811 -403.965103)
			(xy 398.611054 -403.911153) (xy 397.173521 -403.911153) (xy 397.165763 -403.965105) (xy 397.150405 -404.017404)
			(xy 397.12776 -404.066984) (xy 397.09829 -404.112837) (xy 397.062593 -404.154028) (xy 397.021397 -404.18972)
			(xy 396.97554 -404.219184) (xy 396.925957 -404.241823) (xy 396.873656 -404.257173) (xy 396.819703 -404.264924)
			(xy 396.79245 -404.265384) (xy 395.92885 -404.265384) (xy 395.901599 -404.264943) (xy 395.847654 -404.25718)
			(xy 395.795362 -404.24182) (xy 395.745788 -404.219174) (xy 395.699941 -404.189705) (xy 395.658754 -404.154011)
			(xy 395.623065 -404.112819) (xy 395.593602 -404.066968) (xy 395.570963 -404.017391) (xy 395.555609 -403.965097)
			(xy 395.547854 -403.911151) (xy 394.110198 -403.911151) (xy 394.102442 -403.965092) (xy 394.087088 -404.017383)
			(xy 394.064449 -404.066956) (xy 394.034986 -404.112803) (xy 393.999298 -404.153991) (xy 393.958111 -404.18968)
			(xy 393.912265 -404.219145) (xy 393.862692 -404.241785) (xy 393.810402 -404.25714) (xy 393.756459 -404.264897)
			(xy 393.72921 -404.265384) (xy 392.86561 -404.265384) (xy 392.838355 -404.26497) (xy 392.784399 -404.257213)
			(xy 392.732097 -404.241857) (xy 392.682513 -404.219214) (xy 392.636655 -404.189744) (xy 392.595459 -404.154048)
			(xy 392.559762 -404.112853) (xy 392.530291 -404.066996) (xy 392.507646 -404.017412) (xy 392.492289 -403.96511)
			(xy 392.484531 -403.911155) (xy 391.047021 -403.911155) (xy 391.039263 -403.965103) (xy 391.023907 -404.0174)
			(xy 391.001264 -404.066979) (xy 390.971795 -404.11283) (xy 390.9361 -404.154021) (xy 390.894906 -404.189713)
			(xy 390.849052 -404.219178) (xy 390.799471 -404.241817) (xy 390.747173 -404.25717) (xy 390.693223 -404.264923)
			(xy 390.66597 -404.265384) (xy 389.80237 -404.265384) (xy 389.775118 -404.264944) (xy 389.721171 -404.257184)
			(xy 389.668876 -404.241825) (xy 389.6193 -404.219181) (xy 389.57345 -404.189712) (xy 389.532261 -404.154018)
			(xy 389.49657 -404.112826) (xy 389.467105 -404.066974) (xy 389.444465 -404.017396) (xy 389.42911 -403.9651)
			(xy 389.421354 -403.911152) (xy 387.983697 -403.911152) (xy 387.975943 -403.96509) (xy 387.96059 -404.017379)
			(xy 387.937953 -404.066951) (xy 387.908491 -404.112797) (xy 387.872805 -404.153984) (xy 387.831621 -404.189673)
			(xy 387.785777 -404.219138) (xy 387.736207 -404.24178) (xy 387.683919 -404.257136) (xy 387.629978 -404.264896)
			(xy 387.60273 -404.265384) (xy 386.73913 -404.265384) (xy 386.711874 -404.264971) (xy 386.657916 -404.257217)
			(xy 386.605612 -404.241863) (xy 386.556024 -404.21922) (xy 386.510165 -404.189751) (xy 386.468966 -404.154055)
			(xy 386.433267 -404.112859) (xy 386.403794 -404.067002) (xy 386.381148 -404.017417) (xy 386.365789 -403.965113)
			(xy 386.358031 -403.911156) (xy 384.92052 -403.911156) (xy 384.912764 -403.9651) (xy 384.897408 -404.017395)
			(xy 384.874767 -404.066973) (xy 384.845299 -404.112824) (xy 384.809607 -404.154014) (xy 384.768416 -404.189705)
			(xy 384.722564 -404.219171) (xy 384.672986 -404.241812) (xy 384.62069 -404.257166) (xy 384.566742 -404.264921)
			(xy 384.53949 -404.265384) (xy 383.67589 -404.265384) (xy 383.648638 -404.264945) (xy 383.594687 -404.257187)
			(xy 383.542391 -404.24183) (xy 383.492812 -404.219187) (xy 383.44696 -404.189719) (xy 383.405768 -404.154025)
			(xy 383.370075 -404.112832) (xy 383.340608 -404.06698) (xy 383.317966 -404.0174) (xy 383.302611 -403.965103)
			(xy 383.294854 -403.911153) (xy 381.857321 -403.911153) (xy 381.849563 -403.965105) (xy 381.834205 -404.017404)
			(xy 381.81156 -404.066984) (xy 381.78209 -404.112837) (xy 381.746393 -404.154028) (xy 381.705197 -404.18972)
			(xy 381.65934 -404.219184) (xy 381.609757 -404.241823) (xy 381.557456 -404.257173) (xy 381.503503 -404.264924)
			(xy 381.47625 -404.265384) (xy 380.61265 -404.265384) (xy 380.585399 -404.264943) (xy 380.531454 -404.25718)
			(xy 380.479162 -404.24182) (xy 380.429588 -404.219174) (xy 380.383741 -404.189705) (xy 380.342554 -404.154011)
			(xy 380.306865 -404.112819) (xy 380.277402 -404.066968) (xy 380.254763 -404.017391) (xy 380.239409 -403.965097)
			(xy 380.231654 -403.911151) (xy 378.793998 -403.911151) (xy 378.786242 -403.965092) (xy 378.770888 -404.017383)
			(xy 378.748249 -404.066956) (xy 378.718786 -404.112803) (xy 378.683098 -404.153991) (xy 378.641911 -404.18968)
			(xy 378.596065 -404.219145) (xy 378.546492 -404.241785) (xy 378.494202 -404.25714) (xy 378.440259 -404.264897)
			(xy 378.41301 -404.265384) (xy 377.54941 -404.265384) (xy 377.522155 -404.26497) (xy 377.468199 -404.257213)
			(xy 377.415897 -404.241857) (xy 377.366313 -404.219214) (xy 377.320455 -404.189744) (xy 377.279259 -404.154048)
			(xy 377.243562 -404.112853) (xy 377.214091 -404.066996) (xy 377.191446 -404.017412) (xy 377.176089 -403.96511)
			(xy 377.168331 -403.911155) (xy 375.730821 -403.911155) (xy 375.723063 -403.965103) (xy 375.707707 -404.0174)
			(xy 375.685064 -404.066979) (xy 375.655595 -404.11283) (xy 375.6199 -404.154021) (xy 375.578706 -404.189713)
			(xy 375.532852 -404.219178) (xy 375.483271 -404.241817) (xy 375.430973 -404.25717) (xy 375.377023 -404.264923)
			(xy 375.34977 -404.265384) (xy 374.48617 -404.265384) (xy 374.458918 -404.264944) (xy 374.404971 -404.257184)
			(xy 374.352676 -404.241825) (xy 374.3031 -404.219181) (xy 374.25725 -404.189712) (xy 374.216061 -404.154018)
			(xy 374.18037 -404.112826) (xy 374.150905 -404.066974) (xy 374.128265 -404.017396) (xy 374.11291 -403.9651)
			(xy 374.105154 -403.911152) (xy 372.667497 -403.911152) (xy 372.659743 -403.96509) (xy 372.64439 -404.017379)
			(xy 372.621753 -404.066951) (xy 372.592291 -404.112797) (xy 372.556605 -404.153984) (xy 372.515421 -404.189673)
			(xy 372.469577 -404.219138) (xy 372.420007 -404.24178) (xy 372.367719 -404.257136) (xy 372.313778 -404.264896)
			(xy 372.28653 -404.265384) (xy 371.42293 -404.265384) (xy 371.395674 -404.264971) (xy 371.341716 -404.257217)
			(xy 371.289412 -404.241863) (xy 371.239824 -404.21922) (xy 371.193965 -404.189751) (xy 371.152766 -404.154055)
			(xy 371.117067 -404.112859) (xy 371.087594 -404.067002) (xy 371.064948 -404.017417) (xy 371.049589 -403.965113)
			(xy 371.041831 -403.911156) (xy 351.17332 -403.911156) (xy 351.165564 -403.9651) (xy 351.150208 -404.017396)
			(xy 351.127566 -404.066974) (xy 351.098099 -404.112824) (xy 351.062406 -404.154015) (xy 351.021215 -404.189706)
			(xy 350.975363 -404.219172) (xy 350.925785 -404.241812) (xy 350.873489 -404.257166) (xy 350.81954 -404.264922)
			(xy 350.792288 -404.265384) (xy 349.928688 -404.265384) (xy 349.901436 -404.264945) (xy 349.847486 -404.257187)
			(xy 349.795189 -404.24183) (xy 349.74561 -404.219187) (xy 349.699759 -404.189718) (xy 349.658567 -404.154024)
			(xy 349.622875 -404.112832) (xy 349.593408 -404.066979) (xy 349.570766 -404.0174) (xy 349.55541 -403.965102)
			(xy 349.547654 -403.911152) (xy 348.109997 -403.911152) (xy 348.102243 -403.965087) (xy 348.086891 -404.017375)
			(xy 348.064255 -404.066946) (xy 348.034795 -404.112791) (xy 347.999111 -404.153977) (xy 347.957929 -404.189667)
			(xy 347.912088 -404.219132) (xy 347.86252 -404.241775) (xy 347.810234 -404.257133) (xy 347.756295 -404.264895)
			(xy 347.729048 -404.265384) (xy 346.865448 -404.265384) (xy 346.838191 -404.264972) (xy 346.784232 -404.25722)
			(xy 346.731925 -404.241868) (xy 346.682335 -404.219226) (xy 346.636473 -404.189758) (xy 346.595272 -404.154062)
			(xy 346.559571 -404.112865) (xy 346.530097 -404.067007) (xy 346.507449 -404.01742) (xy 346.49209 -403.965115)
			(xy 346.484331 -403.911157) (xy 345.046797 -403.911157) (xy 345.039042 -403.965093) (xy 345.023688 -404.017383)
			(xy 345.001049 -404.066957) (xy 344.971586 -404.112804) (xy 344.935897 -404.153991) (xy 344.89471 -404.189681)
			(xy 344.848864 -404.219145) (xy 344.799291 -404.241785) (xy 344.747001 -404.25714) (xy 344.693057 -404.264897)
			(xy 344.665808 -404.265384) (xy 343.802208 -404.265384) (xy 343.774953 -404.26497) (xy 343.720998 -404.257213)
			(xy 343.668696 -404.241857) (xy 343.619111 -404.219213) (xy 343.573254 -404.189744) (xy 343.532058 -404.154048)
			(xy 343.496361 -404.112852) (xy 343.466891 -404.066996) (xy 343.444246 -404.017412) (xy 343.428889 -403.96511)
			(xy 343.421131 -403.911155) (xy 341.983621 -403.911155) (xy 341.975863 -403.965103) (xy 341.960507 -404.0174)
			(xy 341.937863 -404.066979) (xy 341.908394 -404.112831) (xy 341.872699 -404.154022) (xy 341.831505 -404.189713)
			(xy 341.785651 -404.219179) (xy 341.73607 -404.241818) (xy 341.683772 -404.25717) (xy 341.629821 -404.264923)
			(xy 341.602568 -404.265384) (xy 340.738968 -404.265384) (xy 340.711717 -404.264944) (xy 340.657769 -404.257183)
			(xy 340.605475 -404.241824) (xy 340.555898 -404.21918) (xy 340.510049 -404.189711) (xy 340.46886 -404.154017)
			(xy 340.43317 -404.112825) (xy 340.403705 -404.066974) (xy 340.381064 -404.017395) (xy 340.36571 -403.9651)
			(xy 340.357954 -403.911152) (xy 338.920297 -403.911152) (xy 338.912543 -403.96509) (xy 338.89719 -404.017379)
			(xy 338.874552 -404.066951) (xy 338.84509 -404.112798) (xy 338.809404 -404.153984) (xy 338.76822 -404.189674)
			(xy 338.722376 -404.219139) (xy 338.672805 -404.24178) (xy 338.620517 -404.257137) (xy 338.566576 -404.264896)
			(xy 338.539328 -404.265384) (xy 337.675728 -404.265384) (xy 337.648472 -404.264971) (xy 337.594515 -404.257217)
			(xy 337.54221 -404.241862) (xy 337.492623 -404.21922) (xy 337.446764 -404.189751) (xy 337.405565 -404.154055)
			(xy 337.369866 -404.112859) (xy 337.340394 -404.067001) (xy 337.317748 -404.017416) (xy 337.302389 -403.965113)
			(xy 337.294631 -403.911156) (xy 335.85712 -403.911156) (xy 335.849364 -403.9651) (xy 335.834008 -404.017396)
			(xy 335.811366 -404.066974) (xy 335.781899 -404.112824) (xy 335.746206 -404.154015) (xy 335.705015 -404.189706)
			(xy 335.659163 -404.219172) (xy 335.609585 -404.241812) (xy 335.557289 -404.257166) (xy 335.50334 -404.264922)
			(xy 335.476088 -404.265384) (xy 334.612488 -404.265384) (xy 334.585236 -404.264945) (xy 334.531286 -404.257187)
			(xy 334.478989 -404.24183) (xy 334.42941 -404.219187) (xy 334.383559 -404.189718) (xy 334.342367 -404.154024)
			(xy 334.306675 -404.112832) (xy 334.277208 -404.066979) (xy 334.254566 -404.0174) (xy 334.23921 -403.965102)
			(xy 334.231454 -403.911152) (xy 332.793797 -403.911152) (xy 332.786043 -403.965087) (xy 332.770691 -404.017375)
			(xy 332.748055 -404.066946) (xy 332.718595 -404.112791) (xy 332.682911 -404.153977) (xy 332.641729 -404.189667)
			(xy 332.595888 -404.219132) (xy 332.54632 -404.241775) (xy 332.494034 -404.257133) (xy 332.440095 -404.264895)
			(xy 332.412848 -404.265384) (xy 331.549248 -404.265384) (xy 331.521991 -404.264972) (xy 331.468032 -404.25722)
			(xy 331.415725 -404.241868) (xy 331.366135 -404.219226) (xy 331.320273 -404.189758) (xy 331.279072 -404.154062)
			(xy 331.243371 -404.112865) (xy 331.213897 -404.067007) (xy 331.191249 -404.01742) (xy 331.17589 -403.965115)
			(xy 331.168131 -403.911157) (xy 329.730597 -403.911157) (xy 329.722842 -403.965093) (xy 329.707488 -404.017383)
			(xy 329.684849 -404.066957) (xy 329.655386 -404.112804) (xy 329.619697 -404.153991) (xy 329.57851 -404.189681)
			(xy 329.532664 -404.219145) (xy 329.483091 -404.241785) (xy 329.430801 -404.25714) (xy 329.376857 -404.264897)
			(xy 329.349608 -404.265384) (xy 328.486008 -404.265384) (xy 328.458753 -404.26497) (xy 328.404798 -404.257213)
			(xy 328.352496 -404.241857) (xy 328.302911 -404.219213) (xy 328.257054 -404.189744) (xy 328.215858 -404.154048)
			(xy 328.180161 -404.112852) (xy 328.150691 -404.066996) (xy 328.128046 -404.017412) (xy 328.112689 -403.96511)
			(xy 328.104931 -403.911155) (xy 326.667421 -403.911155) (xy 326.659663 -403.965103) (xy 326.644307 -404.0174)
			(xy 326.621663 -404.066979) (xy 326.592194 -404.112831) (xy 326.556499 -404.154022) (xy 326.515305 -404.189713)
			(xy 326.469451 -404.219179) (xy 326.41987 -404.241818) (xy 326.367572 -404.25717) (xy 326.313621 -404.264923)
			(xy 326.286368 -404.265384) (xy 325.422768 -404.265384) (xy 325.395517 -404.264944) (xy 325.341569 -404.257183)
			(xy 325.289275 -404.241824) (xy 325.239698 -404.21918) (xy 325.193849 -404.189711) (xy 325.15266 -404.154017)
			(xy 325.11697 -404.112825) (xy 325.087505 -404.066974) (xy 325.064864 -404.017395) (xy 325.04951 -403.9651)
			(xy 325.041754 -403.911152) (xy 323.604097 -403.911152) (xy 323.596343 -403.96509) (xy 323.58099 -404.017379)
			(xy 323.558352 -404.066951) (xy 323.52889 -404.112798) (xy 323.493204 -404.153984) (xy 323.45202 -404.189674)
			(xy 323.406176 -404.219139) (xy 323.356605 -404.24178) (xy 323.304317 -404.257137) (xy 323.250376 -404.264896)
			(xy 323.223128 -404.265384) (xy 322.359528 -404.265384) (xy 322.332272 -404.264971) (xy 322.278315 -404.257217)
			(xy 322.22601 -404.241862) (xy 322.176423 -404.21922) (xy 322.130564 -404.189751) (xy 322.089365 -404.154055)
			(xy 322.053666 -404.112859) (xy 322.024194 -404.067001) (xy 322.001548 -404.017416) (xy 321.986189 -403.965113)
			(xy 321.978431 -403.911156) (xy 320.54092 -403.911156) (xy 320.533164 -403.9651) (xy 320.517808 -404.017396)
			(xy 320.495166 -404.066974) (xy 320.465699 -404.112824) (xy 320.430006 -404.154015) (xy 320.388815 -404.189706)
			(xy 320.342963 -404.219172) (xy 320.293385 -404.241812) (xy 320.241089 -404.257166) (xy 320.18714 -404.264922)
			(xy 320.159888 -404.265384) (xy 319.296288 -404.265384) (xy 319.269036 -404.264945) (xy 319.215086 -404.257187)
			(xy 319.162789 -404.24183) (xy 319.11321 -404.219187) (xy 319.067359 -404.189718) (xy 319.026167 -404.154024)
			(xy 318.990475 -404.112832) (xy 318.961008 -404.066979) (xy 318.938366 -404.0174) (xy 318.92301 -403.965102)
			(xy 318.915254 -403.911152) (xy 317.477597 -403.911152) (xy 317.469843 -403.965087) (xy 317.454491 -404.017375)
			(xy 317.431855 -404.066946) (xy 317.402395 -404.112791) (xy 317.366711 -404.153977) (xy 317.325529 -404.189667)
			(xy 317.279688 -404.219132) (xy 317.23012 -404.241775) (xy 317.177834 -404.257133) (xy 317.123895 -404.264895)
			(xy 317.096648 -404.265384) (xy 316.233048 -404.265384) (xy 316.205791 -404.264972) (xy 316.151832 -404.25722)
			(xy 316.099525 -404.241868) (xy 316.049935 -404.219226) (xy 316.004073 -404.189758) (xy 315.962872 -404.154062)
			(xy 315.927171 -404.112865) (xy 315.897697 -404.067007) (xy 315.875049 -404.01742) (xy 315.85969 -403.965115)
			(xy 315.851931 -403.911157) (xy 314.414397 -403.911157) (xy 314.406642 -403.965093) (xy 314.391288 -404.017383)
			(xy 314.368649 -404.066957) (xy 314.339186 -404.112804) (xy 314.303497 -404.153991) (xy 314.26231 -404.189681)
			(xy 314.216464 -404.219145) (xy 314.166891 -404.241785) (xy 314.114601 -404.25714) (xy 314.060657 -404.264897)
			(xy 314.033408 -404.265384) (xy 313.169808 -404.265384) (xy 313.142553 -404.26497) (xy 313.088598 -404.257213)
			(xy 313.036296 -404.241857) (xy 312.986711 -404.219213) (xy 312.940854 -404.189744) (xy 312.899658 -404.154048)
			(xy 312.863961 -404.112852) (xy 312.834491 -404.066996) (xy 312.811846 -404.017412) (xy 312.796489 -403.96511)
			(xy 312.788731 -403.911155) (xy 311.351221 -403.911155) (xy 311.343463 -403.965103) (xy 311.328107 -404.0174)
			(xy 311.305463 -404.066979) (xy 311.275994 -404.112831) (xy 311.240299 -404.154022) (xy 311.199105 -404.189713)
			(xy 311.153251 -404.219179) (xy 311.10367 -404.241818) (xy 311.051372 -404.25717) (xy 310.997421 -404.264923)
			(xy 310.970168 -404.265384) (xy 310.106568 -404.265384) (xy 310.079317 -404.264944) (xy 310.025369 -404.257183)
			(xy 309.973075 -404.241824) (xy 309.923498 -404.21918) (xy 309.877649 -404.189711) (xy 309.83646 -404.154017)
			(xy 309.80077 -404.112825) (xy 309.771305 -404.066974) (xy 309.748664 -404.017395) (xy 309.73331 -403.9651)
			(xy 309.725554 -403.911152) (xy 308.287897 -403.911152) (xy 308.280143 -403.96509) (xy 308.26479 -404.017379)
			(xy 308.242152 -404.066951) (xy 308.21269 -404.112798) (xy 308.177004 -404.153984) (xy 308.13582 -404.189674)
			(xy 308.089976 -404.219139) (xy 308.040405 -404.24178) (xy 307.988117 -404.257137) (xy 307.934176 -404.264896)
			(xy 307.906928 -404.265384) (xy 307.043328 -404.265384) (xy 307.016072 -404.264971) (xy 306.962115 -404.257217)
			(xy 306.90981 -404.241862) (xy 306.860223 -404.21922) (xy 306.814364 -404.189751) (xy 306.773165 -404.154055)
			(xy 306.737466 -404.112859) (xy 306.707994 -404.067001) (xy 306.685348 -404.017416) (xy 306.669989 -403.965113)
			(xy 306.662231 -403.911156) (xy 305.22472 -403.911156) (xy 305.216964 -403.9651) (xy 305.201608 -404.017396)
			(xy 305.178966 -404.066974) (xy 305.149499 -404.112824) (xy 305.113806 -404.154015) (xy 305.072615 -404.189706)
			(xy 305.026763 -404.219172) (xy 304.977185 -404.241812) (xy 304.924889 -404.257166) (xy 304.87094 -404.264922)
			(xy 304.843688 -404.265384) (xy 303.980088 -404.265384) (xy 303.952836 -404.264945) (xy 303.898886 -404.257187)
			(xy 303.846589 -404.24183) (xy 303.79701 -404.219187) (xy 303.751159 -404.189718) (xy 303.709967 -404.154024)
			(xy 303.674275 -404.112832) (xy 303.644808 -404.066979) (xy 303.622166 -404.0174) (xy 303.60681 -403.965102)
			(xy 303.599054 -403.911152) (xy 298.836897 -403.911152) (xy 298.840074 -403.920931) (xy 298.852049 -403.983712)
			(xy 298.856063 -404.0475) (xy 298.852049 -404.111288) (xy 298.840074 -404.174069) (xy 298.820324 -404.234855)
			(xy 298.793112 -404.292686) (xy 298.758866 -404.346651) (xy 298.718128 -404.395898) (xy 298.671538 -404.439652)
			(xy 298.619832 -404.477221) (xy 298.563825 -404.508014) (xy 298.504401 -404.531545) (xy 298.442496 -404.547442)
			(xy 298.379087 -404.555456) (xy 298.34713 -404.55596) (xy 298.346876 -404.55596) (xy 298.315131 -404.555422)
			(xy 298.252136 -404.547497) (xy 298.190616 -404.531797) (xy 298.131527 -404.508566) (xy 298.075787 -404.478166)
			(xy 298.024261 -404.441069) (xy 298.000674 -404.419816) (xy 297.993411 -404.413632) (xy 297.975661 -404.406681)
			(xy 297.956599 -404.406681) (xy 297.938849 -404.413632) (xy 297.931586 -404.419816) (xy 297.908028 -404.441107)
			(xy 297.856512 -404.478235) (xy 297.800771 -404.508654) (xy 297.741674 -404.531889) (xy 297.680142 -404.547579)
			(xy 297.617135 -404.555478) (xy 297.585384 -404.55596) (xy 297.58513 -404.55596) (xy 297.553163 -404.555577)
			(xy 297.489734 -404.547567) (xy 297.427809 -404.531671) (xy 297.368364 -404.508138) (xy 297.312338 -404.47734)
			(xy 297.260613 -404.439763) (xy 297.214007 -404.395999) (xy 297.173253 -404.346739) (xy 297.138995 -404.292759)
			(xy 297.111773 -404.234911) (xy 297.092015 -404.174108) (xy 297.080035 -404.111307) (xy 297.07602 -404.0475)
			(xy 296.316063 -404.0475) (xy 296.312049 -404.111288) (xy 296.300074 -404.174069) (xy 296.280324 -404.234855)
			(xy 296.253112 -404.292686) (xy 296.218866 -404.346651) (xy 296.178128 -404.395898) (xy 296.131538 -404.439652)
			(xy 296.079832 -404.477221) (xy 296.023825 -404.508014) (xy 295.964401 -404.531545) (xy 295.902496 -404.547442)
			(xy 295.839087 -404.555456) (xy 295.80713 -404.55596) (xy 295.806876 -404.55596) (xy 295.775131 -404.555422)
			(xy 295.712136 -404.547497) (xy 295.650616 -404.531797) (xy 295.591527 -404.508566) (xy 295.535787 -404.478166)
			(xy 295.484261 -404.441069) (xy 295.460674 -404.419816) (xy 295.453411 -404.413632) (xy 295.435661 -404.406681)
			(xy 295.416599 -404.406681) (xy 295.398849 -404.413632) (xy 295.391586 -404.419816) (xy 295.368028 -404.441107)
			(xy 295.316512 -404.478235) (xy 295.260771 -404.508654) (xy 295.201674 -404.531889) (xy 295.140142 -404.547579)
			(xy 295.077135 -404.555478) (xy 295.045384 -404.55596) (xy 295.04513 -404.55596) (xy 295.013163 -404.555577)
			(xy 294.949734 -404.547567) (xy 294.887809 -404.531671) (xy 294.828364 -404.508138) (xy 294.772338 -404.47734)
			(xy 294.720613 -404.439763) (xy 294.674007 -404.395999) (xy 294.633253 -404.346739) (xy 294.598995 -404.292759)
			(xy 294.571773 -404.234911) (xy 294.552015 -404.174108) (xy 294.540035 -404.111307) (xy 294.53602 -404.0475)
			(xy 293.926484 -404.0475) (xy 293.92247 -404.111293) (xy 293.910493 -404.174079) (xy 293.890741 -404.23487)
			(xy 293.863525 -404.292705) (xy 293.829276 -404.346674) (xy 293.788532 -404.395924) (xy 293.741937 -404.439679)
			(xy 293.690226 -404.47725) (xy 293.634213 -404.508043) (xy 293.574783 -404.531573) (xy 293.512872 -404.547468)
			(xy 293.449457 -404.555479) (xy 293.417498 -404.55596) (xy 293.417244 -404.55596) (xy 293.385498 -404.555442)
			(xy 293.322502 -404.547512) (xy 293.260982 -404.531809) (xy 293.201894 -404.508575) (xy 293.146154 -404.478171)
			(xy 293.094629 -404.44107) (xy 293.071042 -404.419816) (xy 293.063779 -404.413632) (xy 293.046029 -404.406681)
			(xy 293.026967 -404.406681) (xy 293.009217 -404.413632) (xy 293.001954 -404.419816) (xy 292.978367 -404.441074)
			(xy 292.926858 -404.478206) (xy 292.871123 -404.50863) (xy 292.812032 -404.531871) (xy 292.750504 -404.547567)
			(xy 292.687501 -404.555474) (xy 292.655752 -404.55596) (xy 292.655498 -404.55596) (xy 292.623534 -404.555554)
			(xy 292.56011 -404.547542) (xy 292.498191 -404.531643) (xy 292.438752 -404.50811) (xy 292.382731 -404.477312)
			(xy 292.331013 -404.439736) (xy 292.284411 -404.395974) (xy 292.243662 -404.346717) (xy 292.209408 -404.29274)
			(xy 292.182189 -404.234897) (xy 292.162434 -404.174098) (xy 292.150455 -404.111302) (xy 292.146441 -404.0475)
			(xy 291.386484 -404.0475) (xy 291.38247 -404.111293) (xy 291.370493 -404.174079) (xy 291.350741 -404.23487)
			(xy 291.323525 -404.292705) (xy 291.289276 -404.346674) (xy 291.248532 -404.395924) (xy 291.201937 -404.439679)
			(xy 291.150226 -404.47725) (xy 291.094213 -404.508043) (xy 291.034783 -404.531573) (xy 290.972872 -404.547468)
			(xy 290.909457 -404.555479) (xy 290.877498 -404.55596) (xy 290.877244 -404.55596) (xy 290.845498 -404.555442)
			(xy 290.782502 -404.547512) (xy 290.720982 -404.531809) (xy 290.661894 -404.508575) (xy 290.606154 -404.478171)
			(xy 290.554629 -404.44107) (xy 290.531042 -404.419816) (xy 290.523779 -404.413632) (xy 290.506029 -404.406681)
			(xy 290.486967 -404.406681) (xy 290.469217 -404.413632) (xy 290.461954 -404.419816) (xy 290.438367 -404.441074)
			(xy 290.386858 -404.478206) (xy 290.331123 -404.50863) (xy 290.272032 -404.531871) (xy 290.210504 -404.547567)
			(xy 290.147501 -404.555474) (xy 290.115752 -404.55596) (xy 290.115498 -404.55596) (xy 290.083534 -404.555554)
			(xy 290.02011 -404.547542) (xy 289.958191 -404.531643) (xy 289.898752 -404.50811) (xy 289.842731 -404.477312)
			(xy 289.791013 -404.439736) (xy 289.744411 -404.395974) (xy 289.703662 -404.346717) (xy 289.669408 -404.29274)
			(xy 289.642189 -404.234897) (xy 289.622434 -404.174098) (xy 289.610455 -404.111302) (xy 289.606441 -404.0475)
			(xy 288.846484 -404.0475) (xy 288.84247 -404.111293) (xy 288.830493 -404.174079) (xy 288.810741 -404.23487)
			(xy 288.783525 -404.292705) (xy 288.749276 -404.346674) (xy 288.708532 -404.395924) (xy 288.661937 -404.439679)
			(xy 288.610226 -404.47725) (xy 288.554213 -404.508043) (xy 288.494783 -404.531573) (xy 288.432872 -404.547468)
			(xy 288.369457 -404.555479) (xy 288.337498 -404.55596) (xy 288.337244 -404.55596) (xy 288.305498 -404.555442)
			(xy 288.242502 -404.547512) (xy 288.180982 -404.531809) (xy 288.121894 -404.508575) (xy 288.066154 -404.478171)
			(xy 288.014629 -404.44107) (xy 287.991042 -404.419816) (xy 287.983779 -404.413632) (xy 287.966029 -404.406681)
			(xy 287.946967 -404.406681) (xy 287.929217 -404.413632) (xy 287.921954 -404.419816) (xy 287.898367 -404.441074)
			(xy 287.846858 -404.478206) (xy 287.791123 -404.50863) (xy 287.732032 -404.531871) (xy 287.670504 -404.547567)
			(xy 287.607501 -404.555474) (xy 287.575752 -404.55596) (xy 287.575498 -404.55596) (xy 287.543534 -404.555554)
			(xy 287.48011 -404.547542) (xy 287.418191 -404.531643) (xy 287.358752 -404.50811) (xy 287.302731 -404.477312)
			(xy 287.251013 -404.439736) (xy 287.204411 -404.395974) (xy 287.163662 -404.346717) (xy 287.129408 -404.29274)
			(xy 287.102189 -404.234897) (xy 287.082434 -404.174098) (xy 287.070455 -404.111302) (xy 287.066441 -404.0475)
			(xy 167.31136 -404.0475) (xy 167.302461 -404.066983) (xy 167.272991 -404.112836) (xy 167.237294 -404.154027)
			(xy 167.196099 -404.189718) (xy 167.150243 -404.219183) (xy 167.10066 -404.241822) (xy 167.04836 -404.257173)
			(xy 166.994407 -404.264924) (xy 166.967154 -404.265384) (xy 166.103554 -404.265384) (xy 166.076303 -404.264943)
			(xy 166.022357 -404.257181) (xy 165.970065 -404.241821) (xy 165.92049 -404.219175) (xy 165.874642 -404.189706)
			(xy 165.833455 -404.154012) (xy 165.797766 -404.112821) (xy 165.768302 -404.06697) (xy 165.745663 -404.017392)
			(xy 165.73031 -403.965098) (xy 165.722554 -403.911151) (xy 164.284898 -403.911151) (xy 164.277142 -403.965092)
			(xy 164.261789 -404.017382) (xy 164.23915 -404.066955) (xy 164.209687 -404.112802) (xy 164.173999 -404.153989)
			(xy 164.132813 -404.189679) (xy 164.086968 -404.219143) (xy 164.037395 -404.241784) (xy 163.985106 -404.257139)
			(xy 163.931163 -404.264897) (xy 163.903914 -404.265384) (xy 163.040314 -404.265384) (xy 163.013059 -404.26497)
			(xy 162.959103 -404.257214) (xy 162.9068 -404.241858) (xy 162.857215 -404.219215) (xy 162.811357 -404.189746)
			(xy 162.77016 -404.15405) (xy 162.734463 -404.112854) (xy 162.704991 -404.066997) (xy 162.682346 -404.017413)
			(xy 162.666989 -403.965111) (xy 162.659231 -403.911155) (xy 161.221721 -403.911155) (xy 161.213963 -403.965102)
			(xy 161.198607 -404.017399) (xy 161.175964 -404.066978) (xy 161.146496 -404.112829) (xy 161.110801 -404.15402)
			(xy 161.069608 -404.189711) (xy 161.023755 -404.219177) (xy 160.974174 -404.241816) (xy 160.921877 -404.257169)
			(xy 160.867926 -404.264922) (xy 160.840674 -404.265384) (xy 159.977074 -404.265384) (xy 159.949822 -404.264944)
			(xy 159.895874 -404.257184) (xy 159.843579 -404.241826) (xy 159.794002 -404.219182) (xy 159.748152 -404.189713)
			(xy 159.706962 -404.154019) (xy 159.671271 -404.112827) (xy 159.641806 -404.066975) (xy 159.619165 -404.017397)
			(xy 159.60381 -403.965101) (xy 159.596054 -403.911152) (xy 158.158397 -403.911152) (xy 158.150643 -403.965089)
			(xy 158.13529 -404.017378) (xy 158.112653 -404.06695) (xy 158.083192 -404.112796) (xy 158.047506 -404.153982)
			(xy 158.006323 -404.189671) (xy 157.96048 -404.219137) (xy 157.91091 -404.241778) (xy 157.858623 -404.257136)
			(xy 157.804682 -404.264895) (xy 157.777434 -404.265384) (xy 156.913834 -404.265384) (xy 156.886578 -404.264971)
			(xy 156.83262 -404.257218) (xy 156.780314 -404.241864) (xy 156.730727 -404.219222) (xy 156.684867 -404.189753)
			(xy 156.643667 -404.154057) (xy 156.607968 -404.112861) (xy 156.578495 -404.067003) (xy 156.555848 -404.017417)
			(xy 156.540489 -403.965114) (xy 156.532731 -403.911156) (xy 155.09522 -403.911156) (xy 155.087464 -403.965099)
			(xy 155.072109 -404.017394) (xy 155.049467 -404.066972) (xy 155.02 -404.112822) (xy 154.984308 -404.154013)
			(xy 154.943118 -404.189704) (xy 154.897267 -404.21917) (xy 154.847689 -404.241811) (xy 154.795394 -404.257165)
			(xy 154.741445 -404.264921) (xy 154.714194 -404.265384) (xy 153.850594 -404.265384) (xy 153.823341 -404.264946)
			(xy 153.769391 -404.257188) (xy 153.717094 -404.241831) (xy 153.667514 -404.219189) (xy 153.621661 -404.18972)
			(xy 153.580469 -404.154026) (xy 153.544776 -404.112834) (xy 153.515309 -404.066981) (xy 153.492666 -404.017401)
			(xy 153.477311 -403.965103) (xy 153.469554 -403.911153) (xy 152.032021 -403.911153) (xy 152.024263 -403.965105)
			(xy 152.008906 -404.017403) (xy 151.986261 -404.066983) (xy 151.956791 -404.112836) (xy 151.921094 -404.154027)
			(xy 151.879899 -404.189718) (xy 151.834043 -404.219183) (xy 151.78446 -404.241822) (xy 151.73216 -404.257173)
			(xy 151.678207 -404.264924) (xy 151.650954 -404.265384) (xy 150.787354 -404.265384) (xy 150.760103 -404.264943)
			(xy 150.706157 -404.257181) (xy 150.653865 -404.241821) (xy 150.60429 -404.219175) (xy 150.558442 -404.189706)
			(xy 150.517255 -404.154012) (xy 150.481566 -404.112821) (xy 150.452102 -404.06697) (xy 150.429463 -404.017392)
			(xy 150.41411 -403.965098) (xy 150.406354 -403.911151) (xy 148.968698 -403.911151) (xy 148.960942 -403.965092)
			(xy 148.945589 -404.017382) (xy 148.92295 -404.066955) (xy 148.893487 -404.112802) (xy 148.857799 -404.153989)
			(xy 148.816613 -404.189679) (xy 148.770768 -404.219143) (xy 148.721195 -404.241784) (xy 148.668906 -404.257139)
			(xy 148.614963 -404.264897) (xy 148.587714 -404.265384) (xy 147.724114 -404.265384) (xy 147.696859 -404.26497)
			(xy 147.642903 -404.257214) (xy 147.5906 -404.241858) (xy 147.541015 -404.219215) (xy 147.495157 -404.189746)
			(xy 147.45396 -404.15405) (xy 147.418263 -404.112854) (xy 147.388791 -404.066997) (xy 147.366146 -404.017413)
			(xy 147.350789 -403.965111) (xy 147.343031 -403.911155) (xy 145.905521 -403.911155) (xy 145.897763 -403.965102)
			(xy 145.882407 -404.017399) (xy 145.859764 -404.066978) (xy 145.830296 -404.112829) (xy 145.794601 -404.15402)
			(xy 145.753408 -404.189711) (xy 145.707555 -404.219177) (xy 145.657974 -404.241816) (xy 145.605677 -404.257169)
			(xy 145.551726 -404.264922) (xy 145.524474 -404.265384) (xy 144.660874 -404.265384) (xy 144.633622 -404.264944)
			(xy 144.579674 -404.257184) (xy 144.527379 -404.241826) (xy 144.477802 -404.219182) (xy 144.431952 -404.189713)
			(xy 144.390762 -404.154019) (xy 144.355071 -404.112827) (xy 144.325606 -404.066975) (xy 144.302965 -404.017397)
			(xy 144.28761 -403.965101) (xy 144.279854 -403.911152) (xy 142.842197 -403.911152) (xy 142.834443 -403.965089)
			(xy 142.81909 -404.017378) (xy 142.796453 -404.06695) (xy 142.766992 -404.112796) (xy 142.731306 -404.153982)
			(xy 142.690123 -404.189671) (xy 142.64428 -404.219137) (xy 142.59471 -404.241778) (xy 142.542423 -404.257136)
			(xy 142.488482 -404.264895) (xy 142.461234 -404.265384) (xy 141.597634 -404.265384) (xy 141.570378 -404.264971)
			(xy 141.51642 -404.257218) (xy 141.464114 -404.241864) (xy 141.414527 -404.219222) (xy 141.368667 -404.189753)
			(xy 141.327467 -404.154057) (xy 141.291768 -404.112861) (xy 141.262295 -404.067003) (xy 141.239648 -404.017417)
			(xy 141.224289 -403.965114) (xy 141.216531 -403.911156) (xy 139.77902 -403.911156) (xy 139.771264 -403.965099)
			(xy 139.755909 -404.017394) (xy 139.733267 -404.066972) (xy 139.7038 -404.112822) (xy 139.668108 -404.154013)
			(xy 139.626918 -404.189704) (xy 139.581067 -404.21917) (xy 139.531489 -404.241811) (xy 139.479194 -404.257165)
			(xy 139.425245 -404.264921) (xy 139.397994 -404.265384) (xy 138.534394 -404.265384) (xy 138.507141 -404.264946)
			(xy 138.453191 -404.257188) (xy 138.400894 -404.241831) (xy 138.351314 -404.219189) (xy 138.305461 -404.18972)
			(xy 138.264269 -404.154026) (xy 138.228576 -404.112834) (xy 138.199109 -404.066981) (xy 138.176466 -404.017401)
			(xy 138.161111 -403.965103) (xy 138.153354 -403.911153) (xy 136.715821 -403.911153) (xy 136.708063 -403.965105)
			(xy 136.692706 -404.017403) (xy 136.670061 -404.066983) (xy 136.640591 -404.112836) (xy 136.604894 -404.154027)
			(xy 136.563699 -404.189718) (xy 136.517843 -404.219183) (xy 136.46826 -404.241822) (xy 136.41596 -404.257173)
			(xy 136.362007 -404.264924) (xy 136.334754 -404.265384) (xy 135.471154 -404.265384) (xy 135.443903 -404.264943)
			(xy 135.389957 -404.257181) (xy 135.337665 -404.241821) (xy 135.28809 -404.219175) (xy 135.242242 -404.189706)
			(xy 135.201055 -404.154012) (xy 135.165366 -404.112821) (xy 135.135902 -404.06697) (xy 135.113263 -404.017392)
			(xy 135.09791 -403.965098) (xy 135.090154 -403.911151) (xy 133.652498 -403.911151) (xy 133.644742 -403.965092)
			(xy 133.629389 -404.017382) (xy 133.60675 -404.066955) (xy 133.577287 -404.112802) (xy 133.541599 -404.153989)
			(xy 133.500413 -404.189679) (xy 133.454568 -404.219143) (xy 133.404995 -404.241784) (xy 133.352706 -404.257139)
			(xy 133.298763 -404.264897) (xy 133.271514 -404.265384) (xy 132.407914 -404.265384) (xy 132.380659 -404.26497)
			(xy 132.326703 -404.257214) (xy 132.2744 -404.241858) (xy 132.224815 -404.219215) (xy 132.178957 -404.189746)
			(xy 132.13776 -404.15405) (xy 132.102063 -404.112854) (xy 132.072591 -404.066997) (xy 132.049946 -404.017413)
			(xy 132.034589 -403.965111) (xy 132.026831 -403.911155) (xy 130.589321 -403.911155) (xy 130.581563 -403.965102)
			(xy 130.566207 -404.017399) (xy 130.543564 -404.066978) (xy 130.514096 -404.112829) (xy 130.478401 -404.15402)
			(xy 130.437208 -404.189711) (xy 130.391355 -404.219177) (xy 130.341774 -404.241816) (xy 130.289477 -404.257169)
			(xy 130.235526 -404.264922) (xy 130.208274 -404.265384) (xy 129.344674 -404.265384) (xy 129.317422 -404.264944)
			(xy 129.263474 -404.257184) (xy 129.211179 -404.241826) (xy 129.161602 -404.219182) (xy 129.115752 -404.189713)
			(xy 129.074562 -404.154019) (xy 129.038871 -404.112827) (xy 129.009406 -404.066975) (xy 128.986765 -404.017397)
			(xy 128.97141 -403.965101) (xy 128.963654 -403.911152) (xy 127.525997 -403.911152) (xy 127.518243 -403.965089)
			(xy 127.50289 -404.017378) (xy 127.480253 -404.06695) (xy 127.450792 -404.112796) (xy 127.415106 -404.153982)
			(xy 127.373923 -404.189671) (xy 127.32808 -404.219137) (xy 127.27851 -404.241778) (xy 127.226223 -404.257136)
			(xy 127.172282 -404.264895) (xy 127.145034 -404.265384) (xy 126.281434 -404.265384) (xy 126.254178 -404.264971)
			(xy 126.20022 -404.257218) (xy 126.147914 -404.241864) (xy 126.098327 -404.219222) (xy 126.052467 -404.189753)
			(xy 126.011267 -404.154057) (xy 125.975568 -404.112861) (xy 125.946095 -404.067003) (xy 125.923448 -404.017417)
			(xy 125.908089 -403.965114) (xy 125.900331 -403.911156) (xy 124.46282 -403.911156) (xy 124.455064 -403.965099)
			(xy 124.439709 -404.017394) (xy 124.417067 -404.066972) (xy 124.3876 -404.112822) (xy 124.351908 -404.154013)
			(xy 124.310718 -404.189704) (xy 124.264867 -404.21917) (xy 124.215289 -404.241811) (xy 124.162994 -404.257165)
			(xy 124.109045 -404.264921) (xy 124.081794 -404.265384) (xy 123.218194 -404.265384) (xy 123.190941 -404.264946)
			(xy 123.136991 -404.257188) (xy 123.084694 -404.241831) (xy 123.035114 -404.219189) (xy 122.989261 -404.18972)
			(xy 122.948069 -404.154026) (xy 122.912376 -404.112834) (xy 122.882909 -404.066981) (xy 122.860266 -404.017401)
			(xy 122.844911 -403.965103) (xy 122.837154 -403.911153) (xy 121.399621 -403.911153) (xy 121.391863 -403.965105)
			(xy 121.376506 -404.017403) (xy 121.353861 -404.066983) (xy 121.324391 -404.112836) (xy 121.288694 -404.154027)
			(xy 121.247499 -404.189718) (xy 121.201643 -404.219183) (xy 121.15206 -404.241822) (xy 121.09976 -404.257173)
			(xy 121.045807 -404.264924) (xy 121.018554 -404.265384) (xy 120.154954 -404.265384) (xy 120.127703 -404.264943)
			(xy 120.073757 -404.257181) (xy 120.021465 -404.241821) (xy 119.97189 -404.219175) (xy 119.926042 -404.189706)
			(xy 119.884855 -404.154012) (xy 119.849166 -404.112821) (xy 119.819702 -404.06697) (xy 119.797063 -404.017392)
			(xy 119.78171 -403.965098) (xy 119.773954 -403.911151) (xy 95.172998 -403.911151) (xy 95.165243 -403.965089)
			(xy 95.149891 -404.017377) (xy 95.127254 -404.066949) (xy 95.097793 -404.112794) (xy 95.062108 -404.153981)
			(xy 95.020925 -404.18967) (xy 94.975082 -404.219135) (xy 94.925513 -404.241777) (xy 94.873226 -404.257135)
			(xy 94.819286 -404.264895) (xy 94.792038 -404.265384) (xy 93.928438 -404.265384) (xy 93.901182 -404.264972)
			(xy 93.847223 -404.257219) (xy 93.794917 -404.241865) (xy 93.745329 -404.219223) (xy 93.699468 -404.189754)
			(xy 93.658269 -404.154058) (xy 93.622569 -404.112862) (xy 93.593095 -404.067004) (xy 93.570448 -404.017418)
			(xy 93.555089 -403.965114) (xy 93.547331 -403.911156) (xy 92.10982 -403.911156) (xy 92.102064 -403.965099)
			(xy 92.086709 -404.017394) (xy 92.064068 -404.066971) (xy 92.034601 -404.112821) (xy 91.99891 -404.154011)
			(xy 91.95772 -404.189703) (xy 91.911869 -404.219169) (xy 91.862292 -404.24181) (xy 91.809997 -404.257165)
			(xy 91.756049 -404.264921) (xy 91.728798 -404.265384) (xy 90.865198 -404.265384) (xy 90.837945 -404.264946)
			(xy 90.783994 -404.257189) (xy 90.731696 -404.241833) (xy 90.682116 -404.21919) (xy 90.636263 -404.189722)
			(xy 90.595071 -404.154028) (xy 90.559377 -404.112835) (xy 90.529909 -404.066982) (xy 90.507267 -404.017402)
			(xy 90.491911 -403.965104) (xy 90.484154 -403.911153) (xy 89.046621 -403.911153) (xy 89.038863 -403.965104)
			(xy 89.023506 -404.017402) (xy 89.000862 -404.066982) (xy 88.971392 -404.112834) (xy 88.935696 -404.154025)
			(xy 88.894501 -404.189717) (xy 88.848645 -404.219182) (xy 88.799063 -404.241821) (xy 88.746763 -404.257172)
			(xy 88.692811 -404.264924) (xy 88.665558 -404.265384) (xy 87.801958 -404.265384) (xy 87.774707 -404.264943)
			(xy 87.72076 -404.257181) (xy 87.668467 -404.241822) (xy 87.618892 -404.219177) (xy 87.573044 -404.189707)
			(xy 87.531857 -404.154014) (xy 87.496167 -404.112822) (xy 87.466703 -404.066971) (xy 87.444064 -404.017393)
			(xy 87.42871 -403.965098) (xy 87.420954 -403.911151) (xy 85.983298 -403.911151) (xy 85.975542 -403.965091)
			(xy 85.960189 -404.017381) (xy 85.937551 -404.066954) (xy 85.908088 -404.112801) (xy 85.872401 -404.153988)
			(xy 85.831215 -404.189677) (xy 85.78537 -404.219142) (xy 85.735798 -404.241783) (xy 85.683509 -404.257138)
			(xy 85.629567 -404.264897) (xy 85.602318 -404.265384) (xy 84.738718 -404.265384) (xy 84.711463 -404.26497)
			(xy 84.657506 -404.257215) (xy 84.605203 -404.241859) (xy 84.555617 -404.219217) (xy 84.509759 -404.189747)
			(xy 84.468562 -404.154051) (xy 84.432864 -404.112855) (xy 84.403392 -404.066999) (xy 84.380747 -404.017414)
			(xy 84.365389 -403.965111) (xy 84.357631 -403.911155) (xy 82.920121 -403.911155) (xy 82.912364 -403.965102)
			(xy 82.897007 -404.017398) (xy 82.874365 -404.066976) (xy 82.844897 -404.112828) (xy 82.809203 -404.154018)
			(xy 82.76801 -404.18971) (xy 82.722157 -404.219175) (xy 82.672577 -404.241815) (xy 82.62028 -404.257168)
			(xy 82.56633 -404.264922) (xy 82.539078 -404.265384) (xy 81.675478 -404.265384) (xy 81.648226 -404.264945)
			(xy 81.594277 -404.257185) (xy 81.541982 -404.241827) (xy 81.492404 -404.219183) (xy 81.446554 -404.189715)
			(xy 81.405364 -404.154021) (xy 81.369672 -404.112829) (xy 81.340206 -404.066976) (xy 81.317565 -404.017397)
			(xy 81.30221 -403.965101) (xy 81.294454 -403.911152) (xy 79.856797 -403.911152) (xy 79.849043 -403.965089)
			(xy 79.833691 -404.017377) (xy 79.811054 -404.066949) (xy 79.781593 -404.112794) (xy 79.745908 -404.153981)
			(xy 79.704725 -404.18967) (xy 79.658882 -404.219135) (xy 79.609313 -404.241777) (xy 79.557026 -404.257135)
			(xy 79.503086 -404.264895) (xy 79.475838 -404.265384) (xy 78.612238 -404.265384) (xy 78.584982 -404.264972)
			(xy 78.531023 -404.257219) (xy 78.478717 -404.241865) (xy 78.429129 -404.219223) (xy 78.383268 -404.189754)
			(xy 78.342069 -404.154058) (xy 78.306369 -404.112862) (xy 78.276895 -404.067004) (xy 78.254248 -404.017418)
			(xy 78.238889 -403.965114) (xy 78.231131 -403.911156) (xy 76.79362 -403.911156) (xy 76.785864 -403.965099)
			(xy 76.770509 -404.017394) (xy 76.747868 -404.066971) (xy 76.718401 -404.112821) (xy 76.68271 -404.154011)
			(xy 76.64152 -404.189703) (xy 76.595669 -404.219169) (xy 76.546092 -404.24181) (xy 76.493797 -404.257165)
			(xy 76.439849 -404.264921) (xy 76.412598 -404.265384) (xy 75.548998 -404.265384) (xy 75.521745 -404.264946)
			(xy 75.467794 -404.257189) (xy 75.415496 -404.241833) (xy 75.365916 -404.21919) (xy 75.320063 -404.189722)
			(xy 75.278871 -404.154028) (xy 75.243177 -404.112835) (xy 75.213709 -404.066982) (xy 75.191067 -404.017402)
			(xy 75.175711 -403.965104) (xy 75.167954 -403.911153) (xy 73.730421 -403.911153) (xy 73.722663 -403.965104)
			(xy 73.707306 -404.017402) (xy 73.684662 -404.066982) (xy 73.655192 -404.112834) (xy 73.619496 -404.154025)
			(xy 73.578301 -404.189717) (xy 73.532445 -404.219182) (xy 73.482863 -404.241821) (xy 73.430563 -404.257172)
			(xy 73.376611 -404.264924) (xy 73.349358 -404.265384) (xy 72.485758 -404.265384) (xy 72.458507 -404.264943)
			(xy 72.40456 -404.257181) (xy 72.352267 -404.241822) (xy 72.302692 -404.219177) (xy 72.256844 -404.189707)
			(xy 72.215657 -404.154014) (xy 72.179967 -404.112822) (xy 72.150503 -404.066971) (xy 72.127864 -404.017393)
			(xy 72.11251 -403.965098) (xy 72.104754 -403.911151) (xy 70.667098 -403.911151) (xy 70.659342 -403.965091)
			(xy 70.643989 -404.017381) (xy 70.621351 -404.066954) (xy 70.591888 -404.112801) (xy 70.556201 -404.153988)
			(xy 70.515015 -404.189677) (xy 70.46917 -404.219142) (xy 70.419598 -404.241783) (xy 70.367309 -404.257138)
			(xy 70.313367 -404.264897) (xy 70.286118 -404.265384) (xy 69.422518 -404.265384) (xy 69.395263 -404.26497)
			(xy 69.341306 -404.257215) (xy 69.289003 -404.241859) (xy 69.239417 -404.219217) (xy 69.193559 -404.189747)
			(xy 69.152362 -404.154051) (xy 69.116664 -404.112855) (xy 69.087192 -404.066999) (xy 69.064547 -404.017414)
			(xy 69.049189 -403.965111) (xy 69.041431 -403.911155) (xy 67.603921 -403.911155) (xy 67.596164 -403.965102)
			(xy 67.580807 -404.017398) (xy 67.558165 -404.066976) (xy 67.528697 -404.112828) (xy 67.493003 -404.154018)
			(xy 67.45181 -404.18971) (xy 67.405957 -404.219175) (xy 67.356377 -404.241815) (xy 67.30408 -404.257168)
			(xy 67.25013 -404.264922) (xy 67.222878 -404.265384) (xy 66.359278 -404.265384) (xy 66.332026 -404.264945)
			(xy 66.278077 -404.257185) (xy 66.225782 -404.241827) (xy 66.176204 -404.219183) (xy 66.130354 -404.189715)
			(xy 66.089164 -404.154021) (xy 66.053472 -404.112829) (xy 66.024006 -404.066976) (xy 66.001365 -404.017397)
			(xy 65.98601 -403.965101) (xy 65.978254 -403.911152) (xy 64.540597 -403.911152) (xy 64.532843 -403.965089)
			(xy 64.517491 -404.017377) (xy 64.494854 -404.066949) (xy 64.465393 -404.112794) (xy 64.429708 -404.153981)
			(xy 64.388525 -404.18967) (xy 64.342682 -404.219135) (xy 64.293113 -404.241777) (xy 64.240826 -404.257135)
			(xy 64.186886 -404.264895) (xy 64.159638 -404.265384) (xy 63.296038 -404.265384) (xy 63.268782 -404.264972)
			(xy 63.214823 -404.257219) (xy 63.162517 -404.241865) (xy 63.112929 -404.219223) (xy 63.067068 -404.189754)
			(xy 63.025869 -404.154058) (xy 62.990169 -404.112862) (xy 62.960695 -404.067004) (xy 62.938048 -404.017418)
			(xy 62.922689 -403.965114) (xy 62.914931 -403.911156) (xy 61.47742 -403.911156) (xy 61.469664 -403.965099)
			(xy 61.454309 -404.017394) (xy 61.431668 -404.066971) (xy 61.402201 -404.112821) (xy 61.36651 -404.154011)
			(xy 61.32532 -404.189703) (xy 61.279469 -404.219169) (xy 61.229892 -404.24181) (xy 61.177597 -404.257165)
			(xy 61.123649 -404.264921) (xy 61.096398 -404.265384) (xy 60.232798 -404.265384) (xy 60.205545 -404.264946)
			(xy 60.151594 -404.257189) (xy 60.099296 -404.241833) (xy 60.049716 -404.21919) (xy 60.003863 -404.189722)
			(xy 59.962671 -404.154028) (xy 59.926977 -404.112835) (xy 59.897509 -404.066982) (xy 59.874867 -404.017402)
			(xy 59.859511 -403.965104) (xy 59.851754 -403.911153) (xy 58.414221 -403.911153) (xy 58.406463 -403.965104)
			(xy 58.391106 -404.017402) (xy 58.368462 -404.066982) (xy 58.338992 -404.112834) (xy 58.303296 -404.154025)
			(xy 58.262101 -404.189717) (xy 58.216245 -404.219182) (xy 58.166663 -404.241821) (xy 58.114363 -404.257172)
			(xy 58.060411 -404.264924) (xy 58.033158 -404.265384) (xy 57.169558 -404.265384) (xy 57.142307 -404.264943)
			(xy 57.08836 -404.257181) (xy 57.036067 -404.241822) (xy 56.986492 -404.219177) (xy 56.940644 -404.189707)
			(xy 56.899457 -404.154014) (xy 56.863767 -404.112822) (xy 56.834303 -404.066971) (xy 56.811664 -404.017393)
			(xy 56.79631 -403.965098) (xy 56.788554 -403.911151) (xy 55.350898 -403.911151) (xy 55.343142 -403.965091)
			(xy 55.327789 -404.017381) (xy 55.305151 -404.066954) (xy 55.275688 -404.112801) (xy 55.240001 -404.153988)
			(xy 55.198815 -404.189677) (xy 55.15297 -404.219142) (xy 55.103398 -404.241783) (xy 55.051109 -404.257138)
			(xy 54.997167 -404.264897) (xy 54.969918 -404.265384) (xy 54.106318 -404.265384) (xy 54.079063 -404.26497)
			(xy 54.025106 -404.257215) (xy 53.972803 -404.241859) (xy 53.923217 -404.219217) (xy 53.877359 -404.189747)
			(xy 53.836162 -404.154051) (xy 53.800464 -404.112855) (xy 53.770992 -404.066999) (xy 53.748347 -404.017414)
			(xy 53.732989 -403.965111) (xy 53.725231 -403.911155) (xy 52.287721 -403.911155) (xy 52.279964 -403.965102)
			(xy 52.264607 -404.017398) (xy 52.241965 -404.066976) (xy 52.212497 -404.112828) (xy 52.176803 -404.154018)
			(xy 52.13561 -404.18971) (xy 52.089757 -404.219175) (xy 52.040177 -404.241815) (xy 51.98788 -404.257168)
			(xy 51.93393 -404.264922) (xy 51.906678 -404.265384) (xy 51.043078 -404.265384) (xy 51.015826 -404.264945)
			(xy 50.961877 -404.257185) (xy 50.909582 -404.241827) (xy 50.860004 -404.219183) (xy 50.814154 -404.189715)
			(xy 50.772964 -404.154021) (xy 50.737272 -404.112829) (xy 50.707806 -404.066976) (xy 50.685165 -404.017397)
			(xy 50.66981 -403.965101) (xy 50.662054 -403.911152) (xy 49.224397 -403.911152) (xy 49.216643 -403.965089)
			(xy 49.201291 -404.017377) (xy 49.178654 -404.066949) (xy 49.149193 -404.112794) (xy 49.113508 -404.153981)
			(xy 49.072325 -404.18967) (xy 49.026482 -404.219135) (xy 48.976913 -404.241777) (xy 48.924626 -404.257135)
			(xy 48.870686 -404.264895) (xy 48.843438 -404.265384) (xy 47.979838 -404.265384) (xy 47.952582 -404.264972)
			(xy 47.898623 -404.257219) (xy 47.846317 -404.241865) (xy 47.796729 -404.219223) (xy 47.750868 -404.189754)
			(xy 47.709669 -404.154058) (xy 47.673969 -404.112862) (xy 47.644495 -404.067004) (xy 47.621848 -404.017418)
			(xy 47.606489 -403.965114) (xy 47.598731 -403.911156) (xy 2.610452 -403.911156) (xy 2.622121 -403.942439)
			(xy 2.666338 -404.039266) (xy 2.717346 -404.132693) (xy 2.774884 -404.222247) (xy 2.838661 -404.307471)
			(xy 2.908351 -404.387931) (xy 2.945638 -404.425912) (xy 3.748786 -405.22906) (xy 102.242112 -405.22906)
			(xy 102.242112 -404.36546) (xy 102.242598 -404.338209) (xy 102.250354 -404.284261) (xy 102.265709 -404.231966)
			(xy 102.288351 -404.182389) (xy 102.317817 -404.136539) (xy 102.353508 -404.095348) (xy 102.394699 -404.059657)
			(xy 102.440549 -404.030191) (xy 102.490126 -404.007549) (xy 102.542421 -403.992194) (xy 102.596369 -403.984438)
			(xy 102.650871 -403.984438) (xy 102.704819 -403.992194) (xy 102.757114 -404.007549) (xy 102.806691 -404.030191)
			(xy 102.852541 -404.059657) (xy 102.893732 -404.095348) (xy 102.929423 -404.136539) (xy 102.958889 -404.182389)
			(xy 102.981531 -404.231966) (xy 102.996886 -404.284261) (xy 103.004642 -404.338209) (xy 103.005128 -404.36546)
			(xy 103.005128 -405.22906) (xy 103.004642 -405.256311) (xy 102.996886 -405.310259) (xy 102.981531 -405.362554)
			(xy 102.958889 -405.412131) (xy 102.929423 -405.457981) (xy 102.893732 -405.499172) (xy 102.852541 -405.534863)
			(xy 102.806691 -405.564329) (xy 102.757114 -405.586971) (xy 102.704819 -405.602326) (xy 102.650871 -405.610082)
			(xy 102.596369 -405.610082) (xy 102.542421 -405.602326) (xy 102.490126 -405.586971) (xy 102.440549 -405.564329)
			(xy 102.394699 -405.534863) (xy 102.353508 -405.499172) (xy 102.317817 -405.457981) (xy 102.288351 -405.412131)
			(xy 102.265709 -405.362554) (xy 102.250354 -405.310259) (xy 102.242598 -405.256311) (xy 102.242112 -405.22906)
			(xy 3.748786 -405.22906) (xy 5.555234 -407.035508) (xy 15.978632 -407.035508) (xy 15.978632 -406.171908)
			(xy 15.979118 -406.144657) (xy 15.986874 -406.090709) (xy 16.002229 -406.038414) (xy 16.024871 -405.988837)
			(xy 16.054337 -405.942987) (xy 16.090028 -405.901796) (xy 16.131219 -405.866105) (xy 16.177069 -405.836639)
			(xy 16.226646 -405.813997) (xy 16.278941 -405.798642) (xy 16.332889 -405.790886) (xy 16.387391 -405.790886)
			(xy 16.441339 -405.798642) (xy 16.493634 -405.813997) (xy 16.543211 -405.836639) (xy 16.589061 -405.866105)
			(xy 16.630252 -405.901796) (xy 16.665943 -405.942987) (xy 16.695409 -405.988837) (xy 16.718051 -406.038414)
			(xy 16.733406 -406.090709) (xy 16.741162 -406.144657) (xy 16.741648 -406.171908) (xy 16.741648 -407.031753)
			(xy 48.944975 -407.031753) (xy 48.944975 -406.977247) (xy 48.952733 -406.923295) (xy 48.96809 -406.870997)
			(xy 48.990734 -406.821417) (xy 49.020204 -406.775565) (xy 49.0559 -406.734373) (xy 49.097095 -406.698681)
			(xy 49.142951 -406.669216) (xy 49.192533 -406.646577) (xy 49.244833 -406.631225) (xy 49.298785 -406.623473)
			(xy 49.326038 -406.623012) (xy 50.189638 -406.623012) (xy 50.216889 -406.62346) (xy 50.270835 -406.631222)
			(xy 50.323128 -406.646581) (xy 50.372703 -406.669225) (xy 50.418551 -406.698694) (xy 50.459739 -406.734388)
			(xy 50.495428 -406.775579) (xy 50.524893 -406.82143) (xy 50.547532 -406.871007) (xy 50.562886 -406.923302)
			(xy 50.570642 -406.977249) (xy 50.570642 -407.031749) (xy 52.008298 -407.031749) (xy 52.008298 -406.977251)
			(xy 52.016054 -406.923308) (xy 52.031407 -406.871018) (xy 52.054045 -406.821445) (xy 52.083508 -406.775598)
			(xy 52.119195 -406.734411) (xy 52.16038 -406.698721) (xy 52.206226 -406.669256) (xy 52.255797 -406.646615)
			(xy 52.308087 -406.631258) (xy 52.362029 -406.6235) (xy 52.389278 -406.623012) (xy 53.252878 -406.623012)
			(xy 53.280133 -406.623433) (xy 53.33409 -406.631188) (xy 53.386393 -406.646543) (xy 53.435978 -406.669186)
			(xy 53.481837 -406.698655) (xy 53.523034 -406.73435) (xy 53.558732 -406.775546) (xy 53.588204 -406.821402)
			(xy 53.610849 -406.870987) (xy 53.626207 -406.923289) (xy 53.633965 -406.977245) (xy 53.633965 -407.031752)
			(xy 55.071475 -407.031752) (xy 55.071475 -406.977248) (xy 55.079232 -406.923298) (xy 55.094589 -406.871002)
			(xy 55.117231 -406.821423) (xy 55.146699 -406.775571) (xy 55.182393 -406.73438) (xy 55.223586 -406.698688)
			(xy 55.269439 -406.669222) (xy 55.319018 -406.646582) (xy 55.371316 -406.631229) (xy 55.425266 -406.623474)
			(xy 55.452518 -406.623012) (xy 56.316118 -406.623012) (xy 56.34337 -406.623459) (xy 56.397318 -406.631218)
			(xy 56.449614 -406.646576) (xy 56.499191 -406.669219) (xy 56.545042 -406.698687) (xy 56.586232 -406.734381)
			(xy 56.621924 -406.775573) (xy 56.65139 -406.821424) (xy 56.674031 -406.871003) (xy 56.689386 -406.923299)
			(xy 56.697142 -406.977248) (xy 56.697142 -407.031748) (xy 58.134798 -407.031748) (xy 58.134798 -406.977252)
			(xy 58.142553 -406.923311) (xy 58.157905 -406.871022) (xy 58.180542 -406.821451) (xy 58.210003 -406.775605)
			(xy 58.245688 -406.734418) (xy 58.286871 -406.698728) (xy 58.332714 -406.669262) (xy 58.382283 -406.64662)
			(xy 58.43457 -406.631262) (xy 58.48851 -406.623501) (xy 58.515758 -406.623012) (xy 59.379358 -406.623012)
			(xy 59.406614 -406.623432) (xy 59.460573 -406.631185) (xy 59.512878 -406.646538) (xy 59.562466 -406.669179)
			(xy 59.608327 -406.698648) (xy 59.649527 -406.734343) (xy 59.685227 -406.775539) (xy 59.714701 -406.821397)
			(xy 59.737348 -406.870982) (xy 59.752707 -406.923286) (xy 59.760465 -406.977244) (xy 59.760465 -407.03175)
			(xy 61.197998 -407.03175) (xy 61.197998 -406.97725) (xy 61.205754 -406.923306) (xy 61.221108 -406.871014)
			(xy 61.243748 -406.821439) (xy 61.273213 -406.775592) (xy 61.308902 -406.734404) (xy 61.35009 -406.698714)
			(xy 61.395938 -406.669249) (xy 61.445512 -406.646609) (xy 61.497804 -406.631255) (xy 61.551748 -406.623498)
			(xy 61.578998 -406.623012) (xy 62.442598 -406.623012) (xy 62.469852 -406.623435) (xy 62.523806 -406.631192)
			(xy 62.576107 -406.646549) (xy 62.62569 -406.669192) (xy 62.671546 -406.698662) (xy 62.712741 -406.734357)
			(xy 62.748437 -406.775552) (xy 62.777907 -406.821408) (xy 62.800551 -406.870991) (xy 62.815908 -406.923292)
			(xy 62.823665 -406.977246) (xy 62.823665 -407.031753) (xy 64.261175 -407.031753) (xy 64.261175 -406.977247)
			(xy 64.268933 -406.923295) (xy 64.28429 -406.870997) (xy 64.306934 -406.821417) (xy 64.336404 -406.775565)
			(xy 64.3721 -406.734373) (xy 64.413295 -406.698681) (xy 64.459151 -406.669216) (xy 64.508733 -406.646577)
			(xy 64.561033 -406.631225) (xy 64.614985 -406.623473) (xy 64.642238 -406.623012) (xy 65.505838 -406.623012)
			(xy 65.533089 -406.62346) (xy 65.587035 -406.631222) (xy 65.639328 -406.646581) (xy 65.688903 -406.669225)
			(xy 65.734751 -406.698694) (xy 65.775939 -406.734388) (xy 65.811628 -406.775579) (xy 65.841093 -406.82143)
			(xy 65.863732 -406.871007) (xy 65.879086 -406.923302) (xy 65.886842 -406.977249) (xy 65.886842 -407.031749)
			(xy 67.324498 -407.031749) (xy 67.324498 -406.977251) (xy 67.332254 -406.923308) (xy 67.347607 -406.871018)
			(xy 67.370245 -406.821445) (xy 67.399708 -406.775598) (xy 67.435395 -406.734411) (xy 67.47658 -406.698721)
			(xy 67.522426 -406.669256) (xy 67.571997 -406.646615) (xy 67.624287 -406.631258) (xy 67.678229 -406.6235)
			(xy 67.705478 -406.623012) (xy 68.569078 -406.623012) (xy 68.596333 -406.623433) (xy 68.65029 -406.631188)
			(xy 68.702593 -406.646543) (xy 68.752178 -406.669186) (xy 68.798037 -406.698655) (xy 68.839234 -406.73435)
			(xy 68.874932 -406.775546) (xy 68.904404 -406.821402) (xy 68.927049 -406.870987) (xy 68.942407 -406.923289)
			(xy 68.950165 -406.977245) (xy 68.950165 -407.031752) (xy 70.387675 -407.031752) (xy 70.387675 -406.977248)
			(xy 70.395432 -406.923298) (xy 70.410789 -406.871002) (xy 70.433431 -406.821423) (xy 70.462899 -406.775571)
			(xy 70.498593 -406.73438) (xy 70.539786 -406.698688) (xy 70.585639 -406.669222) (xy 70.635218 -406.646582)
			(xy 70.687516 -406.631229) (xy 70.741466 -406.623474) (xy 70.768718 -406.623012) (xy 71.632318 -406.623012)
			(xy 71.65957 -406.623459) (xy 71.713518 -406.631218) (xy 71.765814 -406.646576) (xy 71.815391 -406.669219)
			(xy 71.861242 -406.698687) (xy 71.902432 -406.734381) (xy 71.938124 -406.775573) (xy 71.96759 -406.821424)
			(xy 71.990231 -406.871003) (xy 72.005586 -406.923299) (xy 72.013342 -406.977248) (xy 72.013342 -407.031748)
			(xy 73.450998 -407.031748) (xy 73.450998 -406.977252) (xy 73.458753 -406.923311) (xy 73.474105 -406.871022)
			(xy 73.496742 -406.821451) (xy 73.526203 -406.775605) (xy 73.561888 -406.734418) (xy 73.603071 -406.698728)
			(xy 73.648914 -406.669262) (xy 73.698483 -406.64662) (xy 73.75077 -406.631262) (xy 73.80471 -406.623501)
			(xy 73.831958 -406.623012) (xy 74.695558 -406.623012) (xy 74.722814 -406.623432) (xy 74.776773 -406.631185)
			(xy 74.829078 -406.646538) (xy 74.878666 -406.669179) (xy 74.924527 -406.698648) (xy 74.965727 -406.734343)
			(xy 75.001427 -406.775539) (xy 75.030901 -406.821397) (xy 75.053548 -406.870982) (xy 75.068907 -406.923286)
			(xy 75.076665 -406.977244) (xy 75.076665 -407.03175) (xy 76.514198 -407.03175) (xy 76.514198 -406.97725)
			(xy 76.521954 -406.923306) (xy 76.537308 -406.871014) (xy 76.559948 -406.821439) (xy 76.589413 -406.775592)
			(xy 76.625102 -406.734404) (xy 76.66629 -406.698714) (xy 76.712138 -406.669249) (xy 76.761712 -406.646609)
			(xy 76.814004 -406.631255) (xy 76.867948 -406.623498) (xy 76.895198 -406.623012) (xy 77.758798 -406.623012)
			(xy 77.786052 -406.623435) (xy 77.840006 -406.631192) (xy 77.892307 -406.646549) (xy 77.94189 -406.669192)
			(xy 77.987746 -406.698662) (xy 78.028941 -406.734357) (xy 78.064637 -406.775552) (xy 78.094107 -406.821408)
			(xy 78.116751 -406.870991) (xy 78.132108 -406.923292) (xy 78.139865 -406.977246) (xy 78.139865 -407.031753)
			(xy 79.577375 -407.031753) (xy 79.577375 -406.977247) (xy 79.585133 -406.923295) (xy 79.60049 -406.870997)
			(xy 79.623134 -406.821417) (xy 79.652604 -406.775565) (xy 79.6883 -406.734373) (xy 79.729495 -406.698681)
			(xy 79.775351 -406.669216) (xy 79.824933 -406.646577) (xy 79.877233 -406.631225) (xy 79.931185 -406.623473)
			(xy 79.958438 -406.623012) (xy 80.822038 -406.623012) (xy 80.849289 -406.62346) (xy 80.903235 -406.631222)
			(xy 80.955528 -406.646581) (xy 81.005103 -406.669225) (xy 81.050951 -406.698694) (xy 81.092139 -406.734388)
			(xy 81.127828 -406.775579) (xy 81.157293 -406.82143) (xy 81.179932 -406.871007) (xy 81.195286 -406.923302)
			(xy 81.203042 -406.977249) (xy 81.203042 -407.031749) (xy 82.640698 -407.031749) (xy 82.640698 -406.977251)
			(xy 82.648454 -406.923308) (xy 82.663807 -406.871018) (xy 82.686445 -406.821445) (xy 82.715908 -406.775598)
			(xy 82.751595 -406.734411) (xy 82.79278 -406.698721) (xy 82.838626 -406.669256) (xy 82.888197 -406.646615)
			(xy 82.940487 -406.631258) (xy 82.994429 -406.6235) (xy 83.021678 -406.623012) (xy 83.885278 -406.623012)
			(xy 83.912533 -406.623433) (xy 83.96649 -406.631188) (xy 84.018793 -406.646543) (xy 84.068378 -406.669186)
			(xy 84.114237 -406.698655) (xy 84.155434 -406.73435) (xy 84.191132 -406.775546) (xy 84.220604 -406.821402)
			(xy 84.243249 -406.870987) (xy 84.258607 -406.923289) (xy 84.266365 -406.977245) (xy 84.266365 -407.031752)
			(xy 85.703875 -407.031752) (xy 85.703875 -406.977248) (xy 85.711632 -406.923298) (xy 85.726989 -406.871002)
			(xy 85.749631 -406.821423) (xy 85.779099 -406.775571) (xy 85.814793 -406.73438) (xy 85.855986 -406.698688)
			(xy 85.901839 -406.669222) (xy 85.951418 -406.646582) (xy 86.003716 -406.631229) (xy 86.057666 -406.623474)
			(xy 86.084918 -406.623012) (xy 86.948518 -406.623012) (xy 86.97577 -406.623459) (xy 87.029718 -406.631218)
			(xy 87.082014 -406.646576) (xy 87.131591 -406.669219) (xy 87.177442 -406.698687) (xy 87.218632 -406.734381)
			(xy 87.254324 -406.775573) (xy 87.28379 -406.821424) (xy 87.306431 -406.871003) (xy 87.321786 -406.923299)
			(xy 87.329542 -406.977248) (xy 87.329542 -407.031748) (xy 88.767198 -407.031748) (xy 88.767198 -406.977252)
			(xy 88.774953 -406.923311) (xy 88.790305 -406.871022) (xy 88.812942 -406.821451) (xy 88.842403 -406.775605)
			(xy 88.878088 -406.734418) (xy 88.919271 -406.698728) (xy 88.965114 -406.669262) (xy 89.014683 -406.64662)
			(xy 89.06697 -406.631262) (xy 89.12091 -406.623501) (xy 89.148158 -406.623012) (xy 90.011758 -406.623012)
			(xy 90.039014 -406.623432) (xy 90.092973 -406.631185) (xy 90.145278 -406.646538) (xy 90.194866 -406.669179)
			(xy 90.240727 -406.698648) (xy 90.281927 -406.734343) (xy 90.317627 -406.775539) (xy 90.347101 -406.821397)
			(xy 90.369748 -406.870982) (xy 90.385107 -406.923286) (xy 90.392865 -406.977244) (xy 90.392865 -407.03175)
			(xy 91.830398 -407.03175) (xy 91.830398 -406.97725) (xy 91.838154 -406.923306) (xy 91.853508 -406.871014)
			(xy 91.876148 -406.821439) (xy 91.905613 -406.775592) (xy 91.941302 -406.734404) (xy 91.98249 -406.698714)
			(xy 92.028338 -406.669249) (xy 92.077912 -406.646609) (xy 92.130204 -406.631255) (xy 92.184148 -406.623498)
			(xy 92.211398 -406.623012) (xy 93.074998 -406.623012) (xy 93.102252 -406.623435) (xy 93.156206 -406.631192)
			(xy 93.208507 -406.646549) (xy 93.25809 -406.669192) (xy 93.303946 -406.698662) (xy 93.345141 -406.734357)
			(xy 93.380837 -406.775552) (xy 93.410307 -406.821408) (xy 93.432951 -406.870991) (xy 93.448308 -406.923292)
			(xy 93.456065 -406.977246) (xy 93.456065 -407.031753) (xy 94.893575 -407.031753) (xy 94.893575 -406.977247)
			(xy 94.901333 -406.923295) (xy 94.91669 -406.870997) (xy 94.939334 -406.821417) (xy 94.968804 -406.775565)
			(xy 95.0045 -406.734373) (xy 95.045695 -406.698681) (xy 95.091551 -406.669216) (xy 95.141133 -406.646577)
			(xy 95.193433 -406.631225) (xy 95.247385 -406.623473) (xy 95.274638 -406.623012) (xy 96.138238 -406.623012)
			(xy 96.165489 -406.62346) (xy 96.219435 -406.631222) (xy 96.271728 -406.646581) (xy 96.321303 -406.669225)
			(xy 96.367151 -406.698694) (xy 96.408339 -406.734388) (xy 96.444028 -406.775579) (xy 96.473493 -406.82143)
			(xy 96.496132 -406.871007) (xy 96.511486 -406.923302) (xy 96.519242 -406.977249) (xy 96.519242 -407.031751)
			(xy 96.511486 -407.085698) (xy 96.496132 -407.137993) (xy 96.495694 -407.138953) (xy 106.243063 -407.138953)
			(xy 106.243063 -407.084447) (xy 106.250821 -407.030495) (xy 106.266177 -406.978197) (xy 106.288821 -406.928617)
			(xy 106.31829 -406.882763) (xy 106.353985 -406.841571) (xy 106.395179 -406.805878) (xy 106.441034 -406.776411)
			(xy 106.490616 -406.75377) (xy 106.542915 -406.738416) (xy 106.596867 -406.730662) (xy 106.62412 -406.7302)
			(xy 107.48772 -406.7302) (xy 107.514971 -406.730671) (xy 107.568918 -406.73843) (xy 107.621211 -406.753787)
			(xy 107.670787 -406.77643) (xy 107.716636 -406.805898) (xy 107.757824 -406.84159) (xy 107.793514 -406.88278)
			(xy 107.82298 -406.928631) (xy 107.84562 -406.978208) (xy 107.860974 -407.030502) (xy 107.861153 -407.031748)
			(xy 121.120198 -407.031748) (xy 121.120198 -406.977252) (xy 121.127953 -406.923312) (xy 121.143305 -406.871023)
			(xy 121.165942 -406.821452) (xy 121.195402 -406.775606) (xy 121.231087 -406.734419) (xy 121.272269 -406.69873)
			(xy 121.318111 -406.669264) (xy 121.36768 -406.646621) (xy 121.419967 -406.631263) (xy 121.473906 -406.623501)
			(xy 121.501154 -406.623012) (xy 122.364754 -406.623012) (xy 122.39201 -406.623432) (xy 122.445969 -406.631184)
			(xy 122.498275 -406.646537) (xy 122.547864 -406.669178) (xy 122.593725 -406.698646) (xy 122.634926 -406.734342)
			(xy 122.670626 -406.775538) (xy 122.7001 -406.821396) (xy 122.722747 -406.870981) (xy 122.738106 -406.923286)
			(xy 122.745865 -406.977244) (xy 122.745865 -407.03175) (xy 124.183398 -407.03175) (xy 124.183398 -406.97725)
			(xy 124.191154 -406.923306) (xy 124.206508 -406.871015) (xy 124.229148 -406.821441) (xy 124.258612 -406.775593)
			(xy 124.294301 -406.734405) (xy 124.335488 -406.698715) (xy 124.381335 -406.669251) (xy 124.430909 -406.64661)
			(xy 124.4832 -406.631255) (xy 124.537144 -406.623499) (xy 124.564394 -406.623012) (xy 125.427994 -406.623012)
			(xy 125.455249 -406.623434) (xy 125.509203 -406.631191) (xy 125.561504 -406.646548) (xy 125.611088 -406.669191)
			(xy 125.656944 -406.69866) (xy 125.69814 -406.734356) (xy 125.733836 -406.775551) (xy 125.763306 -406.821407)
			(xy 125.78595 -406.87099) (xy 125.801308 -406.923291) (xy 125.809065 -406.977245) (xy 125.809065 -407.031753)
			(xy 127.246575 -407.031753) (xy 127.246575 -406.977247) (xy 127.254333 -406.923296) (xy 127.26969 -406.870998)
			(xy 127.292334 -406.821418) (xy 127.321803 -406.775566) (xy 127.357499 -406.734375) (xy 127.398693 -406.698683)
			(xy 127.444548 -406.669217) (xy 127.49413 -406.646578) (xy 127.546429 -406.631226) (xy 127.600381 -406.623473)
			(xy 127.627634 -406.623012) (xy 128.491234 -406.623012) (xy 128.518485 -406.62346) (xy 128.572432 -406.631221)
			(xy 128.624725 -406.64658) (xy 128.674301 -406.669224) (xy 128.720149 -406.698693) (xy 128.761338 -406.734386)
			(xy 128.797028 -406.775578) (xy 128.826492 -406.821429) (xy 128.849132 -406.871007) (xy 128.864486 -406.923301)
			(xy 128.872242 -406.977249) (xy 128.872242 -407.031749) (xy 130.309898 -407.031749) (xy 130.309898 -406.977251)
			(xy 130.317654 -406.923309) (xy 130.333007 -406.871019) (xy 130.355645 -406.821446) (xy 130.385107 -406.775599)
			(xy 130.420794 -406.734412) (xy 130.461979 -406.698722) (xy 130.507823 -406.669257) (xy 130.557395 -406.646616)
			(xy 130.609683 -406.631259) (xy 130.663625 -406.6235) (xy 130.690874 -406.623012) (xy 131.554474 -406.623012)
			(xy 131.58173 -406.623433) (xy 131.635686 -406.631187) (xy 131.68799 -406.646542) (xy 131.737576 -406.669184)
			(xy 131.783435 -406.698653) (xy 131.824633 -406.734349) (xy 131.860331 -406.775544) (xy 131.889803 -406.821401)
			(xy 131.912449 -406.870986) (xy 131.927807 -406.923288) (xy 131.935565 -406.977245) (xy 131.935565 -407.031752)
			(xy 133.373075 -407.031752) (xy 133.373075 -406.977248) (xy 133.380832 -406.923299) (xy 133.396188 -406.871002)
			(xy 133.418831 -406.821424) (xy 133.448298 -406.775573) (xy 133.483992 -406.734382) (xy 133.525184 -406.69869)
			(xy 133.571036 -406.669224) (xy 133.620616 -406.646583) (xy 133.672912 -406.631229) (xy 133.726862 -406.623474)
			(xy 133.754114 -406.623012) (xy 134.617714 -406.623012) (xy 134.644966 -406.623459) (xy 134.698915 -406.631217)
			(xy 134.751211 -406.646574) (xy 134.800789 -406.669218) (xy 134.84664 -406.698686) (xy 134.887831 -406.734379)
			(xy 134.923523 -406.775571) (xy 134.952989 -406.821423) (xy 134.97563 -406.871002) (xy 134.990986 -406.923299)
			(xy 134.998742 -406.977248) (xy 134.998742 -407.031748) (xy 136.436398 -407.031748) (xy 136.436398 -406.977252)
			(xy 136.444153 -406.923312) (xy 136.459505 -406.871023) (xy 136.482142 -406.821452) (xy 136.511602 -406.775606)
			(xy 136.547287 -406.734419) (xy 136.588469 -406.69873) (xy 136.634311 -406.669264) (xy 136.68388 -406.646621)
			(xy 136.736167 -406.631263) (xy 136.790106 -406.623501) (xy 136.817354 -406.623012) (xy 137.680954 -406.623012)
			(xy 137.70821 -406.623432) (xy 137.762169 -406.631184) (xy 137.814475 -406.646537) (xy 137.864064 -406.669178)
			(xy 137.909925 -406.698646) (xy 137.951126 -406.734342) (xy 137.986826 -406.775538) (xy 138.0163 -406.821396)
			(xy 138.038947 -406.870981) (xy 138.054306 -406.923286) (xy 138.062065 -406.977244) (xy 138.062065 -407.03175)
			(xy 139.499598 -407.03175) (xy 139.499598 -406.97725) (xy 139.507354 -406.923306) (xy 139.522708 -406.871015)
			(xy 139.545348 -406.821441) (xy 139.574812 -406.775593) (xy 139.610501 -406.734405) (xy 139.651688 -406.698715)
			(xy 139.697535 -406.669251) (xy 139.747109 -406.64661) (xy 139.7994 -406.631255) (xy 139.853344 -406.623499)
			(xy 139.880594 -406.623012) (xy 140.744194 -406.623012) (xy 140.771449 -406.623434) (xy 140.825403 -406.631191)
			(xy 140.877704 -406.646548) (xy 140.927288 -406.669191) (xy 140.973144 -406.69866) (xy 141.01434 -406.734356)
			(xy 141.050036 -406.775551) (xy 141.079506 -406.821407) (xy 141.10215 -406.87099) (xy 141.117508 -406.923291)
			(xy 141.125265 -406.977245) (xy 141.125265 -407.031753) (xy 142.562775 -407.031753) (xy 142.562775 -406.977247)
			(xy 142.570533 -406.923296) (xy 142.58589 -406.870998) (xy 142.608534 -406.821418) (xy 142.638003 -406.775566)
			(xy 142.673699 -406.734375) (xy 142.714893 -406.698683) (xy 142.760748 -406.669217) (xy 142.81033 -406.646578)
			(xy 142.862629 -406.631226) (xy 142.916581 -406.623473) (xy 142.943834 -406.623012) (xy 143.807434 -406.623012)
			(xy 143.834685 -406.62346) (xy 143.888632 -406.631221) (xy 143.940925 -406.64658) (xy 143.990501 -406.669224)
			(xy 144.036349 -406.698693) (xy 144.077538 -406.734386) (xy 144.113228 -406.775578) (xy 144.142692 -406.821429)
			(xy 144.165332 -406.871007) (xy 144.180686 -406.923301) (xy 144.188442 -406.977249) (xy 144.188442 -407.031749)
			(xy 145.626098 -407.031749) (xy 145.626098 -406.977251) (xy 145.633854 -406.923309) (xy 145.649207 -406.871019)
			(xy 145.671845 -406.821446) (xy 145.701307 -406.775599) (xy 145.736994 -406.734412) (xy 145.778179 -406.698722)
			(xy 145.824023 -406.669257) (xy 145.873595 -406.646616) (xy 145.925883 -406.631259) (xy 145.979825 -406.6235)
			(xy 146.007074 -406.623012) (xy 146.870674 -406.623012) (xy 146.89793 -406.623433) (xy 146.951886 -406.631187)
			(xy 147.00419 -406.646542) (xy 147.053776 -406.669184) (xy 147.099635 -406.698653) (xy 147.140833 -406.734349)
			(xy 147.176531 -406.775544) (xy 147.206003 -406.821401) (xy 147.228649 -406.870986) (xy 147.244007 -406.923288)
			(xy 147.251765 -406.977245) (xy 147.251765 -407.031752) (xy 148.689275 -407.031752) (xy 148.689275 -406.977248)
			(xy 148.697032 -406.923299) (xy 148.712388 -406.871002) (xy 148.735031 -406.821424) (xy 148.764498 -406.775573)
			(xy 148.800192 -406.734382) (xy 148.841384 -406.69869) (xy 148.887236 -406.669224) (xy 148.936816 -406.646583)
			(xy 148.989112 -406.631229) (xy 149.043062 -406.623474) (xy 149.070314 -406.623012) (xy 149.933914 -406.623012)
			(xy 149.961166 -406.623459) (xy 150.015115 -406.631217) (xy 150.067411 -406.646574) (xy 150.116989 -406.669218)
			(xy 150.16284 -406.698686) (xy 150.204031 -406.734379) (xy 150.239723 -406.775571) (xy 150.269189 -406.821423)
			(xy 150.29183 -406.871002) (xy 150.307186 -406.923299) (xy 150.314942 -406.977248) (xy 150.314942 -407.031748)
			(xy 151.752598 -407.031748) (xy 151.752598 -406.977252) (xy 151.760353 -406.923312) (xy 151.775705 -406.871023)
			(xy 151.798342 -406.821452) (xy 151.827802 -406.775606) (xy 151.863487 -406.734419) (xy 151.904669 -406.69873)
			(xy 151.950511 -406.669264) (xy 152.00008 -406.646621) (xy 152.052367 -406.631263) (xy 152.106306 -406.623501)
			(xy 152.133554 -406.623012) (xy 152.997154 -406.623012) (xy 153.02441 -406.623432) (xy 153.078369 -406.631184)
			(xy 153.130675 -406.646537) (xy 153.180264 -406.669178) (xy 153.226125 -406.698646) (xy 153.267326 -406.734342)
			(xy 153.303026 -406.775538) (xy 153.3325 -406.821396) (xy 153.355147 -406.870981) (xy 153.370506 -406.923286)
			(xy 153.378265 -406.977244) (xy 153.378265 -407.03175) (xy 154.815798 -407.03175) (xy 154.815798 -406.97725)
			(xy 154.823554 -406.923306) (xy 154.838908 -406.871015) (xy 154.861548 -406.821441) (xy 154.891012 -406.775593)
			(xy 154.926701 -406.734405) (xy 154.967888 -406.698715) (xy 155.013735 -406.669251) (xy 155.063309 -406.64661)
			(xy 155.1156 -406.631255) (xy 155.169544 -406.623499) (xy 155.196794 -406.623012) (xy 156.060394 -406.623012)
			(xy 156.087649 -406.623434) (xy 156.141603 -406.631191) (xy 156.193904 -406.646548) (xy 156.243488 -406.669191)
			(xy 156.289344 -406.69866) (xy 156.33054 -406.734356) (xy 156.366236 -406.775551) (xy 156.395706 -406.821407)
			(xy 156.41835 -406.87099) (xy 156.433708 -406.923291) (xy 156.441465 -406.977245) (xy 156.441465 -407.031753)
			(xy 157.878975 -407.031753) (xy 157.878975 -406.977247) (xy 157.886733 -406.923296) (xy 157.90209 -406.870998)
			(xy 157.924734 -406.821418) (xy 157.954203 -406.775566) (xy 157.989899 -406.734375) (xy 158.031093 -406.698683)
			(xy 158.076948 -406.669217) (xy 158.12653 -406.646578) (xy 158.178829 -406.631226) (xy 158.232781 -406.623473)
			(xy 158.260034 -406.623012) (xy 159.123634 -406.623012) (xy 159.150885 -406.62346) (xy 159.204832 -406.631221)
			(xy 159.257125 -406.64658) (xy 159.306701 -406.669224) (xy 159.352549 -406.698693) (xy 159.393738 -406.734386)
			(xy 159.429428 -406.775578) (xy 159.458892 -406.821429) (xy 159.481532 -406.871007) (xy 159.496886 -406.923301)
			(xy 159.504642 -406.977249) (xy 159.504642 -407.031749) (xy 160.942298 -407.031749) (xy 160.942298 -406.977251)
			(xy 160.950054 -406.923309) (xy 160.965407 -406.871019) (xy 160.988045 -406.821446) (xy 161.017507 -406.775599)
			(xy 161.053194 -406.734412) (xy 161.094379 -406.698722) (xy 161.140223 -406.669257) (xy 161.189795 -406.646616)
			(xy 161.242083 -406.631259) (xy 161.296025 -406.6235) (xy 161.323274 -406.623012) (xy 162.186874 -406.623012)
			(xy 162.21413 -406.623433) (xy 162.268086 -406.631187) (xy 162.32039 -406.646542) (xy 162.369976 -406.669184)
			(xy 162.415835 -406.698653) (xy 162.457033 -406.734349) (xy 162.492731 -406.775544) (xy 162.522203 -406.821401)
			(xy 162.544849 -406.870986) (xy 162.560207 -406.923288) (xy 162.567965 -406.977245) (xy 162.567965 -407.031752)
			(xy 164.005475 -407.031752) (xy 164.005475 -406.977248) (xy 164.013232 -406.923299) (xy 164.028588 -406.871002)
			(xy 164.051231 -406.821424) (xy 164.080698 -406.775573) (xy 164.116392 -406.734382) (xy 164.157584 -406.69869)
			(xy 164.203436 -406.669224) (xy 164.253016 -406.646583) (xy 164.305312 -406.631229) (xy 164.359262 -406.623474)
			(xy 164.386514 -406.623012) (xy 165.250114 -406.623012) (xy 165.277366 -406.623459) (xy 165.331315 -406.631217)
			(xy 165.383611 -406.646574) (xy 165.433189 -406.669218) (xy 165.47904 -406.698686) (xy 165.520231 -406.734379)
			(xy 165.555923 -406.775571) (xy 165.585389 -406.821423) (xy 165.60803 -406.871002) (xy 165.623386 -406.923299)
			(xy 165.631142 -406.977248) (xy 165.631142 -407.031748) (xy 167.068798 -407.031748) (xy 167.068798 -406.977252)
			(xy 167.076553 -406.923312) (xy 167.091905 -406.871023) (xy 167.114542 -406.821452) (xy 167.144002 -406.775606)
			(xy 167.179687 -406.734419) (xy 167.220869 -406.69873) (xy 167.266711 -406.669264) (xy 167.31628 -406.646621)
			(xy 167.368567 -406.631263) (xy 167.422506 -406.623501) (xy 167.449754 -406.623012) (xy 168.313354 -406.623012)
			(xy 168.34061 -406.623432) (xy 168.394569 -406.631184) (xy 168.446875 -406.646537) (xy 168.496464 -406.669178)
			(xy 168.542325 -406.698646) (xy 168.583526 -406.734342) (xy 168.619226 -406.775538) (xy 168.6487 -406.821396)
			(xy 168.671347 -406.870981) (xy 168.686706 -406.923286) (xy 168.694465 -406.977244) (xy 168.694465 -407.031749)
			(xy 304.945298 -407.031749) (xy 304.945298 -406.977251) (xy 304.953054 -406.923307) (xy 304.968408 -406.871016)
			(xy 304.991047 -406.821442) (xy 305.02051 -406.775595) (xy 305.056199 -406.734407) (xy 305.097385 -406.698718)
			(xy 305.143232 -406.669252) (xy 305.192805 -406.646612) (xy 305.245095 -406.631257) (xy 305.299039 -406.623499)
			(xy 305.326288 -406.623012) (xy 306.189888 -406.623012) (xy 306.217143 -406.623434) (xy 306.271098 -406.63119)
			(xy 306.3234 -406.646546) (xy 306.372984 -406.669189) (xy 306.418841 -406.698658) (xy 306.460038 -406.734354)
			(xy 306.495735 -406.775549) (xy 306.525205 -406.821405) (xy 306.54785 -406.870989) (xy 306.563207 -406.92329)
			(xy 306.570965 -406.977245) (xy 306.570965 -407.031753) (xy 308.008475 -407.031753) (xy 308.008475 -406.977247)
			(xy 308.016233 -406.923297) (xy 308.031589 -406.870999) (xy 308.054233 -406.82142) (xy 308.083702 -406.775568)
			(xy 308.119397 -406.734377) (xy 308.16059 -406.698685) (xy 308.206445 -406.669219) (xy 308.256026 -406.64658)
			(xy 308.308324 -406.631227) (xy 308.362275 -406.623473) (xy 308.389528 -406.623012) (xy 309.253128 -406.623012)
			(xy 309.280379 -406.62346) (xy 309.334327 -406.63122) (xy 309.386621 -406.646578) (xy 309.436197 -406.669222)
			(xy 309.482047 -406.698691) (xy 309.523236 -406.734384) (xy 309.558926 -406.775576) (xy 309.588391 -406.821427)
			(xy 309.611032 -406.871005) (xy 309.626386 -406.923301) (xy 309.634142 -406.977249) (xy 309.634142 -407.031748)
			(xy 311.071798 -407.031748) (xy 311.071798 -406.977252) (xy 311.079553 -406.92331) (xy 311.094906 -406.87102)
			(xy 311.117544 -406.821448) (xy 311.147005 -406.775601) (xy 311.182692 -406.734414) (xy 311.223876 -406.698725)
			(xy 311.26972 -406.669259) (xy 311.31929 -406.646617) (xy 311.371578 -406.63126) (xy 311.42552 -406.6235)
			(xy 311.452768 -406.623012) (xy 312.316368 -406.623012) (xy 312.343624 -406.623433) (xy 312.397581 -406.631186)
			(xy 312.449886 -406.64654) (xy 312.499472 -406.669182) (xy 312.545332 -406.698651) (xy 312.586531 -406.734347)
			(xy 312.62223 -406.775542) (xy 312.651702 -406.821399) (xy 312.674348 -406.870984) (xy 312.689707 -406.923288)
			(xy 312.697465 -406.977244) (xy 312.697465 -407.031752) (xy 314.134975 -407.031752) (xy 314.134975 -406.977248)
			(xy 314.142732 -406.923299) (xy 314.158088 -406.871004) (xy 314.18073 -406.821426) (xy 314.210197 -406.775575)
			(xy 314.245889 -406.734384) (xy 314.287081 -406.698692) (xy 314.332933 -406.669226) (xy 314.382511 -406.646585)
			(xy 314.434807 -406.63123) (xy 314.488756 -406.623475) (xy 314.516008 -406.623012) (xy 315.379608 -406.623012)
			(xy 315.40686 -406.623458) (xy 315.46081 -406.631216) (xy 315.513107 -406.646573) (xy 315.562685 -406.669216)
			(xy 315.608537 -406.698684) (xy 315.649729 -406.734377) (xy 315.685421 -406.775569) (xy 315.714888 -406.821422)
			(xy 315.73753 -406.871001) (xy 315.752885 -406.923298) (xy 315.760642 -406.977248) (xy 315.760642 -407.031752)
			(xy 315.760642 -407.031754) (xy 317.198175 -407.031754) (xy 317.198175 -406.977246) (xy 317.205933 -406.923294)
			(xy 317.221291 -406.870995) (xy 317.243936 -406.821414) (xy 317.273407 -406.775561) (xy 317.309104 -406.73437)
			(xy 317.3503 -406.698678) (xy 317.396157 -406.669213) (xy 317.44574 -406.646574) (xy 317.498041 -406.631223)
			(xy 317.551994 -406.623472) (xy 317.579248 -406.623012) (xy 318.442848 -406.623012) (xy 318.470098 -406.623461)
			(xy 318.524044 -406.631224) (xy 318.576336 -406.646584) (xy 318.625909 -406.669229) (xy 318.671756 -406.698698)
			(xy 318.712943 -406.734391) (xy 318.748631 -406.775582) (xy 318.778094 -406.821433) (xy 318.800733 -406.87101)
			(xy 318.816087 -406.923303) (xy 318.823842 -406.97725) (xy 318.823842 -407.031749) (xy 320.261498 -407.031749)
			(xy 320.261498 -406.977251) (xy 320.269254 -406.923307) (xy 320.284608 -406.871016) (xy 320.307247 -406.821442)
			(xy 320.33671 -406.775595) (xy 320.372399 -406.734407) (xy 320.413585 -406.698718) (xy 320.459432 -406.669252)
			(xy 320.509005 -406.646612) (xy 320.561295 -406.631257) (xy 320.615239 -406.623499) (xy 320.642488 -406.623012)
			(xy 321.506088 -406.623012) (xy 321.533343 -406.623434) (xy 321.587298 -406.63119) (xy 321.6396 -406.646546)
			(xy 321.689184 -406.669189) (xy 321.735041 -406.698658) (xy 321.776238 -406.734354) (xy 321.811935 -406.775549)
			(xy 321.841405 -406.821405) (xy 321.86405 -406.870989) (xy 321.879407 -406.92329) (xy 321.887165 -406.977245)
			(xy 321.887165 -407.031753) (xy 323.324675 -407.031753) (xy 323.324675 -406.977247) (xy 323.332433 -406.923297)
			(xy 323.347789 -406.870999) (xy 323.370433 -406.82142) (xy 323.399902 -406.775568) (xy 323.435597 -406.734377)
			(xy 323.47679 -406.698685) (xy 323.522645 -406.669219) (xy 323.572226 -406.64658) (xy 323.624524 -406.631227)
			(xy 323.678475 -406.623473) (xy 323.705728 -406.623012) (xy 324.569328 -406.623012) (xy 324.596579 -406.62346)
			(xy 324.650527 -406.63122) (xy 324.702821 -406.646578) (xy 324.752397 -406.669222) (xy 324.798247 -406.698691)
			(xy 324.839436 -406.734384) (xy 324.875126 -406.775576) (xy 324.904591 -406.821427) (xy 324.927232 -406.871005)
			(xy 324.942586 -406.923301) (xy 324.950342 -406.977249) (xy 324.950342 -407.031748) (xy 326.387998 -407.031748)
			(xy 326.387998 -406.977252) (xy 326.395753 -406.92331) (xy 326.411106 -406.87102) (xy 326.433744 -406.821448)
			(xy 326.463205 -406.775601) (xy 326.498892 -406.734414) (xy 326.540076 -406.698725) (xy 326.58592 -406.669259)
			(xy 326.63549 -406.646617) (xy 326.687778 -406.63126) (xy 326.74172 -406.6235) (xy 326.768968 -406.623012)
			(xy 327.632568 -406.623012) (xy 327.659824 -406.623433) (xy 327.713781 -406.631186) (xy 327.766086 -406.64654)
			(xy 327.815672 -406.669182) (xy 327.861532 -406.698651) (xy 327.902731 -406.734347) (xy 327.93843 -406.775542)
			(xy 327.967902 -406.821399) (xy 327.990548 -406.870984) (xy 328.005907 -406.923288) (xy 328.013665 -406.977244)
			(xy 328.013665 -407.031752) (xy 329.451175 -407.031752) (xy 329.451175 -406.977248) (xy 329.458932 -406.923299)
			(xy 329.474288 -406.871004) (xy 329.49693 -406.821426) (xy 329.526397 -406.775575) (xy 329.562089 -406.734384)
			(xy 329.603281 -406.698692) (xy 329.649133 -406.669226) (xy 329.698711 -406.646585) (xy 329.751007 -406.63123)
			(xy 329.804956 -406.623475) (xy 329.832208 -406.623012) (xy 330.695808 -406.623012) (xy 330.72306 -406.623458)
			(xy 330.77701 -406.631216) (xy 330.829307 -406.646573) (xy 330.878885 -406.669216) (xy 330.924737 -406.698684)
			(xy 330.965929 -406.734377) (xy 331.001621 -406.775569) (xy 331.031088 -406.821422) (xy 331.05373 -406.871001)
			(xy 331.069085 -406.923298) (xy 331.076842 -406.977248) (xy 331.076842 -407.031752) (xy 331.076842 -407.031754)
			(xy 332.514375 -407.031754) (xy 332.514375 -406.977246) (xy 332.522133 -406.923294) (xy 332.537491 -406.870995)
			(xy 332.560136 -406.821414) (xy 332.589607 -406.775561) (xy 332.625304 -406.73437) (xy 332.6665 -406.698678)
			(xy 332.712357 -406.669213) (xy 332.76194 -406.646574) (xy 332.814241 -406.631223) (xy 332.868194 -406.623472)
			(xy 332.895448 -406.623012) (xy 333.759048 -406.623012) (xy 333.786298 -406.623461) (xy 333.840244 -406.631224)
			(xy 333.892536 -406.646584) (xy 333.942109 -406.669229) (xy 333.987956 -406.698698) (xy 334.029143 -406.734391)
			(xy 334.064831 -406.775582) (xy 334.094294 -406.821433) (xy 334.116933 -406.87101) (xy 334.132287 -406.923303)
			(xy 334.140042 -406.97725) (xy 334.140042 -407.031749) (xy 335.577698 -407.031749) (xy 335.577698 -406.977251)
			(xy 335.585454 -406.923307) (xy 335.600808 -406.871016) (xy 335.623447 -406.821442) (xy 335.65291 -406.775595)
			(xy 335.688599 -406.734407) (xy 335.729785 -406.698718) (xy 335.775632 -406.669252) (xy 335.825205 -406.646612)
			(xy 335.877495 -406.631257) (xy 335.931439 -406.623499) (xy 335.958688 -406.623012) (xy 336.822288 -406.623012)
			(xy 336.849543 -406.623434) (xy 336.903498 -406.63119) (xy 336.9558 -406.646546) (xy 337.005384 -406.669189)
			(xy 337.051241 -406.698658) (xy 337.092438 -406.734354) (xy 337.128135 -406.775549) (xy 337.157605 -406.821405)
			(xy 337.18025 -406.870989) (xy 337.195607 -406.92329) (xy 337.203365 -406.977245) (xy 337.203365 -407.031753)
			(xy 338.640875 -407.031753) (xy 338.640875 -406.977247) (xy 338.648633 -406.923297) (xy 338.663989 -406.870999)
			(xy 338.686633 -406.82142) (xy 338.716102 -406.775568) (xy 338.751797 -406.734377) (xy 338.79299 -406.698685)
			(xy 338.838845 -406.669219) (xy 338.888426 -406.64658) (xy 338.940724 -406.631227) (xy 338.994675 -406.623473)
			(xy 339.021928 -406.623012) (xy 339.885528 -406.623012) (xy 339.912779 -406.62346) (xy 339.966727 -406.63122)
			(xy 340.019021 -406.646578) (xy 340.068597 -406.669222) (xy 340.114447 -406.698691) (xy 340.155636 -406.734384)
			(xy 340.191326 -406.775576) (xy 340.220791 -406.821427) (xy 340.243432 -406.871005) (xy 340.258786 -406.923301)
			(xy 340.266542 -406.977249) (xy 340.266542 -407.031748) (xy 341.704198 -407.031748) (xy 341.704198 -406.977252)
			(xy 341.711953 -406.92331) (xy 341.727306 -406.87102) (xy 341.749944 -406.821448) (xy 341.779405 -406.775601)
			(xy 341.815092 -406.734414) (xy 341.856276 -406.698725) (xy 341.90212 -406.669259) (xy 341.95169 -406.646617)
			(xy 342.003978 -406.63126) (xy 342.05792 -406.6235) (xy 342.085168 -406.623012) (xy 342.948768 -406.623012)
			(xy 342.976024 -406.623433) (xy 343.029981 -406.631186) (xy 343.082286 -406.64654) (xy 343.131872 -406.669182)
			(xy 343.177732 -406.698651) (xy 343.218931 -406.734347) (xy 343.25463 -406.775542) (xy 343.284102 -406.821399)
			(xy 343.306748 -406.870984) (xy 343.322107 -406.923288) (xy 343.329865 -406.977244) (xy 343.329865 -407.031752)
			(xy 344.767375 -407.031752) (xy 344.767375 -406.977248) (xy 344.775132 -406.923299) (xy 344.790488 -406.871004)
			(xy 344.81313 -406.821426) (xy 344.842597 -406.775575) (xy 344.878289 -406.734384) (xy 344.919481 -406.698692)
			(xy 344.965333 -406.669226) (xy 345.014911 -406.646585) (xy 345.067207 -406.63123) (xy 345.121156 -406.623475)
			(xy 345.148408 -406.623012) (xy 346.012008 -406.623012) (xy 346.03926 -406.623458) (xy 346.09321 -406.631216)
			(xy 346.145507 -406.646573) (xy 346.195085 -406.669216) (xy 346.240937 -406.698684) (xy 346.282129 -406.734377)
			(xy 346.317821 -406.775569) (xy 346.347288 -406.821422) (xy 346.36993 -406.871001) (xy 346.385285 -406.923298)
			(xy 346.393042 -406.977248) (xy 346.393042 -407.031752) (xy 346.393042 -407.031754) (xy 347.830575 -407.031754)
			(xy 347.830575 -406.977246) (xy 347.838333 -406.923294) (xy 347.853691 -406.870995) (xy 347.876336 -406.821414)
			(xy 347.905807 -406.775561) (xy 347.941504 -406.73437) (xy 347.9827 -406.698678) (xy 348.028557 -406.669213)
			(xy 348.07814 -406.646574) (xy 348.130441 -406.631223) (xy 348.184394 -406.623472) (xy 348.211648 -406.623012)
			(xy 349.075248 -406.623012) (xy 349.102498 -406.623461) (xy 349.156444 -406.631224) (xy 349.208736 -406.646584)
			(xy 349.258309 -406.669229) (xy 349.304156 -406.698698) (xy 349.345343 -406.734391) (xy 349.381031 -406.775582)
			(xy 349.410494 -406.821433) (xy 349.433133 -406.87101) (xy 349.448487 -406.923303) (xy 349.456242 -406.97725)
			(xy 349.456242 -407.031749) (xy 350.893898 -407.031749) (xy 350.893898 -406.977251) (xy 350.901654 -406.923307)
			(xy 350.917008 -406.871016) (xy 350.939647 -406.821442) (xy 350.96911 -406.775595) (xy 351.004799 -406.734407)
			(xy 351.045985 -406.698718) (xy 351.091832 -406.669252) (xy 351.141405 -406.646612) (xy 351.193695 -406.631257)
			(xy 351.247639 -406.623499) (xy 351.274888 -406.623012) (xy 352.138488 -406.623012) (xy 352.165743 -406.623434)
			(xy 352.219698 -406.63119) (xy 352.272 -406.646546) (xy 352.321584 -406.669189) (xy 352.367441 -406.698658)
			(xy 352.408638 -406.734354) (xy 352.444335 -406.775549) (xy 352.473805 -406.821405) (xy 352.49645 -406.870989)
			(xy 352.511807 -406.92329) (xy 352.519565 -406.977245) (xy 352.519565 -407.031753) (xy 372.388075 -407.031753)
			(xy 372.388075 -406.977247) (xy 372.395833 -406.923296) (xy 372.411189 -406.870999) (xy 372.433833 -406.821419)
			(xy 372.463302 -406.775567) (xy 372.498997 -406.734376) (xy 372.540191 -406.698684) (xy 372.586046 -406.669219)
			(xy 372.635627 -406.646579) (xy 372.687926 -406.631226) (xy 372.741877 -406.623473) (xy 372.76913 -406.623012)
			(xy 373.63273 -406.623012) (xy 373.659981 -406.62346) (xy 373.713929 -406.63122) (xy 373.766222 -406.646579)
			(xy 373.815799 -406.669223) (xy 373.861648 -406.698691) (xy 373.902836 -406.734385) (xy 373.938527 -406.775576)
			(xy 373.967992 -406.821428) (xy 373.990632 -406.871006) (xy 374.005986 -406.923301) (xy 374.013742 -406.977249)
			(xy 374.013742 -407.031748) (xy 375.451398 -407.031748) (xy 375.451398 -406.977252) (xy 375.459153 -406.923309)
			(xy 375.474506 -406.87102) (xy 375.497144 -406.821447) (xy 375.526606 -406.775601) (xy 375.562292 -406.734414)
			(xy 375.603477 -406.698724) (xy 375.649321 -406.669258) (xy 375.698892 -406.646617) (xy 375.75118 -406.63126)
			(xy 375.805122 -406.6235) (xy 375.83237 -406.623012) (xy 376.69597 -406.623012) (xy 376.723226 -406.623433)
			(xy 376.777183 -406.631187) (xy 376.829487 -406.646541) (xy 376.879074 -406.669183) (xy 376.924933 -406.698652)
			(xy 376.966131 -406.734347) (xy 377.00183 -406.775543) (xy 377.031303 -406.8214) (xy 377.053948 -406.870985)
			(xy 377.069307 -406.923288) (xy 377.077065 -406.977244) (xy 377.077065 -407.031752) (xy 378.514575 -407.031752)
			(xy 378.514575 -406.977248) (xy 378.522332 -406.923299) (xy 378.537688 -406.871003) (xy 378.56033 -406.821425)
			(xy 378.589797 -406.775574) (xy 378.62549 -406.734383) (xy 378.666682 -406.698691) (xy 378.712534 -406.669225)
			(xy 378.762113 -406.646584) (xy 378.814409 -406.63123) (xy 378.868358 -406.623475) (xy 378.89561 -406.623012)
			(xy 379.75921 -406.623012) (xy 379.786462 -406.623459) (xy 379.840412 -406.631217) (xy 379.892708 -406.646573)
			(xy 379.942287 -406.669216) (xy 379.988138 -406.698684) (xy 380.029329 -406.734378) (xy 380.065022 -406.77557)
			(xy 380.094489 -406.821422) (xy 380.11713 -406.871001) (xy 380.132486 -406.923298) (xy 380.140242 -406.977248)
			(xy 380.140242 -407.031748) (xy 381.577898 -407.031748) (xy 381.577898 -406.977252) (xy 381.585653 -406.923312)
			(xy 381.601005 -406.871024) (xy 381.623641 -406.821453) (xy 381.653101 -406.775607) (xy 381.688785 -406.734421)
			(xy 381.729967 -406.698731) (xy 381.775809 -406.669265) (xy 381.825377 -406.646622) (xy 381.877663 -406.631264)
			(xy 381.931603 -406.623502) (xy 381.95885 -406.623012) (xy 382.82245 -406.623012) (xy 382.849707 -406.623431)
			(xy 382.903666 -406.631183) (xy 382.955973 -406.646536) (xy 383.005562 -406.669176) (xy 383.051423 -406.698645)
			(xy 383.092624 -406.73434) (xy 383.128325 -406.775536) (xy 383.1578 -406.821394) (xy 383.180447 -406.870981)
			(xy 383.195806 -406.923285) (xy 383.203565 -406.977243) (xy 383.203565 -407.031749) (xy 384.641098 -407.031749)
			(xy 384.641098 -406.977251) (xy 384.648854 -406.923307) (xy 384.664208 -406.871016) (xy 384.686847 -406.821442)
			(xy 384.716311 -406.775594) (xy 384.751999 -406.734406) (xy 384.793186 -406.698717) (xy 384.839033 -406.669252)
			(xy 384.888606 -406.646611) (xy 384.940897 -406.631256) (xy 384.994841 -406.623499) (xy 385.02209 -406.623012)
			(xy 385.88569 -406.623012) (xy 385.912945 -406.623434) (xy 385.9669 -406.63119) (xy 386.019202 -406.646546)
			(xy 386.068786 -406.66919) (xy 386.114642 -406.698659) (xy 386.155838 -406.734354) (xy 386.191535 -406.77555)
			(xy 386.221006 -406.821406) (xy 386.24365 -406.870989) (xy 386.259007 -406.923291) (xy 386.266765 -406.977245)
			(xy 386.266765 -407.031753) (xy 387.704275 -407.031753) (xy 387.704275 -406.977247) (xy 387.712033 -406.923296)
			(xy 387.727389 -406.870999) (xy 387.750033 -406.821419) (xy 387.779502 -406.775567) (xy 387.815197 -406.734376)
			(xy 387.856391 -406.698684) (xy 387.902246 -406.669219) (xy 387.951827 -406.646579) (xy 388.004126 -406.631226)
			(xy 388.058077 -406.623473) (xy 388.08533 -406.623012) (xy 388.94893 -406.623012) (xy 388.976181 -406.62346)
			(xy 389.030129 -406.63122) (xy 389.082422 -406.646579) (xy 389.131999 -406.669223) (xy 389.177848 -406.698691)
			(xy 389.219036 -406.734385) (xy 389.254727 -406.775576) (xy 389.284192 -406.821428) (xy 389.306832 -406.871006)
			(xy 389.322186 -406.923301) (xy 389.329942 -406.977249) (xy 389.329942 -407.031748) (xy 390.767598 -407.031748)
			(xy 390.767598 -406.977252) (xy 390.775353 -406.923309) (xy 390.790706 -406.87102) (xy 390.813344 -406.821447)
			(xy 390.842806 -406.775601) (xy 390.878492 -406.734414) (xy 390.919677 -406.698724) (xy 390.965521 -406.669258)
			(xy 391.015092 -406.646617) (xy 391.06738 -406.63126) (xy 391.121322 -406.6235) (xy 391.14857 -406.623012)
			(xy 392.01217 -406.623012) (xy 392.039426 -406.623433) (xy 392.093383 -406.631187) (xy 392.145687 -406.646541)
			(xy 392.195274 -406.669183) (xy 392.241133 -406.698652) (xy 392.282331 -406.734347) (xy 392.31803 -406.775543)
			(xy 392.347503 -406.8214) (xy 392.370148 -406.870985) (xy 392.385507 -406.923288) (xy 392.393265 -406.977244)
			(xy 392.393265 -407.031752) (xy 393.830775 -407.031752) (xy 393.830775 -406.977248) (xy 393.838532 -406.923299)
			(xy 393.853888 -406.871003) (xy 393.87653 -406.821425) (xy 393.905997 -406.775574) (xy 393.94169 -406.734383)
			(xy 393.982882 -406.698691) (xy 394.028734 -406.669225) (xy 394.078313 -406.646584) (xy 394.130609 -406.63123)
			(xy 394.184558 -406.623475) (xy 394.21181 -406.623012) (xy 395.07541 -406.623012) (xy 395.102662 -406.623459)
			(xy 395.156612 -406.631217) (xy 395.208908 -406.646573) (xy 395.258487 -406.669216) (xy 395.304338 -406.698684)
			(xy 395.345529 -406.734378) (xy 395.381222 -406.77557) (xy 395.410689 -406.821422) (xy 395.43333 -406.871001)
			(xy 395.448686 -406.923298) (xy 395.456442 -406.977248) (xy 395.456442 -407.031748) (xy 396.894098 -407.031748)
			(xy 396.894098 -406.977252) (xy 396.901853 -406.923312) (xy 396.917205 -406.871024) (xy 396.939841 -406.821453)
			(xy 396.969301 -406.775607) (xy 397.004985 -406.734421) (xy 397.046167 -406.698731) (xy 397.092009 -406.669265)
			(xy 397.141577 -406.646622) (xy 397.193863 -406.631264) (xy 397.247803 -406.623502) (xy 397.27505 -406.623012)
			(xy 398.13865 -406.623012) (xy 398.165907 -406.623431) (xy 398.219866 -406.631183) (xy 398.272173 -406.646536)
			(xy 398.321762 -406.669176) (xy 398.367623 -406.698645) (xy 398.408824 -406.73434) (xy 398.444525 -406.775536)
			(xy 398.474 -406.821394) (xy 398.496647 -406.870981) (xy 398.512006 -406.923285) (xy 398.519765 -406.977243)
			(xy 398.519765 -407.031749) (xy 399.957298 -407.031749) (xy 399.957298 -406.977251) (xy 399.965054 -406.923307)
			(xy 399.980408 -406.871016) (xy 400.003047 -406.821442) (xy 400.032511 -406.775594) (xy 400.068199 -406.734406)
			(xy 400.109386 -406.698717) (xy 400.155233 -406.669252) (xy 400.204806 -406.646611) (xy 400.257097 -406.631256)
			(xy 400.311041 -406.623499) (xy 400.33829 -406.623012) (xy 401.20189 -406.623012) (xy 401.229145 -406.623434)
			(xy 401.2831 -406.63119) (xy 401.335402 -406.646546) (xy 401.384986 -406.66919) (xy 401.430842 -406.698659)
			(xy 401.472038 -406.734354) (xy 401.507735 -406.77555) (xy 401.537206 -406.821406) (xy 401.55985 -406.870989)
			(xy 401.575207 -406.923291) (xy 401.582965 -406.977245) (xy 401.582965 -407.031753) (xy 403.020475 -407.031753)
			(xy 403.020475 -406.977247) (xy 403.028233 -406.923296) (xy 403.043589 -406.870999) (xy 403.066233 -406.821419)
			(xy 403.095702 -406.775567) (xy 403.131397 -406.734376) (xy 403.172591 -406.698684) (xy 403.218446 -406.669219)
			(xy 403.268027 -406.646579) (xy 403.320326 -406.631226) (xy 403.374277 -406.623473) (xy 403.40153 -406.623012)
			(xy 404.26513 -406.623012) (xy 404.292381 -406.62346) (xy 404.346329 -406.63122) (xy 404.398622 -406.646579)
			(xy 404.448199 -406.669223) (xy 404.494048 -406.698691) (xy 404.535236 -406.734385) (xy 404.570927 -406.775576)
			(xy 404.600392 -406.821428) (xy 404.623032 -406.871006) (xy 404.638386 -406.923301) (xy 404.646142 -406.977249)
			(xy 404.646142 -407.031748) (xy 406.083798 -407.031748) (xy 406.083798 -406.977252) (xy 406.091553 -406.923309)
			(xy 406.106906 -406.87102) (xy 406.129544 -406.821447) (xy 406.159006 -406.775601) (xy 406.194692 -406.734414)
			(xy 406.235877 -406.698724) (xy 406.281721 -406.669258) (xy 406.331292 -406.646617) (xy 406.38358 -406.63126)
			(xy 406.437522 -406.6235) (xy 406.46477 -406.623012) (xy 407.32837 -406.623012) (xy 407.355626 -406.623433)
			(xy 407.409583 -406.631187) (xy 407.461887 -406.646541) (xy 407.511474 -406.669183) (xy 407.557333 -406.698652)
			(xy 407.598531 -406.734347) (xy 407.63423 -406.775543) (xy 407.663703 -406.8214) (xy 407.686348 -406.870985)
			(xy 407.701707 -406.923288) (xy 407.709465 -406.977244) (xy 407.709465 -407.031752) (xy 409.146975 -407.031752)
			(xy 409.146975 -406.977248) (xy 409.154732 -406.923299) (xy 409.170088 -406.871003) (xy 409.19273 -406.821425)
			(xy 409.222197 -406.775574) (xy 409.25789 -406.734383) (xy 409.299082 -406.698691) (xy 409.344934 -406.669225)
			(xy 409.394513 -406.646584) (xy 409.446809 -406.63123) (xy 409.500758 -406.623475) (xy 409.52801 -406.623012)
			(xy 410.39161 -406.623012) (xy 410.418862 -406.623459) (xy 410.472812 -406.631217) (xy 410.525108 -406.646573)
			(xy 410.574687 -406.669216) (xy 410.620538 -406.698684) (xy 410.661729 -406.734378) (xy 410.697422 -406.77557)
			(xy 410.726889 -406.821422) (xy 410.74953 -406.871001) (xy 410.764886 -406.923298) (xy 410.772642 -406.977248)
			(xy 410.772642 -407.031748) (xy 412.210298 -407.031748) (xy 412.210298 -406.977252) (xy 412.218053 -406.923312)
			(xy 412.233405 -406.871024) (xy 412.256041 -406.821453) (xy 412.285501 -406.775607) (xy 412.321185 -406.734421)
			(xy 412.362367 -406.698731) (xy 412.408209 -406.669265) (xy 412.457777 -406.646622) (xy 412.510063 -406.631264)
			(xy 412.564003 -406.623502) (xy 412.59125 -406.623012) (xy 413.45485 -406.623012) (xy 413.482107 -406.623431)
			(xy 413.536066 -406.631183) (xy 413.588373 -406.646536) (xy 413.637962 -406.669176) (xy 413.683823 -406.698645)
			(xy 413.725024 -406.73434) (xy 413.760725 -406.775536) (xy 413.7902 -406.821394) (xy 413.812847 -406.870981)
			(xy 413.828206 -406.923285) (xy 413.835965 -406.977243) (xy 413.835965 -407.031749) (xy 415.273498 -407.031749)
			(xy 415.273498 -406.977251) (xy 415.281254 -406.923307) (xy 415.296608 -406.871016) (xy 415.319247 -406.821442)
			(xy 415.348711 -406.775594) (xy 415.384399 -406.734406) (xy 415.425586 -406.698717) (xy 415.471433 -406.669252)
			(xy 415.521006 -406.646611) (xy 415.573297 -406.631256) (xy 415.627241 -406.623499) (xy 415.65449 -406.623012)
			(xy 416.51809 -406.623012) (xy 416.545345 -406.623434) (xy 416.5993 -406.63119) (xy 416.651602 -406.646546)
			(xy 416.701186 -406.66919) (xy 416.747042 -406.698659) (xy 416.788238 -406.734354) (xy 416.823935 -406.77555)
			(xy 416.853406 -406.821406) (xy 416.87605 -406.870989) (xy 416.891407 -406.923291) (xy 416.899165 -406.977245)
			(xy 416.899165 -407.031753) (xy 418.336675 -407.031753) (xy 418.336675 -406.977247) (xy 418.344433 -406.923296)
			(xy 418.359789 -406.870999) (xy 418.382433 -406.821419) (xy 418.411902 -406.775567) (xy 418.447597 -406.734376)
			(xy 418.488791 -406.698684) (xy 418.534646 -406.669219) (xy 418.584227 -406.646579) (xy 418.636526 -406.631226)
			(xy 418.690477 -406.623473) (xy 418.71773 -406.623012) (xy 419.58133 -406.623012) (xy 419.608581 -406.62346)
			(xy 419.662529 -406.63122) (xy 419.714822 -406.646579) (xy 419.764399 -406.669223) (xy 419.810248 -406.698691)
			(xy 419.851436 -406.734385) (xy 419.887127 -406.775576) (xy 419.916592 -406.821428) (xy 419.939232 -406.871006)
			(xy 419.954586 -406.923301) (xy 419.962342 -406.977249) (xy 419.962342 -407.031751) (xy 419.954586 -407.085699)
			(xy 419.939232 -407.137994) (xy 419.916592 -407.187572) (xy 419.887127 -407.233424) (xy 419.851436 -407.274615)
			(xy 419.810248 -407.310309) (xy 419.764399 -407.339777) (xy 419.714822 -407.362421) (xy 419.662529 -407.37778)
			(xy 419.608581 -407.38554) (xy 419.58133 -407.386028) (xy 418.71773 -407.386028) (xy 418.690477 -407.385527)
			(xy 418.636526 -407.377774) (xy 418.584227 -407.362421) (xy 418.534646 -407.339781) (xy 418.488791 -407.310316)
			(xy 418.447597 -407.274624) (xy 418.411902 -407.233433) (xy 418.382433 -407.187581) (xy 418.359789 -407.138001)
			(xy 418.344433 -407.085704) (xy 418.336675 -407.031753) (xy 416.899165 -407.031753) (xy 416.899165 -407.031755)
			(xy 416.891407 -407.085709) (xy 416.87605 -407.138011) (xy 416.853406 -407.187594) (xy 416.823935 -407.23345)
			(xy 416.788238 -407.274646) (xy 416.747042 -407.310341) (xy 416.701186 -407.33981) (xy 416.651602 -407.362454)
			(xy 416.5993 -407.37781) (xy 416.545345 -407.385566) (xy 416.51809 -407.386028) (xy 415.65449 -407.386028)
			(xy 415.627241 -407.385501) (xy 415.573297 -407.377744) (xy 415.521006 -407.362389) (xy 415.471433 -407.339748)
			(xy 415.425586 -407.310283) (xy 415.384399 -407.274594) (xy 415.348711 -407.233406) (xy 415.319247 -407.187558)
			(xy 415.296608 -407.137984) (xy 415.281254 -407.085693) (xy 415.273498 -407.031749) (xy 413.835965 -407.031749)
			(xy 413.835965 -407.031757) (xy 413.828206 -407.085715) (xy 413.812847 -407.138019) (xy 413.7902 -407.187606)
			(xy 413.760725 -407.233464) (xy 413.725024 -407.27466) (xy 413.683823 -407.310355) (xy 413.637962 -407.339824)
			(xy 413.588373 -407.362464) (xy 413.536066 -407.377817) (xy 413.482107 -407.385569) (xy 413.45485 -407.386028)
			(xy 412.59125 -407.386028) (xy 412.564003 -407.385498) (xy 412.510063 -407.377736) (xy 412.457777 -407.362378)
			(xy 412.408209 -407.339735) (xy 412.362367 -407.310269) (xy 412.321185 -407.274579) (xy 412.285501 -407.233393)
			(xy 412.256041 -407.187547) (xy 412.233405 -407.137976) (xy 412.218053 -407.085688) (xy 412.210298 -407.031748)
			(xy 410.772642 -407.031748) (xy 410.772642 -407.031752) (xy 410.764886 -407.085702) (xy 410.74953 -407.137999)
			(xy 410.726889 -407.187578) (xy 410.697422 -407.23343) (xy 410.661729 -407.274622) (xy 410.620538 -407.310316)
			(xy 410.574687 -407.339784) (xy 410.525108 -407.362427) (xy 410.472812 -407.377783) (xy 410.418862 -407.385541)
			(xy 410.39161 -407.386028) (xy 409.52801 -407.386028) (xy 409.500758 -407.385525) (xy 409.446809 -407.37777)
			(xy 409.394513 -407.362416) (xy 409.344934 -407.339775) (xy 409.299082 -407.310309) (xy 409.25789 -407.274617)
			(xy 409.222197 -407.233426) (xy 409.19273 -407.187575) (xy 409.170088 -407.137997) (xy 409.154732 -407.085701)
			(xy 409.146975 -407.031752) (xy 407.709465 -407.031752) (xy 407.709465 -407.031756) (xy 407.701707 -407.085712)
			(xy 407.686348 -407.138015) (xy 407.663703 -407.1876) (xy 407.63423 -407.233457) (xy 407.598531 -407.274653)
			(xy 407.557333 -407.310348) (xy 407.511474 -407.339817) (xy 407.461887 -407.362459) (xy 407.409583 -407.377813)
			(xy 407.355626 -407.385567) (xy 407.32837 -407.386028) (xy 406.46477 -407.386028) (xy 406.437522 -407.3855)
			(xy 406.38358 -407.37774) (xy 406.331292 -407.362383) (xy 406.281721 -407.339742) (xy 406.235877 -407.310276)
			(xy 406.194692 -407.274586) (xy 406.159006 -407.233399) (xy 406.129544 -407.187553) (xy 406.106906 -407.13798)
			(xy 406.091553 -407.085691) (xy 406.083798 -407.031748) (xy 404.646142 -407.031748) (xy 404.646142 -407.031751)
			(xy 404.638386 -407.085699) (xy 404.623032 -407.137994) (xy 404.600392 -407.187572) (xy 404.570927 -407.233424)
			(xy 404.535236 -407.274615) (xy 404.494048 -407.310309) (xy 404.448199 -407.339777) (xy 404.398622 -407.362421)
			(xy 404.346329 -407.37778) (xy 404.292381 -407.38554) (xy 404.26513 -407.386028) (xy 403.40153 -407.386028)
			(xy 403.374277 -407.385527) (xy 403.320326 -407.377774) (xy 403.268027 -407.362421) (xy 403.218446 -407.339781)
			(xy 403.172591 -407.310316) (xy 403.131397 -407.274624) (xy 403.095702 -407.233433) (xy 403.066233 -407.187581)
			(xy 403.043589 -407.138001) (xy 403.028233 -407.085704) (xy 403.020475 -407.031753) (xy 401.582965 -407.031753)
			(xy 401.582965 -407.031755) (xy 401.575207 -407.085709) (xy 401.55985 -407.138011) (xy 401.537206 -407.187594)
			(xy 401.507735 -407.23345) (xy 401.472038 -407.274646) (xy 401.430842 -407.310341) (xy 401.384986 -407.33981)
			(xy 401.335402 -407.362454) (xy 401.2831 -407.37781) (xy 401.229145 -407.385566) (xy 401.20189 -407.386028)
			(xy 400.33829 -407.386028) (xy 400.311041 -407.385501) (xy 400.257097 -407.377744) (xy 400.204806 -407.362389)
			(xy 400.155233 -407.339748) (xy 400.109386 -407.310283) (xy 400.068199 -407.274594) (xy 400.032511 -407.233406)
			(xy 400.003047 -407.187558) (xy 399.980408 -407.137984) (xy 399.965054 -407.085693) (xy 399.957298 -407.031749)
			(xy 398.519765 -407.031749) (xy 398.519765 -407.031757) (xy 398.512006 -407.085715) (xy 398.496647 -407.138019)
			(xy 398.474 -407.187606) (xy 398.444525 -407.233464) (xy 398.408824 -407.27466) (xy 398.367623 -407.310355)
			(xy 398.321762 -407.339824) (xy 398.272173 -407.362464) (xy 398.219866 -407.377817) (xy 398.165907 -407.385569)
			(xy 398.13865 -407.386028) (xy 397.27505 -407.386028) (xy 397.247803 -407.385498) (xy 397.193863 -407.377736)
			(xy 397.141577 -407.362378) (xy 397.092009 -407.339735) (xy 397.046167 -407.310269) (xy 397.004985 -407.274579)
			(xy 396.969301 -407.233393) (xy 396.939841 -407.187547) (xy 396.917205 -407.137976) (xy 396.901853 -407.085688)
			(xy 396.894098 -407.031748) (xy 395.456442 -407.031748) (xy 395.456442 -407.031752) (xy 395.448686 -407.085702)
			(xy 395.43333 -407.137999) (xy 395.410689 -407.187578) (xy 395.381222 -407.23343) (xy 395.345529 -407.274622)
			(xy 395.304338 -407.310316) (xy 395.258487 -407.339784) (xy 395.208908 -407.362427) (xy 395.156612 -407.377783)
			(xy 395.102662 -407.385541) (xy 395.07541 -407.386028) (xy 394.21181 -407.386028) (xy 394.184558 -407.385525)
			(xy 394.130609 -407.37777) (xy 394.078313 -407.362416) (xy 394.028734 -407.339775) (xy 393.982882 -407.310309)
			(xy 393.94169 -407.274617) (xy 393.905997 -407.233426) (xy 393.87653 -407.187575) (xy 393.853888 -407.137997)
			(xy 393.838532 -407.085701) (xy 393.830775 -407.031752) (xy 392.393265 -407.031752) (xy 392.393265 -407.031756)
			(xy 392.385507 -407.085712) (xy 392.370148 -407.138015) (xy 392.347503 -407.1876) (xy 392.31803 -407.233457)
			(xy 392.282331 -407.274653) (xy 392.241133 -407.310348) (xy 392.195274 -407.339817) (xy 392.145687 -407.362459)
			(xy 392.093383 -407.377813) (xy 392.039426 -407.385567) (xy 392.01217 -407.386028) (xy 391.14857 -407.386028)
			(xy 391.121322 -407.3855) (xy 391.06738 -407.37774) (xy 391.015092 -407.362383) (xy 390.965521 -407.339742)
			(xy 390.919677 -407.310276) (xy 390.878492 -407.274586) (xy 390.842806 -407.233399) (xy 390.813344 -407.187553)
			(xy 390.790706 -407.13798) (xy 390.775353 -407.085691) (xy 390.767598 -407.031748) (xy 389.329942 -407.031748)
			(xy 389.329942 -407.031751) (xy 389.322186 -407.085699) (xy 389.306832 -407.137994) (xy 389.284192 -407.187572)
			(xy 389.254727 -407.233424) (xy 389.219036 -407.274615) (xy 389.177848 -407.310309) (xy 389.131999 -407.339777)
			(xy 389.082422 -407.362421) (xy 389.030129 -407.37778) (xy 388.976181 -407.38554) (xy 388.94893 -407.386028)
			(xy 388.08533 -407.386028) (xy 388.058077 -407.385527) (xy 388.004126 -407.377774) (xy 387.951827 -407.362421)
			(xy 387.902246 -407.339781) (xy 387.856391 -407.310316) (xy 387.815197 -407.274624) (xy 387.779502 -407.233433)
			(xy 387.750033 -407.187581) (xy 387.727389 -407.138001) (xy 387.712033 -407.085704) (xy 387.704275 -407.031753)
			(xy 386.266765 -407.031753) (xy 386.266765 -407.031755) (xy 386.259007 -407.085709) (xy 386.24365 -407.138011)
			(xy 386.221006 -407.187594) (xy 386.191535 -407.23345) (xy 386.155838 -407.274646) (xy 386.114642 -407.310341)
			(xy 386.068786 -407.33981) (xy 386.019202 -407.362454) (xy 385.9669 -407.37781) (xy 385.912945 -407.385566)
			(xy 385.88569 -407.386028) (xy 385.02209 -407.386028) (xy 384.994841 -407.385501) (xy 384.940897 -407.377744)
			(xy 384.888606 -407.362389) (xy 384.839033 -407.339748) (xy 384.793186 -407.310283) (xy 384.751999 -407.274594)
			(xy 384.716311 -407.233406) (xy 384.686847 -407.187558) (xy 384.664208 -407.137984) (xy 384.648854 -407.085693)
			(xy 384.641098 -407.031749) (xy 383.203565 -407.031749) (xy 383.203565 -407.031757) (xy 383.195806 -407.085715)
			(xy 383.180447 -407.138019) (xy 383.1578 -407.187606) (xy 383.128325 -407.233464) (xy 383.092624 -407.27466)
			(xy 383.051423 -407.310355) (xy 383.005562 -407.339824) (xy 382.955973 -407.362464) (xy 382.903666 -407.377817)
			(xy 382.849707 -407.385569) (xy 382.82245 -407.386028) (xy 381.95885 -407.386028) (xy 381.931603 -407.385498)
			(xy 381.877663 -407.377736) (xy 381.825377 -407.362378) (xy 381.775809 -407.339735) (xy 381.729967 -407.310269)
			(xy 381.688785 -407.274579) (xy 381.653101 -407.233393) (xy 381.623641 -407.187547) (xy 381.601005 -407.137976)
			(xy 381.585653 -407.085688) (xy 381.577898 -407.031748) (xy 380.140242 -407.031748) (xy 380.140242 -407.031752)
			(xy 380.132486 -407.085702) (xy 380.11713 -407.137999) (xy 380.094489 -407.187578) (xy 380.065022 -407.23343)
			(xy 380.029329 -407.274622) (xy 379.988138 -407.310316) (xy 379.942287 -407.339784) (xy 379.892708 -407.362427)
			(xy 379.840412 -407.377783) (xy 379.786462 -407.385541) (xy 379.75921 -407.386028) (xy 378.89561 -407.386028)
			(xy 378.868358 -407.385525) (xy 378.814409 -407.37777) (xy 378.762113 -407.362416) (xy 378.712534 -407.339775)
			(xy 378.666682 -407.310309) (xy 378.62549 -407.274617) (xy 378.589797 -407.233426) (xy 378.56033 -407.187575)
			(xy 378.537688 -407.137997) (xy 378.522332 -407.085701) (xy 378.514575 -407.031752) (xy 377.077065 -407.031752)
			(xy 377.077065 -407.031756) (xy 377.069307 -407.085712) (xy 377.053948 -407.138015) (xy 377.031303 -407.1876)
			(xy 377.00183 -407.233457) (xy 376.966131 -407.274653) (xy 376.924933 -407.310348) (xy 376.879074 -407.339817)
			(xy 376.829487 -407.362459) (xy 376.777183 -407.377813) (xy 376.723226 -407.385567) (xy 376.69597 -407.386028)
			(xy 375.83237 -407.386028) (xy 375.805122 -407.3855) (xy 375.75118 -407.37774) (xy 375.698892 -407.362383)
			(xy 375.649321 -407.339742) (xy 375.603477 -407.310276) (xy 375.562292 -407.274586) (xy 375.526606 -407.233399)
			(xy 375.497144 -407.187553) (xy 375.474506 -407.13798) (xy 375.459153 -407.085691) (xy 375.451398 -407.031748)
			(xy 374.013742 -407.031748) (xy 374.013742 -407.031751) (xy 374.005986 -407.085699) (xy 373.990632 -407.137994)
			(xy 373.967992 -407.187572) (xy 373.938527 -407.233424) (xy 373.902836 -407.274615) (xy 373.861648 -407.310309)
			(xy 373.815799 -407.339777) (xy 373.766222 -407.362421) (xy 373.713929 -407.37778) (xy 373.659981 -407.38554)
			(xy 373.63273 -407.386028) (xy 372.76913 -407.386028) (xy 372.741877 -407.385527) (xy 372.687926 -407.377774)
			(xy 372.635627 -407.362421) (xy 372.586046 -407.339781) (xy 372.540191 -407.310316) (xy 372.498997 -407.274624)
			(xy 372.463302 -407.233433) (xy 372.433833 -407.187581) (xy 372.411189 -407.138001) (xy 372.395833 -407.085704)
			(xy 372.388075 -407.031753) (xy 352.519565 -407.031753) (xy 352.519565 -407.031755) (xy 352.511807 -407.08571)
			(xy 352.49645 -407.138011) (xy 352.473805 -407.187595) (xy 352.444335 -407.233451) (xy 352.408638 -407.274646)
			(xy 352.367441 -407.310342) (xy 352.321584 -407.339811) (xy 352.272 -407.362454) (xy 352.219698 -407.37781)
			(xy 352.165743 -407.385566) (xy 352.138488 -407.386028) (xy 351.274888 -407.386028) (xy 351.247639 -407.385501)
			(xy 351.193695 -407.377743) (xy 351.141405 -407.362388) (xy 351.091832 -407.339748) (xy 351.045985 -407.310282)
			(xy 351.004799 -407.274593) (xy 350.96911 -407.233405) (xy 350.939647 -407.187558) (xy 350.917008 -407.137984)
			(xy 350.901654 -407.085693) (xy 350.893898 -407.031749) (xy 349.456242 -407.031749) (xy 349.456242 -407.03175)
			(xy 349.448487 -407.085697) (xy 349.433133 -407.137991) (xy 349.410494 -407.187567) (xy 349.381031 -407.233418)
			(xy 349.345343 -407.274609) (xy 349.304156 -407.310302) (xy 349.258309 -407.339771) (xy 349.208736 -407.362416)
			(xy 349.156444 -407.377776) (xy 349.102498 -407.385539) (xy 349.075248 -407.386028) (xy 348.211648 -407.386028)
			(xy 348.184394 -407.385528) (xy 348.130441 -407.377777) (xy 348.07814 -407.362426) (xy 348.028557 -407.339787)
			(xy 347.9827 -407.310322) (xy 347.941504 -407.27463) (xy 347.905807 -407.233439) (xy 347.876336 -407.187586)
			(xy 347.853691 -407.138005) (xy 347.838333 -407.085706) (xy 347.830575 -407.031754) (xy 346.393042 -407.031754)
			(xy 346.385285 -407.085702) (xy 346.36993 -407.137999) (xy 346.347288 -407.187578) (xy 346.317821 -407.233431)
			(xy 346.282129 -407.274623) (xy 346.240937 -407.310316) (xy 346.195085 -407.339784) (xy 346.145507 -407.362427)
			(xy 346.09321 -407.377784) (xy 346.03926 -407.385542) (xy 346.012008 -407.386028) (xy 345.148408 -407.386028)
			(xy 345.121156 -407.385525) (xy 345.067207 -407.37777) (xy 345.014911 -407.362415) (xy 344.965333 -407.339774)
			(xy 344.919481 -407.310308) (xy 344.878289 -407.274616) (xy 344.842597 -407.233425) (xy 344.81313 -407.187574)
			(xy 344.790488 -407.137996) (xy 344.775132 -407.085701) (xy 344.767375 -407.031752) (xy 343.329865 -407.031752)
			(xy 343.329865 -407.031756) (xy 343.322107 -407.085712) (xy 343.306748 -407.138016) (xy 343.284102 -407.187601)
			(xy 343.25463 -407.233458) (xy 343.218931 -407.274653) (xy 343.177732 -407.310349) (xy 343.131872 -407.339818)
			(xy 343.082286 -407.36246) (xy 343.029981 -407.377814) (xy 342.976024 -407.385567) (xy 342.948768 -407.386028)
			(xy 342.085168 -407.386028) (xy 342.05792 -407.3855) (xy 342.003978 -407.37774) (xy 341.95169 -407.362383)
			(xy 341.90212 -407.339741) (xy 341.856276 -407.310275) (xy 341.815092 -407.274586) (xy 341.779405 -407.233399)
			(xy 341.749944 -407.187552) (xy 341.727306 -407.13798) (xy 341.711953 -407.08569) (xy 341.704198 -407.031748)
			(xy 340.266542 -407.031748) (xy 340.266542 -407.031751) (xy 340.258786 -407.0857) (xy 340.243432 -407.137995)
			(xy 340.220791 -407.187573) (xy 340.191326 -407.233424) (xy 340.155636 -407.274616) (xy 340.114447 -407.310309)
			(xy 340.068597 -407.339778) (xy 340.019021 -407.362422) (xy 339.966727 -407.37778) (xy 339.912779 -407.38554)
			(xy 339.885528 -407.386028) (xy 339.021928 -407.386028) (xy 338.994675 -407.385527) (xy 338.940724 -407.377773)
			(xy 338.888426 -407.36242) (xy 338.838845 -407.339781) (xy 338.79299 -407.310315) (xy 338.751797 -407.274623)
			(xy 338.716102 -407.233432) (xy 338.686633 -407.18758) (xy 338.663989 -407.138001) (xy 338.648633 -407.085703)
			(xy 338.640875 -407.031753) (xy 337.203365 -407.031753) (xy 337.203365 -407.031755) (xy 337.195607 -407.08571)
			(xy 337.18025 -407.138011) (xy 337.157605 -407.187595) (xy 337.128135 -407.233451) (xy 337.092438 -407.274646)
			(xy 337.051241 -407.310342) (xy 337.005384 -407.339811) (xy 336.9558 -407.362454) (xy 336.903498 -407.37781)
			(xy 336.849543 -407.385566) (xy 336.822288 -407.386028) (xy 335.958688 -407.386028) (xy 335.931439 -407.385501)
			(xy 335.877495 -407.377743) (xy 335.825205 -407.362388) (xy 335.775632 -407.339748) (xy 335.729785 -407.310282)
			(xy 335.688599 -407.274593) (xy 335.65291 -407.233405) (xy 335.623447 -407.187558) (xy 335.600808 -407.137984)
			(xy 335.585454 -407.085693) (xy 335.577698 -407.031749) (xy 334.140042 -407.031749) (xy 334.140042 -407.03175)
			(xy 334.132287 -407.085697) (xy 334.116933 -407.137991) (xy 334.094294 -407.187567) (xy 334.064831 -407.233418)
			(xy 334.029143 -407.274609) (xy 333.987956 -407.310302) (xy 333.942109 -407.339771) (xy 333.892536 -407.362416)
			(xy 333.840244 -407.377776) (xy 333.786298 -407.385539) (xy 333.759048 -407.386028) (xy 332.895448 -407.386028)
			(xy 332.868194 -407.385528) (xy 332.814241 -407.377777) (xy 332.76194 -407.362426) (xy 332.712357 -407.339787)
			(xy 332.6665 -407.310322) (xy 332.625304 -407.27463) (xy 332.589607 -407.233439) (xy 332.560136 -407.187586)
			(xy 332.537491 -407.138005) (xy 332.522133 -407.085706) (xy 332.514375 -407.031754) (xy 331.076842 -407.031754)
			(xy 331.069085 -407.085702) (xy 331.05373 -407.137999) (xy 331.031088 -407.187578) (xy 331.001621 -407.233431)
			(xy 330.965929 -407.274623) (xy 330.924737 -407.310316) (xy 330.878885 -407.339784) (xy 330.829307 -407.362427)
			(xy 330.77701 -407.377784) (xy 330.72306 -407.385542) (xy 330.695808 -407.386028) (xy 329.832208 -407.386028)
			(xy 329.804956 -407.385525) (xy 329.751007 -407.37777) (xy 329.698711 -407.362415) (xy 329.649133 -407.339774)
			(xy 329.603281 -407.310308) (xy 329.562089 -407.274616) (xy 329.526397 -407.233425) (xy 329.49693 -407.187574)
			(xy 329.474288 -407.137996) (xy 329.458932 -407.085701) (xy 329.451175 -407.031752) (xy 328.013665 -407.031752)
			(xy 328.013665 -407.031756) (xy 328.005907 -407.085712) (xy 327.990548 -407.138016) (xy 327.967902 -407.187601)
			(xy 327.93843 -407.233458) (xy 327.902731 -407.274653) (xy 327.861532 -407.310349) (xy 327.815672 -407.339818)
			(xy 327.766086 -407.36246) (xy 327.713781 -407.377814) (xy 327.659824 -407.385567) (xy 327.632568 -407.386028)
			(xy 326.768968 -407.386028) (xy 326.74172 -407.3855) (xy 326.687778 -407.37774) (xy 326.63549 -407.362383)
			(xy 326.58592 -407.339741) (xy 326.540076 -407.310275) (xy 326.498892 -407.274586) (xy 326.463205 -407.233399)
			(xy 326.433744 -407.187552) (xy 326.411106 -407.13798) (xy 326.395753 -407.08569) (xy 326.387998 -407.031748)
			(xy 324.950342 -407.031748) (xy 324.950342 -407.031751) (xy 324.942586 -407.0857) (xy 324.927232 -407.137995)
			(xy 324.904591 -407.187573) (xy 324.875126 -407.233424) (xy 324.839436 -407.274616) (xy 324.798247 -407.310309)
			(xy 324.752397 -407.339778) (xy 324.702821 -407.362422) (xy 324.650527 -407.37778) (xy 324.596579 -407.38554)
			(xy 324.569328 -407.386028) (xy 323.705728 -407.386028) (xy 323.678475 -407.385527) (xy 323.624524 -407.377773)
			(xy 323.572226 -407.36242) (xy 323.522645 -407.339781) (xy 323.47679 -407.310315) (xy 323.435597 -407.274623)
			(xy 323.399902 -407.233432) (xy 323.370433 -407.18758) (xy 323.347789 -407.138001) (xy 323.332433 -407.085703)
			(xy 323.324675 -407.031753) (xy 321.887165 -407.031753) (xy 321.887165 -407.031755) (xy 321.879407 -407.08571)
			(xy 321.86405 -407.138011) (xy 321.841405 -407.187595) (xy 321.811935 -407.233451) (xy 321.776238 -407.274646)
			(xy 321.735041 -407.310342) (xy 321.689184 -407.339811) (xy 321.6396 -407.362454) (xy 321.587298 -407.37781)
			(xy 321.533343 -407.385566) (xy 321.506088 -407.386028) (xy 320.642488 -407.386028) (xy 320.615239 -407.385501)
			(xy 320.561295 -407.377743) (xy 320.509005 -407.362388) (xy 320.459432 -407.339748) (xy 320.413585 -407.310282)
			(xy 320.372399 -407.274593) (xy 320.33671 -407.233405) (xy 320.307247 -407.187558) (xy 320.284608 -407.137984)
			(xy 320.269254 -407.085693) (xy 320.261498 -407.031749) (xy 318.823842 -407.031749) (xy 318.823842 -407.03175)
			(xy 318.816087 -407.085697) (xy 318.800733 -407.137991) (xy 318.778094 -407.187567) (xy 318.748631 -407.233418)
			(xy 318.712943 -407.274609) (xy 318.671756 -407.310302) (xy 318.625909 -407.339771) (xy 318.576336 -407.362416)
			(xy 318.524044 -407.377776) (xy 318.470098 -407.385539) (xy 318.442848 -407.386028) (xy 317.579248 -407.386028)
			(xy 317.551994 -407.385528) (xy 317.498041 -407.377777) (xy 317.44574 -407.362426) (xy 317.396157 -407.339787)
			(xy 317.3503 -407.310322) (xy 317.309104 -407.27463) (xy 317.273407 -407.233439) (xy 317.243936 -407.187586)
			(xy 317.221291 -407.138005) (xy 317.205933 -407.085706) (xy 317.198175 -407.031754) (xy 315.760642 -407.031754)
			(xy 315.752885 -407.085702) (xy 315.73753 -407.137999) (xy 315.714888 -407.187578) (xy 315.685421 -407.233431)
			(xy 315.649729 -407.274623) (xy 315.608537 -407.310316) (xy 315.562685 -407.339784) (xy 315.513107 -407.362427)
			(xy 315.46081 -407.377784) (xy 315.40686 -407.385542) (xy 315.379608 -407.386028) (xy 314.516008 -407.386028)
			(xy 314.488756 -407.385525) (xy 314.434807 -407.37777) (xy 314.382511 -407.362415) (xy 314.332933 -407.339774)
			(xy 314.287081 -407.310308) (xy 314.245889 -407.274616) (xy 314.210197 -407.233425) (xy 314.18073 -407.187574)
			(xy 314.158088 -407.137996) (xy 314.142732 -407.085701) (xy 314.134975 -407.031752) (xy 312.697465 -407.031752)
			(xy 312.697465 -407.031756) (xy 312.689707 -407.085712) (xy 312.674348 -407.138016) (xy 312.651702 -407.187601)
			(xy 312.62223 -407.233458) (xy 312.586531 -407.274653) (xy 312.545332 -407.310349) (xy 312.499472 -407.339818)
			(xy 312.449886 -407.36246) (xy 312.397581 -407.377814) (xy 312.343624 -407.385567) (xy 312.316368 -407.386028)
			(xy 311.452768 -407.386028) (xy 311.42552 -407.3855) (xy 311.371578 -407.37774) (xy 311.31929 -407.362383)
			(xy 311.26972 -407.339741) (xy 311.223876 -407.310275) (xy 311.182692 -407.274586) (xy 311.147005 -407.233399)
			(xy 311.117544 -407.187552) (xy 311.094906 -407.13798) (xy 311.079553 -407.08569) (xy 311.071798 -407.031748)
			(xy 309.634142 -407.031748) (xy 309.634142 -407.031751) (xy 309.626386 -407.0857) (xy 309.611032 -407.137995)
			(xy 309.588391 -407.187573) (xy 309.558926 -407.233424) (xy 309.523236 -407.274616) (xy 309.482047 -407.310309)
			(xy 309.436197 -407.339778) (xy 309.386621 -407.362422) (xy 309.334327 -407.37778) (xy 309.280379 -407.38554)
			(xy 309.253128 -407.386028) (xy 308.389528 -407.386028) (xy 308.362275 -407.385527) (xy 308.308324 -407.377773)
			(xy 308.256026 -407.36242) (xy 308.206445 -407.339781) (xy 308.16059 -407.310315) (xy 308.119397 -407.274623)
			(xy 308.083702 -407.233432) (xy 308.054233 -407.18758) (xy 308.031589 -407.138001) (xy 308.016233 -407.085703)
			(xy 308.008475 -407.031753) (xy 306.570965 -407.031753) (xy 306.570965 -407.031755) (xy 306.563207 -407.08571)
			(xy 306.54785 -407.138011) (xy 306.525205 -407.187595) (xy 306.495735 -407.233451) (xy 306.460038 -407.274646)
			(xy 306.418841 -407.310342) (xy 306.372984 -407.339811) (xy 306.3234 -407.362454) (xy 306.271098 -407.37781)
			(xy 306.217143 -407.385566) (xy 306.189888 -407.386028) (xy 305.326288 -407.386028) (xy 305.299039 -407.385501)
			(xy 305.245095 -407.377743) (xy 305.192805 -407.362388) (xy 305.143232 -407.339748) (xy 305.097385 -407.310282)
			(xy 305.056199 -407.274593) (xy 305.02051 -407.233405) (xy 304.991047 -407.187558) (xy 304.968408 -407.137984)
			(xy 304.953054 -407.085693) (xy 304.945298 -407.031749) (xy 168.694465 -407.031749) (xy 168.694465 -407.031756)
			(xy 168.686706 -407.085714) (xy 168.671347 -407.138019) (xy 168.6487 -407.187604) (xy 168.619226 -407.233462)
			(xy 168.583526 -407.274658) (xy 168.542325 -407.310354) (xy 168.496464 -407.339822) (xy 168.446875 -407.362463)
			(xy 168.394569 -407.377816) (xy 168.34061 -407.385568) (xy 168.313354 -407.386028) (xy 167.449754 -407.386028)
			(xy 167.422506 -407.385499) (xy 167.368567 -407.377737) (xy 167.31628 -407.362379) (xy 167.266711 -407.339736)
			(xy 167.220869 -407.31027) (xy 167.179687 -407.274581) (xy 167.144002 -407.233394) (xy 167.114542 -407.187548)
			(xy 167.091905 -407.137977) (xy 167.076553 -407.085688) (xy 167.068798 -407.031748) (xy 165.631142 -407.031748)
			(xy 165.631142 -407.031752) (xy 165.623386 -407.085701) (xy 165.60803 -407.137998) (xy 165.585389 -407.187577)
			(xy 165.555923 -407.233429) (xy 165.520231 -407.274621) (xy 165.47904 -407.310314) (xy 165.433189 -407.339782)
			(xy 165.383611 -407.362426) (xy 165.331315 -407.377783) (xy 165.277366 -407.385541) (xy 165.250114 -407.386028)
			(xy 164.386514 -407.386028) (xy 164.359262 -407.385526) (xy 164.305312 -407.377771) (xy 164.253016 -407.362417)
			(xy 164.203436 -407.339776) (xy 164.157584 -407.31031) (xy 164.116392 -407.274618) (xy 164.080698 -407.233427)
			(xy 164.051231 -407.187576) (xy 164.028588 -407.137998) (xy 164.013232 -407.085701) (xy 164.005475 -407.031752)
			(xy 162.567965 -407.031752) (xy 162.567965 -407.031755) (xy 162.560207 -407.085712) (xy 162.544849 -407.138014)
			(xy 162.522203 -407.187599) (xy 162.492731 -407.233456) (xy 162.457033 -407.274651) (xy 162.415835 -407.310347)
			(xy 162.369976 -407.339816) (xy 162.32039 -407.362458) (xy 162.268086 -407.377813) (xy 162.21413 -407.385567)
			(xy 162.186874 -407.386028) (xy 161.323274 -407.386028) (xy 161.296025 -407.3855) (xy 161.242083 -407.377741)
			(xy 161.189795 -407.362384) (xy 161.140223 -407.339743) (xy 161.094379 -407.310278) (xy 161.053194 -407.274588)
			(xy 161.017507 -407.233401) (xy 160.988045 -407.187554) (xy 160.965407 -407.137981) (xy 160.950054 -407.085691)
			(xy 160.942298 -407.031749) (xy 159.504642 -407.031749) (xy 159.504642 -407.031751) (xy 159.496886 -407.085699)
			(xy 159.481532 -407.137993) (xy 159.458892 -407.187571) (xy 159.429428 -407.233422) (xy 159.393738 -407.274614)
			(xy 159.352549 -407.310307) (xy 159.306701 -407.339776) (xy 159.257125 -407.36242) (xy 159.204832 -407.377779)
			(xy 159.150885 -407.38554) (xy 159.123634 -407.386028) (xy 158.260034 -407.386028) (xy 158.232781 -407.385527)
			(xy 158.178829 -407.377774) (xy 158.12653 -407.362422) (xy 158.076948 -407.339783) (xy 158.031093 -407.310317)
			(xy 157.989899 -407.274625) (xy 157.954203 -407.233434) (xy 157.924734 -407.187582) (xy 157.90209 -407.138002)
			(xy 157.886733 -407.085704) (xy 157.878975 -407.031753) (xy 156.441465 -407.031753) (xy 156.441465 -407.031755)
			(xy 156.433708 -407.085709) (xy 156.41835 -407.13801) (xy 156.395706 -407.187593) (xy 156.366236 -407.233449)
			(xy 156.33054 -407.274644) (xy 156.289344 -407.31034) (xy 156.243488 -407.339809) (xy 156.193904 -407.362452)
			(xy 156.141603 -407.377809) (xy 156.087649 -407.385566) (xy 156.060394 -407.386028) (xy 155.196794 -407.386028)
			(xy 155.169544 -407.385501) (xy 155.1156 -407.377745) (xy 155.063309 -407.36239) (xy 155.013735 -407.339749)
			(xy 154.967888 -407.310285) (xy 154.926701 -407.274595) (xy 154.891012 -407.233407) (xy 154.861548 -407.187559)
			(xy 154.838908 -407.137985) (xy 154.823554 -407.085694) (xy 154.815798 -407.03175) (xy 153.378265 -407.03175)
			(xy 153.378265 -407.031756) (xy 153.370506 -407.085714) (xy 153.355147 -407.138019) (xy 153.3325 -407.187604)
			(xy 153.303026 -407.233462) (xy 153.267326 -407.274658) (xy 153.226125 -407.310354) (xy 153.180264 -407.339822)
			(xy 153.130675 -407.362463) (xy 153.078369 -407.377816) (xy 153.02441 -407.385568) (xy 152.997154 -407.386028)
			(xy 152.133554 -407.386028) (xy 152.106306 -407.385499) (xy 152.052367 -407.377737) (xy 152.00008 -407.362379)
			(xy 151.950511 -407.339736) (xy 151.904669 -407.31027) (xy 151.863487 -407.274581) (xy 151.827802 -407.233394)
			(xy 151.798342 -407.187548) (xy 151.775705 -407.137977) (xy 151.760353 -407.085688) (xy 151.752598 -407.031748)
			(xy 150.314942 -407.031748) (xy 150.314942 -407.031752) (xy 150.307186 -407.085701) (xy 150.29183 -407.137998)
			(xy 150.269189 -407.187577) (xy 150.239723 -407.233429) (xy 150.204031 -407.274621) (xy 150.16284 -407.310314)
			(xy 150.116989 -407.339782) (xy 150.067411 -407.362426) (xy 150.015115 -407.377783) (xy 149.961166 -407.385541)
			(xy 149.933914 -407.386028) (xy 149.070314 -407.386028) (xy 149.043062 -407.385526) (xy 148.989112 -407.377771)
			(xy 148.936816 -407.362417) (xy 148.887236 -407.339776) (xy 148.841384 -407.31031) (xy 148.800192 -407.274618)
			(xy 148.764498 -407.233427) (xy 148.735031 -407.187576) (xy 148.712388 -407.137998) (xy 148.697032 -407.085701)
			(xy 148.689275 -407.031752) (xy 147.251765 -407.031752) (xy 147.251765 -407.031755) (xy 147.244007 -407.085712)
			(xy 147.228649 -407.138014) (xy 147.206003 -407.187599) (xy 147.176531 -407.233456) (xy 147.140833 -407.274651)
			(xy 147.099635 -407.310347) (xy 147.053776 -407.339816) (xy 147.00419 -407.362458) (xy 146.951886 -407.377813)
			(xy 146.89793 -407.385567) (xy 146.870674 -407.386028) (xy 146.007074 -407.386028) (xy 145.979825 -407.3855)
			(xy 145.925883 -407.377741) (xy 145.873595 -407.362384) (xy 145.824023 -407.339743) (xy 145.778179 -407.310278)
			(xy 145.736994 -407.274588) (xy 145.701307 -407.233401) (xy 145.671845 -407.187554) (xy 145.649207 -407.137981)
			(xy 145.633854 -407.085691) (xy 145.626098 -407.031749) (xy 144.188442 -407.031749) (xy 144.188442 -407.031751)
			(xy 144.180686 -407.085699) (xy 144.165332 -407.137993) (xy 144.142692 -407.187571) (xy 144.113228 -407.233422)
			(xy 144.077538 -407.274614) (xy 144.036349 -407.310307) (xy 143.990501 -407.339776) (xy 143.940925 -407.36242)
			(xy 143.888632 -407.377779) (xy 143.834685 -407.38554) (xy 143.807434 -407.386028) (xy 142.943834 -407.386028)
			(xy 142.916581 -407.385527) (xy 142.862629 -407.377774) (xy 142.81033 -407.362422) (xy 142.760748 -407.339783)
			(xy 142.714893 -407.310317) (xy 142.673699 -407.274625) (xy 142.638003 -407.233434) (xy 142.608534 -407.187582)
			(xy 142.58589 -407.138002) (xy 142.570533 -407.085704) (xy 142.562775 -407.031753) (xy 141.125265 -407.031753)
			(xy 141.125265 -407.031755) (xy 141.117508 -407.085709) (xy 141.10215 -407.13801) (xy 141.079506 -407.187593)
			(xy 141.050036 -407.233449) (xy 141.01434 -407.274644) (xy 140.973144 -407.31034) (xy 140.927288 -407.339809)
			(xy 140.877704 -407.362452) (xy 140.825403 -407.377809) (xy 140.771449 -407.385566) (xy 140.744194 -407.386028)
			(xy 139.880594 -407.386028) (xy 139.853344 -407.385501) (xy 139.7994 -407.377745) (xy 139.747109 -407.36239)
			(xy 139.697535 -407.339749) (xy 139.651688 -407.310285) (xy 139.610501 -407.274595) (xy 139.574812 -407.233407)
			(xy 139.545348 -407.187559) (xy 139.522708 -407.137985) (xy 139.507354 -407.085694) (xy 139.499598 -407.03175)
			(xy 138.062065 -407.03175) (xy 138.062065 -407.031756) (xy 138.054306 -407.085714) (xy 138.038947 -407.138019)
			(xy 138.0163 -407.187604) (xy 137.986826 -407.233462) (xy 137.951126 -407.274658) (xy 137.909925 -407.310354)
			(xy 137.864064 -407.339822) (xy 137.814475 -407.362463) (xy 137.762169 -407.377816) (xy 137.70821 -407.385568)
			(xy 137.680954 -407.386028) (xy 136.817354 -407.386028) (xy 136.790106 -407.385499) (xy 136.736167 -407.377737)
			(xy 136.68388 -407.362379) (xy 136.634311 -407.339736) (xy 136.588469 -407.31027) (xy 136.547287 -407.274581)
			(xy 136.511602 -407.233394) (xy 136.482142 -407.187548) (xy 136.459505 -407.137977) (xy 136.444153 -407.085688)
			(xy 136.436398 -407.031748) (xy 134.998742 -407.031748) (xy 134.998742 -407.031752) (xy 134.990986 -407.085701)
			(xy 134.97563 -407.137998) (xy 134.952989 -407.187577) (xy 134.923523 -407.233429) (xy 134.887831 -407.274621)
			(xy 134.84664 -407.310314) (xy 134.800789 -407.339782) (xy 134.751211 -407.362426) (xy 134.698915 -407.377783)
			(xy 134.644966 -407.385541) (xy 134.617714 -407.386028) (xy 133.754114 -407.386028) (xy 133.726862 -407.385526)
			(xy 133.672912 -407.377771) (xy 133.620616 -407.362417) (xy 133.571036 -407.339776) (xy 133.525184 -407.31031)
			(xy 133.483992 -407.274618) (xy 133.448298 -407.233427) (xy 133.418831 -407.187576) (xy 133.396188 -407.137998)
			(xy 133.380832 -407.085701) (xy 133.373075 -407.031752) (xy 131.935565 -407.031752) (xy 131.935565 -407.031755)
			(xy 131.927807 -407.085712) (xy 131.912449 -407.138014) (xy 131.889803 -407.187599) (xy 131.860331 -407.233456)
			(xy 131.824633 -407.274651) (xy 131.783435 -407.310347) (xy 131.737576 -407.339816) (xy 131.68799 -407.362458)
			(xy 131.635686 -407.377813) (xy 131.58173 -407.385567) (xy 131.554474 -407.386028) (xy 130.690874 -407.386028)
			(xy 130.663625 -407.3855) (xy 130.609683 -407.377741) (xy 130.557395 -407.362384) (xy 130.507823 -407.339743)
			(xy 130.461979 -407.310278) (xy 130.420794 -407.274588) (xy 130.385107 -407.233401) (xy 130.355645 -407.187554)
			(xy 130.333007 -407.137981) (xy 130.317654 -407.085691) (xy 130.309898 -407.031749) (xy 128.872242 -407.031749)
			(xy 128.872242 -407.031751) (xy 128.864486 -407.085699) (xy 128.849132 -407.137993) (xy 128.826492 -407.187571)
			(xy 128.797028 -407.233422) (xy 128.761338 -407.274614) (xy 128.720149 -407.310307) (xy 128.674301 -407.339776)
			(xy 128.624725 -407.36242) (xy 128.572432 -407.377779) (xy 128.518485 -407.38554) (xy 128.491234 -407.386028)
			(xy 127.627634 -407.386028) (xy 127.600381 -407.385527) (xy 127.546429 -407.377774) (xy 127.49413 -407.362422)
			(xy 127.444548 -407.339783) (xy 127.398693 -407.310317) (xy 127.357499 -407.274625) (xy 127.321803 -407.233434)
			(xy 127.292334 -407.187582) (xy 127.26969 -407.138002) (xy 127.254333 -407.085704) (xy 127.246575 -407.031753)
			(xy 125.809065 -407.031753) (xy 125.809065 -407.031755) (xy 125.801308 -407.085709) (xy 125.78595 -407.13801)
			(xy 125.763306 -407.187593) (xy 125.733836 -407.233449) (xy 125.69814 -407.274644) (xy 125.656944 -407.31034)
			(xy 125.611088 -407.339809) (xy 125.561504 -407.362452) (xy 125.509203 -407.377809) (xy 125.455249 -407.385566)
			(xy 125.427994 -407.386028) (xy 124.564394 -407.386028) (xy 124.537144 -407.385501) (xy 124.4832 -407.377745)
			(xy 124.430909 -407.36239) (xy 124.381335 -407.339749) (xy 124.335488 -407.310285) (xy 124.294301 -407.274595)
			(xy 124.258612 -407.233407) (xy 124.229148 -407.187559) (xy 124.206508 -407.137985) (xy 124.191154 -407.085694)
			(xy 124.183398 -407.03175) (xy 122.745865 -407.03175) (xy 122.745865 -407.031756) (xy 122.738106 -407.085714)
			(xy 122.722747 -407.138019) (xy 122.7001 -407.187604) (xy 122.670626 -407.233462) (xy 122.634926 -407.274658)
			(xy 122.593725 -407.310354) (xy 122.547864 -407.339822) (xy 122.498275 -407.362463) (xy 122.445969 -407.377816)
			(xy 122.39201 -407.385568) (xy 122.364754 -407.386028) (xy 121.501154 -407.386028) (xy 121.473906 -407.385499)
			(xy 121.419967 -407.377737) (xy 121.36768 -407.362379) (xy 121.318111 -407.339736) (xy 121.272269 -407.31027)
			(xy 121.231087 -407.274581) (xy 121.195402 -407.233394) (xy 121.165942 -407.187548) (xy 121.143305 -407.137977)
			(xy 121.127953 -407.085688) (xy 121.120198 -407.031748) (xy 107.861153 -407.031748) (xy 107.86873 -407.084449)
			(xy 107.86873 -407.138951) (xy 107.860974 -407.192898) (xy 107.84562 -407.245192) (xy 107.822979 -407.294769)
			(xy 107.793514 -407.34062) (xy 107.757824 -407.38181) (xy 107.716636 -407.417502) (xy 107.670787 -407.44697)
			(xy 107.621211 -407.469613) (xy 107.568918 -407.48497) (xy 107.514971 -407.492729) (xy 107.48772 -407.493216)
			(xy 106.62412 -407.493216) (xy 106.596867 -407.492738) (xy 106.542915 -407.484984) (xy 106.490616 -407.46963)
			(xy 106.441034 -407.446989) (xy 106.395179 -407.417522) (xy 106.353985 -407.381829) (xy 106.31829 -407.340637)
			(xy 106.288821 -407.294783) (xy 106.266177 -407.245203) (xy 106.250821 -407.192905) (xy 106.243063 -407.138953)
			(xy 96.495694 -407.138953) (xy 96.473493 -407.18757) (xy 96.444028 -407.233421) (xy 96.408339 -407.274612)
			(xy 96.367151 -407.310306) (xy 96.321303 -407.339775) (xy 96.271728 -407.362419) (xy 96.219435 -407.377778)
			(xy 96.165489 -407.38554) (xy 96.138238 -407.386028) (xy 95.274638 -407.386028) (xy 95.247385 -407.385527)
			(xy 95.193433 -407.377775) (xy 95.141133 -407.362423) (xy 95.091551 -407.339784) (xy 95.045695 -407.310319)
			(xy 95.0045 -407.274627) (xy 94.968804 -407.233435) (xy 94.939334 -407.187583) (xy 94.91669 -407.138003)
			(xy 94.901333 -407.085705) (xy 94.893575 -407.031753) (xy 93.456065 -407.031753) (xy 93.456065 -407.031754)
			(xy 93.448308 -407.085708) (xy 93.432951 -407.138009) (xy 93.410307 -407.187592) (xy 93.380837 -407.233448)
			(xy 93.345141 -407.274643) (xy 93.303946 -407.310338) (xy 93.25809 -407.339808) (xy 93.208507 -407.362451)
			(xy 93.156206 -407.377808) (xy 93.102252 -407.385565) (xy 93.074998 -407.386028) (xy 92.211398 -407.386028)
			(xy 92.184148 -407.385502) (xy 92.130204 -407.377745) (xy 92.077912 -407.362391) (xy 92.028338 -407.339751)
			(xy 91.98249 -407.310286) (xy 91.941302 -407.274596) (xy 91.905613 -407.233408) (xy 91.876148 -407.187561)
			(xy 91.853508 -407.137986) (xy 91.838154 -407.085694) (xy 91.830398 -407.03175) (xy 90.392865 -407.03175)
			(xy 90.392865 -407.031756) (xy 90.385107 -407.085714) (xy 90.369748 -407.138018) (xy 90.347101 -407.187603)
			(xy 90.317627 -407.233461) (xy 90.281927 -407.274657) (xy 90.240727 -407.310352) (xy 90.194866 -407.339821)
			(xy 90.145278 -407.362462) (xy 90.092973 -407.377815) (xy 90.039014 -407.385568) (xy 90.011758 -407.386028)
			(xy 89.148158 -407.386028) (xy 89.12091 -407.385499) (xy 89.06697 -407.377738) (xy 89.014683 -407.36238)
			(xy 88.965114 -407.339738) (xy 88.919271 -407.310272) (xy 88.878088 -407.274582) (xy 88.842403 -407.233395)
			(xy 88.812942 -407.187549) (xy 88.790305 -407.137978) (xy 88.774953 -407.085689) (xy 88.767198 -407.031748)
			(xy 87.329542 -407.031748) (xy 87.329542 -407.031752) (xy 87.321786 -407.085701) (xy 87.306431 -407.137997)
			(xy 87.28379 -407.187576) (xy 87.254324 -407.233427) (xy 87.218632 -407.274619) (xy 87.177442 -407.310313)
			(xy 87.131591 -407.339781) (xy 87.082014 -407.362424) (xy 87.029718 -407.377782) (xy 86.97577 -407.385541)
			(xy 86.948518 -407.386028) (xy 86.084918 -407.386028) (xy 86.057666 -407.385526) (xy 86.003716 -407.377771)
			(xy 85.951418 -407.362418) (xy 85.901839 -407.339778) (xy 85.855986 -407.310312) (xy 85.814793 -407.27462)
			(xy 85.779099 -407.233429) (xy 85.749631 -407.187577) (xy 85.726989 -407.137998) (xy 85.711632 -407.085702)
			(xy 85.703875 -407.031752) (xy 84.266365 -407.031752) (xy 84.266365 -407.031755) (xy 84.258607 -407.085711)
			(xy 84.243249 -407.138013) (xy 84.220604 -407.187598) (xy 84.191132 -407.233454) (xy 84.155434 -407.27465)
			(xy 84.114237 -407.310345) (xy 84.068378 -407.339814) (xy 84.018793 -407.362457) (xy 83.96649 -407.377812)
			(xy 83.912533 -407.385567) (xy 83.885278 -407.386028) (xy 83.021678 -407.386028) (xy 82.994429 -407.3855)
			(xy 82.940487 -407.377742) (xy 82.888197 -407.362385) (xy 82.838626 -407.339744) (xy 82.79278 -407.310279)
			(xy 82.751595 -407.274589) (xy 82.715908 -407.233402) (xy 82.686445 -407.187555) (xy 82.663807 -407.137982)
			(xy 82.648454 -407.085692) (xy 82.640698 -407.031749) (xy 81.203042 -407.031749) (xy 81.203042 -407.031751)
			(xy 81.195286 -407.085698) (xy 81.179932 -407.137993) (xy 81.157293 -407.18757) (xy 81.127828 -407.233421)
			(xy 81.092139 -407.274612) (xy 81.050951 -407.310306) (xy 81.005103 -407.339775) (xy 80.955528 -407.362419)
			(xy 80.903235 -407.377778) (xy 80.849289 -407.38554) (xy 80.822038 -407.386028) (xy 79.958438 -407.386028)
			(xy 79.931185 -407.385527) (xy 79.877233 -407.377775) (xy 79.824933 -407.362423) (xy 79.775351 -407.339784)
			(xy 79.729495 -407.310319) (xy 79.6883 -407.274627) (xy 79.652604 -407.233435) (xy 79.623134 -407.187583)
			(xy 79.60049 -407.138003) (xy 79.585133 -407.085705) (xy 79.577375 -407.031753) (xy 78.139865 -407.031753)
			(xy 78.139865 -407.031754) (xy 78.132108 -407.085708) (xy 78.116751 -407.138009) (xy 78.094107 -407.187592)
			(xy 78.064637 -407.233448) (xy 78.028941 -407.274643) (xy 77.987746 -407.310338) (xy 77.94189 -407.339808)
			(xy 77.892307 -407.362451) (xy 77.840006 -407.377808) (xy 77.786052 -407.385565) (xy 77.758798 -407.386028)
			(xy 76.895198 -407.386028) (xy 76.867948 -407.385502) (xy 76.814004 -407.377745) (xy 76.761712 -407.362391)
			(xy 76.712138 -407.339751) (xy 76.66629 -407.310286) (xy 76.625102 -407.274596) (xy 76.589413 -407.233408)
			(xy 76.559948 -407.187561) (xy 76.537308 -407.137986) (xy 76.521954 -407.085694) (xy 76.514198 -407.03175)
			(xy 75.076665 -407.03175) (xy 75.076665 -407.031756) (xy 75.068907 -407.085714) (xy 75.053548 -407.138018)
			(xy 75.030901 -407.187603) (xy 75.001427 -407.233461) (xy 74.965727 -407.274657) (xy 74.924527 -407.310352)
			(xy 74.878666 -407.339821) (xy 74.829078 -407.362462) (xy 74.776773 -407.377815) (xy 74.722814 -407.385568)
			(xy 74.695558 -407.386028) (xy 73.831958 -407.386028) (xy 73.80471 -407.385499) (xy 73.75077 -407.377738)
			(xy 73.698483 -407.36238) (xy 73.648914 -407.339738) (xy 73.603071 -407.310272) (xy 73.561888 -407.274582)
			(xy 73.526203 -407.233395) (xy 73.496742 -407.187549) (xy 73.474105 -407.137978) (xy 73.458753 -407.085689)
			(xy 73.450998 -407.031748) (xy 72.013342 -407.031748) (xy 72.013342 -407.031752) (xy 72.005586 -407.085701)
			(xy 71.990231 -407.137997) (xy 71.96759 -407.187576) (xy 71.938124 -407.233427) (xy 71.902432 -407.274619)
			(xy 71.861242 -407.310313) (xy 71.815391 -407.339781) (xy 71.765814 -407.362424) (xy 71.713518 -407.377782)
			(xy 71.65957 -407.385541) (xy 71.632318 -407.386028) (xy 70.768718 -407.386028) (xy 70.741466 -407.385526)
			(xy 70.687516 -407.377771) (xy 70.635218 -407.362418) (xy 70.585639 -407.339778) (xy 70.539786 -407.310312)
			(xy 70.498593 -407.27462) (xy 70.462899 -407.233429) (xy 70.433431 -407.187577) (xy 70.410789 -407.137998)
			(xy 70.395432 -407.085702) (xy 70.387675 -407.031752) (xy 68.950165 -407.031752) (xy 68.950165 -407.031755)
			(xy 68.942407 -407.085711) (xy 68.927049 -407.138013) (xy 68.904404 -407.187598) (xy 68.874932 -407.233454)
			(xy 68.839234 -407.27465) (xy 68.798037 -407.310345) (xy 68.752178 -407.339814) (xy 68.702593 -407.362457)
			(xy 68.65029 -407.377812) (xy 68.596333 -407.385567) (xy 68.569078 -407.386028) (xy 67.705478 -407.386028)
			(xy 67.678229 -407.3855) (xy 67.624287 -407.377742) (xy 67.571997 -407.362385) (xy 67.522426 -407.339744)
			(xy 67.47658 -407.310279) (xy 67.435395 -407.274589) (xy 67.399708 -407.233402) (xy 67.370245 -407.187555)
			(xy 67.347607 -407.137982) (xy 67.332254 -407.085692) (xy 67.324498 -407.031749) (xy 65.886842 -407.031749)
			(xy 65.886842 -407.031751) (xy 65.879086 -407.085698) (xy 65.863732 -407.137993) (xy 65.841093 -407.18757)
			(xy 65.811628 -407.233421) (xy 65.775939 -407.274612) (xy 65.734751 -407.310306) (xy 65.688903 -407.339775)
			(xy 65.639328 -407.362419) (xy 65.587035 -407.377778) (xy 65.533089 -407.38554) (xy 65.505838 -407.386028)
			(xy 64.642238 -407.386028) (xy 64.614985 -407.385527) (xy 64.561033 -407.377775) (xy 64.508733 -407.362423)
			(xy 64.459151 -407.339784) (xy 64.413295 -407.310319) (xy 64.3721 -407.274627) (xy 64.336404 -407.233435)
			(xy 64.306934 -407.187583) (xy 64.28429 -407.138003) (xy 64.268933 -407.085705) (xy 64.261175 -407.031753)
			(xy 62.823665 -407.031753) (xy 62.823665 -407.031754) (xy 62.815908 -407.085708) (xy 62.800551 -407.138009)
			(xy 62.777907 -407.187592) (xy 62.748437 -407.233448) (xy 62.712741 -407.274643) (xy 62.671546 -407.310338)
			(xy 62.62569 -407.339808) (xy 62.576107 -407.362451) (xy 62.523806 -407.377808) (xy 62.469852 -407.385565)
			(xy 62.442598 -407.386028) (xy 61.578998 -407.386028) (xy 61.551748 -407.385502) (xy 61.497804 -407.377745)
			(xy 61.445512 -407.362391) (xy 61.395938 -407.339751) (xy 61.35009 -407.310286) (xy 61.308902 -407.274596)
			(xy 61.273213 -407.233408) (xy 61.243748 -407.187561) (xy 61.221108 -407.137986) (xy 61.205754 -407.085694)
			(xy 61.197998 -407.03175) (xy 59.760465 -407.03175) (xy 59.760465 -407.031756) (xy 59.752707 -407.085714)
			(xy 59.737348 -407.138018) (xy 59.714701 -407.187603) (xy 59.685227 -407.233461) (xy 59.649527 -407.274657)
			(xy 59.608327 -407.310352) (xy 59.562466 -407.339821) (xy 59.512878 -407.362462) (xy 59.460573 -407.377815)
			(xy 59.406614 -407.385568) (xy 59.379358 -407.386028) (xy 58.515758 -407.386028) (xy 58.48851 -407.385499)
			(xy 58.43457 -407.377738) (xy 58.382283 -407.36238) (xy 58.332714 -407.339738) (xy 58.286871 -407.310272)
			(xy 58.245688 -407.274582) (xy 58.210003 -407.233395) (xy 58.180542 -407.187549) (xy 58.157905 -407.137978)
			(xy 58.142553 -407.085689) (xy 58.134798 -407.031748) (xy 56.697142 -407.031748) (xy 56.697142 -407.031752)
			(xy 56.689386 -407.085701) (xy 56.674031 -407.137997) (xy 56.65139 -407.187576) (xy 56.621924 -407.233427)
			(xy 56.586232 -407.274619) (xy 56.545042 -407.310313) (xy 56.499191 -407.339781) (xy 56.449614 -407.362424)
			(xy 56.397318 -407.377782) (xy 56.34337 -407.385541) (xy 56.316118 -407.386028) (xy 55.452518 -407.386028)
			(xy 55.425266 -407.385526) (xy 55.371316 -407.377771) (xy 55.319018 -407.362418) (xy 55.269439 -407.339778)
			(xy 55.223586 -407.310312) (xy 55.182393 -407.27462) (xy 55.146699 -407.233429) (xy 55.117231 -407.187577)
			(xy 55.094589 -407.137998) (xy 55.079232 -407.085702) (xy 55.071475 -407.031752) (xy 53.633965 -407.031752)
			(xy 53.633965 -407.031755) (xy 53.626207 -407.085711) (xy 53.610849 -407.138013) (xy 53.588204 -407.187598)
			(xy 53.558732 -407.233454) (xy 53.523034 -407.27465) (xy 53.481837 -407.310345) (xy 53.435978 -407.339814)
			(xy 53.386393 -407.362457) (xy 53.33409 -407.377812) (xy 53.280133 -407.385567) (xy 53.252878 -407.386028)
			(xy 52.389278 -407.386028) (xy 52.362029 -407.3855) (xy 52.308087 -407.377742) (xy 52.255797 -407.362385)
			(xy 52.206226 -407.339744) (xy 52.16038 -407.310279) (xy 52.119195 -407.274589) (xy 52.083508 -407.233402)
			(xy 52.054045 -407.187555) (xy 52.031407 -407.137982) (xy 52.016054 -407.085692) (xy 52.008298 -407.031749)
			(xy 50.570642 -407.031749) (xy 50.570642 -407.031751) (xy 50.562886 -407.085698) (xy 50.547532 -407.137993)
			(xy 50.524893 -407.18757) (xy 50.495428 -407.233421) (xy 50.459739 -407.274612) (xy 50.418551 -407.310306)
			(xy 50.372703 -407.339775) (xy 50.323128 -407.362419) (xy 50.270835 -407.377778) (xy 50.216889 -407.38554)
			(xy 50.189638 -407.386028) (xy 49.326038 -407.386028) (xy 49.298785 -407.385527) (xy 49.244833 -407.377775)
			(xy 49.192533 -407.362423) (xy 49.142951 -407.339784) (xy 49.097095 -407.310319) (xy 49.0559 -407.274627)
			(xy 49.020204 -407.233435) (xy 48.990734 -407.187583) (xy 48.96809 -407.138003) (xy 48.952733 -407.085705)
			(xy 48.944975 -407.031753) (xy 16.741648 -407.031753) (xy 16.741648 -407.035508) (xy 16.741162 -407.062759)
			(xy 16.733406 -407.116707) (xy 16.718051 -407.169002) (xy 16.695409 -407.218579) (xy 16.665943 -407.264429)
			(xy 16.630252 -407.30562) (xy 16.589061 -407.341311) (xy 16.543211 -407.370777) (xy 16.493634 -407.393419)
			(xy 16.441339 -407.408774) (xy 16.387391 -407.41653) (xy 16.332889 -407.41653) (xy 16.278941 -407.408774)
			(xy 16.226646 -407.393419) (xy 16.177069 -407.370777) (xy 16.131219 -407.341311) (xy 16.090028 -407.30562)
			(xy 16.054337 -407.264429) (xy 16.024871 -407.218579) (xy 16.002229 -407.169002) (xy 15.986874 -407.116707)
			(xy 15.979118 -407.062759) (xy 15.978632 -407.035508) (xy 5.555234 -407.035508) (xy 6.274054 -407.754328)
			(xy 6.323476 -407.804436) (xy 6.417282 -407.909377) (xy 6.505056 -408.019414) (xy 6.586523 -408.134198)
			(xy 6.661426 -408.25337) (xy 6.729529 -408.376554) (xy 6.790618 -408.503362) (xy 6.844501 -408.633397)
			(xy 6.891008 -408.766247) (xy 6.929993 -408.901497) (xy 6.961334 -409.03872) (xy 6.984932 -409.177484)
			(xy 7.000712 -409.317352) (xy 7.008625 -409.457886) (xy 7.00913 -409.528264) (xy 7.00913 -410.057457)
			(xy 48.944923 -410.057457) (xy 48.944923 -410.002943) (xy 48.952682 -409.948984) (xy 48.968041 -409.896679)
			(xy 48.990688 -409.847092) (xy 49.020162 -409.801233) (xy 49.055863 -409.760036) (xy 49.097064 -409.724339)
			(xy 49.142925 -409.69487) (xy 49.192515 -409.672228) (xy 49.244821 -409.656874) (xy 49.298781 -409.64912)
			(xy 49.326038 -409.64866) (xy 50.189638 -409.64866) (xy 50.216885 -409.649213) (xy 50.270824 -409.656973)
			(xy 50.32311 -409.67233) (xy 50.372678 -409.694972) (xy 50.41852 -409.724436) (xy 50.459702 -409.760125)
			(xy 50.495386 -409.801311) (xy 50.524847 -409.847155) (xy 50.547483 -409.896726) (xy 50.562835 -409.949013)
			(xy 50.57059 -410.002953) (xy 50.57059 -410.057447) (xy 50.570589 -410.057453) (xy 52.008246 -410.057453)
			(xy 52.008246 -410.002947) (xy 52.016002 -409.948997) (xy 52.031358 -409.8967) (xy 52.053999 -409.84712)
			(xy 52.083466 -409.801267) (xy 52.119158 -409.760074) (xy 52.160349 -409.724379) (xy 52.206201 -409.69491)
			(xy 52.255779 -409.672265) (xy 52.308076 -409.656907) (xy 52.362025 -409.649147) (xy 52.389278 -409.64866)
			(xy 53.252878 -409.64866) (xy 53.28013 -409.649186) (xy 53.334078 -409.65694) (xy 53.386374 -409.672292)
			(xy 53.435953 -409.694932) (xy 53.481805 -409.724397) (xy 53.522997 -409.760087) (xy 53.55869 -409.801277)
			(xy 53.588158 -409.847127) (xy 53.6108 -409.896705) (xy 53.626156 -409.949) (xy 53.633913 -410.002948)
			(xy 53.633913 -410.057452) (xy 53.633912 -410.057456) (xy 55.071423 -410.057456) (xy 55.071423 -410.002944)
			(xy 55.079181 -409.948987) (xy 55.094539 -409.896683) (xy 55.117185 -409.847098) (xy 55.146657 -409.80124)
			(xy 55.182356 -409.760043) (xy 55.223554 -409.724346) (xy 55.269413 -409.694876) (xy 55.319 -409.672233)
			(xy 55.371305 -409.656877) (xy 55.425262 -409.649122) (xy 55.452518 -409.64866) (xy 56.316118 -409.64866)
			(xy 56.343366 -409.649211) (xy 56.397307 -409.656969) (xy 56.449595 -409.672325) (xy 56.499166 -409.694965)
			(xy 56.54501 -409.724429) (xy 56.586195 -409.760118) (xy 56.621882 -409.801304) (xy 56.651344 -409.84715)
			(xy 56.673982 -409.896721) (xy 56.689334 -409.94901) (xy 56.69709 -410.002952) (xy 56.69709 -410.057448)
			(xy 56.697089 -410.057452) (xy 58.134746 -410.057452) (xy 58.134746 -410.002948) (xy 58.142502 -409.949)
			(xy 58.157856 -409.896704) (xy 58.180496 -409.847125) (xy 58.209961 -409.801273) (xy 58.245651 -409.760081)
			(xy 58.28684 -409.724386) (xy 58.332689 -409.694916) (xy 58.382265 -409.672271) (xy 58.434559 -409.656911)
			(xy 58.488506 -409.649149) (xy 58.515758 -409.64866) (xy 59.379358 -409.64866) (xy 59.406611 -409.649184)
			(xy 59.460561 -409.656936) (xy 59.51286 -409.672287) (xy 59.562441 -409.694925) (xy 59.608296 -409.72439)
			(xy 59.64949 -409.76008) (xy 59.685185 -409.801271) (xy 59.714655 -409.847122) (xy 59.737298 -409.896701)
			(xy 59.752655 -409.948997) (xy 59.760413 -410.002948) (xy 59.760413 -410.057452) (xy 59.760413 -410.057453)
			(xy 61.197946 -410.057453) (xy 61.197946 -410.002947) (xy 61.205703 -409.948994) (xy 61.221059 -409.896695)
			(xy 61.243702 -409.847114) (xy 61.273171 -409.80126) (xy 61.308865 -409.760066) (xy 61.350059 -409.724372)
			(xy 61.395913 -409.694903) (xy 61.445494 -409.67226) (xy 61.497793 -409.656903) (xy 61.551745 -409.649146)
			(xy 61.578998 -409.64866) (xy 62.442598 -409.64866) (xy 62.469849 -409.649187) (xy 62.523795 -409.656943)
			(xy 62.576089 -409.672298) (xy 62.625665 -409.694938) (xy 62.671515 -409.724404) (xy 62.712704 -409.760094)
			(xy 62.748395 -409.801284) (xy 62.777861 -409.847133) (xy 62.800502 -409.896709) (xy 62.815856 -409.949003)
			(xy 62.823613 -410.002949) (xy 62.823613 -410.057451) (xy 62.823612 -410.057457) (xy 64.261123 -410.057457)
			(xy 64.261123 -410.002943) (xy 64.268882 -409.948984) (xy 64.284241 -409.896679) (xy 64.306888 -409.847092)
			(xy 64.336362 -409.801233) (xy 64.372063 -409.760036) (xy 64.413264 -409.724339) (xy 64.459125 -409.69487)
			(xy 64.508715 -409.672228) (xy 64.561021 -409.656874) (xy 64.614981 -409.64912) (xy 64.642238 -409.64866)
			(xy 65.505838 -409.64866) (xy 65.533085 -409.649213) (xy 65.587024 -409.656973) (xy 65.63931 -409.67233)
			(xy 65.688878 -409.694972) (xy 65.73472 -409.724436) (xy 65.775902 -409.760125) (xy 65.811586 -409.801311)
			(xy 65.841047 -409.847155) (xy 65.863683 -409.896726) (xy 65.879035 -409.949013) (xy 65.88679 -410.002953)
			(xy 65.88679 -410.057447) (xy 65.886789 -410.057453) (xy 67.324446 -410.057453) (xy 67.324446 -410.002947)
			(xy 67.332202 -409.948997) (xy 67.347558 -409.8967) (xy 67.370199 -409.84712) (xy 67.399666 -409.801267)
			(xy 67.435358 -409.760074) (xy 67.476549 -409.724379) (xy 67.522401 -409.69491) (xy 67.571979 -409.672265)
			(xy 67.624276 -409.656907) (xy 67.678225 -409.649147) (xy 67.705478 -409.64866) (xy 68.569078 -409.64866)
			(xy 68.59633 -409.649186) (xy 68.650278 -409.65694) (xy 68.702574 -409.672292) (xy 68.752153 -409.694932)
			(xy 68.798005 -409.724397) (xy 68.839197 -409.760087) (xy 68.87489 -409.801277) (xy 68.904358 -409.847127)
			(xy 68.927 -409.896705) (xy 68.942356 -409.949) (xy 68.950113 -410.002948) (xy 68.950113 -410.057452)
			(xy 68.950112 -410.057456) (xy 70.387623 -410.057456) (xy 70.387623 -410.002944) (xy 70.395381 -409.948987)
			(xy 70.410739 -409.896683) (xy 70.433385 -409.847098) (xy 70.462857 -409.80124) (xy 70.498556 -409.760043)
			(xy 70.539754 -409.724346) (xy 70.585613 -409.694876) (xy 70.6352 -409.672233) (xy 70.687505 -409.656877)
			(xy 70.741462 -409.649122) (xy 70.768718 -409.64866) (xy 71.632318 -409.64866) (xy 71.659566 -409.649211)
			(xy 71.713507 -409.656969) (xy 71.765795 -409.672325) (xy 71.815366 -409.694965) (xy 71.86121 -409.724429)
			(xy 71.902395 -409.760118) (xy 71.938082 -409.801304) (xy 71.967544 -409.84715) (xy 71.990182 -409.896721)
			(xy 72.005534 -409.94901) (xy 72.01329 -410.002952) (xy 72.01329 -410.057448) (xy 72.013289 -410.057452)
			(xy 73.450946 -410.057452) (xy 73.450946 -410.002948) (xy 73.458702 -409.949) (xy 73.474056 -409.896704)
			(xy 73.496696 -409.847125) (xy 73.526161 -409.801273) (xy 73.561851 -409.760081) (xy 73.60304 -409.724386)
			(xy 73.648889 -409.694916) (xy 73.698465 -409.672271) (xy 73.750759 -409.656911) (xy 73.804706 -409.649149)
			(xy 73.831958 -409.64866) (xy 74.695558 -409.64866) (xy 74.722811 -409.649184) (xy 74.776761 -409.656936)
			(xy 74.82906 -409.672287) (xy 74.878641 -409.694925) (xy 74.924496 -409.72439) (xy 74.96569 -409.76008)
			(xy 75.001385 -409.801271) (xy 75.030855 -409.847122) (xy 75.053498 -409.896701) (xy 75.068855 -409.948997)
			(xy 75.076613 -410.002948) (xy 75.076613 -410.057452) (xy 75.076613 -410.057453) (xy 76.514146 -410.057453)
			(xy 76.514146 -410.002947) (xy 76.521903 -409.948994) (xy 76.537259 -409.896695) (xy 76.559902 -409.847114)
			(xy 76.589371 -409.80126) (xy 76.625065 -409.760066) (xy 76.666259 -409.724372) (xy 76.712113 -409.694903)
			(xy 76.761694 -409.67226) (xy 76.813993 -409.656903) (xy 76.867945 -409.649146) (xy 76.895198 -409.64866)
			(xy 77.758798 -409.64866) (xy 77.786049 -409.649187) (xy 77.839995 -409.656943) (xy 77.892289 -409.672298)
			(xy 77.941865 -409.694938) (xy 77.987715 -409.724404) (xy 78.028904 -409.760094) (xy 78.064595 -409.801284)
			(xy 78.094061 -409.847133) (xy 78.116702 -409.896709) (xy 78.132056 -409.949003) (xy 78.139813 -410.002949)
			(xy 78.139813 -410.057451) (xy 78.139812 -410.057457) (xy 79.577323 -410.057457) (xy 79.577323 -410.002943)
			(xy 79.585082 -409.948984) (xy 79.600441 -409.896679) (xy 79.623088 -409.847092) (xy 79.652562 -409.801233)
			(xy 79.688263 -409.760036) (xy 79.729464 -409.724339) (xy 79.775325 -409.69487) (xy 79.824915 -409.672228)
			(xy 79.877221 -409.656874) (xy 79.931181 -409.64912) (xy 79.958438 -409.64866) (xy 80.822038 -409.64866)
			(xy 80.849285 -409.649213) (xy 80.903224 -409.656973) (xy 80.95551 -409.67233) (xy 81.005078 -409.694972)
			(xy 81.05092 -409.724436) (xy 81.092102 -409.760125) (xy 81.127786 -409.801311) (xy 81.157247 -409.847155)
			(xy 81.179883 -409.896726) (xy 81.195235 -409.949013) (xy 81.20299 -410.002953) (xy 81.20299 -410.057447)
			(xy 81.202989 -410.057453) (xy 82.640646 -410.057453) (xy 82.640646 -410.002947) (xy 82.648402 -409.948997)
			(xy 82.663758 -409.8967) (xy 82.686399 -409.84712) (xy 82.715866 -409.801267) (xy 82.751558 -409.760074)
			(xy 82.792749 -409.724379) (xy 82.838601 -409.69491) (xy 82.888179 -409.672265) (xy 82.940476 -409.656907)
			(xy 82.994425 -409.649147) (xy 83.021678 -409.64866) (xy 83.885278 -409.64866) (xy 83.91253 -409.649186)
			(xy 83.966478 -409.65694) (xy 84.018774 -409.672292) (xy 84.068353 -409.694932) (xy 84.114205 -409.724397)
			(xy 84.155397 -409.760087) (xy 84.19109 -409.801277) (xy 84.220558 -409.847127) (xy 84.2432 -409.896705)
			(xy 84.258556 -409.949) (xy 84.266313 -410.002948) (xy 84.266313 -410.057452) (xy 84.266312 -410.057456)
			(xy 85.703823 -410.057456) (xy 85.703823 -410.002944) (xy 85.711581 -409.948987) (xy 85.726939 -409.896683)
			(xy 85.749585 -409.847098) (xy 85.779057 -409.80124) (xy 85.814756 -409.760043) (xy 85.855954 -409.724346)
			(xy 85.901813 -409.694876) (xy 85.9514 -409.672233) (xy 86.003705 -409.656877) (xy 86.057662 -409.649122)
			(xy 86.084918 -409.64866) (xy 86.948518 -409.64866) (xy 86.975766 -409.649211) (xy 87.029707 -409.656969)
			(xy 87.081995 -409.672325) (xy 87.131566 -409.694965) (xy 87.17741 -409.724429) (xy 87.218595 -409.760118)
			(xy 87.254282 -409.801304) (xy 87.283744 -409.84715) (xy 87.306382 -409.896721) (xy 87.321734 -409.94901)
			(xy 87.32949 -410.002952) (xy 87.32949 -410.057448) (xy 87.329489 -410.057452) (xy 88.767146 -410.057452)
			(xy 88.767146 -410.002948) (xy 88.774902 -409.949) (xy 88.790256 -409.896704) (xy 88.812896 -409.847125)
			(xy 88.842361 -409.801273) (xy 88.878051 -409.760081) (xy 88.91924 -409.724386) (xy 88.965089 -409.694916)
			(xy 89.014665 -409.672271) (xy 89.066959 -409.656911) (xy 89.120906 -409.649149) (xy 89.148158 -409.64866)
			(xy 90.011758 -409.64866) (xy 90.039011 -409.649184) (xy 90.092961 -409.656936) (xy 90.14526 -409.672287)
			(xy 90.194841 -409.694925) (xy 90.240696 -409.72439) (xy 90.28189 -409.76008) (xy 90.317585 -409.801271)
			(xy 90.347055 -409.847122) (xy 90.369698 -409.896701) (xy 90.385055 -409.948997) (xy 90.392813 -410.002948)
			(xy 90.392813 -410.057452) (xy 90.392813 -410.057453) (xy 91.830346 -410.057453) (xy 91.830346 -410.002947)
			(xy 91.838103 -409.948994) (xy 91.853459 -409.896695) (xy 91.876102 -409.847114) (xy 91.905571 -409.80126)
			(xy 91.941265 -409.760066) (xy 91.982459 -409.724372) (xy 92.028313 -409.694903) (xy 92.077894 -409.67226)
			(xy 92.130193 -409.656903) (xy 92.184145 -409.649146) (xy 92.211398 -409.64866) (xy 93.074998 -409.64866)
			(xy 93.102249 -409.649187) (xy 93.156195 -409.656943) (xy 93.208489 -409.672298) (xy 93.258065 -409.694938)
			(xy 93.303915 -409.724404) (xy 93.345104 -409.760094) (xy 93.380795 -409.801284) (xy 93.410261 -409.847133)
			(xy 93.432902 -409.896709) (xy 93.448256 -409.949003) (xy 93.456013 -410.002949) (xy 93.456013 -410.057451)
			(xy 93.456012 -410.057457) (xy 94.893523 -410.057457) (xy 94.893523 -410.002943) (xy 94.901282 -409.948984)
			(xy 94.916641 -409.896679) (xy 94.939288 -409.847092) (xy 94.968762 -409.801233) (xy 95.004463 -409.760036)
			(xy 95.045664 -409.724339) (xy 95.091525 -409.69487) (xy 95.141115 -409.672228) (xy 95.193421 -409.656874)
			(xy 95.247381 -409.64912) (xy 95.274638 -409.64866) (xy 96.138238 -409.64866) (xy 96.165485 -409.649213)
			(xy 96.219424 -409.656973) (xy 96.27171 -409.67233) (xy 96.321278 -409.694972) (xy 96.36712 -409.724436)
			(xy 96.408302 -409.760125) (xy 96.443986 -409.801311) (xy 96.473447 -409.847155) (xy 96.496083 -409.896726)
			(xy 96.511435 -409.949013) (xy 96.51919 -410.002953) (xy 96.51919 -410.057447) (xy 96.519189 -410.057451)
			(xy 121.120146 -410.057451) (xy 121.120146 -410.002949) (xy 121.127902 -409.949) (xy 121.143256 -409.896705)
			(xy 121.165895 -409.847127) (xy 121.19536 -409.801275) (xy 121.231049 -409.760082) (xy 121.272238 -409.724388)
			(xy 121.318086 -409.694918) (xy 121.367662 -409.672272) (xy 121.419955 -409.656911) (xy 121.473903 -409.649149)
			(xy 121.501154 -409.64866) (xy 122.364754 -409.64866) (xy 122.392007 -409.649184) (xy 122.445958 -409.656935)
			(xy 122.498257 -409.672286) (xy 122.547839 -409.694924) (xy 122.593694 -409.724388) (xy 122.634889 -409.760079)
			(xy 122.670584 -409.801269) (xy 122.700054 -409.847121) (xy 122.722698 -409.8967) (xy 122.738055 -409.948997)
			(xy 122.745813 -410.002947) (xy 122.745813 -410.057453) (xy 124.183346 -410.057453) (xy 124.183346 -410.002947)
			(xy 124.191103 -409.948995) (xy 124.206459 -409.896696) (xy 124.229102 -409.847115) (xy 124.25857 -409.801261)
			(xy 124.294264 -409.760068) (xy 124.335457 -409.724373) (xy 124.38131 -409.694904) (xy 124.430891 -409.672261)
			(xy 124.483189 -409.656904) (xy 124.537141 -409.649146) (xy 124.564394 -409.64866) (xy 125.427994 -409.64866)
			(xy 125.455245 -409.649187) (xy 125.509192 -409.656942) (xy 125.561486 -409.672297) (xy 125.611063 -409.694937)
			(xy 125.656913 -409.724402) (xy 125.698103 -409.760093) (xy 125.733794 -409.801282) (xy 125.76326 -409.847132)
			(xy 125.785901 -409.896708) (xy 125.801256 -409.949002) (xy 125.809013 -410.002949) (xy 125.809013 -410.057451)
			(xy 125.809012 -410.057457) (xy 127.246523 -410.057457) (xy 127.246523 -410.002943) (xy 127.254282 -409.948985)
			(xy 127.269641 -409.89668) (xy 127.292287 -409.847093) (xy 127.321761 -409.801235) (xy 127.357462 -409.760037)
			(xy 127.398662 -409.724341) (xy 127.444523 -409.694871) (xy 127.494112 -409.672229) (xy 127.546418 -409.656874)
			(xy 127.600377 -409.649121) (xy 127.627634 -409.64866) (xy 128.491234 -409.64866) (xy 128.518481 -409.649213)
			(xy 128.572421 -409.656972) (xy 128.624707 -409.672329) (xy 128.674276 -409.69497) (xy 128.720118 -409.724435)
			(xy 128.761301 -409.760123) (xy 128.796985 -409.801309) (xy 128.826446 -409.847154) (xy 128.849083 -409.896725)
			(xy 128.864435 -409.949012) (xy 128.87219 -410.002953) (xy 128.87219 -410.057447) (xy 128.872189 -410.057452)
			(xy 130.309846 -410.057452) (xy 130.309846 -410.002948) (xy 130.317602 -409.948998) (xy 130.332957 -409.896701)
			(xy 130.355599 -409.847121) (xy 130.385065 -409.801268) (xy 130.420757 -409.760075) (xy 130.461947 -409.72438)
			(xy 130.507798 -409.694911) (xy 130.557376 -409.672266) (xy 130.609672 -409.656908) (xy 130.663622 -409.649148)
			(xy 130.690874 -409.64866) (xy 131.554474 -409.64866) (xy 131.581726 -409.649185) (xy 131.635675 -409.656939)
			(xy 131.687972 -409.672291) (xy 131.737551 -409.69493) (xy 131.783403 -409.724395) (xy 131.824596 -409.760086)
			(xy 131.860289 -409.801276) (xy 131.889757 -409.847126) (xy 131.9124 -409.896704) (xy 131.927756 -409.949)
			(xy 131.935513 -410.002948) (xy 131.935513 -410.057452) (xy 131.935512 -410.057456) (xy 133.373023 -410.057456)
			(xy 133.373023 -410.002944) (xy 133.380781 -409.948987) (xy 133.396139 -409.896684) (xy 133.418784 -409.847099)
			(xy 133.448256 -409.801241) (xy 133.483954 -409.760045) (xy 133.525152 -409.724348) (xy 133.571011 -409.694878)
			(xy 133.620597 -409.672234) (xy 133.672901 -409.656878) (xy 133.726858 -409.649122) (xy 133.754114 -409.64866)
			(xy 134.617714 -409.64866) (xy 134.644962 -409.649211) (xy 134.698904 -409.656969) (xy 134.751193 -409.672324)
			(xy 134.800764 -409.694964) (xy 134.846609 -409.724428) (xy 134.887794 -409.760116) (xy 134.923481 -409.801303)
			(xy 134.952943 -409.847149) (xy 134.975581 -409.896721) (xy 134.990934 -409.94901) (xy 134.99869 -410.002952)
			(xy 134.99869 -410.057448) (xy 134.99869 -410.057451) (xy 136.436346 -410.057451) (xy 136.436346 -410.002949)
			(xy 136.444102 -409.949) (xy 136.459456 -409.896705) (xy 136.482095 -409.847127) (xy 136.51156 -409.801275)
			(xy 136.547249 -409.760082) (xy 136.588438 -409.724388) (xy 136.634286 -409.694918) (xy 136.683862 -409.672272)
			(xy 136.736155 -409.656911) (xy 136.790103 -409.649149) (xy 136.817354 -409.64866) (xy 137.680954 -409.64866)
			(xy 137.708207 -409.649184) (xy 137.762158 -409.656935) (xy 137.814457 -409.672286) (xy 137.864039 -409.694924)
			(xy 137.909894 -409.724388) (xy 137.951089 -409.760079) (xy 137.986784 -409.801269) (xy 138.016254 -409.847121)
			(xy 138.038898 -409.8967) (xy 138.054255 -409.948997) (xy 138.062013 -410.002947) (xy 138.062013 -410.057453)
			(xy 139.499546 -410.057453) (xy 139.499546 -410.002947) (xy 139.507303 -409.948995) (xy 139.522659 -409.896696)
			(xy 139.545302 -409.847115) (xy 139.57477 -409.801261) (xy 139.610464 -409.760068) (xy 139.651657 -409.724373)
			(xy 139.69751 -409.694904) (xy 139.747091 -409.672261) (xy 139.799389 -409.656904) (xy 139.853341 -409.649146)
			(xy 139.880594 -409.64866) (xy 140.744194 -409.64866) (xy 140.771445 -409.649187) (xy 140.825392 -409.656942)
			(xy 140.877686 -409.672297) (xy 140.927263 -409.694937) (xy 140.973113 -409.724402) (xy 141.014303 -409.760093)
			(xy 141.049994 -409.801282) (xy 141.07946 -409.847132) (xy 141.102101 -409.896708) (xy 141.117456 -409.949002)
			(xy 141.125213 -410.002949) (xy 141.125213 -410.057451) (xy 141.125212 -410.057457) (xy 142.562723 -410.057457)
			(xy 142.562723 -410.002943) (xy 142.570482 -409.948985) (xy 142.585841 -409.89668) (xy 142.608487 -409.847093)
			(xy 142.637961 -409.801235) (xy 142.673662 -409.760037) (xy 142.714862 -409.724341) (xy 142.760723 -409.694871)
			(xy 142.810312 -409.672229) (xy 142.862618 -409.656874) (xy 142.916577 -409.649121) (xy 142.943834 -409.64866)
			(xy 143.807434 -409.64866) (xy 143.834681 -409.649213) (xy 143.888621 -409.656972) (xy 143.940907 -409.672329)
			(xy 143.990476 -409.69497) (xy 144.036318 -409.724435) (xy 144.077501 -409.760123) (xy 144.113185 -409.801309)
			(xy 144.142646 -409.847154) (xy 144.165283 -409.896725) (xy 144.180635 -409.949012) (xy 144.18839 -410.002953)
			(xy 144.18839 -410.057447) (xy 144.188389 -410.057452) (xy 145.626046 -410.057452) (xy 145.626046 -410.002948)
			(xy 145.633802 -409.948998) (xy 145.649157 -409.896701) (xy 145.671799 -409.847121) (xy 145.701265 -409.801268)
			(xy 145.736957 -409.760075) (xy 145.778147 -409.72438) (xy 145.823998 -409.694911) (xy 145.873576 -409.672266)
			(xy 145.925872 -409.656908) (xy 145.979822 -409.649148) (xy 146.007074 -409.64866) (xy 146.870674 -409.64866)
			(xy 146.897926 -409.649185) (xy 146.951875 -409.656939) (xy 147.004172 -409.672291) (xy 147.053751 -409.69493)
			(xy 147.099603 -409.724395) (xy 147.140796 -409.760086) (xy 147.176489 -409.801276) (xy 147.205957 -409.847126)
			(xy 147.2286 -409.896704) (xy 147.243956 -409.949) (xy 147.251713 -410.002948) (xy 147.251713 -410.057452)
			(xy 147.251712 -410.057456) (xy 148.689223 -410.057456) (xy 148.689223 -410.002944) (xy 148.696981 -409.948987)
			(xy 148.712339 -409.896684) (xy 148.734984 -409.847099) (xy 148.764456 -409.801241) (xy 148.800154 -409.760045)
			(xy 148.841352 -409.724348) (xy 148.887211 -409.694878) (xy 148.936797 -409.672234) (xy 148.989101 -409.656878)
			(xy 149.043058 -409.649122) (xy 149.070314 -409.64866) (xy 149.933914 -409.64866) (xy 149.961162 -409.649211)
			(xy 150.015104 -409.656969) (xy 150.067393 -409.672324) (xy 150.116964 -409.694964) (xy 150.162809 -409.724428)
			(xy 150.203994 -409.760116) (xy 150.239681 -409.801303) (xy 150.269143 -409.847149) (xy 150.291781 -409.896721)
			(xy 150.307134 -409.94901) (xy 150.31489 -410.002952) (xy 150.31489 -410.057448) (xy 150.31489 -410.057451)
			(xy 151.752546 -410.057451) (xy 151.752546 -410.002949) (xy 151.760302 -409.949) (xy 151.775656 -409.896705)
			(xy 151.798295 -409.847127) (xy 151.82776 -409.801275) (xy 151.863449 -409.760082) (xy 151.904638 -409.724388)
			(xy 151.950486 -409.694918) (xy 152.000062 -409.672272) (xy 152.052355 -409.656911) (xy 152.106303 -409.649149)
			(xy 152.133554 -409.64866) (xy 152.997154 -409.64866) (xy 153.024407 -409.649184) (xy 153.078358 -409.656935)
			(xy 153.130657 -409.672286) (xy 153.180239 -409.694924) (xy 153.226094 -409.724388) (xy 153.267289 -409.760079)
			(xy 153.302984 -409.801269) (xy 153.332454 -409.847121) (xy 153.355098 -409.8967) (xy 153.370455 -409.948997)
			(xy 153.378213 -410.002947) (xy 153.378213 -410.057453) (xy 154.815746 -410.057453) (xy 154.815746 -410.002947)
			(xy 154.823503 -409.948995) (xy 154.838859 -409.896696) (xy 154.861502 -409.847115) (xy 154.89097 -409.801261)
			(xy 154.926664 -409.760068) (xy 154.967857 -409.724373) (xy 155.01371 -409.694904) (xy 155.063291 -409.672261)
			(xy 155.115589 -409.656904) (xy 155.169541 -409.649146) (xy 155.196794 -409.64866) (xy 156.060394 -409.64866)
			(xy 156.087645 -409.649187) (xy 156.141592 -409.656942) (xy 156.193886 -409.672297) (xy 156.243463 -409.694937)
			(xy 156.289313 -409.724402) (xy 156.330503 -409.760093) (xy 156.366194 -409.801282) (xy 156.39566 -409.847132)
			(xy 156.418301 -409.896708) (xy 156.433656 -409.949002) (xy 156.441413 -410.002949) (xy 156.441413 -410.057451)
			(xy 156.441412 -410.057457) (xy 157.878923 -410.057457) (xy 157.878923 -410.002943) (xy 157.886682 -409.948985)
			(xy 157.902041 -409.89668) (xy 157.924687 -409.847093) (xy 157.954161 -409.801235) (xy 157.989862 -409.760037)
			(xy 158.031062 -409.724341) (xy 158.076923 -409.694871) (xy 158.126512 -409.672229) (xy 158.178818 -409.656874)
			(xy 158.232777 -409.649121) (xy 158.260034 -409.64866) (xy 159.123634 -409.64866) (xy 159.150881 -409.649213)
			(xy 159.204821 -409.656972) (xy 159.257107 -409.672329) (xy 159.306676 -409.69497) (xy 159.352518 -409.724435)
			(xy 159.393701 -409.760123) (xy 159.429385 -409.801309) (xy 159.458846 -409.847154) (xy 159.481483 -409.896725)
			(xy 159.496835 -409.949012) (xy 159.50459 -410.002953) (xy 159.50459 -410.057447) (xy 159.504589 -410.057452)
			(xy 160.942246 -410.057452) (xy 160.942246 -410.002948) (xy 160.950002 -409.948998) (xy 160.965357 -409.896701)
			(xy 160.987999 -409.847121) (xy 161.017465 -409.801268) (xy 161.053157 -409.760075) (xy 161.094347 -409.72438)
			(xy 161.140198 -409.694911) (xy 161.189776 -409.672266) (xy 161.242072 -409.656908) (xy 161.296022 -409.649148)
			(xy 161.323274 -409.64866) (xy 162.186874 -409.64866) (xy 162.214126 -409.649185) (xy 162.268075 -409.656939)
			(xy 162.320372 -409.672291) (xy 162.369951 -409.69493) (xy 162.415803 -409.724395) (xy 162.456996 -409.760086)
			(xy 162.492689 -409.801276) (xy 162.522157 -409.847126) (xy 162.5448 -409.896704) (xy 162.560156 -409.949)
			(xy 162.567913 -410.002948) (xy 162.567913 -410.057452) (xy 162.567912 -410.057456) (xy 164.005423 -410.057456)
			(xy 164.005423 -410.002944) (xy 164.013181 -409.948987) (xy 164.028539 -409.896684) (xy 164.051184 -409.847099)
			(xy 164.080656 -409.801241) (xy 164.116354 -409.760045) (xy 164.157552 -409.724348) (xy 164.203411 -409.694878)
			(xy 164.252997 -409.672234) (xy 164.305301 -409.656878) (xy 164.359258 -409.649122) (xy 164.386514 -409.64866)
			(xy 165.250114 -409.64866) (xy 165.277362 -409.649211) (xy 165.331304 -409.656969) (xy 165.383593 -409.672324)
			(xy 165.433164 -409.694964) (xy 165.479009 -409.724428) (xy 165.520194 -409.760116) (xy 165.555881 -409.801303)
			(xy 165.585343 -409.847149) (xy 165.607981 -409.896721) (xy 165.623334 -409.94901) (xy 165.63109 -410.002952)
			(xy 165.63109 -410.057448) (xy 165.63109 -410.057451) (xy 167.068746 -410.057451) (xy 167.068746 -410.002949)
			(xy 167.076502 -409.949) (xy 167.091856 -409.896705) (xy 167.114495 -409.847127) (xy 167.14396 -409.801275)
			(xy 167.179649 -409.760082) (xy 167.220838 -409.724388) (xy 167.266686 -409.694918) (xy 167.316262 -409.672272)
			(xy 167.368555 -409.656911) (xy 167.422503 -409.649149) (xy 167.449754 -409.64866) (xy 168.313354 -409.64866)
			(xy 168.340607 -409.649184) (xy 168.394558 -409.656935) (xy 168.446857 -409.672286) (xy 168.496439 -409.694924)
			(xy 168.542294 -409.724388) (xy 168.583489 -409.760079) (xy 168.619184 -409.801269) (xy 168.648654 -409.847121)
			(xy 168.671298 -409.8967) (xy 168.686655 -409.948997) (xy 168.694413 -410.002947) (xy 168.694413 -410.057453)
			(xy 168.686655 -410.111403) (xy 168.671298 -410.1637) (xy 168.648654 -410.213279) (xy 168.619184 -410.259131)
			(xy 168.583489 -410.300321) (xy 168.542294 -410.336012) (xy 168.496439 -410.365476) (xy 168.446857 -410.388114)
			(xy 168.394558 -410.403465) (xy 168.340607 -410.411216) (xy 168.313354 -410.411676) (xy 167.449754 -410.411676)
			(xy 167.422503 -410.411251) (xy 167.368555 -410.403489) (xy 167.316262 -410.388128) (xy 167.266686 -410.365482)
			(xy 167.220838 -410.336012) (xy 167.179649 -410.300318) (xy 167.14396 -410.259125) (xy 167.114495 -410.213273)
			(xy 167.091856 -410.163695) (xy 167.076502 -410.1114) (xy 167.068746 -410.057451) (xy 165.63109 -410.057451)
			(xy 165.623334 -410.11139) (xy 165.607981 -410.163679) (xy 165.585343 -410.213251) (xy 165.555881 -410.259097)
			(xy 165.520194 -410.300284) (xy 165.479009 -410.335972) (xy 165.433164 -410.365436) (xy 165.383593 -410.388076)
			(xy 165.331304 -410.403431) (xy 165.277362 -410.411189) (xy 165.250114 -410.411676) (xy 164.386514 -410.411676)
			(xy 164.359258 -410.411278) (xy 164.305301 -410.403522) (xy 164.252997 -410.388166) (xy 164.203411 -410.365522)
			(xy 164.157552 -410.336052) (xy 164.116354 -410.300355) (xy 164.080656 -410.259159) (xy 164.051184 -410.213301)
			(xy 164.028539 -410.163716) (xy 164.013181 -410.111413) (xy 164.005423 -410.057456) (xy 162.567912 -410.057456)
			(xy 162.560156 -410.1114) (xy 162.5448 -410.163696) (xy 162.522157 -410.213274) (xy 162.492689 -410.259124)
			(xy 162.456996 -410.300314) (xy 162.415803 -410.336005) (xy 162.369951 -410.36547) (xy 162.320372 -410.388109)
			(xy 162.268075 -410.403461) (xy 162.214126 -410.411215) (xy 162.186874 -410.411676) (xy 161.323274 -410.411676)
			(xy 161.296022 -410.411252) (xy 161.242072 -410.403492) (xy 161.189776 -410.388134) (xy 161.140198 -410.365489)
			(xy 161.094347 -410.33602) (xy 161.053157 -410.300325) (xy 161.017465 -410.259132) (xy 160.987999 -410.213279)
			(xy 160.965357 -410.163699) (xy 160.950002 -410.111402) (xy 160.942246 -410.057452) (xy 159.504589 -410.057452)
			(xy 159.496835 -410.111388) (xy 159.481483 -410.163675) (xy 159.458846 -410.213246) (xy 159.429385 -410.259091)
			(xy 159.393701 -410.300277) (xy 159.352518 -410.335965) (xy 159.306676 -410.36543) (xy 159.257107 -410.388071)
			(xy 159.204821 -410.403428) (xy 159.150881 -410.411187) (xy 159.123634 -410.411676) (xy 158.260034 -410.411676)
			(xy 158.232777 -410.411279) (xy 158.178818 -410.403526) (xy 158.126512 -410.388171) (xy 158.076923 -410.365529)
			(xy 158.031062 -410.336059) (xy 157.989862 -410.300363) (xy 157.954161 -410.259165) (xy 157.924687 -410.213307)
			(xy 157.902041 -410.16372) (xy 157.886682 -410.111415) (xy 157.878923 -410.057457) (xy 156.441412 -410.057457)
			(xy 156.433656 -410.111398) (xy 156.418301 -410.163692) (xy 156.39566 -410.213268) (xy 156.366194 -410.259118)
			(xy 156.330503 -410.300307) (xy 156.289313 -410.335998) (xy 156.243463 -410.365463) (xy 156.193886 -410.388103)
			(xy 156.141592 -410.403458) (xy 156.087645 -410.411213) (xy 156.060394 -410.411676) (xy 155.196794 -410.411676)
			(xy 155.169541 -410.411254) (xy 155.115589 -410.403496) (xy 155.063291 -410.388139) (xy 155.01371 -410.365496)
			(xy 154.967857 -410.336027) (xy 154.926664 -410.300332) (xy 154.89097 -410.259139) (xy 154.861502 -410.213285)
			(xy 154.838859 -410.163704) (xy 154.823503 -410.111405) (xy 154.815746 -410.057453) (xy 153.378213 -410.057453)
			(xy 153.370455 -410.111403) (xy 153.355098 -410.1637) (xy 153.332454 -410.213279) (xy 153.302984 -410.259131)
			(xy 153.267289 -410.300321) (xy 153.226094 -410.336012) (xy 153.180239 -410.365476) (xy 153.130657 -410.388114)
			(xy 153.078358 -410.403465) (xy 153.024407 -410.411216) (xy 152.997154 -410.411676) (xy 152.133554 -410.411676)
			(xy 152.106303 -410.411251) (xy 152.052355 -410.403489) (xy 152.000062 -410.388128) (xy 151.950486 -410.365482)
			(xy 151.904638 -410.336012) (xy 151.863449 -410.300318) (xy 151.82776 -410.259125) (xy 151.798295 -410.213273)
			(xy 151.775656 -410.163695) (xy 151.760302 -410.1114) (xy 151.752546 -410.057451) (xy 150.31489 -410.057451)
			(xy 150.307134 -410.11139) (xy 150.291781 -410.163679) (xy 150.269143 -410.213251) (xy 150.239681 -410.259097)
			(xy 150.203994 -410.300284) (xy 150.162809 -410.335972) (xy 150.116964 -410.365436) (xy 150.067393 -410.388076)
			(xy 150.015104 -410.403431) (xy 149.961162 -410.411189) (xy 149.933914 -410.411676) (xy 149.070314 -410.411676)
			(xy 149.043058 -410.411278) (xy 148.989101 -410.403522) (xy 148.936797 -410.388166) (xy 148.887211 -410.365522)
			(xy 148.841352 -410.336052) (xy 148.800154 -410.300355) (xy 148.764456 -410.259159) (xy 148.734984 -410.213301)
			(xy 148.712339 -410.163716) (xy 148.696981 -410.111413) (xy 148.689223 -410.057456) (xy 147.251712 -410.057456)
			(xy 147.243956 -410.1114) (xy 147.2286 -410.163696) (xy 147.205957 -410.213274) (xy 147.176489 -410.259124)
			(xy 147.140796 -410.300314) (xy 147.099603 -410.336005) (xy 147.053751 -410.36547) (xy 147.004172 -410.388109)
			(xy 146.951875 -410.403461) (xy 146.897926 -410.411215) (xy 146.870674 -410.411676) (xy 146.007074 -410.411676)
			(xy 145.979822 -410.411252) (xy 145.925872 -410.403492) (xy 145.873576 -410.388134) (xy 145.823998 -410.365489)
			(xy 145.778147 -410.33602) (xy 145.736957 -410.300325) (xy 145.701265 -410.259132) (xy 145.671799 -410.213279)
			(xy 145.649157 -410.163699) (xy 145.633802 -410.111402) (xy 145.626046 -410.057452) (xy 144.188389 -410.057452)
			(xy 144.180635 -410.111388) (xy 144.165283 -410.163675) (xy 144.142646 -410.213246) (xy 144.113185 -410.259091)
			(xy 144.077501 -410.300277) (xy 144.036318 -410.335965) (xy 143.990476 -410.36543) (xy 143.940907 -410.388071)
			(xy 143.888621 -410.403428) (xy 143.834681 -410.411187) (xy 143.807434 -410.411676) (xy 142.943834 -410.411676)
			(xy 142.916577 -410.411279) (xy 142.862618 -410.403526) (xy 142.810312 -410.388171) (xy 142.760723 -410.365529)
			(xy 142.714862 -410.336059) (xy 142.673662 -410.300363) (xy 142.637961 -410.259165) (xy 142.608487 -410.213307)
			(xy 142.585841 -410.16372) (xy 142.570482 -410.111415) (xy 142.562723 -410.057457) (xy 141.125212 -410.057457)
			(xy 141.117456 -410.111398) (xy 141.102101 -410.163692) (xy 141.07946 -410.213268) (xy 141.049994 -410.259118)
			(xy 141.014303 -410.300307) (xy 140.973113 -410.335998) (xy 140.927263 -410.365463) (xy 140.877686 -410.388103)
			(xy 140.825392 -410.403458) (xy 140.771445 -410.411213) (xy 140.744194 -410.411676) (xy 139.880594 -410.411676)
			(xy 139.853341 -410.411254) (xy 139.799389 -410.403496) (xy 139.747091 -410.388139) (xy 139.69751 -410.365496)
			(xy 139.651657 -410.336027) (xy 139.610464 -410.300332) (xy 139.57477 -410.259139) (xy 139.545302 -410.213285)
			(xy 139.522659 -410.163704) (xy 139.507303 -410.111405) (xy 139.499546 -410.057453) (xy 138.062013 -410.057453)
			(xy 138.054255 -410.111403) (xy 138.038898 -410.1637) (xy 138.016254 -410.213279) (xy 137.986784 -410.259131)
			(xy 137.951089 -410.300321) (xy 137.909894 -410.336012) (xy 137.864039 -410.365476) (xy 137.814457 -410.388114)
			(xy 137.762158 -410.403465) (xy 137.708207 -410.411216) (xy 137.680954 -410.411676) (xy 136.817354 -410.411676)
			(xy 136.790103 -410.411251) (xy 136.736155 -410.403489) (xy 136.683862 -410.388128) (xy 136.634286 -410.365482)
			(xy 136.588438 -410.336012) (xy 136.547249 -410.300318) (xy 136.51156 -410.259125) (xy 136.482095 -410.213273)
			(xy 136.459456 -410.163695) (xy 136.444102 -410.1114) (xy 136.436346 -410.057451) (xy 134.99869 -410.057451)
			(xy 134.990934 -410.11139) (xy 134.975581 -410.163679) (xy 134.952943 -410.213251) (xy 134.923481 -410.259097)
			(xy 134.887794 -410.300284) (xy 134.846609 -410.335972) (xy 134.800764 -410.365436) (xy 134.751193 -410.388076)
			(xy 134.698904 -410.403431) (xy 134.644962 -410.411189) (xy 134.617714 -410.411676) (xy 133.754114 -410.411676)
			(xy 133.726858 -410.411278) (xy 133.672901 -410.403522) (xy 133.620597 -410.388166) (xy 133.571011 -410.365522)
			(xy 133.525152 -410.336052) (xy 133.483954 -410.300355) (xy 133.448256 -410.259159) (xy 133.418784 -410.213301)
			(xy 133.396139 -410.163716) (xy 133.380781 -410.111413) (xy 133.373023 -410.057456) (xy 131.935512 -410.057456)
			(xy 131.927756 -410.1114) (xy 131.9124 -410.163696) (xy 131.889757 -410.213274) (xy 131.860289 -410.259124)
			(xy 131.824596 -410.300314) (xy 131.783403 -410.336005) (xy 131.737551 -410.36547) (xy 131.687972 -410.388109)
			(xy 131.635675 -410.403461) (xy 131.581726 -410.411215) (xy 131.554474 -410.411676) (xy 130.690874 -410.411676)
			(xy 130.663622 -410.411252) (xy 130.609672 -410.403492) (xy 130.557376 -410.388134) (xy 130.507798 -410.365489)
			(xy 130.461947 -410.33602) (xy 130.420757 -410.300325) (xy 130.385065 -410.259132) (xy 130.355599 -410.213279)
			(xy 130.332957 -410.163699) (xy 130.317602 -410.111402) (xy 130.309846 -410.057452) (xy 128.872189 -410.057452)
			(xy 128.864435 -410.111388) (xy 128.849083 -410.163675) (xy 128.826446 -410.213246) (xy 128.796985 -410.259091)
			(xy 128.761301 -410.300277) (xy 128.720118 -410.335965) (xy 128.674276 -410.36543) (xy 128.624707 -410.388071)
			(xy 128.572421 -410.403428) (xy 128.518481 -410.411187) (xy 128.491234 -410.411676) (xy 127.627634 -410.411676)
			(xy 127.600377 -410.411279) (xy 127.546418 -410.403526) (xy 127.494112 -410.388171) (xy 127.444523 -410.365529)
			(xy 127.398662 -410.336059) (xy 127.357462 -410.300363) (xy 127.321761 -410.259165) (xy 127.292287 -410.213307)
			(xy 127.269641 -410.16372) (xy 127.254282 -410.111415) (xy 127.246523 -410.057457) (xy 125.809012 -410.057457)
			(xy 125.801256 -410.111398) (xy 125.785901 -410.163692) (xy 125.76326 -410.213268) (xy 125.733794 -410.259118)
			(xy 125.698103 -410.300307) (xy 125.656913 -410.335998) (xy 125.611063 -410.365463) (xy 125.561486 -410.388103)
			(xy 125.509192 -410.403458) (xy 125.455245 -410.411213) (xy 125.427994 -410.411676) (xy 124.564394 -410.411676)
			(xy 124.537141 -410.411254) (xy 124.483189 -410.403496) (xy 124.430891 -410.388139) (xy 124.38131 -410.365496)
			(xy 124.335457 -410.336027) (xy 124.294264 -410.300332) (xy 124.25857 -410.259139) (xy 124.229102 -410.213285)
			(xy 124.206459 -410.163704) (xy 124.191103 -410.111405) (xy 124.183346 -410.057453) (xy 122.745813 -410.057453)
			(xy 122.738055 -410.111403) (xy 122.722698 -410.1637) (xy 122.700054 -410.213279) (xy 122.670584 -410.259131)
			(xy 122.634889 -410.300321) (xy 122.593694 -410.336012) (xy 122.547839 -410.365476) (xy 122.498257 -410.388114)
			(xy 122.445958 -410.403465) (xy 122.392007 -410.411216) (xy 122.364754 -410.411676) (xy 121.501154 -410.411676)
			(xy 121.473903 -410.411251) (xy 121.419955 -410.403489) (xy 121.367662 -410.388128) (xy 121.318086 -410.365482)
			(xy 121.272238 -410.336012) (xy 121.231049 -410.300318) (xy 121.19536 -410.259125) (xy 121.165895 -410.213273)
			(xy 121.143256 -410.163695) (xy 121.127902 -410.1114) (xy 121.120146 -410.057451) (xy 96.519189 -410.057451)
			(xy 96.511435 -410.111387) (xy 96.496083 -410.163674) (xy 96.473447 -410.213245) (xy 96.443986 -410.259089)
			(xy 96.408302 -410.300275) (xy 96.36712 -410.335964) (xy 96.321278 -410.365428) (xy 96.27171 -410.38807)
			(xy 96.219424 -410.403427) (xy 96.165485 -410.411187) (xy 96.138238 -410.411676) (xy 95.274638 -410.411676)
			(xy 95.247381 -410.41128) (xy 95.193421 -410.403526) (xy 95.141115 -410.388172) (xy 95.091525 -410.36553)
			(xy 95.045664 -410.336061) (xy 95.004463 -410.300364) (xy 94.968762 -410.259167) (xy 94.939288 -410.213308)
			(xy 94.916641 -410.163721) (xy 94.901282 -410.111416) (xy 94.893523 -410.057457) (xy 93.456012 -410.057457)
			(xy 93.448256 -410.111397) (xy 93.432902 -410.163691) (xy 93.410261 -410.213267) (xy 93.380795 -410.259116)
			(xy 93.345104 -410.300306) (xy 93.303915 -410.335996) (xy 93.258065 -410.365462) (xy 93.208489 -410.388102)
			(xy 93.156195 -410.403457) (xy 93.102249 -410.411213) (xy 93.074998 -410.411676) (xy 92.211398 -410.411676)
			(xy 92.184145 -410.411254) (xy 92.130193 -410.403497) (xy 92.077894 -410.38814) (xy 92.028313 -410.365497)
			(xy 91.982459 -410.336028) (xy 91.941265 -410.300334) (xy 91.905571 -410.25914) (xy 91.876102 -410.213286)
			(xy 91.853459 -410.163705) (xy 91.838103 -410.111406) (xy 91.830346 -410.057453) (xy 90.392813 -410.057453)
			(xy 90.385055 -410.111403) (xy 90.369698 -410.163699) (xy 90.347055 -410.213278) (xy 90.317585 -410.259129)
			(xy 90.28189 -410.30032) (xy 90.240696 -410.33601) (xy 90.194841 -410.365475) (xy 90.14526 -410.388113)
			(xy 90.092961 -410.403464) (xy 90.039011 -410.411216) (xy 90.011758 -410.411676) (xy 89.148158 -410.411676)
			(xy 89.120906 -410.411251) (xy 89.066959 -410.403489) (xy 89.014665 -410.388129) (xy 88.965089 -410.365484)
			(xy 88.91924 -410.336014) (xy 88.878051 -410.300319) (xy 88.842361 -410.259127) (xy 88.812896 -410.213275)
			(xy 88.790256 -410.163696) (xy 88.774902 -410.1114) (xy 88.767146 -410.057452) (xy 87.329489 -410.057452)
			(xy 87.321734 -410.11139) (xy 87.306382 -410.163679) (xy 87.283744 -410.21325) (xy 87.254282 -410.259096)
			(xy 87.218595 -410.300282) (xy 87.17741 -410.335971) (xy 87.131566 -410.365435) (xy 87.081995 -410.388075)
			(xy 87.029707 -410.403431) (xy 86.975766 -410.411189) (xy 86.948518 -410.411676) (xy 86.084918 -410.411676)
			(xy 86.057662 -410.411278) (xy 86.003705 -410.403523) (xy 85.9514 -410.388167) (xy 85.901813 -410.365524)
			(xy 85.855954 -410.336054) (xy 85.814756 -410.300357) (xy 85.779057 -410.25916) (xy 85.749585 -410.213302)
			(xy 85.726939 -410.163717) (xy 85.711581 -410.111413) (xy 85.703823 -410.057456) (xy 84.266312 -410.057456)
			(xy 84.258556 -410.1114) (xy 84.2432 -410.163695) (xy 84.220558 -410.213273) (xy 84.19109 -410.259123)
			(xy 84.155397 -410.300313) (xy 84.114205 -410.336003) (xy 84.068353 -410.365468) (xy 84.018774 -410.388108)
			(xy 83.966478 -410.40346) (xy 83.91253 -410.411214) (xy 83.885278 -410.411676) (xy 83.021678 -410.411676)
			(xy 82.994425 -410.411253) (xy 82.940476 -410.403493) (xy 82.888179 -410.388135) (xy 82.838601 -410.36549)
			(xy 82.792749 -410.336021) (xy 82.751558 -410.300326) (xy 82.715866 -410.259133) (xy 82.686399 -410.21328)
			(xy 82.663758 -410.1637) (xy 82.648402 -410.111403) (xy 82.640646 -410.057453) (xy 81.202989 -410.057453)
			(xy 81.195235 -410.111387) (xy 81.179883 -410.163674) (xy 81.157247 -410.213245) (xy 81.127786 -410.259089)
			(xy 81.092102 -410.300275) (xy 81.05092 -410.335964) (xy 81.005078 -410.365428) (xy 80.95551 -410.38807)
			(xy 80.903224 -410.403427) (xy 80.849285 -410.411187) (xy 80.822038 -410.411676) (xy 79.958438 -410.411676)
			(xy 79.931181 -410.41128) (xy 79.877221 -410.403526) (xy 79.824915 -410.388172) (xy 79.775325 -410.36553)
			(xy 79.729464 -410.336061) (xy 79.688263 -410.300364) (xy 79.652562 -410.259167) (xy 79.623088 -410.213308)
			(xy 79.600441 -410.163721) (xy 79.585082 -410.111416) (xy 79.577323 -410.057457) (xy 78.139812 -410.057457)
			(xy 78.132056 -410.111397) (xy 78.116702 -410.163691) (xy 78.094061 -410.213267) (xy 78.064595 -410.259116)
			(xy 78.028904 -410.300306) (xy 77.987715 -410.335996) (xy 77.941865 -410.365462) (xy 77.892289 -410.388102)
			(xy 77.839995 -410.403457) (xy 77.786049 -410.411213) (xy 77.758798 -410.411676) (xy 76.895198 -410.411676)
			(xy 76.867945 -410.411254) (xy 76.813993 -410.403497) (xy 76.761694 -410.38814) (xy 76.712113 -410.365497)
			(xy 76.666259 -410.336028) (xy 76.625065 -410.300334) (xy 76.589371 -410.25914) (xy 76.559902 -410.213286)
			(xy 76.537259 -410.163705) (xy 76.521903 -410.111406) (xy 76.514146 -410.057453) (xy 75.076613 -410.057453)
			(xy 75.068855 -410.111403) (xy 75.053498 -410.163699) (xy 75.030855 -410.213278) (xy 75.001385 -410.259129)
			(xy 74.96569 -410.30032) (xy 74.924496 -410.33601) (xy 74.878641 -410.365475) (xy 74.82906 -410.388113)
			(xy 74.776761 -410.403464) (xy 74.722811 -410.411216) (xy 74.695558 -410.411676) (xy 73.831958 -410.411676)
			(xy 73.804706 -410.411251) (xy 73.750759 -410.403489) (xy 73.698465 -410.388129) (xy 73.648889 -410.365484)
			(xy 73.60304 -410.336014) (xy 73.561851 -410.300319) (xy 73.526161 -410.259127) (xy 73.496696 -410.213275)
			(xy 73.474056 -410.163696) (xy 73.458702 -410.1114) (xy 73.450946 -410.057452) (xy 72.013289 -410.057452)
			(xy 72.005534 -410.11139) (xy 71.990182 -410.163679) (xy 71.967544 -410.21325) (xy 71.938082 -410.259096)
			(xy 71.902395 -410.300282) (xy 71.86121 -410.335971) (xy 71.815366 -410.365435) (xy 71.765795 -410.388075)
			(xy 71.713507 -410.403431) (xy 71.659566 -410.411189) (xy 71.632318 -410.411676) (xy 70.768718 -410.411676)
			(xy 70.741462 -410.411278) (xy 70.687505 -410.403523) (xy 70.6352 -410.388167) (xy 70.585613 -410.365524)
			(xy 70.539754 -410.336054) (xy 70.498556 -410.300357) (xy 70.462857 -410.25916) (xy 70.433385 -410.213302)
			(xy 70.410739 -410.163717) (xy 70.395381 -410.111413) (xy 70.387623 -410.057456) (xy 68.950112 -410.057456)
			(xy 68.942356 -410.1114) (xy 68.927 -410.163695) (xy 68.904358 -410.213273) (xy 68.87489 -410.259123)
			(xy 68.839197 -410.300313) (xy 68.798005 -410.336003) (xy 68.752153 -410.365468) (xy 68.702574 -410.388108)
			(xy 68.650278 -410.40346) (xy 68.59633 -410.411214) (xy 68.569078 -410.411676) (xy 67.705478 -410.411676)
			(xy 67.678225 -410.411253) (xy 67.624276 -410.403493) (xy 67.571979 -410.388135) (xy 67.522401 -410.36549)
			(xy 67.476549 -410.336021) (xy 67.435358 -410.300326) (xy 67.399666 -410.259133) (xy 67.370199 -410.21328)
			(xy 67.347558 -410.1637) (xy 67.332202 -410.111403) (xy 67.324446 -410.057453) (xy 65.886789 -410.057453)
			(xy 65.879035 -410.111387) (xy 65.863683 -410.163674) (xy 65.841047 -410.213245) (xy 65.811586 -410.259089)
			(xy 65.775902 -410.300275) (xy 65.73472 -410.335964) (xy 65.688878 -410.365428) (xy 65.63931 -410.38807)
			(xy 65.587024 -410.403427) (xy 65.533085 -410.411187) (xy 65.505838 -410.411676) (xy 64.642238 -410.411676)
			(xy 64.614981 -410.41128) (xy 64.561021 -410.403526) (xy 64.508715 -410.388172) (xy 64.459125 -410.36553)
			(xy 64.413264 -410.336061) (xy 64.372063 -410.300364) (xy 64.336362 -410.259167) (xy 64.306888 -410.213308)
			(xy 64.284241 -410.163721) (xy 64.268882 -410.111416) (xy 64.261123 -410.057457) (xy 62.823612 -410.057457)
			(xy 62.815856 -410.111397) (xy 62.800502 -410.163691) (xy 62.777861 -410.213267) (xy 62.748395 -410.259116)
			(xy 62.712704 -410.300306) (xy 62.671515 -410.335996) (xy 62.625665 -410.365462) (xy 62.576089 -410.388102)
			(xy 62.523795 -410.403457) (xy 62.469849 -410.411213) (xy 62.442598 -410.411676) (xy 61.578998 -410.411676)
			(xy 61.551745 -410.411254) (xy 61.497793 -410.403497) (xy 61.445494 -410.38814) (xy 61.395913 -410.365497)
			(xy 61.350059 -410.336028) (xy 61.308865 -410.300334) (xy 61.273171 -410.25914) (xy 61.243702 -410.213286)
			(xy 61.221059 -410.163705) (xy 61.205703 -410.111406) (xy 61.197946 -410.057453) (xy 59.760413 -410.057453)
			(xy 59.752655 -410.111403) (xy 59.737298 -410.163699) (xy 59.714655 -410.213278) (xy 59.685185 -410.259129)
			(xy 59.64949 -410.30032) (xy 59.608296 -410.33601) (xy 59.562441 -410.365475) (xy 59.51286 -410.388113)
			(xy 59.460561 -410.403464) (xy 59.406611 -410.411216) (xy 59.379358 -410.411676) (xy 58.515758 -410.411676)
			(xy 58.488506 -410.411251) (xy 58.434559 -410.403489) (xy 58.382265 -410.388129) (xy 58.332689 -410.365484)
			(xy 58.28684 -410.336014) (xy 58.245651 -410.300319) (xy 58.209961 -410.259127) (xy 58.180496 -410.213275)
			(xy 58.157856 -410.163696) (xy 58.142502 -410.1114) (xy 58.134746 -410.057452) (xy 56.697089 -410.057452)
			(xy 56.689334 -410.11139) (xy 56.673982 -410.163679) (xy 56.651344 -410.21325) (xy 56.621882 -410.259096)
			(xy 56.586195 -410.300282) (xy 56.54501 -410.335971) (xy 56.499166 -410.365435) (xy 56.449595 -410.388075)
			(xy 56.397307 -410.403431) (xy 56.343366 -410.411189) (xy 56.316118 -410.411676) (xy 55.452518 -410.411676)
			(xy 55.425262 -410.411278) (xy 55.371305 -410.403523) (xy 55.319 -410.388167) (xy 55.269413 -410.365524)
			(xy 55.223554 -410.336054) (xy 55.182356 -410.300357) (xy 55.146657 -410.25916) (xy 55.117185 -410.213302)
			(xy 55.094539 -410.163717) (xy 55.079181 -410.111413) (xy 55.071423 -410.057456) (xy 53.633912 -410.057456)
			(xy 53.626156 -410.1114) (xy 53.6108 -410.163695) (xy 53.588158 -410.213273) (xy 53.55869 -410.259123)
			(xy 53.522997 -410.300313) (xy 53.481805 -410.336003) (xy 53.435953 -410.365468) (xy 53.386374 -410.388108)
			(xy 53.334078 -410.40346) (xy 53.28013 -410.411214) (xy 53.252878 -410.411676) (xy 52.389278 -410.411676)
			(xy 52.362025 -410.411253) (xy 52.308076 -410.403493) (xy 52.255779 -410.388135) (xy 52.206201 -410.36549)
			(xy 52.160349 -410.336021) (xy 52.119158 -410.300326) (xy 52.083466 -410.259133) (xy 52.053999 -410.21328)
			(xy 52.031358 -410.1637) (xy 52.016002 -410.111403) (xy 52.008246 -410.057453) (xy 50.570589 -410.057453)
			(xy 50.562835 -410.111387) (xy 50.547483 -410.163674) (xy 50.524847 -410.213245) (xy 50.495386 -410.259089)
			(xy 50.459702 -410.300275) (xy 50.41852 -410.335964) (xy 50.372678 -410.365428) (xy 50.32311 -410.38807)
			(xy 50.270824 -410.403427) (xy 50.216885 -410.411187) (xy 50.189638 -410.411676) (xy 49.326038 -410.411676)
			(xy 49.298781 -410.41128) (xy 49.244821 -410.403526) (xy 49.192515 -410.388172) (xy 49.142925 -410.36553)
			(xy 49.097064 -410.336061) (xy 49.055863 -410.300364) (xy 49.020162 -410.259167) (xy 48.990688 -410.213308)
			(xy 48.968041 -410.163721) (xy 48.952682 -410.111416) (xy 48.944923 -410.057457) (xy 7.00913 -410.057457)
			(xy 7.00913 -411.241049) (xy 101.876886 -411.241049) (xy 101.876886 -411.186551) (xy 101.884641 -411.132608)
			(xy 101.899994 -411.080318) (xy 101.922631 -411.030744) (xy 101.952093 -410.984897) (xy 101.98778 -410.943708)
			(xy 102.028964 -410.908017) (xy 102.074809 -410.878551) (xy 102.12438 -410.855908) (xy 102.176669 -410.840549)
			(xy 102.230611 -410.832788) (xy 102.25786 -410.8323) (xy 103.12146 -410.8323) (xy 103.148715 -410.832745)
			(xy 103.202672 -410.840497) (xy 103.254975 -410.85585) (xy 103.304562 -410.878491) (xy 103.350421 -410.907958)
			(xy 103.391619 -410.943653) (xy 103.427318 -410.984847) (xy 103.45679 -411.030703) (xy 103.479436 -411.080287)
			(xy 103.494794 -411.132589) (xy 103.502553 -411.186545) (xy 103.502553 -411.241055) (xy 103.494794 -411.295011)
			(xy 103.479436 -411.347313) (xy 103.45679 -411.396897) (xy 103.427318 -411.442753) (xy 103.391619 -411.483947)
			(xy 103.350421 -411.519642) (xy 103.304562 -411.549109) (xy 103.254975 -411.57175) (xy 103.202672 -411.587103)
			(xy 103.148715 -411.594855) (xy 103.12146 -411.595316) (xy 102.25786 -411.595316) (xy 102.230611 -411.594812)
			(xy 102.176669 -411.587051) (xy 102.12438 -411.571692) (xy 102.074809 -411.549049) (xy 102.028964 -411.519583)
			(xy 101.98778 -411.483892) (xy 101.952093 -411.442703) (xy 101.922631 -411.396856) (xy 101.899994 -411.347282)
			(xy 101.884641 -411.294992) (xy 101.876886 -411.241049) (xy 7.00913 -411.241049) (xy 7.00913 -424.470068)
			(xy 39.528496 -424.470068) (xy 39.528496 -417.770056) (xy 39.529001 -417.664532) (xy 39.537085 -417.453638)
			(xy 39.553241 -417.243209) (xy 39.577444 -417.033552) (xy 39.609661 -416.824977) (xy 39.649843 -416.617789)
			(xy 39.697931 -416.412292) (xy 39.753855 -416.208788) (xy 39.817532 -416.007575) (xy 39.88887 -415.808948)
			(xy 39.967764 -415.6132) (xy 40.054097 -415.420618) (xy 40.147744 -415.231483) (xy 40.248566 -415.046074)
			(xy 40.356416 -414.864663) (xy 40.471135 -414.687516) (xy 40.592555 -414.514894) (xy 40.720498 -414.347048)
			(xy 40.854776 -414.184226) (xy 40.995192 -414.026667) (xy 41.14154 -413.874602) (xy 41.293605 -413.728254)
			(xy 41.451164 -413.587838) (xy 41.613986 -413.45356) (xy 41.781832 -413.325617) (xy 41.954454 -413.204197)
			(xy 42.131601 -413.089478) (xy 42.313012 -412.981628) (xy 42.498421 -412.880806) (xy 42.687556 -412.787159)
			(xy 42.880138 -412.700826) (xy 43.075886 -412.621932) (xy 43.274513 -412.550594) (xy 43.475726 -412.486917)
			(xy 43.67923 -412.430993) (xy 43.884727 -412.382905) (xy 44.091915 -412.342723) (xy 44.30049 -412.310506)
			(xy 44.510147 -412.286303) (xy 44.720576 -412.270147) (xy 44.93147 -412.262063) (xy 45.142518 -412.262063)
			(xy 45.353412 -412.270147) (xy 45.563841 -412.286303) (xy 45.773498 -412.310506) (xy 45.982073 -412.342723)
			(xy 46.189261 -412.382905) (xy 46.394758 -412.430993) (xy 46.598262 -412.486917) (xy 46.799475 -412.550594)
			(xy 46.998102 -412.621932) (xy 47.19385 -412.700826) (xy 47.386432 -412.787159) (xy 47.575567 -412.880806)
			(xy 47.760976 -412.981628) (xy 47.942387 -413.089478) (xy 48.119534 -413.204197) (xy 48.292156 -413.325617)
			(xy 48.460002 -413.45356) (xy 48.622824 -413.587838) (xy 48.649451 -413.611568) (xy 104.877616 -413.611568)
			(xy 104.877616 -412.747968) (xy 104.878102 -412.720717) (xy 104.885858 -412.666769) (xy 104.901213 -412.614474)
			(xy 104.923855 -412.564897) (xy 104.953321 -412.519047) (xy 104.989012 -412.477856) (xy 105.030203 -412.442165)
			(xy 105.076053 -412.412699) (xy 105.12563 -412.390057) (xy 105.177925 -412.374702) (xy 105.231873 -412.366946)
			(xy 105.286375 -412.366946) (xy 105.340323 -412.374702) (xy 105.392618 -412.390057) (xy 105.442195 -412.412699)
			(xy 105.488045 -412.442165) (xy 105.529236 -412.477856) (xy 105.564927 -412.519047) (xy 105.594393 -412.564897)
			(xy 105.617035 -412.614474) (xy 105.63239 -412.666769) (xy 105.640146 -412.720717) (xy 105.640632 -412.747968)
			(xy 105.640632 -413.611568) (xy 105.640146 -413.638819) (xy 105.63239 -413.692767) (xy 105.617035 -413.745062)
			(xy 105.594393 -413.794639) (xy 105.584722 -413.809688) (xy 116.689632 -413.809688) (xy 116.689632 -412.946088)
			(xy 116.690118 -412.918837) (xy 116.697874 -412.864889) (xy 116.713229 -412.812594) (xy 116.735871 -412.763017)
			(xy 116.765337 -412.717167) (xy 116.801028 -412.675976) (xy 116.842219 -412.640285) (xy 116.888069 -412.610819)
			(xy 116.937646 -412.588177) (xy 116.989941 -412.572822) (xy 117.043889 -412.565066) (xy 117.098391 -412.565066)
			(xy 117.152339 -412.572822) (xy 117.204634 -412.588177) (xy 117.254211 -412.610819) (xy 117.300061 -412.640285)
			(xy 117.341252 -412.675976) (xy 117.376943 -412.717167) (xy 117.406409 -412.763017) (xy 117.429051 -412.812594)
			(xy 117.444406 -412.864889) (xy 117.452162 -412.918837) (xy 117.452648 -412.946088) (xy 117.452648 -413.809688)
			(xy 117.452162 -413.836939) (xy 117.444406 -413.890887) (xy 117.429051 -413.943182) (xy 117.406409 -413.992759)
			(xy 117.376943 -414.038609) (xy 117.341252 -414.0798) (xy 117.300061 -414.115491) (xy 117.254211 -414.144957)
			(xy 117.204634 -414.167599) (xy 117.152339 -414.182954) (xy 117.098391 -414.19071) (xy 117.043889 -414.19071)
			(xy 116.989941 -414.182954) (xy 116.937646 -414.167599) (xy 116.888069 -414.144957) (xy 116.842219 -414.115491)
			(xy 116.801028 -414.0798) (xy 116.765337 -414.038609) (xy 116.735871 -413.992759) (xy 116.713229 -413.943182)
			(xy 116.697874 -413.890887) (xy 116.690118 -413.836939) (xy 116.689632 -413.809688) (xy 105.584722 -413.809688)
			(xy 105.564927 -413.840489) (xy 105.529236 -413.88168) (xy 105.488045 -413.917371) (xy 105.442195 -413.946837)
			(xy 105.392618 -413.969479) (xy 105.340323 -413.984834) (xy 105.286375 -413.99259) (xy 105.231873 -413.99259)
			(xy 105.177925 -413.984834) (xy 105.12563 -413.969479) (xy 105.076053 -413.946837) (xy 105.030203 -413.917371)
			(xy 104.989012 -413.88168) (xy 104.953321 -413.840489) (xy 104.923855 -413.794639) (xy 104.901213 -413.745062)
			(xy 104.885858 -413.692767) (xy 104.878102 -413.638819) (xy 104.877616 -413.611568) (xy 48.649451 -413.611568)
			(xy 48.780383 -413.728254) (xy 48.932448 -413.874602) (xy 49.078796 -414.026667) (xy 49.219212 -414.184226)
			(xy 49.35349 -414.347048) (xy 49.481433 -414.514894) (xy 49.602853 -414.687516) (xy 49.717572 -414.864663)
			(xy 49.825422 -415.046074) (xy 49.926244 -415.231483) (xy 50.019891 -415.420618) (xy 50.106224 -415.6132)
			(xy 50.133819 -415.681668) (xy 100.559616 -415.681668) (xy 100.559616 -414.818068) (xy 100.560102 -414.790817)
			(xy 100.567858 -414.736869) (xy 100.583213 -414.684574) (xy 100.605855 -414.634997) (xy 100.635321 -414.589147)
			(xy 100.671012 -414.547956) (xy 100.712203 -414.512265) (xy 100.758053 -414.482799) (xy 100.80763 -414.460157)
			(xy 100.859925 -414.444802) (xy 100.913873 -414.437046) (xy 100.968375 -414.437046) (xy 101.022323 -414.444802)
			(xy 101.074618 -414.460157) (xy 101.124195 -414.482799) (xy 101.170045 -414.512265) (xy 101.211236 -414.547956)
			(xy 101.246927 -414.589147) (xy 101.276393 -414.634997) (xy 101.299035 -414.684574) (xy 101.31439 -414.736869)
			(xy 101.322146 -414.790817) (xy 101.322632 -414.818068) (xy 101.322632 -415.681668) (xy 101.322146 -415.708919)
			(xy 101.31439 -415.762867) (xy 101.299035 -415.815162) (xy 101.276393 -415.864739) (xy 101.246927 -415.910589)
			(xy 101.211236 -415.95178) (xy 101.170045 -415.987471) (xy 101.124195 -416.016937) (xy 101.074618 -416.039579)
			(xy 101.022323 -416.054934) (xy 100.968375 -416.06269) (xy 100.913873 -416.06269) (xy 100.859925 -416.054934)
			(xy 100.80763 -416.039579) (xy 100.758053 -416.016937) (xy 100.712203 -415.987471) (xy 100.671012 -415.95178)
			(xy 100.635321 -415.910589) (xy 100.605855 -415.864739) (xy 100.583213 -415.815162) (xy 100.567858 -415.762867)
			(xy 100.560102 -415.708919) (xy 100.559616 -415.681668) (xy 50.133819 -415.681668) (xy 50.185118 -415.808948)
			(xy 50.256456 -416.007575) (xy 50.320133 -416.208788) (xy 50.376057 -416.412292) (xy 50.424145 -416.617789)
			(xy 50.464327 -416.824977) (xy 50.496544 -417.033552) (xy 50.520747 -417.243209) (xy 50.536903 -417.453638)
			(xy 50.544987 -417.664532) (xy 50.545492 -417.770056) (xy 50.545492 -420.089838) (xy 58.13806 -420.089838)
			(xy 58.138171 -420.074752) (xy 58.139951 -420.044634) (xy 58.141616 -420.02964) (xy 58.141616 -418.95014)
			(xy 58.139949 -418.935146) (xy 58.138169 -418.905028) (xy 58.13806 -418.889942) (xy 58.138171 -418.874856)
			(xy 58.139951 -418.844738) (xy 58.141616 -418.829744) (xy 58.141616 -418.218874) (xy 58.142085 -418.206785)
			(xy 58.149546 -418.183788) (xy 58.163733 -418.164211) (xy 58.183264 -418.14996) (xy 58.206237 -418.142424)
			(xy 58.218324 -418.141912) (xy 59.158124 -418.141912) (xy 59.170235 -418.142296) (xy 59.193265 -418.149803)
			(xy 59.212839 -418.164073) (xy 59.227033 -418.183702) (xy 59.234451 -418.206761) (xy 59.234832 -418.218874)
			(xy 59.234832 -420.760398) (xy 59.23439 -420.77249) (xy 59.226931 -420.795495) (xy 59.212739 -420.815078)
			(xy 59.193198 -420.829327) (xy 59.170215 -420.836854) (xy 59.158124 -420.83736) (xy 58.218324 -420.83736)
			(xy 58.206212 -420.836963) (xy 58.183179 -420.829465) (xy 58.163602 -420.8152) (xy 58.149408 -420.795571)
			(xy 58.141994 -420.772511) (xy 58.141616 -420.760398) (xy 58.141616 -420.150036) (xy 58.139948 -420.135042)
			(xy 58.138169 -420.104924) (xy 58.13806 -420.089838) (xy 50.545492 -420.089838) (xy 50.545492 -421.089836)
			(xy 60.138056 -421.089836) (xy 60.138167 -421.07475) (xy 60.139947 -421.044632) (xy 60.141612 -421.029638)
			(xy 60.141612 -419.950138) (xy 60.139945 -419.935144) (xy 60.138165 -419.905026) (xy 60.138056 -419.88994)
			(xy 60.138167 -419.874854) (xy 60.139947 -419.844736) (xy 60.141612 -419.829742) (xy 60.141612 -419.218872)
			(xy 60.14204 -419.206794) (xy 60.149513 -419.183822) (xy 60.163718 -419.164284) (xy 60.183265 -419.150091)
			(xy 60.206242 -419.142633) (xy 60.21832 -419.142164) (xy 61.15812 -419.142164) (xy 61.170193 -419.142647)
			(xy 61.193156 -419.150112) (xy 61.21269 -419.164304) (xy 61.226885 -419.183837) (xy 61.234352 -419.206799)
			(xy 61.234828 -419.218872) (xy 61.234828 -421.089836) (xy 68.13804 -421.089836) (xy 68.138151 -421.07475)
			(xy 68.139931 -421.044632) (xy 68.141596 -421.029638) (xy 68.141596 -419.950138) (xy 68.139929 -419.935144)
			(xy 68.138149 -419.905026) (xy 68.13804 -419.88994) (xy 68.138151 -419.874854) (xy 68.139931 -419.844736)
			(xy 68.141596 -419.829742) (xy 68.141596 -419.218872) (xy 68.14204 -419.206796) (xy 68.149511 -419.183827)
			(xy 68.163712 -419.16429) (xy 68.183255 -419.150096) (xy 68.206227 -419.142635) (xy 68.218304 -419.142164)
			(xy 69.158104 -419.142164) (xy 69.170176 -419.14266) (xy 69.193139 -419.150121) (xy 69.212673 -419.16431)
			(xy 69.226868 -419.18384) (xy 69.234336 -419.2068) (xy 69.234812 -419.218872) (xy 69.234812 -420.089838)
			(xy 70.138036 -420.089838) (xy 70.138149 -420.074753) (xy 70.139929 -420.044634) (xy 70.141592 -420.02964)
			(xy 70.141592 -418.95014) (xy 70.139925 -418.935146) (xy 70.138145 -418.905028) (xy 70.138036 -418.889942)
			(xy 70.13815 -418.874857) (xy 70.139929 -418.844738) (xy 70.141592 -418.829744) (xy 70.141592 -418.218874)
			(xy 70.142084 -418.206788) (xy 70.149542 -418.183794) (xy 70.163724 -418.164219) (xy 70.183249 -418.149968)
			(xy 70.206216 -418.142428) (xy 70.2183 -418.141912) (xy 71.1581 -418.141912) (xy 71.17021 -418.142316)
			(xy 71.193239 -418.149817) (xy 71.212814 -418.164081) (xy 71.227008 -418.183706) (xy 71.234426 -418.206762)
			(xy 71.234808 -418.218874) (xy 71.234808 -420.760398) (xy 71.234292 -420.772483) (xy 71.226841 -420.795475)
			(xy 71.212666 -420.815051) (xy 71.193146 -420.829303) (xy 71.170183 -420.836844) (xy 71.1581 -420.83736)
			(xy 70.2183 -420.83736) (xy 70.206187 -420.836983) (xy 70.183153 -420.829479) (xy 70.163576 -420.815209)
			(xy 70.149383 -420.795576) (xy 70.14197 -420.772512) (xy 70.141592 -420.760398) (xy 70.141592 -420.150036)
			(xy 70.139924 -420.135042) (xy 70.138145 -420.104924) (xy 70.138036 -420.089838) (xy 69.234812 -420.089838)
			(xy 69.234812 -421.089836) (xy 72.138032 -421.089836) (xy 72.138145 -421.074751) (xy 72.139925 -421.044632)
			(xy 72.141588 -421.029638) (xy 72.141588 -419.950138) (xy 72.13992 -419.935144) (xy 72.138141 -419.905026)
			(xy 72.138032 -419.88994) (xy 72.138145 -419.874855) (xy 72.139925 -419.844736) (xy 72.141588 -419.829742)
			(xy 72.141588 -419.218872) (xy 72.14204 -419.206796) (xy 72.14951 -419.183829) (xy 72.16371 -419.164293)
			(xy 72.18325 -419.150099) (xy 72.20622 -419.142636) (xy 72.218296 -419.142164) (xy 73.158096 -419.142164)
			(xy 73.170168 -419.142667) (xy 73.19313 -419.150125) (xy 73.212665 -419.164313) (xy 73.22686 -419.183841)
			(xy 73.234328 -419.206801) (xy 73.234804 -419.218872) (xy 73.234804 -419.702852) (xy 110.957342 -419.702852)
			(xy 110.957342 -419.648348) (xy 110.965098 -419.594399) (xy 110.980453 -419.542102) (xy 111.003093 -419.492523)
			(xy 111.032558 -419.44667) (xy 111.068249 -419.405477) (xy 111.109438 -419.369782) (xy 111.155288 -419.340312)
			(xy 111.204865 -419.317667) (xy 111.25716 -419.302306) (xy 111.311108 -419.294545) (xy 111.33836 -419.294056)
			(xy 112.20196 -419.294056) (xy 112.229212 -419.294589) (xy 112.283162 -419.30234) (xy 112.33546 -419.317691)
			(xy 112.385041 -419.340329) (xy 112.430894 -419.369793) (xy 112.472088 -419.405484) (xy 112.507783 -419.446674)
			(xy 112.537251 -419.492524) (xy 112.559895 -419.542102) (xy 112.575251 -419.594399) (xy 112.583009 -419.648348)
			(xy 112.583009 -419.702852) (xy 112.575251 -419.756801) (xy 112.559895 -419.809098) (xy 112.537251 -419.858676)
			(xy 112.507783 -419.904526) (xy 112.472088 -419.945716) (xy 112.430894 -419.981407) (xy 112.385041 -420.010871)
			(xy 112.33546 -420.033509) (xy 112.283162 -420.04886) (xy 112.229212 -420.056611) (xy 112.20196 -420.057072)
			(xy 111.33836 -420.057072) (xy 111.311108 -420.056655) (xy 111.25716 -420.048894) (xy 111.204865 -420.033533)
			(xy 111.155288 -420.010888) (xy 111.109438 -419.981418) (xy 111.068249 -419.945723) (xy 111.032558 -419.90453)
			(xy 111.003093 -419.858677) (xy 110.980453 -419.809098) (xy 110.965098 -419.756801) (xy 110.957342 -419.702852)
			(xy 73.234804 -419.702852) (xy 73.234804 -421.760396) (xy 73.234384 -421.772479) (xy 73.226917 -421.795462)
			(xy 73.212713 -421.815013) (xy 73.193162 -421.829217) (xy 73.170179 -421.836684) (xy 73.158096 -421.837104)
			(xy 72.218296 -421.837104) (xy 72.206221 -421.836639) (xy 72.183253 -421.829175) (xy 72.163716 -421.814979)
			(xy 72.149521 -421.79544) (xy 72.14206 -421.772471) (xy 72.141588 -421.760396) (xy 72.141588 -421.150034)
			(xy 72.13992 -421.13504) (xy 72.138141 -421.104922) (xy 72.138032 -421.089836) (xy 69.234812 -421.089836)
			(xy 69.234812 -421.760396) (xy 69.234332 -421.77247) (xy 69.226871 -421.795436) (xy 69.212679 -421.814973)
			(xy 69.193143 -421.829168) (xy 69.170178 -421.836631) (xy 69.158104 -421.837104) (xy 68.218304 -421.837104)
			(xy 68.206221 -421.836684) (xy 68.183238 -421.829217) (xy 68.163687 -421.815013) (xy 68.149483 -421.795462)
			(xy 68.142016 -421.772479) (xy 68.141596 -421.760396) (xy 68.141596 -421.150034) (xy 68.139928 -421.13504)
			(xy 68.138149 -421.104922) (xy 68.13804 -421.089836) (xy 61.234828 -421.089836) (xy 61.234828 -421.760396)
			(xy 61.234333 -421.772468) (xy 61.226874 -421.795432) (xy 61.212684 -421.814967) (xy 61.193154 -421.829163)
			(xy 61.170192 -421.836629) (xy 61.15812 -421.837104) (xy 60.21832 -421.837104) (xy 60.206238 -421.83667)
			(xy 60.183255 -421.829208) (xy 60.163704 -421.815007) (xy 60.1495 -421.795459) (xy 60.142032 -421.772478)
			(xy 60.141612 -421.760396) (xy 60.141612 -421.150034) (xy 60.139944 -421.13504) (xy 60.138165 -421.104922)
			(xy 60.138056 -421.089836) (xy 50.545492 -421.089836) (xy 50.545492 -423.68978) (xy 58.13806 -423.68978)
			(xy 58.138175 -423.674695) (xy 58.139953 -423.644576) (xy 58.141616 -423.629582) (xy 58.141616 -422.550082)
			(xy 58.139952 -422.535088) (xy 58.138171 -422.50497) (xy 58.13806 -422.489884) (xy 58.138175 -422.474799)
			(xy 58.139953 -422.44468) (xy 58.141616 -422.429686) (xy 58.141616 -421.81907) (xy 58.142081 -421.806981)
			(xy 58.149543 -421.783984) (xy 58.163731 -421.764406) (xy 58.183263 -421.750156) (xy 58.206237 -421.74262)
			(xy 58.218324 -421.742108) (xy 59.158124 -421.742108) (xy 59.170235 -421.742496) (xy 59.193264 -421.750003)
			(xy 59.212838 -421.764272) (xy 59.227031 -421.783899) (xy 59.23445 -421.806958) (xy 59.234832 -421.81907)
			(xy 59.234832 -423.68978) (xy 62.138052 -423.68978) (xy 62.138167 -423.674695) (xy 62.139945 -423.644576)
			(xy 62.141608 -423.629582) (xy 62.141608 -422.550082) (xy 62.139944 -422.535088) (xy 62.138163 -422.50497)
			(xy 62.138052 -422.489884) (xy 62.138167 -422.474799) (xy 62.139945 -422.44468) (xy 62.141608 -422.429686)
			(xy 62.141608 -421.81907) (xy 62.142081 -421.806982) (xy 62.149542 -421.783986) (xy 62.163728 -421.764409)
			(xy 62.183258 -421.750158) (xy 62.20623 -421.742621) (xy 62.218316 -421.742108) (xy 63.158116 -421.742108)
			(xy 63.170227 -421.742503) (xy 63.193256 -421.750008) (xy 63.212829 -421.764274) (xy 63.227023 -421.783901)
			(xy 63.234442 -421.806958) (xy 63.234824 -421.81907) (xy 63.234824 -424.360594) (xy 63.234387 -424.372687)
			(xy 63.226927 -424.395693) (xy 63.212734 -424.415276) (xy 63.193192 -424.429526) (xy 63.170207 -424.437051)
			(xy 63.158116 -424.437556) (xy 62.218316 -424.437556) (xy 62.206214 -424.437071) (xy 62.183196 -424.429582)
			(xy 62.163628 -424.415337) (xy 62.149431 -424.395733) (xy 62.142 -424.372697) (xy 62.141608 -424.360594)
			(xy 62.141608 -423.749978) (xy 62.139944 -423.734984) (xy 62.138162 -423.704866) (xy 62.138052 -423.68978)
			(xy 59.234832 -423.68978) (xy 59.234832 -424.360594) (xy 59.234387 -424.372686) (xy 59.226928 -424.395691)
			(xy 59.212737 -424.415274) (xy 59.193197 -424.429523) (xy 59.170215 -424.43705) (xy 59.158124 -424.437556)
			(xy 58.218324 -424.437556) (xy 58.206222 -424.437064) (xy 58.183205 -424.429578) (xy 58.163637 -424.415334)
			(xy 58.149439 -424.395732) (xy 58.142008 -424.372697) (xy 58.141616 -424.360594) (xy 58.141616 -423.749978)
			(xy 58.139952 -423.734984) (xy 58.13817 -423.704866) (xy 58.13806 -423.68978) (xy 50.545492 -423.68978)
			(xy 50.545492 -424.470068) (xy 50.544987 -424.575592) (xy 50.54061 -424.689778) (xy 64.138048 -424.689778)
			(xy 64.138163 -424.674693) (xy 64.139941 -424.644574) (xy 64.141604 -424.62958) (xy 64.141604 -423.55008)
			(xy 64.13994 -423.535086) (xy 64.138158 -423.504968) (xy 64.138048 -423.489882) (xy 64.138163 -423.474797)
			(xy 64.139941 -423.444678) (xy 64.141604 -423.429684) (xy 64.141604 -422.819068) (xy 64.142037 -422.806991)
			(xy 64.14951 -422.78402) (xy 64.163714 -422.764483) (xy 64.18326 -422.75029) (xy 64.206234 -422.74283)
			(xy 64.218312 -422.74236) (xy 65.158112 -422.74236) (xy 65.170184 -422.742854) (xy 65.193146 -422.750316)
			(xy 65.21268 -422.764506) (xy 65.226875 -422.784036) (xy 65.234343 -422.806996) (xy 65.23482 -422.819068)
			(xy 65.23482 -424.689778) (xy 68.13804 -424.689778) (xy 68.138155 -424.674693) (xy 68.139933 -424.644574)
			(xy 68.141596 -424.62958) (xy 68.141596 -423.55008) (xy 68.139932 -423.535086) (xy 68.13815 -423.504968)
			(xy 68.13804 -423.489882) (xy 68.138155 -423.474797) (xy 68.139933 -423.444678) (xy 68.141596 -423.429684)
			(xy 68.141596 -422.819068) (xy 68.142037 -422.806991) (xy 68.149509 -422.784022) (xy 68.163711 -422.764485)
			(xy 68.183255 -422.750292) (xy 68.206227 -422.742831) (xy 68.218304 -422.74236) (xy 69.158104 -422.74236)
			(xy 69.170176 -422.74286) (xy 69.193137 -422.75032) (xy 69.212672 -422.764508) (xy 69.226867 -422.784037)
			(xy 69.234335 -422.806997) (xy 69.234812 -422.819068) (xy 69.234812 -423.68978) (xy 70.138036 -423.68978)
			(xy 70.138153 -423.674695) (xy 70.139931 -423.644576) (xy 70.141592 -423.629582) (xy 70.141592 -422.550082)
			(xy 70.139928 -422.535088) (xy 70.138147 -422.50497) (xy 70.138036 -422.489884) (xy 70.138153 -422.474799)
			(xy 70.139931 -422.44468) (xy 70.141592 -422.429686) (xy 70.141592 -421.81907) (xy 70.142081 -421.806984)
			(xy 70.14954 -421.78399) (xy 70.163723 -421.764415) (xy 70.183248 -421.750163) (xy 70.206215 -421.742624)
			(xy 70.2183 -421.742108) (xy 71.1581 -421.742108) (xy 71.17021 -421.742516) (xy 71.193238 -421.750017)
			(xy 71.212812 -421.76428) (xy 71.227007 -421.783904) (xy 71.234426 -421.806959) (xy 71.234808 -421.81907)
			(xy 71.234808 -424.360594) (xy 71.234288 -424.372678) (xy 71.226839 -424.395671) (xy 71.212664 -424.415247)
			(xy 71.193145 -424.429499) (xy 71.170183 -424.43704) (xy 71.1581 -424.437556) (xy 70.2183 -424.437556)
			(xy 70.206197 -424.437085) (xy 70.183179 -424.429592) (xy 70.163611 -424.415343) (xy 70.149414 -424.395736)
			(xy 70.141983 -424.372698) (xy 70.141592 -424.360594) (xy 70.141592 -423.749978) (xy 70.139928 -423.734984)
			(xy 70.138146 -423.704866) (xy 70.138036 -423.68978) (xy 69.234812 -423.68978) (xy 69.234812 -424.689778)
			(xy 72.138032 -424.689778) (xy 72.138149 -424.674693) (xy 72.139927 -424.644574) (xy 72.141588 -424.62958)
			(xy 72.141588 -423.55008) (xy 72.139924 -423.535086) (xy 72.138142 -423.504968) (xy 72.138032 -423.489882)
			(xy 72.138149 -423.474797) (xy 72.139927 -423.444678) (xy 72.141588 -423.429684) (xy 72.141588 -422.819068)
			(xy 72.142037 -422.806992) (xy 72.149508 -422.784025) (xy 72.163708 -422.764488) (xy 72.18325 -422.750295)
			(xy 72.20622 -422.742832) (xy 72.218296 -422.74236) (xy 73.158096 -422.74236) (xy 73.170167 -422.742867)
			(xy 73.193129 -422.750325) (xy 73.212663 -422.764511) (xy 73.226859 -422.784039) (xy 73.234327 -422.806997)
			(xy 73.234804 -422.819068) (xy 73.234804 -424.80464) (xy 109.929157 -424.80464) (xy 109.929157 -424.6755)
			(xy 109.937107 -424.546605) (xy 109.952977 -424.418445) (xy 109.976706 -424.291504) (xy 110.008205 -424.166265)
			(xy 110.047354 -424.043202) (xy 110.094005 -423.922783) (xy 110.14798 -423.805464) (xy 110.209075 -423.69169)
			(xy 110.277058 -423.581893) (xy 110.351672 -423.47649) (xy 110.432633 -423.37588) (xy 110.519633 -423.280445)
			(xy 110.612344 -423.190546) (xy 110.710414 -423.106525) (xy 110.813469 -423.028701) (xy 110.92112 -422.957369)
			(xy 111.032959 -422.892799) (xy 111.14856 -422.835237) (xy 111.267485 -422.7849) (xy 111.389284 -422.74198)
			(xy 111.513494 -422.706639) (xy 111.639643 -422.679012) (xy 111.767255 -422.659203) (xy 111.895844 -422.647287)
			(xy 112.024922 -422.643311) (xy 112.154 -422.647287) (xy 112.282589 -422.659203) (xy 112.410201 -422.679012)
			(xy 112.53635 -422.706639) (xy 112.66056 -422.74198) (xy 112.782359 -422.7849) (xy 112.901284 -422.835237)
			(xy 113.016885 -422.892799) (xy 113.128724 -422.957369) (xy 113.236375 -423.028701) (xy 113.33943 -423.106525)
			(xy 113.4375 -423.190546) (xy 113.530211 -423.280445) (xy 113.617211 -423.37588) (xy 113.698172 -423.47649)
			(xy 113.772786 -423.581893) (xy 113.840769 -423.69169) (xy 113.901864 -423.805464) (xy 113.955839 -423.922783)
			(xy 114.00249 -424.043202) (xy 114.041639 -424.166265) (xy 114.073138 -424.291504) (xy 114.096867 -424.418445)
			(xy 114.112737 -424.546605) (xy 114.120687 -424.6755) (xy 114.121184 -424.74007) (xy 114.120687 -424.80464)
			(xy 114.112737 -424.933535) (xy 114.096867 -425.061695) (xy 114.073138 -425.188636) (xy 114.041639 -425.313875)
			(xy 114.00249 -425.436938) (xy 113.955839 -425.557357) (xy 113.901864 -425.674676) (xy 113.840769 -425.78845)
			(xy 113.772786 -425.898247) (xy 113.698172 -426.00365) (xy 113.617211 -426.10426) (xy 113.530211 -426.199695)
			(xy 113.4375 -426.289594) (xy 113.33943 -426.373615) (xy 113.236375 -426.451439) (xy 113.128724 -426.522771)
			(xy 113.016885 -426.587341) (xy 112.901284 -426.644903) (xy 112.782359 -426.69524) (xy 112.66056 -426.73816)
			(xy 112.53635 -426.773501) (xy 112.410201 -426.801128) (xy 112.282589 -426.820937) (xy 112.154 -426.832853)
			(xy 112.024922 -426.83683) (xy 111.895844 -426.832853) (xy 111.767255 -426.820937) (xy 111.639643 -426.801128)
			(xy 111.513494 -426.773501) (xy 111.389284 -426.73816) (xy 111.267485 -426.69524) (xy 111.14856 -426.644903)
			(xy 111.032959 -426.587341) (xy 110.92112 -426.522771) (xy 110.813469 -426.451439) (xy 110.710414 -426.373615)
			(xy 110.612344 -426.289594) (xy 110.519633 -426.199695) (xy 110.432633 -426.10426) (xy 110.351672 -426.00365)
			(xy 110.277058 -425.898247) (xy 110.209075 -425.78845) (xy 110.14798 -425.674676) (xy 110.094005 -425.557357)
			(xy 110.047354 -425.436938) (xy 110.008205 -425.313875) (xy 109.976706 -425.188636) (xy 109.952977 -425.061695)
			(xy 109.937107 -424.933535) (xy 109.929157 -424.80464) (xy 73.234804 -424.80464) (xy 73.234804 -425.360592)
			(xy 73.234381 -425.372675) (xy 73.226915 -425.395658) (xy 73.212712 -425.415209) (xy 73.193162 -425.429413)
			(xy 73.170179 -425.43688) (xy 73.158096 -425.4373) (xy 72.218296 -425.4373) (xy 72.206212 -425.436891)
			(xy 72.183228 -425.429421) (xy 72.163677 -425.415214) (xy 72.149473 -425.395661) (xy 72.142007 -425.372676)
			(xy 72.141588 -425.360592) (xy 72.141588 -424.749976) (xy 72.139924 -424.734982) (xy 72.138142 -424.704864)
			(xy 72.138032 -424.689778) (xy 69.234812 -424.689778) (xy 69.234812 -425.360592) (xy 69.234381 -425.372674)
			(xy 69.226916 -425.395656) (xy 69.212714 -425.415206) (xy 69.193167 -425.429411) (xy 69.170186 -425.436879)
			(xy 69.158104 -425.4373) (xy 68.218304 -425.4373) (xy 68.206221 -425.436884) (xy 68.183237 -425.429417)
			(xy 68.163686 -425.415212) (xy 68.149482 -425.39566) (xy 68.142015 -425.372675) (xy 68.141596 -425.360592)
			(xy 68.141596 -424.749976) (xy 68.139932 -424.734982) (xy 68.13815 -424.704864) (xy 68.13804 -424.689778)
			(xy 65.23482 -424.689778) (xy 65.23482 -425.360592) (xy 65.234329 -425.372665) (xy 65.22687 -425.39563)
			(xy 65.21268 -425.415166) (xy 65.193148 -425.429361) (xy 65.170185 -425.436826) (xy 65.158112 -425.4373)
			(xy 64.218312 -425.4373) (xy 64.206229 -425.436877) (xy 64.183246 -425.429412) (xy 64.163694 -425.415208)
			(xy 64.14949 -425.395658) (xy 64.142024 -425.372675) (xy 64.141604 -425.360592) (xy 64.141604 -424.749976)
			(xy 64.13994 -424.734982) (xy 64.138158 -424.704864) (xy 64.138048 -424.689778) (xy 50.54061 -424.689778)
			(xy 50.536903 -424.786486) (xy 50.520747 -424.996915) (xy 50.496544 -425.206572) (xy 50.464327 -425.415147)
			(xy 50.424145 -425.622335) (xy 50.376057 -425.827832) (xy 50.320133 -426.031336) (xy 50.256456 -426.232549)
			(xy 50.185118 -426.431176) (xy 50.106224 -426.626924) (xy 50.019891 -426.819506) (xy 49.926244 -427.008641)
			(xy 49.825422 -427.19405) (xy 49.768393 -427.289976) (xy 58.13806 -427.289976) (xy 58.138174 -427.274891)
			(xy 58.139952 -427.244772) (xy 58.141616 -427.229778) (xy 58.141616 -426.150024) (xy 58.139947 -426.135031)
			(xy 58.138169 -426.104912) (xy 58.13806 -426.089826) (xy 58.13817 -426.07474) (xy 58.139951 -426.044622)
			(xy 58.141616 -426.029628) (xy 58.141616 -425.419012) (xy 58.142023 -425.406928) (xy 58.149491 -425.383941)
			(xy 58.163697 -425.364389) (xy 58.183252 -425.350185) (xy 58.206239 -425.342722) (xy 58.218324 -425.342304)
			(xy 59.158124 -425.342304) (xy 59.170201 -425.342744) (xy 59.193171 -425.350215) (xy 59.212709 -425.364417)
			(xy 59.226902 -425.383961) (xy 59.234361 -425.406935) (xy 59.234832 -425.419012) (xy 59.234832 -427.960536)
			(xy 59.234367 -427.97261) (xy 59.226898 -427.995574) (xy 59.2127 -428.015109) (xy 59.193164 -428.029303)
			(xy 59.170198 -428.036769) (xy 59.158124 -428.037244) (xy 58.218324 -428.037244) (xy 58.206254 -428.036716)
			(xy 58.183294 -428.029264) (xy 58.16376 -428.015083) (xy 58.149563 -427.99556) (xy 58.142093 -427.972605)
			(xy 58.141616 -427.960536) (xy 58.141616 -427.350174) (xy 58.139952 -427.33518) (xy 58.13817 -427.305062)
			(xy 58.13806 -427.289976) (xy 49.768393 -427.289976) (xy 49.717572 -427.375461) (xy 49.602853 -427.552608)
			(xy 49.481433 -427.72523) (xy 49.35349 -427.893076) (xy 49.219212 -428.055898) (xy 49.078796 -428.213457)
			(xy 49.0054 -428.28972) (xy 60.138056 -428.28972) (xy 60.138166 -428.274634) (xy 60.139947 -428.244516)
			(xy 60.141612 -428.229522) (xy 60.141612 -427.150022) (xy 60.139943 -427.135029) (xy 60.138165 -427.10491)
			(xy 60.138056 -427.089824) (xy 60.138166 -427.074738) (xy 60.139947 -427.04462) (xy 60.141612 -427.029626)
			(xy 60.141612 -426.41901) (xy 60.142115 -426.406924) (xy 60.149566 -426.383928) (xy 60.163744 -426.364351)
			(xy 60.183268 -426.350099) (xy 60.206236 -426.342562) (xy 60.21832 -426.342048) (xy 61.15812 -426.342048)
			(xy 61.170225 -426.342499) (xy 61.193244 -426.349997) (xy 61.212812 -426.364252) (xy 61.227008 -426.383863)
			(xy 61.234437 -426.406904) (xy 61.234828 -426.41901) (xy 61.234828 -427.289976) (xy 62.138052 -427.289976)
			(xy 62.138166 -427.274891) (xy 62.139944 -427.244772) (xy 62.141608 -427.229778) (xy 62.141608 -426.150024)
			(xy 62.139939 -426.135031) (xy 62.138161 -426.104912) (xy 62.138052 -426.089826) (xy 62.138162 -426.07474)
			(xy 62.139943 -426.044622) (xy 62.141608 -426.029628) (xy 62.141608 -425.419012) (xy 62.142023 -425.406928)
			(xy 62.149489 -425.383943) (xy 62.163694 -425.364392) (xy 62.183247 -425.350188) (xy 62.206232 -425.342723)
			(xy 62.218316 -425.342304) (xy 63.158116 -425.342304) (xy 63.170193 -425.342751) (xy 63.193162 -425.350219)
			(xy 63.2127 -425.36442) (xy 63.226894 -425.383963) (xy 63.234353 -425.406935) (xy 63.234824 -425.419012)
			(xy 63.234824 -427.960536) (xy 63.234367 -427.972611) (xy 63.226896 -427.995577) (xy 63.212697 -428.015112)
			(xy 63.193159 -428.029306) (xy 63.170191 -428.03677) (xy 63.158116 -428.037244) (xy 62.218316 -428.037244)
			(xy 62.206246 -428.036723) (xy 62.183285 -428.029269) (xy 62.163751 -428.015086) (xy 62.149555 -427.995561)
			(xy 62.142085 -427.972606) (xy 62.141608 -427.960536) (xy 62.141608 -427.350174) (xy 62.139944 -427.33518)
			(xy 62.138162 -427.305062) (xy 62.138052 -427.289976) (xy 61.234828 -427.289976) (xy 61.234828 -428.28972)
			(xy 64.138048 -428.28972) (xy 64.138158 -428.274634) (xy 64.139939 -428.244516) (xy 64.141604 -428.229522)
			(xy 64.141604 -427.150022) (xy 64.139935 -427.135029) (xy 64.138157 -427.10491) (xy 64.138048 -427.089824)
			(xy 64.138158 -427.074738) (xy 64.139939 -427.04462) (xy 64.141604 -427.029626) (xy 64.141604 -426.41901)
			(xy 64.142115 -426.406925) (xy 64.149565 -426.38393) (xy 64.163741 -426.364353) (xy 64.183263 -426.350101)
			(xy 64.206228 -426.342563) (xy 64.218312 -426.342048) (xy 65.158112 -426.342048) (xy 65.170216 -426.342505)
			(xy 65.193235 -426.350002) (xy 65.212804 -426.364255) (xy 65.227 -426.383864) (xy 65.234429 -426.406905)
			(xy 65.23482 -426.41901) (xy 65.23482 -427.289976) (xy 66.138044 -427.289976) (xy 66.138159 -427.274891)
			(xy 66.139936 -427.244772) (xy 66.1416 -427.229778) (xy 66.1416 -426.150024) (xy 66.139931 -426.135031)
			(xy 66.138153 -426.104912) (xy 66.138044 -426.089826) (xy 66.138154 -426.07474) (xy 66.139935 -426.044622)
			(xy 66.1416 -426.029628) (xy 66.1416 -425.419012) (xy 66.142023 -425.406929) (xy 66.149488 -425.383946)
			(xy 66.163692 -425.364394) (xy 66.183242 -425.35019) (xy 66.206225 -425.342724) (xy 66.218308 -425.342304)
			(xy 67.158108 -425.342304) (xy 67.170192 -425.342706) (xy 67.193177 -425.350177) (xy 67.212729 -425.364386)
			(xy 67.226932 -425.383941) (xy 67.234397 -425.406928) (xy 67.234816 -425.419012) (xy 67.234816 -427.960536)
			(xy 67.234367 -427.972612) (xy 67.226895 -427.995579) (xy 67.212695 -428.015115) (xy 67.193154 -428.029308)
			(xy 67.170184 -428.036771) (xy 67.158108 -428.037244) (xy 66.218308 -428.037244) (xy 66.206237 -428.03673)
			(xy 66.183277 -428.029274) (xy 66.163743 -428.015089) (xy 66.149547 -427.995563) (xy 66.142077 -427.972606)
			(xy 66.1416 -427.960536) (xy 66.1416 -427.350174) (xy 66.139936 -427.33518) (xy 66.138154 -427.305062)
			(xy 66.138044 -427.289976) (xy 65.23482 -427.289976) (xy 65.23482 -428.28972) (xy 68.13804 -428.28972)
			(xy 68.138152 -428.274634) (xy 68.139933 -428.244516) (xy 68.141596 -428.229522) (xy 68.141596 -427.150022)
			(xy 68.139927 -427.135029) (xy 68.138149 -427.10491) (xy 68.13804 -427.089824) (xy 68.13815 -427.074738)
			(xy 68.139931 -427.04462) (xy 68.141596 -427.029626) (xy 68.141596 -426.41901) (xy 68.142115 -426.406925)
			(xy 68.149564 -426.383932) (xy 68.163739 -426.364356) (xy 68.183258 -426.350104) (xy 68.206221 -426.342564)
			(xy 68.218304 -426.342048) (xy 69.158104 -426.342048) (xy 69.170208 -426.342512) (xy 69.193227 -426.350006)
			(xy 69.212795 -426.364257) (xy 69.226991 -426.383866) (xy 69.234421 -426.406905) (xy 69.234812 -426.41901)
			(xy 69.234812 -427.289976) (xy 70.138036 -427.289976) (xy 70.138153 -427.274891) (xy 70.13993 -427.244772)
			(xy 70.141592 -427.229778) (xy 70.141592 -426.150024) (xy 70.139923 -426.135031) (xy 70.138145 -426.104912)
			(xy 70.138036 -426.089826) (xy 70.138148 -426.07474) (xy 70.139929 -426.044622) (xy 70.141592 -426.029628)
			(xy 70.141592 -425.419012) (xy 70.142023 -425.40693) (xy 70.149487 -425.383948) (xy 70.163689 -425.364397)
			(xy 70.183237 -425.350193) (xy 70.206218 -425.342725) (xy 70.2183 -425.342304) (xy 71.1581 -425.342304)
			(xy 71.170184 -425.342713) (xy 71.193169 -425.350182) (xy 71.21272 -425.364388) (xy 71.226924 -425.383942)
			(xy 71.234389 -425.406928) (xy 71.234808 -425.419012) (xy 71.234808 -427.960536) (xy 71.234367 -427.972612)
			(xy 71.226894 -427.995581) (xy 71.212692 -428.015117) (xy 71.193149 -428.029311) (xy 71.170177 -428.036772)
			(xy 71.1581 -428.037244) (xy 70.2183 -428.037244) (xy 70.206229 -428.036736) (xy 70.183268 -428.029278)
			(xy 70.163734 -428.015092) (xy 70.149538 -427.995564) (xy 70.142069 -427.972607) (xy 70.141592 -427.960536)
			(xy 70.141592 -427.350174) (xy 70.139928 -427.33518) (xy 70.138146 -427.305062) (xy 70.138036 -427.289976)
			(xy 69.234812 -427.289976) (xy 69.234812 -428.28972) (xy 72.138032 -428.28972) (xy 72.138144 -428.274634)
			(xy 72.139925 -428.244516) (xy 72.141588 -428.229522) (xy 72.141588 -427.150022) (xy 72.139919 -427.135029)
			(xy 72.138141 -427.10491) (xy 72.138032 -427.089824) (xy 72.138144 -427.074738) (xy 72.139925 -427.04462)
			(xy 72.141588 -427.029626) (xy 72.141588 -426.41901) (xy 72.142017 -426.406916) (xy 72.149477 -426.383908)
			(xy 72.163671 -426.364324) (xy 72.183216 -426.350075) (xy 72.206204 -426.342551) (xy 72.218296 -426.342048)
			(xy 73.158096 -426.342048) (xy 73.170199 -426.342519) (xy 73.193218 -426.350011) (xy 73.212787 -426.36426)
			(xy 73.226983 -426.383867) (xy 73.234413 -426.406905) (xy 73.234804 -426.41901) (xy 73.234804 -427.289976)
			(xy 75.138026 -427.289976) (xy 75.138117 -427.275402) (xy 75.139771 -427.246301) (xy 75.141328 -427.23181)
			(xy 75.141328 -426.147992) (xy 75.139785 -426.1335) (xy 75.138132 -426.1044) (xy 75.138026 -426.089826)
			(xy 75.138121 -426.075252) (xy 75.139773 -426.046151) (xy 75.141328 -426.03166) (xy 75.141328 -425.419012)
			(xy 75.141727 -425.406901) (xy 75.149227 -425.383869) (xy 75.163492 -425.364294) (xy 75.183119 -425.3501)
			(xy 75.206178 -425.342684) (xy 75.21829 -425.342304) (xy 76.15809 -425.342304) (xy 76.170175 -425.342815)
			(xy 76.19317 -425.350265) (xy 76.212747 -425.364441) (xy 76.226999 -425.383963) (xy 76.234537 -425.406928)
			(xy 76.235052 -425.419012) (xy 76.235052 -427.960536) (xy 76.234615 -427.972642) (xy 76.227112 -427.995661)
			(xy 76.212854 -428.015229) (xy 76.19324 -428.029424) (xy 76.170197 -428.036854) (xy 76.15809 -428.037244)
			(xy 75.21829 -428.037244) (xy 75.206198 -428.036801) (xy 75.183195 -428.029339) (xy 75.163614 -428.015147)
			(xy 75.149364 -427.995608) (xy 75.141835 -427.972626) (xy 75.141328 -427.960536) (xy 75.141328 -427.348142)
			(xy 75.139781 -427.33365) (xy 75.138131 -427.30455) (xy 75.138026 -427.289976) (xy 73.234804 -427.289976)
			(xy 73.234804 -428.28972) (xy 77.138022 -428.28972) (xy 77.138117 -428.275146) (xy 77.139768 -428.246045)
			(xy 77.141324 -428.231554) (xy 77.141324 -427.14799) (xy 77.139781 -427.133498) (xy 77.138128 -427.104398)
			(xy 77.138022 -427.089824) (xy 77.138117 -427.07525) (xy 77.139769 -427.046149) (xy 77.141324 -427.031658)
			(xy 77.141324 -426.41901) (xy 77.14182 -426.406897) (xy 77.149303 -426.383857) (xy 77.163539 -426.364256)
			(xy 77.183135 -426.350014) (xy 77.206174 -426.342524) (xy 77.218286 -426.342048) (xy 78.158086 -426.342048)
			(xy 78.170209 -426.342472) (xy 78.193269 -426.349962) (xy 78.212885 -426.364212) (xy 78.227136 -426.383827)
			(xy 78.234627 -426.406887) (xy 78.235048 -426.41901) (xy 78.235048 -427.289976) (xy 79.138018 -427.289976)
			(xy 79.138109 -427.275402) (xy 79.139763 -427.246301) (xy 79.14132 -427.23181) (xy 79.14132 -426.147992)
			(xy 79.139777 -426.1335) (xy 79.138124 -426.1044) (xy 79.138018 -426.089826) (xy 79.138113 -426.075252)
			(xy 79.139765 -426.046151) (xy 79.14132 -426.03166) (xy 79.14132 -425.419012) (xy 79.141727 -425.406902)
			(xy 79.149226 -425.383872) (xy 79.163489 -425.364297) (xy 79.183114 -425.350102) (xy 79.20617 -425.342685)
			(xy 79.218282 -425.342304) (xy 80.158082 -425.342304) (xy 80.170167 -425.342822) (xy 80.193161 -425.35027)
			(xy 80.212738 -425.364444) (xy 80.226991 -425.383965) (xy 80.234529 -425.406929) (xy 80.235044 -425.419012)
			(xy 80.235044 -427.960536) (xy 80.234615 -427.972642) (xy 80.227111 -427.995663) (xy 80.212851 -428.015232)
			(xy 80.193235 -428.029427) (xy 80.17019 -428.036855) (xy 80.158082 -428.037244) (xy 79.218282 -428.037244)
			(xy 79.20619 -428.036808) (xy 79.183186 -428.029344) (xy 79.163605 -428.01515) (xy 79.149355 -427.995609)
			(xy 79.141827 -427.972627) (xy 79.14132 -427.960536) (xy 79.14132 -427.348142) (xy 79.139773 -427.33365)
			(xy 79.138123 -427.30455) (xy 79.138018 -427.289976) (xy 78.235048 -427.289976) (xy 78.235048 -428.28972)
			(xy 81.138014 -428.28972) (xy 81.138108 -428.275146) (xy 81.13976 -428.246045) (xy 81.141316 -428.231554)
			(xy 81.141316 -427.14799) (xy 81.139773 -427.133498) (xy 81.13812 -427.104398) (xy 81.138014 -427.089824)
			(xy 81.138108 -427.07525) (xy 81.13976 -427.046149) (xy 81.141316 -427.031658) (xy 81.141316 -426.41901)
			(xy 81.14182 -426.406898) (xy 81.149302 -426.383859) (xy 81.163536 -426.364259) (xy 81.18313 -426.350016)
			(xy 81.206166 -426.342525) (xy 81.218278 -426.342048) (xy 82.158078 -426.342048) (xy 82.170201 -426.342479)
			(xy 82.19326 -426.349966) (xy 82.212877 -426.364215) (xy 82.227128 -426.383829) (xy 82.234619 -426.406887)
			(xy 82.23504 -426.41901) (xy 82.23504 -427.289976) (xy 83.13801 -427.289976) (xy 83.1381 -427.275402)
			(xy 83.139755 -427.246301) (xy 83.141312 -427.23181) (xy 83.141312 -426.147992) (xy 83.139769 -426.1335)
			(xy 83.138116 -426.1044) (xy 83.13801 -426.089826) (xy 83.138105 -426.075252) (xy 83.139756 -426.046151)
			(xy 83.141312 -426.03166) (xy 83.141312 -425.419012) (xy 83.141727 -425.406903) (xy 83.149224 -425.383874)
			(xy 83.163486 -425.364299) (xy 83.183109 -425.350105) (xy 83.206163 -425.342686) (xy 83.218274 -425.342304)
			(xy 84.158074 -425.342304) (xy 84.170159 -425.342829) (xy 84.193152 -425.350274) (xy 84.21273 -425.364447)
			(xy 84.226982 -425.383966) (xy 84.234521 -425.406929) (xy 84.235036 -425.419012) (xy 84.235036 -427.960536)
			(xy 84.234615 -427.972643) (xy 84.22711 -427.995665) (xy 84.212848 -428.015235) (xy 84.19323 -428.029429)
			(xy 84.170183 -428.036856) (xy 84.158074 -428.037244) (xy 83.218274 -428.037244) (xy 83.206181 -428.036815)
			(xy 83.183177 -428.029349) (xy 83.163596 -428.015153) (xy 83.149347 -427.995611) (xy 83.141819 -427.972627)
			(xy 83.141312 -427.960536) (xy 83.141312 -427.348142) (xy 83.139765 -427.33365) (xy 83.138115 -427.30455)
			(xy 83.13801 -427.289976) (xy 82.23504 -427.289976) (xy 82.23504 -428.28972) (xy 85.138006 -428.28972)
			(xy 85.1381 -428.275146) (xy 85.139752 -428.246045) (xy 85.141308 -428.231554) (xy 85.141308 -427.14799)
			(xy 85.139765 -427.133498) (xy 85.138112 -427.104398) (xy 85.138006 -427.089824) (xy 85.1381 -427.07525)
			(xy 85.139752 -427.046149) (xy 85.141308 -427.031658) (xy 85.141308 -426.41901) (xy 85.14182 -426.406899)
			(xy 85.149301 -426.383861) (xy 85.163533 -426.364262) (xy 85.183125 -426.350019) (xy 85.206159 -426.342526)
			(xy 85.21827 -426.342048) (xy 86.15807 -426.342048) (xy 86.170192 -426.342486) (xy 86.193252 -426.349971)
			(xy 86.212868 -426.364218) (xy 86.22712 -426.38383) (xy 86.234611 -426.406888) (xy 86.235032 -426.41901)
			(xy 86.235032 -427.289976) (xy 87.138002 -427.289976) (xy 87.138092 -427.275402) (xy 87.139747 -427.246301)
			(xy 87.141304 -427.23181) (xy 87.141304 -426.147992) (xy 87.139761 -426.1335) (xy 87.138108 -426.1044)
			(xy 87.138002 -426.089826) (xy 87.138097 -426.075252) (xy 87.139748 -426.046151) (xy 87.141304 -426.03166)
			(xy 87.141304 -425.419012) (xy 87.141727 -425.406903) (xy 87.149223 -425.383876) (xy 87.163483 -425.364302)
			(xy 87.183104 -425.350107) (xy 87.206156 -425.342687) (xy 87.218266 -425.342304) (xy 88.158066 -425.342304)
			(xy 88.17015 -425.342836) (xy 88.193144 -425.350279) (xy 88.212721 -425.36445) (xy 88.226974 -425.383968)
			(xy 88.234513 -425.40693) (xy 88.235028 -425.419012) (xy 88.235028 -427.960536) (xy 88.234615 -427.972644)
			(xy 88.227109 -427.995668) (xy 88.212845 -428.015238) (xy 88.193225 -428.029432) (xy 88.170175 -428.036857)
			(xy 88.158066 -428.037244) (xy 87.218266 -428.037244) (xy 87.206173 -428.036821) (xy 87.183169 -428.029353)
			(xy 87.163588 -428.015156) (xy 87.149339 -427.995612) (xy 87.141811 -427.972628) (xy 87.141304 -427.960536)
			(xy 87.141304 -427.348142) (xy 87.139757 -427.33365) (xy 87.138107 -427.30455) (xy 87.138002 -427.289976)
			(xy 86.235032 -427.289976) (xy 86.235032 -428.28972) (xy 89.137998 -428.28972) (xy 89.138092 -428.275146)
			(xy 89.139744 -428.246045) (xy 89.1413 -428.231554) (xy 89.1413 -427.14799) (xy 89.139757 -427.133498)
			(xy 89.138104 -427.104398) (xy 89.137998 -427.089824) (xy 89.138092 -427.07525) (xy 89.139744 -427.046149)
			(xy 89.1413 -427.031658) (xy 89.1413 -426.41901) (xy 89.14182 -426.4069) (xy 89.1493 -426.383863)
			(xy 89.163531 -426.364265) (xy 89.18312 -426.350022) (xy 89.206152 -426.342527) (xy 89.218262 -426.342048)
			(xy 90.158062 -426.342048) (xy 90.170184 -426.342492) (xy 90.193243 -426.349975) (xy 90.21286 -426.36422)
			(xy 90.227112 -426.383832) (xy 90.234603 -426.406888) (xy 90.235024 -426.41901) (xy 90.235024 -427.289976)
			(xy 125.218444 -427.289976) (xy 125.218925 -427.257419) (xy 125.226874 -427.192793) (xy 125.242661 -427.129623)
			(xy 125.266051 -427.068856) (xy 125.296692 -427.011403) (xy 125.334125 -426.958126) (xy 125.377788 -426.909823)
			(xy 125.402086 -426.888148) (xy 125.482858 -426.723302) (xy 125.487543 -426.71278) (xy 125.491036 -426.690025)
			(xy 125.487558 -426.667269) (xy 125.482858 -426.656754) (xy 125.401832 -426.491654) (xy 125.377574 -426.469952)
			(xy 125.333975 -426.421622) (xy 125.296599 -426.368332) (xy 125.266005 -426.310881) (xy 125.242649 -426.250125)
			(xy 125.226881 -426.186974) (xy 125.218936 -426.122371) (xy 125.218444 -426.089826) (xy 125.219149 -426.0507)
			(xy 125.23062 -425.973293) (xy 125.241304 -425.935648) (xy 125.241304 -425.419012) (xy 125.241727 -425.406903)
			(xy 125.249223 -425.383876) (xy 125.263483 -425.364302) (xy 125.283104 -425.350107) (xy 125.306156 -425.342687)
			(xy 125.318266 -425.342304) (xy 126.258066 -425.342304) (xy 126.27015 -425.342836) (xy 126.293144 -425.350279)
			(xy 126.312721 -425.36445) (xy 126.326974 -425.383968) (xy 126.334513 -425.40693) (xy 126.335028 -425.419012)
			(xy 126.335028 -427.960536) (xy 126.334615 -427.972644) (xy 126.327109 -427.995668) (xy 126.312845 -428.015238)
			(xy 126.293225 -428.029432) (xy 126.270175 -428.036857) (xy 126.258066 -428.037244) (xy 125.318266 -428.037244)
			(xy 125.306173 -428.036821) (xy 125.283169 -428.029353) (xy 125.263588 -428.015156) (xy 125.249339 -427.995612)
			(xy 125.241811 -427.972628) (xy 125.241304 -427.960536) (xy 125.241304 -427.444154) (xy 125.230611 -427.40651)
			(xy 125.219138 -427.329103) (xy 125.218444 -427.289976) (xy 90.235024 -427.289976) (xy 90.235024 -428.960534)
			(xy 90.234669 -428.972662) (xy 90.227162 -428.995729) (xy 90.212895 -429.015347) (xy 90.193264 -429.029595)
			(xy 90.170191 -429.03708) (xy 90.158062 -429.037496) (xy 89.218262 -429.037496) (xy 89.206149 -429.037021)
			(xy 89.18311 -429.029528) (xy 89.163512 -429.015285) (xy 89.14927 -428.995686) (xy 89.141778 -428.972647)
			(xy 89.1413 -428.960534) (xy 89.1413 -428.347886) (xy 89.139757 -428.333394) (xy 89.138104 -428.304294)
			(xy 89.137998 -428.28972) (xy 86.235032 -428.28972) (xy 86.235032 -428.960534) (xy 86.234617 -428.972653)
			(xy 86.227117 -428.995703) (xy 86.212861 -429.015307) (xy 86.193245 -429.029546) (xy 86.17019 -429.037027)
			(xy 86.15807 -429.037496) (xy 85.21827 -429.037496) (xy 85.206157 -429.037014) (xy 85.183119 -429.029523)
			(xy 85.16352 -429.015282) (xy 85.149279 -428.995685) (xy 85.141786 -428.972647) (xy 85.141308 -428.960534)
			(xy 85.141308 -428.347886) (xy 85.139765 -428.333394) (xy 85.138112 -428.304294) (xy 85.138006 -428.28972)
			(xy 82.23504 -428.28972) (xy 82.23504 -428.960534) (xy 82.234617 -428.972653) (xy 82.227118 -428.995701)
			(xy 82.212864 -429.015304) (xy 82.19325 -429.029543) (xy 82.170197 -429.037026) (xy 82.158078 -429.037496)
			(xy 81.218278 -429.037496) (xy 81.206166 -429.037008) (xy 81.183127 -429.029519) (xy 81.163529 -429.01528)
			(xy 81.149287 -428.995683) (xy 81.141794 -428.972646) (xy 81.141316 -428.960534) (xy 81.141316 -428.347886)
			(xy 81.139773 -428.333394) (xy 81.13812 -428.304294) (xy 81.138014 -428.28972) (xy 78.235048 -428.28972)
			(xy 78.235048 -428.960534) (xy 78.234617 -428.972652) (xy 78.227119 -428.995698) (xy 78.212867 -429.015301)
			(xy 78.193255 -429.029541) (xy 78.170204 -429.037025) (xy 78.158086 -429.037496) (xy 77.218286 -429.037496)
			(xy 77.206174 -429.037001) (xy 77.183136 -429.029514) (xy 77.163537 -429.015277) (xy 77.149295 -428.995682)
			(xy 77.141802 -428.972646) (xy 77.141324 -428.960534) (xy 77.141324 -428.347886) (xy 77.139781 -428.333394)
			(xy 77.138128 -428.304294) (xy 77.138022 -428.28972) (xy 73.234804 -428.28972) (xy 73.234804 -428.960534)
			(xy 73.234323 -428.972621) (xy 73.226862 -428.995615) (xy 73.212677 -429.015191) (xy 73.19315 -429.029442)
			(xy 73.170181 -429.036981) (xy 73.158096 -429.037496) (xy 72.218296 -429.037496) (xy 72.206187 -429.037087)
			(xy 72.183158 -429.029586) (xy 72.163585 -429.015323) (xy 72.149391 -428.995699) (xy 72.141971 -428.972645)
			(xy 72.141588 -428.960534) (xy 72.141588 -428.349918) (xy 72.139919 -428.334925) (xy 72.138141 -428.304806)
			(xy 72.138032 -428.28972) (xy 69.234812 -428.28972) (xy 69.234812 -428.960534) (xy 69.234421 -428.97263)
			(xy 69.226949 -428.99564) (xy 69.212744 -429.015223) (xy 69.193192 -429.029471) (xy 69.170199 -429.036994)
			(xy 69.158104 -429.037496) (xy 68.218304 -429.037496) (xy 68.206195 -429.03708) (xy 68.183167 -429.029582)
			(xy 68.163593 -429.01532) (xy 68.149399 -428.995698) (xy 68.141979 -428.972644) (xy 68.141596 -428.960534)
			(xy 68.141596 -428.349918) (xy 68.139927 -428.334925) (xy 68.138149 -428.304806) (xy 68.13804 -428.28972)
			(xy 65.23482 -428.28972) (xy 65.23482 -428.960534) (xy 65.234421 -428.972629) (xy 65.22695 -428.995638)
			(xy 65.212747 -429.015221) (xy 65.193197 -429.029469) (xy 65.170206 -429.036993) (xy 65.158112 -429.037496)
			(xy 64.218312 -429.037496) (xy 64.206203 -429.037073) (xy 64.183176 -429.029577) (xy 64.163602 -429.015317)
			(xy 64.149407 -428.995696) (xy 64.141987 -428.972644) (xy 64.141604 -428.960534) (xy 64.141604 -428.349918)
			(xy 64.139935 -428.334925) (xy 64.138157 -428.304806) (xy 64.138048 -428.28972) (xy 61.234828 -428.28972)
			(xy 61.234828 -428.960534) (xy 61.234421 -428.972629) (xy 61.226951 -428.995636) (xy 61.21275 -429.015218)
			(xy 61.193202 -429.029466) (xy 61.170213 -429.036992) (xy 61.15812 -429.037496) (xy 60.21832 -429.037496)
			(xy 60.206212 -429.037066) (xy 60.183185 -429.029572) (xy 60.163611 -429.015314) (xy 60.149416 -428.995695)
			(xy 60.141995 -428.972643) (xy 60.141612 -428.960534) (xy 60.141612 -428.349918) (xy 60.139943 -428.334925)
			(xy 60.138165 -428.304806) (xy 60.138056 -428.28972) (xy 49.0054 -428.28972) (xy 48.932448 -428.365522)
			(xy 48.780383 -428.51187) (xy 48.622824 -428.652286) (xy 48.460002 -428.786564) (xy 48.292156 -428.914507)
			(xy 48.119534 -429.035927) (xy 47.942387 -429.150646) (xy 47.760976 -429.258496) (xy 47.575567 -429.359318)
			(xy 47.386432 -429.452965) (xy 47.19385 -429.539298) (xy 46.998102 -429.618192) (xy 46.799475 -429.68953)
			(xy 46.598262 -429.753207) (xy 46.394758 -429.809131) (xy 46.189261 -429.857219) (xy 45.982073 -429.897401)
			(xy 45.773498 -429.929618) (xy 45.563841 -429.953821) (xy 45.353412 -429.969977) (xy 45.142518 -429.978061)
			(xy 44.93147 -429.978061) (xy 44.720576 -429.969977) (xy 44.510147 -429.953821) (xy 44.30049 -429.929618)
			(xy 44.091915 -429.897401) (xy 43.884727 -429.857219) (xy 43.67923 -429.809131) (xy 43.475726 -429.753207)
			(xy 43.274513 -429.68953) (xy 43.075886 -429.618192) (xy 42.880138 -429.539298) (xy 42.687556 -429.452965)
			(xy 42.498421 -429.359318) (xy 42.313012 -429.258496) (xy 42.131601 -429.150646) (xy 41.954454 -429.035927)
			(xy 41.781832 -428.914507) (xy 41.613986 -428.786564) (xy 41.451164 -428.652286) (xy 41.293605 -428.51187)
			(xy 41.14154 -428.365522) (xy 40.995192 -428.213457) (xy 40.854776 -428.055898) (xy 40.720498 -427.893076)
			(xy 40.592555 -427.72523) (xy 40.471135 -427.552608) (xy 40.356416 -427.375461) (xy 40.248566 -427.19405)
			(xy 40.147744 -427.008641) (xy 40.054097 -426.819506) (xy 39.967764 -426.626924) (xy 39.88887 -426.431176)
			(xy 39.817532 -426.232549) (xy 39.753855 -426.031336) (xy 39.697931 -425.827832) (xy 39.649843 -425.622335)
			(xy 39.609661 -425.415147) (xy 39.577444 -425.206572) (xy 39.553241 -424.996915) (xy 39.537085 -424.786486)
			(xy 39.529001 -424.575592) (xy 39.528496 -424.470068) (xy 7.00913 -424.470068) (xy 7.00913 -430.889918)
			(xy 58.118502 -430.889918) (xy 58.119027 -430.857363) (xy 58.12697 -430.792739) (xy 58.142751 -430.72957)
			(xy 58.166134 -430.668804) (xy 58.196768 -430.611351) (xy 58.234193 -430.558072) (xy 58.27785 -430.509766)
			(xy 58.302144 -430.48809) (xy 58.382916 -430.323244) (xy 58.387643 -430.312738) (xy 58.391123 -430.289973)
			(xy 58.387627 -430.267211) (xy 58.382916 -430.256696) (xy 58.30189 -430.091596) (xy 58.277644 -430.069882)
			(xy 58.234046 -430.021552) (xy 58.19667 -429.968265) (xy 58.166075 -429.910815) (xy 58.142717 -429.850062)
			(xy 58.126945 -429.786913) (xy 58.118996 -429.722312) (xy 58.118502 -429.689768) (xy 58.11923 -429.650443)
			(xy 58.130834 -429.572653) (xy 58.141616 -429.534828) (xy 58.141616 -429.018954) (xy 58.142068 -429.006864)
			(xy 58.149534 -428.983866) (xy 58.163726 -428.964289) (xy 58.18326 -428.950039) (xy 58.206236 -428.942504)
			(xy 58.218324 -428.941992) (xy 59.158124 -428.941992) (xy 59.170233 -428.942396) (xy 59.19326 -428.949901)
			(xy 59.212832 -428.964166) (xy 59.227026 -428.983789) (xy 59.234448 -429.006843) (xy 59.234832 -429.018954)
			(xy 59.234832 -431.560478) (xy 59.234373 -431.572569) (xy 59.226919 -431.595574) (xy 59.212732 -431.615156)
			(xy 59.193194 -431.629407) (xy 59.170214 -431.636934) (xy 59.158124 -431.63744) (xy 58.218324 -431.63744)
			(xy 58.20622 -431.636964) (xy 58.183201 -431.629476) (xy 58.163631 -431.615228) (xy 58.149434 -431.595622)
			(xy 58.142005 -431.572583) (xy 58.141616 -431.560478) (xy 58.141616 -431.044858) (xy 58.130821 -431.007035)
			(xy 58.119212 -430.929244) (xy 58.118502 -430.889918) (xy 7.00913 -430.889918) (xy 7.00913 -431.889916)
			(xy 60.118498 -431.889916) (xy 60.119023 -431.857361) (xy 60.126966 -431.792737) (xy 60.142747 -431.729569)
			(xy 60.16613 -431.668802) (xy 60.196764 -431.611349) (xy 60.234189 -431.55807) (xy 60.277846 -431.509764)
			(xy 60.30214 -431.488088) (xy 60.382912 -431.323242) (xy 60.387641 -431.312736) (xy 60.391121 -431.289971)
			(xy 60.387624 -431.267209) (xy 60.382912 -431.256694) (xy 60.301886 -431.091594) (xy 60.277638 -431.069882)
			(xy 60.23404 -431.021552) (xy 60.196665 -430.968264) (xy 60.16607 -430.910814) (xy 60.142712 -430.850061)
			(xy 60.126941 -430.786912) (xy 60.118992 -430.72231) (xy 60.118498 -430.689766) (xy 60.119226 -430.650441)
			(xy 60.13083 -430.572651) (xy 60.141612 -430.534826) (xy 60.141612 -430.018952) (xy 60.142024 -430.006873)
			(xy 60.149502 -429.983901) (xy 60.163711 -429.964363) (xy 60.183262 -429.950171) (xy 60.206241 -429.942713)
			(xy 60.21832 -429.942244) (xy 61.15812 -429.942244) (xy 61.170191 -429.942747) (xy 61.19315 -429.950209)
			(xy 61.212683 -429.964397) (xy 61.226878 -429.983924) (xy 61.234349 -430.006881) (xy 61.234828 -430.018952)
			(xy 61.234828 -430.889918) (xy 62.118494 -430.889918) (xy 62.118988 -430.857362) (xy 62.126932 -430.792736)
			(xy 62.142716 -430.729565) (xy 62.166103 -430.668798) (xy 62.196743 -430.611344) (xy 62.234175 -430.558067)
			(xy 62.277839 -430.509765) (xy 62.302136 -430.48809) (xy 62.382908 -430.323244) (xy 62.387636 -430.312738)
			(xy 62.391116 -430.289973) (xy 62.38762 -430.26721) (xy 62.382908 -430.256696) (xy 62.301882 -430.091596)
			(xy 62.277634 -430.069883) (xy 62.234037 -430.021553) (xy 62.196661 -429.968266) (xy 62.166066 -429.910816)
			(xy 62.142708 -429.850063) (xy 62.126937 -429.786914) (xy 62.118988 -429.722312) (xy 62.118494 -429.689768)
			(xy 62.119222 -429.650443) (xy 62.130827 -429.572653) (xy 62.141608 -429.534828) (xy 62.141608 -429.018954)
			(xy 62.142068 -429.006865) (xy 62.149533 -428.983868) (xy 62.163723 -428.964292) (xy 62.183255 -428.950042)
			(xy 62.206229 -428.942505) (xy 62.218316 -428.941992) (xy 63.158116 -428.941992) (xy 63.170225 -428.942402)
			(xy 63.193251 -428.949905) (xy 63.212824 -428.964169) (xy 63.227018 -428.983791) (xy 63.23444 -429.006844)
			(xy 63.234824 -429.018954) (xy 63.234824 -431.560478) (xy 63.234373 -431.57257) (xy 63.226918 -431.595576)
			(xy 63.212729 -431.615159) (xy 63.193189 -431.629409) (xy 63.170206 -431.636935) (xy 63.158116 -431.63744)
			(xy 62.218316 -431.63744) (xy 62.206212 -431.63697) (xy 62.183192 -431.62948) (xy 62.163622 -431.615231)
			(xy 62.149426 -431.595623) (xy 62.141997 -431.572583) (xy 62.141608 -431.560478) (xy 62.141608 -431.044858)
			(xy 62.130813 -431.007035) (xy 62.119204 -430.929244) (xy 62.118494 -430.889918) (xy 61.234828 -430.889918)
			(xy 61.234828 -431.889916) (xy 64.11849 -431.889916) (xy 64.118984 -431.85736) (xy 64.126928 -431.792734)
			(xy 64.142712 -431.729563) (xy 64.1661 -431.668796) (xy 64.196739 -431.611343) (xy 64.234171 -431.558065)
			(xy 64.277835 -431.509763) (xy 64.302132 -431.488088) (xy 64.382904 -431.323242) (xy 64.387634 -431.312736)
			(xy 64.391114 -431.289971) (xy 64.387616 -431.267208) (xy 64.382904 -431.256694) (xy 64.301878 -431.091594)
			(xy 64.277628 -431.069883) (xy 64.234031 -431.021553) (xy 64.196656 -430.968265) (xy 64.166061 -430.910815)
			(xy 64.142704 -430.850061) (xy 64.126933 -430.786912) (xy 64.118984 -430.72231) (xy 64.11849 -430.689766)
			(xy 64.119218 -430.650441) (xy 64.130822 -430.572651) (xy 64.141604 -430.534826) (xy 64.141604 -430.018952)
			(xy 64.142023 -430.006874) (xy 64.149501 -429.983903) (xy 64.163708 -429.964366) (xy 64.183257 -429.950173)
			(xy 64.206233 -429.942714) (xy 64.218312 -429.942244) (xy 65.158112 -429.942244) (xy 65.170182 -429.942753)
			(xy 65.193142 -429.950213) (xy 65.212674 -429.9644) (xy 65.22687 -429.983926) (xy 65.234341 -430.006882)
			(xy 65.23482 -430.018952) (xy 65.23482 -430.889918) (xy 66.118486 -430.889918) (xy 66.118982 -430.857362)
			(xy 66.126927 -430.792736) (xy 66.14271 -430.729566) (xy 66.166097 -430.668798) (xy 66.196736 -430.611345)
			(xy 66.234168 -430.558067) (xy 66.277831 -430.509765) (xy 66.302128 -430.48809) (xy 66.3829 -430.323244)
			(xy 66.387628 -430.312738) (xy 66.391109 -430.289973) (xy 66.387612 -430.26721) (xy 66.3829 -430.256696)
			(xy 66.301874 -430.091596) (xy 66.277624 -430.069885) (xy 66.234027 -430.021555) (xy 66.196652 -429.968266)
			(xy 66.166057 -429.910816) (xy 66.1427 -429.850063) (xy 66.126929 -429.786914) (xy 66.11898 -429.722312)
			(xy 66.118486 -429.689768) (xy 66.119215 -429.650443) (xy 66.130819 -429.572653) (xy 66.1416 -429.534828)
			(xy 66.1416 -429.018954) (xy 66.142067 -429.006866) (xy 66.149532 -428.983871) (xy 66.16372 -428.964295)
			(xy 66.18325 -428.950044) (xy 66.206222 -428.942507) (xy 66.218308 -428.941992) (xy 67.158108 -428.941992)
			(xy 67.170217 -428.942409) (xy 67.193243 -428.94991) (xy 67.212815 -428.964172) (xy 67.22701 -428.983792)
			(xy 67.234432 -429.006844) (xy 67.234816 -429.018954) (xy 67.234816 -431.560478) (xy 67.234373 -431.572571)
			(xy 67.226917 -431.595578) (xy 67.212726 -431.615162) (xy 67.193184 -431.629412) (xy 67.170199 -431.636937)
			(xy 67.158108 -431.63744) (xy 66.218308 -431.63744) (xy 66.206204 -431.636978) (xy 66.183183 -431.629485)
			(xy 66.163613 -431.615234) (xy 66.149417 -431.595625) (xy 66.141989 -431.572584) (xy 66.1416 -431.560478)
			(xy 66.1416 -431.044858) (xy 66.130805 -431.007035) (xy 66.119196 -430.929244) (xy 66.118486 -430.889918)
			(xy 65.23482 -430.889918) (xy 65.23482 -431.889916) (xy 68.118482 -431.889916) (xy 68.118978 -431.85736)
			(xy 68.126923 -431.792734) (xy 68.142707 -431.729564) (xy 68.166094 -431.668796) (xy 68.196732 -431.611343)
			(xy 68.234164 -431.558066) (xy 68.277827 -431.509763) (xy 68.302124 -431.488088) (xy 68.382896 -431.323242)
			(xy 68.387626 -431.312737) (xy 68.391106 -431.289971) (xy 68.387609 -431.267208) (xy 68.382896 -431.256694)
			(xy 68.30187 -431.091594) (xy 68.277639 -431.069863) (xy 68.234037 -431.021538) (xy 68.196658 -430.968255)
			(xy 68.166059 -430.910808) (xy 68.142699 -430.850057) (xy 68.126926 -430.78691) (xy 68.118976 -430.72231)
			(xy 68.118482 -430.689766) (xy 68.11921 -430.650441) (xy 68.130815 -430.572651) (xy 68.141596 -430.534826)
			(xy 68.141596 -430.018952) (xy 68.142023 -430.006875) (xy 68.149499 -429.983905) (xy 68.163705 -429.964368)
			(xy 68.183252 -429.950176) (xy 68.206226 -429.942715) (xy 68.218304 -429.942244) (xy 69.158104 -429.942244)
			(xy 69.170174 -429.94276) (xy 69.193133 -429.950218) (xy 69.212666 -429.964403) (xy 69.226862 -429.983927)
			(xy 69.234333 -430.006882) (xy 69.234812 -430.018952) (xy 69.234812 -430.889918) (xy 70.118478 -430.889918)
			(xy 70.118977 -430.857362) (xy 70.126921 -430.792736) (xy 70.142705 -430.729566) (xy 70.166091 -430.668799)
			(xy 70.19673 -430.611346) (xy 70.234161 -430.558068) (xy 70.277823 -430.509765) (xy 70.30212 -430.48809)
			(xy 70.382892 -430.323244) (xy 70.38762 -430.312738) (xy 70.391101 -430.289973) (xy 70.387604 -430.26721)
			(xy 70.382892 -430.256696) (xy 70.301866 -430.091596) (xy 70.277635 -430.069865) (xy 70.234033 -430.02154)
			(xy 70.196654 -429.968256) (xy 70.166056 -429.91081) (xy 70.142695 -429.850059) (xy 70.126922 -429.786912)
			(xy 70.118972 -429.722312) (xy 70.118478 -429.689768) (xy 70.119207 -429.650443) (xy 70.130811 -429.572653)
			(xy 70.141592 -429.534828) (xy 70.141592 -429.018954) (xy 70.142067 -429.006867) (xy 70.149531 -428.983873)
			(xy 70.163717 -428.964298) (xy 70.183245 -428.950047) (xy 70.206214 -428.942508) (xy 70.2183 -428.941992)
			(xy 71.1581 -428.941992) (xy 71.170208 -428.942416) (xy 71.193234 -428.949914) (xy 71.212807 -428.964174)
			(xy 71.227001 -428.983794) (xy 71.234424 -429.006845) (xy 71.234808 -429.018954) (xy 71.234808 -431.560478)
			(xy 71.234275 -431.572562) (xy 71.22683 -431.595553) (xy 71.212659 -431.61513) (xy 71.193142 -431.629383)
			(xy 71.170182 -431.636924) (xy 71.1581 -431.63744) (xy 70.2183 -431.63744) (xy 70.206195 -431.636984)
			(xy 70.183175 -431.62949) (xy 70.163605 -431.615237) (xy 70.149409 -431.595626) (xy 70.141981 -431.572584)
			(xy 70.141592 -431.560478) (xy 70.141592 -431.044858) (xy 70.130797 -431.007036) (xy 70.119188 -430.929244)
			(xy 70.118478 -430.889918) (xy 69.234812 -430.889918) (xy 69.234812 -431.889916) (xy 72.118474 -431.889916)
			(xy 72.118973 -431.85736) (xy 72.126917 -431.792734) (xy 72.142701 -431.729564) (xy 72.166088 -431.668797)
			(xy 72.196726 -431.611344) (xy 72.234157 -431.558066) (xy 72.277819 -431.509763) (xy 72.302116 -431.488088)
			(xy 72.382888 -431.323242) (xy 72.387618 -431.312736) (xy 72.391099 -431.289971) (xy 72.387601 -431.267208)
			(xy 72.382888 -431.256694) (xy 72.301862 -431.091594) (xy 72.277629 -431.069865) (xy 72.234028 -431.02154)
			(xy 72.196649 -430.968256) (xy 72.166051 -430.910809) (xy 72.142691 -430.850058) (xy 72.126918 -430.78691)
			(xy 72.118968 -430.72231) (xy 72.118474 -430.689766) (xy 72.119203 -430.650441) (xy 72.130807 -430.572651)
			(xy 72.141588 -430.534826) (xy 72.141588 -430.018952) (xy 72.142023 -430.006875) (xy 72.149498 -429.983907)
			(xy 72.163703 -429.964371) (xy 72.183247 -429.950178) (xy 72.206219 -429.942716) (xy 72.218296 -429.942244)
			(xy 73.158096 -429.942244) (xy 73.170166 -429.942767) (xy 73.193124 -429.950222) (xy 73.212657 -429.964406)
			(xy 73.226854 -429.983929) (xy 73.234325 -430.006883) (xy 73.234804 -430.018952) (xy 73.234804 -430.889918)
			(xy 75.118468 -430.889918) (xy 75.118971 -430.857362) (xy 75.126915 -430.792737) (xy 75.142698 -430.729567)
			(xy 75.166084 -430.668799) (xy 75.196722 -430.611346) (xy 75.234152 -430.558069) (xy 75.277814 -430.509765)
			(xy 75.30211 -430.48809) (xy 75.382882 -430.323244) (xy 75.387611 -430.312738) (xy 75.391092 -430.289973)
			(xy 75.387595 -430.26721) (xy 75.382882 -430.256696) (xy 75.301856 -430.091596) (xy 75.277623 -430.069867)
			(xy 75.234022 -430.021542) (xy 75.196643 -429.968258) (xy 75.166045 -429.910811) (xy 75.142685 -429.850059)
			(xy 75.126912 -429.786912) (xy 75.118962 -429.722312) (xy 75.118468 -429.689768) (xy 75.11916 -429.650641)
			(xy 75.13064 -429.573235) (xy 75.141328 -429.53559) (xy 75.141328 -429.018954) (xy 75.141772 -429.006838)
			(xy 75.149271 -428.983795) (xy 75.163521 -428.964195) (xy 75.183127 -428.949955) (xy 75.206174 -428.942467)
			(xy 75.21829 -428.941992) (xy 76.15809 -428.941992) (xy 76.170199 -428.94252) (xy 76.193235 -428.949999)
			(xy 76.212832 -428.964228) (xy 76.227076 -428.983815) (xy 76.234572 -429.006845) (xy 76.235052 -429.018954)
			(xy 76.235052 -431.560478) (xy 76.234621 -431.572601) (xy 76.227134 -431.59566) (xy 76.212885 -431.615277)
			(xy 76.193271 -431.629528) (xy 76.170213 -431.637019) (xy 76.15809 -431.63744) (xy 75.21829 -431.63744)
			(xy 75.206165 -431.637048) (xy 75.183102 -431.62955) (xy 75.163485 -431.615292) (xy 75.149235 -431.59567)
			(xy 75.141747 -431.572604) (xy 75.141328 -431.560478) (xy 75.141328 -431.044096) (xy 75.130645 -431.00645)
			(xy 75.119165 -430.929044) (xy 75.118468 -430.889918) (xy 73.234804 -430.889918) (xy 73.234804 -431.889916)
			(xy 77.118464 -431.889916) (xy 77.118967 -431.85736) (xy 77.126911 -431.792735) (xy 77.142694 -431.729565)
			(xy 77.16608 -431.668798) (xy 77.196718 -431.611344) (xy 77.234148 -431.558067) (xy 77.27781 -431.509763)
			(xy 77.302106 -431.488088) (xy 77.382878 -431.323242) (xy 77.387608 -431.312737) (xy 77.39109 -431.289971)
			(xy 77.387591 -431.267208) (xy 77.382878 -431.256694) (xy 77.301852 -431.091594) (xy 77.277617 -431.069867)
			(xy 77.234016 -431.021541) (xy 77.196638 -430.968257) (xy 77.16604 -430.910809) (xy 77.14268 -430.850058)
			(xy 77.126908 -430.78691) (xy 77.118958 -430.72231) (xy 77.118464 -430.689766) (xy 77.119155 -430.650639)
			(xy 77.130636 -430.573233) (xy 77.141324 -430.535588) (xy 77.141324 -430.018952) (xy 77.141676 -430.006838)
			(xy 77.149191 -429.983805) (xy 77.163469 -429.964231) (xy 77.183105 -429.950039) (xy 77.20617 -429.942624)
			(xy 77.218286 -429.942244) (xy 78.158086 -429.942244) (xy 78.170175 -429.942719) (xy 78.193176 -429.950173)
			(xy 78.212757 -429.964357) (xy 78.227007 -429.983889) (xy 78.234539 -430.006864) (xy 78.235048 -430.018952)
			(xy 78.235048 -430.889918) (xy 79.11846 -430.889918) (xy 79.118965 -430.857362) (xy 79.126909 -430.792737)
			(xy 79.142692 -430.729567) (xy 79.166078 -430.6688) (xy 79.196715 -430.611347) (xy 79.234145 -430.558069)
			(xy 79.277806 -430.509765) (xy 79.302102 -430.48809) (xy 79.382874 -430.323244) (xy 79.387603 -430.312738)
			(xy 79.391085 -430.289973) (xy 79.387587 -430.26721) (xy 79.382874 -430.256696) (xy 79.301848 -430.091596)
			(xy 79.277613 -430.069869) (xy 79.234013 -430.021543) (xy 79.196634 -429.968258) (xy 79.166036 -429.910811)
			(xy 79.142677 -429.85006) (xy 79.126904 -429.786912) (xy 79.118954 -429.722312) (xy 79.11846 -429.689768)
			(xy 79.119152 -429.650641) (xy 79.130632 -429.573235) (xy 79.14132 -429.53559) (xy 79.14132 -429.018954)
			(xy 79.141772 -429.006839) (xy 79.14927 -428.983797) (xy 79.163518 -428.964198) (xy 79.183122 -428.949957)
			(xy 79.206167 -428.942468) (xy 79.218282 -428.941992) (xy 80.158082 -428.941992) (xy 80.170191 -428.942526)
			(xy 80.193226 -428.950003) (xy 80.212824 -428.964231) (xy 80.227068 -428.983817) (xy 80.234563 -429.006845)
			(xy 80.235044 -429.018954) (xy 80.235044 -431.560478) (xy 80.234621 -431.572601) (xy 80.227133 -431.595663)
			(xy 80.212882 -431.61528) (xy 80.193266 -431.629531) (xy 80.170205 -431.63702) (xy 80.158082 -431.63744)
			(xy 79.218282 -431.63744) (xy 79.206156 -431.637055) (xy 79.183093 -431.629555) (xy 79.163476 -431.615295)
			(xy 79.149227 -431.595671) (xy 79.141739 -431.572604) (xy 79.14132 -431.560478) (xy 79.14132 -431.044096)
			(xy 79.130637 -431.00645) (xy 79.119157 -430.929044) (xy 79.11846 -430.889918) (xy 78.235048 -430.889918)
			(xy 78.235048 -431.889916) (xy 81.118456 -431.889916) (xy 81.118961 -431.85736) (xy 81.126905 -431.792735)
			(xy 81.142688 -431.729565) (xy 81.166074 -431.668798) (xy 81.196711 -431.611345) (xy 81.234141 -431.558067)
			(xy 81.277802 -431.509763) (xy 81.302098 -431.488088) (xy 81.38287 -431.323242) (xy 81.387601 -431.312737)
			(xy 81.391082 -431.289971) (xy 81.387584 -431.267208) (xy 81.38287 -431.256694) (xy 81.301844 -431.091594)
			(xy 81.277608 -431.069869) (xy 81.234007 -431.021543) (xy 81.196629 -430.968257) (xy 81.166031 -430.91081)
			(xy 81.142672 -430.850058) (xy 81.1269 -430.78691) (xy 81.11895 -430.72231) (xy 81.118456 -430.689766)
			(xy 81.119148 -430.650639) (xy 81.130628 -430.573233) (xy 81.141316 -430.535588) (xy 81.141316 -430.018952)
			(xy 81.141676 -430.006839) (xy 81.14919 -429.983807) (xy 81.163466 -429.964234) (xy 81.1831 -429.950041)
			(xy 81.206163 -429.942625) (xy 81.218278 -429.942244) (xy 82.158078 -429.942244) (xy 82.170167 -429.942726)
			(xy 82.193167 -429.950177) (xy 82.212748 -429.96436) (xy 82.226999 -429.983891) (xy 82.234531 -430.006865)
			(xy 82.23504 -430.018952) (xy 82.23504 -430.889918) (xy 83.118452 -430.889918) (xy 83.11896 -430.857362)
			(xy 83.126904 -430.792737) (xy 83.142686 -430.729568) (xy 83.166072 -430.668801) (xy 83.196709 -430.611347)
			(xy 83.234138 -430.558069) (xy 83.277798 -430.509766) (xy 83.302094 -430.48809) (xy 83.382866 -430.323244)
			(xy 83.387591 -430.312737) (xy 83.391068 -430.289973) (xy 83.387574 -430.267211) (xy 83.382866 -430.256696)
			(xy 83.30184 -430.091596) (xy 83.277604 -430.069871) (xy 83.234003 -430.021544) (xy 83.196625 -429.968259)
			(xy 83.166028 -429.910812) (xy 83.142668 -429.85006) (xy 83.126896 -429.786912) (xy 83.118946 -429.722312)
			(xy 83.118452 -429.689768) (xy 83.119144 -429.650641) (xy 83.130624 -429.573235) (xy 83.141312 -429.53559)
			(xy 83.141312 -429.018954) (xy 83.141772 -429.00684) (xy 83.149269 -428.983799) (xy 83.163515 -428.964201)
			(xy 83.183117 -428.94996) (xy 83.20616 -428.942469) (xy 83.218274 -428.941992) (xy 84.158074 -428.941992)
			(xy 84.170183 -428.942533) (xy 84.193217 -428.950008) (xy 84.212815 -428.964233) (xy 84.227059 -428.983818)
			(xy 84.234555 -429.006846) (xy 84.235036 -429.018954) (xy 84.235036 -431.560478) (xy 84.234621 -431.572602)
			(xy 84.227132 -431.595665) (xy 84.21288 -431.615282) (xy 84.193261 -431.629533) (xy 84.170198 -431.637022)
			(xy 84.158074 -431.63744) (xy 83.218274 -431.63744) (xy 83.206156 -431.63701) (xy 83.183108 -431.629513)
			(xy 83.163505 -431.615261) (xy 83.149265 -431.595649) (xy 83.141782 -431.572596) (xy 83.141312 -431.560478)
			(xy 83.141312 -431.044096) (xy 83.130629 -431.00645) (xy 83.119149 -430.929044) (xy 83.118452 -430.889918)
			(xy 82.23504 -430.889918) (xy 82.23504 -431.889916) (xy 85.118448 -431.889916) (xy 85.118956 -431.85736)
			(xy 85.1269 -431.792735) (xy 85.142683 -431.729566) (xy 85.166068 -431.668799) (xy 85.196705 -431.611346)
			(xy 85.234134 -431.558068) (xy 85.277794 -431.509764) (xy 85.30209 -431.488088) (xy 85.382862 -431.323242)
			(xy 85.387588 -431.312736) (xy 85.391066 -431.289971) (xy 85.387571 -431.267209) (xy 85.382862 -431.256694)
			(xy 85.301836 -431.091594) (xy 85.277598 -431.069871) (xy 85.233998 -431.021544) (xy 85.19662 -430.968258)
			(xy 85.166023 -430.91081) (xy 85.142664 -430.850059) (xy 85.126892 -430.786911) (xy 85.118942 -430.72231)
			(xy 85.118448 -430.689766) (xy 85.11914 -430.650639) (xy 85.13062 -430.573233) (xy 85.141308 -430.535588)
			(xy 85.141308 -430.018952) (xy 85.141676 -430.00684) (xy 85.149189 -429.98381) (xy 85.163463 -429.964237)
			(xy 85.183095 -429.950044) (xy 85.206156 -429.942626) (xy 85.21827 -429.942244) (xy 86.15807 -429.942244)
			(xy 86.170158 -429.942733) (xy 86.193159 -429.950182) (xy 86.212739 -429.964363) (xy 86.226991 -429.983892)
			(xy 86.234523 -430.006865) (xy 86.235032 -430.018952) (xy 86.235032 -430.889918) (xy 87.118444 -430.889918)
			(xy 87.118955 -430.857362) (xy 87.126898 -430.792738) (xy 87.142681 -430.729568) (xy 87.166066 -430.668801)
			(xy 87.196702 -430.611348) (xy 87.234131 -430.55807) (xy 87.277791 -430.509766) (xy 87.302086 -430.48809)
			(xy 87.382858 -430.323244) (xy 87.387583 -430.312737) (xy 87.391061 -430.289973) (xy 87.387567 -430.267211)
			(xy 87.382858 -430.256696) (xy 87.301832 -430.091596) (xy 87.277594 -430.069872) (xy 87.233994 -430.021546)
			(xy 87.196616 -429.96826) (xy 87.166019 -429.910812) (xy 87.14266 -429.85006) (xy 87.126888 -429.786912)
			(xy 87.118938 -429.722312) (xy 87.118444 -429.689768) (xy 87.119137 -429.650641) (xy 87.130616 -429.573235)
			(xy 87.141304 -429.53559) (xy 87.141304 -429.018954) (xy 87.141772 -429.00684) (xy 87.149268 -428.983801)
			(xy 87.163512 -428.964203) (xy 87.183112 -428.949962) (xy 87.206152 -428.94247) (xy 87.218266 -428.941992)
			(xy 88.158066 -428.941992) (xy 88.170174 -428.94254) (xy 88.193209 -428.950012) (xy 88.212807 -428.964236)
			(xy 88.227051 -428.98382) (xy 88.234547 -429.006846) (xy 88.235028 -429.018954) (xy 88.235028 -431.560478)
			(xy 88.234621 -431.572603) (xy 88.22713 -431.595667) (xy 88.212877 -431.615285) (xy 88.193256 -431.629536)
			(xy 88.170191 -431.637023) (xy 88.158066 -431.63744) (xy 87.218266 -431.63744) (xy 87.206147 -431.637017)
			(xy 87.183099 -431.629518) (xy 87.163496 -431.615264) (xy 87.149257 -431.59565) (xy 87.141774 -431.572597)
			(xy 87.141304 -431.560478) (xy 87.141304 -431.044096) (xy 87.13062 -431.00645) (xy 87.119141 -430.929044)
			(xy 87.118444 -430.889918) (xy 86.235032 -430.889918) (xy 86.235032 -431.889916) (xy 89.11844 -431.889916)
			(xy 89.118951 -431.85736) (xy 89.126895 -431.792736) (xy 89.142677 -431.729566) (xy 89.166062 -431.668799)
			(xy 89.196698 -431.611346) (xy 89.234127 -431.558068) (xy 89.277787 -431.509764) (xy 89.302082 -431.488088)
			(xy 89.382854 -431.323242) (xy 89.387581 -431.312736) (xy 89.391058 -431.289971) (xy 89.387563 -431.267209)
			(xy 89.382854 -431.256694) (xy 89.301828 -431.091594) (xy 89.277588 -431.069872) (xy 89.233989 -431.021545)
			(xy 89.196611 -430.968259) (xy 89.166014 -430.910811) (xy 89.142655 -430.850059) (xy 89.126883 -430.786911)
			(xy 89.118934 -430.72231) (xy 89.11844 -430.689766) (xy 89.119132 -430.650639) (xy 89.130612 -430.573233)
			(xy 89.1413 -430.535588) (xy 89.1413 -430.018952) (xy 89.141676 -430.006841) (xy 89.149188 -429.983812)
			(xy 89.16346 -429.96424) (xy 89.18309 -429.950047) (xy 89.206149 -429.942627) (xy 89.218262 -429.942244)
			(xy 90.158062 -429.942244) (xy 90.17015 -429.94274) (xy 90.19315 -429.950187) (xy 90.212731 -429.964366)
			(xy 90.226983 -429.983894) (xy 90.234515 -430.006866) (xy 90.235024 -430.018952) (xy 90.235024 -431.360072)
			(xy 108.40466 -431.360072) (xy 108.405158 -431.275192) (xy 108.413115 -431.105619) (xy 108.429011 -430.936605)
			(xy 108.452812 -430.768522) (xy 108.484466 -430.601739) (xy 108.523902 -430.436623) (xy 108.571034 -430.273538)
			(xy 108.625758 -430.11284) (xy 108.687955 -429.954885) (xy 108.757487 -429.800018) (xy 108.834202 -429.648581)
			(xy 108.91793 -429.500905) (xy 109.008488 -429.357317) (xy 109.105677 -429.218131) (xy 109.209284 -429.083654)
			(xy 109.319079 -428.954181) (xy 109.434823 -428.829996) (xy 109.55626 -428.711373) (xy 109.683124 -428.598572)
			(xy 109.815135 -428.491842) (xy 109.952005 -428.391417) (xy 110.09343 -428.297518) (xy 110.239102 -428.21035)
			(xy 110.3887 -428.130107) (xy 110.541894 -428.056963) (xy 110.698348 -427.991081) (xy 110.857718 -427.932604)
			(xy 111.019654 -427.881662) (xy 111.1838 -427.838366) (xy 111.349795 -427.802811) (xy 111.517274 -427.775076)
			(xy 111.685869 -427.755222) (xy 111.855209 -427.743292) (xy 112.024922 -427.739313) (xy 112.194635 -427.743292)
			(xy 112.363975 -427.755222) (xy 112.53257 -427.775076) (xy 112.700049 -427.802811) (xy 112.866044 -427.838366)
			(xy 113.03019 -427.881662) (xy 113.192126 -427.932604) (xy 113.351496 -427.991081) (xy 113.50795 -428.056963)
			(xy 113.661144 -428.130107) (xy 113.810742 -428.21035) (xy 113.943382 -428.28972) (xy 127.21844 -428.28972)
			(xy 127.218962 -428.25714) (xy 127.226934 -428.192469) (xy 127.242748 -428.129258) (xy 127.266169 -428.068452)
			(xy 127.296844 -428.010964) (xy 127.334314 -427.957655) (xy 127.378018 -427.909325) (xy 127.402336 -427.887638)
			(xy 127.482854 -427.7233) (xy 127.487541 -427.712778) (xy 127.491033 -427.690023) (xy 127.487555 -427.667267)
			(xy 127.482854 -427.656752) (xy 127.401828 -427.491652) (xy 127.377568 -427.469952) (xy 127.33397 -427.421621)
			(xy 127.296594 -427.368331) (xy 127.266 -427.310879) (xy 127.242644 -427.250124) (xy 127.226876 -427.186972)
			(xy 127.218931 -427.122369) (xy 127.21844 -427.089824) (xy 127.219145 -427.050698) (xy 127.230616 -426.973291)
			(xy 127.2413 -426.935646) (xy 127.2413 -426.41901) (xy 127.24182 -426.4069) (xy 127.2493 -426.383863)
			(xy 127.263531 -426.364265) (xy 127.28312 -426.350022) (xy 127.306152 -426.342527) (xy 127.318262 -426.342048)
			(xy 128.258062 -426.342048) (xy 128.270184 -426.342492) (xy 128.293243 -426.349975) (xy 128.31286 -426.36422)
			(xy 128.327112 -426.383832) (xy 128.334603 -426.406888) (xy 128.335024 -426.41901) (xy 128.335024 -427.289976)
			(xy 129.218436 -427.289976) (xy 129.21892 -427.25742) (xy 129.226868 -427.192794) (xy 129.242656 -427.129624)
			(xy 129.266045 -427.068857) (xy 129.296685 -427.011404) (xy 129.334118 -426.958126) (xy 129.377781 -426.909823)
			(xy 129.402078 -426.888148) (xy 129.48285 -426.723302) (xy 129.487536 -426.71278) (xy 129.491028 -426.690025)
			(xy 129.487551 -426.667269) (xy 129.48285 -426.656754) (xy 129.401824 -426.491654) (xy 129.377564 -426.469954)
			(xy 129.333966 -426.421623) (xy 129.29659 -426.368333) (xy 129.265996 -426.310881) (xy 129.242641 -426.250126)
			(xy 129.226873 -426.186974) (xy 129.218928 -426.122371) (xy 129.218436 -426.089826) (xy 129.219142 -426.0507)
			(xy 129.230612 -425.973294) (xy 129.241296 -425.935648) (xy 129.241296 -425.419012) (xy 129.241727 -425.406904)
			(xy 129.249222 -425.383878) (xy 129.26348 -425.364305) (xy 129.283099 -425.35011) (xy 129.306149 -425.342688)
			(xy 129.318258 -425.342304) (xy 130.258058 -425.342304) (xy 130.270142 -425.342842) (xy 130.293135 -425.350283)
			(xy 130.312713 -425.364453) (xy 130.326966 -425.383969) (xy 130.334505 -425.40693) (xy 130.33502 -425.419012)
			(xy 130.33502 -427.960536) (xy 130.334615 -427.972645) (xy 130.327108 -427.99567) (xy 130.312843 -428.01524)
			(xy 130.29322 -428.029435) (xy 130.270168 -428.036858) (xy 130.258058 -428.037244) (xy 129.318258 -428.037244)
			(xy 129.306165 -428.036828) (xy 129.28316 -428.029358) (xy 129.263579 -428.015159) (xy 129.249331 -427.995614)
			(xy 129.241803 -427.972628) (xy 129.241296 -427.960536) (xy 129.241296 -427.444154) (xy 129.230603 -427.40651)
			(xy 129.21913 -427.329103) (xy 129.218436 -427.289976) (xy 128.335024 -427.289976) (xy 128.335024 -428.28972)
			(xy 131.218432 -428.28972) (xy 131.218956 -428.25714) (xy 131.226928 -428.19247) (xy 131.242743 -428.129258)
			(xy 131.266163 -428.068453) (xy 131.296838 -428.010965) (xy 131.334307 -427.957656) (xy 131.37801 -427.909325)
			(xy 131.402328 -427.887638) (xy 131.482846 -427.7233) (xy 131.487533 -427.712778) (xy 131.491026 -427.690023)
			(xy 131.487547 -427.667267) (xy 131.482846 -427.656752) (xy 131.40182 -427.491652) (xy 131.377558 -427.469954)
			(xy 131.33396 -427.421622) (xy 131.296585 -427.368332) (xy 131.265991 -427.31088) (xy 131.242636 -427.250124)
			(xy 131.226868 -427.186973) (xy 131.218923 -427.122369) (xy 131.218432 -427.089824) (xy 131.219137 -427.050698)
			(xy 131.230608 -426.973291) (xy 131.241292 -426.935646) (xy 131.241292 -426.41901) (xy 131.24182 -426.406901)
			(xy 131.249299 -426.383865) (xy 131.263528 -426.364268) (xy 131.283115 -426.350024) (xy 131.306145 -426.342528)
			(xy 131.318254 -426.342048) (xy 132.258054 -426.342048) (xy 132.270175 -426.342499) (xy 132.293234 -426.34998)
			(xy 132.312851 -426.364223) (xy 132.327104 -426.383833) (xy 132.334595 -426.406889) (xy 132.335016 -426.41901)
			(xy 132.335016 -427.289976) (xy 133.218428 -427.289976) (xy 133.218915 -427.25742) (xy 133.226863 -427.192794)
			(xy 133.24265 -427.129624) (xy 133.266039 -427.068857) (xy 133.296679 -427.011404) (xy 133.334111 -426.958127)
			(xy 133.377773 -426.909823) (xy 133.40207 -426.888148) (xy 133.482842 -426.723302) (xy 133.487528 -426.71278)
			(xy 133.491021 -426.690025) (xy 133.487543 -426.667269) (xy 133.482842 -426.656754) (xy 133.401816 -426.491654)
			(xy 133.377555 -426.469956) (xy 133.333957 -426.421624) (xy 133.296582 -426.368334) (xy 133.265988 -426.310882)
			(xy 133.242632 -426.250126) (xy 133.226865 -426.186975) (xy 133.21892 -426.122371) (xy 133.218428 -426.089826)
			(xy 133.219134 -426.0507) (xy 133.230605 -425.973294) (xy 133.241288 -425.935648) (xy 133.241288 -425.419012)
			(xy 133.241727 -425.406905) (xy 133.249221 -425.38388) (xy 133.263477 -425.364308) (xy 133.283094 -425.350113)
			(xy 133.306142 -425.342689) (xy 133.31825 -425.342304) (xy 134.25805 -425.342304) (xy 134.270133 -425.342849)
			(xy 134.293126 -425.350288) (xy 134.312704 -425.364455) (xy 134.326958 -425.383971) (xy 134.334497 -425.406931)
			(xy 134.335012 -425.419012) (xy 134.335012 -427.960536) (xy 134.334614 -427.972646) (xy 134.327107 -427.995672)
			(xy 134.31284 -428.015243) (xy 134.293215 -428.029437) (xy 134.270161 -428.036859) (xy 134.25805 -428.037244)
			(xy 133.31825 -428.037244) (xy 133.306161 -428.03675) (xy 133.28316 -428.029305) (xy 133.263578 -428.015126)
			(xy 133.249326 -427.995597) (xy 133.241795 -427.972623) (xy 133.241288 -427.960536) (xy 133.241288 -427.444154)
			(xy 133.230595 -427.406511) (xy 133.219122 -427.329103) (xy 133.218428 -427.289976) (xy 132.335016 -427.289976)
			(xy 132.335016 -428.28972) (xy 135.218424 -428.28972) (xy 135.218951 -428.25714) (xy 135.226923 -428.19247)
			(xy 135.242737 -428.129259) (xy 135.266157 -428.068453) (xy 135.296831 -428.010965) (xy 135.3343 -427.957656)
			(xy 135.378002 -427.909325) (xy 135.40232 -427.887638) (xy 135.482838 -427.7233) (xy 135.487526 -427.712778)
			(xy 135.491018 -427.690023) (xy 135.48754 -427.667267) (xy 135.482838 -427.656752) (xy 135.401812 -427.491652)
			(xy 135.377549 -427.469956) (xy 135.333951 -427.421624) (xy 135.296576 -427.368333) (xy 135.265983 -427.310881)
			(xy 135.242628 -427.250125) (xy 135.22686 -427.186973) (xy 135.218915 -427.122369) (xy 135.218424 -427.089824)
			(xy 135.21913 -427.050698) (xy 135.230601 -426.973292) (xy 135.241284 -426.935646) (xy 135.241284 -426.41901)
			(xy 135.241669 -426.406883) (xy 135.249164 -426.383817) (xy 135.263423 -426.364198) (xy 135.283049 -426.349948)
			(xy 135.306119 -426.342464) (xy 135.318246 -426.342048) (xy 136.258046 -426.342048) (xy 136.270164 -426.342473)
			(xy 136.29321 -426.349974) (xy 136.312812 -426.364228) (xy 136.327052 -426.38384) (xy 136.334536 -426.406892)
			(xy 136.335008 -426.41901) (xy 136.335008 -427.289976) (xy 137.21842 -427.289976) (xy 137.218909 -427.25742)
			(xy 137.226858 -427.192794) (xy 137.242644 -427.129625) (xy 137.266033 -427.068858) (xy 137.296672 -427.011405)
			(xy 137.334103 -426.958127) (xy 137.377765 -426.909823) (xy 137.402062 -426.888148) (xy 137.482834 -426.723302)
			(xy 137.48752 -426.71278) (xy 137.491014 -426.690025) (xy 137.487536 -426.667268) (xy 137.482834 -426.656754)
			(xy 137.401808 -426.491654) (xy 137.377545 -426.469958) (xy 137.333947 -426.421625) (xy 137.296573 -426.368335)
			(xy 137.265979 -426.310882) (xy 137.242624 -426.250126) (xy 137.226856 -426.186975) (xy 137.218912 -426.122371)
			(xy 137.21842 -426.089826) (xy 137.219126 -426.0507) (xy 137.230597 -425.973294) (xy 137.24128 -425.935648)
			(xy 137.24128 -425.419012) (xy 137.241727 -425.406906) (xy 137.24922 -425.383882) (xy 137.263475 -425.364311)
			(xy 137.283089 -425.350115) (xy 137.306135 -425.342691) (xy 137.318242 -425.342304) (xy 138.258042 -425.342304)
			(xy 138.27013 -425.342771) (xy 138.293126 -425.350235) (xy 138.312702 -425.364423) (xy 138.326953 -425.383953)
			(xy 138.33449 -425.406925) (xy 138.335004 -425.419012) (xy 138.335004 -427.960536) (xy 138.334614 -427.972646)
			(xy 138.327106 -427.995674) (xy 138.312837 -428.015246) (xy 138.29321 -428.02944) (xy 138.270154 -428.03686)
			(xy 138.258042 -428.037244) (xy 137.318242 -428.037244) (xy 137.306153 -428.036757) (xy 137.283151 -428.029309)
			(xy 137.263569 -428.015129) (xy 137.249318 -427.995598) (xy 137.241787 -427.972623) (xy 137.24128 -427.960536)
			(xy 137.24128 -427.444154) (xy 137.230587 -427.406511) (xy 137.219114 -427.329103) (xy 137.21842 -427.289976)
			(xy 136.335008 -427.289976) (xy 136.335008 -428.28972) (xy 139.218416 -428.28972) (xy 139.218946 -428.25714)
			(xy 139.226917 -428.19247) (xy 139.242731 -428.129259) (xy 139.266151 -428.068454) (xy 139.296825 -428.010966)
			(xy 139.334293 -427.957657) (xy 139.377995 -427.909325) (xy 139.402312 -427.887638) (xy 139.48283 -427.7233)
			(xy 139.487518 -427.712778) (xy 139.491011 -427.690023) (xy 139.487532 -427.667266) (xy 139.48283 -427.656752)
			(xy 139.401804 -427.491652) (xy 139.377539 -427.469958) (xy 139.333942 -427.421625) (xy 139.296568 -427.368334)
			(xy 139.265974 -427.310881) (xy 139.24262 -427.250125) (xy 139.226852 -427.186973) (xy 139.218907 -427.122369)
			(xy 139.218416 -427.089824) (xy 139.219118 -427.050698) (xy 139.230591 -426.973291) (xy 139.241276 -426.935646)
			(xy 139.241276 -426.41901) (xy 139.241669 -426.406884) (xy 139.249163 -426.383819) (xy 139.26342 -426.364201)
			(xy 139.283044 -426.34995) (xy 139.306112 -426.342465) (xy 139.318238 -426.342048) (xy 140.258038 -426.342048)
			(xy 140.270156 -426.342479) (xy 140.293202 -426.349978) (xy 140.312804 -426.36423) (xy 140.327044 -426.383841)
			(xy 140.334528 -426.406892) (xy 140.335 -426.41901) (xy 140.335 -427.289976) (xy 142.21841 -427.289976)
			(xy 142.218903 -427.25742) (xy 142.226851 -427.192795) (xy 142.242637 -427.129625) (xy 142.266025 -427.068859)
			(xy 142.296664 -427.011406) (xy 142.334095 -426.958128) (xy 142.377756 -426.909824) (xy 142.402052 -426.888148)
			(xy 142.482824 -426.723302) (xy 142.487511 -426.71278) (xy 142.491005 -426.690025) (xy 142.487526 -426.667268)
			(xy 142.482824 -426.656754) (xy 142.401798 -426.491654) (xy 142.377533 -426.46996) (xy 142.333936 -426.421627)
			(xy 142.296562 -426.368336) (xy 142.265969 -426.310883) (xy 142.242614 -426.250127) (xy 142.226846 -426.186975)
			(xy 142.218902 -426.122371) (xy 142.21841 -426.089826) (xy 142.219128 -426.050501) (xy 142.230739 -425.972711)
			(xy 142.241524 -425.934886) (xy 142.241524 -425.419012) (xy 142.241924 -425.406927) (xy 142.249392 -425.383939)
			(xy 142.2636 -425.364386) (xy 142.283157 -425.350183) (xy 142.306147 -425.34272) (xy 142.318232 -425.342304)
			(xy 143.258032 -425.342304) (xy 143.270109 -425.342737) (xy 143.29308 -425.35021) (xy 143.312617 -425.364414)
			(xy 143.32681 -425.38396) (xy 143.33427 -425.406934) (xy 143.33474 -425.419012) (xy 143.33474 -427.960536)
			(xy 143.334267 -427.972609) (xy 143.326799 -427.995572) (xy 143.312603 -428.015106) (xy 143.293069 -428.0293)
			(xy 143.270105 -428.036768) (xy 143.258032 -428.037244) (xy 142.318232 -428.037244) (xy 142.306163 -428.036709)
			(xy 142.283203 -428.02926) (xy 142.263668 -428.01508) (xy 142.249471 -427.995558) (xy 142.242001 -427.972605)
			(xy 142.241524 -427.960536) (xy 142.241524 -427.444916) (xy 142.23072 -427.407096) (xy 142.219117 -427.329303)
			(xy 142.21841 -427.289976) (xy 140.335 -427.289976) (xy 140.335 -428.28972) (xy 144.218406 -428.28972)
			(xy 144.218939 -428.257141) (xy 144.226911 -428.192471) (xy 144.242724 -428.12926) (xy 144.266143 -428.068455)
			(xy 144.296817 -428.010967) (xy 144.334284 -427.957657) (xy 144.377985 -427.909326) (xy 144.402302 -427.887638)
			(xy 144.48282 -427.7233) (xy 144.487509 -427.712779) (xy 144.491002 -427.690023) (xy 144.487523 -427.667266)
			(xy 144.48282 -427.656752) (xy 144.401794 -427.491652) (xy 144.377527 -427.46996) (xy 144.33393 -427.421626)
			(xy 144.296556 -427.368335) (xy 144.265964 -427.310882) (xy 144.242609 -427.250125) (xy 144.226842 -427.186973)
			(xy 144.218897 -427.122369) (xy 144.218406 -427.089824) (xy 144.219124 -427.050499) (xy 144.230735 -426.972709)
			(xy 144.24152 -426.934884) (xy 144.24152 -426.41901) (xy 144.242016 -426.406923) (xy 144.249467 -426.383926)
			(xy 144.263647 -426.364348) (xy 144.283173 -426.350096) (xy 144.306143 -426.34256) (xy 144.318228 -426.342048)
			(xy 145.258028 -426.342048) (xy 145.270133 -426.342492) (xy 145.293152 -426.349993) (xy 145.312721 -426.364249)
			(xy 145.326916 -426.383861) (xy 145.334345 -426.406904) (xy 145.334736 -426.41901) (xy 145.334736 -427.289976)
			(xy 146.218402 -427.289976) (xy 146.218898 -427.25742) (xy 146.226845 -427.192795) (xy 146.242632 -427.129626)
			(xy 146.266019 -427.068859) (xy 146.296658 -427.011406) (xy 146.334088 -426.958128) (xy 146.377748 -426.909824)
			(xy 146.402044 -426.888148) (xy 146.482816 -426.723302) (xy 146.487503 -426.71278) (xy 146.490997 -426.690025)
			(xy 146.487518 -426.667268) (xy 146.482816 -426.656754) (xy 146.40179 -426.491654) (xy 146.377523 -426.469962)
			(xy 146.333927 -426.421628) (xy 146.296553 -426.368337) (xy 146.26596 -426.310884) (xy 146.242606 -426.250127)
			(xy 146.226838 -426.186975) (xy 146.218894 -426.122371) (xy 146.218402 -426.089826) (xy 146.219121 -426.050501)
			(xy 146.230731 -425.972711) (xy 146.241516 -425.934886) (xy 146.241516 -425.419012) (xy 146.241923 -425.406928)
			(xy 146.249391 -425.383941) (xy 146.263597 -425.364389) (xy 146.283152 -425.350185) (xy 146.306139 -425.342722)
			(xy 146.318224 -425.342304) (xy 147.258024 -425.342304) (xy 147.270101 -425.342744) (xy 147.293071 -425.350215)
			(xy 147.312609 -425.364417) (xy 147.326802 -425.383961) (xy 147.334261 -425.406935) (xy 147.334732 -425.419012)
			(xy 147.334732 -427.960536) (xy 147.334267 -427.97261) (xy 147.326798 -427.995574) (xy 147.3126 -428.015109)
			(xy 147.293064 -428.029303) (xy 147.270098 -428.036769) (xy 147.258024 -428.037244) (xy 146.318224 -428.037244)
			(xy 146.306154 -428.036716) (xy 146.283194 -428.029264) (xy 146.26366 -428.015083) (xy 146.249463 -427.99556)
			(xy 146.241993 -427.972605) (xy 146.241516 -427.960536) (xy 146.241516 -427.444916) (xy 146.230712 -427.407096)
			(xy 146.219109 -427.329303) (xy 146.218402 -427.289976) (xy 145.334736 -427.289976) (xy 145.334736 -428.28972)
			(xy 148.218398 -428.28972) (xy 148.218934 -428.257141) (xy 148.226905 -428.192471) (xy 148.242719 -428.12926)
			(xy 148.266137 -428.068455) (xy 148.29681 -428.010967) (xy 148.334277 -427.957658) (xy 148.377977 -427.909326)
			(xy 148.402294 -427.887638) (xy 148.482812 -427.7233) (xy 148.487501 -427.712779) (xy 148.490995 -427.690023)
			(xy 148.487515 -427.667266) (xy 148.482812 -427.656752) (xy 148.401786 -427.491652) (xy 148.377517 -427.469962)
			(xy 148.333921 -427.421628) (xy 148.296548 -427.368336) (xy 148.265955 -427.310882) (xy 148.242601 -427.250126)
			(xy 148.226834 -427.186973) (xy 148.218889 -427.122369) (xy 148.218398 -427.089824) (xy 148.219117 -427.050499)
			(xy 148.230727 -426.972709) (xy 148.241512 -426.934884) (xy 148.241512 -426.41901) (xy 148.242015 -426.406924)
			(xy 148.249466 -426.383928) (xy 148.263644 -426.364351) (xy 148.283168 -426.350099) (xy 148.306136 -426.342562)
			(xy 148.31822 -426.342048) (xy 149.25802 -426.342048) (xy 149.270125 -426.342499) (xy 149.293144 -426.349997)
			(xy 149.312712 -426.364252) (xy 149.326908 -426.383863) (xy 149.334337 -426.406904) (xy 149.334728 -426.41901)
			(xy 149.334728 -427.289976) (xy 150.218394 -427.289976) (xy 150.218858 -427.257419) (xy 150.226808 -427.192791)
			(xy 150.242597 -427.12962) (xy 150.265989 -427.068853) (xy 150.296633 -427.0114) (xy 150.334069 -426.958123)
			(xy 150.377737 -426.909822) (xy 150.402036 -426.888148) (xy 150.482808 -426.723302) (xy 150.487495 -426.71278)
			(xy 150.49099 -426.690025) (xy 150.487511 -426.667268) (xy 150.482808 -426.656754) (xy 150.401782 -426.491654)
			(xy 150.377514 -426.469963) (xy 150.333917 -426.42163) (xy 150.296544 -426.368338) (xy 150.265952 -426.310884)
			(xy 150.242597 -426.250128) (xy 150.22683 -426.186975) (xy 150.218886 -426.122371) (xy 150.218394 -426.089826)
			(xy 150.219113 -426.050501) (xy 150.230724 -425.972711) (xy 150.241508 -425.934886) (xy 150.241508 -425.419012)
			(xy 150.241923 -425.406928) (xy 150.249389 -425.383943) (xy 150.263594 -425.364392) (xy 150.283147 -425.350188)
			(xy 150.306132 -425.342723) (xy 150.318216 -425.342304) (xy 151.258016 -425.342304) (xy 151.270093 -425.342751)
			(xy 151.293062 -425.350219) (xy 151.3126 -425.36442) (xy 151.326794 -425.383963) (xy 151.334253 -425.406935)
			(xy 151.334724 -425.419012) (xy 151.334724 -427.960536) (xy 151.334267 -427.972611) (xy 151.326796 -427.995577)
			(xy 151.312597 -428.015112) (xy 151.293059 -428.029306) (xy 151.270091 -428.03677) (xy 151.258016 -428.037244)
			(xy 150.318216 -428.037244) (xy 150.306146 -428.036723) (xy 150.283185 -428.029269) (xy 150.263651 -428.015086)
			(xy 150.249455 -427.995561) (xy 150.241985 -427.972606) (xy 150.241508 -427.960536) (xy 150.241508 -427.444916)
			(xy 150.230704 -427.407096) (xy 150.219101 -427.329303) (xy 150.218394 -427.289976) (xy 149.334728 -427.289976)
			(xy 149.334728 -428.28972) (xy 152.21839 -428.28972) (xy 152.218928 -428.257141) (xy 152.226899 -428.192471)
			(xy 152.242713 -428.129261) (xy 152.266131 -428.068456) (xy 152.296803 -428.010968) (xy 152.33427 -427.957658)
			(xy 152.377969 -427.909326) (xy 152.402286 -427.887638) (xy 152.482804 -427.7233) (xy 152.487493 -427.712779)
			(xy 152.490987 -427.690023) (xy 152.487507 -427.667266) (xy 152.482804 -427.656752) (xy 152.401778 -427.491652)
			(xy 152.377508 -427.469963) (xy 152.333912 -427.421629) (xy 152.296539 -427.368337) (xy 152.265947 -427.310883)
			(xy 152.242593 -427.250126) (xy 152.226826 -427.186974) (xy 152.218881 -427.122369) (xy 152.21839 -427.089824)
			(xy 152.219109 -427.050499) (xy 152.230719 -426.972709) (xy 152.241504 -426.934884) (xy 152.241504 -426.41901)
			(xy 152.242015 -426.406925) (xy 152.249465 -426.38393) (xy 152.263641 -426.364353) (xy 152.283163 -426.350101)
			(xy 152.306128 -426.342563) (xy 152.318212 -426.342048) (xy 153.258012 -426.342048) (xy 153.270116 -426.342505)
			(xy 153.293135 -426.350002) (xy 153.312704 -426.364255) (xy 153.3269 -426.383864) (xy 153.334329 -426.406905)
			(xy 153.33472 -426.41901) (xy 153.33472 -427.289976) (xy 154.218386 -427.289976) (xy 154.218853 -427.257419)
			(xy 154.226802 -427.192792) (xy 154.242591 -427.129621) (xy 154.265983 -427.068853) (xy 154.296626 -427.0114)
			(xy 154.334062 -426.958124) (xy 154.377729 -426.909822) (xy 154.402028 -426.888148) (xy 154.4828 -426.723302)
			(xy 154.487488 -426.71278) (xy 154.490983 -426.690025) (xy 154.487503 -426.667268) (xy 154.4828 -426.656754)
			(xy 154.401774 -426.491654) (xy 154.377504 -426.469965) (xy 154.333908 -426.421631) (xy 154.296535 -426.368339)
			(xy 154.265943 -426.310885) (xy 154.242589 -426.250128) (xy 154.226822 -426.186976) (xy 154.218878 -426.122371)
			(xy 154.218386 -426.089826) (xy 154.219105 -426.050501) (xy 154.230716 -425.972711) (xy 154.2415 -425.934886)
			(xy 154.2415 -425.419012) (xy 154.241923 -425.406929) (xy 154.249388 -425.383946) (xy 154.263592 -425.364394)
			(xy 154.283142 -425.35019) (xy 154.306125 -425.342724) (xy 154.318208 -425.342304) (xy 155.258008 -425.342304)
			(xy 155.270092 -425.342706) (xy 155.293077 -425.350177) (xy 155.312629 -425.364386) (xy 155.326832 -425.383941)
			(xy 155.334297 -425.406928) (xy 155.334716 -425.419012) (xy 155.334716 -427.960536) (xy 155.334267 -427.972612)
			(xy 155.326795 -427.995579) (xy 155.312595 -428.015115) (xy 155.293054 -428.029308) (xy 155.270084 -428.036771)
			(xy 155.258008 -428.037244) (xy 154.318208 -428.037244) (xy 154.306137 -428.03673) (xy 154.283177 -428.029274)
			(xy 154.263643 -428.015089) (xy 154.249447 -427.995563) (xy 154.241977 -427.972606) (xy 154.2415 -427.960536)
			(xy 154.2415 -427.444916) (xy 154.230696 -427.407096) (xy 154.219092 -427.329303) (xy 154.218386 -427.289976)
			(xy 153.33472 -427.289976) (xy 153.33472 -428.28972) (xy 156.218382 -428.28972) (xy 156.218923 -428.257141)
			(xy 156.226894 -428.192472) (xy 156.242707 -428.129261) (xy 156.266125 -428.068456) (xy 156.296797 -428.010968)
			(xy 156.334263 -427.957658) (xy 156.377962 -427.909326) (xy 156.402278 -427.887638) (xy 156.482796 -427.7233)
			(xy 156.487485 -427.712779) (xy 156.49098 -427.690023) (xy 156.487499 -427.667266) (xy 156.482796 -427.656752)
			(xy 156.40177 -427.491652) (xy 156.377518 -427.469943) (xy 156.333918 -427.421614) (xy 156.296541 -427.368327)
			(xy 156.265945 -427.310876) (xy 156.242588 -427.250122) (xy 156.226819 -427.186972) (xy 156.218874 -427.122369)
			(xy 156.218382 -427.089824) (xy 156.219101 -427.050499) (xy 156.230712 -426.972709) (xy 156.241496 -426.934884)
			(xy 156.241496 -426.41901) (xy 156.242015 -426.406925) (xy 156.249464 -426.383932) (xy 156.263639 -426.364356)
			(xy 156.283158 -426.350104) (xy 156.306121 -426.342564) (xy 156.318204 -426.342048) (xy 157.258004 -426.342048)
			(xy 157.270108 -426.342512) (xy 157.293127 -426.350006) (xy 157.312695 -426.364257) (xy 157.326891 -426.383866)
			(xy 157.334321 -426.406905) (xy 157.334712 -426.41901) (xy 157.334712 -428.960534) (xy 157.334321 -428.97263)
			(xy 157.326849 -428.99564) (xy 157.312644 -429.015223) (xy 157.293092 -429.029471) (xy 157.270099 -429.036994)
			(xy 157.258004 -429.037496) (xy 156.318204 -429.037496) (xy 156.306095 -429.03708) (xy 156.283067 -429.029582)
			(xy 156.263493 -429.01532) (xy 156.249299 -428.995698) (xy 156.241879 -428.972644) (xy 156.241496 -428.960534)
			(xy 156.241496 -428.44466) (xy 156.230701 -428.406837) (xy 156.219092 -428.329046) (xy 156.218382 -428.28972)
			(xy 153.33472 -428.28972) (xy 153.33472 -428.960534) (xy 153.334321 -428.972629) (xy 153.32685 -428.995638)
			(xy 153.312647 -429.015221) (xy 153.293097 -429.029469) (xy 153.270106 -429.036993) (xy 153.258012 -429.037496)
			(xy 152.318212 -429.037496) (xy 152.306103 -429.037073) (xy 152.283076 -429.029577) (xy 152.263502 -429.015317)
			(xy 152.249307 -428.995696) (xy 152.241887 -428.972644) (xy 152.241504 -428.960534) (xy 152.241504 -428.44466)
			(xy 152.230709 -428.406837) (xy 152.2191 -428.329046) (xy 152.21839 -428.28972) (xy 149.334728 -428.28972)
			(xy 149.334728 -428.960534) (xy 149.334321 -428.972629) (xy 149.326851 -428.995636) (xy 149.31265 -429.015218)
			(xy 149.293102 -429.029466) (xy 149.270113 -429.036992) (xy 149.25802 -429.037496) (xy 148.31822 -429.037496)
			(xy 148.306112 -429.037066) (xy 148.283085 -429.029572) (xy 148.263511 -429.015314) (xy 148.249316 -428.995695)
			(xy 148.241895 -428.972643) (xy 148.241512 -428.960534) (xy 148.241512 -428.44466) (xy 148.230718 -428.406837)
			(xy 148.219108 -428.329046) (xy 148.218398 -428.28972) (xy 145.334736 -428.28972) (xy 145.334736 -428.960534)
			(xy 145.334321 -428.972628) (xy 145.326852 -428.995634) (xy 145.312653 -429.015215) (xy 145.293107 -429.029464)
			(xy 145.27012 -429.03699) (xy 145.258028 -429.037496) (xy 144.318228 -429.037496) (xy 144.30612 -429.03706)
			(xy 144.283093 -429.029567) (xy 144.263519 -429.015311) (xy 144.249324 -428.995693) (xy 144.241903 -428.972643)
			(xy 144.24152 -428.960534) (xy 144.24152 -428.44466) (xy 144.230726 -428.406837) (xy 144.219116 -428.329046)
			(xy 144.218406 -428.28972) (xy 140.335 -428.28972) (xy 140.335 -428.960534) (xy 140.334518 -428.972647)
			(xy 140.327026 -428.995684) (xy 140.312785 -429.015282) (xy 140.293188 -429.029524) (xy 140.270151 -429.037017)
			(xy 140.258038 -429.037496) (xy 139.318238 -429.037496) (xy 139.306121 -429.037008) (xy 139.283069 -429.029531)
			(xy 139.263456 -429.015295) (xy 139.249202 -428.995696) (xy 139.241703 -428.972651) (xy 139.241276 -428.960534)
			(xy 139.241276 -428.443898) (xy 139.230592 -428.406252) (xy 139.219113 -428.328846) (xy 139.218416 -428.28972)
			(xy 136.335008 -428.28972) (xy 136.335008 -428.960534) (xy 136.334518 -428.972646) (xy 136.327027 -428.995682)
			(xy 136.312788 -429.01528) (xy 136.293193 -429.029522) (xy 136.270158 -429.037016) (xy 136.258046 -429.037496)
			(xy 135.318246 -429.037496) (xy 135.306129 -429.037002) (xy 135.283077 -429.029526) (xy 135.263464 -429.015292)
			(xy 135.249211 -428.995694) (xy 135.241711 -428.972651) (xy 135.241284 -428.960534) (xy 135.241284 -428.443898)
			(xy 135.2306 -428.406252) (xy 135.219121 -428.328846) (xy 135.218424 -428.28972) (xy 132.335016 -428.28972)
			(xy 132.335016 -428.960534) (xy 132.334668 -428.972663) (xy 132.327161 -428.995731) (xy 132.312892 -429.015349)
			(xy 132.293259 -429.029598) (xy 132.270184 -429.037081) (xy 132.258054 -429.037496) (xy 131.318254 -429.037496)
			(xy 131.30614 -429.037028) (xy 131.283101 -429.029532) (xy 131.263503 -429.015288) (xy 131.249262 -428.995688)
			(xy 131.24177 -428.972648) (xy 131.241292 -428.960534) (xy 131.241292 -428.443898) (xy 131.230608 -428.406252)
			(xy 131.219129 -428.328846) (xy 131.218432 -428.28972) (xy 128.335024 -428.28972) (xy 128.335024 -428.960534)
			(xy 128.334669 -428.972662) (xy 128.327162 -428.995729) (xy 128.312895 -429.015347) (xy 128.293264 -429.029595)
			(xy 128.270191 -429.03708) (xy 128.258062 -429.037496) (xy 127.318262 -429.037496) (xy 127.306149 -429.037021)
			(xy 127.28311 -429.029528) (xy 127.263512 -429.015285) (xy 127.24927 -428.995686) (xy 127.241778 -428.972647)
			(xy 127.2413 -428.960534) (xy 127.2413 -428.443898) (xy 127.230617 -428.406252) (xy 127.219137 -428.328846)
			(xy 127.21844 -428.28972) (xy 113.943382 -428.28972) (xy 113.956414 -428.297518) (xy 114.097839 -428.391417)
			(xy 114.234709 -428.491842) (xy 114.36672 -428.598572) (xy 114.493584 -428.711373) (xy 114.615021 -428.829996)
			(xy 114.730765 -428.954181) (xy 114.84056 -429.083654) (xy 114.944167 -429.218131) (xy 115.041356 -429.357317)
			(xy 115.131914 -429.500905) (xy 115.215642 -429.648581) (xy 115.292357 -429.800018) (xy 115.361889 -429.954885)
			(xy 115.424086 -430.11284) (xy 115.47881 -430.273538) (xy 115.525942 -430.436623) (xy 115.565378 -430.601739)
			(xy 115.597032 -430.768522) (xy 115.614222 -430.889918) (xy 125.238002 -430.889918) (xy 125.238096 -430.875344)
			(xy 125.239748 -430.846243) (xy 125.241304 -430.831752) (xy 125.241304 -429.747934) (xy 125.239756 -429.733442)
			(xy 125.238106 -429.704342) (xy 125.238002 -429.689768) (xy 125.2381 -429.675194) (xy 125.23975 -429.646093)
			(xy 125.241304 -429.631602) (xy 125.241304 -429.018954) (xy 125.241772 -429.00684) (xy 125.249268 -428.983801)
			(xy 125.263512 -428.964203) (xy 125.283112 -428.949962) (xy 125.306152 -428.94247) (xy 125.318266 -428.941992)
			(xy 126.258066 -428.941992) (xy 126.270174 -428.94254) (xy 126.293209 -428.950012) (xy 126.312807 -428.964236)
			(xy 126.327051 -428.98382) (xy 126.334547 -429.006846) (xy 126.335028 -429.018954) (xy 126.335028 -431.560478)
			(xy 126.334621 -431.572603) (xy 126.32713 -431.595667) (xy 126.312877 -431.615285) (xy 126.293256 -431.629536)
			(xy 126.270191 -431.637023) (xy 126.258066 -431.63744) (xy 125.318266 -431.63744) (xy 125.306147 -431.637017)
			(xy 125.283099 -431.629518) (xy 125.263496 -431.615264) (xy 125.249257 -431.59565) (xy 125.241774 -431.572597)
			(xy 125.241304 -431.560478) (xy 125.241304 -430.948084) (xy 125.23976 -430.933592) (xy 125.238108 -430.904492)
			(xy 125.238002 -430.889918) (xy 115.614222 -430.889918) (xy 115.620833 -430.936605) (xy 115.636729 -431.105619)
			(xy 115.644686 -431.275192) (xy 115.645184 -431.360072) (xy 115.644698 -431.445674) (xy 115.63661 -431.616688)
			(xy 115.620446 -431.787128) (xy 115.605768 -431.889916) (xy 127.237998 -431.889916) (xy 127.238092 -431.875342)
			(xy 127.239744 -431.846241) (xy 127.2413 -431.83175) (xy 127.2413 -430.747932) (xy 127.239752 -430.73344)
			(xy 127.238102 -430.70434) (xy 127.237998 -430.689766) (xy 127.238096 -430.675192) (xy 127.239746 -430.646091)
			(xy 127.2413 -430.6316) (xy 127.2413 -430.018952) (xy 127.241676 -430.006841) (xy 127.249188 -429.983812)
			(xy 127.26346 -429.96424) (xy 127.28309 -429.950047) (xy 127.306149 -429.942627) (xy 127.318262 -429.942244)
			(xy 128.258062 -429.942244) (xy 128.27015 -429.94274) (xy 128.29315 -429.950187) (xy 128.312731 -429.964366)
			(xy 128.326983 -429.983894) (xy 128.334515 -430.006866) (xy 128.335024 -430.018952) (xy 128.335024 -430.889918)
			(xy 129.237994 -430.889918) (xy 129.238088 -430.875344) (xy 129.23974 -430.846243) (xy 129.241296 -430.831752)
			(xy 129.241296 -429.747934) (xy 129.239749 -429.733442) (xy 129.238098 -429.704342) (xy 129.237994 -429.689768)
			(xy 129.238092 -429.675194) (xy 129.239742 -429.646093) (xy 129.241296 -429.631602) (xy 129.241296 -429.018954)
			(xy 129.241772 -429.006841) (xy 129.249267 -428.983804) (xy 129.263509 -428.964206) (xy 129.283107 -428.949965)
			(xy 129.306145 -428.942471) (xy 129.318258 -428.941992) (xy 130.258058 -428.941992) (xy 130.270166 -428.942547)
			(xy 130.2932 -428.950017) (xy 130.312798 -428.964239) (xy 130.327043 -428.983821) (xy 130.334539 -429.006847)
			(xy 130.33502 -429.018954) (xy 130.33502 -431.560478) (xy 130.334621 -431.572604) (xy 130.327129 -431.595669)
			(xy 130.312874 -431.615288) (xy 130.293251 -431.629538) (xy 130.270184 -431.637024) (xy 130.258058 -431.63744)
			(xy 129.318258 -431.63744) (xy 129.306139 -431.637024) (xy 129.283091 -431.629522) (xy 129.263488 -431.615267)
			(xy 129.249248 -431.595652) (xy 129.241766 -431.572597) (xy 129.241296 -431.560478) (xy 129.241296 -430.948084)
			(xy 129.239753 -430.933592) (xy 129.2381 -430.904492) (xy 129.237994 -430.889918) (xy 128.335024 -430.889918)
			(xy 128.335024 -431.889916) (xy 131.23799 -431.889916) (xy 131.238084 -431.875342) (xy 131.239736 -431.846241)
			(xy 131.241292 -431.83175) (xy 131.241292 -430.747932) (xy 131.239744 -430.73344) (xy 131.238094 -430.70434)
			(xy 131.23799 -430.689766) (xy 131.238088 -430.675192) (xy 131.239738 -430.646091) (xy 131.241292 -430.6316)
			(xy 131.241292 -430.018952) (xy 131.241675 -430.006841) (xy 131.249187 -429.983814) (xy 131.263458 -429.964242)
			(xy 131.283085 -429.950049) (xy 131.306142 -429.942628) (xy 131.318254 -429.942244) (xy 132.258054 -429.942244)
			(xy 132.270142 -429.942747) (xy 132.293141 -429.950191) (xy 132.312722 -429.964368) (xy 132.326974 -429.983895)
			(xy 132.334507 -430.006866) (xy 132.335016 -430.018952) (xy 132.335016 -430.889918) (xy 133.237986 -430.889918)
			(xy 133.23808 -430.875344) (xy 133.239732 -430.846243) (xy 133.241288 -430.831752) (xy 133.241288 -429.747934)
			(xy 133.239741 -429.733442) (xy 133.23809 -429.704342) (xy 133.237986 -429.689768) (xy 133.238084 -429.675194)
			(xy 133.239734 -429.646093) (xy 133.241288 -429.631602) (xy 133.241288 -429.018954) (xy 133.241772 -429.006842)
			(xy 133.249266 -428.983806) (xy 133.263506 -428.964209) (xy 133.283102 -428.949967) (xy 133.306138 -428.942472)
			(xy 133.31825 -428.941992) (xy 134.25805 -428.941992) (xy 134.270163 -428.942468) (xy 134.2932 -428.949964)
			(xy 134.312797 -428.964206) (xy 134.327038 -428.983804) (xy 134.334532 -429.006841) (xy 134.335012 -429.018954)
			(xy 134.335012 -431.560478) (xy 134.33447 -431.572586) (xy 134.326995 -431.59562) (xy 134.312769 -431.615218)
			(xy 134.293185 -431.629462) (xy 134.270158 -431.636959) (xy 134.25805 -431.63744) (xy 133.31825 -431.63744)
			(xy 133.306131 -431.63703) (xy 133.283082 -431.629527) (xy 133.263479 -431.615269) (xy 133.24924 -431.595653)
			(xy 133.241758 -431.572598) (xy 133.241288 -431.560478) (xy 133.241288 -430.948084) (xy 133.239745 -430.933592)
			(xy 133.238092 -430.904492) (xy 133.237986 -430.889918) (xy 132.335016 -430.889918) (xy 132.335016 -431.889916)
			(xy 135.237982 -431.889916) (xy 135.238076 -431.875342) (xy 135.239728 -431.846241) (xy 135.241284 -431.83175)
			(xy 135.241284 -430.747932) (xy 135.239736 -430.73344) (xy 135.238086 -430.70434) (xy 135.237982 -430.689766)
			(xy 135.23808 -430.675192) (xy 135.23973 -430.646091) (xy 135.241284 -430.6316) (xy 135.241284 -430.018952)
			(xy 135.241675 -430.006842) (xy 135.249186 -429.983816) (xy 135.263455 -429.964245) (xy 135.28308 -429.950052)
			(xy 135.306135 -429.942629) (xy 135.318246 -429.942244) (xy 136.258046 -429.942244) (xy 136.270138 -429.942668)
			(xy 136.293141 -429.950138) (xy 136.312721 -429.964336) (xy 136.32697 -429.983878) (xy 136.3345 -430.006861)
			(xy 136.335008 -430.018952) (xy 136.335008 -430.889918) (xy 137.237978 -430.889918) (xy 137.238072 -430.875344)
			(xy 137.239724 -430.846243) (xy 137.24128 -430.831752) (xy 137.24128 -429.747934) (xy 137.239733 -429.733442)
			(xy 137.238082 -429.704342) (xy 137.237978 -429.689768) (xy 137.238076 -429.675194) (xy 137.239726 -429.646093)
			(xy 137.24128 -429.631602) (xy 137.24128 -429.018954) (xy 137.241673 -429.006833) (xy 137.249178 -428.983781)
			(xy 137.263439 -428.964176) (xy 137.28306 -428.949938) (xy 137.30612 -428.942459) (xy 137.318242 -428.941992)
			(xy 138.258042 -428.941992) (xy 138.270154 -428.942475) (xy 138.293191 -428.949968) (xy 138.312788 -428.964209)
			(xy 138.32703 -428.983805) (xy 138.334524 -429.006842) (xy 138.335004 -429.018954) (xy 138.335004 -431.560478)
			(xy 138.33447 -431.572587) (xy 138.326994 -431.595623) (xy 138.312767 -431.615221) (xy 138.29318 -431.629465)
			(xy 138.270151 -431.63696) (xy 138.258042 -431.63744) (xy 137.318242 -431.63744) (xy 137.306119 -431.637004)
			(xy 137.283058 -431.629521) (xy 137.26344 -431.615274) (xy 137.249188 -431.59566) (xy 137.241699 -431.572601)
			(xy 137.24128 -431.560478) (xy 137.24128 -430.948084) (xy 137.239737 -430.933592) (xy 137.238084 -430.904492)
			(xy 137.237978 -430.889918) (xy 136.335008 -430.889918) (xy 136.335008 -431.889916) (xy 139.237974 -431.889916)
			(xy 139.238068 -431.875342) (xy 139.23972 -431.846241) (xy 139.241276 -431.83175) (xy 139.241276 -430.747932)
			(xy 139.239728 -430.73344) (xy 139.238078 -430.70434) (xy 139.237974 -430.689766) (xy 139.238072 -430.675192)
			(xy 139.239722 -430.646091) (xy 139.241276 -430.6316) (xy 139.241276 -430.018952) (xy 139.241675 -430.006843)
			(xy 139.249185 -429.983818) (xy 139.263452 -429.964248) (xy 139.283075 -429.950054) (xy 139.306128 -429.94263)
			(xy 139.318238 -429.942244) (xy 140.258038 -429.942244) (xy 140.27013 -429.942675) (xy 140.293133 -429.950143)
			(xy 140.312712 -429.964338) (xy 140.326961 -429.983879) (xy 140.334492 -430.006861) (xy 140.335 -430.018952)
			(xy 140.335 -430.889918) (xy 142.237968 -430.889918) (xy 142.238077 -430.874832) (xy 142.239859 -430.844714)
			(xy 142.241524 -430.82972) (xy 142.241524 -429.749966) (xy 142.239859 -429.734972) (xy 142.238078 -429.704854)
			(xy 142.237968 -429.689768) (xy 142.238082 -429.674682) (xy 142.23986 -429.644564) (xy 142.241524 -429.62957)
			(xy 142.241524 -429.018954) (xy 142.241968 -429.006864) (xy 142.249435 -428.983864) (xy 142.263628 -428.964286)
			(xy 142.283165 -428.950037) (xy 142.306143 -428.942503) (xy 142.318232 -428.941992) (xy 143.258032 -428.941992)
			(xy 143.270142 -428.942389) (xy 143.293169 -428.949896) (xy 143.312741 -428.964163) (xy 143.326934 -428.983788)
			(xy 143.334356 -429.006843) (xy 143.33474 -429.018954) (xy 143.33474 -431.560478) (xy 143.334273 -431.572568)
			(xy 143.32682 -431.595572) (xy 143.312634 -431.615154) (xy 143.293099 -431.629404) (xy 143.270121 -431.636933)
			(xy 143.258032 -431.63744) (xy 142.318232 -431.63744) (xy 142.306129 -431.636957) (xy 142.283109 -431.629471)
			(xy 142.263539 -431.615225) (xy 142.249342 -431.59562) (xy 142.241913 -431.572582) (xy 142.241524 -431.560478)
			(xy 142.241524 -430.950116) (xy 142.239855 -430.935123) (xy 142.238077 -430.905004) (xy 142.237968 -430.889918)
			(xy 140.335 -430.889918) (xy 140.335 -431.889916) (xy 144.237964 -431.889916) (xy 144.238073 -431.87483)
			(xy 144.239855 -431.844712) (xy 144.24152 -431.829718) (xy 144.24152 -430.749964) (xy 144.239855 -430.73497)
			(xy 144.238074 -430.704852) (xy 144.237964 -430.689766) (xy 144.238078 -430.67468) (xy 144.239856 -430.644562)
			(xy 144.24152 -430.629568) (xy 144.24152 -430.018952) (xy 144.241924 -430.006872) (xy 144.249403 -429.983899)
			(xy 144.263614 -429.96436) (xy 144.283167 -429.950168) (xy 144.306148 -429.942712) (xy 144.318228 -429.942244)
			(xy 145.258028 -429.942244) (xy 145.270099 -429.942739) (xy 145.293059 -429.950204) (xy 145.312592 -429.964394)
			(xy 145.326787 -429.983923) (xy 145.334258 -430.006881) (xy 145.334736 -430.018952) (xy 145.334736 -430.889918)
			(xy 146.23796 -430.889918) (xy 146.238069 -430.874832) (xy 146.239851 -430.844714) (xy 146.241516 -430.82972)
			(xy 146.241516 -429.749966) (xy 146.239851 -429.734972) (xy 146.23807 -429.704854) (xy 146.23796 -429.689768)
			(xy 146.238074 -429.674682) (xy 146.239852 -429.644564) (xy 146.241516 -429.62957) (xy 146.241516 -429.018954)
			(xy 146.241968 -429.006864) (xy 146.249434 -428.983866) (xy 146.263626 -428.964289) (xy 146.28316 -428.950039)
			(xy 146.306136 -428.942504) (xy 146.318224 -428.941992) (xy 147.258024 -428.941992) (xy 147.270133 -428.942396)
			(xy 147.29316 -428.949901) (xy 147.312732 -428.964166) (xy 147.326926 -428.983789) (xy 147.334348 -429.006843)
			(xy 147.334732 -429.018954) (xy 147.334732 -431.560478) (xy 147.334273 -431.572569) (xy 147.326819 -431.595574)
			(xy 147.312632 -431.615156) (xy 147.293094 -431.629407) (xy 147.270114 -431.636934) (xy 147.258024 -431.63744)
			(xy 146.318224 -431.63744) (xy 146.30612 -431.636964) (xy 146.283101 -431.629476) (xy 146.263531 -431.615228)
			(xy 146.249334 -431.595622) (xy 146.241905 -431.572583) (xy 146.241516 -431.560478) (xy 146.241516 -430.950116)
			(xy 146.239847 -430.935123) (xy 146.238069 -430.905004) (xy 146.23796 -430.889918) (xy 145.334736 -430.889918)
			(xy 145.334736 -431.889916) (xy 148.237956 -431.889916) (xy 148.238065 -431.87483) (xy 148.239847 -431.844712)
			(xy 148.241512 -431.829718) (xy 148.241512 -430.749964) (xy 148.239847 -430.73497) (xy 148.238066 -430.704852)
			(xy 148.237956 -430.689766) (xy 148.23807 -430.67468) (xy 148.239848 -430.644562) (xy 148.241512 -430.629568)
			(xy 148.241512 -430.018952) (xy 148.241924 -430.006873) (xy 148.249402 -429.983901) (xy 148.263611 -429.964363)
			(xy 148.283162 -429.950171) (xy 148.306141 -429.942713) (xy 148.31822 -429.942244) (xy 149.25802 -429.942244)
			(xy 149.270091 -429.942747) (xy 149.29305 -429.950209) (xy 149.312583 -429.964397) (xy 149.326778 -429.983924)
			(xy 149.334249 -430.006881) (xy 149.334728 -430.018952) (xy 149.334728 -430.889918) (xy 150.237952 -430.889918)
			(xy 150.238061 -430.874832) (xy 150.239843 -430.844714) (xy 150.241508 -430.82972) (xy 150.241508 -429.749966)
			(xy 150.239843 -429.734972) (xy 150.238062 -429.704854) (xy 150.237952 -429.689768) (xy 150.238066 -429.674682)
			(xy 150.239844 -429.644564) (xy 150.241508 -429.62957) (xy 150.241508 -429.018954) (xy 150.241968 -429.006865)
			(xy 150.249433 -428.983868) (xy 150.263623 -428.964292) (xy 150.283155 -428.950042) (xy 150.306129 -428.942505)
			(xy 150.318216 -428.941992) (xy 151.258016 -428.941992) (xy 151.270125 -428.942402) (xy 151.293151 -428.949905)
			(xy 151.312724 -428.964169) (xy 151.326918 -428.983791) (xy 151.33434 -429.006844) (xy 151.334724 -429.018954)
			(xy 151.334724 -431.560478) (xy 151.334273 -431.57257) (xy 151.326818 -431.595576) (xy 151.312629 -431.615159)
			(xy 151.293089 -431.629409) (xy 151.270106 -431.636935) (xy 151.258016 -431.63744) (xy 150.318216 -431.63744)
			(xy 150.306112 -431.63697) (xy 150.283092 -431.62948) (xy 150.263522 -431.615231) (xy 150.249326 -431.595623)
			(xy 150.241897 -431.572583) (xy 150.241508 -431.560478) (xy 150.241508 -430.950116) (xy 150.239839 -430.935123)
			(xy 150.238061 -430.905004) (xy 150.237952 -430.889918) (xy 149.334728 -430.889918) (xy 149.334728 -431.889916)
			(xy 152.237948 -431.889916) (xy 152.238057 -431.87483) (xy 152.239839 -431.844712) (xy 152.241504 -431.829718)
			(xy 152.241504 -430.749964) (xy 152.239839 -430.73497) (xy 152.238058 -430.704852) (xy 152.237948 -430.689766)
			(xy 152.238062 -430.67468) (xy 152.23984 -430.644562) (xy 152.241504 -430.629568) (xy 152.241504 -430.018952)
			(xy 152.241923 -430.006874) (xy 152.249401 -429.983903) (xy 152.263608 -429.964366) (xy 152.283157 -429.950173)
			(xy 152.306133 -429.942714) (xy 152.318212 -429.942244) (xy 153.258012 -429.942244) (xy 153.270082 -429.942753)
			(xy 153.293042 -429.950213) (xy 153.312574 -429.9644) (xy 153.32677 -429.983926) (xy 153.334241 -430.006882)
			(xy 153.33472 -430.018952) (xy 153.33472 -430.889918) (xy 154.237944 -430.889918) (xy 154.238053 -430.874832)
			(xy 154.239835 -430.844714) (xy 154.2415 -430.82972) (xy 154.2415 -429.749966) (xy 154.239835 -429.734972)
			(xy 154.238054 -429.704854) (xy 154.237944 -429.689768) (xy 154.238058 -429.674682) (xy 154.239836 -429.644564)
			(xy 154.2415 -429.62957) (xy 154.2415 -429.018954) (xy 154.241967 -429.006866) (xy 154.249432 -428.983871)
			(xy 154.26362 -428.964295) (xy 154.28315 -428.950044) (xy 154.306122 -428.942507) (xy 154.318208 -428.941992)
			(xy 155.258008 -428.941992) (xy 155.270117 -428.942409) (xy 155.293143 -428.94991) (xy 155.312715 -428.964172)
			(xy 155.32691 -428.983792) (xy 155.334332 -429.006844) (xy 155.334716 -429.018954) (xy 155.334716 -431.560478)
			(xy 155.334273 -431.572571) (xy 155.326817 -431.595578) (xy 155.312626 -431.615162) (xy 155.293084 -431.629412)
			(xy 155.270099 -431.636937) (xy 155.258008 -431.63744) (xy 154.318208 -431.63744) (xy 154.306104 -431.636978)
			(xy 154.283083 -431.629485) (xy 154.263513 -431.615234) (xy 154.249317 -431.595625) (xy 154.241889 -431.572584)
			(xy 154.2415 -431.560478) (xy 154.2415 -430.950116) (xy 154.239831 -430.935123) (xy 154.238053 -430.905004)
			(xy 154.237944 -430.889918) (xy 153.33472 -430.889918) (xy 153.33472 -431.889916) (xy 156.23794 -431.889916)
			(xy 156.238051 -431.87483) (xy 156.239833 -431.844712) (xy 156.241496 -431.829718) (xy 156.241496 -430.749964)
			(xy 156.239831 -430.73497) (xy 156.23805 -430.704852) (xy 156.23794 -430.689766) (xy 156.238054 -430.67468)
			(xy 156.239832 -430.644562) (xy 156.241496 -430.629568) (xy 156.241496 -430.018952) (xy 156.241923 -430.006875)
			(xy 156.249399 -429.983905) (xy 156.263605 -429.964368) (xy 156.283152 -429.950176) (xy 156.306126 -429.942715)
			(xy 156.318204 -429.942244) (xy 157.258004 -429.942244) (xy 157.270074 -429.94276) (xy 157.293033 -429.950218)
			(xy 157.312566 -429.964403) (xy 157.326762 -429.983927) (xy 157.334233 -430.006882) (xy 157.334712 -430.018952)
			(xy 157.334712 -432.560476) (xy 157.334267 -432.572557) (xy 157.326806 -432.595538) (xy 157.312609 -432.615089)
			(xy 157.293063 -432.629294) (xy 157.270085 -432.636762) (xy 157.258004 -432.637184) (xy 156.318204 -432.637184)
			(xy 156.306119 -432.636784) (xy 156.283132 -432.629314) (xy 156.26358 -432.615106) (xy 156.249376 -432.59555)
			(xy 156.241913 -432.572561) (xy 156.241496 -432.560476) (xy 156.241496 -431.950114) (xy 156.239826 -431.935121)
			(xy 156.238049 -431.905002) (xy 156.23794 -431.889916) (xy 153.33472 -431.889916) (xy 153.33472 -432.560476)
			(xy 153.334267 -432.572556) (xy 153.326807 -432.595536) (xy 153.312611 -432.615086) (xy 153.293068 -432.629291)
			(xy 153.270092 -432.636761) (xy 153.258012 -432.637184) (xy 152.318212 -432.637184) (xy 152.306128 -432.636777)
			(xy 152.283141 -432.629309) (xy 152.263589 -432.615103) (xy 152.249385 -432.595548) (xy 152.241922 -432.572561)
			(xy 152.241504 -432.560476) (xy 152.241504 -431.950114) (xy 152.239834 -431.935121) (xy 152.238057 -431.905002)
			(xy 152.237948 -431.889916) (xy 149.334728 -431.889916) (xy 149.334728 -432.560476) (xy 149.334267 -432.572555)
			(xy 149.326809 -432.595534) (xy 149.312614 -432.615083) (xy 149.293073 -432.629288) (xy 149.270099 -432.63676)
			(xy 149.25802 -432.637184) (xy 148.31822 -432.637184) (xy 148.306136 -432.63677) (xy 148.28315 -432.629305)
			(xy 148.263597 -432.6151) (xy 148.249393 -432.595547) (xy 148.24193 -432.57256) (xy 148.241512 -432.560476)
			(xy 148.241512 -431.950114) (xy 148.239842 -431.935121) (xy 148.238065 -431.905002) (xy 148.237956 -431.889916)
			(xy 145.334736 -431.889916) (xy 145.334736 -432.560476) (xy 145.334216 -432.572547) (xy 145.326763 -432.595508)
			(xy 145.31258 -432.615043) (xy 145.293055 -432.62924) (xy 145.270098 -432.636708) (xy 145.258028 -432.637184)
			(xy 144.318228 -432.637184) (xy 144.306144 -432.636763) (xy 144.283159 -432.6293) (xy 144.263606 -432.615097)
			(xy 144.249402 -432.595545) (xy 144.241938 -432.57256) (xy 144.24152 -432.560476) (xy 144.24152 -431.950114)
			(xy 144.23985 -431.935121) (xy 144.238073 -431.905002) (xy 144.237964 -431.889916) (xy 140.335 -431.889916)
			(xy 140.335 -432.560476) (xy 140.334563 -432.572584) (xy 140.32707 -432.59561) (xy 140.312814 -432.615184)
			(xy 140.293196 -432.629379) (xy 140.270147 -432.6368) (xy 140.258038 -432.637184) (xy 139.318238 -432.637184)
			(xy 139.306153 -432.636661) (xy 139.283157 -432.629217) (xy 139.263579 -432.615044) (xy 139.249326 -432.595524)
			(xy 139.241789 -432.572559) (xy 139.241276 -432.560476) (xy 139.241276 -431.948082) (xy 139.239733 -431.93359)
			(xy 139.23808 -431.90449) (xy 139.237974 -431.889916) (xy 136.335008 -431.889916) (xy 136.335008 -432.560476)
			(xy 136.334563 -432.572583) (xy 136.327071 -432.595608) (xy 136.312817 -432.615181) (xy 136.293201 -432.629376)
			(xy 136.270154 -432.636799) (xy 136.258046 -432.637184) (xy 135.318246 -432.637184) (xy 135.306161 -432.636654)
			(xy 135.283166 -432.629213) (xy 135.263587 -432.615042) (xy 135.249334 -432.595522) (xy 135.241797 -432.572559)
			(xy 135.241284 -432.560476) (xy 135.241284 -431.948082) (xy 135.239741 -431.93359) (xy 135.238088 -431.90449)
			(xy 135.237982 -431.889916) (xy 132.335016 -431.889916) (xy 132.335016 -432.560476) (xy 132.334563 -432.572582)
			(xy 132.327072 -432.595606) (xy 132.31282 -432.615178) (xy 132.293206 -432.629374) (xy 132.270161 -432.636798)
			(xy 132.258054 -432.637184) (xy 131.318254 -432.637184) (xy 131.306164 -432.636732) (xy 131.283166 -432.629266)
			(xy 131.263589 -432.615074) (xy 131.249339 -432.59554) (xy 131.241804 -432.572564) (xy 131.241292 -432.560476)
			(xy 131.241292 -431.948082) (xy 131.239749 -431.93359) (xy 131.238096 -431.90449) (xy 131.23799 -431.889916)
			(xy 128.335024 -431.889916) (xy 128.335024 -432.560476) (xy 128.334563 -432.572581) (xy 128.327074 -432.595604)
			(xy 128.312823 -432.615175) (xy 128.293212 -432.629371) (xy 128.270168 -432.636797) (xy 128.258062 -432.637184)
			(xy 127.318262 -432.637184) (xy 127.306173 -432.636726) (xy 127.283175 -432.629261) (xy 127.263598 -432.615072)
			(xy 127.249348 -432.595538) (xy 127.241812 -432.572564) (xy 127.2413 -432.560476) (xy 127.2413 -431.948082)
			(xy 127.239756 -431.93359) (xy 127.238104 -431.90449) (xy 127.237998 -431.889916) (xy 115.605768 -431.889916)
			(xy 115.596243 -431.956613) (xy 115.564055 -432.124765) (xy 115.523953 -432.291207) (xy 115.476027 -432.455567)
			(xy 115.420385 -432.617477) (xy 115.35715 -432.776576) (xy 115.286464 -432.932508) (xy 115.208486 -433.084923)
			(xy 115.12339 -433.233482) (xy 115.031365 -433.377851) (xy 114.932619 -433.517709) (xy 114.82737 -433.652742)
			(xy 114.715856 -433.782648) (xy 114.598325 -433.907137) (xy 114.47504 -434.02593) (xy 114.346277 -434.138763)
			(xy 114.212324 -434.245381) (xy 114.07348 -434.345548) (xy 113.930056 -434.439039) (xy 113.843394 -434.48986)
			(xy 125.218444 -434.48986) (xy 125.218914 -434.457303) (xy 125.226865 -434.392677) (xy 125.242654 -434.329506)
			(xy 125.266045 -434.268739) (xy 125.296688 -434.211286) (xy 125.334122 -434.158009) (xy 125.377788 -434.109706)
			(xy 125.402086 -434.088032) (xy 125.482858 -433.923186) (xy 125.487554 -433.912668) (xy 125.491043 -433.889911)
			(xy 125.487561 -433.867153) (xy 125.482858 -433.856638) (xy 125.402086 -433.691792) (xy 125.377801 -433.670106)
			(xy 125.334148 -433.621797) (xy 125.296723 -433.568519) (xy 125.266085 -433.511068) (xy 125.242694 -433.450305)
			(xy 125.2269 -433.38714) (xy 125.21894 -433.322519) (xy 125.218444 -433.289964) (xy 125.219136 -433.250837)
			(xy 125.230616 -433.173431) (xy 125.241304 -433.135786) (xy 125.241304 -432.618896) (xy 125.241713 -432.606787)
			(xy 125.249214 -432.583758) (xy 125.263477 -432.564185) (xy 125.283101 -432.549991) (xy 125.306155 -432.542571)
			(xy 125.318266 -432.542188) (xy 126.258066 -432.542188) (xy 126.270159 -432.542637) (xy 126.293166 -432.55009)
			(xy 126.312751 -432.56428) (xy 126.327001 -432.583821) (xy 126.334525 -432.606805) (xy 126.335028 -432.618896)
			(xy 126.335028 -435.16042) (xy 126.334601 -435.172527) (xy 126.3271 -435.19555) (xy 126.31284 -435.215121)
			(xy 126.293222 -435.229316) (xy 126.270174 -435.236741) (xy 126.258066 -435.237128) (xy 125.318266 -435.237128)
			(xy 125.306171 -435.236721) (xy 125.283164 -435.229251) (xy 125.263582 -435.21505) (xy 125.249334 -435.195502)
			(xy 125.241808 -435.172513) (xy 125.241304 -435.16042) (xy 125.241304 -434.644038) (xy 125.230608 -434.606395)
			(xy 125.219137 -434.528987) (xy 125.218444 -434.48986) (xy 113.843394 -434.48986) (xy 113.782372 -434.525645)
			(xy 113.630759 -434.605172) (xy 113.475556 -434.677443) (xy 113.396522 -434.710332) (xy 113.382851 -434.716444)
			(xy 113.359598 -434.735293) (xy 113.342813 -434.760077) (xy 113.333939 -434.788665) (xy 113.333741 -434.818598)
			(xy 113.342235 -434.847301) (xy 113.358691 -434.872305) (xy 113.369852 -434.88229) (xy 113.419298 -434.924299)
			(xy 113.513487 -435.013553) (xy 113.601975 -435.108462) (xy 113.684422 -435.208663) (xy 113.760513 -435.313772)
			(xy 113.829956 -435.423387) (xy 113.866512 -435.489858) (xy 127.21844 -435.489858) (xy 127.21891 -435.457301)
			(xy 127.226861 -435.392675) (xy 127.24265 -435.329504) (xy 127.266042 -435.268737) (xy 127.296684 -435.211284)
			(xy 127.334119 -435.158007) (xy 127.377784 -435.109705) (xy 127.402082 -435.08803) (xy 127.482854 -434.923184)
			(xy 127.487552 -434.912666) (xy 127.49104 -434.889909) (xy 127.487557 -434.867151) (xy 127.482854 -434.856636)
			(xy 127.402082 -434.69179) (xy 127.377795 -434.670106) (xy 127.334142 -434.621797) (xy 127.296717 -434.568518)
			(xy 127.26608 -434.511067) (xy 127.24269 -434.450303) (xy 127.226896 -434.387138) (xy 127.218936 -434.322517)
			(xy 127.21844 -434.289962) (xy 127.219132 -434.250835) (xy 127.230612 -434.173429) (xy 127.2413 -434.135784)
			(xy 127.2413 -433.618894) (xy 127.241806 -433.606783) (xy 127.24929 -433.583746) (xy 127.263525 -433.564148)
			(xy 127.283117 -433.549905) (xy 127.306151 -433.542411) (xy 127.318262 -433.541932) (xy 128.258062 -433.541932)
			(xy 128.270182 -433.542392) (xy 128.293239 -433.549873) (xy 128.312854 -433.564115) (xy 128.327107 -433.583722)
			(xy 128.334601 -433.606774) (xy 128.335024 -433.618894) (xy 128.335024 -434.48986) (xy 129.218436 -434.48986)
			(xy 129.218909 -434.457303) (xy 129.226859 -434.392677) (xy 129.242648 -434.329507) (xy 129.266039 -434.26874)
			(xy 129.296681 -434.211287) (xy 129.334115 -434.15801) (xy 129.37778 -434.109707) (xy 129.402078 -434.088032)
			(xy 129.48285 -433.923186) (xy 129.487547 -433.912668) (xy 129.491035 -433.889911) (xy 129.487553 -433.867153)
			(xy 129.48285 -433.856638) (xy 129.402078 -433.691792) (xy 129.377811 -433.670085) (xy 129.334154 -433.621783)
			(xy 129.296724 -433.568509) (xy 129.266083 -433.511061) (xy 129.242689 -433.450301) (xy 129.226893 -433.387138)
			(xy 129.218932 -433.322518) (xy 129.218436 -433.289964) (xy 129.219128 -433.250837) (xy 129.230608 -433.173431)
			(xy 129.241296 -433.135786) (xy 129.241296 -432.618896) (xy 129.241713 -432.606787) (xy 129.249213 -432.583761)
			(xy 129.263474 -432.564188) (xy 129.283096 -432.549993) (xy 129.306148 -432.542572) (xy 129.318258 -432.542188)
			(xy 130.258058 -432.542188) (xy 130.27015 -432.542644) (xy 130.293158 -432.550095) (xy 130.312742 -432.564283)
			(xy 130.326993 -432.583822) (xy 130.334517 -432.606805) (xy 130.33502 -432.618896) (xy 130.33502 -435.16042)
			(xy 130.334601 -435.172528) (xy 130.327099 -435.195552) (xy 130.312837 -435.215123) (xy 130.293217 -435.229318)
			(xy 130.270167 -435.236742) (xy 130.258058 -435.237128) (xy 129.318258 -435.237128) (xy 129.306163 -435.236728)
			(xy 129.283156 -435.229256) (xy 129.263574 -435.215053) (xy 129.249326 -435.195504) (xy 129.2418 -435.172514)
			(xy 129.241296 -435.16042) (xy 129.241296 -434.644038) (xy 129.2306 -434.606395) (xy 129.219129 -434.528987)
			(xy 129.218436 -434.48986) (xy 128.335024 -434.48986) (xy 128.335024 -435.489858) (xy 131.218432 -435.489858)
			(xy 131.218905 -435.457301) (xy 131.226855 -435.392675) (xy 131.242645 -435.329505) (xy 131.266036 -435.268738)
			(xy 131.296678 -435.211285) (xy 131.334112 -435.158008) (xy 131.377776 -435.109705) (xy 131.402074 -435.08803)
			(xy 131.482846 -434.923184) (xy 131.487544 -434.912667) (xy 131.491033 -434.889909) (xy 131.48755 -434.867151)
			(xy 131.482846 -434.856636) (xy 131.402074 -434.69179) (xy 131.377805 -434.670085) (xy 131.334148 -434.621782)
			(xy 131.296719 -434.568508) (xy 131.266078 -434.51106) (xy 131.242685 -434.450299) (xy 131.226889 -434.387136)
			(xy 131.218928 -434.322516) (xy 131.218432 -434.289962) (xy 131.219124 -434.250835) (xy 131.230604 -434.173429)
			(xy 131.241292 -434.135784) (xy 131.241292 -433.618894) (xy 131.241806 -433.606784) (xy 131.249289 -433.583748)
			(xy 131.263522 -433.564151) (xy 131.283112 -433.549908) (xy 131.306144 -433.542412) (xy 131.318254 -433.541932)
			(xy 132.258054 -433.541932) (xy 132.270174 -433.542399) (xy 132.29323 -433.549878) (xy 132.312846 -433.564117)
			(xy 132.327098 -433.583723) (xy 132.334593 -433.606775) (xy 132.335016 -433.618894) (xy 132.335016 -434.48986)
			(xy 133.218428 -434.48986) (xy 133.218903 -434.457303) (xy 133.226854 -434.392677) (xy 133.242643 -434.329507)
			(xy 133.266033 -434.26874) (xy 133.296675 -434.211287) (xy 133.334108 -434.15801) (xy 133.377772 -434.109707)
			(xy 133.40207 -434.088032) (xy 133.482842 -433.923186) (xy 133.487539 -433.912668) (xy 133.491028 -433.889911)
			(xy 133.487546 -433.867153) (xy 133.482842 -433.856638) (xy 133.40207 -433.691792) (xy 133.377802 -433.670087)
			(xy 133.334145 -433.621784) (xy 133.296716 -433.56851) (xy 133.266075 -433.511062) (xy 133.242681 -433.450301)
			(xy 133.226885 -433.387138) (xy 133.218924 -433.322518) (xy 133.218428 -433.289964) (xy 133.219121 -433.250837)
			(xy 133.2306 -433.173431) (xy 133.241288 -433.135786) (xy 133.241288 -432.618896) (xy 133.241713 -432.606788)
			(xy 133.249212 -432.583763) (xy 133.263472 -432.564191) (xy 133.283091 -432.549996) (xy 133.306141 -432.542573)
			(xy 133.31825 -432.542188) (xy 134.25805 -432.542188) (xy 134.270142 -432.542651) (xy 134.293149 -432.5501)
			(xy 134.312734 -432.564285) (xy 134.326984 -432.583823) (xy 134.334509 -432.606806) (xy 134.335012 -432.618896)
			(xy 134.335012 -435.16042) (xy 134.334601 -435.172529) (xy 134.327097 -435.195555) (xy 134.312834 -435.215126)
			(xy 134.293212 -435.229321) (xy 134.27016 -435.236743) (xy 134.25805 -435.237128) (xy 133.31825 -435.237128)
			(xy 133.30616 -435.23665) (xy 133.283155 -435.229203) (xy 133.263572 -435.21502) (xy 133.249321 -435.195487)
			(xy 133.241793 -435.172508) (xy 133.241288 -435.16042) (xy 133.241288 -434.644038) (xy 133.230592 -434.606395)
			(xy 133.219121 -434.528987) (xy 133.218428 -434.48986) (xy 132.335016 -434.48986) (xy 132.335016 -435.489858)
			(xy 135.218424 -435.489858) (xy 135.218899 -435.457301) (xy 135.22685 -435.392675) (xy 135.242639 -435.329505)
			(xy 135.266029 -435.268738) (xy 135.296671 -435.211286) (xy 135.334105 -435.158008) (xy 135.377768 -435.109705)
			(xy 135.402066 -435.08803) (xy 135.482838 -434.923184) (xy 135.487537 -434.912667) (xy 135.491026 -434.889909)
			(xy 135.487542 -434.867151) (xy 135.482838 -434.856636) (xy 135.402066 -434.69179) (xy 135.377796 -434.670087)
			(xy 135.334139 -434.621784) (xy 135.29671 -434.568509) (xy 135.26607 -434.511061) (xy 135.242676 -434.4503)
			(xy 135.226881 -434.387136) (xy 135.21892 -434.322516) (xy 135.218424 -434.289962) (xy 135.219116 -434.250835)
			(xy 135.230596 -434.173429) (xy 135.241284 -434.135784) (xy 135.241284 -433.618894) (xy 135.241656 -433.606766)
			(xy 135.249155 -433.5837) (xy 135.263418 -433.564081) (xy 135.283046 -433.549831) (xy 135.306118 -433.542348)
			(xy 135.318246 -433.541932) (xy 136.258046 -433.541932) (xy 136.270162 -433.542372) (xy 136.293206 -433.549872)
			(xy 136.312807 -433.564122) (xy 136.327047 -433.58373) (xy 136.334534 -433.606777) (xy 136.335008 -433.618894)
			(xy 136.335008 -434.48986) (xy 137.21842 -434.48986) (xy 137.218898 -434.457303) (xy 137.226848 -434.392678)
			(xy 137.242637 -434.329508) (xy 137.266027 -434.268741) (xy 137.296668 -434.211288) (xy 137.334101 -434.158011)
			(xy 137.377765 -434.109707) (xy 137.402062 -434.088032) (xy 137.482834 -433.923186) (xy 137.487531 -433.912668)
			(xy 137.491021 -433.889911) (xy 137.487538 -433.867153) (xy 137.482834 -433.856638) (xy 137.402062 -433.691792)
			(xy 137.377792 -433.670089) (xy 137.334135 -433.621785) (xy 137.296707 -433.568511) (xy 137.266066 -433.511062)
			(xy 137.242673 -433.450302) (xy 137.226877 -433.387138) (xy 137.218916 -433.322518) (xy 137.21842 -433.289964)
			(xy 137.219113 -433.250837) (xy 137.230592 -433.173431) (xy 137.24128 -433.135786) (xy 137.24128 -432.618896)
			(xy 137.241712 -432.606789) (xy 137.249211 -432.583765) (xy 137.263469 -432.564194) (xy 137.283086 -432.549998)
			(xy 137.306134 -432.542574) (xy 137.318242 -432.542188) (xy 138.258042 -432.542188) (xy 138.270139 -432.542572)
			(xy 138.293149 -432.550047) (xy 138.312732 -432.564253) (xy 138.326979 -432.583806) (xy 138.334502 -432.606801)
			(xy 138.335004 -432.618896) (xy 138.335004 -435.16042) (xy 138.334601 -435.17253) (xy 138.327096 -435.195557)
			(xy 138.312831 -435.215129) (xy 138.293207 -435.229323) (xy 138.270153 -435.236744) (xy 138.258042 -435.237128)
			(xy 137.318242 -435.237128) (xy 137.306151 -435.236656) (xy 137.283147 -435.229207) (xy 137.263563 -435.215023)
			(xy 137.249313 -435.195488) (xy 137.241785 -435.172509) (xy 137.24128 -435.16042) (xy 137.24128 -434.644038)
			(xy 137.230583 -434.606395) (xy 137.219112 -434.528987) (xy 137.21842 -434.48986) (xy 136.335008 -434.48986)
			(xy 136.335008 -435.489858) (xy 139.218416 -435.489858) (xy 139.218894 -435.457301) (xy 139.226845 -435.392676)
			(xy 139.242633 -435.329506) (xy 139.266023 -435.268739) (xy 139.296665 -435.211286) (xy 139.334097 -435.158009)
			(xy 139.377761 -435.109705) (xy 139.402058 -435.08803) (xy 139.48283 -434.923184) (xy 139.487529 -434.912667)
			(xy 139.491018 -434.889909) (xy 139.487534 -434.86715) (xy 139.48283 -434.856636) (xy 139.402058 -434.69179)
			(xy 139.377786 -434.670089) (xy 139.33413 -434.621785) (xy 139.296701 -434.56851) (xy 139.266061 -434.511061)
			(xy 139.242668 -434.4503) (xy 139.226873 -434.387136) (xy 139.218912 -434.322516) (xy 139.218416 -434.289962)
			(xy 139.219105 -434.250835) (xy 139.230586 -434.173429) (xy 139.241276 -434.135784) (xy 139.241276 -433.618894)
			(xy 139.241656 -433.606767) (xy 139.249154 -433.583702) (xy 139.263415 -433.564084) (xy 139.283041 -433.549834)
			(xy 139.306111 -433.542349) (xy 139.318238 -433.541932) (xy 140.258038 -433.541932) (xy 140.270154 -433.542379)
			(xy 140.293197 -433.549876) (xy 140.312798 -433.564125) (xy 140.327038 -433.583731) (xy 140.334526 -433.606778)
			(xy 140.335 -433.618894) (xy 140.335 -434.48986) (xy 142.21841 -434.48986) (xy 142.218892 -434.457304)
			(xy 142.226842 -434.392678) (xy 142.24263 -434.329508) (xy 142.26602 -434.268742) (xy 142.29666 -434.211289)
			(xy 142.334092 -434.158011) (xy 142.377755 -434.109707) (xy 142.402052 -434.088032) (xy 142.482824 -433.923186)
			(xy 142.487522 -433.912668) (xy 142.491012 -433.889911) (xy 142.487529 -433.867152) (xy 142.482824 -433.856638)
			(xy 142.402052 -433.691792) (xy 142.37778 -433.670091) (xy 142.334124 -433.621787) (xy 142.296696 -433.568512)
			(xy 142.266055 -433.511063) (xy 142.242663 -433.450302) (xy 142.226867 -433.387138) (xy 142.218906 -433.322518)
			(xy 142.21841 -433.289964) (xy 142.219137 -433.250639) (xy 142.230742 -433.172849) (xy 142.241524 -433.135024)
			(xy 142.241524 -432.618896) (xy 142.24191 -432.60681) (xy 142.249382 -432.583822) (xy 142.263594 -432.564268)
			(xy 142.283154 -432.550066) (xy 142.306146 -432.542604) (xy 142.318232 -432.542188) (xy 143.258032 -432.542188)
			(xy 143.270108 -432.542637) (xy 143.293075 -432.550108) (xy 143.312612 -432.564308) (xy 143.326805 -432.58385)
			(xy 143.334268 -432.60682) (xy 143.33474 -432.618896) (xy 143.33474 -435.16042) (xy 143.334253 -435.172492)
			(xy 143.326789 -435.195455) (xy 143.312597 -435.214989) (xy 143.293065 -435.229184) (xy 143.270104 -435.236651)
			(xy 143.258032 -435.237128) (xy 142.318232 -435.237128) (xy 142.306153 -435.23666) (xy 142.283175 -435.229204)
			(xy 142.263626 -435.215011) (xy 142.24942 -435.195472) (xy 142.241948 -435.172499) (xy 142.241524 -435.16042)
			(xy 142.241524 -434.6448) (xy 142.230717 -434.606981) (xy 142.219115 -434.529187) (xy 142.21841 -434.48986)
			(xy 140.335 -434.48986) (xy 140.335 -435.489858) (xy 144.218406 -435.489858) (xy 144.218888 -435.457302)
			(xy 144.226838 -435.392676) (xy 144.242626 -435.329506) (xy 144.266016 -435.26874) (xy 144.296657 -435.211287)
			(xy 144.334089 -435.158009) (xy 144.377751 -435.109705) (xy 144.402048 -435.08803) (xy 144.48282 -434.923184)
			(xy 144.48752 -434.912667) (xy 144.491009 -434.889909) (xy 144.487525 -434.86715) (xy 144.48282 -434.856636)
			(xy 144.402048 -434.69179) (xy 144.377774 -434.670091) (xy 144.334118 -434.621786) (xy 144.29669 -434.568511)
			(xy 144.266051 -434.511062) (xy 144.242658 -434.450301) (xy 144.226863 -434.387137) (xy 144.218902 -434.322516)
			(xy 144.218406 -434.289962) (xy 144.219132 -434.250637) (xy 144.230738 -434.172847) (xy 144.24152 -434.135022)
			(xy 144.24152 -433.618894) (xy 144.242002 -433.606806) (xy 144.249458 -433.583809) (xy 144.263641 -433.564231)
			(xy 144.28317 -433.54998) (xy 144.306142 -433.542444) (xy 144.318228 -433.541932) (xy 145.258028 -433.541932)
			(xy 145.270142 -433.542293) (xy 145.293175 -433.549804) (xy 145.312751 -433.564079) (xy 145.326943 -433.583714)
			(xy 145.334357 -433.606779) (xy 145.334736 -433.618894) (xy 145.334736 -434.48986) (xy 146.218402 -434.48986)
			(xy 146.218886 -434.457304) (xy 146.226836 -434.392678) (xy 146.242624 -434.329509) (xy 146.266014 -434.268742)
			(xy 146.296654 -434.211289) (xy 146.334085 -434.158012) (xy 146.377747 -434.109707) (xy 146.402044 -434.088032)
			(xy 146.482816 -433.923186) (xy 146.487514 -433.912668) (xy 146.491005 -433.889911) (xy 146.487521 -433.867152)
			(xy 146.482816 -433.856638) (xy 146.402044 -433.691792) (xy 146.37777 -433.670093) (xy 146.334115 -433.621788)
			(xy 146.296687 -433.568513) (xy 146.266047 -433.511064) (xy 146.242654 -433.450302) (xy 146.226859 -433.387139)
			(xy 146.218898 -433.322518) (xy 146.218402 -433.289964) (xy 146.219129 -433.250639) (xy 146.230734 -433.172849)
			(xy 146.241516 -433.135024) (xy 146.241516 -432.618896) (xy 146.241909 -432.606811) (xy 146.249381 -432.583824)
			(xy 146.263591 -432.564271) (xy 146.283149 -432.550068) (xy 146.306138 -432.542605) (xy 146.318224 -432.542188)
			(xy 147.258024 -432.542188) (xy 147.270099 -432.542644) (xy 147.293067 -432.550113) (xy 147.312603 -432.564311)
			(xy 147.326797 -432.583851) (xy 147.334259 -432.606821) (xy 147.334732 -432.618896) (xy 147.334732 -435.16042)
			(xy 147.334253 -435.172493) (xy 147.326788 -435.195457) (xy 147.312594 -435.214991) (xy 147.29306 -435.229186)
			(xy 147.270097 -435.236652) (xy 147.258024 -435.237128) (xy 146.318224 -435.237128) (xy 146.306145 -435.236667)
			(xy 146.283166 -435.229209) (xy 146.263617 -435.215014) (xy 146.249412 -435.195473) (xy 146.24194 -435.172499)
			(xy 146.241516 -435.16042) (xy 146.241516 -434.6448) (xy 146.230709 -434.606981) (xy 146.219107 -434.529187)
			(xy 146.218402 -434.48986) (xy 145.334736 -434.48986) (xy 145.334736 -435.489858) (xy 148.218398 -435.489858)
			(xy 148.218882 -435.457302) (xy 148.226832 -435.392676) (xy 148.242621 -435.329507) (xy 148.26601 -435.26874)
			(xy 148.29665 -435.211287) (xy 148.334082 -435.15801) (xy 148.377743 -435.109706) (xy 148.40204 -435.08803)
			(xy 148.482812 -434.923184) (xy 148.487512 -434.912667) (xy 148.491002 -434.889909) (xy 148.487517 -434.86715)
			(xy 148.482812 -434.856636) (xy 148.40204 -434.69179) (xy 148.377765 -434.670093) (xy 148.334109 -434.621788)
			(xy 148.296681 -434.568512) (xy 148.266042 -434.511063) (xy 148.24265 -434.450301) (xy 148.226855 -434.387137)
			(xy 148.218894 -434.322516) (xy 148.218398 -434.289962) (xy 148.219125 -434.250637) (xy 148.23073 -434.172847)
			(xy 148.241512 -434.135022) (xy 148.241512 -433.618894) (xy 148.242002 -433.606807) (xy 148.249457 -433.583811)
			(xy 148.263639 -433.564234) (xy 148.283165 -433.549982) (xy 148.306135 -433.542445) (xy 148.31822 -433.541932)
			(xy 149.25802 -433.541932) (xy 149.270133 -433.5423) (xy 149.293167 -433.549808) (xy 149.312742 -433.564081)
			(xy 149.326935 -433.583715) (xy 149.334349 -433.606779) (xy 149.334728 -433.618894) (xy 149.334728 -434.48986)
			(xy 150.218394 -434.48986) (xy 150.218847 -434.457302) (xy 150.226798 -434.392675) (xy 150.242589 -434.329503)
			(xy 150.265983 -434.268735) (xy 150.296629 -434.211283) (xy 150.334067 -434.158006) (xy 150.377736 -434.109705)
			(xy 150.402036 -434.088032) (xy 150.482808 -433.923186) (xy 150.487506 -433.912668) (xy 150.490997 -433.889911)
			(xy 150.487513 -433.867152) (xy 150.482808 -433.856638) (xy 150.402036 -433.691792) (xy 150.377761 -433.670095)
			(xy 150.334105 -433.62179) (xy 150.296678 -433.568513) (xy 150.266038 -433.511064) (xy 150.242646 -433.450303)
			(xy 150.226851 -433.387139) (xy 150.21889 -433.322518) (xy 150.218394 -433.289964) (xy 150.219121 -433.250639)
			(xy 150.230726 -433.172849) (xy 150.241508 -433.135024) (xy 150.241508 -432.618896) (xy 150.241909 -432.606811)
			(xy 150.24938 -432.583826) (xy 150.263588 -432.564274) (xy 150.283144 -432.550071) (xy 150.306131 -432.542606)
			(xy 150.318216 -432.542188) (xy 151.258016 -432.542188) (xy 151.270091 -432.542651) (xy 151.293058 -432.550117)
			(xy 151.312594 -432.564314) (xy 151.326788 -432.583853) (xy 151.334251 -432.606821) (xy 151.334724 -432.618896)
			(xy 151.334724 -435.16042) (xy 151.334253 -435.172494) (xy 151.326787 -435.195459) (xy 151.312591 -435.214994)
			(xy 151.293055 -435.229189) (xy 151.27009 -435.236654) (xy 151.258016 -435.237128) (xy 150.318216 -435.237128)
			(xy 150.306144 -435.236622) (xy 150.283181 -435.229167) (xy 150.263645 -435.21498) (xy 150.24945 -435.195451)
			(xy 150.241983 -435.172492) (xy 150.241508 -435.16042) (xy 150.241508 -434.6448) (xy 150.230701 -434.606981)
			(xy 150.219099 -434.529187) (xy 150.218394 -434.48986) (xy 149.334728 -434.48986) (xy 149.334728 -435.489858)
			(xy 152.21839 -435.489858) (xy 152.218843 -435.4573) (xy 152.226794 -435.392673) (xy 152.242585 -435.329501)
			(xy 152.265979 -435.268734) (xy 152.296625 -435.211281) (xy 152.334063 -435.158004) (xy 152.377732 -435.109703)
			(xy 152.402032 -435.08803) (xy 152.482804 -434.923184) (xy 152.487504 -434.912667) (xy 152.490995 -434.889909)
			(xy 152.487509 -434.86715) (xy 152.482804 -434.856636) (xy 152.402032 -434.69179) (xy 152.377755 -434.670095)
			(xy 152.3341 -434.621789) (xy 152.296673 -434.568512) (xy 152.266033 -434.511063) (xy 152.242641 -434.450301)
			(xy 152.226847 -434.387137) (xy 152.218886 -434.322516) (xy 152.21839 -434.289962) (xy 152.219117 -434.250637)
			(xy 152.230722 -434.172847) (xy 152.241504 -434.135022) (xy 152.241504 -433.618894) (xy 152.242002 -433.606808)
			(xy 152.249456 -433.583813) (xy 152.263636 -433.564236) (xy 152.28316 -433.549985) (xy 152.306128 -433.542447)
			(xy 152.318212 -433.541932) (xy 153.258012 -433.541932) (xy 153.270125 -433.542306) (xy 153.293158 -433.549813)
			(xy 153.312734 -433.564084) (xy 153.326927 -433.583717) (xy 153.334341 -433.60678) (xy 153.33472 -433.618894)
			(xy 153.33472 -434.48986) (xy 154.218386 -434.48986) (xy 154.218842 -434.457302) (xy 154.226793 -434.392675)
			(xy 154.242584 -434.329504) (xy 154.265977 -434.268736) (xy 154.296622 -434.211283) (xy 154.33406 -434.158007)
			(xy 154.377728 -434.109705) (xy 154.402028 -434.088032) (xy 154.4828 -433.923186) (xy 154.487499 -433.912668)
			(xy 154.49099 -433.889911) (xy 154.487505 -433.867152) (xy 154.4828 -433.856638) (xy 154.402028 -433.691792)
			(xy 154.377751 -433.670097) (xy 154.334096 -433.621791) (xy 154.296669 -433.568514) (xy 154.26603 -433.511065)
			(xy 154.242638 -433.450303) (xy 154.226843 -433.387139) (xy 154.218882 -433.322518) (xy 154.218386 -433.289964)
			(xy 154.219114 -433.250639) (xy 154.230718 -433.172849) (xy 154.2415 -433.135024) (xy 154.2415 -432.618896)
			(xy 154.241909 -432.606812) (xy 154.249379 -432.583828) (xy 154.263586 -432.564277) (xy 154.283139 -432.550073)
			(xy 154.306124 -432.542607) (xy 154.318208 -432.542188) (xy 155.258008 -432.542188) (xy 155.270083 -432.542657)
			(xy 155.293049 -432.550122) (xy 155.312586 -432.564317) (xy 155.32678 -432.583854) (xy 155.334243 -432.606821)
			(xy 155.334716 -432.618896) (xy 155.334716 -433.130695) (xy 197.035917 -433.130695) (xy 197.035917 -432.953425)
			(xy 197.04387 -432.776334) (xy 197.059761 -432.599778) (xy 197.083556 -432.424113) (xy 197.115209 -432.249692)
			(xy 197.154655 -432.076867) (xy 197.201815 -431.905986) (xy 197.256594 -431.737392) (xy 197.318882 -431.571427)
			(xy 197.388554 -431.408422) (xy 197.465468 -431.248708) (xy 197.549471 -431.092605) (xy 197.640392 -430.940428)
			(xy 197.738049 -430.792484) (xy 197.842246 -430.64907) (xy 197.952772 -430.510475) (xy 198.069404 -430.376978)
			(xy 198.191909 -430.248849) (xy 198.320038 -430.126344) (xy 198.453535 -430.009712) (xy 198.59213 -429.899186)
			(xy 198.735544 -429.794989) (xy 198.883488 -429.697332) (xy 199.035665 -429.606411) (xy 199.191768 -429.522408)
			(xy 199.351482 -429.445494) (xy 199.514487 -429.375822) (xy 199.680452 -429.313534) (xy 199.849046 -429.258755)
			(xy 200.019927 -429.211595) (xy 200.192752 -429.172149) (xy 200.367173 -429.140496) (xy 200.542838 -429.116701)
			(xy 200.719394 -429.10081) (xy 200.896485 -429.092857) (xy 201.073755 -429.092857) (xy 201.250846 -429.10081)
			(xy 201.427402 -429.116701) (xy 201.603067 -429.140496) (xy 201.777488 -429.172149) (xy 201.950313 -429.211595)
			(xy 202.121194 -429.258755) (xy 202.289788 -429.313534) (xy 202.455753 -429.375822) (xy 202.618758 -429.445494)
			(xy 202.778472 -429.522408) (xy 202.934575 -429.606411) (xy 203.086752 -429.697332) (xy 203.234696 -429.794989)
			(xy 203.37811 -429.899186) (xy 203.516705 -430.009712) (xy 203.650202 -430.126344) (xy 203.778331 -430.248849)
			(xy 203.900836 -430.376978) (xy 204.017468 -430.510475) (xy 204.127994 -430.64907) (xy 204.232191 -430.792484)
			(xy 204.329848 -430.940428) (xy 204.420769 -431.092605) (xy 204.504772 -431.248708) (xy 204.581686 -431.408422)
			(xy 204.651358 -431.571427) (xy 204.713646 -431.737392) (xy 204.768425 -431.905986) (xy 204.815585 -432.076867)
			(xy 204.855031 -432.249692) (xy 204.886684 -432.424113) (xy 204.910479 -432.599778) (xy 204.92637 -432.776334)
			(xy 204.934323 -432.953425) (xy 204.93482 -433.04206) (xy 204.934323 -433.130695) (xy 204.92637 -433.307786)
			(xy 204.910479 -433.484342) (xy 204.886684 -433.660007) (xy 204.855031 -433.834428) (xy 204.815585 -434.007253)
			(xy 204.768425 -434.178134) (xy 204.713646 -434.346728) (xy 204.651358 -434.512693) (xy 204.581686 -434.675698)
			(xy 204.504772 -434.835412) (xy 204.420769 -434.991515) (xy 204.329848 -435.143692) (xy 204.232191 -435.291636)
			(xy 204.127994 -435.43505) (xy 204.057751 -435.523132) (xy 205.85684 -435.523132) (xy 205.85684 -415.567368)
			(xy 205.857337 -415.542419) (xy 205.865152 -415.493137) (xy 205.88057 -415.44568) (xy 205.903211 -415.401214)
			(xy 205.93252 -415.360831) (xy 205.949804 -415.342832) (xy 206.989172 -414.303464) (xy 207.007169 -414.286175)
			(xy 207.047542 -414.256843) (xy 207.092007 -414.234188) (xy 207.139468 -414.218769) (xy 207.188756 -414.210963)
			(xy 207.213708 -414.2105) (xy 232.807256 -414.2105) (xy 239.488472 -407.529284) (xy 239.506473 -407.512)
			(xy 239.546848 -407.482676) (xy 239.591312 -407.460027) (xy 239.638771 -407.444612) (xy 239.688058 -407.436808)
			(xy 239.713008 -407.43632) (xy 280.100532 -407.43632) (xy 280.125481 -407.436823) (xy 280.174763 -407.444637)
			(xy 280.222219 -407.460054) (xy 280.266685 -407.482694) (xy 280.307069 -407.512001) (xy 280.325068 -407.529284)
			(xy 280.739596 -407.943812) (xy 280.756896 -407.961798) (xy 280.786219 -408.002177) (xy 280.808865 -408.046645)
			(xy 280.824276 -408.094108) (xy 280.832075 -408.143397) (xy 280.83256 -408.168348) (xy 280.83256 -410.057453)
			(xy 304.945246 -410.057453) (xy 304.945246 -410.002947) (xy 304.953003 -409.948996) (xy 304.968358 -409.896698)
			(xy 304.991001 -409.847117) (xy 305.020468 -409.801263) (xy 305.056162 -409.76007) (xy 305.097354 -409.724375)
			(xy 305.143207 -409.694906) (xy 305.192786 -409.672263) (xy 305.245084 -409.656905) (xy 305.299035 -409.649147)
			(xy 305.326288 -409.64866) (xy 306.189888 -409.64866) (xy 306.217139 -409.649186) (xy 306.271087 -409.656941)
			(xy 306.323382 -409.672295) (xy 306.372959 -409.694935) (xy 306.41881 -409.7244) (xy 306.460001 -409.760091)
			(xy 306.495693 -409.80128) (xy 306.525159 -409.84713) (xy 306.547801 -409.896707) (xy 306.563156 -409.949001)
			(xy 306.570913 -410.002949) (xy 306.570913 -410.057451) (xy 306.570912 -410.057456) (xy 308.008423 -410.057456)
			(xy 308.008423 -410.002944) (xy 308.016181 -409.948986) (xy 308.03154 -409.896681) (xy 308.054187 -409.847095)
			(xy 308.08366 -409.801236) (xy 308.119359 -409.76004) (xy 308.160559 -409.724343) (xy 308.206419 -409.694873)
			(xy 308.256007 -409.67223) (xy 308.308313 -409.656875) (xy 308.362272 -409.649121) (xy 308.389528 -409.64866)
			(xy 309.253128 -409.64866) (xy 309.280376 -409.649212) (xy 309.334316 -409.656971) (xy 309.386603 -409.672327)
			(xy 309.436172 -409.694968) (xy 309.482015 -409.724433) (xy 309.523199 -409.760121) (xy 309.558884 -409.801307)
			(xy 309.588345 -409.847152) (xy 309.610982 -409.896724) (xy 309.626335 -409.949012) (xy 309.63409 -410.002952)
			(xy 309.63409 -410.057448) (xy 309.634089 -410.057452) (xy 311.071746 -410.057452) (xy 311.071746 -410.002948)
			(xy 311.079502 -409.948998) (xy 311.094857 -409.896702) (xy 311.117498 -409.847123) (xy 311.146963 -409.80127)
			(xy 311.182654 -409.760077) (xy 311.223844 -409.724383) (xy 311.269695 -409.694913) (xy 311.319272 -409.672268)
			(xy 311.371567 -409.656909) (xy 311.425516 -409.649148) (xy 311.452768 -409.64866) (xy 312.316368 -409.64866)
			(xy 312.34362 -409.649185) (xy 312.39757 -409.656938) (xy 312.449867 -409.67229) (xy 312.499447 -409.694928)
			(xy 312.545301 -409.724393) (xy 312.586494 -409.760084) (xy 312.622188 -409.801274) (xy 312.651656 -409.847125)
			(xy 312.674299 -409.896703) (xy 312.689655 -409.948999) (xy 312.697413 -410.002948) (xy 312.697413 -410.057452)
			(xy 312.697412 -410.057456) (xy 314.134923 -410.057456) (xy 314.134923 -410.002944) (xy 314.142681 -409.948988)
			(xy 314.158039 -409.896685) (xy 314.180684 -409.8471) (xy 314.210155 -409.801243) (xy 314.245852 -409.760047)
			(xy 314.287049 -409.72435) (xy 314.332907 -409.69488) (xy 314.382493 -409.672236) (xy 314.434796 -409.656879)
			(xy 314.488752 -409.649122) (xy 314.516008 -409.64866) (xy 315.379608 -409.64866) (xy 315.406857 -409.649211)
			(xy 315.460799 -409.656968) (xy 315.513088 -409.672322) (xy 315.56266 -409.694962) (xy 315.608506 -409.724426)
			(xy 315.649691 -409.760114) (xy 315.685379 -409.801301) (xy 315.714842 -409.847147) (xy 315.737481 -409.896719)
			(xy 315.752834 -409.949009) (xy 315.76059 -410.002951) (xy 315.76059 -410.057449) (xy 315.760589 -410.057457)
			(xy 317.198123 -410.057457) (xy 317.198123 -410.002943) (xy 317.205882 -409.948983) (xy 317.221242 -409.896677)
			(xy 317.24389 -409.847089) (xy 317.273365 -409.80123) (xy 317.309066 -409.760033) (xy 317.350268 -409.724336)
			(xy 317.396131 -409.694867) (xy 317.445722 -409.672225) (xy 317.49803 -409.656872) (xy 317.551991 -409.64912)
			(xy 317.579248 -409.64866) (xy 318.442848 -409.64866) (xy 318.470095 -409.649213) (xy 318.524033 -409.656975)
			(xy 318.576317 -409.672333) (xy 318.625884 -409.694975) (xy 318.671725 -409.72444) (xy 318.712906 -409.760128)
			(xy 318.748589 -409.801314) (xy 318.778048 -409.847158) (xy 318.800684 -409.896728) (xy 318.816035 -409.949014)
			(xy 318.82379 -410.002953) (xy 318.82379 -410.057447) (xy 318.823789 -410.057453) (xy 320.261446 -410.057453)
			(xy 320.261446 -410.002947) (xy 320.269203 -409.948996) (xy 320.284558 -409.896698) (xy 320.307201 -409.847117)
			(xy 320.336668 -409.801263) (xy 320.372362 -409.76007) (xy 320.413554 -409.724375) (xy 320.459407 -409.694906)
			(xy 320.508986 -409.672263) (xy 320.561284 -409.656905) (xy 320.615235 -409.649147) (xy 320.642488 -409.64866)
			(xy 321.506088 -409.64866) (xy 321.533339 -409.649186) (xy 321.587287 -409.656941) (xy 321.639582 -409.672295)
			(xy 321.689159 -409.694935) (xy 321.73501 -409.7244) (xy 321.776201 -409.760091) (xy 321.811893 -409.80128)
			(xy 321.841359 -409.84713) (xy 321.864001 -409.896707) (xy 321.879356 -409.949001) (xy 321.887113 -410.002949)
			(xy 321.887113 -410.057451) (xy 321.887112 -410.057456) (xy 323.324623 -410.057456) (xy 323.324623 -410.002944)
			(xy 323.332381 -409.948986) (xy 323.34774 -409.896681) (xy 323.370387 -409.847095) (xy 323.39986 -409.801236)
			(xy 323.435559 -409.76004) (xy 323.476759 -409.724343) (xy 323.522619 -409.694873) (xy 323.572207 -409.67223)
			(xy 323.624513 -409.656875) (xy 323.678472 -409.649121) (xy 323.705728 -409.64866) (xy 324.569328 -409.64866)
			(xy 324.596576 -409.649212) (xy 324.650516 -409.656971) (xy 324.702803 -409.672327) (xy 324.752372 -409.694968)
			(xy 324.798215 -409.724433) (xy 324.839399 -409.760121) (xy 324.875084 -409.801307) (xy 324.904545 -409.847152)
			(xy 324.927182 -409.896724) (xy 324.942535 -409.949012) (xy 324.95029 -410.002952) (xy 324.95029 -410.057448)
			(xy 324.950289 -410.057452) (xy 326.387946 -410.057452) (xy 326.387946 -410.002948) (xy 326.395702 -409.948998)
			(xy 326.411057 -409.896702) (xy 326.433698 -409.847123) (xy 326.463163 -409.80127) (xy 326.498854 -409.760077)
			(xy 326.540044 -409.724383) (xy 326.585895 -409.694913) (xy 326.635472 -409.672268) (xy 326.687767 -409.656909)
			(xy 326.741716 -409.649148) (xy 326.768968 -409.64866) (xy 327.632568 -409.64866) (xy 327.65982 -409.649185)
			(xy 327.71377 -409.656938) (xy 327.766067 -409.67229) (xy 327.815647 -409.694928) (xy 327.861501 -409.724393)
			(xy 327.902694 -409.760084) (xy 327.938388 -409.801274) (xy 327.967856 -409.847125) (xy 327.990499 -409.896703)
			(xy 328.005855 -409.948999) (xy 328.013613 -410.002948) (xy 328.013613 -410.057452) (xy 328.013612 -410.057456)
			(xy 329.451123 -410.057456) (xy 329.451123 -410.002944) (xy 329.458881 -409.948988) (xy 329.474239 -409.896685)
			(xy 329.496884 -409.8471) (xy 329.526355 -409.801243) (xy 329.562052 -409.760047) (xy 329.603249 -409.72435)
			(xy 329.649107 -409.69488) (xy 329.698693 -409.672236) (xy 329.750996 -409.656879) (xy 329.804952 -409.649122)
			(xy 329.832208 -409.64866) (xy 330.695808 -409.64866) (xy 330.723057 -409.649211) (xy 330.776999 -409.656968)
			(xy 330.829288 -409.672322) (xy 330.87886 -409.694962) (xy 330.924706 -409.724426) (xy 330.965891 -409.760114)
			(xy 331.001579 -409.801301) (xy 331.031042 -409.847147) (xy 331.053681 -409.896719) (xy 331.069034 -409.949009)
			(xy 331.07679 -410.002951) (xy 331.07679 -410.057449) (xy 331.076789 -410.057457) (xy 332.514323 -410.057457)
			(xy 332.514323 -410.002943) (xy 332.522082 -409.948983) (xy 332.537442 -409.896677) (xy 332.56009 -409.847089)
			(xy 332.589565 -409.80123) (xy 332.625266 -409.760033) (xy 332.666468 -409.724336) (xy 332.712331 -409.694867)
			(xy 332.761922 -409.672225) (xy 332.81423 -409.656872) (xy 332.868191 -409.64912) (xy 332.895448 -409.64866)
			(xy 333.759048 -409.64866) (xy 333.786295 -409.649213) (xy 333.840233 -409.656975) (xy 333.892517 -409.672333)
			(xy 333.942084 -409.694975) (xy 333.987925 -409.72444) (xy 334.029106 -409.760128) (xy 334.064789 -409.801314)
			(xy 334.094248 -409.847158) (xy 334.116884 -409.896728) (xy 334.132235 -409.949014) (xy 334.13999 -410.002953)
			(xy 334.13999 -410.057447) (xy 334.139989 -410.057453) (xy 335.577646 -410.057453) (xy 335.577646 -410.002947)
			(xy 335.585403 -409.948996) (xy 335.600758 -409.896698) (xy 335.623401 -409.847117) (xy 335.652868 -409.801263)
			(xy 335.688562 -409.76007) (xy 335.729754 -409.724375) (xy 335.775607 -409.694906) (xy 335.825186 -409.672263)
			(xy 335.877484 -409.656905) (xy 335.931435 -409.649147) (xy 335.958688 -409.64866) (xy 336.822288 -409.64866)
			(xy 336.849539 -409.649186) (xy 336.903487 -409.656941) (xy 336.955782 -409.672295) (xy 337.005359 -409.694935)
			(xy 337.05121 -409.7244) (xy 337.092401 -409.760091) (xy 337.128093 -409.80128) (xy 337.157559 -409.84713)
			(xy 337.180201 -409.896707) (xy 337.195556 -409.949001) (xy 337.203313 -410.002949) (xy 337.203313 -410.057451)
			(xy 337.203312 -410.057456) (xy 338.640823 -410.057456) (xy 338.640823 -410.002944) (xy 338.648581 -409.948986)
			(xy 338.66394 -409.896681) (xy 338.686587 -409.847095) (xy 338.71606 -409.801236) (xy 338.751759 -409.76004)
			(xy 338.792959 -409.724343) (xy 338.838819 -409.694873) (xy 338.888407 -409.67223) (xy 338.940713 -409.656875)
			(xy 338.994672 -409.649121) (xy 339.021928 -409.64866) (xy 339.885528 -409.64866) (xy 339.912776 -409.649212)
			(xy 339.966716 -409.656971) (xy 340.019003 -409.672327) (xy 340.068572 -409.694968) (xy 340.114415 -409.724433)
			(xy 340.155599 -409.760121) (xy 340.191284 -409.801307) (xy 340.220745 -409.847152) (xy 340.243382 -409.896724)
			(xy 340.258735 -409.949012) (xy 340.26649 -410.002952) (xy 340.26649 -410.057448) (xy 340.266489 -410.057452)
			(xy 341.704146 -410.057452) (xy 341.704146 -410.002948) (xy 341.711902 -409.948998) (xy 341.727257 -409.896702)
			(xy 341.749898 -409.847123) (xy 341.779363 -409.80127) (xy 341.815054 -409.760077) (xy 341.856244 -409.724383)
			(xy 341.902095 -409.694913) (xy 341.951672 -409.672268) (xy 342.003967 -409.656909) (xy 342.057916 -409.649148)
			(xy 342.085168 -409.64866) (xy 342.948768 -409.64866) (xy 342.97602 -409.649185) (xy 343.02997 -409.656938)
			(xy 343.082267 -409.67229) (xy 343.131847 -409.694928) (xy 343.177701 -409.724393) (xy 343.218894 -409.760084)
			(xy 343.254588 -409.801274) (xy 343.284056 -409.847125) (xy 343.306699 -409.896703) (xy 343.322055 -409.948999)
			(xy 343.329813 -410.002948) (xy 343.329813 -410.057452) (xy 343.329812 -410.057456) (xy 344.767323 -410.057456)
			(xy 344.767323 -410.002944) (xy 344.775081 -409.948988) (xy 344.790439 -409.896685) (xy 344.813084 -409.8471)
			(xy 344.842555 -409.801243) (xy 344.878252 -409.760047) (xy 344.919449 -409.72435) (xy 344.965307 -409.69488)
			(xy 345.014893 -409.672236) (xy 345.067196 -409.656879) (xy 345.121152 -409.649122) (xy 345.148408 -409.64866)
			(xy 346.012008 -409.64866) (xy 346.039257 -409.649211) (xy 346.093199 -409.656968) (xy 346.145488 -409.672322)
			(xy 346.19506 -409.694962) (xy 346.240906 -409.724426) (xy 346.282091 -409.760114) (xy 346.317779 -409.801301)
			(xy 346.347242 -409.847147) (xy 346.369881 -409.896719) (xy 346.385234 -409.949009) (xy 346.39299 -410.002951)
			(xy 346.39299 -410.057449) (xy 346.392989 -410.057457) (xy 347.830523 -410.057457) (xy 347.830523 -410.002943)
			(xy 347.838282 -409.948983) (xy 347.853642 -409.896677) (xy 347.87629 -409.847089) (xy 347.905765 -409.80123)
			(xy 347.941466 -409.760033) (xy 347.982668 -409.724336) (xy 348.028531 -409.694867) (xy 348.078122 -409.672225)
			(xy 348.13043 -409.656872) (xy 348.184391 -409.64912) (xy 348.211648 -409.64866) (xy 349.075248 -409.64866)
			(xy 349.102495 -409.649213) (xy 349.156433 -409.656975) (xy 349.208717 -409.672333) (xy 349.258284 -409.694975)
			(xy 349.304125 -409.72444) (xy 349.345306 -409.760128) (xy 349.380989 -409.801314) (xy 349.410448 -409.847158)
			(xy 349.433084 -409.896728) (xy 349.448435 -409.949014) (xy 349.45619 -410.002953) (xy 349.45619 -410.057447)
			(xy 349.456189 -410.057453) (xy 350.893846 -410.057453) (xy 350.893846 -410.002947) (xy 350.901603 -409.948996)
			(xy 350.916958 -409.896698) (xy 350.939601 -409.847117) (xy 350.969068 -409.801263) (xy 351.004762 -409.76007)
			(xy 351.045954 -409.724375) (xy 351.091807 -409.694906) (xy 351.141386 -409.672263) (xy 351.193684 -409.656905)
			(xy 351.247635 -409.649147) (xy 351.274888 -409.64866) (xy 352.138488 -409.64866) (xy 352.165739 -409.649186)
			(xy 352.219687 -409.656941) (xy 352.271982 -409.672295) (xy 352.321559 -409.694935) (xy 352.36741 -409.7244)
			(xy 352.408601 -409.760091) (xy 352.444293 -409.80128) (xy 352.473759 -409.84713) (xy 352.496401 -409.896707)
			(xy 352.511756 -409.949001) (xy 352.519513 -410.002949) (xy 352.519513 -410.057451) (xy 352.519512 -410.057457)
			(xy 372.388023 -410.057457) (xy 372.388023 -410.002943) (xy 372.395781 -409.948985) (xy 372.41114 -409.896681)
			(xy 372.433787 -409.847094) (xy 372.46326 -409.801236) (xy 372.49896 -409.760039) (xy 372.54016 -409.724342)
			(xy 372.586021 -409.694872) (xy 372.635609 -409.67223) (xy 372.687915 -409.656875) (xy 372.741873 -409.649121)
			(xy 372.76913 -409.64866) (xy 373.63273 -409.64866) (xy 373.659978 -409.649212) (xy 373.713917 -409.656972)
			(xy 373.766204 -409.672328) (xy 373.815773 -409.694969) (xy 373.861616 -409.724434) (xy 373.902799 -409.760122)
			(xy 373.938484 -409.801308) (xy 373.967945 -409.847153) (xy 373.990583 -409.896724) (xy 374.005935 -409.949012)
			(xy 374.01369 -410.002952) (xy 374.01369 -410.057448) (xy 374.013689 -410.057452) (xy 375.451346 -410.057452)
			(xy 375.451346 -410.002948) (xy 375.459102 -409.948998) (xy 375.474457 -409.896701) (xy 375.497098 -409.847122)
			(xy 375.526564 -409.801269) (xy 375.562255 -409.760076) (xy 375.603445 -409.724382) (xy 375.649296 -409.694912)
			(xy 375.698873 -409.672268) (xy 375.751169 -409.656909) (xy 375.805118 -409.649148) (xy 375.83237 -409.64866)
			(xy 376.69597 -409.64866) (xy 376.723222 -409.649185) (xy 376.777172 -409.656938) (xy 376.829469 -409.67229)
			(xy 376.879048 -409.694929) (xy 376.924901 -409.724394) (xy 376.966094 -409.760084) (xy 377.001788 -409.801274)
			(xy 377.031257 -409.847125) (xy 377.053899 -409.896703) (xy 377.069256 -409.948999) (xy 377.077013 -410.002948)
			(xy 377.077013 -410.057452) (xy 377.077012 -410.057456) (xy 378.514523 -410.057456) (xy 378.514523 -410.002944)
			(xy 378.522281 -409.948988) (xy 378.537639 -409.896685) (xy 378.560284 -409.8471) (xy 378.589755 -409.801242)
			(xy 378.625453 -409.760046) (xy 378.66665 -409.724349) (xy 378.712509 -409.694879) (xy 378.762094 -409.672235)
			(xy 378.814398 -409.656879) (xy 378.868354 -409.649122) (xy 378.89561 -409.64866) (xy 379.75921 -409.64866)
			(xy 379.786458 -409.649211) (xy 379.840401 -409.656968) (xy 379.89269 -409.672323) (xy 379.942261 -409.694962)
			(xy 379.988107 -409.724426) (xy 380.029292 -409.760115) (xy 380.06498 -409.801301) (xy 380.094442 -409.847147)
			(xy 380.117081 -409.89672) (xy 380.132434 -409.949009) (xy 380.14019 -410.002952) (xy 380.14019 -410.057448)
			(xy 380.14019 -410.057451) (xy 381.577846 -410.057451) (xy 381.577846 -410.002949) (xy 381.585602 -409.949001)
			(xy 381.600955 -409.896706) (xy 381.623595 -409.847128) (xy 381.653059 -409.801276) (xy 381.688748 -409.760083)
			(xy 381.729936 -409.724389) (xy 381.775784 -409.694919) (xy 381.825359 -409.672273) (xy 381.877652 -409.656912)
			(xy 381.931599 -409.649149) (xy 381.95885 -409.64866) (xy 382.82245 -409.64866) (xy 382.849703 -409.649184)
			(xy 382.903655 -409.656934) (xy 382.955954 -409.672285) (xy 383.005536 -409.694923) (xy 383.051392 -409.724387)
			(xy 383.092587 -409.760077) (xy 383.128283 -409.801268) (xy 383.157753 -409.84712) (xy 383.180398 -409.896699)
			(xy 383.195755 -409.948996) (xy 383.203513 -410.002947) (xy 383.203513 -410.057453) (xy 384.641046 -410.057453)
			(xy 384.641046 -410.002947) (xy 384.648803 -409.948996) (xy 384.664159 -409.896697) (xy 384.686801 -409.847117)
			(xy 384.716269 -409.801263) (xy 384.751962 -409.760069) (xy 384.793155 -409.724375) (xy 384.839008 -409.694906)
			(xy 384.888588 -409.672262) (xy 384.940886 -409.656905) (xy 384.994837 -409.649147) (xy 385.02209 -409.64866)
			(xy 385.88569 -409.64866) (xy 385.912941 -409.649187) (xy 385.966889 -409.656942) (xy 386.019183 -409.672296)
			(xy 386.06876 -409.694936) (xy 386.114611 -409.724401) (xy 386.155801 -409.760092) (xy 386.191493 -409.801281)
			(xy 386.22096 -409.847131) (xy 386.243601 -409.896707) (xy 386.258956 -409.949002) (xy 386.266713 -410.002949)
			(xy 386.266713 -410.057451) (xy 386.266712 -410.057457) (xy 387.704223 -410.057457) (xy 387.704223 -410.002943)
			(xy 387.711981 -409.948985) (xy 387.72734 -409.896681) (xy 387.749987 -409.847094) (xy 387.77946 -409.801236)
			(xy 387.81516 -409.760039) (xy 387.85636 -409.724342) (xy 387.902221 -409.694872) (xy 387.951809 -409.67223)
			(xy 388.004115 -409.656875) (xy 388.058073 -409.649121) (xy 388.08533 -409.64866) (xy 388.94893 -409.64866)
			(xy 388.976178 -409.649212) (xy 389.030117 -409.656972) (xy 389.082404 -409.672328) (xy 389.131973 -409.694969)
			(xy 389.177816 -409.724434) (xy 389.218999 -409.760122) (xy 389.254684 -409.801308) (xy 389.284145 -409.847153)
			(xy 389.306783 -409.896724) (xy 389.322135 -409.949012) (xy 389.32989 -410.002952) (xy 389.32989 -410.057448)
			(xy 389.329889 -410.057452) (xy 390.767546 -410.057452) (xy 390.767546 -410.002948) (xy 390.775302 -409.948998)
			(xy 390.790657 -409.896701) (xy 390.813298 -409.847122) (xy 390.842764 -409.801269) (xy 390.878455 -409.760076)
			(xy 390.919645 -409.724382) (xy 390.965496 -409.694912) (xy 391.015073 -409.672268) (xy 391.067369 -409.656909)
			(xy 391.121318 -409.649148) (xy 391.14857 -409.64866) (xy 392.01217 -409.64866) (xy 392.039422 -409.649185)
			(xy 392.093372 -409.656938) (xy 392.145669 -409.67229) (xy 392.195248 -409.694929) (xy 392.241101 -409.724394)
			(xy 392.282294 -409.760084) (xy 392.317988 -409.801274) (xy 392.347457 -409.847125) (xy 392.370099 -409.896703)
			(xy 392.385456 -409.948999) (xy 392.393213 -410.002948) (xy 392.393213 -410.057452) (xy 392.393212 -410.057456)
			(xy 393.830723 -410.057456) (xy 393.830723 -410.002944) (xy 393.838481 -409.948988) (xy 393.853839 -409.896685)
			(xy 393.876484 -409.8471) (xy 393.905955 -409.801242) (xy 393.941653 -409.760046) (xy 393.98285 -409.724349)
			(xy 394.028709 -409.694879) (xy 394.078294 -409.672235) (xy 394.130598 -409.656879) (xy 394.184554 -409.649122)
			(xy 394.21181 -409.64866) (xy 395.07541 -409.64866) (xy 395.102658 -409.649211) (xy 395.156601 -409.656968)
			(xy 395.20889 -409.672323) (xy 395.258461 -409.694962) (xy 395.304307 -409.724426) (xy 395.345492 -409.760115)
			(xy 395.38118 -409.801301) (xy 395.410642 -409.847147) (xy 395.433281 -409.89672) (xy 395.448634 -409.949009)
			(xy 395.45639 -410.002952) (xy 395.45639 -410.057448) (xy 395.45639 -410.057451) (xy 396.894046 -410.057451)
			(xy 396.894046 -410.002949) (xy 396.901802 -409.949001) (xy 396.917155 -409.896706) (xy 396.939795 -409.847128)
			(xy 396.969259 -409.801276) (xy 397.004948 -409.760083) (xy 397.046136 -409.724389) (xy 397.091984 -409.694919)
			(xy 397.141559 -409.672273) (xy 397.193852 -409.656912) (xy 397.247799 -409.649149) (xy 397.27505 -409.64866)
			(xy 398.13865 -409.64866) (xy 398.165903 -409.649184) (xy 398.219855 -409.656934) (xy 398.272154 -409.672285)
			(xy 398.321736 -409.694923) (xy 398.367592 -409.724387) (xy 398.408787 -409.760077) (xy 398.444483 -409.801268)
			(xy 398.473953 -409.84712) (xy 398.496598 -409.896699) (xy 398.511955 -409.948996) (xy 398.519713 -410.002947)
			(xy 398.519713 -410.057453) (xy 399.957246 -410.057453) (xy 399.957246 -410.002947) (xy 399.965003 -409.948996)
			(xy 399.980359 -409.896697) (xy 400.003001 -409.847117) (xy 400.032469 -409.801263) (xy 400.068162 -409.760069)
			(xy 400.109355 -409.724375) (xy 400.155208 -409.694906) (xy 400.204788 -409.672262) (xy 400.257086 -409.656905)
			(xy 400.311037 -409.649147) (xy 400.33829 -409.64866) (xy 401.20189 -409.64866) (xy 401.229141 -409.649187)
			(xy 401.283089 -409.656942) (xy 401.335383 -409.672296) (xy 401.38496 -409.694936) (xy 401.430811 -409.724401)
			(xy 401.472001 -409.760092) (xy 401.507693 -409.801281) (xy 401.53716 -409.847131) (xy 401.559801 -409.896707)
			(xy 401.575156 -409.949002) (xy 401.582913 -410.002949) (xy 401.582913 -410.057451) (xy 401.582912 -410.057457)
			(xy 403.020423 -410.057457) (xy 403.020423 -410.002943) (xy 403.028181 -409.948985) (xy 403.04354 -409.896681)
			(xy 403.066187 -409.847094) (xy 403.09566 -409.801236) (xy 403.13136 -409.760039) (xy 403.17256 -409.724342)
			(xy 403.218421 -409.694872) (xy 403.268009 -409.67223) (xy 403.320315 -409.656875) (xy 403.374273 -409.649121)
			(xy 403.40153 -409.64866) (xy 404.26513 -409.64866) (xy 404.292378 -409.649212) (xy 404.346317 -409.656972)
			(xy 404.398604 -409.672328) (xy 404.448173 -409.694969) (xy 404.494016 -409.724434) (xy 404.535199 -409.760122)
			(xy 404.570884 -409.801308) (xy 404.600345 -409.847153) (xy 404.622983 -409.896724) (xy 404.638335 -409.949012)
			(xy 404.64609 -410.002952) (xy 404.64609 -410.057448) (xy 404.646089 -410.057452) (xy 406.083746 -410.057452)
			(xy 406.083746 -410.002948) (xy 406.091502 -409.948998) (xy 406.106857 -409.896701) (xy 406.129498 -409.847122)
			(xy 406.158964 -409.801269) (xy 406.194655 -409.760076) (xy 406.235845 -409.724382) (xy 406.281696 -409.694912)
			(xy 406.331273 -409.672268) (xy 406.383569 -409.656909) (xy 406.437518 -409.649148) (xy 406.46477 -409.64866)
			(xy 407.32837 -409.64866) (xy 407.355622 -409.649185) (xy 407.409572 -409.656938) (xy 407.461869 -409.67229)
			(xy 407.511448 -409.694929) (xy 407.557301 -409.724394) (xy 407.598494 -409.760084) (xy 407.634188 -409.801274)
			(xy 407.663657 -409.847125) (xy 407.686299 -409.896703) (xy 407.701656 -409.948999) (xy 407.709413 -410.002948)
			(xy 407.709413 -410.057452) (xy 407.709412 -410.057456) (xy 409.146923 -410.057456) (xy 409.146923 -410.002944)
			(xy 409.154681 -409.948988) (xy 409.170039 -409.896685) (xy 409.192684 -409.8471) (xy 409.222155 -409.801242)
			(xy 409.257853 -409.760046) (xy 409.29905 -409.724349) (xy 409.344909 -409.694879) (xy 409.394494 -409.672235)
			(xy 409.446798 -409.656879) (xy 409.500754 -409.649122) (xy 409.52801 -409.64866) (xy 410.39161 -409.64866)
			(xy 410.418858 -409.649211) (xy 410.472801 -409.656968) (xy 410.52509 -409.672323) (xy 410.574661 -409.694962)
			(xy 410.620507 -409.724426) (xy 410.661692 -409.760115) (xy 410.69738 -409.801301) (xy 410.726842 -409.847147)
			(xy 410.749481 -409.89672) (xy 410.764834 -409.949009) (xy 410.77259 -410.002952) (xy 410.77259 -410.057448)
			(xy 410.77259 -410.057451) (xy 412.210246 -410.057451) (xy 412.210246 -410.002949) (xy 412.218002 -409.949001)
			(xy 412.233355 -409.896706) (xy 412.255995 -409.847128) (xy 412.285459 -409.801276) (xy 412.321148 -409.760083)
			(xy 412.362336 -409.724389) (xy 412.408184 -409.694919) (xy 412.457759 -409.672273) (xy 412.510052 -409.656912)
			(xy 412.563999 -409.649149) (xy 412.59125 -409.64866) (xy 413.45485 -409.64866) (xy 413.482103 -409.649184)
			(xy 413.536055 -409.656934) (xy 413.588354 -409.672285) (xy 413.637936 -409.694923) (xy 413.683792 -409.724387)
			(xy 413.724987 -409.760077) (xy 413.760683 -409.801268) (xy 413.790153 -409.84712) (xy 413.812798 -409.896699)
			(xy 413.828155 -409.948996) (xy 413.835913 -410.002947) (xy 413.835913 -410.057453) (xy 415.273446 -410.057453)
			(xy 415.273446 -410.002947) (xy 415.281203 -409.948996) (xy 415.296559 -409.896697) (xy 415.319201 -409.847117)
			(xy 415.348669 -409.801263) (xy 415.384362 -409.760069) (xy 415.425555 -409.724375) (xy 415.471408 -409.694906)
			(xy 415.520988 -409.672262) (xy 415.573286 -409.656905) (xy 415.627237 -409.649147) (xy 415.65449 -409.64866)
			(xy 416.51809 -409.64866) (xy 416.545341 -409.649187) (xy 416.599289 -409.656942) (xy 416.651583 -409.672296)
			(xy 416.70116 -409.694936) (xy 416.747011 -409.724401) (xy 416.788201 -409.760092) (xy 416.823893 -409.801281)
			(xy 416.85336 -409.847131) (xy 416.876001 -409.896707) (xy 416.891356 -409.949002) (xy 416.899113 -410.002949)
			(xy 416.899113 -410.057451) (xy 416.899112 -410.057457) (xy 418.336623 -410.057457) (xy 418.336623 -410.002943)
			(xy 418.344381 -409.948985) (xy 418.35974 -409.896681) (xy 418.382387 -409.847094) (xy 418.41186 -409.801236)
			(xy 418.44756 -409.760039) (xy 418.48876 -409.724342) (xy 418.534621 -409.694872) (xy 418.584209 -409.67223)
			(xy 418.636515 -409.656875) (xy 418.690473 -409.649121) (xy 418.71773 -409.64866) (xy 419.58133 -409.64866)
			(xy 419.608578 -409.649212) (xy 419.662517 -409.656972) (xy 419.714804 -409.672328) (xy 419.764373 -409.694969)
			(xy 419.810216 -409.724434) (xy 419.851399 -409.760122) (xy 419.887084 -409.801308) (xy 419.916545 -409.847153)
			(xy 419.939183 -409.896724) (xy 419.954535 -409.949012) (xy 419.96229 -410.002952) (xy 419.96229 -410.057448)
			(xy 419.954535 -410.111388) (xy 419.939183 -410.163676) (xy 419.916545 -410.213247) (xy 419.887084 -410.259092)
			(xy 419.851399 -410.300278) (xy 419.810216 -410.335966) (xy 419.764373 -410.365431) (xy 419.714804 -410.388072)
			(xy 419.662517 -410.403428) (xy 419.608578 -410.411188) (xy 419.58133 -410.411676) (xy 418.71773 -410.411676)
			(xy 418.690473 -410.411279) (xy 418.636515 -410.403525) (xy 418.584209 -410.38817) (xy 418.534621 -410.365528)
			(xy 418.48876 -410.336058) (xy 418.44756 -410.300361) (xy 418.41186 -410.259164) (xy 418.382387 -410.213306)
			(xy 418.35974 -410.163719) (xy 418.344381 -410.111415) (xy 418.336623 -410.057457) (xy 416.899112 -410.057457)
			(xy 416.891356 -410.111398) (xy 416.876001 -410.163693) (xy 416.85336 -410.213269) (xy 416.823893 -410.259119)
			(xy 416.788201 -410.300308) (xy 416.747011 -410.335999) (xy 416.70116 -410.365464) (xy 416.651583 -410.388104)
			(xy 416.599289 -410.403458) (xy 416.545341 -410.411213) (xy 416.51809 -410.411676) (xy 415.65449 -410.411676)
			(xy 415.627237 -410.411253) (xy 415.573286 -410.403495) (xy 415.520988 -410.388138) (xy 415.471408 -410.365494)
			(xy 415.425555 -410.336025) (xy 415.384362 -410.300331) (xy 415.348669 -410.259137) (xy 415.319201 -410.213283)
			(xy 415.296559 -410.163703) (xy 415.281203 -410.111404) (xy 415.273446 -410.057453) (xy 413.835913 -410.057453)
			(xy 413.828155 -410.111404) (xy 413.812798 -410.163701) (xy 413.790153 -410.21328) (xy 413.760683 -410.259132)
			(xy 413.724987 -410.300323) (xy 413.683792 -410.336013) (xy 413.637936 -410.365477) (xy 413.588354 -410.388115)
			(xy 413.536055 -410.403466) (xy 413.482103 -410.411216) (xy 413.45485 -410.411676) (xy 412.59125 -410.411676)
			(xy 412.563999 -410.411251) (xy 412.510052 -410.403488) (xy 412.457759 -410.388127) (xy 412.408184 -410.365481)
			(xy 412.362336 -410.336011) (xy 412.321148 -410.300317) (xy 412.285459 -410.259124) (xy 412.255995 -410.213272)
			(xy 412.233355 -410.163694) (xy 412.218002 -410.111399) (xy 412.210246 -410.057451) (xy 410.77259 -410.057451)
			(xy 410.764834 -410.111391) (xy 410.749481 -410.16368) (xy 410.726842 -410.213253) (xy 410.69738 -410.259099)
			(xy 410.661692 -410.300285) (xy 410.620507 -410.335974) (xy 410.574661 -410.365438) (xy 410.52509 -410.388077)
			(xy 410.472801 -410.403432) (xy 410.418858 -410.411189) (xy 410.39161 -410.411676) (xy 409.52801 -410.411676)
			(xy 409.500754 -410.411278) (xy 409.446798 -410.403521) (xy 409.394494 -410.388165) (xy 409.344909 -410.365521)
			(xy 409.29905 -410.336051) (xy 409.257853 -410.300354) (xy 409.222155 -410.259158) (xy 409.192684 -410.2133)
			(xy 409.170039 -410.163715) (xy 409.154681 -410.111412) (xy 409.146923 -410.057456) (xy 407.709412 -410.057456)
			(xy 407.701656 -410.111401) (xy 407.686299 -410.163697) (xy 407.663657 -410.213275) (xy 407.634188 -410.259126)
			(xy 407.598494 -410.300316) (xy 407.557301 -410.336006) (xy 407.511448 -410.365471) (xy 407.461869 -410.38811)
			(xy 407.409572 -410.403462) (xy 407.355622 -410.411215) (xy 407.32837 -410.411676) (xy 406.46477 -410.411676)
			(xy 406.437518 -410.411252) (xy 406.383569 -410.403491) (xy 406.331273 -410.388132) (xy 406.281696 -410.365488)
			(xy 406.235845 -410.336018) (xy 406.194655 -410.300324) (xy 406.158964 -410.259131) (xy 406.129498 -410.213278)
			(xy 406.106857 -410.163699) (xy 406.091502 -410.111402) (xy 406.083746 -410.057452) (xy 404.646089 -410.057452)
			(xy 404.638335 -410.111388) (xy 404.622983 -410.163676) (xy 404.600345 -410.213247) (xy 404.570884 -410.259092)
			(xy 404.535199 -410.300278) (xy 404.494016 -410.335966) (xy 404.448173 -410.365431) (xy 404.398604 -410.388072)
			(xy 404.346317 -410.403428) (xy 404.292378 -410.411188) (xy 404.26513 -410.411676) (xy 403.40153 -410.411676)
			(xy 403.374273 -410.411279) (xy 403.320315 -410.403525) (xy 403.268009 -410.38817) (xy 403.218421 -410.365528)
			(xy 403.17256 -410.336058) (xy 403.13136 -410.300361) (xy 403.09566 -410.259164) (xy 403.066187 -410.213306)
			(xy 403.04354 -410.163719) (xy 403.028181 -410.111415) (xy 403.020423 -410.057457) (xy 401.582912 -410.057457)
			(xy 401.575156 -410.111398) (xy 401.559801 -410.163693) (xy 401.53716 -410.213269) (xy 401.507693 -410.259119)
			(xy 401.472001 -410.300308) (xy 401.430811 -410.335999) (xy 401.38496 -410.365464) (xy 401.335383 -410.388104)
			(xy 401.283089 -410.403458) (xy 401.229141 -410.411213) (xy 401.20189 -410.411676) (xy 400.33829 -410.411676)
			(xy 400.311037 -410.411253) (xy 400.257086 -410.403495) (xy 400.204788 -410.388138) (xy 400.155208 -410.365494)
			(xy 400.109355 -410.336025) (xy 400.068162 -410.300331) (xy 400.032469 -410.259137) (xy 400.003001 -410.213283)
			(xy 399.980359 -410.163703) (xy 399.965003 -410.111404) (xy 399.957246 -410.057453) (xy 398.519713 -410.057453)
			(xy 398.511955 -410.111404) (xy 398.496598 -410.163701) (xy 398.473953 -410.21328) (xy 398.444483 -410.259132)
			(xy 398.408787 -410.300323) (xy 398.367592 -410.336013) (xy 398.321736 -410.365477) (xy 398.272154 -410.388115)
			(xy 398.219855 -410.403466) (xy 398.165903 -410.411216) (xy 398.13865 -410.411676) (xy 397.27505 -410.411676)
			(xy 397.247799 -410.411251) (xy 397.193852 -410.403488) (xy 397.141559 -410.388127) (xy 397.091984 -410.365481)
			(xy 397.046136 -410.336011) (xy 397.004948 -410.300317) (xy 396.969259 -410.259124) (xy 396.939795 -410.213272)
			(xy 396.917155 -410.163694) (xy 396.901802 -410.111399) (xy 396.894046 -410.057451) (xy 395.45639 -410.057451)
			(xy 395.448634 -410.111391) (xy 395.433281 -410.16368) (xy 395.410642 -410.213253) (xy 395.38118 -410.259099)
			(xy 395.345492 -410.300285) (xy 395.304307 -410.335974) (xy 395.258461 -410.365438) (xy 395.20889 -410.388077)
			(xy 395.156601 -410.403432) (xy 395.102658 -410.411189) (xy 395.07541 -410.411676) (xy 394.21181 -410.411676)
			(xy 394.184554 -410.411278) (xy 394.130598 -410.403521) (xy 394.078294 -410.388165) (xy 394.028709 -410.365521)
			(xy 393.98285 -410.336051) (xy 393.941653 -410.300354) (xy 393.905955 -410.259158) (xy 393.876484 -410.2133)
			(xy 393.853839 -410.163715) (xy 393.838481 -410.111412) (xy 393.830723 -410.057456) (xy 392.393212 -410.057456)
			(xy 392.385456 -410.111401) (xy 392.370099 -410.163697) (xy 392.347457 -410.213275) (xy 392.317988 -410.259126)
			(xy 392.282294 -410.300316) (xy 392.241101 -410.336006) (xy 392.195248 -410.365471) (xy 392.145669 -410.38811)
			(xy 392.093372 -410.403462) (xy 392.039422 -410.411215) (xy 392.01217 -410.411676) (xy 391.14857 -410.411676)
			(xy 391.121318 -410.411252) (xy 391.067369 -410.403491) (xy 391.015073 -410.388132) (xy 390.965496 -410.365488)
			(xy 390.919645 -410.336018) (xy 390.878455 -410.300324) (xy 390.842764 -410.259131) (xy 390.813298 -410.213278)
			(xy 390.790657 -410.163699) (xy 390.775302 -410.111402) (xy 390.767546 -410.057452) (xy 389.329889 -410.057452)
			(xy 389.322135 -410.111388) (xy 389.306783 -410.163676) (xy 389.284145 -410.213247) (xy 389.254684 -410.259092)
			(xy 389.218999 -410.300278) (xy 389.177816 -410.335966) (xy 389.131973 -410.365431) (xy 389.082404 -410.388072)
			(xy 389.030117 -410.403428) (xy 388.976178 -410.411188) (xy 388.94893 -410.411676) (xy 388.08533 -410.411676)
			(xy 388.058073 -410.411279) (xy 388.004115 -410.403525) (xy 387.951809 -410.38817) (xy 387.902221 -410.365528)
			(xy 387.85636 -410.336058) (xy 387.81516 -410.300361) (xy 387.77946 -410.259164) (xy 387.749987 -410.213306)
			(xy 387.72734 -410.163719) (xy 387.711981 -410.111415) (xy 387.704223 -410.057457) (xy 386.266712 -410.057457)
			(xy 386.258956 -410.111398) (xy 386.243601 -410.163693) (xy 386.22096 -410.213269) (xy 386.191493 -410.259119)
			(xy 386.155801 -410.300308) (xy 386.114611 -410.335999) (xy 386.06876 -410.365464) (xy 386.019183 -410.388104)
			(xy 385.966889 -410.403458) (xy 385.912941 -410.411213) (xy 385.88569 -410.411676) (xy 385.02209 -410.411676)
			(xy 384.994837 -410.411253) (xy 384.940886 -410.403495) (xy 384.888588 -410.388138) (xy 384.839008 -410.365494)
			(xy 384.793155 -410.336025) (xy 384.751962 -410.300331) (xy 384.716269 -410.259137) (xy 384.686801 -410.213283)
			(xy 384.664159 -410.163703) (xy 384.648803 -410.111404) (xy 384.641046 -410.057453) (xy 383.203513 -410.057453)
			(xy 383.195755 -410.111404) (xy 383.180398 -410.163701) (xy 383.157753 -410.21328) (xy 383.128283 -410.259132)
			(xy 383.092587 -410.300323) (xy 383.051392 -410.336013) (xy 383.005536 -410.365477) (xy 382.955954 -410.388115)
			(xy 382.903655 -410.403466) (xy 382.849703 -410.411216) (xy 382.82245 -410.411676) (xy 381.95885 -410.411676)
			(xy 381.931599 -410.411251) (xy 381.877652 -410.403488) (xy 381.825359 -410.388127) (xy 381.775784 -410.365481)
			(xy 381.729936 -410.336011) (xy 381.688748 -410.300317) (xy 381.653059 -410.259124) (xy 381.623595 -410.213272)
			(xy 381.600955 -410.163694) (xy 381.585602 -410.111399) (xy 381.577846 -410.057451) (xy 380.14019 -410.057451)
			(xy 380.132434 -410.111391) (xy 380.117081 -410.16368) (xy 380.094442 -410.213253) (xy 380.06498 -410.259099)
			(xy 380.029292 -410.300285) (xy 379.988107 -410.335974) (xy 379.942261 -410.365438) (xy 379.89269 -410.388077)
			(xy 379.840401 -410.403432) (xy 379.786458 -410.411189) (xy 379.75921 -410.411676) (xy 378.89561 -410.411676)
			(xy 378.868354 -410.411278) (xy 378.814398 -410.403521) (xy 378.762094 -410.388165) (xy 378.712509 -410.365521)
			(xy 378.66665 -410.336051) (xy 378.625453 -410.300354) (xy 378.589755 -410.259158) (xy 378.560284 -410.2133)
			(xy 378.537639 -410.163715) (xy 378.522281 -410.111412) (xy 378.514523 -410.057456) (xy 377.077012 -410.057456)
			(xy 377.069256 -410.111401) (xy 377.053899 -410.163697) (xy 377.031257 -410.213275) (xy 377.001788 -410.259126)
			(xy 376.966094 -410.300316) (xy 376.924901 -410.336006) (xy 376.879048 -410.365471) (xy 376.829469 -410.38811)
			(xy 376.777172 -410.403462) (xy 376.723222 -410.411215) (xy 376.69597 -410.411676) (xy 375.83237 -410.411676)
			(xy 375.805118 -410.411252) (xy 375.751169 -410.403491) (xy 375.698873 -410.388132) (xy 375.649296 -410.365488)
			(xy 375.603445 -410.336018) (xy 375.562255 -410.300324) (xy 375.526564 -410.259131) (xy 375.497098 -410.213278)
			(xy 375.474457 -410.163699) (xy 375.459102 -410.111402) (xy 375.451346 -410.057452) (xy 374.013689 -410.057452)
			(xy 374.005935 -410.111388) (xy 373.990583 -410.163676) (xy 373.967945 -410.213247) (xy 373.938484 -410.259092)
			(xy 373.902799 -410.300278) (xy 373.861616 -410.335966) (xy 373.815773 -410.365431) (xy 373.766204 -410.388072)
			(xy 373.713917 -410.403428) (xy 373.659978 -410.411188) (xy 373.63273 -410.411676) (xy 372.76913 -410.411676)
			(xy 372.741873 -410.411279) (xy 372.687915 -410.403525) (xy 372.635609 -410.38817) (xy 372.586021 -410.365528)
			(xy 372.54016 -410.336058) (xy 372.49896 -410.300361) (xy 372.46326 -410.259164) (xy 372.433787 -410.213306)
			(xy 372.41114 -410.163719) (xy 372.395781 -410.111415) (xy 372.388023 -410.057457) (xy 352.519512 -410.057457)
			(xy 352.511756 -410.111399) (xy 352.496401 -410.163693) (xy 352.473759 -410.21327) (xy 352.444293 -410.25912)
			(xy 352.408601 -410.300309) (xy 352.36741 -410.336) (xy 352.321559 -410.365465) (xy 352.271982 -410.388105)
			(xy 352.219687 -410.403459) (xy 352.165739 -410.411214) (xy 352.138488 -410.411676) (xy 351.274888 -410.411676)
			(xy 351.247635 -410.411253) (xy 351.193684 -410.403495) (xy 351.141386 -410.388137) (xy 351.091807 -410.365494)
			(xy 351.045954 -410.336025) (xy 351.004762 -410.30033) (xy 350.969068 -410.259137) (xy 350.939601 -410.213283)
			(xy 350.916958 -410.163702) (xy 350.901603 -410.111404) (xy 350.893846 -410.057453) (xy 349.456189 -410.057453)
			(xy 349.448435 -410.111386) (xy 349.433084 -410.163672) (xy 349.410448 -410.213242) (xy 349.380989 -410.259086)
			(xy 349.345306 -410.300272) (xy 349.304125 -410.33596) (xy 349.258284 -410.365425) (xy 349.208717 -410.388067)
			(xy 349.156433 -410.403425) (xy 349.102495 -410.411187) (xy 349.075248 -410.411676) (xy 348.211648 -410.411676)
			(xy 348.184391 -410.41128) (xy 348.13043 -410.403528) (xy 348.078122 -410.388175) (xy 348.028531 -410.365533)
			(xy 347.982668 -410.336064) (xy 347.941466 -410.300367) (xy 347.905765 -410.25917) (xy 347.87629 -410.213311)
			(xy 347.853642 -410.163723) (xy 347.838282 -410.111417) (xy 347.830523 -410.057457) (xy 346.392989 -410.057457)
			(xy 346.385234 -410.111391) (xy 346.369881 -410.163681) (xy 346.347242 -410.213253) (xy 346.317779 -410.259099)
			(xy 346.282091 -410.300286) (xy 346.240906 -410.335974) (xy 346.19506 -410.365438) (xy 346.145488 -410.388078)
			(xy 346.093199 -410.403432) (xy 346.039257 -410.411189) (xy 346.012008 -410.411676) (xy 345.148408 -410.411676)
			(xy 345.121152 -410.411278) (xy 345.067196 -410.403521) (xy 345.014893 -410.388164) (xy 344.965307 -410.36552)
			(xy 344.919449 -410.33605) (xy 344.878252 -410.300353) (xy 344.842555 -410.259157) (xy 344.813084 -410.2133)
			(xy 344.790439 -410.163715) (xy 344.775081 -410.111412) (xy 344.767323 -410.057456) (xy 343.329812 -410.057456)
			(xy 343.322055 -410.111401) (xy 343.306699 -410.163697) (xy 343.284056 -410.213275) (xy 343.254588 -410.259126)
			(xy 343.218894 -410.300316) (xy 343.177701 -410.336007) (xy 343.131847 -410.365472) (xy 343.082267 -410.38811)
			(xy 343.02997 -410.403462) (xy 342.97602 -410.411215) (xy 342.948768 -410.411676) (xy 342.085168 -410.411676)
			(xy 342.057916 -410.411252) (xy 342.003967 -410.403491) (xy 341.951672 -410.388132) (xy 341.902095 -410.365487)
			(xy 341.856244 -410.336017) (xy 341.815054 -410.300323) (xy 341.779363 -410.25913) (xy 341.749898 -410.213277)
			(xy 341.727257 -410.163698) (xy 341.711902 -410.111402) (xy 341.704146 -410.057452) (xy 340.266489 -410.057452)
			(xy 340.258735 -410.111388) (xy 340.243382 -410.163676) (xy 340.220745 -410.213248) (xy 340.191284 -410.259093)
			(xy 340.155599 -410.300279) (xy 340.114415 -410.335967) (xy 340.068572 -410.365432) (xy 340.019003 -410.388073)
			(xy 339.966716 -410.403429) (xy 339.912776 -410.411188) (xy 339.885528 -410.411676) (xy 339.021928 -410.411676)
			(xy 338.994672 -410.411279) (xy 338.940713 -410.403525) (xy 338.888407 -410.38817) (xy 338.838819 -410.365527)
			(xy 338.792959 -410.336057) (xy 338.751759 -410.30036) (xy 338.71606 -410.259164) (xy 338.686587 -410.213305)
			(xy 338.66394 -410.163719) (xy 338.648581 -410.111414) (xy 338.640823 -410.057456) (xy 337.203312 -410.057456)
			(xy 337.195556 -410.111399) (xy 337.180201 -410.163693) (xy 337.157559 -410.21327) (xy 337.128093 -410.25912)
			(xy 337.092401 -410.300309) (xy 337.05121 -410.336) (xy 337.005359 -410.365465) (xy 336.955782 -410.388105)
			(xy 336.903487 -410.403459) (xy 336.849539 -410.411214) (xy 336.822288 -410.411676) (xy 335.958688 -410.411676)
			(xy 335.931435 -410.411253) (xy 335.877484 -410.403495) (xy 335.825186 -410.388137) (xy 335.775607 -410.365494)
			(xy 335.729754 -410.336025) (xy 335.688562 -410.30033) (xy 335.652868 -410.259137) (xy 335.623401 -410.213283)
			(xy 335.600758 -410.163702) (xy 335.585403 -410.111404) (xy 335.577646 -410.057453) (xy 334.139989 -410.057453)
			(xy 334.132235 -410.111386) (xy 334.116884 -410.163672) (xy 334.094248 -410.213242) (xy 334.064789 -410.259086)
			(xy 334.029106 -410.300272) (xy 333.987925 -410.33596) (xy 333.942084 -410.365425) (xy 333.892517 -410.388067)
			(xy 333.840233 -410.403425) (xy 333.786295 -410.411187) (xy 333.759048 -410.411676) (xy 332.895448 -410.411676)
			(xy 332.868191 -410.41128) (xy 332.81423 -410.403528) (xy 332.761922 -410.388175) (xy 332.712331 -410.365533)
			(xy 332.666468 -410.336064) (xy 332.625266 -410.300367) (xy 332.589565 -410.25917) (xy 332.56009 -410.213311)
			(xy 332.537442 -410.163723) (xy 332.522082 -410.111417) (xy 332.514323 -410.057457) (xy 331.076789 -410.057457)
			(xy 331.069034 -410.111391) (xy 331.053681 -410.163681) (xy 331.031042 -410.213253) (xy 331.001579 -410.259099)
			(xy 330.965891 -410.300286) (xy 330.924706 -410.335974) (xy 330.87886 -410.365438) (xy 330.829288 -410.388078)
			(xy 330.776999 -410.403432) (xy 330.723057 -410.411189) (xy 330.695808 -410.411676) (xy 329.832208 -410.411676)
			(xy 329.804952 -410.411278) (xy 329.750996 -410.403521) (xy 329.698693 -410.388164) (xy 329.649107 -410.36552)
			(xy 329.603249 -410.33605) (xy 329.562052 -410.300353) (xy 329.526355 -410.259157) (xy 329.496884 -410.2133)
			(xy 329.474239 -410.163715) (xy 329.458881 -410.111412) (xy 329.451123 -410.057456) (xy 328.013612 -410.057456)
			(xy 328.005855 -410.111401) (xy 327.990499 -410.163697) (xy 327.967856 -410.213275) (xy 327.938388 -410.259126)
			(xy 327.902694 -410.300316) (xy 327.861501 -410.336007) (xy 327.815647 -410.365472) (xy 327.766067 -410.38811)
			(xy 327.71377 -410.403462) (xy 327.65982 -410.411215) (xy 327.632568 -410.411676) (xy 326.768968 -410.411676)
			(xy 326.741716 -410.411252) (xy 326.687767 -410.403491) (xy 326.635472 -410.388132) (xy 326.585895 -410.365487)
			(xy 326.540044 -410.336017) (xy 326.498854 -410.300323) (xy 326.463163 -410.25913) (xy 326.433698 -410.213277)
			(xy 326.411057 -410.163698) (xy 326.395702 -410.111402) (xy 326.387946 -410.057452) (xy 324.950289 -410.057452)
			(xy 324.942535 -410.111388) (xy 324.927182 -410.163676) (xy 324.904545 -410.213248) (xy 324.875084 -410.259093)
			(xy 324.839399 -410.300279) (xy 324.798215 -410.335967) (xy 324.752372 -410.365432) (xy 324.702803 -410.388073)
			(xy 324.650516 -410.403429) (xy 324.596576 -410.411188) (xy 324.569328 -410.411676) (xy 323.705728 -410.411676)
			(xy 323.678472 -410.411279) (xy 323.624513 -410.403525) (xy 323.572207 -410.38817) (xy 323.522619 -410.365527)
			(xy 323.476759 -410.336057) (xy 323.435559 -410.30036) (xy 323.39986 -410.259164) (xy 323.370387 -410.213305)
			(xy 323.34774 -410.163719) (xy 323.332381 -410.111414) (xy 323.324623 -410.057456) (xy 321.887112 -410.057456)
			(xy 321.879356 -410.111399) (xy 321.864001 -410.163693) (xy 321.841359 -410.21327) (xy 321.811893 -410.25912)
			(xy 321.776201 -410.300309) (xy 321.73501 -410.336) (xy 321.689159 -410.365465) (xy 321.639582 -410.388105)
			(xy 321.587287 -410.403459) (xy 321.533339 -410.411214) (xy 321.506088 -410.411676) (xy 320.642488 -410.411676)
			(xy 320.615235 -410.411253) (xy 320.561284 -410.403495) (xy 320.508986 -410.388137) (xy 320.459407 -410.365494)
			(xy 320.413554 -410.336025) (xy 320.372362 -410.30033) (xy 320.336668 -410.259137) (xy 320.307201 -410.213283)
			(xy 320.284558 -410.163702) (xy 320.269203 -410.111404) (xy 320.261446 -410.057453) (xy 318.823789 -410.057453)
			(xy 318.816035 -410.111386) (xy 318.800684 -410.163672) (xy 318.778048 -410.213242) (xy 318.748589 -410.259086)
			(xy 318.712906 -410.300272) (xy 318.671725 -410.33596) (xy 318.625884 -410.365425) (xy 318.576317 -410.388067)
			(xy 318.524033 -410.403425) (xy 318.470095 -410.411187) (xy 318.442848 -410.411676) (xy 317.579248 -410.411676)
			(xy 317.551991 -410.41128) (xy 317.49803 -410.403528) (xy 317.445722 -410.388175) (xy 317.396131 -410.365533)
			(xy 317.350268 -410.336064) (xy 317.309066 -410.300367) (xy 317.273365 -410.25917) (xy 317.24389 -410.213311)
			(xy 317.221242 -410.163723) (xy 317.205882 -410.111417) (xy 317.198123 -410.057457) (xy 315.760589 -410.057457)
			(xy 315.752834 -410.111391) (xy 315.737481 -410.163681) (xy 315.714842 -410.213253) (xy 315.685379 -410.259099)
			(xy 315.649691 -410.300286) (xy 315.608506 -410.335974) (xy 315.56266 -410.365438) (xy 315.513088 -410.388078)
			(xy 315.460799 -410.403432) (xy 315.406857 -410.411189) (xy 315.379608 -410.411676) (xy 314.516008 -410.411676)
			(xy 314.488752 -410.411278) (xy 314.434796 -410.403521) (xy 314.382493 -410.388164) (xy 314.332907 -410.36552)
			(xy 314.287049 -410.33605) (xy 314.245852 -410.300353) (xy 314.210155 -410.259157) (xy 314.180684 -410.2133)
			(xy 314.158039 -410.163715) (xy 314.142681 -410.111412) (xy 314.134923 -410.057456) (xy 312.697412 -410.057456)
			(xy 312.689655 -410.111401) (xy 312.674299 -410.163697) (xy 312.651656 -410.213275) (xy 312.622188 -410.259126)
			(xy 312.586494 -410.300316) (xy 312.545301 -410.336007) (xy 312.499447 -410.365472) (xy 312.449867 -410.38811)
			(xy 312.39757 -410.403462) (xy 312.34362 -410.411215) (xy 312.316368 -410.411676) (xy 311.452768 -410.411676)
			(xy 311.425516 -410.411252) (xy 311.371567 -410.403491) (xy 311.319272 -410.388132) (xy 311.269695 -410.365487)
			(xy 311.223844 -410.336017) (xy 311.182654 -410.300323) (xy 311.146963 -410.25913) (xy 311.117498 -410.213277)
			(xy 311.094857 -410.163698) (xy 311.079502 -410.111402) (xy 311.071746 -410.057452) (xy 309.634089 -410.057452)
			(xy 309.626335 -410.111388) (xy 309.610982 -410.163676) (xy 309.588345 -410.213248) (xy 309.558884 -410.259093)
			(xy 309.523199 -410.300279) (xy 309.482015 -410.335967) (xy 309.436172 -410.365432) (xy 309.386603 -410.388073)
			(xy 309.334316 -410.403429) (xy 309.280376 -410.411188) (xy 309.253128 -410.411676) (xy 308.389528 -410.411676)
			(xy 308.362272 -410.411279) (xy 308.308313 -410.403525) (xy 308.256007 -410.38817) (xy 308.206419 -410.365527)
			(xy 308.160559 -410.336057) (xy 308.119359 -410.30036) (xy 308.08366 -410.259164) (xy 308.054187 -410.213305)
			(xy 308.03154 -410.163719) (xy 308.016181 -410.111414) (xy 308.008423 -410.057456) (xy 306.570912 -410.057456)
			(xy 306.563156 -410.111399) (xy 306.547801 -410.163693) (xy 306.525159 -410.21327) (xy 306.495693 -410.25912)
			(xy 306.460001 -410.300309) (xy 306.41881 -410.336) (xy 306.372959 -410.365465) (xy 306.323382 -410.388105)
			(xy 306.271087 -410.403459) (xy 306.217139 -410.411214) (xy 306.189888 -410.411676) (xy 305.326288 -410.411676)
			(xy 305.299035 -410.411253) (xy 305.245084 -410.403495) (xy 305.192786 -410.388137) (xy 305.143207 -410.365494)
			(xy 305.097354 -410.336025) (xy 305.056162 -410.30033) (xy 305.020468 -410.259137) (xy 304.991001 -410.213283)
			(xy 304.968358 -410.163702) (xy 304.953003 -410.111404) (xy 304.945246 -410.057453) (xy 280.83256 -410.057453)
			(xy 280.83256 -415.172652) (xy 280.832075 -415.197601) (xy 280.824257 -415.246884) (xy 280.808837 -415.294341)
			(xy 280.786193 -415.338807) (xy 280.756881 -415.37919) (xy 280.739596 -415.397188) (xy 280.152348 -415.984436)
			(xy 280.134386 -416.001764) (xy 280.094003 -416.03109) (xy 280.04953 -416.053738) (xy 280.002061 -416.069148)
			(xy 279.952766 -416.076943) (xy 279.927812 -416.0774) (xy 275.812504 -416.0774) (xy 270.721328 -421.168576)
			(xy 270.703321 -421.185853) (xy 270.662948 -421.21518) (xy 270.618486 -421.23783) (xy 270.571027 -421.253247)
			(xy 270.521742 -421.261051) (xy 270.496792 -421.26154) (xy 233.339132 -421.26154) (xy 231.01554 -423.585132)
			(xy 231.01554 -424.804386) (xy 357.679233 -424.804386) (xy 357.679233 -424.675246) (xy 357.687183 -424.546351)
			(xy 357.703053 -424.418191) (xy 357.726782 -424.29125) (xy 357.758281 -424.166011) (xy 357.79743 -424.042948)
			(xy 357.844081 -423.922529) (xy 357.898056 -423.80521) (xy 357.959151 -423.691436) (xy 358.027134 -423.581639)
			(xy 358.101748 -423.476236) (xy 358.182709 -423.375626) (xy 358.269709 -423.280191) (xy 358.36242 -423.190292)
			(xy 358.46049 -423.106271) (xy 358.563545 -423.028447) (xy 358.671196 -422.957115) (xy 358.783035 -422.892545)
			(xy 358.898636 -422.834983) (xy 359.017561 -422.784646) (xy 359.13936 -422.741726) (xy 359.26357 -422.706385)
			(xy 359.389719 -422.678758) (xy 359.517331 -422.658949) (xy 359.64592 -422.647033) (xy 359.774998 -422.643057)
			(xy 359.904076 -422.647033) (xy 360.032665 -422.658949) (xy 360.160277 -422.678758) (xy 360.286426 -422.706385)
			(xy 360.410636 -422.741726) (xy 360.532435 -422.784646) (xy 360.65136 -422.834983) (xy 360.766961 -422.892545)
			(xy 360.8788 -422.957115) (xy 360.986451 -423.028447) (xy 361.089506 -423.106271) (xy 361.187576 -423.190292)
			(xy 361.280287 -423.280191) (xy 361.367287 -423.375626) (xy 361.448248 -423.476236) (xy 361.522862 -423.581639)
			(xy 361.590845 -423.691436) (xy 361.65194 -423.80521) (xy 361.705915 -423.922529) (xy 361.752566 -424.042948)
			(xy 361.791715 -424.166011) (xy 361.823214 -424.29125) (xy 361.846943 -424.418191) (xy 361.853367 -424.470068)
			(xy 421.270176 -424.470068) (xy 421.270176 -417.770056) (xy 421.270681 -417.664527) (xy 421.278765 -417.453623)
			(xy 421.294922 -417.243184) (xy 421.319127 -417.033518) (xy 421.351345 -416.824934) (xy 421.391528 -416.617736)
			(xy 421.439619 -416.412229) (xy 421.495545 -416.208716) (xy 421.559226 -416.007493) (xy 421.630567 -415.808858)
			(xy 421.709464 -415.613101) (xy 421.795802 -415.420509) (xy 421.889452 -415.231366) (xy 421.990279 -415.045949)
			(xy 422.098134 -414.864529) (xy 422.212858 -414.687374) (xy 422.334284 -414.514743) (xy 422.462233 -414.34689)
			(xy 422.596517 -414.184061) (xy 422.73694 -414.026495) (xy 422.883295 -413.874423) (xy 423.035367 -413.728068)
			(xy 423.192933 -413.587645) (xy 423.355762 -413.453361) (xy 423.523615 -413.325412) (xy 423.696246 -413.203986)
			(xy 423.873401 -413.089262) (xy 424.054821 -412.981407) (xy 424.240238 -412.88058) (xy 424.429381 -412.78693)
			(xy 424.621973 -412.700592) (xy 424.81773 -412.621695) (xy 425.016365 -412.550354) (xy 425.217588 -412.486673)
			(xy 425.421101 -412.430747) (xy 425.626608 -412.382656) (xy 425.833806 -412.342473) (xy 426.04239 -412.310255)
			(xy 426.252056 -412.28605) (xy 426.462495 -412.269893) (xy 426.673399 -412.261809) (xy 426.884457 -412.261809)
			(xy 427.095361 -412.269893) (xy 427.3058 -412.28605) (xy 427.515466 -412.310255) (xy 427.72405 -412.342473)
			(xy 427.931248 -412.382656) (xy 428.136755 -412.430747) (xy 428.340268 -412.486673) (xy 428.541491 -412.550354)
			(xy 428.740126 -412.621695) (xy 428.935883 -412.700592) (xy 429.128475 -412.78693) (xy 429.317618 -412.88058)
			(xy 429.503035 -412.981407) (xy 429.684455 -413.089262) (xy 429.86161 -413.203986) (xy 430.034241 -413.325412)
			(xy 430.202094 -413.453361) (xy 430.364923 -413.587645) (xy 430.522489 -413.728068) (xy 430.674561 -413.874423)
			(xy 430.820916 -414.026495) (xy 430.961339 -414.184061) (xy 431.095623 -414.34689) (xy 431.223572 -414.514743)
			(xy 431.344998 -414.687374) (xy 431.459722 -414.864529) (xy 431.567577 -415.045949) (xy 431.668404 -415.231366)
			(xy 431.762054 -415.420509) (xy 431.848392 -415.613101) (xy 431.927289 -415.808858) (xy 431.99863 -416.007493)
			(xy 432.062311 -416.208716) (xy 432.118237 -416.412229) (xy 432.166328 -416.617736) (xy 432.206511 -416.824934)
			(xy 432.238729 -417.033518) (xy 432.262934 -417.243184) (xy 432.279091 -417.453623) (xy 432.287175 -417.664527)
			(xy 432.28768 -417.770056) (xy 432.28768 -424.470068) (xy 432.287175 -424.575597) (xy 432.279091 -424.786501)
			(xy 432.262934 -424.99694) (xy 432.238729 -425.206606) (xy 432.206511 -425.41519) (xy 432.166328 -425.622388)
			(xy 432.118237 -425.827895) (xy 432.062311 -426.031408) (xy 431.99863 -426.232631) (xy 431.927289 -426.431266)
			(xy 431.848392 -426.627023) (xy 431.762054 -426.819615) (xy 431.668404 -427.008758) (xy 431.567577 -427.194175)
			(xy 431.459722 -427.375595) (xy 431.344998 -427.55275) (xy 431.223572 -427.725381) (xy 431.095623 -427.893234)
			(xy 430.961339 -428.056063) (xy 430.820916 -428.213629) (xy 430.674561 -428.365701) (xy 430.522489 -428.512056)
			(xy 430.364923 -428.652479) (xy 430.202094 -428.786763) (xy 430.034241 -428.914712) (xy 429.86161 -429.036138)
			(xy 429.684455 -429.150862) (xy 429.503035 -429.258717) (xy 429.317618 -429.359544) (xy 429.128475 -429.453194)
			(xy 428.935883 -429.539532) (xy 428.740126 -429.618429) (xy 428.541491 -429.68977) (xy 428.340268 -429.753451)
			(xy 428.136755 -429.809377) (xy 427.931248 -429.857468) (xy 427.72405 -429.897651) (xy 427.515466 -429.929869)
			(xy 427.3058 -429.954074) (xy 427.095361 -429.970231) (xy 426.884457 -429.978315) (xy 426.673399 -429.978315)
			(xy 426.462495 -429.970231) (xy 426.252056 -429.954074) (xy 426.04239 -429.929869) (xy 425.833806 -429.897651)
			(xy 425.626608 -429.857468) (xy 425.421101 -429.809377) (xy 425.217588 -429.753451) (xy 425.016365 -429.68977)
			(xy 424.81773 -429.618429) (xy 424.621973 -429.539532) (xy 424.429381 -429.453194) (xy 424.240238 -429.359544)
			(xy 424.054821 -429.258717) (xy 423.873401 -429.150862) (xy 423.696246 -429.036138) (xy 423.523615 -428.914712)
			(xy 423.355762 -428.786763) (xy 423.192933 -428.652479) (xy 423.035367 -428.512056) (xy 422.883295 -428.365701)
			(xy 422.73694 -428.213629) (xy 422.596517 -428.056063) (xy 422.462233 -427.893234) (xy 422.334284 -427.725381)
			(xy 422.212858 -427.55275) (xy 422.098134 -427.375595) (xy 421.990279 -427.194175) (xy 421.889452 -427.008758)
			(xy 421.795802 -426.819615) (xy 421.709464 -426.627023) (xy 421.630567 -426.431266) (xy 421.559226 -426.232631)
			(xy 421.495545 -426.031408) (xy 421.439619 -425.827895) (xy 421.391528 -425.622388) (xy 421.351345 -425.41519)
			(xy 421.319127 -425.206606) (xy 421.294922 -424.99694) (xy 421.278765 -424.786501) (xy 421.270681 -424.575597)
			(xy 421.270176 -424.470068) (xy 361.853367 -424.470068) (xy 361.862813 -424.546351) (xy 361.870763 -424.675246)
			(xy 361.87126 -424.739816) (xy 361.870763 -424.804386) (xy 361.862813 -424.933281) (xy 361.846943 -425.061441)
			(xy 361.823214 -425.188382) (xy 361.791715 -425.313621) (xy 361.752566 -425.436684) (xy 361.705915 -425.557103)
			(xy 361.65194 -425.674422) (xy 361.590845 -425.788196) (xy 361.522862 -425.897993) (xy 361.448248 -426.003396)
			(xy 361.367287 -426.104006) (xy 361.280287 -426.199441) (xy 361.187576 -426.28934) (xy 361.089506 -426.373361)
			(xy 360.986451 -426.451185) (xy 360.8788 -426.522517) (xy 360.766961 -426.587087) (xy 360.65136 -426.644649)
			(xy 360.532435 -426.694986) (xy 360.410636 -426.737906) (xy 360.286426 -426.773247) (xy 360.160277 -426.800874)
			(xy 360.032665 -426.820683) (xy 359.904076 -426.832599) (xy 359.774998 -426.836576) (xy 359.64592 -426.832599)
			(xy 359.517331 -426.820683) (xy 359.389719 -426.800874) (xy 359.26357 -426.773247) (xy 359.13936 -426.737906)
			(xy 359.017561 -426.694986) (xy 358.898636 -426.644649) (xy 358.783035 -426.587087) (xy 358.671196 -426.522517)
			(xy 358.563545 -426.451185) (xy 358.46049 -426.373361) (xy 358.36242 -426.28934) (xy 358.269709 -426.199441)
			(xy 358.182709 -426.104006) (xy 358.101748 -426.003396) (xy 358.027134 -425.897993) (xy 357.959151 -425.788196)
			(xy 357.898056 -425.674422) (xy 357.844081 -425.557103) (xy 357.79743 -425.436684) (xy 357.758281 -425.313621)
			(xy 357.726782 -425.188382) (xy 357.703053 -425.061441) (xy 357.687183 -424.933281) (xy 357.679233 -424.804386)
			(xy 231.01554 -424.804386) (xy 231.01554 -427.289976) (xy 314.138056 -427.289976) (xy 314.13817 -427.274891)
			(xy 314.139948 -427.244772) (xy 314.141612 -427.229778) (xy 314.141612 -426.150024) (xy 314.139943 -426.135031)
			(xy 314.138165 -426.104912) (xy 314.138056 -426.089826) (xy 314.138166 -426.07474) (xy 314.139947 -426.044622)
			(xy 314.141612 -426.029628) (xy 314.141612 -425.419012) (xy 314.142023 -425.406928) (xy 314.14949 -425.383942)
			(xy 314.163696 -425.36439) (xy 314.183249 -425.350186) (xy 314.206236 -425.342722) (xy 314.21832 -425.342304)
			(xy 315.15812 -425.342304) (xy 315.170197 -425.342748) (xy 315.193167 -425.350217) (xy 315.212704 -425.364419)
			(xy 315.226898 -425.383962) (xy 315.234357 -425.406935) (xy 315.234828 -425.419012) (xy 315.234828 -427.960536)
			(xy 315.234367 -427.97261) (xy 315.226897 -427.995576) (xy 315.212699 -428.01511) (xy 315.193161 -428.029304)
			(xy 315.170195 -428.036769) (xy 315.15812 -428.037244) (xy 314.21832 -428.037244) (xy 314.20625 -428.036719)
			(xy 314.18329 -428.029267) (xy 314.163755 -428.015085) (xy 314.149559 -427.995561) (xy 314.142089 -427.972606)
			(xy 314.141612 -427.960536) (xy 314.141612 -427.350174) (xy 314.139948 -427.33518) (xy 314.138166 -427.305062)
			(xy 314.138056 -427.289976) (xy 231.01554 -427.289976) (xy 231.01554 -428.28972) (xy 316.138052 -428.28972)
			(xy 316.138162 -428.274634) (xy 316.139943 -428.244516) (xy 316.141608 -428.229522) (xy 316.141608 -427.150022)
			(xy 316.139939 -427.135029) (xy 316.138161 -427.10491) (xy 316.138052 -427.089824) (xy 316.138162 -427.074738)
			(xy 316.139943 -427.04462) (xy 316.141608 -427.029626) (xy 316.141608 -426.41901) (xy 316.142115 -426.406924)
			(xy 316.149565 -426.383929) (xy 316.163743 -426.364352) (xy 316.183266 -426.3501) (xy 316.206232 -426.342562)
			(xy 316.218316 -426.342048) (xy 317.158116 -426.342048) (xy 317.170221 -426.342502) (xy 317.193239 -426.349999)
			(xy 317.212808 -426.364253) (xy 317.227004 -426.383863) (xy 317.234433 -426.406904) (xy 317.234824 -426.41901)
			(xy 317.234824 -427.289976) (xy 318.138048 -427.289976) (xy 318.138162 -427.274891) (xy 318.13994 -427.244772)
			(xy 318.141604 -427.229778) (xy 318.141604 -426.150024) (xy 318.139935 -426.135031) (xy 318.138157 -426.104912)
			(xy 318.138048 -426.089826) (xy 318.138158 -426.07474) (xy 318.139939 -426.044622) (xy 318.141604 -426.029628)
			(xy 318.141604 -425.419012) (xy 318.142023 -425.406929) (xy 318.149489 -425.383944) (xy 318.163693 -425.364393)
			(xy 318.183244 -425.350189) (xy 318.206229 -425.342723) (xy 318.218312 -425.342304) (xy 319.158112 -425.342304)
			(xy 319.170188 -425.342754) (xy 319.193158 -425.350222) (xy 319.212696 -425.364421) (xy 319.226889 -425.383964)
			(xy 319.234349 -425.406935) (xy 319.23482 -425.419012) (xy 319.23482 -427.960536) (xy 319.234367 -427.972611)
			(xy 319.226896 -427.995578) (xy 319.212696 -428.015113) (xy 319.193156 -428.029307) (xy 319.170187 -428.036771)
			(xy 319.158112 -428.037244) (xy 318.218312 -428.037244) (xy 318.206242 -428.036726) (xy 318.183281 -428.029271)
			(xy 318.163747 -428.015087) (xy 318.149551 -427.995562) (xy 318.142081 -427.972606) (xy 318.141604 -427.960536)
			(xy 318.141604 -427.350174) (xy 318.13994 -427.33518) (xy 318.138158 -427.305062) (xy 318.138048 -427.289976)
			(xy 317.234824 -427.289976) (xy 317.234824 -428.28972) (xy 320.138044 -428.28972) (xy 320.138154 -428.274634)
			(xy 320.139935 -428.244516) (xy 320.1416 -428.229522) (xy 320.1416 -427.150022) (xy 320.139931 -427.135029)
			(xy 320.138153 -427.10491) (xy 320.138044 -427.089824) (xy 320.138154 -427.074738) (xy 320.139935 -427.04462)
			(xy 320.1416 -427.029626) (xy 320.1416 -426.41901) (xy 320.142115 -426.406925) (xy 320.149564 -426.383931)
			(xy 320.16374 -426.364355) (xy 320.183261 -426.350103) (xy 320.206225 -426.342563) (xy 320.218308 -426.342048)
			(xy 321.158108 -426.342048) (xy 321.170212 -426.342509) (xy 321.193231 -426.350004) (xy 321.212799 -426.364256)
			(xy 321.226996 -426.383865) (xy 321.234425 -426.406905) (xy 321.234816 -426.41901) (xy 321.234816 -427.289976)
			(xy 322.13804 -427.289976) (xy 322.138155 -427.274891) (xy 322.139932 -427.244772) (xy 322.141596 -427.229778)
			(xy 322.141596 -426.150024) (xy 322.139927 -426.135031) (xy 322.138149 -426.104912) (xy 322.13804 -426.089826)
			(xy 322.13815 -426.07474) (xy 322.139931 -426.044622) (xy 322.141596 -426.029628) (xy 322.141596 -425.419012)
			(xy 322.142023 -425.40693) (xy 322.149488 -425.383947) (xy 322.16369 -425.364396) (xy 322.183239 -425.350191)
			(xy 322.206222 -425.342724) (xy 322.218304 -425.342304) (xy 323.158104 -425.342304) (xy 323.170188 -425.342709)
			(xy 323.193173 -425.350179) (xy 323.212724 -425.364387) (xy 323.226928 -425.383941) (xy 323.234393 -425.406928)
			(xy 323.234812 -425.419012) (xy 323.234812 -427.960536) (xy 323.234367 -427.972612) (xy 323.226895 -427.99558)
			(xy 323.212693 -428.015116) (xy 323.193151 -428.029309) (xy 323.17018 -428.036772) (xy 323.158104 -428.037244)
			(xy 322.218304 -428.037244) (xy 322.206233 -428.036733) (xy 322.183272 -428.029276) (xy 322.163738 -428.01509)
			(xy 322.149542 -427.995564) (xy 322.142073 -427.972607) (xy 322.141596 -427.960536) (xy 322.141596 -427.350174)
			(xy 322.139932 -427.33518) (xy 322.13815 -427.305062) (xy 322.13804 -427.289976) (xy 321.234816 -427.289976)
			(xy 321.234816 -428.28972) (xy 324.138036 -428.28972) (xy 324.138148 -428.274634) (xy 324.139929 -428.244516)
			(xy 324.141592 -428.229522) (xy 324.141592 -427.150022) (xy 324.139923 -427.135029) (xy 324.138145 -427.10491)
			(xy 324.138036 -427.089824) (xy 324.138148 -427.074738) (xy 324.139929 -427.04462) (xy 324.141592 -427.029626)
			(xy 324.141592 -426.41901) (xy 324.142115 -426.406926) (xy 324.149563 -426.383934) (xy 324.163737 -426.364358)
			(xy 324.183256 -426.350105) (xy 324.206218 -426.342564) (xy 324.2183 -426.342048) (xy 325.1581 -426.342048)
			(xy 325.170204 -426.342515) (xy 325.193222 -426.350009) (xy 325.212791 -426.364259) (xy 325.226987 -426.383866)
			(xy 325.234417 -426.406905) (xy 325.234808 -426.41901) (xy 325.234808 -427.289976) (xy 326.138032 -427.289976)
			(xy 326.138149 -427.274891) (xy 326.139927 -427.244772) (xy 326.141588 -427.229778) (xy 326.141588 -426.150024)
			(xy 326.139919 -426.135031) (xy 326.138141 -426.104912) (xy 326.138032 -426.089826) (xy 326.138144 -426.07474)
			(xy 326.139925 -426.044622) (xy 326.141588 -426.029628) (xy 326.141588 -425.419012) (xy 326.142023 -425.40693)
			(xy 326.149487 -425.383949) (xy 326.163687 -425.364399) (xy 326.183234 -425.350194) (xy 326.206214 -425.342726)
			(xy 326.218296 -425.342304) (xy 327.158096 -425.342304) (xy 327.17018 -425.342716) (xy 327.193164 -425.350184)
			(xy 327.212716 -425.36439) (xy 327.22692 -425.383943) (xy 327.234385 -425.406928) (xy 327.234804 -425.419012)
			(xy 327.234804 -427.960536) (xy 327.234367 -427.972613) (xy 327.226894 -427.995582) (xy 327.21269 -428.015119)
			(xy 327.193146 -428.029312) (xy 327.170173 -428.036773) (xy 327.158096 -428.037244) (xy 326.218296 -428.037244)
			(xy 326.206225 -428.03674) (xy 326.183264 -428.02928) (xy 326.16373 -428.015093) (xy 326.149534 -427.995565)
			(xy 326.142065 -427.972607) (xy 326.141588 -427.960536) (xy 326.141588 -427.350174) (xy 326.139924 -427.33518)
			(xy 326.138142 -427.305062) (xy 326.138032 -427.289976) (xy 325.234808 -427.289976) (xy 325.234808 -428.28972)
			(xy 328.138028 -428.28972) (xy 328.13814 -428.274634) (xy 328.139921 -428.244516) (xy 328.141584 -428.229522)
			(xy 328.141584 -427.150022) (xy 328.139915 -427.135029) (xy 328.138137 -427.10491) (xy 328.138028 -427.089824)
			(xy 328.13814 -427.074738) (xy 328.139921 -427.04462) (xy 328.141584 -427.029626) (xy 328.141584 -426.41901)
			(xy 328.142017 -426.406917) (xy 328.149476 -426.383909) (xy 328.16367 -426.364325) (xy 328.183214 -426.350076)
			(xy 328.2062 -426.342551) (xy 328.218292 -426.342048) (xy 329.158092 -426.342048) (xy 329.170195 -426.342522)
			(xy 329.193214 -426.350013) (xy 329.212782 -426.364262) (xy 329.226979 -426.383868) (xy 329.234409 -426.406906)
			(xy 329.2348 -426.41901) (xy 329.2348 -427.289976) (xy 331.138022 -427.289976) (xy 331.138113 -427.275402)
			(xy 331.139767 -427.246301) (xy 331.141324 -427.23181) (xy 331.141324 -426.147992) (xy 331.139781 -426.1335)
			(xy 331.138128 -426.1044) (xy 331.138022 -426.089826) (xy 331.138117 -426.075252) (xy 331.139769 -426.046151)
			(xy 331.141324 -426.03166) (xy 331.141324 -425.419012) (xy 331.141727 -425.406901) (xy 331.149226 -425.38387)
			(xy 331.16349 -425.364295) (xy 331.183116 -425.350101) (xy 331.206174 -425.342684) (xy 331.218286 -425.342304)
			(xy 332.158086 -425.342304) (xy 332.170171 -425.342819) (xy 332.193165 -425.350267) (xy 332.212742 -425.364443)
			(xy 332.226995 -425.383964) (xy 332.234533 -425.406929) (xy 332.235048 -425.419012) (xy 332.235048 -427.960536)
			(xy 332.234615 -427.972642) (xy 332.227111 -427.995662) (xy 332.212852 -428.01523) (xy 332.193238 -428.029426)
			(xy 332.170193 -428.036854) (xy 332.158086 -428.037244) (xy 331.218286 -428.037244) (xy 331.206194 -428.036804)
			(xy 331.18319 -428.029342) (xy 331.163609 -428.015149) (xy 331.14936 -427.995609) (xy 331.141831 -427.972627)
			(xy 331.141324 -427.960536) (xy 331.141324 -427.348142) (xy 331.139777 -427.33365) (xy 331.138127 -427.30455)
			(xy 331.138022 -427.289976) (xy 329.2348 -427.289976) (xy 329.2348 -428.28972) (xy 333.138018 -428.28972)
			(xy 333.138113 -428.275146) (xy 333.139764 -428.246045) (xy 333.14132 -428.231554) (xy 333.14132 -427.14799)
			(xy 333.139777 -427.133498) (xy 333.138124 -427.104398) (xy 333.138018 -427.089824) (xy 333.138113 -427.07525)
			(xy 333.139765 -427.046149) (xy 333.14132 -427.031658) (xy 333.14132 -426.41901) (xy 333.14182 -426.406898)
			(xy 333.149302 -426.383858) (xy 333.163538 -426.364258) (xy 333.183133 -426.350015) (xy 333.20617 -426.342525)
			(xy 333.218282 -426.342048) (xy 334.158082 -426.342048) (xy 334.170205 -426.342475) (xy 334.193265 -426.349964)
			(xy 334.212881 -426.364213) (xy 334.227132 -426.383828) (xy 334.234623 -426.406887) (xy 334.235044 -426.41901)
			(xy 334.235044 -427.289976) (xy 335.138014 -427.289976) (xy 335.138104 -427.275402) (xy 335.139759 -427.246301)
			(xy 335.141316 -427.23181) (xy 335.141316 -426.147992) (xy 335.139773 -426.1335) (xy 335.13812 -426.1044)
			(xy 335.138014 -426.089826) (xy 335.138109 -426.075252) (xy 335.13976 -426.046151) (xy 335.141316 -426.03166)
			(xy 335.141316 -425.419012) (xy 335.141727 -425.406902) (xy 335.149225 -425.383873) (xy 335.163487 -425.364298)
			(xy 335.183111 -425.350104) (xy 335.206167 -425.342685) (xy 335.218278 -425.342304) (xy 336.158078 -425.342304)
			(xy 336.170163 -425.342825) (xy 336.193157 -425.350272) (xy 336.212734 -425.364446) (xy 336.226986 -425.383966)
			(xy 336.234525 -425.406929) (xy 336.23504 -425.419012) (xy 336.23504 -427.960536) (xy 336.234615 -427.972643)
			(xy 336.22711 -427.995664) (xy 336.21285 -428.015233) (xy 336.193233 -428.029428) (xy 336.170186 -428.036855)
			(xy 336.158078 -428.037244) (xy 335.218278 -428.037244) (xy 335.206186 -428.036811) (xy 335.183182 -428.029347)
			(xy 335.163601 -428.015152) (xy 335.149351 -427.99561) (xy 335.141823 -427.972627) (xy 335.141316 -427.960536)
			(xy 335.141316 -427.348142) (xy 335.139769 -427.33365) (xy 335.138119 -427.30455) (xy 335.138014 -427.289976)
			(xy 334.235044 -427.289976) (xy 334.235044 -428.28972) (xy 337.13801 -428.28972) (xy 337.138104 -428.275146)
			(xy 337.139756 -428.246045) (xy 337.141312 -428.231554) (xy 337.141312 -427.14799) (xy 337.139769 -427.133498)
			(xy 337.138116 -427.104398) (xy 337.13801 -427.089824) (xy 337.138104 -427.07525) (xy 337.139756 -427.046149)
			(xy 337.141312 -427.031658) (xy 337.141312 -426.41901) (xy 337.14182 -426.406899) (xy 337.149301 -426.38386)
			(xy 337.163535 -426.36426) (xy 337.183128 -426.350018) (xy 337.206163 -426.342526) (xy 337.218274 -426.342048)
			(xy 338.158074 -426.342048) (xy 338.170196 -426.342482) (xy 338.193256 -426.349969) (xy 338.212872 -426.364216)
			(xy 338.227124 -426.38383) (xy 338.234615 -426.406888) (xy 338.235036 -426.41901) (xy 338.235036 -427.289976)
			(xy 339.138006 -427.289976) (xy 339.138096 -427.275402) (xy 339.139751 -427.246301) (xy 339.141308 -427.23181)
			(xy 339.141308 -426.147992) (xy 339.139765 -426.1335) (xy 339.138112 -426.1044) (xy 339.138006 -426.089826)
			(xy 339.138101 -426.075252) (xy 339.139752 -426.046151) (xy 339.141308 -426.03166) (xy 339.141308 -425.419012)
			(xy 339.141727 -425.406903) (xy 339.149224 -425.383875) (xy 339.163485 -425.364301) (xy 339.183106 -425.350106)
			(xy 339.20616 -425.342687) (xy 339.21827 -425.342304) (xy 340.15807 -425.342304) (xy 340.170154 -425.342832)
			(xy 340.193148 -425.350276) (xy 340.212725 -425.364448) (xy 340.226978 -425.383967) (xy 340.234517 -425.40693)
			(xy 340.235032 -425.419012) (xy 340.235032 -427.960536) (xy 340.234615 -427.972644) (xy 340.227109 -427.995667)
			(xy 340.212847 -428.015236) (xy 340.193228 -428.029431) (xy 340.170179 -428.036856) (xy 340.15807 -428.037244)
			(xy 339.21827 -428.037244) (xy 339.206177 -428.036818) (xy 339.183173 -428.029351) (xy 339.163592 -428.015154)
			(xy 339.149343 -427.995612) (xy 339.141815 -427.972627) (xy 339.141308 -427.960536) (xy 339.141308 -427.348142)
			(xy 339.139761 -427.33365) (xy 339.138111 -427.30455) (xy 339.138006 -427.289976) (xy 338.235036 -427.289976)
			(xy 338.235036 -428.28972) (xy 341.138002 -428.28972) (xy 341.138096 -428.275146) (xy 341.139748 -428.246045)
			(xy 341.141304 -428.231554) (xy 341.141304 -427.14799) (xy 341.139761 -427.133498) (xy 341.138108 -427.104398)
			(xy 341.138002 -427.089824) (xy 341.138096 -427.07525) (xy 341.139748 -427.046149) (xy 341.141304 -427.031658)
			(xy 341.141304 -426.41901) (xy 341.14182 -426.406899) (xy 341.1493 -426.383862) (xy 341.163532 -426.364263)
			(xy 341.183123 -426.35002) (xy 341.206156 -426.342527) (xy 341.218266 -426.342048) (xy 342.158066 -426.342048)
			(xy 342.170188 -426.342489) (xy 342.193247 -426.349973) (xy 342.212864 -426.364219) (xy 342.227116 -426.383831)
			(xy 342.234607 -426.406888) (xy 342.235028 -426.41901) (xy 342.235028 -427.289976) (xy 343.137998 -427.289976)
			(xy 343.138088 -427.275402) (xy 343.139743 -427.246301) (xy 343.1413 -427.23181) (xy 343.1413 -426.147992)
			(xy 343.139757 -426.1335) (xy 343.138104 -426.1044) (xy 343.137998 -426.089826) (xy 343.138093 -426.075252)
			(xy 343.139744 -426.046151) (xy 343.1413 -426.03166) (xy 343.1413 -425.419012) (xy 343.141727 -425.406904)
			(xy 343.149223 -425.383877) (xy 343.163482 -425.364304) (xy 343.183101 -425.350109) (xy 343.206152 -425.342688)
			(xy 343.218262 -425.342304) (xy 344.158062 -425.342304) (xy 344.170146 -425.342839) (xy 344.193139 -425.350281)
			(xy 344.212717 -425.364451) (xy 344.22697 -425.383968) (xy 344.234509 -425.40693) (xy 344.235024 -425.419012)
			(xy 344.235024 -427.960536) (xy 344.234615 -427.972644) (xy 344.227108 -427.995669) (xy 344.212844 -428.015239)
			(xy 344.193223 -428.029433) (xy 344.170172 -428.036857) (xy 344.158062 -428.037244) (xy 343.218262 -428.037244)
			(xy 343.206169 -428.036825) (xy 343.183164 -428.029356) (xy 343.163584 -428.015157) (xy 343.149335 -427.995613)
			(xy 343.141807 -427.972628) (xy 343.1413 -427.960536) (xy 343.1413 -427.348142) (xy 343.139753 -427.33365)
			(xy 343.138103 -427.30455) (xy 343.137998 -427.289976) (xy 342.235028 -427.289976) (xy 342.235028 -428.28972)
			(xy 345.137994 -428.28972) (xy 345.138088 -428.275146) (xy 345.13974 -428.246045) (xy 345.141296 -428.231554)
			(xy 345.141296 -427.14799) (xy 345.139753 -427.133498) (xy 345.1381 -427.104398) (xy 345.137994 -427.089824)
			(xy 345.138088 -427.07525) (xy 345.13974 -427.046149) (xy 345.141296 -427.031658) (xy 345.141296 -426.41901)
			(xy 345.14182 -426.4069) (xy 345.149299 -426.383864) (xy 345.163529 -426.364266) (xy 345.183118 -426.350023)
			(xy 345.206148 -426.342528) (xy 345.218258 -426.342048) (xy 346.158058 -426.342048) (xy 346.17018 -426.342496)
			(xy 346.193239 -426.349978) (xy 346.212855 -426.364222) (xy 346.227108 -426.383833) (xy 346.234599 -426.406889)
			(xy 346.23502 -426.41901) (xy 346.23502 -427.289976) (xy 381.21844 -427.289976) (xy 381.218922 -427.257419)
			(xy 381.226871 -427.192794) (xy 381.242658 -427.129623) (xy 381.266048 -427.068856) (xy 381.296688 -427.011404)
			(xy 381.334121 -426.958126) (xy 381.377785 -426.909823) (xy 381.402082 -426.888148) (xy 381.482854 -426.723302)
			(xy 381.487539 -426.71278) (xy 381.491032 -426.690025) (xy 381.487554 -426.667269) (xy 381.482854 -426.656754)
			(xy 381.401828 -426.491654) (xy 381.377569 -426.469953) (xy 381.333971 -426.421622) (xy 381.296595 -426.368333)
			(xy 381.266001 -426.310881) (xy 381.242645 -426.250126) (xy 381.226877 -426.186974) (xy 381.218932 -426.122371)
			(xy 381.21844 -426.089826) (xy 381.219145 -426.0507) (xy 381.230616 -425.973293) (xy 381.2413 -425.935648)
			(xy 381.2413 -425.419012) (xy 381.241727 -425.406904) (xy 381.249223 -425.383877) (xy 381.263482 -425.364304)
			(xy 381.283101 -425.350109) (xy 381.306152 -425.342688) (xy 381.318262 -425.342304) (xy 382.258062 -425.342304)
			(xy 382.270146 -425.342839) (xy 382.293139 -425.350281) (xy 382.312717 -425.364451) (xy 382.32697 -425.383968)
			(xy 382.334509 -425.40693) (xy 382.335024 -425.419012) (xy 382.335024 -427.960536) (xy 382.334615 -427.972644)
			(xy 382.327108 -427.995669) (xy 382.312844 -428.015239) (xy 382.293223 -428.029433) (xy 382.270172 -428.036857)
			(xy 382.258062 -428.037244) (xy 381.318262 -428.037244) (xy 381.306169 -428.036825) (xy 381.283164 -428.029356)
			(xy 381.263584 -428.015157) (xy 381.249335 -427.995613) (xy 381.241807 -427.972628) (xy 381.2413 -427.960536)
			(xy 381.2413 -427.444154) (xy 381.230607 -427.40651) (xy 381.219134 -427.329103) (xy 381.21844 -427.289976)
			(xy 346.23502 -427.289976) (xy 346.23502 -428.960534) (xy 346.234669 -428.972663) (xy 346.227162 -428.99573)
			(xy 346.212894 -429.015348) (xy 346.193262 -429.029597) (xy 346.170187 -429.03708) (xy 346.158058 -429.037496)
			(xy 345.218258 -429.037496) (xy 345.206145 -429.037025) (xy 345.183106 -429.02953) (xy 345.163508 -429.015287)
			(xy 345.149266 -428.995687) (xy 345.141774 -428.972647) (xy 345.141296 -428.960534) (xy 345.141296 -428.347886)
			(xy 345.139753 -428.333394) (xy 345.1381 -428.304294) (xy 345.137994 -428.28972) (xy 342.235028 -428.28972)
			(xy 342.235028 -428.960534) (xy 342.234617 -428.972654) (xy 342.227116 -428.995704) (xy 342.21286 -429.015308)
			(xy 342.193243 -429.029547) (xy 342.170186 -429.037027) (xy 342.158066 -429.037496) (xy 341.218266 -429.037496)
			(xy 341.206153 -429.037018) (xy 341.183114 -429.029525) (xy 341.163516 -429.015284) (xy 341.149275 -428.995686)
			(xy 341.141782 -428.972647) (xy 341.141304 -428.960534) (xy 341.141304 -428.347886) (xy 341.139761 -428.333394)
			(xy 341.138108 -428.304294) (xy 341.138002 -428.28972) (xy 338.235036 -428.28972) (xy 338.235036 -428.960534)
			(xy 338.234617 -428.972653) (xy 338.227117 -428.995702) (xy 338.212862 -429.015305) (xy 338.193248 -429.029545)
			(xy 338.170193 -429.037026) (xy 338.158074 -429.037496) (xy 337.218274 -429.037496) (xy 337.206161 -429.037011)
			(xy 337.183123 -429.029521) (xy 337.163525 -429.015281) (xy 337.149283 -428.995684) (xy 337.14179 -428.972646)
			(xy 337.141312 -428.960534) (xy 337.141312 -428.347886) (xy 337.139769 -428.333394) (xy 337.138116 -428.304294)
			(xy 337.13801 -428.28972) (xy 334.235044 -428.28972) (xy 334.235044 -428.960534) (xy 334.234617 -428.972652)
			(xy 334.227118 -428.9957) (xy 334.212865 -429.015302) (xy 334.193253 -429.029542) (xy 334.1702 -429.037025)
			(xy 334.158082 -429.037496) (xy 333.218282 -429.037496) (xy 333.20617 -429.037004) (xy 333.183132 -429.029516)
			(xy 333.163533 -429.015278) (xy 333.149291 -428.995683) (xy 333.141798 -428.972646) (xy 333.14132 -428.960534)
			(xy 333.14132 -428.347886) (xy 333.139777 -428.333394) (xy 333.138124 -428.304294) (xy 333.138018 -428.28972)
			(xy 329.2348 -428.28972) (xy 329.2348 -428.960534) (xy 329.234322 -428.972621) (xy 329.226861 -428.995616)
			(xy 329.212676 -429.015192) (xy 329.193148 -429.029443) (xy 329.170178 -429.036981) (xy 329.158092 -429.037496)
			(xy 328.218292 -429.037496) (xy 328.206182 -429.037091) (xy 328.183154 -429.029588) (xy 328.163581 -429.015324)
			(xy 328.149386 -428.9957) (xy 328.141967 -428.972645) (xy 328.141584 -428.960534) (xy 328.141584 -428.349918)
			(xy 328.139915 -428.334925) (xy 328.138137 -428.304806) (xy 328.138028 -428.28972) (xy 325.234808 -428.28972)
			(xy 325.234808 -428.960534) (xy 325.234323 -428.972621) (xy 325.226862 -428.995614) (xy 325.212679 -429.01519)
			(xy 325.193153 -429.029441) (xy 325.170185 -429.03698) (xy 325.1581 -429.037496) (xy 324.2183 -429.037496)
			(xy 324.206191 -429.037084) (xy 324.183163 -429.029584) (xy 324.163589 -429.015321) (xy 324.149395 -428.995699)
			(xy 324.141975 -428.972645) (xy 324.141592 -428.960534) (xy 324.141592 -428.349918) (xy 324.139923 -428.334925)
			(xy 324.138145 -428.304806) (xy 324.138036 -428.28972) (xy 321.234816 -428.28972) (xy 321.234816 -428.960534)
			(xy 321.234421 -428.97263) (xy 321.226949 -428.995639) (xy 321.212746 -429.015222) (xy 321.193195 -429.02947)
			(xy 321.170203 -429.036993) (xy 321.158108 -429.037496) (xy 320.218308 -429.037496) (xy 320.206199 -429.037077)
			(xy 320.183171 -429.029579) (xy 320.163598 -429.015319) (xy 320.149403 -428.995697) (xy 320.141983 -428.972644)
			(xy 320.1416 -428.960534) (xy 320.1416 -428.349918) (xy 320.139931 -428.334925) (xy 320.138153 -428.304806)
			(xy 320.138044 -428.28972) (xy 317.234824 -428.28972) (xy 317.234824 -428.960534) (xy 317.234421 -428.972629)
			(xy 317.226951 -428.995637) (xy 317.212749 -429.015219) (xy 317.1932 -429.029467) (xy 317.17021 -429.036992)
			(xy 317.158116 -429.037496) (xy 316.218316 -429.037496) (xy 316.206208 -429.03707) (xy 316.18318 -429.029574)
			(xy 316.163607 -429.015315) (xy 316.149412 -428.995695) (xy 316.141991 -428.972644) (xy 316.141608 -428.960534)
			(xy 316.141608 -428.349918) (xy 316.139939 -428.334925) (xy 316.138161 -428.304806) (xy 316.138052 -428.28972)
			(xy 231.01554 -428.28972) (xy 231.01554 -433.130695) (xy 266.885917 -433.130695) (xy 266.885917 -432.953425)
			(xy 266.89387 -432.776334) (xy 266.909761 -432.599778) (xy 266.933556 -432.424113) (xy 266.965209 -432.249692)
			(xy 267.004655 -432.076867) (xy 267.051815 -431.905986) (xy 267.106594 -431.737392) (xy 267.168882 -431.571427)
			(xy 267.238554 -431.408422) (xy 267.315468 -431.248708) (xy 267.399471 -431.092605) (xy 267.490392 -430.940428)
			(xy 267.588049 -430.792484) (xy 267.692246 -430.64907) (xy 267.802772 -430.510475) (xy 267.919404 -430.376978)
			(xy 268.041909 -430.248849) (xy 268.170038 -430.126344) (xy 268.303535 -430.009712) (xy 268.44213 -429.899186)
			(xy 268.585544 -429.794989) (xy 268.733488 -429.697332) (xy 268.885665 -429.606411) (xy 269.041768 -429.522408)
			(xy 269.201482 -429.445494) (xy 269.364487 -429.375822) (xy 269.530452 -429.313534) (xy 269.699046 -429.258755)
			(xy 269.869927 -429.211595) (xy 270.042752 -429.172149) (xy 270.217173 -429.140496) (xy 270.392838 -429.116701)
			(xy 270.569394 -429.10081) (xy 270.746485 -429.092857) (xy 270.923755 -429.092857) (xy 271.100846 -429.10081)
			(xy 271.277402 -429.116701) (xy 271.453067 -429.140496) (xy 271.627488 -429.172149) (xy 271.800313 -429.211595)
			(xy 271.971194 -429.258755) (xy 272.139788 -429.313534) (xy 272.305753 -429.375822) (xy 272.468758 -429.445494)
			(xy 272.628472 -429.522408) (xy 272.784575 -429.606411) (xy 272.936752 -429.697332) (xy 273.084696 -429.794989)
			(xy 273.22811 -429.899186) (xy 273.366705 -430.009712) (xy 273.500202 -430.126344) (xy 273.628331 -430.248849)
			(xy 273.750836 -430.376978) (xy 273.867468 -430.510475) (xy 273.977994 -430.64907) (xy 274.082191 -430.792484)
			(xy 274.146507 -430.889918) (xy 314.118498 -430.889918) (xy 314.119024 -430.857363) (xy 314.126967 -430.792739)
			(xy 314.142748 -430.729571) (xy 314.166131 -430.668804) (xy 314.196764 -430.611351) (xy 314.23419 -430.558072)
			(xy 314.277846 -430.509767) (xy 314.30214 -430.48809) (xy 314.382912 -430.323244) (xy 314.38764 -430.312738)
			(xy 314.39112 -430.289973) (xy 314.387623 -430.267211) (xy 314.382912 -430.256696) (xy 314.301886 -430.091596)
			(xy 314.277639 -430.069883) (xy 314.234041 -430.021553) (xy 314.196666 -429.968265) (xy 314.16607 -429.910816)
			(xy 314.142713 -429.850062) (xy 314.126941 -429.786914) (xy 314.118992 -429.722312) (xy 314.118498 -429.689768)
			(xy 314.119226 -429.650443) (xy 314.13083 -429.572653) (xy 314.141612 -429.534828) (xy 314.141612 -429.018954)
			(xy 314.142068 -429.006865) (xy 314.149534 -428.983867) (xy 314.163724 -428.964291) (xy 314.183258 -428.950041)
			(xy 314.206232 -428.942505) (xy 314.21832 -428.941992) (xy 315.15812 -428.941992) (xy 315.170229 -428.942399)
			(xy 315.193256 -428.949903) (xy 315.212828 -428.964167) (xy 315.227022 -428.98379) (xy 315.234444 -429.006843)
			(xy 315.234828 -429.018954) (xy 315.234828 -431.560478) (xy 315.234373 -431.57257) (xy 315.226919 -431.595575)
			(xy 315.21273 -431.615158) (xy 315.193192 -431.629408) (xy 315.17021 -431.636935) (xy 315.15812 -431.63744)
			(xy 314.21832 -431.63744) (xy 314.206216 -431.636967) (xy 314.183196 -431.629478) (xy 314.163627 -431.61523)
			(xy 314.14943 -431.595622) (xy 314.142001 -431.572583) (xy 314.141612 -431.560478) (xy 314.141612 -431.044858)
			(xy 314.130817 -431.007035) (xy 314.119208 -430.929244) (xy 314.118498 -430.889918) (xy 274.146507 -430.889918)
			(xy 274.179848 -430.940428) (xy 274.270769 -431.092605) (xy 274.354772 -431.248708) (xy 274.431686 -431.408422)
			(xy 274.501358 -431.571427) (xy 274.563646 -431.737392) (xy 274.613204 -431.889916) (xy 316.118494 -431.889916)
			(xy 316.118986 -431.85736) (xy 316.126931 -431.792733) (xy 316.142715 -431.729563) (xy 316.166103 -431.668795)
			(xy 316.196742 -431.611342) (xy 316.234175 -431.558065) (xy 316.277838 -431.509763) (xy 316.302136 -431.488088)
			(xy 316.382908 -431.323242) (xy 316.387637 -431.312736) (xy 316.391117 -431.289971) (xy 316.38762 -431.267208)
			(xy 316.382908 -431.256694) (xy 316.301882 -431.091594) (xy 316.277633 -431.069883) (xy 316.234036 -431.021552)
			(xy 316.19666 -430.968264) (xy 316.166065 -430.910814) (xy 316.142708 -430.850061) (xy 316.126937 -430.786912)
			(xy 316.118988 -430.72231) (xy 316.118494 -430.689766) (xy 316.119222 -430.650441) (xy 316.130826 -430.572651)
			(xy 316.141608 -430.534826) (xy 316.141608 -430.018952) (xy 316.142023 -430.006873) (xy 316.149501 -429.983902)
			(xy 316.16371 -429.964364) (xy 316.183259 -429.950172) (xy 316.206237 -429.942713) (xy 316.218316 -429.942244)
			(xy 317.158116 -429.942244) (xy 317.170187 -429.94275) (xy 317.193146 -429.950211) (xy 317.212679 -429.964399)
			(xy 317.226874 -429.983925) (xy 317.234345 -430.006882) (xy 317.234824 -430.018952) (xy 317.234824 -430.889918)
			(xy 318.11849 -430.889918) (xy 318.118985 -430.857362) (xy 318.126929 -430.792736) (xy 318.142713 -430.729565)
			(xy 318.1661 -430.668798) (xy 318.196739 -430.611345) (xy 318.234171 -430.558067) (xy 318.277835 -430.509765)
			(xy 318.302132 -430.48809) (xy 318.382904 -430.323244) (xy 318.387632 -430.312738) (xy 318.391113 -430.289973)
			(xy 318.387616 -430.26721) (xy 318.382904 -430.256696) (xy 318.301878 -430.091596) (xy 318.277629 -430.069884)
			(xy 318.234032 -430.021554) (xy 318.196657 -429.968266) (xy 318.166062 -429.910816) (xy 318.142704 -429.850063)
			(xy 318.126933 -429.786914) (xy 318.118984 -429.722312) (xy 318.11849 -429.689768) (xy 318.119218 -429.650443)
			(xy 318.130823 -429.572653) (xy 318.141604 -429.534828) (xy 318.141604 -429.018954) (xy 318.142067 -429.006866)
			(xy 318.149532 -428.98387) (xy 318.163721 -428.964293) (xy 318.183253 -428.950043) (xy 318.206225 -428.942506)
			(xy 318.218312 -428.941992) (xy 319.158112 -428.941992) (xy 319.170221 -428.942406) (xy 319.193247 -428.949908)
			(xy 319.212819 -428.96417) (xy 319.227014 -428.983792) (xy 319.234436 -429.006844) (xy 319.23482 -429.018954)
			(xy 319.23482 -431.560478) (xy 319.234373 -431.57257) (xy 319.226918 -431.595577) (xy 319.212727 -431.615161)
			(xy 319.193187 -431.629411) (xy 319.170203 -431.636936) (xy 319.158112 -431.63744) (xy 318.218312 -431.63744)
			(xy 318.206208 -431.636974) (xy 318.183188 -431.629483) (xy 318.163618 -431.615232) (xy 318.149422 -431.595624)
			(xy 318.141993 -431.572583) (xy 318.141604 -431.560478) (xy 318.141604 -431.044858) (xy 318.130809 -431.007035)
			(xy 318.1192 -430.929244) (xy 318.11849 -430.889918) (xy 317.234824 -430.889918) (xy 317.234824 -431.889916)
			(xy 320.118486 -431.889916) (xy 320.118981 -431.85736) (xy 320.126925 -431.792734) (xy 320.14271 -431.729563)
			(xy 320.166097 -431.668796) (xy 320.196736 -431.611343) (xy 320.234168 -431.558065) (xy 320.277831 -431.509763)
			(xy 320.302128 -431.488088) (xy 320.3829 -431.323242) (xy 320.38763 -431.312736) (xy 320.39111 -431.289971)
			(xy 320.387612 -431.267208) (xy 320.3829 -431.256694) (xy 320.301874 -431.091594) (xy 320.277623 -431.069884)
			(xy 320.234026 -431.021554) (xy 320.196651 -430.968265) (xy 320.166057 -430.910815) (xy 320.1427 -430.850061)
			(xy 320.126929 -430.786912) (xy 320.11898 -430.72231) (xy 320.118486 -430.689766) (xy 320.119214 -430.650441)
			(xy 320.130819 -430.572651) (xy 320.1416 -430.534826) (xy 320.1416 -430.018952) (xy 320.142023 -430.006874)
			(xy 320.1495 -429.983904) (xy 320.163707 -429.964367) (xy 320.183254 -429.950174) (xy 320.20623 -429.942714)
			(xy 320.218308 -429.942244) (xy 321.158108 -429.942244) (xy 321.170178 -429.942757) (xy 321.193137 -429.950216)
			(xy 321.21267 -429.964401) (xy 321.226866 -429.983927) (xy 321.234337 -430.006882) (xy 321.234816 -430.018952)
			(xy 321.234816 -430.889918) (xy 322.118482 -430.889918) (xy 322.11898 -430.857362) (xy 322.126924 -430.792736)
			(xy 322.142708 -430.729566) (xy 322.166094 -430.668798) (xy 322.196733 -430.611345) (xy 322.234164 -430.558068)
			(xy 322.277827 -430.509765) (xy 322.302124 -430.48809) (xy 322.382896 -430.323244) (xy 322.387625 -430.312738)
			(xy 322.391105 -430.289973) (xy 322.387608 -430.26721) (xy 322.382896 -430.256696) (xy 322.30187 -430.091596)
			(xy 322.27764 -430.069864) (xy 322.234038 -430.02154) (xy 322.196658 -429.968256) (xy 322.16606 -429.91081)
			(xy 322.142699 -429.850059) (xy 322.126926 -429.786912) (xy 322.118976 -429.722312) (xy 322.118482 -429.689768)
			(xy 322.119211 -429.650443) (xy 322.130815 -429.572653) (xy 322.141596 -429.534828) (xy 322.141596 -429.018954)
			(xy 322.142067 -429.006866) (xy 322.149531 -428.983872) (xy 322.163718 -428.964296) (xy 322.183248 -428.950046)
			(xy 322.206218 -428.942507) (xy 322.218304 -428.941992) (xy 323.158104 -428.941992) (xy 323.170212 -428.942413)
			(xy 323.193238 -428.949912) (xy 323.212811 -428.964173) (xy 323.227006 -428.983793) (xy 323.234428 -429.006844)
			(xy 323.234812 -429.018954) (xy 323.234812 -431.560478) (xy 323.234373 -431.572571) (xy 323.226916 -431.595579)
			(xy 323.212724 -431.615164) (xy 323.193182 -431.629413) (xy 323.170196 -431.636937) (xy 323.158104 -431.63744)
			(xy 322.218304 -431.63744) (xy 322.206199 -431.636981) (xy 322.183179 -431.629488) (xy 322.163609 -431.615236)
			(xy 322.149413 -431.595625) (xy 322.141985 -431.572584) (xy 322.141596 -431.560478) (xy 322.141596 -431.044858)
			(xy 322.130801 -431.007035) (xy 322.119192 -430.929244) (xy 322.118482 -430.889918) (xy 321.234816 -430.889918)
			(xy 321.234816 -431.889916) (xy 324.118478 -431.889916) (xy 324.118976 -431.85736) (xy 324.12692 -431.792734)
			(xy 324.142704 -431.729564) (xy 324.166091 -431.668797) (xy 324.196729 -431.611343) (xy 324.23416 -431.558066)
			(xy 324.277823 -431.509763) (xy 324.30212 -431.488088) (xy 324.382892 -431.323242) (xy 324.387622 -431.312737)
			(xy 324.391103 -431.289971) (xy 324.387605 -431.267208) (xy 324.382892 -431.256694) (xy 324.301866 -431.091594)
			(xy 324.277634 -431.069864) (xy 324.234032 -431.021539) (xy 324.196653 -430.968255) (xy 324.166055 -430.910808)
			(xy 324.142695 -430.850057) (xy 324.126922 -430.78691) (xy 324.118972 -430.72231) (xy 324.118478 -430.689766)
			(xy 324.119206 -430.650441) (xy 324.130811 -430.572651) (xy 324.141592 -430.534826) (xy 324.141592 -430.018952)
			(xy 324.142023 -430.006875) (xy 324.149499 -429.983906) (xy 324.163704 -429.96437) (xy 324.183249 -429.950177)
			(xy 324.206223 -429.942716) (xy 324.2183 -429.942244) (xy 325.1581 -429.942244) (xy 325.17017 -429.942764)
			(xy 325.193129 -429.95022) (xy 325.212662 -429.964404) (xy 325.226858 -429.983928) (xy 325.234329 -430.006883)
			(xy 325.234808 -430.018952) (xy 325.234808 -430.889918) (xy 326.118474 -430.889918) (xy 326.118974 -430.857362)
			(xy 326.126919 -430.792736) (xy 326.142702 -430.729566) (xy 326.166088 -430.668799) (xy 326.196726 -430.611346)
			(xy 326.234157 -430.558068) (xy 326.277819 -430.509765) (xy 326.302116 -430.48809) (xy 326.382888 -430.323244)
			(xy 326.387617 -430.312738) (xy 326.391098 -430.289973) (xy 326.3876 -430.26721) (xy 326.382888 -430.256696)
			(xy 326.301862 -430.091596) (xy 326.27763 -430.069866) (xy 326.234029 -430.021541) (xy 326.19665 -429.968257)
			(xy 326.166051 -429.91081) (xy 326.142691 -429.850059) (xy 326.126918 -429.786912) (xy 326.118968 -429.722312)
			(xy 326.118474 -429.689768) (xy 326.119203 -429.650443) (xy 326.130807 -429.572653) (xy 326.141588 -429.534828)
			(xy 326.141588 -429.018954) (xy 326.141969 -429.006857) (xy 326.149444 -428.983847) (xy 326.163651 -428.964264)
			(xy 326.183205 -428.950016) (xy 326.2062 -428.942494) (xy 326.218296 -428.941992) (xy 327.158096 -428.941992)
			(xy 327.170204 -428.942419) (xy 327.19323 -428.949917) (xy 327.212802 -428.964176) (xy 327.226997 -428.983795)
			(xy 327.23442 -429.006845) (xy 327.234804 -429.018954) (xy 327.234804 -431.560478) (xy 327.234275 -431.572562)
			(xy 327.226829 -431.595555) (xy 327.212657 -431.615131) (xy 327.19314 -431.629384) (xy 327.170178 -431.636924)
			(xy 327.158096 -431.63744) (xy 326.218296 -431.63744) (xy 326.206191 -431.636988) (xy 326.18317 -431.629492)
			(xy 326.163601 -431.615238) (xy 326.149405 -431.595627) (xy 326.141977 -431.572584) (xy 326.141588 -431.560478)
			(xy 326.141588 -431.044858) (xy 326.130793 -431.007036) (xy 326.119184 -430.929244) (xy 326.118474 -430.889918)
			(xy 325.234808 -430.889918) (xy 325.234808 -431.889916) (xy 328.11847 -431.889916) (xy 328.11897 -431.85736)
			(xy 328.126915 -431.792734) (xy 328.142698 -431.729564) (xy 328.166084 -431.668797) (xy 328.196723 -431.611344)
			(xy 328.234153 -431.558066) (xy 328.277815 -431.509763) (xy 328.302112 -431.488088) (xy 328.382884 -431.323242)
			(xy 328.387614 -431.312737) (xy 328.391095 -431.289971) (xy 328.387597 -431.267208) (xy 328.382884 -431.256694)
			(xy 328.301858 -431.091594) (xy 328.277624 -431.069866) (xy 328.234023 -431.02154) (xy 328.196644 -430.968256)
			(xy 328.166046 -430.910809) (xy 328.142687 -430.850058) (xy 328.126914 -430.78691) (xy 328.118964 -430.72231)
			(xy 328.11847 -430.689766) (xy 328.119199 -430.650441) (xy 328.130803 -430.572651) (xy 328.141584 -430.534826)
			(xy 328.141584 -430.018952) (xy 328.142023 -430.006876) (xy 328.149498 -429.983908) (xy 328.163701 -429.964373)
			(xy 328.183244 -429.95018) (xy 328.206215 -429.942717) (xy 328.218292 -429.942244) (xy 329.158092 -429.942244)
			(xy 329.170161 -429.94277) (xy 329.19312 -429.950225) (xy 329.212653 -429.964407) (xy 329.22685 -429.98393)
			(xy 329.234321 -430.006883) (xy 329.2348 -430.018952) (xy 329.2348 -430.889918) (xy 331.118464 -430.889918)
			(xy 331.118968 -430.857362) (xy 331.126912 -430.792737) (xy 331.142695 -430.729567) (xy 331.166081 -430.6688)
			(xy 331.196718 -430.611347) (xy 331.234148 -430.558069) (xy 331.27781 -430.509765) (xy 331.302106 -430.48809)
			(xy 331.382878 -430.323244) (xy 331.387607 -430.312738) (xy 331.391089 -430.289973) (xy 331.387591 -430.26721)
			(xy 331.382878 -430.256696) (xy 331.301852 -430.091596) (xy 331.277618 -430.069868) (xy 331.234017 -430.021542)
			(xy 331.196639 -429.968258) (xy 331.166041 -429.910811) (xy 331.142681 -429.85006) (xy 331.126908 -429.786912)
			(xy 331.118958 -429.722312) (xy 331.118464 -429.689768) (xy 331.119156 -429.650641) (xy 331.130636 -429.573235)
			(xy 331.141324 -429.53559) (xy 331.141324 -429.018954) (xy 331.141772 -429.006838) (xy 331.14927 -428.983796)
			(xy 331.163519 -428.964196) (xy 331.183125 -428.949956) (xy 331.20617 -428.942467) (xy 331.218286 -428.941992)
			(xy 332.158086 -428.941992) (xy 332.170195 -428.942523) (xy 332.19323 -428.950001) (xy 332.212828 -428.964229)
			(xy 332.227072 -428.983816) (xy 332.234568 -429.006845) (xy 332.235048 -429.018954) (xy 332.235048 -431.560478)
			(xy 332.234621 -431.572601) (xy 332.227133 -431.595662) (xy 332.212884 -431.615278) (xy 332.193269 -431.62953)
			(xy 332.170209 -431.63702) (xy 332.158086 -431.63744) (xy 331.218286 -431.63744) (xy 331.20616 -431.637051)
			(xy 331.183097 -431.629553) (xy 331.163481 -431.615294) (xy 331.149231 -431.59567) (xy 331.141743 -431.572604)
			(xy 331.141324 -431.560478) (xy 331.141324 -431.044096) (xy 331.130641 -431.00645) (xy 331.119161 -430.929044)
			(xy 331.118464 -430.889918) (xy 329.2348 -430.889918) (xy 329.2348 -431.889916) (xy 333.11846 -431.889916)
			(xy 333.118964 -431.85736) (xy 333.126908 -431.792735) (xy 333.142691 -431.729565) (xy 333.166077 -431.668798)
			(xy 333.196715 -431.611345) (xy 333.234145 -431.558067) (xy 333.277806 -431.509763) (xy 333.302102 -431.488088)
			(xy 333.382874 -431.323242) (xy 333.387605 -431.312737) (xy 333.391086 -431.289971) (xy 333.387587 -431.267208)
			(xy 333.382874 -431.256694) (xy 333.301848 -431.091594) (xy 333.277612 -431.069868) (xy 333.234012 -431.021542)
			(xy 333.196633 -430.968257) (xy 333.166036 -430.91081) (xy 333.142676 -430.850058) (xy 333.126904 -430.78691)
			(xy 333.118954 -430.72231) (xy 333.11846 -430.689766) (xy 333.119152 -430.650639) (xy 333.130632 -430.573233)
			(xy 333.14132 -430.535588) (xy 333.14132 -430.018952) (xy 333.141676 -430.006839) (xy 333.149191 -429.983806)
			(xy 333.163467 -429.964232) (xy 333.183103 -429.95004) (xy 333.206167 -429.942624) (xy 333.218282 -429.942244)
			(xy 334.158082 -429.942244) (xy 334.170171 -429.942723) (xy 334.193172 -429.950175) (xy 334.212752 -429.964358)
			(xy 334.227003 -429.98389) (xy 334.234535 -430.006865) (xy 334.235044 -430.018952) (xy 334.235044 -430.889918)
			(xy 335.118456 -430.889918) (xy 335.118963 -430.857362) (xy 335.126906 -430.792737) (xy 335.142689 -430.729567)
			(xy 335.166075 -430.6688) (xy 335.196712 -430.611347) (xy 335.234141 -430.558069) (xy 335.277802 -430.509765)
			(xy 335.302098 -430.48809) (xy 335.38287 -430.323244) (xy 335.3876 -430.312738) (xy 335.391082 -430.289973)
			(xy 335.387583 -430.26721) (xy 335.38287 -430.256696) (xy 335.301844 -430.091596) (xy 335.277609 -430.06987)
			(xy 335.234008 -430.021544) (xy 335.19663 -429.968259) (xy 335.166032 -429.910811) (xy 335.142673 -429.85006)
			(xy 335.1269 -429.786912) (xy 335.11895 -429.722312) (xy 335.118456 -429.689768) (xy 335.119148 -429.650641)
			(xy 335.130628 -429.573235) (xy 335.141316 -429.53559) (xy 335.141316 -429.018954) (xy 335.141772 -429.006839)
			(xy 335.149269 -428.983798) (xy 335.163516 -428.964199) (xy 335.18312 -428.949958) (xy 335.206163 -428.942468)
			(xy 335.218278 -428.941992) (xy 336.158078 -428.941992) (xy 336.170187 -428.94253) (xy 336.193222 -428.950005)
			(xy 336.21282 -428.964232) (xy 336.227064 -428.983817) (xy 336.234559 -429.006846) (xy 336.23504 -429.018954)
			(xy 336.23504 -431.560478) (xy 336.234621 -431.572602) (xy 336.227132 -431.595664) (xy 336.212881 -431.615281)
			(xy 336.193264 -431.629532) (xy 336.170202 -431.637021) (xy 336.158078 -431.63744) (xy 335.218278 -431.63744)
			(xy 335.20616 -431.637007) (xy 335.183112 -431.629511) (xy 335.163509 -431.61526) (xy 335.149269 -431.595648)
			(xy 335.141786 -431.572596) (xy 335.141316 -431.560478) (xy 335.141316 -431.044096) (xy 335.130633 -431.00645)
			(xy 335.119153 -430.929044) (xy 335.118456 -430.889918) (xy 334.235044 -430.889918) (xy 334.235044 -431.889916)
			(xy 337.118452 -431.889916) (xy 337.118959 -431.85736) (xy 337.126903 -431.792735) (xy 337.142686 -431.729565)
			(xy 337.166071 -431.668798) (xy 337.196708 -431.611345) (xy 337.234138 -431.558067) (xy 337.277798 -431.509764)
			(xy 337.302094 -431.488088) (xy 337.382866 -431.323242) (xy 337.387592 -431.312736) (xy 337.391069 -431.289971)
			(xy 337.387575 -431.267209) (xy 337.382866 -431.256694) (xy 337.30184 -431.091594) (xy 337.277603 -431.06987)
			(xy 337.234003 -431.021543) (xy 337.196624 -430.968258) (xy 337.166027 -430.91081) (xy 337.142668 -430.850058)
			(xy 337.126896 -430.78691) (xy 337.118946 -430.72231) (xy 337.118452 -430.689766) (xy 337.119144 -430.650639)
			(xy 337.130624 -430.573233) (xy 337.141312 -430.535588) (xy 337.141312 -430.018952) (xy 337.141676 -430.006839)
			(xy 337.14919 -429.983809) (xy 337.163465 -429.964235) (xy 337.183098 -429.950043) (xy 337.20616 -429.942625)
			(xy 337.218274 -429.942244) (xy 338.158074 -429.942244) (xy 338.170163 -429.94273) (xy 338.193163 -429.95018)
			(xy 338.212744 -429.964361) (xy 338.226995 -429.983891) (xy 338.234527 -430.006865) (xy 338.235036 -430.018952)
			(xy 338.235036 -430.889918) (xy 339.118448 -430.889918) (xy 339.118957 -430.857362) (xy 339.126901 -430.792737)
			(xy 339.142684 -430.729568) (xy 339.166069 -430.668801) (xy 339.196705 -430.611348) (xy 339.234134 -430.55807)
			(xy 339.277794 -430.509766) (xy 339.30209 -430.48809) (xy 339.382862 -430.323244) (xy 339.387587 -430.312737)
			(xy 339.391065 -430.289973) (xy 339.387571 -430.267211) (xy 339.382862 -430.256696) (xy 339.301836 -430.091596)
			(xy 339.277599 -430.069871) (xy 339.233999 -430.021545) (xy 339.196621 -429.96826) (xy 339.166024 -429.910812)
			(xy 339.142664 -429.85006) (xy 339.126892 -429.786912) (xy 339.118942 -429.722312) (xy 339.118448 -429.689768)
			(xy 339.119141 -429.650641) (xy 339.13062 -429.573235) (xy 339.141308 -429.53559) (xy 339.141308 -429.018954)
			(xy 339.141772 -429.00684) (xy 339.149268 -428.9838) (xy 339.163513 -428.964202) (xy 339.183115 -428.949961)
			(xy 339.206156 -428.94247) (xy 339.21827 -428.941992) (xy 340.15807 -428.941992) (xy 340.170178 -428.942537)
			(xy 340.193213 -428.95001) (xy 340.212811 -428.964235) (xy 340.227055 -428.983819) (xy 340.234551 -429.006846)
			(xy 340.235032 -429.018954) (xy 340.235032 -431.560478) (xy 340.234621 -431.572603) (xy 340.227131 -431.595666)
			(xy 340.212878 -431.615284) (xy 340.193259 -431.629535) (xy 340.170195 -431.637022) (xy 340.15807 -431.63744)
			(xy 339.21827 -431.63744) (xy 339.206152 -431.637014) (xy 339.183104 -431.629515) (xy 339.163501 -431.615262)
			(xy 339.149261 -431.59565) (xy 339.141778 -431.572597) (xy 339.141308 -431.560478) (xy 339.141308 -431.044096)
			(xy 339.130624 -431.00645) (xy 339.119145 -430.929044) (xy 339.118448 -430.889918) (xy 338.235036 -430.889918)
			(xy 338.235036 -431.889916) (xy 341.118444 -431.889916) (xy 341.118953 -431.85736) (xy 341.126897 -431.792735)
			(xy 341.14268 -431.729566) (xy 341.166065 -431.668799) (xy 341.196702 -431.611346) (xy 341.23413 -431.558068)
			(xy 341.27779 -431.509764) (xy 341.302086 -431.488088) (xy 341.382858 -431.323242) (xy 341.387585 -431.312736)
			(xy 341.391062 -431.289971) (xy 341.387567 -431.267209) (xy 341.382858 -431.256694) (xy 341.301832 -431.091594)
			(xy 341.277593 -431.069871) (xy 341.233993 -431.021544) (xy 341.196616 -430.968259) (xy 341.166019 -430.910811)
			(xy 341.14266 -430.850059) (xy 341.126887 -430.786911) (xy 341.118938 -430.72231) (xy 341.118444 -430.689766)
			(xy 341.119136 -430.650639) (xy 341.130616 -430.573233) (xy 341.141304 -430.535588) (xy 341.141304 -430.018952)
			(xy 341.141676 -430.00684) (xy 341.149189 -429.983811) (xy 341.163462 -429.964238) (xy 341.183093 -429.950045)
			(xy 341.206153 -429.942626) (xy 341.218266 -429.942244) (xy 342.158066 -429.942244) (xy 342.170154 -429.942736)
			(xy 342.193154 -429.950184) (xy 342.212735 -429.964364) (xy 342.226987 -429.983893) (xy 342.234519 -430.006866)
			(xy 342.235028 -430.018952) (xy 342.235028 -430.889918) (xy 343.11844 -430.889918) (xy 343.118952 -430.857362)
			(xy 343.126896 -430.792738) (xy 343.142678 -430.729568) (xy 343.166063 -430.668801) (xy 343.196699 -430.611348)
			(xy 343.234127 -430.55807) (xy 343.277787 -430.509766) (xy 343.302082 -430.48809) (xy 343.382854 -430.323244)
			(xy 343.387579 -430.312737) (xy 343.391058 -430.289973) (xy 343.387563 -430.267211) (xy 343.382854 -430.256696)
			(xy 343.301828 -430.091596) (xy 343.277589 -430.069873) (xy 343.23399 -430.021546) (xy 343.196612 -429.968261)
			(xy 343.166015 -429.910813) (xy 343.142656 -429.850061) (xy 343.126884 -429.786913) (xy 343.118934 -429.722312)
			(xy 343.11844 -429.689768) (xy 343.119133 -429.650641) (xy 343.130612 -429.573235) (xy 343.1413 -429.53559)
			(xy 343.1413 -429.018954) (xy 343.141772 -429.006841) (xy 343.149267 -428.983803) (xy 343.163511 -428.964205)
			(xy 343.18311 -428.949964) (xy 343.206149 -428.942471) (xy 343.218262 -428.941992) (xy 344.158062 -428.941992)
			(xy 344.17017 -428.942543) (xy 344.193204 -428.950015) (xy 344.212803 -428.964238) (xy 344.227047 -428.98382)
			(xy 344.234543 -429.006847) (xy 344.235024 -429.018954) (xy 344.235024 -431.560478) (xy 344.234621 -431.572603)
			(xy 344.22713 -431.595668) (xy 344.212875 -431.615287) (xy 344.193254 -431.629537) (xy 344.170187 -431.637023)
			(xy 344.158062 -431.63744) (xy 343.218262 -431.63744) (xy 343.206143 -431.63702) (xy 343.183095 -431.62952)
			(xy 343.163492 -431.615265) (xy 343.149253 -431.595651) (xy 343.14177 -431.572597) (xy 343.1413 -431.560478)
			(xy 343.1413 -431.044096) (xy 343.130616 -431.00645) (xy 343.119137 -430.929044) (xy 343.11844 -430.889918)
			(xy 342.235028 -430.889918) (xy 342.235028 -431.889916) (xy 345.118436 -431.889916) (xy 345.118948 -431.85736)
			(xy 345.126892 -431.792736) (xy 345.142674 -431.729566) (xy 345.166059 -431.6688) (xy 345.196695 -431.611346)
			(xy 345.234123 -431.558068) (xy 345.277783 -431.509764) (xy 345.302078 -431.488088) (xy 345.38285 -431.323242)
			(xy 345.387577 -431.312736) (xy 345.391055 -431.289971) (xy 345.38756 -431.267209) (xy 345.38285 -431.256694)
			(xy 345.301824 -431.091594) (xy 345.277584 -431.069873) (xy 345.233984 -431.021546) (xy 345.196607 -430.96826)
			(xy 345.16601 -430.910811) (xy 345.142651 -430.850059) (xy 345.126879 -430.786911) (xy 345.11893 -430.72231)
			(xy 345.118436 -430.689766) (xy 345.119129 -430.650639) (xy 345.130608 -430.573233) (xy 345.141296 -430.535588)
			(xy 345.141296 -430.018952) (xy 345.141676 -430.006841) (xy 345.149188 -429.983813) (xy 345.163459 -429.964241)
			(xy 345.183088 -429.950048) (xy 345.206145 -429.942628) (xy 345.218258 -429.942244) (xy 346.158058 -429.942244)
			(xy 346.170146 -429.942743) (xy 346.193146 -429.950189) (xy 346.212727 -429.964367) (xy 346.226979 -429.983894)
			(xy 346.234511 -430.006866) (xy 346.23502 -430.018952) (xy 346.23502 -431.359818) (xy 356.154736 -431.359818)
			(xy 356.155234 -431.274938) (xy 356.163191 -431.105365) (xy 356.179087 -430.936351) (xy 356.202888 -430.768268)
			(xy 356.234542 -430.601485) (xy 356.273978 -430.436369) (xy 356.32111 -430.273284) (xy 356.375834 -430.112586)
			(xy 356.438031 -429.954631) (xy 356.507563 -429.799764) (xy 356.584278 -429.648327) (xy 356.668006 -429.500651)
			(xy 356.758564 -429.357063) (xy 356.855753 -429.217877) (xy 356.95936 -429.0834) (xy 357.069155 -428.953927)
			(xy 357.184899 -428.829742) (xy 357.306336 -428.711119) (xy 357.4332 -428.598318) (xy 357.565211 -428.491588)
			(xy 357.702081 -428.391163) (xy 357.843506 -428.297264) (xy 357.989178 -428.210096) (xy 358.138776 -428.129853)
			(xy 358.29197 -428.056709) (xy 358.448424 -427.990827) (xy 358.607794 -427.93235) (xy 358.76973 -427.881408)
			(xy 358.933876 -427.838112) (xy 359.099871 -427.802557) (xy 359.26735 -427.774822) (xy 359.435945 -427.754968)
			(xy 359.605285 -427.743038) (xy 359.774998 -427.739059) (xy 359.944711 -427.743038) (xy 360.114051 -427.754968)
			(xy 360.282646 -427.774822) (xy 360.450125 -427.802557) (xy 360.61612 -427.838112) (xy 360.780266 -427.881408)
			(xy 360.942202 -427.93235) (xy 361.101572 -427.990827) (xy 361.258026 -428.056709) (xy 361.41122 -428.129853)
			(xy 361.560818 -428.210096) (xy 361.693883 -428.28972) (xy 383.218436 -428.28972) (xy 383.218959 -428.25714)
			(xy 383.226931 -428.19247) (xy 383.242746 -428.129258) (xy 383.266166 -428.068452) (xy 383.296841 -428.010965)
			(xy 383.334311 -427.957656) (xy 383.378014 -427.909325) (xy 383.402332 -427.887638) (xy 383.48285 -427.7233)
			(xy 383.487537 -427.712778) (xy 383.491029 -427.690023) (xy 383.487551 -427.667267) (xy 383.48285 -427.656752)
			(xy 383.401824 -427.491652) (xy 383.377563 -427.469953) (xy 383.333965 -427.421622) (xy 383.29659 -427.368332)
			(xy 383.265996 -427.31088) (xy 383.24264 -427.250124) (xy 383.226872 -427.186973) (xy 383.218927 -427.122369)
			(xy 383.218436 -427.089824) (xy 383.219141 -427.050698) (xy 383.230612 -426.973291) (xy 383.241296 -426.935646)
			(xy 383.241296 -426.41901) (xy 383.24182 -426.4069) (xy 383.249299 -426.383864) (xy 383.263529 -426.364266)
			(xy 383.283118 -426.350023) (xy 383.306148 -426.342528) (xy 383.318258 -426.342048) (xy 384.258058 -426.342048)
			(xy 384.27018 -426.342496) (xy 384.293239 -426.349978) (xy 384.312855 -426.364222) (xy 384.327108 -426.383833)
			(xy 384.334599 -426.406889) (xy 384.33502 -426.41901) (xy 384.33502 -427.289976) (xy 385.218432 -427.289976)
			(xy 385.218917 -427.25742) (xy 385.226866 -427.192794) (xy 385.242653 -427.129624) (xy 385.266042 -427.068857)
			(xy 385.296682 -427.011404) (xy 385.334114 -426.958126) (xy 385.377777 -426.909823) (xy 385.402074 -426.888148)
			(xy 385.482846 -426.723302) (xy 385.487532 -426.71278) (xy 385.491025 -426.690025) (xy 385.487547 -426.667269)
			(xy 385.482846 -426.656754) (xy 385.40182 -426.491654) (xy 385.377559 -426.469955) (xy 385.333961 -426.421623)
			(xy 385.296586 -426.368334) (xy 385.265992 -426.310881) (xy 385.242637 -426.250126) (xy 385.226869 -426.186974)
			(xy 385.218924 -426.122371) (xy 385.218432 -426.089826) (xy 385.219138 -426.0507) (xy 385.230609 -425.973294)
			(xy 385.241292 -425.935648) (xy 385.241292 -425.419012) (xy 385.241727 -425.406905) (xy 385.249222 -425.383879)
			(xy 385.263479 -425.364307) (xy 385.283096 -425.350111) (xy 385.306145 -425.342689) (xy 385.318254 -425.342304)
			(xy 386.258054 -425.342304) (xy 386.270138 -425.342846) (xy 386.293131 -425.350286) (xy 386.312708 -425.364454)
			(xy 386.326962 -425.38397) (xy 386.334501 -425.40693) (xy 386.335016 -425.419012) (xy 386.335016 -427.960536)
			(xy 386.334615 -427.972645) (xy 386.327107 -427.995671) (xy 386.312841 -428.015242) (xy 386.293218 -428.029436)
			(xy 386.270165 -428.036859) (xy 386.258054 -428.037244) (xy 385.318254 -428.037244) (xy 385.30616 -428.036832)
			(xy 385.283156 -428.02936) (xy 385.263575 -428.01516) (xy 385.249327 -427.995615) (xy 385.241799 -427.972628)
			(xy 385.241292 -427.960536) (xy 385.241292 -427.444154) (xy 385.230599 -427.40651) (xy 385.219126 -427.329103)
			(xy 385.218432 -427.289976) (xy 384.33502 -427.289976) (xy 384.33502 -428.28972) (xy 387.218428 -428.28972)
			(xy 387.218954 -428.25714) (xy 387.226926 -428.19247) (xy 387.24274 -428.129258) (xy 387.26616 -428.068453)
			(xy 387.296834 -428.010965) (xy 387.334304 -427.957656) (xy 387.378006 -427.909325) (xy 387.402324 -427.887638)
			(xy 387.482842 -427.7233) (xy 387.487529 -427.712778) (xy 387.491022 -427.690023) (xy 387.487543 -427.667267)
			(xy 387.482842 -427.656752) (xy 387.401816 -427.491652) (xy 387.377554 -427.469955) (xy 387.333956 -427.421623)
			(xy 387.296581 -427.368333) (xy 387.265987 -427.31088) (xy 387.242632 -427.250124) (xy 387.226864 -427.186973)
			(xy 387.218919 -427.122369) (xy 387.218428 -427.089824) (xy 387.219133 -427.050698) (xy 387.230604 -426.973292)
			(xy 387.241288 -426.935646) (xy 387.241288 -426.41901) (xy 387.24182 -426.406901) (xy 387.249298 -426.383867)
			(xy 387.263526 -426.364269) (xy 387.283113 -426.350025) (xy 387.306141 -426.342529) (xy 387.31825 -426.342048)
			(xy 388.25805 -426.342048) (xy 388.270168 -426.342469) (xy 388.293215 -426.349972) (xy 388.312816 -426.364226)
			(xy 388.327056 -426.383839) (xy 388.33454 -426.406891) (xy 388.335012 -426.41901) (xy 388.335012 -427.289976)
			(xy 389.218424 -427.289976) (xy 389.218912 -427.25742) (xy 389.22686 -427.192794) (xy 389.242647 -427.129624)
			(xy 389.266036 -427.068858) (xy 389.296675 -427.011405) (xy 389.334107 -426.958127) (xy 389.377769 -426.909823)
			(xy 389.402066 -426.888148) (xy 389.482838 -426.723302) (xy 389.487524 -426.71278) (xy 389.491018 -426.690025)
			(xy 389.487539 -426.667268) (xy 389.482838 -426.656754) (xy 389.401812 -426.491654) (xy 389.37755 -426.469957)
			(xy 389.333952 -426.421625) (xy 389.296577 -426.368334) (xy 389.265984 -426.310882) (xy 389.242628 -426.250126)
			(xy 389.22686 -426.186975) (xy 389.218916 -426.122371) (xy 389.218424 -426.089826) (xy 389.21913 -426.0507)
			(xy 389.230601 -425.973294) (xy 389.241284 -425.935648) (xy 389.241284 -425.419012) (xy 389.241727 -425.406905)
			(xy 389.249221 -425.383881) (xy 389.263476 -425.364309) (xy 389.283091 -425.350114) (xy 389.306138 -425.34269)
			(xy 389.318246 -425.342304) (xy 390.258046 -425.342304) (xy 390.270134 -425.342767) (xy 390.29313 -425.350232)
			(xy 390.312707 -425.364421) (xy 390.326957 -425.383953) (xy 390.334494 -425.406925) (xy 390.335008 -425.419012)
			(xy 390.335008 -427.960536) (xy 390.334614 -427.972646) (xy 390.327106 -427.995673) (xy 390.312838 -428.015245)
			(xy 390.293213 -428.029438) (xy 390.270157 -428.03686) (xy 390.258046 -428.037244) (xy 389.318246 -428.037244)
			(xy 389.306157 -428.036753) (xy 389.283155 -428.029307) (xy 389.263573 -428.015127) (xy 389.249322 -427.995597)
			(xy 389.241791 -427.972623) (xy 389.241284 -427.960536) (xy 389.241284 -427.444154) (xy 389.230591 -427.406511)
			(xy 389.219118 -427.329103) (xy 389.218424 -427.289976) (xy 388.335012 -427.289976) (xy 388.335012 -428.28972)
			(xy 391.21842 -428.28972) (xy 391.218948 -428.25714) (xy 391.22692 -428.19247) (xy 391.242734 -428.129259)
			(xy 391.266154 -428.068454) (xy 391.296828 -428.010966) (xy 391.334297 -427.957657) (xy 391.377999 -427.909325)
			(xy 391.402316 -427.887638) (xy 391.482834 -427.7233) (xy 391.487522 -427.712778) (xy 391.491015 -427.690023)
			(xy 391.487536 -427.667266) (xy 391.482834 -427.656752) (xy 391.401808 -427.491652) (xy 391.377544 -427.469957)
			(xy 391.333947 -427.421624) (xy 391.296572 -427.368334) (xy 391.265979 -427.310881) (xy 391.242624 -427.250125)
			(xy 391.226856 -427.186973) (xy 391.218911 -427.122369) (xy 391.21842 -427.089824) (xy 391.219126 -427.050698)
			(xy 391.230597 -426.973292) (xy 391.24128 -426.935646) (xy 391.24128 -426.41901) (xy 391.241669 -426.406884)
			(xy 391.249164 -426.383818) (xy 391.263422 -426.364199) (xy 391.283047 -426.349949) (xy 391.306115 -426.342464)
			(xy 391.318242 -426.342048) (xy 392.258042 -426.342048) (xy 392.27016 -426.342476) (xy 392.293206 -426.349976)
			(xy 392.312808 -426.364229) (xy 392.327048 -426.383841) (xy 392.334532 -426.406892) (xy 392.335004 -426.41901)
			(xy 392.335004 -427.289976) (xy 393.218416 -427.289976) (xy 393.218907 -427.25742) (xy 393.226855 -427.192794)
			(xy 393.242641 -427.129625) (xy 393.26603 -427.068858) (xy 393.296669 -427.011405) (xy 393.3341 -426.958127)
			(xy 393.377761 -426.909823) (xy 393.402058 -426.888148) (xy 393.48283 -426.723302) (xy 393.487517 -426.71278)
			(xy 393.49101 -426.690025) (xy 393.487532 -426.667268) (xy 393.48283 -426.656754) (xy 393.401804 -426.491654)
			(xy 393.37754 -426.469959) (xy 393.333943 -426.421626) (xy 393.296568 -426.368335) (xy 393.265975 -426.310883)
			(xy 393.24262 -426.250127) (xy 393.226852 -426.186975) (xy 393.218908 -426.122371) (xy 393.218416 -426.089826)
			(xy 393.219118 -426.0507) (xy 393.230591 -425.973293) (xy 393.241276 -425.935648) (xy 393.241276 -425.419012)
			(xy 393.241726 -425.406906) (xy 393.24922 -425.383883) (xy 393.263473 -425.364312) (xy 393.283086 -425.350116)
			(xy 393.306131 -425.342691) (xy 393.318238 -425.342304) (xy 394.258038 -425.342304) (xy 394.270126 -425.342774)
			(xy 394.293122 -425.350237) (xy 394.312698 -425.364424) (xy 394.326949 -425.383954) (xy 394.334486 -425.406926)
			(xy 394.335 -425.419012) (xy 394.335 -427.960536) (xy 394.334614 -427.972647) (xy 394.327105 -427.995675)
			(xy 394.312835 -428.015248) (xy 394.293208 -428.029441) (xy 394.27015 -428.036861) (xy 394.258038 -428.037244)
			(xy 393.318238 -428.037244) (xy 393.306149 -428.03676) (xy 393.283147 -428.029312) (xy 393.263565 -428.01513)
			(xy 393.249314 -427.995599) (xy 393.241783 -427.972623) (xy 393.241276 -427.960536) (xy 393.241276 -427.444154)
			(xy 393.230583 -427.406511) (xy 393.21911 -427.329103) (xy 393.218416 -427.289976) (xy 392.335004 -427.289976)
			(xy 392.335004 -428.28972) (xy 395.218412 -428.28972) (xy 395.218943 -428.25714) (xy 395.226915 -428.192471)
			(xy 395.242729 -428.129259) (xy 395.266148 -428.068454) (xy 395.296821 -428.010966) (xy 395.33429 -427.957657)
			(xy 395.377991 -427.909326) (xy 395.402308 -427.887638) (xy 395.482826 -427.7233) (xy 395.487514 -427.712778)
			(xy 395.491008 -427.690023) (xy 395.487528 -427.667266) (xy 395.482826 -427.656752) (xy 395.4018 -427.491652)
			(xy 395.377534 -427.469959) (xy 395.333937 -427.421626) (xy 395.296563 -427.368334) (xy 395.26597 -427.310881)
			(xy 395.242615 -427.250125) (xy 395.226848 -427.186973) (xy 395.218903 -427.122369) (xy 395.218412 -427.089824)
			(xy 395.219114 -427.050698) (xy 395.230587 -426.973291) (xy 395.241272 -426.935646) (xy 395.241272 -426.41901)
			(xy 395.241669 -426.406884) (xy 395.249163 -426.38382) (xy 395.263419 -426.364202) (xy 395.283042 -426.349952)
			(xy 395.306108 -426.342465) (xy 395.318234 -426.342048) (xy 396.258034 -426.342048) (xy 396.270151 -426.342483)
			(xy 396.293197 -426.349981) (xy 396.312799 -426.364232) (xy 396.327039 -426.383842) (xy 396.334524 -426.406892)
			(xy 396.334996 -426.41901) (xy 396.334996 -427.289976) (xy 398.218406 -427.289976) (xy 398.2189 -427.25742)
			(xy 398.226848 -427.192795) (xy 398.242634 -427.129626) (xy 398.266022 -427.068859) (xy 398.296661 -427.011406)
			(xy 398.334091 -426.958128) (xy 398.377752 -426.909824) (xy 398.402048 -426.888148) (xy 398.48282 -426.723302)
			(xy 398.487507 -426.71278) (xy 398.491001 -426.690025) (xy 398.487522 -426.667268) (xy 398.48282 -426.656754)
			(xy 398.401794 -426.491654) (xy 398.377528 -426.469961) (xy 398.333931 -426.421628) (xy 398.296557 -426.368336)
			(xy 398.265964 -426.310883) (xy 398.24261 -426.250127) (xy 398.226842 -426.186975) (xy 398.218898 -426.122371)
			(xy 398.218406 -426.089826) (xy 398.219125 -426.050501) (xy 398.230735 -425.972711) (xy 398.24152 -425.934886)
			(xy 398.24152 -425.419012) (xy 398.241924 -425.406927) (xy 398.249391 -425.38394) (xy 398.263599 -425.364387)
			(xy 398.283154 -425.350184) (xy 398.306143 -425.342721) (xy 398.318228 -425.342304) (xy 399.258028 -425.342304)
			(xy 399.270105 -425.34274) (xy 399.293075 -425.350212) (xy 399.312613 -425.364415) (xy 399.326806 -425.38396)
			(xy 399.334266 -425.406935) (xy 399.334736 -425.419012) (xy 399.334736 -427.960536) (xy 399.334267 -427.97261)
			(xy 399.326798 -427.995573) (xy 399.312602 -428.015107) (xy 399.293066 -428.029302) (xy 399.270102 -428.036768)
			(xy 399.258028 -428.037244) (xy 398.318228 -428.037244) (xy 398.306158 -428.036713) (xy 398.283198 -428.029262)
			(xy 398.263664 -428.015082) (xy 398.249467 -427.995559) (xy 398.241997 -427.972605) (xy 398.24152 -427.960536)
			(xy 398.24152 -427.444916) (xy 398.230716 -427.407096) (xy 398.219113 -427.329303) (xy 398.218406 -427.289976)
			(xy 396.334996 -427.289976) (xy 396.334996 -428.28972) (xy 400.218402 -428.28972) (xy 400.218937 -428.257141)
			(xy 400.226908 -428.192471) (xy 400.242722 -428.12926) (xy 400.26614 -428.068455) (xy 400.296813 -428.010967)
			(xy 400.334281 -427.957658) (xy 400.377981 -427.909326) (xy 400.402298 -427.887638) (xy 400.482816 -427.7233)
			(xy 400.487504 -427.712778) (xy 400.490998 -427.690023) (xy 400.487518 -427.667266) (xy 400.482816 -427.656752)
			(xy 400.40179 -427.491652) (xy 400.377522 -427.469961) (xy 400.333926 -427.421627) (xy 400.296552 -427.368335)
			(xy 400.265959 -427.310882) (xy 400.242605 -427.250125) (xy 400.226838 -427.186973) (xy 400.218893 -427.122369)
			(xy 400.218402 -427.089824) (xy 400.21912 -427.050499) (xy 400.230731 -426.972709) (xy 400.241516 -426.934884)
			(xy 400.241516 -426.41901) (xy 400.242016 -426.406923) (xy 400.249467 -426.383927) (xy 400.263646 -426.364349)
			(xy 400.283171 -426.350097) (xy 400.306139 -426.342561) (xy 400.318224 -426.342048) (xy 401.258024 -426.342048)
			(xy 401.270129 -426.342495) (xy 401.293148 -426.349995) (xy 401.312716 -426.36425) (xy 401.326912 -426.383862)
			(xy 401.334341 -426.406904) (xy 401.334732 -426.41901) (xy 401.334732 -427.289976) (xy 402.218398 -427.289976)
			(xy 402.218895 -427.25742) (xy 402.226843 -427.192795) (xy 402.242629 -427.129626) (xy 402.266016 -427.068859)
			(xy 402.296654 -427.011407) (xy 402.334084 -426.958128) (xy 402.377744 -426.909824) (xy 402.40204 -426.888148)
			(xy 402.482812 -426.723302) (xy 402.487499 -426.71278) (xy 402.490994 -426.690025) (xy 402.487514 -426.667268)
			(xy 402.482812 -426.656754) (xy 402.401786 -426.491654) (xy 402.377518 -426.469963) (xy 402.333922 -426.421629)
			(xy 402.296548 -426.368337) (xy 402.265956 -426.310884) (xy 402.242601 -426.250127) (xy 402.226834 -426.186975)
			(xy 402.21889 -426.122371) (xy 402.218398 -426.089826) (xy 402.219117 -426.050501) (xy 402.230727 -425.972711)
			(xy 402.241512 -425.934886) (xy 402.241512 -425.419012) (xy 402.241923 -425.406928) (xy 402.24939 -425.383942)
			(xy 402.263596 -425.36439) (xy 402.283149 -425.350186) (xy 402.306136 -425.342722) (xy 402.31822 -425.342304)
			(xy 403.25802 -425.342304) (xy 403.270097 -425.342748) (xy 403.293067 -425.350217) (xy 403.312604 -425.364419)
			(xy 403.326798 -425.383962) (xy 403.334257 -425.406935) (xy 403.334728 -425.419012) (xy 403.334728 -427.960536)
			(xy 403.334267 -427.97261) (xy 403.326797 -427.995576) (xy 403.312599 -428.01511) (xy 403.293061 -428.029304)
			(xy 403.270095 -428.036769) (xy 403.25802 -428.037244) (xy 402.31822 -428.037244) (xy 402.30615 -428.036719)
			(xy 402.28319 -428.029267) (xy 402.263655 -428.015085) (xy 402.249459 -427.995561) (xy 402.241989 -427.972606)
			(xy 402.241512 -427.960536) (xy 402.241512 -427.444916) (xy 402.230708 -427.407096) (xy 402.219105 -427.329303)
			(xy 402.218398 -427.289976) (xy 401.334732 -427.289976) (xy 401.334732 -428.28972) (xy 404.218394 -428.28972)
			(xy 404.218931 -428.257141) (xy 404.226902 -428.192471) (xy 404.242715 -428.12926) (xy 404.266134 -428.068455)
			(xy 404.296806 -428.010967) (xy 404.334273 -427.957658) (xy 404.377973 -427.909326) (xy 404.40229 -427.887638)
			(xy 404.482808 -427.7233) (xy 404.487497 -427.712779) (xy 404.490991 -427.690023) (xy 404.487511 -427.667266)
			(xy 404.482808 -427.656752) (xy 404.401782 -427.491652) (xy 404.377513 -427.469963) (xy 404.333917 -427.421628)
			(xy 404.296543 -427.368336) (xy 404.265951 -427.310883) (xy 404.242597 -427.250126) (xy 404.22683 -427.186974)
			(xy 404.218885 -427.122369) (xy 404.218394 -427.089824) (xy 404.219113 -427.050499) (xy 404.230723 -426.972709)
			(xy 404.241508 -426.934884) (xy 404.241508 -426.41901) (xy 404.242015 -426.406924) (xy 404.249465 -426.383929)
			(xy 404.263643 -426.364352) (xy 404.283166 -426.3501) (xy 404.306132 -426.342562) (xy 404.318216 -426.342048)
			(xy 405.258016 -426.342048) (xy 405.270121 -426.342502) (xy 405.293139 -426.349999) (xy 405.312708 -426.364253)
			(xy 405.326904 -426.383863) (xy 405.334333 -426.406904) (xy 405.334724 -426.41901) (xy 405.334724 -427.289976)
			(xy 406.21839 -427.289976) (xy 406.218856 -427.257419) (xy 406.226805 -427.192792) (xy 406.242594 -427.129621)
			(xy 406.265986 -427.068853) (xy 406.296629 -427.0114) (xy 406.334066 -426.958124) (xy 406.377733 -426.909822)
			(xy 406.402032 -426.888148) (xy 406.482804 -426.723302) (xy 406.487492 -426.71278) (xy 406.490987 -426.690025)
			(xy 406.487507 -426.667268) (xy 406.482804 -426.656754) (xy 406.401778 -426.491654) (xy 406.377509 -426.469964)
			(xy 406.333913 -426.42163) (xy 406.29654 -426.368338) (xy 406.265947 -426.310884) (xy 406.242593 -426.250128)
			(xy 406.226826 -426.186975) (xy 406.218882 -426.122371) (xy 406.21839 -426.089826) (xy 406.219109 -426.050501)
			(xy 406.23072 -425.972711) (xy 406.241504 -425.934886) (xy 406.241504 -425.419012) (xy 406.241923 -425.406929)
			(xy 406.249389 -425.383944) (xy 406.263593 -425.364393) (xy 406.283144 -425.350189) (xy 406.306129 -425.342723)
			(xy 406.318212 -425.342304) (xy 407.258012 -425.342304) (xy 407.270088 -425.342754) (xy 407.293058 -425.350222)
			(xy 407.312596 -425.364421) (xy 407.326789 -425.383964) (xy 407.334249 -425.406935) (xy 407.33472 -425.419012)
			(xy 407.33472 -427.960536) (xy 407.334267 -427.972611) (xy 407.326796 -427.995578) (xy 407.312596 -428.015113)
			(xy 407.293056 -428.029307) (xy 407.270087 -428.036771) (xy 407.258012 -428.037244) (xy 406.318212 -428.037244)
			(xy 406.306142 -428.036726) (xy 406.283181 -428.029271) (xy 406.263647 -428.015087) (xy 406.249451 -427.995562)
			(xy 406.241981 -427.972606) (xy 406.241504 -427.960536) (xy 406.241504 -427.444916) (xy 406.2307 -427.407096)
			(xy 406.219097 -427.329303) (xy 406.21839 -427.289976) (xy 405.334724 -427.289976) (xy 405.334724 -428.28972)
			(xy 408.218386 -428.28972) (xy 408.218926 -428.257141) (xy 408.226897 -428.192472) (xy 408.24271 -428.129261)
			(xy 408.266128 -428.068456) (xy 408.2968 -428.010968) (xy 408.334266 -427.957658) (xy 408.377966 -427.909326)
			(xy 408.402282 -427.887638) (xy 408.4828 -427.7233) (xy 408.487489 -427.712779) (xy 408.490984 -427.690023)
			(xy 408.487503 -427.667266) (xy 408.4828 -427.656752) (xy 408.401774 -427.491652) (xy 408.377503 -427.469964)
			(xy 408.333907 -427.42163) (xy 408.296534 -427.368337) (xy 408.265942 -427.310883) (xy 408.242588 -427.250126)
			(xy 408.226822 -427.186974) (xy 408.218877 -427.122369) (xy 408.218386 -427.089824) (xy 408.219105 -427.050499)
			(xy 408.230716 -426.972709) (xy 408.2415 -426.934884) (xy 408.2415 -426.41901) (xy 408.242015 -426.406925)
			(xy 408.249464 -426.383931) (xy 408.26364 -426.364355) (xy 408.283161 -426.350103) (xy 408.306125 -426.342563)
			(xy 408.318208 -426.342048) (xy 409.258008 -426.342048) (xy 409.270112 -426.342509) (xy 409.293131 -426.350004)
			(xy 409.312699 -426.364256) (xy 409.326896 -426.383865) (xy 409.334325 -426.406905) (xy 409.334716 -426.41901)
			(xy 409.334716 -427.289976) (xy 410.218382 -427.289976) (xy 410.218851 -427.257419) (xy 410.2268 -427.192792)
			(xy 410.242588 -427.129621) (xy 410.26598 -427.068854) (xy 410.296623 -427.011401) (xy 410.334059 -426.958124)
			(xy 410.377725 -426.909822) (xy 410.402024 -426.888148) (xy 410.482796 -426.723302) (xy 410.487484 -426.71278)
			(xy 410.490979 -426.690025) (xy 410.487499 -426.667268) (xy 410.482796 -426.656754) (xy 410.40177 -426.491654)
			(xy 410.377519 -426.469944) (xy 410.333919 -426.421616) (xy 410.296541 -426.368328) (xy 410.265945 -426.310878)
			(xy 410.242588 -426.250124) (xy 410.226819 -426.186973) (xy 410.218874 -426.122371) (xy 410.218382 -426.089826)
			(xy 410.219102 -426.050501) (xy 410.230712 -425.972711) (xy 410.241496 -425.934886) (xy 410.241496 -425.419012)
			(xy 410.241923 -425.40693) (xy 410.249388 -425.383947) (xy 410.26359 -425.364396) (xy 410.283139 -425.350191)
			(xy 410.306122 -425.342724) (xy 410.318204 -425.342304) (xy 411.258004 -425.342304) (xy 411.270088 -425.342709)
			(xy 411.293073 -425.350179) (xy 411.312624 -425.364387) (xy 411.326828 -425.383941) (xy 411.334293 -425.406928)
			(xy 411.334712 -425.419012) (xy 411.334712 -427.960536) (xy 411.334267 -427.972612) (xy 411.326795 -427.99558)
			(xy 411.312593 -428.015116) (xy 411.293051 -428.029309) (xy 411.27008 -428.036772) (xy 411.258004 -428.037244)
			(xy 410.318204 -428.037244) (xy 410.306133 -428.036733) (xy 410.283172 -428.029276) (xy 410.263638 -428.01509)
			(xy 410.249442 -427.995564) (xy 410.241973 -427.972607) (xy 410.241496 -427.960536) (xy 410.241496 -427.444916)
			(xy 410.230692 -427.407096) (xy 410.219088 -427.329303) (xy 410.218382 -427.289976) (xy 409.334716 -427.289976)
			(xy 409.334716 -428.28972) (xy 412.218378 -428.28972) (xy 412.21892 -428.257141) (xy 412.226891 -428.192472)
			(xy 412.242704 -428.129261) (xy 412.266122 -428.068456) (xy 412.296793 -428.010968) (xy 412.334259 -427.957659)
			(xy 412.377958 -427.909326) (xy 412.402274 -427.887638) (xy 412.482792 -427.7233) (xy 412.487482 -427.712779)
			(xy 412.490977 -427.690023) (xy 412.487496 -427.667266) (xy 412.482792 -427.656752) (xy 412.401766 -427.491652)
			(xy 412.377514 -427.469944) (xy 412.333913 -427.421615) (xy 412.296536 -427.368327) (xy 412.26594 -427.310877)
			(xy 412.242584 -427.250122) (xy 412.226815 -427.186972) (xy 412.21887 -427.122369) (xy 412.218378 -427.089824)
			(xy 412.219097 -427.050499) (xy 412.230708 -426.972709) (xy 412.241492 -426.934884) (xy 412.241492 -426.41901)
			(xy 412.242015 -426.406926) (xy 412.249463 -426.383934) (xy 412.263637 -426.364358) (xy 412.283156 -426.350105)
			(xy 412.306118 -426.342564) (xy 412.3182 -426.342048) (xy 413.258 -426.342048) (xy 413.270104 -426.342515)
			(xy 413.293122 -426.350009) (xy 413.312691 -426.364259) (xy 413.326887 -426.383866) (xy 413.334317 -426.406905)
			(xy 413.334708 -426.41901) (xy 413.334708 -428.960534) (xy 413.334223 -428.972621) (xy 413.326762 -428.995614)
			(xy 413.312579 -429.01519) (xy 413.293053 -429.029441) (xy 413.270085 -429.03698) (xy 413.258 -429.037496)
			(xy 412.3182 -429.037496) (xy 412.306091 -429.037084) (xy 412.283063 -429.029584) (xy 412.263489 -429.015321)
			(xy 412.249295 -428.995699) (xy 412.241875 -428.972645) (xy 412.241492 -428.960534) (xy 412.241492 -428.44466)
			(xy 412.230697 -428.406837) (xy 412.219088 -428.329046) (xy 412.218378 -428.28972) (xy 409.334716 -428.28972)
			(xy 409.334716 -428.960534) (xy 409.334321 -428.97263) (xy 409.326849 -428.995639) (xy 409.312646 -429.015222)
			(xy 409.293095 -429.02947) (xy 409.270103 -429.036993) (xy 409.258008 -429.037496) (xy 408.318208 -429.037496)
			(xy 408.306099 -429.037077) (xy 408.283071 -429.029579) (xy 408.263498 -429.015319) (xy 408.249303 -428.995697)
			(xy 408.241883 -428.972644) (xy 408.2415 -428.960534) (xy 408.2415 -428.44466) (xy 408.230705 -428.406837)
			(xy 408.219096 -428.329046) (xy 408.218386 -428.28972) (xy 405.334724 -428.28972) (xy 405.334724 -428.960534)
			(xy 405.334321 -428.972629) (xy 405.326851 -428.995637) (xy 405.312649 -429.015219) (xy 405.2931 -429.029467)
			(xy 405.27011 -429.036992) (xy 405.258016 -429.037496) (xy 404.318216 -429.037496) (xy 404.306108 -429.03707)
			(xy 404.28308 -429.029574) (xy 404.263507 -429.015315) (xy 404.249312 -428.995695) (xy 404.241891 -428.972644)
			(xy 404.241508 -428.960534) (xy 404.241508 -428.44466) (xy 404.230713 -428.406837) (xy 404.219104 -428.329046)
			(xy 404.218394 -428.28972) (xy 401.334732 -428.28972) (xy 401.334732 -428.960534) (xy 401.334321 -428.972628)
			(xy 401.326852 -428.995635) (xy 401.312652 -429.015216) (xy 401.293105 -429.029465) (xy 401.270117 -429.036991)
			(xy 401.258024 -429.037496) (xy 400.318224 -429.037496) (xy 400.306116 -429.037063) (xy 400.283089 -429.02957)
			(xy 400.263515 -429.015313) (xy 400.24932 -428.995694) (xy 400.241899 -428.972643) (xy 400.241516 -428.960534)
			(xy 400.241516 -428.44466) (xy 400.230722 -428.406837) (xy 400.219112 -428.329046) (xy 400.218402 -428.28972)
			(xy 396.334996 -428.28972) (xy 396.334996 -428.960534) (xy 396.334518 -428.972647) (xy 396.327025 -428.995686)
			(xy 396.312784 -429.015284) (xy 396.293186 -429.029525) (xy 396.270147 -429.037018) (xy 396.258034 -429.037496)
			(xy 395.318234 -429.037496) (xy 395.306125 -429.03696) (xy 395.283088 -429.029486) (xy 395.263489 -429.01526)
			(xy 395.249245 -428.995673) (xy 395.241751 -428.972643) (xy 395.241272 -428.960534) (xy 395.241272 -428.443898)
			(xy 395.230588 -428.406252) (xy 395.219109 -428.328846) (xy 395.218412 -428.28972) (xy 392.335004 -428.28972)
			(xy 392.335004 -428.960534) (xy 392.334518 -428.972646) (xy 392.327027 -428.995683) (xy 392.312787 -429.015281)
			(xy 392.293191 -429.029523) (xy 392.270154 -429.037017) (xy 392.258042 -429.037496) (xy 391.318242 -429.037496)
			(xy 391.306125 -429.037005) (xy 391.283073 -429.029528) (xy 391.26346 -429.015294) (xy 391.249206 -428.995695)
			(xy 391.241707 -428.972651) (xy 391.24128 -428.960534) (xy 391.24128 -428.443898) (xy 391.230596 -428.406252)
			(xy 391.219117 -428.328846) (xy 391.21842 -428.28972) (xy 388.335012 -428.28972) (xy 388.335012 -428.960534)
			(xy 388.334518 -428.972645) (xy 388.327028 -428.995681) (xy 388.31279 -429.015278) (xy 388.293196 -429.02952)
			(xy 388.270161 -429.037016) (xy 388.25805 -429.037496) (xy 387.31825 -429.037496) (xy 387.306136 -429.037031)
			(xy 387.283097 -429.029535) (xy 387.263499 -429.015289) (xy 387.249258 -428.995689) (xy 387.241766 -428.972648)
			(xy 387.241288 -428.960534) (xy 387.241288 -428.443898) (xy 387.230604 -428.406252) (xy 387.219125 -428.328846)
			(xy 387.218428 -428.28972) (xy 384.33502 -428.28972) (xy 384.33502 -428.960534) (xy 384.334669 -428.972663)
			(xy 384.327162 -428.99573) (xy 384.312894 -429.015348) (xy 384.293262 -429.029597) (xy 384.270187 -429.03708)
			(xy 384.258058 -429.037496) (xy 383.318258 -429.037496) (xy 383.306145 -429.037025) (xy 383.283106 -429.02953)
			(xy 383.263508 -429.015287) (xy 383.249266 -428.995687) (xy 383.241774 -428.972647) (xy 383.241296 -428.960534)
			(xy 383.241296 -428.443898) (xy 383.230613 -428.406252) (xy 383.219133 -428.328846) (xy 383.218436 -428.28972)
			(xy 361.693883 -428.28972) (xy 361.70649 -428.297264) (xy 361.847915 -428.391163) (xy 361.984785 -428.491588)
			(xy 362.116796 -428.598318) (xy 362.24366 -428.711119) (xy 362.365097 -428.829742) (xy 362.480841 -428.953927)
			(xy 362.590636 -429.0834) (xy 362.694243 -429.217877) (xy 362.791432 -429.357063) (xy 362.88199 -429.500651)
			(xy 362.965718 -429.648327) (xy 363.042433 -429.799764) (xy 363.111965 -429.954631) (xy 363.174162 -430.112586)
			(xy 363.228886 -430.273284) (xy 363.276018 -430.436369) (xy 363.315454 -430.601485) (xy 363.347108 -430.768268)
			(xy 363.364334 -430.889918) (xy 381.237998 -430.889918) (xy 381.238092 -430.875344) (xy 381.239744 -430.846243)
			(xy 381.2413 -430.831752) (xy 381.2413 -429.747934) (xy 381.239752 -429.733442) (xy 381.238102 -429.704342)
			(xy 381.237998 -429.689768) (xy 381.238096 -429.675194) (xy 381.239746 -429.646093) (xy 381.2413 -429.631602)
			(xy 381.2413 -429.018954) (xy 381.241772 -429.006841) (xy 381.249267 -428.983803) (xy 381.263511 -428.964205)
			(xy 381.28311 -428.949964) (xy 381.306149 -428.942471) (xy 381.318262 -428.941992) (xy 382.258062 -428.941992)
			(xy 382.27017 -428.942543) (xy 382.293204 -428.950015) (xy 382.312803 -428.964238) (xy 382.327047 -428.98382)
			(xy 382.334543 -429.006847) (xy 382.335024 -429.018954) (xy 382.335024 -431.560478) (xy 382.334621 -431.572603)
			(xy 382.32713 -431.595668) (xy 382.312875 -431.615287) (xy 382.293254 -431.629537) (xy 382.270187 -431.637023)
			(xy 382.258062 -431.63744) (xy 381.318262 -431.63744) (xy 381.306143 -431.63702) (xy 381.283095 -431.62952)
			(xy 381.263492 -431.615265) (xy 381.249253 -431.595651) (xy 381.24177 -431.572597) (xy 381.2413 -431.560478)
			(xy 381.2413 -430.948084) (xy 381.239756 -430.933592) (xy 381.238104 -430.904492) (xy 381.237998 -430.889918)
			(xy 363.364334 -430.889918) (xy 363.370909 -430.936351) (xy 363.386805 -431.105365) (xy 363.394762 -431.274938)
			(xy 363.39526 -431.359818) (xy 363.39483 -431.445421) (xy 363.38674 -431.616436) (xy 363.370574 -431.786877)
			(xy 363.355859 -431.889916) (xy 383.237994 -431.889916) (xy 383.238088 -431.875342) (xy 383.23974 -431.846241)
			(xy 383.241296 -431.83175) (xy 383.241296 -430.747932) (xy 383.239748 -430.73344) (xy 383.238098 -430.70434)
			(xy 383.237994 -430.689766) (xy 383.238092 -430.675192) (xy 383.239742 -430.646091) (xy 383.241296 -430.6316)
			(xy 383.241296 -430.018952) (xy 383.241676 -430.006841) (xy 383.249188 -429.983813) (xy 383.263459 -429.964241)
			(xy 383.283088 -429.950048) (xy 383.306145 -429.942628) (xy 383.318258 -429.942244) (xy 384.258058 -429.942244)
			(xy 384.270146 -429.942743) (xy 384.293146 -429.950189) (xy 384.312727 -429.964367) (xy 384.326979 -429.983894)
			(xy 384.334511 -430.006866) (xy 384.33502 -430.018952) (xy 384.33502 -430.889918) (xy 385.23799 -430.889918)
			(xy 385.238084 -430.875344) (xy 385.239736 -430.846243) (xy 385.241292 -430.831752) (xy 385.241292 -429.747934)
			(xy 385.239745 -429.733442) (xy 385.238094 -429.704342) (xy 385.23799 -429.689768) (xy 385.238088 -429.675194)
			(xy 385.239738 -429.646093) (xy 385.241292 -429.631602) (xy 385.241292 -429.018954) (xy 385.241772 -429.006842)
			(xy 385.249266 -428.983805) (xy 385.263508 -428.964208) (xy 385.283105 -428.949966) (xy 385.306142 -428.942472)
			(xy 385.318254 -428.941992) (xy 386.258054 -428.941992) (xy 386.270162 -428.94255) (xy 386.293196 -428.950019)
			(xy 386.312794 -428.96424) (xy 386.327039 -428.983822) (xy 386.334535 -429.006847) (xy 386.335016 -429.018954)
			(xy 386.335016 -431.560478) (xy 386.334621 -431.572604) (xy 386.327129 -431.59567) (xy 386.312872 -431.61529)
			(xy 386.293249 -431.62954) (xy 386.27018 -431.637024) (xy 386.258054 -431.63744) (xy 385.318254 -431.63744)
			(xy 385.306135 -431.637027) (xy 385.283086 -431.629525) (xy 385.263484 -431.615268) (xy 385.249244 -431.595653)
			(xy 385.241762 -431.572598) (xy 385.241292 -431.560478) (xy 385.241292 -430.948084) (xy 385.239749 -430.933592)
			(xy 385.238096 -430.904492) (xy 385.23799 -430.889918) (xy 384.33502 -430.889918) (xy 384.33502 -431.889916)
			(xy 387.237986 -431.889916) (xy 387.23808 -431.875342) (xy 387.239732 -431.846241) (xy 387.241288 -431.83175)
			(xy 387.241288 -430.747932) (xy 387.23974 -430.73344) (xy 387.23809 -430.70434) (xy 387.237986 -430.689766)
			(xy 387.238084 -430.675192) (xy 387.239734 -430.646091) (xy 387.241288 -430.6316) (xy 387.241288 -430.018952)
			(xy 387.241675 -430.006842) (xy 387.249187 -429.983815) (xy 387.263456 -429.964244) (xy 387.283083 -429.95005)
			(xy 387.306138 -429.942629) (xy 387.31825 -429.942244) (xy 388.25805 -429.942244) (xy 388.270137 -429.94275)
			(xy 388.293137 -429.950193) (xy 388.312718 -429.96437) (xy 388.32697 -429.983896) (xy 388.334503 -430.006866)
			(xy 388.335012 -430.018952) (xy 388.335012 -430.889918) (xy 389.237982 -430.889918) (xy 389.238076 -430.875344)
			(xy 389.239728 -430.846243) (xy 389.241284 -430.831752) (xy 389.241284 -429.747934) (xy 389.239737 -429.733442)
			(xy 389.238086 -429.704342) (xy 389.237982 -429.689768) (xy 389.23808 -429.675194) (xy 389.23973 -429.646093)
			(xy 389.241284 -429.631602) (xy 389.241284 -429.018954) (xy 389.241673 -429.006832) (xy 389.249179 -428.98378)
			(xy 389.26344 -428.964175) (xy 389.283062 -428.949937) (xy 389.306124 -428.942459) (xy 389.318246 -428.941992)
			(xy 390.258046 -428.941992) (xy 390.270158 -428.942472) (xy 390.293195 -428.949966) (xy 390.312792 -428.964208)
			(xy 390.327034 -428.983805) (xy 390.334528 -429.006842) (xy 390.335008 -429.018954) (xy 390.335008 -431.560478)
			(xy 390.33447 -431.572587) (xy 390.326995 -431.595622) (xy 390.312768 -431.61522) (xy 390.293183 -431.629464)
			(xy 390.270154 -431.636959) (xy 390.258046 -431.63744) (xy 389.318246 -431.63744) (xy 389.306123 -431.637001)
			(xy 389.283062 -431.629518) (xy 389.263445 -431.615273) (xy 389.249193 -431.595659) (xy 389.241703 -431.5726)
			(xy 389.241284 -431.560478) (xy 389.241284 -430.948084) (xy 389.239741 -430.933592) (xy 389.238088 -430.904492)
			(xy 389.237982 -430.889918) (xy 388.335012 -430.889918) (xy 388.335012 -431.889916) (xy 391.237978 -431.889916)
			(xy 391.238072 -431.875342) (xy 391.239724 -431.846241) (xy 391.24128 -431.83175) (xy 391.24128 -430.747932)
			(xy 391.239732 -430.73344) (xy 391.238082 -430.70434) (xy 391.237978 -430.689766) (xy 391.238076 -430.675192)
			(xy 391.239726 -430.646091) (xy 391.24128 -430.6316) (xy 391.24128 -430.018952) (xy 391.241675 -430.006843)
			(xy 391.249186 -429.983817) (xy 391.263453 -429.964247) (xy 391.283077 -429.950053) (xy 391.306131 -429.94263)
			(xy 391.318242 -429.942244) (xy 392.258042 -429.942244) (xy 392.270134 -429.942672) (xy 392.293137 -429.95014)
			(xy 392.312716 -429.964337) (xy 392.326965 -429.983879) (xy 392.334496 -430.006861) (xy 392.335004 -430.018952)
			(xy 392.335004 -430.889918) (xy 393.237974 -430.889918) (xy 393.238068 -430.875344) (xy 393.23972 -430.846243)
			(xy 393.241276 -430.831752) (xy 393.241276 -429.747934) (xy 393.239729 -429.733442) (xy 393.238078 -429.704342)
			(xy 393.237974 -429.689768) (xy 393.238072 -429.675194) (xy 393.239722 -429.646093) (xy 393.241276 -429.631602)
			(xy 393.241276 -429.018954) (xy 393.241673 -429.006833) (xy 393.249178 -428.983782) (xy 393.263438 -428.964178)
			(xy 393.283057 -428.949939) (xy 393.306117 -428.94246) (xy 393.318238 -428.941992) (xy 394.258038 -428.941992)
			(xy 394.27015 -428.942479) (xy 394.293187 -428.949971) (xy 394.312784 -428.964211) (xy 394.327026 -428.983806)
			(xy 394.33452 -429.006842) (xy 394.335 -429.018954) (xy 394.335 -431.560478) (xy 394.33447 -431.572588)
			(xy 394.326994 -431.595624) (xy 394.312765 -431.615223) (xy 394.293177 -431.629466) (xy 394.270147 -431.636961)
			(xy 394.258038 -431.63744) (xy 393.318238 -431.63744) (xy 393.306115 -431.637007) (xy 393.283054 -431.629523)
			(xy 393.263436 -431.615275) (xy 393.249184 -431.595661) (xy 393.241695 -431.572601) (xy 393.241276 -431.560478)
			(xy 393.241276 -430.948084) (xy 393.239733 -430.933592) (xy 393.23808 -430.904492) (xy 393.237974 -430.889918)
			(xy 392.335004 -430.889918) (xy 392.335004 -431.889916) (xy 395.23797 -431.889916) (xy 395.238064 -431.875342)
			(xy 395.239716 -431.846241) (xy 395.241272 -431.83175) (xy 395.241272 -430.747932) (xy 395.239724 -430.73344)
			(xy 395.238074 -430.70434) (xy 395.23797 -430.689766) (xy 395.238068 -430.675192) (xy 395.239718 -430.646091)
			(xy 395.241272 -430.6316) (xy 395.241272 -430.018952) (xy 395.241675 -430.006843) (xy 395.249184 -429.983819)
			(xy 395.26345 -429.96425) (xy 395.283072 -429.950056) (xy 395.306124 -429.942631) (xy 395.318234 -429.942244)
			(xy 396.258034 -429.942244) (xy 396.270126 -429.942678) (xy 396.293128 -429.950145) (xy 396.312708 -429.96434)
			(xy 396.326957 -429.98388) (xy 396.334488 -430.006862) (xy 396.334996 -430.018952) (xy 396.334996 -430.889918)
			(xy 398.237964 -430.889918) (xy 398.238073 -430.874832) (xy 398.239855 -430.844714) (xy 398.24152 -430.82972)
			(xy 398.24152 -429.749966) (xy 398.239855 -429.734972) (xy 398.238074 -429.704854) (xy 398.237964 -429.689768)
			(xy 398.238078 -429.674682) (xy 398.239856 -429.644564) (xy 398.24152 -429.62957) (xy 398.24152 -429.018954)
			(xy 398.241968 -429.006864) (xy 398.249435 -428.983865) (xy 398.263627 -428.964288) (xy 398.283163 -428.950038)
			(xy 398.306139 -428.942504) (xy 398.318228 -428.941992) (xy 399.258028 -428.941992) (xy 399.270138 -428.942392)
			(xy 399.293164 -428.949899) (xy 399.312736 -428.964165) (xy 399.32693 -428.983789) (xy 399.334352 -429.006843)
			(xy 399.334736 -429.018954) (xy 399.334736 -431.560478) (xy 399.334273 -431.572569) (xy 399.32682 -431.595573)
			(xy 399.312633 -431.615155) (xy 399.293097 -431.629405) (xy 399.270117 -431.636934) (xy 399.258028 -431.63744)
			(xy 398.318228 -431.63744) (xy 398.306125 -431.63696) (xy 398.283105 -431.629473) (xy 398.263535 -431.615227)
			(xy 398.249338 -431.595621) (xy 398.241909 -431.572582) (xy 398.24152 -431.560478) (xy 398.24152 -430.950116)
			(xy 398.239851 -430.935123) (xy 398.238073 -430.905004) (xy 398.237964 -430.889918) (xy 396.334996 -430.889918)
			(xy 396.334996 -431.889916) (xy 400.23796 -431.889916) (xy 400.238069 -431.87483) (xy 400.239851 -431.844712)
			(xy 400.241516 -431.829718) (xy 400.241516 -430.749964) (xy 400.239851 -430.73497) (xy 400.23807 -430.704852)
			(xy 400.23796 -430.689766) (xy 400.238074 -430.67468) (xy 400.239852 -430.644562) (xy 400.241516 -430.629568)
			(xy 400.241516 -430.018952) (xy 400.241924 -430.006873) (xy 400.249402 -429.9839) (xy 400.263613 -429.964361)
			(xy 400.283164 -429.950169) (xy 400.306144 -429.942712) (xy 400.318224 -429.942244) (xy 401.258024 -429.942244)
			(xy 401.270095 -429.942743) (xy 401.293055 -429.950206) (xy 401.312587 -429.964396) (xy 401.326783 -429.983924)
			(xy 401.334253 -430.006881) (xy 401.334732 -430.018952) (xy 401.334732 -430.889918) (xy 402.237956 -430.889918)
			(xy 402.238065 -430.874832) (xy 402.239847 -430.844714) (xy 402.241512 -430.82972) (xy 402.241512 -429.749966)
			(xy 402.239847 -429.734972) (xy 402.238066 -429.704854) (xy 402.237956 -429.689768) (xy 402.23807 -429.674682)
			(xy 402.239848 -429.644564) (xy 402.241512 -429.62957) (xy 402.241512 -429.018954) (xy 402.241968 -429.006865)
			(xy 402.249434 -428.983867) (xy 402.263624 -428.964291) (xy 402.283158 -428.950041) (xy 402.306132 -428.942505)
			(xy 402.31822 -428.941992) (xy 403.25802 -428.941992) (xy 403.270129 -428.942399) (xy 403.293156 -428.949903)
			(xy 403.312728 -428.964167) (xy 403.326922 -428.98379) (xy 403.334344 -429.006843) (xy 403.334728 -429.018954)
			(xy 403.334728 -431.560478) (xy 403.334273 -431.57257) (xy 403.326819 -431.595575) (xy 403.31263 -431.615158)
			(xy 403.293092 -431.629408) (xy 403.27011 -431.636935) (xy 403.25802 -431.63744) (xy 402.31822 -431.63744)
			(xy 402.306116 -431.636967) (xy 402.283096 -431.629478) (xy 402.263527 -431.61523) (xy 402.24933 -431.595622)
			(xy 402.241901 -431.572583) (xy 402.241512 -431.560478) (xy 402.241512 -430.950116) (xy 402.239843 -430.935123)
			(xy 402.238065 -430.905004) (xy 402.237956 -430.889918) (xy 401.334732 -430.889918) (xy 401.334732 -431.889916)
			(xy 404.237952 -431.889916) (xy 404.238061 -431.87483) (xy 404.239843 -431.844712) (xy 404.241508 -431.829718)
			(xy 404.241508 -430.749964) (xy 404.239843 -430.73497) (xy 404.238062 -430.704852) (xy 404.237952 -430.689766)
			(xy 404.238066 -430.67468) (xy 404.239844 -430.644562) (xy 404.241508 -430.629568) (xy 404.241508 -430.018952)
			(xy 404.241923 -430.006873) (xy 404.249401 -429.983902) (xy 404.26361 -429.964364) (xy 404.283159 -429.950172)
			(xy 404.306137 -429.942713) (xy 404.318216 -429.942244) (xy 405.258016 -429.942244) (xy 405.270087 -429.94275)
			(xy 405.293046 -429.950211) (xy 405.312579 -429.964399) (xy 405.326774 -429.983925) (xy 405.334245 -430.006882)
			(xy 405.334724 -430.018952) (xy 405.334724 -430.889918) (xy 406.237948 -430.889918) (xy 406.238057 -430.874832)
			(xy 406.239839 -430.844714) (xy 406.241504 -430.82972) (xy 406.241504 -429.749966) (xy 406.239839 -429.734972)
			(xy 406.238058 -429.704854) (xy 406.237948 -429.689768) (xy 406.238062 -429.674682) (xy 406.23984 -429.644564)
			(xy 406.241504 -429.62957) (xy 406.241504 -429.018954) (xy 406.241967 -429.006866) (xy 406.249432 -428.98387)
			(xy 406.263621 -428.964293) (xy 406.283153 -428.950043) (xy 406.306125 -428.942506) (xy 406.318212 -428.941992)
			(xy 407.258012 -428.941992) (xy 407.270121 -428.942406) (xy 407.293147 -428.949908) (xy 407.312719 -428.96417)
			(xy 407.326914 -428.983792) (xy 407.334336 -429.006844) (xy 407.33472 -429.018954) (xy 407.33472 -431.560478)
			(xy 407.334273 -431.57257) (xy 407.326818 -431.595577) (xy 407.312627 -431.615161) (xy 407.293087 -431.629411)
			(xy 407.270103 -431.636936) (xy 407.258012 -431.63744) (xy 406.318212 -431.63744) (xy 406.306108 -431.636974)
			(xy 406.283088 -431.629483) (xy 406.263518 -431.615232) (xy 406.249322 -431.595624) (xy 406.241893 -431.572583)
			(xy 406.241504 -431.560478) (xy 406.241504 -430.950116) (xy 406.239835 -430.935123) (xy 406.238057 -430.905004)
			(xy 406.237948 -430.889918) (xy 405.334724 -430.889918) (xy 405.334724 -431.889916) (xy 408.237944 -431.889916)
			(xy 408.238053 -431.87483) (xy 408.239835 -431.844712) (xy 408.2415 -431.829718) (xy 408.2415 -430.749964)
			(xy 408.239835 -430.73497) (xy 408.238054 -430.704852) (xy 408.237944 -430.689766) (xy 408.238058 -430.67468)
			(xy 408.239836 -430.644562) (xy 408.2415 -430.629568) (xy 408.2415 -430.018952) (xy 408.241923 -430.006874)
			(xy 408.2494 -429.983904) (xy 408.263607 -429.964367) (xy 408.283154 -429.950174) (xy 408.30613 -429.942714)
			(xy 408.318208 -429.942244) (xy 409.258008 -429.942244) (xy 409.270078 -429.942757) (xy 409.293037 -429.950216)
			(xy 409.31257 -429.964401) (xy 409.326766 -429.983927) (xy 409.334237 -430.006882) (xy 409.334716 -430.018952)
			(xy 409.334716 -430.889918) (xy 410.23794 -430.889918) (xy 410.238051 -430.874832) (xy 410.239833 -430.844714)
			(xy 410.241496 -430.82972) (xy 410.241496 -429.749966) (xy 410.239831 -429.734972) (xy 410.23805 -429.704854)
			(xy 410.23794 -429.689768) (xy 410.238054 -429.674682) (xy 410.239832 -429.644564) (xy 410.241496 -429.62957)
			(xy 410.241496 -429.018954) (xy 410.241967 -429.006866) (xy 410.249431 -428.983872) (xy 410.263618 -428.964296)
			(xy 410.283148 -428.950046) (xy 410.306118 -428.942507) (xy 410.318204 -428.941992) (xy 411.258004 -428.941992)
			(xy 411.270112 -428.942413) (xy 411.293138 -428.949912) (xy 411.312711 -428.964173) (xy 411.326906 -428.983793)
			(xy 411.334328 -429.006844) (xy 411.334712 -429.018954) (xy 411.334712 -431.560478) (xy 411.334273 -431.572571)
			(xy 411.326816 -431.595579) (xy 411.312624 -431.615164) (xy 411.293082 -431.629413) (xy 411.270096 -431.636937)
			(xy 411.258004 -431.63744) (xy 410.318204 -431.63744) (xy 410.306099 -431.636981) (xy 410.283079 -431.629488)
			(xy 410.263509 -431.615236) (xy 410.249313 -431.595625) (xy 410.241885 -431.572584) (xy 410.241496 -431.560478)
			(xy 410.241496 -430.950116) (xy 410.239827 -430.935123) (xy 410.238049 -430.905004) (xy 410.23794 -430.889918)
			(xy 409.334716 -430.889918) (xy 409.334716 -431.889916) (xy 412.237936 -431.889916) (xy 412.238047 -431.87483)
			(xy 412.239829 -431.844712) (xy 412.241492 -431.829718) (xy 412.241492 -430.749964) (xy 412.239827 -430.73497)
			(xy 412.238046 -430.704852) (xy 412.237936 -430.689766) (xy 412.238052 -430.674681) (xy 412.23983 -430.644562)
			(xy 412.241492 -430.629568) (xy 412.241492 -430.018952) (xy 412.241923 -430.006875) (xy 412.249399 -429.983906)
			(xy 412.263604 -429.96437) (xy 412.283149 -429.950177) (xy 412.306123 -429.942716) (xy 412.3182 -429.942244)
			(xy 413.258 -429.942244) (xy 413.27007 -429.942764) (xy 413.293029 -429.95022) (xy 413.312562 -429.964404)
			(xy 413.326758 -429.983928) (xy 413.334229 -430.006883) (xy 413.334708 -430.018952) (xy 413.334708 -432.560476)
			(xy 413.334267 -432.572557) (xy 413.326806 -432.595539) (xy 413.312607 -432.61509) (xy 413.293061 -432.629295)
			(xy 413.270081 -432.636763) (xy 413.258 -432.637184) (xy 412.3182 -432.637184) (xy 412.306115 -432.636787)
			(xy 412.283128 -432.629317) (xy 412.263576 -432.615107) (xy 412.249372 -432.59555) (xy 412.241909 -432.572561)
			(xy 412.241492 -432.560476) (xy 412.241492 -431.950114) (xy 412.239822 -431.935121) (xy 412.238045 -431.905002)
			(xy 412.237936 -431.889916) (xy 409.334716 -431.889916) (xy 409.334716 -432.560476) (xy 409.334267 -432.572557)
			(xy 409.326807 -432.595537) (xy 409.31261 -432.615087) (xy 409.293066 -432.629292) (xy 409.270088 -432.636762)
			(xy 409.258008 -432.637184) (xy 408.318208 -432.637184) (xy 408.306123 -432.63678) (xy 408.283137 -432.629312)
			(xy 408.263584 -432.615105) (xy 408.249381 -432.595549) (xy 408.241917 -432.572561) (xy 408.2415 -432.560476)
			(xy 408.2415 -431.950114) (xy 408.23983 -431.935121) (xy 408.238053 -431.905002) (xy 408.237944 -431.889916)
			(xy 405.334724 -431.889916) (xy 405.334724 -432.560476) (xy 405.334267 -432.572556) (xy 405.326808 -432.595535)
			(xy 405.312613 -432.615084) (xy 405.293071 -432.62929) (xy 405.270096 -432.636761) (xy 405.258016 -432.637184)
			(xy 404.318216 -432.637184) (xy 404.306132 -432.636773) (xy 404.283146 -432.629307) (xy 404.263593 -432.615101)
			(xy 404.249389 -432.595547) (xy 404.241926 -432.57256) (xy 404.241508 -432.560476) (xy 404.241508 -431.950114)
			(xy 404.239838 -431.935121) (xy 404.238061 -431.905002) (xy 404.237952 -431.889916) (xy 401.334732 -431.889916)
			(xy 401.334732 -432.560476) (xy 401.334216 -432.572547) (xy 401.326763 -432.595509) (xy 401.312579 -432.615045)
			(xy 401.293052 -432.629241) (xy 401.270095 -432.636708) (xy 401.258024 -432.637184) (xy 400.318224 -432.637184)
			(xy 400.30614 -432.636766) (xy 400.283154 -432.629303) (xy 400.263601 -432.615099) (xy 400.249397 -432.595546)
			(xy 400.241934 -432.57256) (xy 400.241516 -432.560476) (xy 400.241516 -431.950114) (xy 400.239846 -431.935121)
			(xy 400.238069 -431.905002) (xy 400.23796 -431.889916) (xy 396.334996 -431.889916) (xy 396.334996 -432.560476)
			(xy 396.334563 -432.572584) (xy 396.32707 -432.595611) (xy 396.312813 -432.615185) (xy 396.293194 -432.62938)
			(xy 396.270143 -432.636801) (xy 396.258034 -432.637184) (xy 395.318234 -432.637184) (xy 395.306149 -432.636664)
			(xy 395.283153 -432.62922) (xy 395.263575 -432.615046) (xy 395.249322 -432.595525) (xy 395.241785 -432.572559)
			(xy 395.241272 -432.560476) (xy 395.241272 -431.948082) (xy 395.239729 -431.93359) (xy 395.238076 -431.90449)
			(xy 395.23797 -431.889916) (xy 392.335004 -431.889916) (xy 392.335004 -432.560476) (xy 392.334563 -432.572583)
			(xy 392.327071 -432.595609) (xy 392.312815 -432.615182) (xy 392.293199 -432.629378) (xy 392.27015 -432.6368)
			(xy 392.258042 -432.637184) (xy 391.318242 -432.637184) (xy 391.306157 -432.636657) (xy 391.283162 -432.629215)
			(xy 391.263583 -432.615043) (xy 391.24933 -432.595523) (xy 391.241793 -432.572559) (xy 391.24128 -432.560476)
			(xy 391.24128 -431.948082) (xy 391.239737 -431.93359) (xy 391.238084 -431.90449) (xy 391.237978 -431.889916)
			(xy 388.335012 -431.889916) (xy 388.335012 -432.560476) (xy 388.334563 -432.572582) (xy 388.327072 -432.595607)
			(xy 388.312818 -432.615179) (xy 388.293204 -432.629375) (xy 388.270158 -432.636799) (xy 388.25805 -432.637184)
			(xy 387.31825 -432.637184) (xy 387.306165 -432.636651) (xy 387.28317 -432.62921) (xy 387.263592 -432.61504)
			(xy 387.249339 -432.595522) (xy 387.241801 -432.572559) (xy 387.241288 -432.560476) (xy 387.241288 -431.948082)
			(xy 387.239745 -431.93359) (xy 387.238092 -431.90449) (xy 387.237986 -431.889916) (xy 384.33502 -431.889916)
			(xy 384.33502 -432.560476) (xy 384.334563 -432.572582) (xy 384.327073 -432.595605) (xy 384.312821 -432.615176)
			(xy 384.293209 -432.629373) (xy 384.270165 -432.636797) (xy 384.258058 -432.637184) (xy 383.318258 -432.637184)
			(xy 383.306169 -432.636729) (xy 383.283171 -432.629264) (xy 383.263593 -432.615073) (xy 383.249343 -432.595539)
			(xy 383.241808 -432.572564) (xy 383.241296 -432.560476) (xy 383.241296 -431.948082) (xy 383.239753 -431.93359)
			(xy 383.2381 -431.90449) (xy 383.237994 -431.889916) (xy 363.355859 -431.889916) (xy 363.346369 -431.956363)
			(xy 363.314178 -432.124516) (xy 363.274074 -432.290959) (xy 363.226145 -432.455319) (xy 363.170501 -432.61723)
			(xy 363.107264 -432.776329) (xy 363.036576 -432.932261) (xy 362.958595 -433.084677) (xy 362.873496 -433.233236)
			(xy 362.781469 -433.377605) (xy 362.68272 -433.517463) (xy 362.577469 -433.652495) (xy 362.465953 -433.782401)
			(xy 362.348419 -433.90689) (xy 362.225132 -434.025683) (xy 362.096367 -434.138515) (xy 361.962411 -434.245133)
			(xy 361.823565 -434.345299) (xy 361.680139 -434.438789) (xy 361.593049 -434.48986) (xy 381.21844 -434.48986)
			(xy 381.218911 -434.457303) (xy 381.226862 -434.392677) (xy 381.242651 -434.329506) (xy 381.266042 -434.268739)
			(xy 381.296685 -434.211287) (xy 381.334119 -434.158009) (xy 381.377784 -434.109707) (xy 381.402082 -434.088032)
			(xy 381.482854 -433.923186) (xy 381.48755 -433.912668) (xy 381.491039 -433.889911) (xy 381.487557 -433.867153)
			(xy 381.482854 -433.856638) (xy 381.402082 -433.691792) (xy 381.377796 -433.670107) (xy 381.334143 -433.621798)
			(xy 381.296718 -433.568519) (xy 381.266081 -433.511068) (xy 381.24269 -433.450305) (xy 381.226896 -433.38714)
			(xy 381.218936 -433.322519) (xy 381.21844 -433.289964) (xy 381.219132 -433.250837) (xy 381.230612 -433.173431)
			(xy 381.2413 -433.135786) (xy 381.2413 -432.618896) (xy 381.241713 -432.606787) (xy 381.249213 -432.583759)
			(xy 381.263476 -432.564186) (xy 381.283098 -432.549992) (xy 381.306152 -432.542571) (xy 381.318262 -432.542188)
			(xy 382.258062 -432.542188) (xy 382.270154 -432.542641) (xy 382.293162 -432.550093) (xy 382.312747 -432.564281)
			(xy 382.326997 -432.583821) (xy 382.334521 -432.606805) (xy 382.335024 -432.618896) (xy 382.335024 -435.16042)
			(xy 382.334601 -435.172528) (xy 382.327099 -435.195551) (xy 382.312838 -435.215122) (xy 382.29322 -435.229317)
			(xy 382.270171 -435.236741) (xy 382.258062 -435.237128) (xy 381.318262 -435.237128) (xy 381.306167 -435.236724)
			(xy 381.28316 -435.229253) (xy 381.263578 -435.215052) (xy 381.24933 -435.195503) (xy 381.241804 -435.172514)
			(xy 381.2413 -435.16042) (xy 381.2413 -434.644038) (xy 381.230604 -434.606395) (xy 381.219133 -434.528987)
			(xy 381.21844 -434.48986) (xy 361.593049 -434.48986) (xy 361.532453 -434.525394) (xy 361.380838 -434.60492)
			(xy 361.225633 -434.67719) (xy 361.146598 -434.710078) (xy 361.132966 -434.716266) (xy 361.109724 -434.735103)
			(xy 361.092944 -434.759873) (xy 361.084069 -434.788444) (xy 361.083862 -434.818361) (xy 361.092341 -434.847052)
			(xy 361.108777 -434.872051) (xy 361.119928 -434.882036) (xy 361.169374 -434.924045) (xy 361.263563 -435.013299)
			(xy 361.352051 -435.108208) (xy 361.434498 -435.208409) (xy 361.510589 -435.313518) (xy 361.580032 -435.423133)
			(xy 361.616728 -435.489858) (xy 383.218436 -435.489858) (xy 383.218907 -435.457301) (xy 383.226858 -435.392675)
			(xy 383.242647 -435.329505) (xy 383.266039 -435.268738) (xy 383.296681 -435.211285) (xy 383.334115 -435.158008)
			(xy 383.37778 -435.109705) (xy 383.402078 -435.08803) (xy 383.48285 -434.923184) (xy 383.487548 -434.912666)
			(xy 383.491036 -434.889909) (xy 383.487553 -434.867151) (xy 383.48285 -434.856636) (xy 383.402078 -434.69179)
			(xy 383.37781 -434.670084) (xy 383.334153 -434.621782) (xy 383.296724 -434.568507) (xy 383.266083 -434.51106)
			(xy 383.242689 -434.450299) (xy 383.226893 -434.387136) (xy 383.218932 -434.322516) (xy 383.218436 -434.289962)
			(xy 383.219128 -434.250835) (xy 383.230608 -434.173429) (xy 383.241296 -434.135784) (xy 383.241296 -433.618894)
			(xy 383.241806 -433.606783) (xy 383.24929 -433.583747) (xy 383.263524 -433.564149) (xy 383.283115 -433.549906)
			(xy 383.306148 -433.542412) (xy 383.318258 -433.541932) (xy 384.258058 -433.541932) (xy 384.270178 -433.542396)
			(xy 384.293234 -433.549876) (xy 384.31285 -433.564116) (xy 384.327103 -433.583722) (xy 384.334597 -433.606774)
			(xy 384.33502 -433.618894) (xy 384.33502 -434.48986) (xy 385.218432 -434.48986) (xy 385.218906 -434.457303)
			(xy 385.226856 -434.392677) (xy 385.242645 -434.329507) (xy 385.266036 -434.26874) (xy 385.296678 -434.211287)
			(xy 385.334112 -434.15801) (xy 385.377776 -434.109707) (xy 385.402074 -434.088032) (xy 385.482846 -433.923186)
			(xy 385.487543 -433.912668) (xy 385.491032 -433.889911) (xy 385.487549 -433.867153) (xy 385.482846 -433.856638)
			(xy 385.402074 -433.691792) (xy 385.377806 -433.670086) (xy 385.334149 -433.621783) (xy 385.29672 -433.568509)
			(xy 385.266079 -433.511062) (xy 385.242685 -433.450301) (xy 385.226889 -433.387138) (xy 385.218928 -433.322518)
			(xy 385.218432 -433.289964) (xy 385.219124 -433.250837) (xy 385.230604 -433.173431) (xy 385.241292 -433.135786)
			(xy 385.241292 -432.618896) (xy 385.241713 -432.606788) (xy 385.249212 -432.583762) (xy 385.263473 -432.564189)
			(xy 385.283093 -432.549994) (xy 385.306144 -432.542572) (xy 385.318254 -432.542188) (xy 386.258054 -432.542188)
			(xy 386.270146 -432.542647) (xy 386.293153 -432.550097) (xy 386.312738 -432.564284) (xy 386.326988 -432.583823)
			(xy 386.334513 -432.606806) (xy 386.335016 -432.618896) (xy 386.335016 -435.16042) (xy 386.334601 -435.172528)
			(xy 386.327098 -435.195554) (xy 386.312836 -435.215125) (xy 386.293215 -435.229319) (xy 386.270164 -435.236743)
			(xy 386.258054 -435.237128) (xy 385.318254 -435.237128) (xy 385.306159 -435.236731) (xy 385.283151 -435.229258)
			(xy 385.263569 -435.215054) (xy 385.249322 -435.195505) (xy 385.241796 -435.172514) (xy 385.241292 -435.16042)
			(xy 385.241292 -434.644038) (xy 385.230596 -434.606395) (xy 385.219125 -434.528987) (xy 385.218432 -434.48986)
			(xy 384.33502 -434.48986) (xy 384.33502 -435.489858) (xy 387.218428 -435.489858) (xy 387.218902 -435.457301)
			(xy 387.226853 -435.392675) (xy 387.242642 -435.329505) (xy 387.266033 -435.268738) (xy 387.296674 -435.211285)
			(xy 387.334108 -435.158008) (xy 387.377772 -435.109705) (xy 387.40207 -435.08803) (xy 387.482842 -434.923184)
			(xy 387.48754 -434.912667) (xy 387.491029 -434.889909) (xy 387.487546 -434.867151) (xy 387.482842 -434.856636)
			(xy 387.40207 -434.69179) (xy 387.377801 -434.670086) (xy 387.334144 -434.621783) (xy 387.296715 -434.568508)
			(xy 387.266074 -434.51106) (xy 387.242681 -434.4503) (xy 387.226885 -434.387136) (xy 387.218924 -434.322516)
			(xy 387.218428 -434.289962) (xy 387.21912 -434.250835) (xy 387.2306 -434.173429) (xy 387.241288 -434.135784)
			(xy 387.241288 -433.618894) (xy 387.241806 -433.606784) (xy 387.249289 -433.583749) (xy 387.263521 -433.564152)
			(xy 387.28311 -433.549909) (xy 387.30614 -433.542413) (xy 387.31825 -433.541932) (xy 388.25805 -433.541932)
			(xy 388.270167 -433.542369) (xy 388.29321 -433.549869) (xy 388.312811 -433.564121) (xy 388.327051 -433.583729)
			(xy 388.334538 -433.606777) (xy 388.335012 -433.618894) (xy 388.335012 -434.48986) (xy 389.218424 -434.48986)
			(xy 389.218901 -434.457303) (xy 389.226851 -434.392677) (xy 389.24264 -434.329507) (xy 389.26603 -434.268741)
			(xy 389.296672 -434.211288) (xy 389.334105 -434.15801) (xy 389.377768 -434.109707) (xy 389.402066 -434.088032)
			(xy 389.482838 -433.923186) (xy 389.487535 -433.912668) (xy 389.491025 -433.889911) (xy 389.487542 -433.867153)
			(xy 389.482838 -433.856638) (xy 389.402066 -433.691792) (xy 389.377797 -433.670088) (xy 389.33414 -433.621785)
			(xy 389.296711 -433.56851) (xy 389.26607 -433.511062) (xy 389.242677 -433.450301) (xy 389.226881 -433.387138)
			(xy 389.21892 -433.322518) (xy 389.218424 -433.289964) (xy 389.219117 -433.250837) (xy 389.230596 -433.173431)
			(xy 389.241284 -433.135786) (xy 389.241284 -432.618896) (xy 389.241713 -432.606789) (xy 389.249211 -432.583764)
			(xy 389.26347 -432.564192) (xy 389.283088 -432.549997) (xy 389.306137 -432.542573) (xy 389.318246 -432.542188)
			(xy 390.258046 -432.542188) (xy 390.270143 -432.542569) (xy 390.293153 -432.550044) (xy 390.312736 -432.564251)
			(xy 390.326984 -432.583805) (xy 390.334506 -432.6068) (xy 390.335008 -432.618896) (xy 390.335008 -435.16042)
			(xy 390.334601 -435.172529) (xy 390.327097 -435.195556) (xy 390.312833 -435.215128) (xy 390.29321 -435.229322)
			(xy 390.270157 -435.236744) (xy 390.258046 -435.237128) (xy 389.318246 -435.237128) (xy 389.306156 -435.236653)
			(xy 389.283151 -435.229205) (xy 389.263568 -435.215022) (xy 389.249317 -435.195487) (xy 389.241789 -435.172509)
			(xy 389.241284 -435.16042) (xy 389.241284 -434.644038) (xy 389.230588 -434.606395) (xy 389.219117 -434.528987)
			(xy 389.218424 -434.48986) (xy 388.335012 -434.48986) (xy 388.335012 -435.489858) (xy 391.21842 -435.489858)
			(xy 391.218897 -435.457301) (xy 391.226847 -435.392675) (xy 391.242636 -435.329506) (xy 391.266026 -435.268739)
			(xy 391.296668 -435.211286) (xy 391.334101 -435.158008) (xy 391.377765 -435.109705) (xy 391.402062 -435.08803)
			(xy 391.482834 -434.923184) (xy 391.487533 -434.912667) (xy 391.491022 -434.889909) (xy 391.487538 -434.867151)
			(xy 391.482834 -434.856636) (xy 391.402062 -434.69179) (xy 391.377791 -434.670088) (xy 391.334135 -434.621784)
			(xy 391.296706 -434.568509) (xy 391.266065 -434.511061) (xy 391.242672 -434.4503) (xy 391.226877 -434.387136)
			(xy 391.218916 -434.322516) (xy 391.21842 -434.289962) (xy 391.219112 -434.250835) (xy 391.230592 -434.173429)
			(xy 391.24128 -434.135784) (xy 391.24128 -433.618894) (xy 391.241656 -433.606767) (xy 391.249155 -433.583701)
			(xy 391.263416 -433.564082) (xy 391.283044 -433.549833) (xy 391.306115 -433.542348) (xy 391.318242 -433.541932)
			(xy 392.258042 -433.541932) (xy 392.270158 -433.542376) (xy 392.293202 -433.549874) (xy 392.312802 -433.564123)
			(xy 392.327043 -433.583731) (xy 392.33453 -433.606778) (xy 392.335004 -433.618894) (xy 392.335004 -434.48986)
			(xy 393.218416 -434.48986) (xy 393.218896 -434.457303) (xy 393.226846 -434.392678) (xy 393.242634 -434.329508)
			(xy 393.266024 -434.268741) (xy 393.296665 -434.211288) (xy 393.334098 -434.158011) (xy 393.377761 -434.109707)
			(xy 393.402058 -434.088032) (xy 393.48283 -433.923186) (xy 393.487528 -433.912668) (xy 393.491017 -433.889911)
			(xy 393.487534 -433.867152) (xy 393.48283 -433.856638) (xy 393.402058 -433.691792) (xy 393.377787 -433.67009)
			(xy 393.334131 -433.621786) (xy 393.296702 -433.568511) (xy 393.266062 -433.511063) (xy 393.242669 -433.450302)
			(xy 393.226873 -433.387138) (xy 393.218912 -433.322518) (xy 393.218416 -433.289964) (xy 393.219105 -433.250837)
			(xy 393.230587 -433.173431) (xy 393.241276 -433.135786) (xy 393.241276 -432.618896) (xy 393.241712 -432.606789)
			(xy 393.24921 -432.583766) (xy 393.263467 -432.564195) (xy 393.283083 -432.55) (xy 393.30613 -432.542575)
			(xy 393.318238 -432.542188) (xy 394.258038 -432.542188) (xy 394.270134 -432.542576) (xy 394.293144 -432.550049)
			(xy 394.312728 -432.564254) (xy 394.326975 -432.583807) (xy 394.334498 -432.606801) (xy 394.335 -432.618896)
			(xy 394.335 -435.16042) (xy 394.334601 -435.17253) (xy 394.327096 -435.195558) (xy 394.31283 -435.215131)
			(xy 394.293205 -435.229325) (xy 394.270149 -435.236745) (xy 394.258038 -435.237128) (xy 393.318238 -435.237128)
			(xy 393.306147 -435.23666) (xy 393.283142 -435.22921) (xy 393.263559 -435.215024) (xy 393.249308 -435.195489)
			(xy 393.241781 -435.172509) (xy 393.241276 -435.16042) (xy 393.241276 -434.644038) (xy 393.230579 -434.606395)
			(xy 393.219108 -434.528987) (xy 393.218416 -434.48986) (xy 392.335004 -434.48986) (xy 392.335004 -435.489858)
			(xy 395.218412 -435.489858) (xy 395.218892 -435.457301) (xy 395.226842 -435.392676) (xy 395.24263 -435.329506)
			(xy 395.26602 -435.268739) (xy 395.296661 -435.211286) (xy 395.334094 -435.158009) (xy 395.377757 -435.109705)
			(xy 395.402054 -435.08803) (xy 395.482826 -434.923184) (xy 395.487525 -434.912667) (xy 395.491015 -434.889909)
			(xy 395.487531 -434.86715) (xy 395.482826 -434.856636) (xy 395.402054 -434.69179) (xy 395.377781 -434.67009)
			(xy 395.334125 -434.621785) (xy 395.296697 -434.56851) (xy 395.266057 -434.511062) (xy 395.242664 -434.4503)
			(xy 395.226869 -434.387137) (xy 395.218908 -434.322516) (xy 395.218412 -434.289962) (xy 395.219101 -434.250835)
			(xy 395.230583 -434.173429) (xy 395.241272 -434.135784) (xy 395.241272 -433.618894) (xy 395.241656 -433.606768)
			(xy 395.249154 -433.583703) (xy 395.263413 -433.564085) (xy 395.283039 -433.549835) (xy 395.306107 -433.542349)
			(xy 395.318234 -433.541932) (xy 396.258034 -433.541932) (xy 396.27015 -433.542383) (xy 396.293193 -433.549878)
			(xy 396.312794 -433.564126) (xy 396.327034 -433.583732) (xy 396.334522 -433.606778) (xy 396.334996 -433.618894)
			(xy 396.334996 -434.48986) (xy 398.218406 -434.48986) (xy 398.218889 -434.457304) (xy 398.226839 -434.392678)
			(xy 398.242627 -434.329508) (xy 398.266017 -434.268742) (xy 398.296657 -434.211289) (xy 398.334089 -434.158011)
			(xy 398.377751 -434.109707) (xy 398.402048 -434.088032) (xy 398.48282 -433.923186) (xy 398.487518 -433.912668)
			(xy 398.491008 -433.889911) (xy 398.487525 -433.867152) (xy 398.48282 -433.856638) (xy 398.402048 -433.691792)
			(xy 398.377775 -433.670092) (xy 398.334119 -433.621788) (xy 398.296691 -433.568512) (xy 398.266051 -433.511063)
			(xy 398.242658 -433.450302) (xy 398.226863 -433.387139) (xy 398.218902 -433.322518) (xy 398.218406 -433.289964)
			(xy 398.219133 -433.250639) (xy 398.230738 -433.172849) (xy 398.24152 -433.135024) (xy 398.24152 -432.618896)
			(xy 398.241909 -432.60681) (xy 398.249382 -432.583823) (xy 398.263593 -432.56427) (xy 398.283151 -432.550067)
			(xy 398.306142 -432.542604) (xy 398.318228 -432.542188) (xy 399.258028 -432.542188) (xy 399.270104 -432.54264)
			(xy 399.293071 -432.55011) (xy 399.312607 -432.56431) (xy 399.326801 -432.58385) (xy 399.334264 -432.60682)
			(xy 399.334736 -432.618896) (xy 399.334736 -435.16042) (xy 399.334253 -435.172493) (xy 399.326788 -435.195456)
			(xy 399.312596 -435.21499) (xy 399.293063 -435.229185) (xy 399.270101 -435.236652) (xy 399.258028 -435.237128)
			(xy 398.318228 -435.237128) (xy 398.306149 -435.236664) (xy 398.28317 -435.229206) (xy 398.263621 -435.215013)
			(xy 398.249416 -435.195473) (xy 398.241944 -435.172499) (xy 398.24152 -435.16042) (xy 398.24152 -434.6448)
			(xy 398.230713 -434.606981) (xy 398.219111 -434.529187) (xy 398.218406 -434.48986) (xy 396.334996 -434.48986)
			(xy 396.334996 -435.489858) (xy 400.218402 -435.489858) (xy 400.218885 -435.457302) (xy 400.226835 -435.392676)
			(xy 400.242623 -435.329507) (xy 400.266013 -435.26874) (xy 400.296653 -435.211287) (xy 400.334085 -435.158009)
			(xy 400.377747 -435.109705) (xy 400.402044 -435.08803) (xy 400.482816 -434.923184) (xy 400.487516 -434.912667)
			(xy 400.491006 -434.889909) (xy 400.487521 -434.86715) (xy 400.482816 -434.856636) (xy 400.402044 -434.69179)
			(xy 400.377769 -434.670092) (xy 400.334114 -434.621787) (xy 400.296686 -434.568511) (xy 400.266046 -434.511062)
			(xy 400.242654 -434.450301) (xy 400.226859 -434.387137) (xy 400.218898 -434.322516) (xy 400.218402 -434.289962)
			(xy 400.219129 -434.250637) (xy 400.230734 -434.172847) (xy 400.241516 -434.135022) (xy 400.241516 -433.618894)
			(xy 400.242002 -433.606807) (xy 400.249457 -433.58381) (xy 400.26364 -433.564232) (xy 400.283168 -433.549981)
			(xy 400.306138 -433.542445) (xy 400.318224 -433.541932) (xy 401.258024 -433.541932) (xy 401.270137 -433.542296)
			(xy 401.293171 -433.549806) (xy 401.312746 -433.56408) (xy 401.326939 -433.583715) (xy 401.334353 -433.606779)
			(xy 401.334732 -433.618894) (xy 401.334732 -434.48986) (xy 402.218398 -434.48986) (xy 402.218884 -434.457304)
			(xy 402.226834 -434.392678) (xy 402.242621 -434.329509) (xy 402.266011 -434.268742) (xy 402.296651 -434.21129)
			(xy 402.334082 -434.158012) (xy 402.377744 -434.109708) (xy 402.40204 -434.088032) (xy 402.482812 -433.923186)
			(xy 402.48751 -433.912668) (xy 402.491001 -433.889911) (xy 402.487517 -433.867152) (xy 402.482812 -433.856638)
			(xy 402.40204 -433.691792) (xy 402.377765 -433.670094) (xy 402.33411 -433.621789) (xy 402.296682 -433.568513)
			(xy 402.266043 -433.511064) (xy 402.24265 -433.450303) (xy 402.226855 -433.387139) (xy 402.218894 -433.322518)
			(xy 402.218398 -433.289964) (xy 402.219125 -433.250639) (xy 402.23073 -433.172849) (xy 402.241512 -433.135024)
			(xy 402.241512 -432.618896) (xy 402.241909 -432.606811) (xy 402.24938 -432.583825) (xy 402.26359 -432.564273)
			(xy 402.283146 -432.550069) (xy 402.306135 -432.542606) (xy 402.31822 -432.542188) (xy 403.25802 -432.542188)
			(xy 403.270095 -432.542647) (xy 403.293062 -432.550115) (xy 403.312599 -432.564313) (xy 403.326793 -432.583852)
			(xy 403.334255 -432.606821) (xy 403.334728 -432.618896) (xy 403.334728 -435.16042) (xy 403.334253 -435.172494)
			(xy 403.326787 -435.195458) (xy 403.312593 -435.214993) (xy 403.293058 -435.229187) (xy 403.270094 -435.236653)
			(xy 403.25802 -435.237128) (xy 402.31822 -435.237128) (xy 402.306148 -435.236619) (xy 402.283185 -435.229165)
			(xy 402.26365 -435.214979) (xy 402.249454 -435.195451) (xy 402.241987 -435.172491) (xy 402.241512 -435.16042)
			(xy 402.241512 -434.6448) (xy 402.230705 -434.606981) (xy 402.219103 -434.529187) (xy 402.218398 -434.48986)
			(xy 401.334732 -434.48986) (xy 401.334732 -435.489858) (xy 404.218394 -435.489858) (xy 404.218845 -435.4573)
			(xy 404.226797 -435.392672) (xy 404.242588 -435.329501) (xy 404.265982 -435.268733) (xy 404.296628 -435.211281)
			(xy 404.334066 -435.158004) (xy 404.377736 -435.109703) (xy 404.402036 -435.08803) (xy 404.482808 -434.923184)
			(xy 404.487508 -434.912667) (xy 404.490998 -434.889909) (xy 404.487513 -434.86715) (xy 404.482808 -434.856636)
			(xy 404.402036 -434.69179) (xy 404.37776 -434.670094) (xy 404.334105 -434.621788) (xy 404.296677 -434.568512)
			(xy 404.266038 -434.511063) (xy 404.242645 -434.450301) (xy 404.226851 -434.387137) (xy 404.21889 -434.322516)
			(xy 404.218394 -434.289962) (xy 404.219121 -434.250637) (xy 404.230726 -434.172847) (xy 404.241508 -434.135022)
			(xy 404.241508 -433.618894) (xy 404.242002 -433.606807) (xy 404.249456 -433.583812) (xy 404.263637 -433.564235)
			(xy 404.283163 -433.549984) (xy 404.306131 -433.542446) (xy 404.318216 -433.541932) (xy 405.258016 -433.541932)
			(xy 405.270129 -433.542303) (xy 405.293162 -433.549811) (xy 405.312738 -433.564083) (xy 405.326931 -433.583716)
			(xy 405.334345 -433.606779) (xy 405.334724 -433.618894) (xy 405.334724 -434.48986) (xy 406.21839 -434.48986)
			(xy 406.218844 -434.457302) (xy 406.226796 -434.392675) (xy 406.242586 -434.329503) (xy 406.26598 -434.268736)
			(xy 406.296625 -434.211283) (xy 406.334063 -434.158007) (xy 406.377732 -434.109705) (xy 406.402032 -434.088032)
			(xy 406.482804 -433.923186) (xy 406.487503 -433.912668) (xy 406.490994 -433.889911) (xy 406.487509 -433.867152)
			(xy 406.482804 -433.856638) (xy 406.402032 -433.691792) (xy 406.377756 -433.670096) (xy 406.334101 -433.62179)
			(xy 406.296673 -433.568514) (xy 406.266034 -433.511065) (xy 406.242642 -433.450303) (xy 406.226847 -433.387139)
			(xy 406.218886 -433.322518) (xy 406.21839 -433.289964) (xy 406.219118 -433.250639) (xy 406.230722 -433.172849)
			(xy 406.241504 -433.135024) (xy 406.241504 -432.618896) (xy 406.241909 -432.606812) (xy 406.249379 -432.583827)
			(xy 406.263587 -432.564276) (xy 406.283141 -432.550072) (xy 406.306128 -432.542607) (xy 406.318212 -432.542188)
			(xy 407.258012 -432.542188) (xy 407.270087 -432.542654) (xy 407.293054 -432.550119) (xy 407.31259 -432.564316)
			(xy 407.326784 -432.583854) (xy 407.334247 -432.606821) (xy 407.33472 -432.618896) (xy 407.33472 -435.16042)
			(xy 407.334253 -435.172494) (xy 407.326786 -435.19546) (xy 407.31259 -435.214996) (xy 407.293053 -435.22919)
			(xy 407.270086 -435.236654) (xy 407.258012 -435.237128) (xy 406.318212 -435.237128) (xy 406.30614 -435.236626)
			(xy 406.283177 -435.229169) (xy 406.263641 -435.214982) (xy 406.249446 -435.195452) (xy 406.241979 -435.172492)
			(xy 406.241504 -435.16042) (xy 406.241504 -434.6448) (xy 406.230697 -434.606981) (xy 406.219095 -434.529187)
			(xy 406.21839 -434.48986) (xy 405.334724 -434.48986) (xy 405.334724 -435.489858) (xy 408.218386 -435.489858)
			(xy 408.21884 -435.4573) (xy 408.226792 -435.392673) (xy 408.242583 -435.329502) (xy 408.265976 -435.268734)
			(xy 408.296622 -435.211281) (xy 408.334059 -435.158005) (xy 408.377728 -435.109703) (xy 408.402028 -435.08803)
			(xy 408.4828 -434.923184) (xy 408.4875 -434.912667) (xy 408.490991 -434.889909) (xy 408.487506 -434.86715)
			(xy 408.4828 -434.856636) (xy 408.402028 -434.69179) (xy 408.37775 -434.670096) (xy 408.334095 -434.62179)
			(xy 408.296668 -434.568513) (xy 408.266029 -434.511063) (xy 408.242637 -434.450301) (xy 408.226842 -434.387137)
			(xy 408.218882 -434.322517) (xy 408.218386 -434.289962) (xy 408.219113 -434.250637) (xy 408.230718 -434.172847)
			(xy 408.2415 -434.135022) (xy 408.2415 -433.618894) (xy 408.242002 -433.606808) (xy 408.249455 -433.583814)
			(xy 408.263634 -433.564238) (xy 408.283158 -433.549986) (xy 408.306124 -433.542447) (xy 408.318208 -433.541932)
			(xy 409.258008 -433.541932) (xy 409.270121 -433.54231) (xy 409.293154 -433.549815) (xy 409.312729 -433.564086)
			(xy 409.326923 -433.583717) (xy 409.334337 -433.60678) (xy 409.334716 -433.618894) (xy 409.334716 -434.48986)
			(xy 410.218382 -434.48986) (xy 410.218839 -434.457303) (xy 410.22679 -434.392675) (xy 410.242581 -434.329504)
			(xy 410.265974 -434.268736) (xy 410.296619 -434.211284) (xy 410.334056 -434.158007) (xy 410.377724 -434.109706)
			(xy 410.402024 -434.088032) (xy 410.482796 -433.923186) (xy 410.487495 -433.912668) (xy 410.490986 -433.889911)
			(xy 410.487502 -433.867152) (xy 410.482796 -433.856638) (xy 410.402024 -433.691792) (xy 410.377746 -433.670097)
			(xy 410.334092 -433.621791) (xy 410.296665 -433.568515) (xy 410.266026 -433.511065) (xy 410.242634 -433.450303)
			(xy 410.226839 -433.387139) (xy 410.218878 -433.322518) (xy 410.218382 -433.289964) (xy 410.21911 -433.250639)
			(xy 410.230714 -433.172849) (xy 410.241496 -433.135024) (xy 410.241496 -432.618896) (xy 410.241961 -432.606821)
			(xy 410.249425 -432.583853) (xy 410.263621 -432.564316) (xy 410.28316 -432.550121) (xy 410.306129 -432.54266)
			(xy 410.318204 -432.542188) (xy 411.258004 -432.542188) (xy 411.270078 -432.542661) (xy 411.293045 -432.550124)
			(xy 411.312582 -432.564318) (xy 411.326776 -432.583855) (xy 411.334239 -432.606822) (xy 411.334712 -432.618896)
			(xy 411.334712 -435.16042) (xy 411.334253 -435.172495) (xy 411.326785 -435.195462) (xy 411.312587 -435.214999)
			(xy 411.293048 -435.229193) (xy 411.270079 -435.236655) (xy 411.258004 -435.237128) (xy 410.318204 -435.237128)
			(xy 410.306132 -435.236633) (xy 410.283168 -435.229174) (xy 410.263633 -435.214984) (xy 410.249437 -435.195454)
			(xy 410.241971 -435.172492) (xy 410.241496 -435.16042) (xy 410.241496 -434.6448) (xy 410.230688 -434.606981)
			(xy 410.219087 -434.529187) (xy 410.218382 -434.48986) (xy 409.334716 -434.48986) (xy 409.334716 -435.489858)
			(xy 412.218378 -435.489858) (xy 412.218835 -435.457301) (xy 412.226786 -435.392673) (xy 412.242577 -435.329502)
			(xy 412.26597 -435.268734) (xy 412.296615 -435.211282) (xy 412.334052 -435.158005) (xy 412.37772 -435.109704)
			(xy 412.40202 -435.08803) (xy 412.482792 -434.923184) (xy 412.487493 -434.912667) (xy 412.490984 -434.889909)
			(xy 412.487498 -434.86715) (xy 412.482792 -434.856636) (xy 412.40202 -434.69179) (xy 412.37774 -434.670097)
			(xy 412.334086 -434.621791) (xy 412.296659 -434.568514) (xy 412.266021 -434.511064) (xy 412.242629 -434.450302)
			(xy 412.226834 -434.387137) (xy 412.218874 -434.322517) (xy 412.218378 -434.289962) (xy 412.219106 -434.250637)
			(xy 412.23071 -434.172847) (xy 412.241492 -434.135022) (xy 412.241492 -433.618894) (xy 412.242002 -433.606809)
			(xy 412.249454 -433.583816) (xy 412.263631 -433.564241) (xy 412.283153 -433.549989) (xy 412.306117 -433.542448)
			(xy 412.3182 -433.541932) (xy 413.258 -433.541932) (xy 413.270112 -433.542317) (xy 413.293145 -433.54982)
			(xy 413.312721 -433.564088) (xy 413.326914 -433.583719) (xy 413.334329 -433.60678) (xy 413.334708 -433.618894)
			(xy 413.334708 -436.160418) (xy 413.334209 -436.172504) (xy 413.326753 -436.195497) (xy 413.312573 -436.215072)
			(xy 413.29305 -436.229324) (xy 413.270084 -436.236864) (xy 413.258 -436.23738) (xy 412.3182 -436.23738)
			(xy 412.306089 -436.236984) (xy 412.283058 -436.229482) (xy 412.263483 -436.215216) (xy 412.24929 -436.195589)
			(xy 412.241872 -436.17253) (xy 412.241492 -436.160418) (xy 412.241492 -435.644798) (xy 412.230684 -435.606979)
			(xy 412.219083 -435.529185) (xy 412.218378 -435.489858) (xy 409.334716 -435.489858) (xy 409.334716 -436.160418)
			(xy 409.334307 -436.172513) (xy 409.32684 -436.195522) (xy 409.31264 -436.215105) (xy 409.293092 -436.229353)
			(xy 409.270102 -436.236877) (xy 409.258008 -436.23738) (xy 408.318208 -436.23738) (xy 408.306098 -436.236977)
			(xy 408.283067 -436.229477) (xy 408.263492 -436.215213) (xy 408.249298 -436.195587) (xy 408.24188 -436.17253)
			(xy 408.2415 -436.160418) (xy 408.2415 -435.644798) (xy 408.230692 -435.606979) (xy 408.219091 -435.529185)
			(xy 408.218386 -435.489858) (xy 405.334724 -435.489858) (xy 405.334724 -436.160418) (xy 405.334307 -436.172512)
			(xy 405.326841 -436.195519) (xy 405.312643 -436.215102) (xy 405.293097 -436.229351) (xy 405.270109 -436.236876)
			(xy 405.258016 -436.23738) (xy 404.318216 -436.23738) (xy 404.306106 -436.23697) (xy 404.283076 -436.229472)
			(xy 404.263501 -436.21521) (xy 404.249306 -436.195585) (xy 404.241889 -436.172529) (xy 404.241508 -436.160418)
			(xy 404.241508 -435.644798) (xy 404.2307 -435.606979) (xy 404.219099 -435.529185) (xy 404.218394 -435.489858)
			(xy 401.334732 -435.489858) (xy 401.334732 -436.160418) (xy 401.334308 -436.172511) (xy 401.326843 -436.195517)
			(xy 401.312646 -436.215099) (xy 401.293102 -436.229348) (xy 401.270116 -436.236875) (xy 401.258024 -436.23738)
			(xy 400.318224 -436.23738) (xy 400.306114 -436.236963) (xy 400.283085 -436.229468) (xy 400.263509 -436.215207)
			(xy 400.249315 -436.195584) (xy 400.241897 -436.172529) (xy 400.241516 -436.160418) (xy 400.241516 -435.644798)
			(xy 400.230708 -435.606979) (xy 400.219107 -435.529185) (xy 400.218402 -435.489858) (xy 396.334996 -435.489858)
			(xy 396.334996 -436.160418) (xy 396.334504 -436.17253) (xy 396.327016 -436.195568) (xy 396.312778 -436.215167)
			(xy 396.293183 -436.229409) (xy 396.270146 -436.236902) (xy 396.258034 -436.23738) (xy 395.318234 -436.23738)
			(xy 395.306115 -436.236911) (xy 395.28306 -436.229431) (xy 395.263446 -436.215191) (xy 395.249193 -436.195587)
			(xy 395.241697 -436.172537) (xy 395.241272 -436.160418) (xy 395.241272 -435.644036) (xy 395.230575 -435.606394)
			(xy 395.219104 -435.528985) (xy 395.218412 -435.489858) (xy 392.335004 -435.489858) (xy 392.335004 -436.160418)
			(xy 392.334504 -436.172529) (xy 392.327017 -436.195566) (xy 392.312781 -436.215164) (xy 392.293188 -436.229406)
			(xy 392.270153 -436.236901) (xy 392.258042 -436.23738) (xy 391.318242 -436.23738) (xy 391.306123 -436.236905)
			(xy 391.283069 -436.229426) (xy 391.263455 -436.215188) (xy 391.249201 -436.195585) (xy 391.241705 -436.172536)
			(xy 391.24128 -436.160418) (xy 391.24128 -435.644036) (xy 391.230583 -435.606394) (xy 391.219112 -435.528985)
			(xy 391.21842 -435.489858) (xy 388.335012 -435.489858) (xy 388.335012 -436.160418) (xy 388.334505 -436.172529)
			(xy 388.327018 -436.195564) (xy 388.312784 -436.215161) (xy 388.293193 -436.229404) (xy 388.27016 -436.2369)
			(xy 388.25805 -436.23738) (xy 387.31825 -436.23738) (xy 387.306135 -436.236931) (xy 387.283093 -436.229432)
			(xy 387.263493 -436.215184) (xy 387.249253 -436.195578) (xy 387.241764 -436.172534) (xy 387.241288 -436.160418)
			(xy 387.241288 -435.644036) (xy 387.230591 -435.606393) (xy 387.21912 -435.528985) (xy 387.218428 -435.489858)
			(xy 384.33502 -435.489858) (xy 384.33502 -436.160418) (xy 384.334654 -436.172546) (xy 384.327152 -436.195612)
			(xy 384.312888 -436.215231) (xy 384.293258 -436.22948) (xy 384.270186 -436.236964) (xy 384.258058 -436.23738)
			(xy 383.318258 -436.23738) (xy 383.306143 -436.236924) (xy 383.283101 -436.229428) (xy 383.263502 -436.215181)
			(xy 383.249261 -436.195577) (xy 383.241772 -436.172533) (xy 383.241296 -436.160418) (xy 383.241296 -435.644036)
			(xy 383.230599 -435.606393) (xy 383.219128 -435.528985) (xy 383.218436 -435.489858) (xy 361.616728 -435.489858)
			(xy 361.642562 -435.536833) (xy 361.697938 -435.654184) (xy 361.74595 -435.774736) (xy 361.786412 -435.898026)
			(xy 361.81917 -436.023584) (xy 361.844098 -436.150927) (xy 361.861101 -436.279569) (xy 361.870114 -436.409016)
			(xy 361.871103 -436.538773) (xy 361.864062 -436.668342) (xy 361.849021 -436.797228) (xy 361.826035 -436.924936)
			(xy 361.795194 -437.050978) (xy 361.756614 -437.174871) (xy 361.710445 -437.29614) (xy 361.656862 -437.41432)
			(xy 361.596072 -437.52896) (xy 361.528306 -437.63962) (xy 361.453825 -437.745876) (xy 361.372914 -437.847321)
			(xy 361.285882 -437.943567) (xy 361.193064 -438.034245) (xy 361.128666 -438.089802) (xy 381.237998 -438.089802)
			(xy 381.238091 -438.075228) (xy 381.239744 -438.046127) (xy 381.2413 -438.031636) (xy 381.2413 -436.948072)
			(xy 381.239755 -436.93358) (xy 381.238103 -436.90448) (xy 381.237998 -436.889906) (xy 381.238091 -436.875332)
			(xy 381.239744 -436.846231) (xy 381.2413 -436.83174) (xy 381.2413 -436.219092) (xy 381.241709 -436.206983)
			(xy 381.249211 -436.183955) (xy 381.263474 -436.164382) (xy 381.283097 -436.150188) (xy 381.306151 -436.142767)
			(xy 381.318262 -436.142384) (xy 382.258062 -436.142384) (xy 382.270154 -436.142841) (xy 382.293161 -436.150292)
			(xy 382.312745 -436.16448) (xy 382.326995 -436.184019) (xy 382.334521 -436.207002) (xy 382.335024 -436.219092)
			(xy 382.335024 -438.760616) (xy 382.334598 -438.772723) (xy 382.327097 -438.795747) (xy 382.312837 -438.815318)
			(xy 382.293219 -438.829513) (xy 382.270171 -438.836937) (xy 382.258062 -438.837324) (xy 381.318262 -438.837324)
			(xy 381.306167 -438.836924) (xy 381.283159 -438.829453) (xy 381.263577 -438.81525) (xy 381.249329 -438.795701)
			(xy 381.241804 -438.77271) (xy 381.2413 -438.760616) (xy 381.2413 -438.147968) (xy 381.239755 -438.133476)
			(xy 381.238103 -438.104376) (xy 381.237998 -438.089802) (xy 361.128666 -438.089802) (xy 361.094814 -438.119007)
			(xy 360.991508 -438.19753) (xy 360.883543 -438.269512) (xy 360.771333 -438.334677) (xy 360.655306 -438.392776)
			(xy 360.535907 -438.443587) (xy 360.413594 -438.486915) (xy 360.288835 -438.522593) (xy 360.162108 -438.550485)
			(xy 360.033898 -438.570485) (xy 359.904696 -438.582516) (xy 359.774998 -438.586531) (xy 359.6453 -438.582516)
			(xy 359.516098 -438.570485) (xy 359.387888 -438.550485) (xy 359.261161 -438.522593) (xy 359.136402 -438.486915)
			(xy 359.014089 -438.443587) (xy 358.89469 -438.392776) (xy 358.778663 -438.334677) (xy 358.666453 -438.269512)
			(xy 358.558488 -438.19753) (xy 358.455182 -438.119007) (xy 358.356932 -438.034245) (xy 358.264114 -437.943567)
			(xy 358.177082 -437.847321) (xy 358.096171 -437.745876) (xy 358.02169 -437.63962) (xy 357.953924 -437.52896)
			(xy 357.893134 -437.41432) (xy 357.839551 -437.29614) (xy 357.793382 -437.174871) (xy 357.754802 -437.050978)
			(xy 357.723961 -436.924936) (xy 357.700975 -436.797228) (xy 357.685934 -436.668342) (xy 357.678893 -436.538773)
			(xy 357.679882 -436.409016) (xy 357.688895 -436.279569) (xy 357.705898 -436.150927) (xy 357.730826 -436.023584)
			(xy 357.763584 -435.898026) (xy 357.804046 -435.774736) (xy 357.852058 -435.654184) (xy 357.907434 -435.536833)
			(xy 357.969964 -435.423133) (xy 358.039407 -435.313518) (xy 358.115498 -435.208409) (xy 358.197945 -435.108208)
			(xy 358.286433 -435.013299) (xy 358.380622 -434.924045) (xy 358.430068 -434.882036) (xy 358.441235 -434.872067)
			(xy 358.457661 -434.847056) (xy 358.466134 -434.818358) (xy 358.465926 -434.788437) (xy 358.457055 -434.759859)
			(xy 358.440283 -434.735079) (xy 358.417049 -434.716224) (xy 358.403398 -434.710078) (xy 358.324356 -434.677212)
			(xy 358.169157 -434.604934) (xy 358.017549 -434.5254) (xy 357.869871 -434.438788) (xy 357.726451 -434.345291)
			(xy 357.587612 -434.24512) (xy 357.453663 -434.138498) (xy 357.324904 -434.025662) (xy 357.201623 -433.906867)
			(xy 357.084096 -433.782376) (xy 356.972584 -433.652469) (xy 356.867339 -433.517435) (xy 356.768594 -433.377578)
			(xy 356.676571 -433.233209) (xy 356.591476 -433.084651) (xy 356.513498 -432.932237) (xy 356.442812 -432.776307)
			(xy 356.379576 -432.61721) (xy 356.323932 -432.455301) (xy 356.276004 -432.290943) (xy 356.235899 -432.124503)
			(xy 356.203706 -431.956354) (xy 356.179498 -431.78687) (xy 356.163329 -431.616432) (xy 356.155235 -431.44542)
			(xy 356.154736 -431.359818) (xy 346.23502 -431.359818) (xy 346.23502 -432.560476) (xy 346.234563 -432.572582)
			(xy 346.227073 -432.595605) (xy 346.212821 -432.615176) (xy 346.193209 -432.629373) (xy 346.170165 -432.636797)
			(xy 346.158058 -432.637184) (xy 345.218258 -432.637184) (xy 345.206169 -432.636729) (xy 345.183171 -432.629264)
			(xy 345.163593 -432.615073) (xy 345.149343 -432.595539) (xy 345.141808 -432.572564) (xy 345.141296 -432.560476)
			(xy 345.141296 -432.044094) (xy 345.130612 -432.006448) (xy 345.119133 -431.929042) (xy 345.118436 -431.889916)
			(xy 342.235028 -431.889916) (xy 342.235028 -432.560476) (xy 342.234563 -432.572581) (xy 342.227074 -432.595602)
			(xy 342.212824 -432.615174) (xy 342.193214 -432.62937) (xy 342.170172 -432.636796) (xy 342.158066 -432.637184)
			(xy 341.218266 -432.637184) (xy 341.206177 -432.636722) (xy 341.183179 -432.629259) (xy 341.163602 -432.61507)
			(xy 341.149352 -432.595538) (xy 341.141816 -432.572563) (xy 341.141304 -432.560476) (xy 341.141304 -432.044094)
			(xy 341.13062 -432.006448) (xy 341.119141 -431.929042) (xy 341.118444 -431.889916) (xy 338.235036 -431.889916)
			(xy 338.235036 -432.560476) (xy 338.234564 -432.57258) (xy 338.227075 -432.5956) (xy 338.212827 -432.615171)
			(xy 338.193219 -432.629367) (xy 338.170179 -432.636795) (xy 338.158074 -432.637184) (xy 337.218274 -432.637184)
			(xy 337.206185 -432.636715) (xy 337.183188 -432.629254) (xy 337.163611 -432.615067) (xy 337.14936 -432.595536)
			(xy 337.141824 -432.572563) (xy 337.141312 -432.560476) (xy 337.141312 -432.044094) (xy 337.130628 -432.006448)
			(xy 337.119149 -431.929042) (xy 337.118452 -431.889916) (xy 334.235044 -431.889916) (xy 334.235044 -432.560476)
			(xy 334.234564 -432.572579) (xy 334.227076 -432.595598) (xy 334.21283 -432.615168) (xy 334.193224 -432.629365)
			(xy 334.170186 -432.636794) (xy 334.158082 -432.637184) (xy 333.218282 -432.637184) (xy 333.206194 -432.636709)
			(xy 333.183197 -432.62925) (xy 333.163619 -432.615065) (xy 333.149368 -432.595535) (xy 333.141832 -432.572563)
			(xy 333.14132 -432.560476) (xy 333.14132 -432.044094) (xy 333.130636 -432.006448) (xy 333.119157 -431.929042)
			(xy 333.11846 -431.889916) (xy 329.2348 -431.889916) (xy 329.2348 -432.560476) (xy 329.234367 -432.572558)
			(xy 329.226905 -432.595542) (xy 329.212704 -432.615093) (xy 329.193156 -432.629297) (xy 329.170174 -432.636764)
			(xy 329.158092 -432.637184) (xy 328.218292 -432.637184) (xy 328.206206 -432.636794) (xy 328.183219 -432.629321)
			(xy 328.163667 -432.61511) (xy 328.149464 -432.595552) (xy 328.142001 -432.572562) (xy 328.141584 -432.560476)
			(xy 328.141584 -432.044856) (xy 328.130788 -432.007034) (xy 328.119179 -431.929242) (xy 328.11847 -431.889916)
			(xy 325.234808 -431.889916) (xy 325.234808 -432.560476) (xy 325.234367 -432.572557) (xy 325.226906 -432.595539)
			(xy 325.212707 -432.61509) (xy 325.193161 -432.629295) (xy 325.170181 -432.636763) (xy 325.1581 -432.637184)
			(xy 324.2183 -432.637184) (xy 324.206215 -432.636787) (xy 324.183228 -432.629317) (xy 324.163676 -432.615107)
			(xy 324.149472 -432.59555) (xy 324.142009 -432.572561) (xy 324.141592 -432.560476) (xy 324.141592 -432.044856)
			(xy 324.130796 -432.007034) (xy 324.119187 -431.929242) (xy 324.118478 -431.889916) (xy 321.234816 -431.889916)
			(xy 321.234816 -432.560476) (xy 321.234367 -432.572557) (xy 321.226907 -432.595537) (xy 321.21271 -432.615087)
			(xy 321.193166 -432.629292) (xy 321.170188 -432.636762) (xy 321.158108 -432.637184) (xy 320.218308 -432.637184)
			(xy 320.206223 -432.63678) (xy 320.183237 -432.629312) (xy 320.163684 -432.615105) (xy 320.149481 -432.595549)
			(xy 320.142017 -432.572561) (xy 320.1416 -432.560476) (xy 320.1416 -432.044856) (xy 320.130804 -432.007034)
			(xy 320.119195 -431.929242) (xy 320.118486 -431.889916) (xy 317.234824 -431.889916) (xy 317.234824 -432.560476)
			(xy 317.234367 -432.572556) (xy 317.226908 -432.595535) (xy 317.212713 -432.615084) (xy 317.193171 -432.62929)
			(xy 317.170196 -432.636761) (xy 317.158116 -432.637184) (xy 316.218316 -432.637184) (xy 316.206232 -432.636773)
			(xy 316.183246 -432.629307) (xy 316.163693 -432.615101) (xy 316.149489 -432.595547) (xy 316.142026 -432.57256)
			(xy 316.141608 -432.560476) (xy 316.141608 -432.044856) (xy 316.130813 -432.007034) (xy 316.119203 -431.929242)
			(xy 316.118494 -431.889916) (xy 274.613204 -431.889916) (xy 274.618425 -431.905986) (xy 274.665585 -432.076867)
			(xy 274.705031 -432.249692) (xy 274.736684 -432.424113) (xy 274.760479 -432.599778) (xy 274.77637 -432.776334)
			(xy 274.784323 -432.953425) (xy 274.78482 -433.04206) (xy 274.784323 -433.130695) (xy 274.77637 -433.307786)
			(xy 274.760479 -433.484342) (xy 274.736684 -433.660007) (xy 274.705031 -433.834428) (xy 274.665585 -434.007253)
			(xy 274.618425 -434.178134) (xy 274.563646 -434.346728) (xy 274.509927 -434.48986) (xy 314.138056 -434.48986)
			(xy 314.138169 -434.474774) (xy 314.139948 -434.444656) (xy 314.141612 -434.429662) (xy 314.141612 -433.350162)
			(xy 314.139947 -433.335168) (xy 314.138166 -433.30505) (xy 314.138056 -433.289964) (xy 314.138169 -433.274878)
			(xy 314.139948 -433.24476) (xy 314.141612 -433.229766) (xy 314.141612 -432.618896) (xy 314.142009 -432.606811)
			(xy 314.14948 -432.583825) (xy 314.16369 -432.564273) (xy 314.183246 -432.550069) (xy 314.206235 -432.542606)
			(xy 314.21832 -432.542188) (xy 315.15812 -432.542188) (xy 315.170195 -432.542647) (xy 315.193162 -432.550115)
			(xy 315.212699 -432.564313) (xy 315.226893 -432.583852) (xy 315.234355 -432.606821) (xy 315.234828 -432.618896)
			(xy 315.234828 -435.16042) (xy 315.234353 -435.172494) (xy 315.226887 -435.195458) (xy 315.212693 -435.214993)
			(xy 315.193158 -435.229187) (xy 315.170194 -435.236653) (xy 315.15812 -435.237128) (xy 314.21832 -435.237128)
			(xy 314.206248 -435.236619) (xy 314.183285 -435.229165) (xy 314.16375 -435.214979) (xy 314.149554 -435.195451)
			(xy 314.142087 -435.172491) (xy 314.141612 -435.16042) (xy 314.141612 -434.550058) (xy 314.139946 -434.535064)
			(xy 314.138166 -434.504946) (xy 314.138056 -434.48986) (xy 274.509927 -434.48986) (xy 274.501358 -434.512693)
			(xy 274.431686 -434.675698) (xy 274.354772 -434.835412) (xy 274.270769 -434.991515) (xy 274.179848 -435.143692)
			(xy 274.082191 -435.291636) (xy 273.977994 -435.43505) (xy 273.934286 -435.489858) (xy 316.138052 -435.489858)
			(xy 316.138165 -435.474772) (xy 316.139944 -435.444654) (xy 316.141608 -435.42966) (xy 316.141608 -434.35016)
			(xy 316.139943 -434.335166) (xy 316.138162 -434.305048) (xy 316.138052 -434.289962) (xy 316.138165 -434.274876)
			(xy 316.139944 -434.244758) (xy 316.141608 -434.229764) (xy 316.141608 -433.618894) (xy 316.142102 -433.606807)
			(xy 316.149556 -433.583812) (xy 316.163737 -433.564235) (xy 316.183263 -433.549984) (xy 316.206231 -433.542446)
			(xy 316.218316 -433.541932) (xy 317.158116 -433.541932) (xy 317.170229 -433.542303) (xy 317.193262 -433.549811)
			(xy 317.212838 -433.564083) (xy 317.227031 -433.583716) (xy 317.234445 -433.606779) (xy 317.234824 -433.618894)
			(xy 317.234824 -434.48986) (xy 318.138048 -434.48986) (xy 318.138161 -434.474774) (xy 318.13994 -434.444656)
			(xy 318.141604 -434.429662) (xy 318.141604 -433.350162) (xy 318.139939 -433.335168) (xy 318.138158 -433.30505)
			(xy 318.138048 -433.289964) (xy 318.138161 -433.274878) (xy 318.13994 -433.24476) (xy 318.141604 -433.229766)
			(xy 318.141604 -432.618896) (xy 318.142009 -432.606812) (xy 318.149479 -432.583827) (xy 318.163687 -432.564276)
			(xy 318.183241 -432.550072) (xy 318.206228 -432.542607) (xy 318.218312 -432.542188) (xy 319.158112 -432.542188)
			(xy 319.170187 -432.542654) (xy 319.193154 -432.550119) (xy 319.21269 -432.564316) (xy 319.226884 -432.583854)
			(xy 319.234347 -432.606821) (xy 319.23482 -432.618896) (xy 319.23482 -435.16042) (xy 319.234353 -435.172494)
			(xy 319.226886 -435.19546) (xy 319.21269 -435.214996) (xy 319.193153 -435.22919) (xy 319.170186 -435.236654)
			(xy 319.158112 -435.237128) (xy 318.218312 -435.237128) (xy 318.20624 -435.236626) (xy 318.183277 -435.229169)
			(xy 318.163741 -435.214982) (xy 318.149546 -435.195452) (xy 318.142079 -435.172492) (xy 318.141604 -435.16042)
			(xy 318.141604 -434.550058) (xy 318.139938 -434.535064) (xy 318.138158 -434.504946) (xy 318.138048 -434.48986)
			(xy 317.234824 -434.48986) (xy 317.234824 -435.489858) (xy 320.138044 -435.489858) (xy 320.138157 -435.474772)
			(xy 320.139936 -435.444654) (xy 320.1416 -435.42966) (xy 320.1416 -434.35016) (xy 320.139934 -434.335166)
			(xy 320.138154 -434.305048) (xy 320.138044 -434.289962) (xy 320.138157 -434.274876) (xy 320.139936 -434.244758)
			(xy 320.1416 -434.229764) (xy 320.1416 -433.618894) (xy 320.142102 -433.606808) (xy 320.149555 -433.583814)
			(xy 320.163734 -433.564238) (xy 320.183258 -433.549986) (xy 320.206224 -433.542447) (xy 320.218308 -433.541932)
			(xy 321.158108 -433.541932) (xy 321.170221 -433.54231) (xy 321.193254 -433.549815) (xy 321.212829 -433.564086)
			(xy 321.227023 -433.583717) (xy 321.234437 -433.60678) (xy 321.234816 -433.618894) (xy 321.234816 -434.48986)
			(xy 322.13804 -434.48986) (xy 322.138153 -434.474774) (xy 322.139932 -434.444656) (xy 322.141596 -434.429662)
			(xy 322.141596 -433.350162) (xy 322.139931 -433.335168) (xy 322.13815 -433.30505) (xy 322.13804 -433.289964)
			(xy 322.138153 -433.274878) (xy 322.139932 -433.24476) (xy 322.141596 -433.229766) (xy 322.141596 -432.618896)
			(xy 322.142061 -432.606821) (xy 322.149525 -432.583853) (xy 322.163721 -432.564316) (xy 322.18326 -432.550121)
			(xy 322.206229 -432.54266) (xy 322.218304 -432.542188) (xy 323.158104 -432.542188) (xy 323.170178 -432.542661)
			(xy 323.193145 -432.550124) (xy 323.212682 -432.564318) (xy 323.226876 -432.583855) (xy 323.234339 -432.606822)
			(xy 323.234812 -432.618896) (xy 323.234812 -435.16042) (xy 323.234353 -435.172495) (xy 323.226885 -435.195462)
			(xy 323.212687 -435.214999) (xy 323.193148 -435.229193) (xy 323.170179 -435.236655) (xy 323.158104 -435.237128)
			(xy 322.218304 -435.237128) (xy 322.206232 -435.236633) (xy 322.183268 -435.229174) (xy 322.163733 -435.214984)
			(xy 322.149537 -435.195454) (xy 322.142071 -435.172492) (xy 322.141596 -435.16042) (xy 322.141596 -434.550058)
			(xy 322.13993 -434.535064) (xy 322.13815 -434.504946) (xy 322.13804 -434.48986) (xy 321.234816 -434.48986)
			(xy 321.234816 -435.489858) (xy 324.138036 -435.489858) (xy 324.138151 -435.474773) (xy 324.13993 -435.444654)
			(xy 324.141592 -435.42966) (xy 324.141592 -434.35016) (xy 324.139926 -434.335166) (xy 324.138146 -434.305048)
			(xy 324.138036 -434.289962) (xy 324.138151 -434.274877) (xy 324.13993 -434.244758) (xy 324.141592 -434.229764)
			(xy 324.141592 -433.618894) (xy 324.142102 -433.606809) (xy 324.149554 -433.583816) (xy 324.163731 -433.564241)
			(xy 324.183253 -433.549989) (xy 324.206217 -433.542448) (xy 324.2183 -433.541932) (xy 325.1581 -433.541932)
			(xy 325.170212 -433.542317) (xy 325.193245 -433.54982) (xy 325.212821 -433.564088) (xy 325.227014 -433.583719)
			(xy 325.234429 -433.60678) (xy 325.234808 -433.618894) (xy 325.234808 -434.48986) (xy 326.138032 -434.48986)
			(xy 326.138147 -434.474775) (xy 326.139926 -434.444656) (xy 326.141588 -434.429662) (xy 326.141588 -433.350162)
			(xy 326.139923 -433.335168) (xy 326.138142 -433.30505) (xy 326.138032 -433.289964) (xy 326.138148 -433.274879)
			(xy 326.139926 -433.24476) (xy 326.141588 -433.229766) (xy 326.141588 -432.618896) (xy 326.142061 -432.606822)
			(xy 326.149524 -432.583855) (xy 326.163718 -432.564318) (xy 326.183255 -432.550124) (xy 326.206222 -432.542661)
			(xy 326.218296 -432.542188) (xy 327.158096 -432.542188) (xy 327.17017 -432.542668) (xy 327.193136 -432.550129)
			(xy 327.212673 -432.564321) (xy 327.226868 -432.583857) (xy 327.234331 -432.606822) (xy 327.234804 -432.618896)
			(xy 327.234804 -435.16042) (xy 327.234353 -435.172496) (xy 327.226884 -435.195464) (xy 327.212684 -435.215001)
			(xy 327.193143 -435.229195) (xy 327.170172 -435.236656) (xy 327.158096 -435.237128) (xy 326.218296 -435.237128)
			(xy 326.206223 -435.236639) (xy 326.183259 -435.229178) (xy 326.163724 -435.214987) (xy 326.149529 -435.195455)
			(xy 326.142063 -435.172493) (xy 326.141588 -435.16042) (xy 326.141588 -434.550058) (xy 326.139922 -434.535064)
			(xy 326.138142 -434.504946) (xy 326.138032 -434.48986) (xy 325.234808 -434.48986) (xy 325.234808 -435.489858)
			(xy 328.138028 -435.489858) (xy 328.138143 -435.474773) (xy 328.139922 -435.444654) (xy 328.141584 -435.42966)
			(xy 328.141584 -434.35016) (xy 328.139918 -434.335166) (xy 328.138138 -434.305048) (xy 328.138028 -434.289962)
			(xy 328.138143 -434.274877) (xy 328.139922 -434.244758) (xy 328.141584 -434.229764) (xy 328.141584 -433.618894)
			(xy 328.142003 -433.6068) (xy 328.149467 -433.583792) (xy 328.163664 -433.564208) (xy 328.183211 -433.549959)
			(xy 328.206199 -433.542435) (xy 328.218292 -433.541932) (xy 329.158092 -433.541932) (xy 329.170204 -433.542323)
			(xy 329.193236 -433.549824) (xy 329.212812 -433.564091) (xy 329.227006 -433.58372) (xy 329.234421 -433.606781)
			(xy 329.2348 -433.618894) (xy 329.2348 -434.48986) (xy 331.138022 -434.48986) (xy 331.13812 -434.475286)
			(xy 331.13977 -434.446185) (xy 331.141324 -434.431694) (xy 331.141324 -433.34813) (xy 331.139776 -433.333638)
			(xy 331.138126 -433.304538) (xy 331.138022 -433.289964) (xy 331.13812 -433.27539) (xy 331.13977 -433.246289)
			(xy 331.141324 -433.231798) (xy 331.141324 -432.618896) (xy 331.141713 -432.606785) (xy 331.149217 -432.583753)
			(xy 331.163484 -432.564178) (xy 331.183113 -432.549984) (xy 331.206173 -432.542568) (xy 331.218286 -432.542188)
			(xy 332.158086 -432.542188) (xy 332.17018 -432.54262) (xy 332.193188 -432.550079) (xy 332.212772 -432.564273)
			(xy 332.227021 -432.583817) (xy 332.234545 -432.606804) (xy 332.235048 -432.618896) (xy 332.235048 -435.16042)
			(xy 332.234601 -435.172525) (xy 332.227102 -435.195545) (xy 332.212847 -435.215113) (xy 332.193235 -435.229309)
			(xy 332.170192 -435.236738) (xy 332.158086 -435.237128) (xy 331.218286 -435.237128) (xy 331.206192 -435.236704)
			(xy 331.183186 -435.22924) (xy 331.163603 -435.215043) (xy 331.149354 -435.195499) (xy 331.141828 -435.172512)
			(xy 331.141324 -435.16042) (xy 331.141324 -434.548026) (xy 331.139776 -434.533534) (xy 331.138126 -434.504434)
			(xy 331.138022 -434.48986) (xy 329.2348 -434.48986) (xy 329.2348 -435.489858) (xy 333.138018 -435.489858)
			(xy 333.138116 -435.475284) (xy 333.139766 -435.446183) (xy 333.14132 -435.431692) (xy 333.14132 -434.348128)
			(xy 333.139772 -434.333636) (xy 333.138122 -434.304536) (xy 333.138018 -434.289962) (xy 333.138116 -434.275388)
			(xy 333.139766 -434.246287) (xy 333.14132 -434.231796) (xy 333.14132 -433.618894) (xy 333.141807 -433.606781)
			(xy 333.149293 -433.583741) (xy 333.163532 -433.564141) (xy 333.18313 -433.549899) (xy 333.206169 -433.542408)
			(xy 333.218282 -433.541932) (xy 334.158082 -433.541932) (xy 334.170203 -433.542375) (xy 334.19326 -433.549862)
			(xy 334.212875 -433.564108) (xy 334.227127 -433.583718) (xy 334.234621 -433.606773) (xy 334.235044 -433.618894)
			(xy 334.235044 -434.48986) (xy 335.138014 -434.48986) (xy 335.138111 -434.475286) (xy 335.139761 -434.446185)
			(xy 335.141316 -434.431694) (xy 335.141316 -433.34813) (xy 335.139768 -433.333638) (xy 335.138118 -433.304538)
			(xy 335.138014 -433.289964) (xy 335.138112 -433.27539) (xy 335.139761 -433.246289) (xy 335.141316 -433.231798)
			(xy 335.141316 -432.618896) (xy 335.141713 -432.606785) (xy 335.149215 -432.583755) (xy 335.163481 -432.564181)
			(xy 335.183108 -432.549987) (xy 335.206166 -432.542569) (xy 335.218278 -432.542188) (xy 336.158078 -432.542188)
			(xy 336.170171 -432.542627) (xy 336.193179 -432.550084) (xy 336.212764 -432.564276) (xy 336.227013 -432.583818)
			(xy 336.234537 -432.606804) (xy 336.23504 -432.618896) (xy 336.23504 -435.16042) (xy 336.234601 -435.172526)
			(xy 336.227101 -435.195547) (xy 336.212844 -435.215116) (xy 336.19323 -435.229312) (xy 336.170185 -435.236739)
			(xy 336.158078 -435.237128) (xy 335.218278 -435.237128) (xy 335.206184 -435.236711) (xy 335.183177 -435.229244)
			(xy 335.163595 -435.215046) (xy 335.149346 -435.1955) (xy 335.14182 -435.172513) (xy 335.141316 -435.16042)
			(xy 335.141316 -434.548026) (xy 335.139768 -434.533534) (xy 335.138118 -434.504434) (xy 335.138014 -434.48986)
			(xy 334.235044 -434.48986) (xy 334.235044 -435.489858) (xy 337.13801 -435.489858) (xy 337.138107 -435.475284)
			(xy 337.139757 -435.446183) (xy 337.141312 -435.431692) (xy 337.141312 -434.348128) (xy 337.139764 -434.333636)
			(xy 337.138114 -434.304536) (xy 337.13801 -434.289962) (xy 337.138108 -434.275388) (xy 337.139757 -434.246287)
			(xy 337.141312 -434.231796) (xy 337.141312 -433.618894) (xy 337.141806 -433.606782) (xy 337.149292 -433.583743)
			(xy 337.163529 -433.564143) (xy 337.183125 -433.549901) (xy 337.206162 -433.54241) (xy 337.218274 -433.541932)
			(xy 338.158074 -433.541932) (xy 338.170195 -433.542382) (xy 338.193252 -433.549866) (xy 338.212867 -433.56411)
			(xy 338.227119 -433.58372) (xy 338.234613 -433.606773) (xy 338.235036 -433.618894) (xy 338.235036 -434.48986)
			(xy 339.138006 -434.48986) (xy 339.138104 -434.475286) (xy 339.139753 -434.446185) (xy 339.141308 -434.431694)
			(xy 339.141308 -433.34813) (xy 339.13976 -433.333638) (xy 339.13811 -433.304538) (xy 339.138006 -433.289964)
			(xy 339.138104 -433.27539) (xy 339.139753 -433.246289) (xy 339.141308 -433.231798) (xy 339.141308 -432.618896)
			(xy 339.141713 -432.606786) (xy 339.149214 -432.583757) (xy 339.163479 -432.564184) (xy 339.183103 -432.549989)
			(xy 339.206159 -432.54257) (xy 339.21827 -432.542188) (xy 340.15807 -432.542188) (xy 340.170163 -432.542634)
			(xy 340.19317 -432.550088) (xy 340.212755 -432.564278) (xy 340.227005 -432.58382) (xy 340.234529 -432.606805)
			(xy 340.235032 -432.618896) (xy 340.235032 -435.16042) (xy 340.234601 -435.172527) (xy 340.2271 -435.195549)
			(xy 340.212841 -435.215119) (xy 340.193225 -435.229314) (xy 340.170178 -435.23674) (xy 340.15807 -435.237128)
			(xy 339.21827 -435.237128) (xy 339.206176 -435.236718) (xy 339.183169 -435.229249) (xy 339.163586 -435.215049)
			(xy 339.149338 -435.195502) (xy 339.141812 -435.172513) (xy 339.141308 -435.16042) (xy 339.141308 -434.548026)
			(xy 339.13976 -434.533534) (xy 339.13811 -434.504434) (xy 339.138006 -434.48986) (xy 338.235036 -434.48986)
			(xy 338.235036 -435.489858) (xy 341.138002 -435.489858) (xy 341.138099 -435.475284) (xy 341.139749 -435.446183)
			(xy 341.141304 -435.431692) (xy 341.141304 -434.348128) (xy 341.139756 -434.333636) (xy 341.138106 -434.304536)
			(xy 341.138002 -434.289962) (xy 341.1381 -434.275388) (xy 341.139749 -434.246287) (xy 341.141304 -434.231796)
			(xy 341.141304 -433.618894) (xy 341.141806 -433.606783) (xy 341.149291 -433.583745) (xy 341.163526 -433.564146)
			(xy 341.18312 -433.549904) (xy 341.206155 -433.542411) (xy 341.218266 -433.541932) (xy 342.158066 -433.541932)
			(xy 342.170186 -433.542389) (xy 342.193243 -433.549871) (xy 342.212858 -433.564113) (xy 342.227111 -433.583721)
			(xy 342.234605 -433.606774) (xy 342.235028 -433.618894) (xy 342.235028 -434.48986) (xy 343.137998 -434.48986)
			(xy 343.138096 -434.475286) (xy 343.139745 -434.446185) (xy 343.1413 -434.431694) (xy 343.1413 -433.34813)
			(xy 343.139752 -433.333638) (xy 343.138102 -433.304538) (xy 343.137998 -433.289964) (xy 343.138096 -433.27539)
			(xy 343.139745 -433.246289) (xy 343.1413 -433.231798) (xy 343.1413 -432.618896) (xy 343.141713 -432.606787)
			(xy 343.149213 -432.583759) (xy 343.163476 -432.564186) (xy 343.183098 -432.549992) (xy 343.206152 -432.542571)
			(xy 343.218262 -432.542188) (xy 344.158062 -432.542188) (xy 344.170154 -432.542641) (xy 344.193162 -432.550093)
			(xy 344.212747 -432.564281) (xy 344.226997 -432.583821) (xy 344.234521 -432.606805) (xy 344.235024 -432.618896)
			(xy 344.235024 -435.16042) (xy 344.234601 -435.172528) (xy 344.227099 -435.195551) (xy 344.212838 -435.215122)
			(xy 344.19322 -435.229317) (xy 344.170171 -435.236741) (xy 344.158062 -435.237128) (xy 343.218262 -435.237128)
			(xy 343.206167 -435.236724) (xy 343.18316 -435.229253) (xy 343.163578 -435.215052) (xy 343.14933 -435.195503)
			(xy 343.141804 -435.172514) (xy 343.1413 -435.16042) (xy 343.1413 -434.548026) (xy 343.139752 -434.533534)
			(xy 343.138102 -434.504434) (xy 343.137998 -434.48986) (xy 342.235028 -434.48986) (xy 342.235028 -435.489858)
			(xy 345.137994 -435.489858) (xy 345.138091 -435.475284) (xy 345.139741 -435.446183) (xy 345.141296 -435.431692)
			(xy 345.141296 -434.348128) (xy 345.139748 -434.333636) (xy 345.138098 -434.304536) (xy 345.137994 -434.289962)
			(xy 345.138092 -434.275388) (xy 345.139741 -434.246287) (xy 345.141296 -434.231796) (xy 345.141296 -433.618894)
			(xy 345.141806 -433.606783) (xy 345.14929 -433.583747) (xy 345.163524 -433.564149) (xy 345.183115 -433.549906)
			(xy 345.206148 -433.542412) (xy 345.218258 -433.541932) (xy 346.158058 -433.541932) (xy 346.170178 -433.542396)
			(xy 346.193234 -433.549876) (xy 346.21285 -433.564116) (xy 346.227103 -433.583722) (xy 346.234597 -433.606774)
			(xy 346.23502 -433.618894) (xy 346.23502 -436.160418) (xy 346.234654 -436.172546) (xy 346.227152 -436.195612)
			(xy 346.212888 -436.215231) (xy 346.193258 -436.22948) (xy 346.170186 -436.236964) (xy 346.158058 -436.23738)
			(xy 345.218258 -436.23738) (xy 345.206143 -436.236924) (xy 345.183101 -436.229428) (xy 345.163502 -436.215181)
			(xy 345.149261 -436.195577) (xy 345.141772 -436.172533) (xy 345.141296 -436.160418) (xy 345.141296 -435.548024)
			(xy 345.139748 -435.533532) (xy 345.138098 -435.504432) (xy 345.137994 -435.489858) (xy 342.235028 -435.489858)
			(xy 342.235028 -436.160418) (xy 342.234655 -436.172545) (xy 342.227153 -436.19561) (xy 342.212891 -436.215228)
			(xy 342.193264 -436.229477) (xy 342.170193 -436.236963) (xy 342.158066 -436.23738) (xy 341.218266 -436.23738)
			(xy 341.206151 -436.236918) (xy 341.18311 -436.229423) (xy 341.16351 -436.215178) (xy 341.149269 -436.195576)
			(xy 341.14178 -436.172533) (xy 341.141304 -436.160418) (xy 341.141304 -435.548024) (xy 341.139755 -435.533532)
			(xy 341.138106 -435.504432) (xy 341.138002 -435.489858) (xy 338.235036 -435.489858) (xy 338.235036 -436.160418)
			(xy 338.234655 -436.172544) (xy 338.227154 -436.195608) (xy 338.212894 -436.215225) (xy 338.193269 -436.229474)
			(xy 338.1702 -436.236962) (xy 338.158074 -436.23738) (xy 337.218274 -436.23738) (xy 337.20616 -436.236911)
			(xy 337.183119 -436.229419) (xy 337.163519 -436.215175) (xy 337.149278 -436.195574) (xy 337.141788 -436.172532)
			(xy 337.141312 -436.160418) (xy 337.141312 -435.548024) (xy 337.139763 -435.533532) (xy 337.138114 -435.504432)
			(xy 337.13801 -435.489858) (xy 334.235044 -435.489858) (xy 334.235044 -436.160418) (xy 334.234604 -436.172535)
			(xy 334.227109 -436.195582) (xy 334.21286 -436.215185) (xy 334.19325 -436.229426) (xy 334.1702 -436.236909)
			(xy 334.158082 -436.23738) (xy 333.218282 -436.23738) (xy 333.206168 -436.236904) (xy 333.183127 -436.229414)
			(xy 333.163528 -436.215172) (xy 333.149286 -436.195573) (xy 333.141796 -436.172532) (xy 333.14132 -436.160418)
			(xy 333.14132 -435.548024) (xy 333.139771 -435.533532) (xy 333.138122 -435.504432) (xy 333.138018 -435.489858)
			(xy 329.2348 -435.489858) (xy 329.2348 -436.160418) (xy 329.234309 -436.172505) (xy 329.226852 -436.195499)
			(xy 329.21267 -436.215075) (xy 329.193145 -436.229327) (xy 329.170177 -436.236865) (xy 329.158092 -436.23738)
			(xy 328.218292 -436.23738) (xy 328.206181 -436.23699) (xy 328.18315 -436.229486) (xy 328.163575 -436.215219)
			(xy 328.149381 -436.19559) (xy 328.141964 -436.172531) (xy 328.141584 -436.160418) (xy 328.141584 -435.550056)
			(xy 328.139918 -435.535062) (xy 328.138138 -435.504944) (xy 328.138028 -435.489858) (xy 325.234808 -435.489858)
			(xy 325.234808 -436.160418) (xy 325.234309 -436.172504) (xy 325.226853 -436.195497) (xy 325.212673 -436.215072)
			(xy 325.19315 -436.229324) (xy 325.170184 -436.236864) (xy 325.1581 -436.23738) (xy 324.2183 -436.23738)
			(xy 324.206189 -436.236984) (xy 324.183158 -436.229482) (xy 324.163583 -436.215216) (xy 324.14939 -436.195589)
			(xy 324.141972 -436.17253) (xy 324.141592 -436.160418) (xy 324.141592 -435.550056) (xy 324.139926 -435.535062)
			(xy 324.138146 -435.504944) (xy 324.138036 -435.489858) (xy 321.234816 -435.489858) (xy 321.234816 -436.160418)
			(xy 321.234407 -436.172513) (xy 321.22694 -436.195522) (xy 321.21274 -436.215105) (xy 321.193192 -436.229353)
			(xy 321.170202 -436.236877) (xy 321.158108 -436.23738) (xy 320.218308 -436.23738) (xy 320.206198 -436.236977)
			(xy 320.183167 -436.229477) (xy 320.163592 -436.215213) (xy 320.149398 -436.195587) (xy 320.14198 -436.17253)
			(xy 320.1416 -436.160418) (xy 320.1416 -435.550056) (xy 320.139934 -435.535062) (xy 320.138154 -435.504944)
			(xy 320.138044 -435.489858) (xy 317.234824 -435.489858) (xy 317.234824 -436.160418) (xy 317.234407 -436.172512)
			(xy 317.226941 -436.195519) (xy 317.212743 -436.215102) (xy 317.193197 -436.229351) (xy 317.170209 -436.236876)
			(xy 317.158116 -436.23738) (xy 316.218316 -436.23738) (xy 316.206206 -436.23697) (xy 316.183176 -436.229472)
			(xy 316.163601 -436.21521) (xy 316.149406 -436.195585) (xy 316.141989 -436.172529) (xy 316.141608 -436.160418)
			(xy 316.141608 -435.550056) (xy 316.139942 -435.535062) (xy 316.138162 -435.504944) (xy 316.138052 -435.489858)
			(xy 273.934286 -435.489858) (xy 273.867468 -435.573645) (xy 273.750836 -435.707142) (xy 273.628331 -435.835271)
			(xy 273.500202 -435.957776) (xy 273.366705 -436.074408) (xy 273.22811 -436.184934) (xy 273.084696 -436.289131)
			(xy 272.936752 -436.386788) (xy 272.784575 -436.477709) (xy 272.628472 -436.561712) (xy 272.468758 -436.638626)
			(xy 272.305753 -436.708298) (xy 272.139788 -436.770586) (xy 271.971194 -436.825365) (xy 271.800313 -436.872525)
			(xy 271.627488 -436.911971) (xy 271.453067 -436.943624) (xy 271.277402 -436.967419) (xy 271.100846 -436.98331)
			(xy 270.923755 -436.991263) (xy 270.746485 -436.991263) (xy 270.569394 -436.98331) (xy 270.392838 -436.967419)
			(xy 270.217173 -436.943624) (xy 270.042752 -436.911971) (xy 269.869927 -436.872525) (xy 269.699046 -436.825365)
			(xy 269.530452 -436.770586) (xy 269.364487 -436.708298) (xy 269.201482 -436.638626) (xy 269.041768 -436.561712)
			(xy 268.885665 -436.477709) (xy 268.733488 -436.386788) (xy 268.585544 -436.289131) (xy 268.44213 -436.184934)
			(xy 268.303535 -436.074408) (xy 268.170038 -435.957776) (xy 268.041909 -435.835271) (xy 267.919404 -435.707142)
			(xy 267.802772 -435.573645) (xy 267.692246 -435.43505) (xy 267.588049 -435.291636) (xy 267.490392 -435.143692)
			(xy 267.399471 -434.991515) (xy 267.315468 -434.835412) (xy 267.238554 -434.675698) (xy 267.168882 -434.512693)
			(xy 267.106594 -434.346728) (xy 267.051815 -434.178134) (xy 267.004655 -434.007253) (xy 266.965209 -433.834428)
			(xy 266.933556 -433.660007) (xy 266.909761 -433.484342) (xy 266.89387 -433.307786) (xy 266.885917 -433.130695)
			(xy 231.01554 -433.130695) (xy 231.01554 -435.063392) (xy 231.015024 -435.08834) (xy 231.007214 -435.137622)
			(xy 230.991802 -435.185079) (xy 230.969165 -435.229545) (xy 230.939859 -435.269929) (xy 230.922576 -435.287928)
			(xy 229.133908 -437.076596) (xy 229.115913 -437.093886) (xy 229.075537 -437.12321) (xy 229.031071 -437.145858)
			(xy 228.98361 -437.161272) (xy 228.934323 -437.169073) (xy 228.909372 -437.16956) (xy 207.503268 -437.16956)
			(xy 207.478319 -437.169063) (xy 207.429037 -437.161248) (xy 207.38158 -437.14583) (xy 207.337114 -437.123189)
			(xy 207.296731 -437.09388) (xy 207.278732 -437.076596) (xy 205.949804 -435.747668) (xy 205.932495 -435.72969)
			(xy 205.903173 -435.68931) (xy 205.880529 -435.64484) (xy 205.865119 -435.597375) (xy 205.857324 -435.548084)
			(xy 205.85684 -435.523132) (xy 204.057751 -435.523132) (xy 204.017468 -435.573645) (xy 203.900836 -435.707142)
			(xy 203.778331 -435.835271) (xy 203.650202 -435.957776) (xy 203.516705 -436.074408) (xy 203.37811 -436.184934)
			(xy 203.234696 -436.289131) (xy 203.086752 -436.386788) (xy 202.934575 -436.477709) (xy 202.778472 -436.561712)
			(xy 202.618758 -436.638626) (xy 202.455753 -436.708298) (xy 202.289788 -436.770586) (xy 202.121194 -436.825365)
			(xy 201.950313 -436.872525) (xy 201.777488 -436.911971) (xy 201.603067 -436.943624) (xy 201.427402 -436.967419)
			(xy 201.250846 -436.98331) (xy 201.073755 -436.991263) (xy 200.896485 -436.991263) (xy 200.719394 -436.98331)
			(xy 200.542838 -436.967419) (xy 200.367173 -436.943624) (xy 200.192752 -436.911971) (xy 200.019927 -436.872525)
			(xy 199.849046 -436.825365) (xy 199.680452 -436.770586) (xy 199.514487 -436.708298) (xy 199.351482 -436.638626)
			(xy 199.191768 -436.561712) (xy 199.035665 -436.477709) (xy 198.883488 -436.386788) (xy 198.735544 -436.289131)
			(xy 198.59213 -436.184934) (xy 198.453535 -436.074408) (xy 198.320038 -435.957776) (xy 198.191909 -435.835271)
			(xy 198.069404 -435.707142) (xy 197.952772 -435.573645) (xy 197.842246 -435.43505) (xy 197.738049 -435.291636)
			(xy 197.640392 -435.143692) (xy 197.549471 -434.991515) (xy 197.465468 -434.835412) (xy 197.388554 -434.675698)
			(xy 197.318882 -434.512693) (xy 197.256594 -434.346728) (xy 197.201815 -434.178134) (xy 197.154655 -434.007253)
			(xy 197.115209 -433.834428) (xy 197.083556 -433.660007) (xy 197.059761 -433.484342) (xy 197.04387 -433.307786)
			(xy 197.035917 -433.130695) (xy 155.334716 -433.130695) (xy 155.334716 -435.16042) (xy 155.334253 -435.172495)
			(xy 155.326786 -435.195461) (xy 155.312589 -435.214997) (xy 155.29305 -435.229191) (xy 155.270083 -435.236655)
			(xy 155.258008 -435.237128) (xy 154.318208 -435.237128) (xy 154.306136 -435.236629) (xy 154.283172 -435.229171)
			(xy 154.263637 -435.214983) (xy 154.249441 -435.195453) (xy 154.241975 -435.172492) (xy 154.2415 -435.16042)
			(xy 154.2415 -434.6448) (xy 154.230692 -434.606981) (xy 154.219091 -434.529187) (xy 154.218386 -434.48986)
			(xy 153.33472 -434.48986) (xy 153.33472 -435.489858) (xy 156.218382 -435.489858) (xy 156.218838 -435.457301)
			(xy 156.226789 -435.392673) (xy 156.24258 -435.329502) (xy 156.265973 -435.268734) (xy 156.296618 -435.211281)
			(xy 156.334056 -435.158005) (xy 156.377724 -435.109704) (xy 156.402024 -435.08803) (xy 156.482796 -434.923184)
			(xy 156.487496 -434.912667) (xy 156.490987 -434.889909) (xy 156.487502 -434.86715) (xy 156.482796 -434.856636)
			(xy 156.402024 -434.69179) (xy 156.377745 -434.670096) (xy 156.334091 -434.62179) (xy 156.296664 -434.568513)
			(xy 156.266025 -434.511064) (xy 156.242633 -434.450302) (xy 156.226838 -434.387137) (xy 156.218878 -434.322517)
			(xy 156.218382 -434.289962) (xy 156.219109 -434.250637) (xy 156.230714 -434.172847) (xy 156.241496 -434.135022)
			(xy 156.241496 -433.618894) (xy 156.242002 -433.606809) (xy 156.249455 -433.583815) (xy 156.263633 -433.564239)
			(xy 156.283155 -433.549987) (xy 156.30612 -433.542448) (xy 156.318204 -433.541932) (xy 157.258004 -433.541932)
			(xy 157.270116 -433.542313) (xy 157.293149 -433.549818) (xy 157.312725 -433.564087) (xy 157.326918 -433.583718)
			(xy 157.334333 -433.60678) (xy 157.334712 -433.618894) (xy 157.334712 -436.160418) (xy 157.334307 -436.172513)
			(xy 157.32684 -436.195523) (xy 157.312639 -436.215106) (xy 157.293089 -436.229355) (xy 157.270098 -436.236878)
			(xy 157.258004 -436.23738) (xy 156.318204 -436.23738) (xy 156.306093 -436.23698) (xy 156.283063 -436.229479)
			(xy 156.263488 -436.215214) (xy 156.249294 -436.195588) (xy 156.241876 -436.17253) (xy 156.241496 -436.160418)
			(xy 156.241496 -435.644798) (xy 156.230688 -435.606979) (xy 156.219087 -435.529185) (xy 156.218382 -435.489858)
			(xy 153.33472 -435.489858) (xy 153.33472 -436.160418) (xy 153.334307 -436.172513) (xy 153.326841 -436.195521)
			(xy 153.312642 -436.215104) (xy 153.293094 -436.229352) (xy 153.270105 -436.236877) (xy 153.258012 -436.23738)
			(xy 152.318212 -436.23738) (xy 152.306102 -436.236973) (xy 152.283072 -436.229474) (xy 152.263497 -436.215211)
			(xy 152.249302 -436.195586) (xy 152.241885 -436.17253) (xy 152.241504 -436.160418) (xy 152.241504 -435.644798)
			(xy 152.230696 -435.606979) (xy 152.219095 -435.529185) (xy 152.21839 -435.489858) (xy 149.334728 -435.489858)
			(xy 149.334728 -436.160418) (xy 149.334308 -436.172512) (xy 149.326842 -436.195518) (xy 149.312645 -436.215101)
			(xy 149.293099 -436.22935) (xy 149.270112 -436.236876) (xy 149.25802 -436.23738) (xy 148.31822 -436.23738)
			(xy 148.30611 -436.236966) (xy 148.28308 -436.22947) (xy 148.263505 -436.215208) (xy 148.249311 -436.195585)
			(xy 148.241893 -436.172529) (xy 148.241512 -436.160418) (xy 148.241512 -435.644798) (xy 148.230704 -435.606979)
			(xy 148.219103 -435.529185) (xy 148.218398 -435.489858) (xy 145.334736 -435.489858) (xy 145.334736 -436.160418)
			(xy 145.334308 -436.172511) (xy 145.326843 -436.195516) (xy 145.312647 -436.215098) (xy 145.293104 -436.229347)
			(xy 145.27012 -436.236874) (xy 145.258028 -436.23738) (xy 144.318228 -436.23738) (xy 144.306119 -436.236959)
			(xy 144.283089 -436.229465) (xy 144.263514 -436.215206) (xy 144.249319 -436.195583) (xy 144.241901 -436.172529)
			(xy 144.24152 -436.160418) (xy 144.24152 -435.644798) (xy 144.230712 -435.606979) (xy 144.219111 -435.529185)
			(xy 144.218406 -435.489858) (xy 140.335 -435.489858) (xy 140.335 -436.160418) (xy 140.334504 -436.17253)
			(xy 140.327017 -436.195567) (xy 140.31278 -436.215165) (xy 140.293185 -436.229408) (xy 140.27015 -436.236901)
			(xy 140.258038 -436.23738) (xy 139.318238 -436.23738) (xy 139.306119 -436.236908) (xy 139.283064 -436.229428)
			(xy 139.26345 -436.21519) (xy 139.249197 -436.195586) (xy 139.241701 -436.172537) (xy 139.241276 -436.160418)
			(xy 139.241276 -435.644036) (xy 139.230579 -435.606394) (xy 139.219108 -435.528985) (xy 139.218416 -435.489858)
			(xy 136.335008 -435.489858) (xy 136.335008 -436.160418) (xy 136.334505 -436.172529) (xy 136.327018 -436.195565)
			(xy 136.312782 -436.215163) (xy 136.29319 -436.229405) (xy 136.270157 -436.2369) (xy 136.258046 -436.23738)
			(xy 135.318246 -436.23738) (xy 135.306127 -436.236901) (xy 135.283073 -436.229424) (xy 135.263459 -436.215187)
			(xy 135.249205 -436.195584) (xy 135.241709 -436.172536) (xy 135.241284 -436.160418) (xy 135.241284 -435.644036)
			(xy 135.230587 -435.606394) (xy 135.219116 -435.528985) (xy 135.218424 -435.489858) (xy 132.335016 -435.489858)
			(xy 132.335016 -436.160418) (xy 132.334654 -436.172546) (xy 132.327152 -436.195613) (xy 132.312886 -436.215232)
			(xy 132.293256 -436.229481) (xy 132.270183 -436.236965) (xy 132.258054 -436.23738) (xy 131.318254 -436.23738)
			(xy 131.306139 -436.236928) (xy 131.283097 -436.22943) (xy 131.263498 -436.215182) (xy 131.249257 -436.195578)
			(xy 131.241768 -436.172533) (xy 131.241292 -436.160418) (xy 131.241292 -435.644036) (xy 131.230595 -435.606393)
			(xy 131.219124 -435.528985) (xy 131.218432 -435.489858) (xy 128.335024 -435.489858) (xy 128.335024 -436.160418)
			(xy 128.334655 -436.172545) (xy 128.327153 -436.195611) (xy 128.312889 -436.215229) (xy 128.293261 -436.229478)
			(xy 128.27019 -436.236963) (xy 128.258062 -436.23738) (xy 127.318262 -436.23738) (xy 127.306147 -436.236921)
			(xy 127.283106 -436.229425) (xy 127.263506 -436.21518) (xy 127.249265 -436.195576) (xy 127.241776 -436.172533)
			(xy 127.2413 -436.160418) (xy 127.2413 -435.644036) (xy 127.230603 -435.606393) (xy 127.219132 -435.528985)
			(xy 127.21844 -435.489858) (xy 113.866512 -435.489858) (xy 113.892486 -435.537087) (xy 113.947862 -435.654438)
			(xy 113.995874 -435.77499) (xy 114.036336 -435.89828) (xy 114.069094 -436.023838) (xy 114.094022 -436.151181)
			(xy 114.111025 -436.279823) (xy 114.120038 -436.40927) (xy 114.121027 -436.539027) (xy 114.113986 -436.668596)
			(xy 114.098945 -436.797482) (xy 114.075959 -436.92519) (xy 114.045118 -437.051232) (xy 114.006538 -437.175125)
			(xy 113.960369 -437.296394) (xy 113.906786 -437.414574) (xy 113.845996 -437.529214) (xy 113.77823 -437.639874)
			(xy 113.703749 -437.74613) (xy 113.622838 -437.847575) (xy 113.535806 -437.943821) (xy 113.442988 -438.034499)
			(xy 113.378885 -438.089802) (xy 125.238002 -438.089802) (xy 125.238095 -438.075228) (xy 125.239748 -438.046127)
			(xy 125.241304 -438.031636) (xy 125.241304 -436.948072) (xy 125.239759 -436.93358) (xy 125.238107 -436.90448)
			(xy 125.238002 -436.889906) (xy 125.238095 -436.875332) (xy 125.239748 -436.846231) (xy 125.241304 -436.83174)
			(xy 125.241304 -436.219092) (xy 125.241709 -436.206982) (xy 125.249212 -436.183954) (xy 125.263476 -436.164381)
			(xy 125.2831 -436.150186) (xy 125.306155 -436.142767) (xy 125.318266 -436.142384) (xy 126.258066 -436.142384)
			(xy 126.270158 -436.142837) (xy 126.293165 -436.15029) (xy 126.312749 -436.164478) (xy 126.327 -436.184018)
			(xy 126.334525 -436.207001) (xy 126.335028 -436.219092) (xy 126.335028 -438.760616) (xy 126.334598 -438.772723)
			(xy 126.327097 -438.795746) (xy 126.312838 -438.815316) (xy 126.293222 -438.829511) (xy 126.270174 -438.836937)
			(xy 126.258066 -438.837324) (xy 125.318266 -438.837324) (xy 125.306171 -438.836921) (xy 125.283163 -438.829451)
			(xy 125.263581 -438.815249) (xy 125.249333 -438.7957) (xy 125.241808 -438.77271) (xy 125.241304 -438.760616)
			(xy 125.241304 -438.147968) (xy 125.239759 -438.133476) (xy 125.238107 -438.104376) (xy 125.238002 -438.089802)
			(xy 113.378885 -438.089802) (xy 113.344738 -438.119261) (xy 113.241432 -438.197784) (xy 113.133467 -438.269766)
			(xy 113.021257 -438.334931) (xy 112.90523 -438.39303) (xy 112.785831 -438.443841) (xy 112.663518 -438.487169)
			(xy 112.538759 -438.522847) (xy 112.412032 -438.550739) (xy 112.283822 -438.570739) (xy 112.15462 -438.58277)
			(xy 112.024922 -438.586785) (xy 111.895224 -438.58277) (xy 111.766022 -438.570739) (xy 111.637812 -438.550739)
			(xy 111.511085 -438.522847) (xy 111.386326 -438.487169) (xy 111.264013 -438.443841) (xy 111.144614 -438.39303)
			(xy 111.028587 -438.334931) (xy 110.916377 -438.269766) (xy 110.808412 -438.197784) (xy 110.705106 -438.119261)
			(xy 110.606856 -438.034499) (xy 110.514038 -437.943821) (xy 110.427006 -437.847575) (xy 110.346095 -437.74613)
			(xy 110.271614 -437.639874) (xy 110.203848 -437.529214) (xy 110.143058 -437.414574) (xy 110.089475 -437.296394)
			(xy 110.043306 -437.175125) (xy 110.004726 -437.051232) (xy 109.973885 -436.92519) (xy 109.950899 -436.797482)
			(xy 109.935858 -436.668596) (xy 109.928817 -436.539027) (xy 109.929806 -436.40927) (xy 109.938819 -436.279823)
			(xy 109.955822 -436.151181) (xy 109.98075 -436.023838) (xy 110.013508 -435.89828) (xy 110.05397 -435.77499)
			(xy 110.101982 -435.654438) (xy 110.157358 -435.537087) (xy 110.219888 -435.423387) (xy 110.289331 -435.313772)
			(xy 110.365422 -435.208663) (xy 110.447869 -435.108462) (xy 110.536357 -435.013553) (xy 110.630546 -434.924299)
			(xy 110.679992 -434.88229) (xy 110.691093 -434.872254) (xy 110.707515 -434.847259) (xy 110.71599 -434.818578)
			(xy 110.71579 -434.788672) (xy 110.706933 -434.760107) (xy 110.690178 -434.735334) (xy 110.666963 -434.71648)
			(xy 110.653322 -434.710332) (xy 110.574304 -434.677407) (xy 110.419107 -434.605131) (xy 110.267499 -434.5256)
			(xy 110.119821 -434.438991) (xy 109.976402 -434.345497) (xy 109.837562 -434.245328) (xy 109.703613 -434.138709)
			(xy 109.574854 -434.025876) (xy 109.451573 -433.907083) (xy 109.334045 -433.782595) (xy 109.222533 -433.65269)
			(xy 109.117287 -433.517659) (xy 109.018541 -433.377804) (xy 108.926517 -433.233438) (xy 108.84142 -433.084883)
			(xy 108.763441 -432.932471) (xy 108.692754 -432.776543) (xy 108.629516 -432.617449) (xy 108.57387 -432.455542)
			(xy 108.52594 -432.291187) (xy 108.485833 -432.124749) (xy 108.453638 -431.956601) (xy 108.429428 -431.78712)
			(xy 108.413257 -431.616683) (xy 108.405161 -431.445673) (xy 108.40466 -431.360072) (xy 90.235024 -431.360072)
			(xy 90.235024 -432.560476) (xy 90.234563 -432.572581) (xy 90.227074 -432.595604) (xy 90.212823 -432.615175)
			(xy 90.193212 -432.629371) (xy 90.170168 -432.636797) (xy 90.158062 -432.637184) (xy 89.218262 -432.637184)
			(xy 89.206173 -432.636726) (xy 89.183175 -432.629261) (xy 89.163598 -432.615072) (xy 89.149348 -432.595538)
			(xy 89.141812 -432.572564) (xy 89.1413 -432.560476) (xy 89.1413 -432.044094) (xy 89.130616 -432.006448)
			(xy 89.119137 -431.929042) (xy 89.11844 -431.889916) (xy 86.235032 -431.889916) (xy 86.235032 -432.560476)
			(xy 86.234563 -432.57258) (xy 86.227075 -432.595601) (xy 86.212825 -432.615172) (xy 86.193217 -432.629369)
			(xy 86.170175 -432.636796) (xy 86.15807 -432.637184) (xy 85.21827 -432.637184) (xy 85.206181 -432.636719)
			(xy 85.183184 -432.629257) (xy 85.163606 -432.615069) (xy 85.149356 -432.595537) (xy 85.14182 -432.572563)
			(xy 85.141308 -432.560476) (xy 85.141308 -432.044094) (xy 85.130624 -432.006448) (xy 85.119145 -431.929042)
			(xy 85.118448 -431.889916) (xy 82.23504 -431.889916) (xy 82.23504 -432.560476) (xy 82.234564 -432.57258)
			(xy 82.227076 -432.595599) (xy 82.212828 -432.615169) (xy 82.193222 -432.629366) (xy 82.170183 -432.636795)
			(xy 82.158078 -432.637184) (xy 81.218278 -432.637184) (xy 81.20619 -432.636712) (xy 81.183192 -432.629252)
			(xy 81.163615 -432.615066) (xy 81.149364 -432.595535) (xy 81.141828 -432.572563) (xy 81.141316 -432.560476)
			(xy 81.141316 -432.044094) (xy 81.130632 -432.006448) (xy 81.119153 -431.929042) (xy 81.118456 -431.889916)
			(xy 78.235048 -431.889916) (xy 78.235048 -432.560476) (xy 78.234564 -432.572579) (xy 78.227077 -432.595597)
			(xy 78.212831 -432.615166) (xy 78.193227 -432.629364) (xy 78.17019 -432.636793) (xy 78.158086 -432.637184)
			(xy 77.218286 -432.637184) (xy 77.206198 -432.636705) (xy 77.183201 -432.629248) (xy 77.163623 -432.615063)
			(xy 77.149372 -432.595534) (xy 77.141836 -432.572562) (xy 77.141324 -432.560476) (xy 77.141324 -432.044094)
			(xy 77.13064 -432.006448) (xy 77.119161 -431.929042) (xy 77.118464 -431.889916) (xy 73.234804 -431.889916)
			(xy 73.234804 -432.560476) (xy 73.234367 -432.572558) (xy 73.226905 -432.59554) (xy 73.212706 -432.615091)
			(xy 73.193158 -432.629296) (xy 73.170178 -432.636764) (xy 73.158096 -432.637184) (xy 72.218296 -432.637184)
			(xy 72.206211 -432.636791) (xy 72.183224 -432.629319) (xy 72.163671 -432.615109) (xy 72.149468 -432.595551)
			(xy 72.142005 -432.572562) (xy 72.141588 -432.560476) (xy 72.141588 -432.044856) (xy 72.130792 -432.007034)
			(xy 72.119183 -431.929242) (xy 72.118474 -431.889916) (xy 69.234812 -431.889916) (xy 69.234812 -432.560476)
			(xy 69.234367 -432.572557) (xy 69.226906 -432.595538) (xy 69.212709 -432.615089) (xy 69.193163 -432.629294)
			(xy 69.170185 -432.636762) (xy 69.158104 -432.637184) (xy 68.218304 -432.637184) (xy 68.206219 -432.636784)
			(xy 68.183232 -432.629314) (xy 68.16368 -432.615106) (xy 68.149476 -432.59555) (xy 68.142013 -432.572561)
			(xy 68.141596 -432.560476) (xy 68.141596 -432.044856) (xy 68.1308 -432.007034) (xy 68.119191 -431.929242)
			(xy 68.118482 -431.889916) (xy 65.23482 -431.889916) (xy 65.23482 -432.560476) (xy 65.234367 -432.572556)
			(xy 65.226907 -432.595536) (xy 65.212711 -432.615086) (xy 65.193168 -432.629291) (xy 65.170192 -432.636761)
			(xy 65.158112 -432.637184) (xy 64.218312 -432.637184) (xy 64.206228 -432.636777) (xy 64.183241 -432.629309)
			(xy 64.163689 -432.615103) (xy 64.149485 -432.595548) (xy 64.142022 -432.572561) (xy 64.141604 -432.560476)
			(xy 64.141604 -432.044856) (xy 64.130808 -432.007034) (xy 64.119199 -431.929242) (xy 64.11849 -431.889916)
			(xy 61.234828 -431.889916) (xy 61.234828 -432.560476) (xy 61.234367 -432.572555) (xy 61.226909 -432.595534)
			(xy 61.212714 -432.615083) (xy 61.193173 -432.629288) (xy 61.170199 -432.63676) (xy 61.15812 -432.637184)
			(xy 60.21832 -432.637184) (xy 60.206236 -432.63677) (xy 60.18325 -432.629305) (xy 60.163697 -432.6151)
			(xy 60.149493 -432.595547) (xy 60.14203 -432.57256) (xy 60.141612 -432.560476) (xy 60.141612 -432.044856)
			(xy 60.130817 -432.007033) (xy 60.119207 -431.929242) (xy 60.118498 -431.889916) (xy 7.00913 -431.889916)
			(xy 7.00913 -434.48986) (xy 58.13806 -434.48986) (xy 58.138173 -434.474774) (xy 58.139952 -434.444656)
			(xy 58.141616 -434.429662) (xy 58.141616 -433.350162) (xy 58.139951 -433.335168) (xy 58.13817 -433.30505)
			(xy 58.13806 -433.289964) (xy 58.138173 -433.274878) (xy 58.139952 -433.24476) (xy 58.141616 -433.229766)
			(xy 58.141616 -432.618896) (xy 58.142009 -432.606811) (xy 58.149481 -432.583824) (xy 58.163691 -432.564271)
			(xy 58.183249 -432.550068) (xy 58.206238 -432.542605) (xy 58.218324 -432.542188) (xy 59.158124 -432.542188)
			(xy 59.170199 -432.542644) (xy 59.193167 -432.550113) (xy 59.212703 -432.564311) (xy 59.226897 -432.583851)
			(xy 59.234359 -432.606821) (xy 59.234832 -432.618896) (xy 59.234832 -435.16042) (xy 59.234353 -435.172493)
			(xy 59.226888 -435.195457) (xy 59.212694 -435.214991) (xy 59.19316 -435.229186) (xy 59.170197 -435.236652)
			(xy 59.158124 -435.237128) (xy 58.218324 -435.237128) (xy 58.206245 -435.236667) (xy 58.183266 -435.229209)
			(xy 58.163717 -435.215014) (xy 58.149512 -435.195473) (xy 58.14204 -435.172499) (xy 58.141616 -435.16042)
			(xy 58.141616 -434.550058) (xy 58.13995 -434.535064) (xy 58.13817 -434.504946) (xy 58.13806 -434.48986)
			(xy 7.00913 -434.48986) (xy 7.00913 -435.489858) (xy 60.138056 -435.489858) (xy 60.138169 -435.474772)
			(xy 60.139948 -435.444654) (xy 60.141612 -435.42966) (xy 60.141612 -434.35016) (xy 60.139947 -434.335166)
			(xy 60.138166 -434.305048) (xy 60.138056 -434.289962) (xy 60.138169 -434.274876) (xy 60.139948 -434.244758)
			(xy 60.141612 -434.229764) (xy 60.141612 -433.618894) (xy 60.142102 -433.606807) (xy 60.149557 -433.583811)
			(xy 60.163739 -433.564234) (xy 60.183265 -433.549982) (xy 60.206235 -433.542445) (xy 60.21832 -433.541932)
			(xy 61.15812 -433.541932) (xy 61.170233 -433.5423) (xy 61.193267 -433.549808) (xy 61.212842 -433.564081)
			(xy 61.227035 -433.583715) (xy 61.234449 -433.606779) (xy 61.234828 -433.618894) (xy 61.234828 -434.48986)
			(xy 62.138052 -434.48986) (xy 62.138165 -434.474774) (xy 62.139944 -434.444656) (xy 62.141608 -434.429662)
			(xy 62.141608 -433.350162) (xy 62.139943 -433.335168) (xy 62.138162 -433.30505) (xy 62.138052 -433.289964)
			(xy 62.138165 -433.274878) (xy 62.139944 -433.24476) (xy 62.141608 -433.229766) (xy 62.141608 -432.618896)
			(xy 62.142009 -432.606811) (xy 62.14948 -432.583826) (xy 62.163688 -432.564274) (xy 62.183244 -432.550071)
			(xy 62.206231 -432.542606) (xy 62.218316 -432.542188) (xy 63.158116 -432.542188) (xy 63.170191 -432.542651)
			(xy 63.193158 -432.550117) (xy 63.212694 -432.564314) (xy 63.226888 -432.583853) (xy 63.234351 -432.606821)
			(xy 63.234824 -432.618896) (xy 63.234824 -435.16042) (xy 63.234353 -435.172494) (xy 63.226887 -435.195459)
			(xy 63.212691 -435.214994) (xy 63.193155 -435.229189) (xy 63.17019 -435.236654) (xy 63.158116 -435.237128)
			(xy 62.218316 -435.237128) (xy 62.206244 -435.236622) (xy 62.183281 -435.229167) (xy 62.163745 -435.21498)
			(xy 62.14955 -435.195451) (xy 62.142083 -435.172492) (xy 62.141608 -435.16042) (xy 62.141608 -434.550058)
			(xy 62.139942 -434.535064) (xy 62.138162 -434.504946) (xy 62.138052 -434.48986) (xy 61.234828 -434.48986)
			(xy 61.234828 -435.489858) (xy 64.138048 -435.489858) (xy 64.138161 -435.474772) (xy 64.13994 -435.444654)
			(xy 64.141604 -435.42966) (xy 64.141604 -434.35016) (xy 64.139938 -434.335166) (xy 64.138158 -434.305048)
			(xy 64.138048 -434.289962) (xy 64.138161 -434.274876) (xy 64.13994 -434.244758) (xy 64.141604 -434.229764)
			(xy 64.141604 -433.618894) (xy 64.142102 -433.606808) (xy 64.149556 -433.583813) (xy 64.163736 -433.564236)
			(xy 64.18326 -433.549985) (xy 64.206228 -433.542447) (xy 64.218312 -433.541932) (xy 65.158112 -433.541932)
			(xy 65.170225 -433.542306) (xy 65.193258 -433.549813) (xy 65.212834 -433.564084) (xy 65.227027 -433.583717)
			(xy 65.234441 -433.60678) (xy 65.23482 -433.618894) (xy 65.23482 -434.48986) (xy 66.138044 -434.48986)
			(xy 66.138157 -434.474774) (xy 66.139936 -434.444656) (xy 66.1416 -434.429662) (xy 66.1416 -433.350162)
			(xy 66.139935 -433.335168) (xy 66.138154 -433.30505) (xy 66.138044 -433.289964) (xy 66.138157 -433.274878)
			(xy 66.139936 -433.24476) (xy 66.1416 -433.229766) (xy 66.1416 -432.618896) (xy 66.142009 -432.606812)
			(xy 66.149479 -432.583828) (xy 66.163686 -432.564277) (xy 66.183239 -432.550073) (xy 66.206224 -432.542607)
			(xy 66.218308 -432.542188) (xy 67.158108 -432.542188) (xy 67.170183 -432.542657) (xy 67.193149 -432.550122)
			(xy 67.212686 -432.564317) (xy 67.22688 -432.583854) (xy 67.234343 -432.606821) (xy 67.234816 -432.618896)
			(xy 67.234816 -435.16042) (xy 67.234353 -435.172495) (xy 67.226886 -435.195461) (xy 67.212689 -435.214997)
			(xy 67.19315 -435.229191) (xy 67.170183 -435.236655) (xy 67.158108 -435.237128) (xy 66.218308 -435.237128)
			(xy 66.206236 -435.236629) (xy 66.183272 -435.229171) (xy 66.163737 -435.214983) (xy 66.149541 -435.195453)
			(xy 66.142075 -435.172492) (xy 66.1416 -435.16042) (xy 66.1416 -434.550058) (xy 66.139934 -434.535064)
			(xy 66.138154 -434.504946) (xy 66.138044 -434.48986) (xy 65.23482 -434.48986) (xy 65.23482 -435.489858)
			(xy 68.13804 -435.489858) (xy 68.138153 -435.474772) (xy 68.139932 -435.444654) (xy 68.141596 -435.42966)
			(xy 68.141596 -434.35016) (xy 68.13993 -434.335166) (xy 68.13815 -434.305048) (xy 68.13804 -434.289962)
			(xy 68.138153 -434.274876) (xy 68.139932 -434.244758) (xy 68.141596 -434.229764) (xy 68.141596 -433.618894)
			(xy 68.142102 -433.606809) (xy 68.149555 -433.583815) (xy 68.163733 -433.564239) (xy 68.183255 -433.549987)
			(xy 68.20622 -433.542448) (xy 68.218304 -433.541932) (xy 69.158104 -433.541932) (xy 69.170216 -433.542313)
			(xy 69.193249 -433.549818) (xy 69.212825 -433.564087) (xy 69.227018 -433.583718) (xy 69.234433 -433.60678)
			(xy 69.234812 -433.618894) (xy 69.234812 -434.48986) (xy 70.138036 -434.48986) (xy 70.138151 -434.474775)
			(xy 70.13993 -434.444656) (xy 70.141592 -434.429662) (xy 70.141592 -433.350162) (xy 70.139927 -433.335168)
			(xy 70.138146 -433.30505) (xy 70.138036 -433.289964) (xy 70.138152 -433.274879) (xy 70.13993 -433.24476)
			(xy 70.141592 -433.229766) (xy 70.141592 -432.618896) (xy 70.142061 -432.606821) (xy 70.149524 -432.583854)
			(xy 70.16372 -432.564317) (xy 70.183258 -432.550123) (xy 70.206225 -432.54266) (xy 70.2183 -432.542188)
			(xy 71.1581 -432.542188) (xy 71.170174 -432.542664) (xy 71.193141 -432.550126) (xy 71.212677 -432.56432)
			(xy 71.226872 -432.583856) (xy 71.234335 -432.606822) (xy 71.234808 -432.618896) (xy 71.234808 -435.16042)
			(xy 71.234353 -435.172496) (xy 71.226885 -435.195463) (xy 71.212686 -435.215) (xy 71.193145 -435.229194)
			(xy 71.170176 -435.236656) (xy 71.1581 -435.237128) (xy 70.2183 -435.237128) (xy 70.206227 -435.236636)
			(xy 70.183264 -435.229176) (xy 70.163728 -435.214986) (xy 70.149533 -435.195454) (xy 70.142067 -435.172492)
			(xy 70.141592 -435.16042) (xy 70.141592 -434.550058) (xy 70.139926 -434.535064) (xy 70.138146 -434.504946)
			(xy 70.138036 -434.48986) (xy 69.234812 -434.48986) (xy 69.234812 -435.489858) (xy 72.138032 -435.489858)
			(xy 72.138147 -435.474773) (xy 72.139926 -435.444654) (xy 72.141588 -435.42966) (xy 72.141588 -434.35016)
			(xy 72.139922 -434.335166) (xy 72.138142 -434.305048) (xy 72.138032 -434.289962) (xy 72.138147 -434.274877)
			(xy 72.139926 -434.244758) (xy 72.141588 -434.229764) (xy 72.141588 -433.618894) (xy 72.142003 -433.606799)
			(xy 72.149468 -433.583791) (xy 72.163666 -433.564207) (xy 72.183213 -433.549958) (xy 72.206203 -433.542435)
			(xy 72.218296 -433.541932) (xy 73.158096 -433.541932) (xy 73.170208 -433.54232) (xy 73.193241 -433.549822)
			(xy 73.212817 -433.56409) (xy 73.22701 -433.58372) (xy 73.234425 -433.606781) (xy 73.234804 -433.618894)
			(xy 73.234804 -434.48986) (xy 75.138026 -434.48986) (xy 75.138124 -434.475286) (xy 75.139774 -434.446185)
			(xy 75.141328 -434.431694) (xy 75.141328 -433.34813) (xy 75.13978 -433.333638) (xy 75.13813 -433.304538)
			(xy 75.138026 -433.289964) (xy 75.138124 -433.27539) (xy 75.139774 -433.246289) (xy 75.141328 -433.231798)
			(xy 75.141328 -432.618896) (xy 75.141713 -432.606784) (xy 75.149217 -432.583752) (xy 75.163486 -432.564176)
			(xy 75.183116 -432.549983) (xy 75.206177 -432.542567) (xy 75.21829 -432.542188) (xy 76.15809 -432.542188)
			(xy 76.170184 -432.542617) (xy 76.193192 -432.550077) (xy 76.212776 -432.564271) (xy 76.227025 -432.583816)
			(xy 76.234549 -432.606804) (xy 76.235052 -432.618896) (xy 76.235052 -435.16042) (xy 76.234601 -435.172525)
			(xy 76.227103 -435.195544) (xy 76.212848 -435.215112) (xy 76.193237 -435.229308) (xy 76.170196 -435.236737)
			(xy 76.15809 -435.237128) (xy 75.21829 -435.237128) (xy 75.206197 -435.2367) (xy 75.183191 -435.229237)
			(xy 75.163608 -435.215041) (xy 75.149359 -435.195498) (xy 75.141833 -435.172512) (xy 75.141328 -435.16042)
			(xy 75.141328 -434.548026) (xy 75.13978 -434.533534) (xy 75.13813 -434.504434) (xy 75.138026 -434.48986)
			(xy 73.234804 -434.48986) (xy 73.234804 -435.489858) (xy 77.138022 -435.489858) (xy 77.13812 -435.475284)
			(xy 77.13977 -435.446183) (xy 77.141324 -435.431692) (xy 77.141324 -434.348128) (xy 77.139776 -434.333636)
			(xy 77.138126 -434.304536) (xy 77.138022 -434.289962) (xy 77.13812 -434.275388) (xy 77.13977 -434.246287)
			(xy 77.141324 -434.231796) (xy 77.141324 -433.618894) (xy 77.141807 -433.606781) (xy 77.149294 -433.58374)
			(xy 77.163534 -433.564139) (xy 77.183132 -433.549897) (xy 77.206173 -433.542408) (xy 77.218286 -433.541932)
			(xy 78.158086 -433.541932) (xy 78.170207 -433.542372) (xy 78.193265 -433.54986) (xy 78.21288 -433.564106)
			(xy 78.227131 -433.583717) (xy 78.234625 -433.606773) (xy 78.235048 -433.618894) (xy 78.235048 -434.48986)
			(xy 79.138018 -434.48986) (xy 79.138116 -434.475286) (xy 79.139766 -434.446185) (xy 79.14132 -434.431694)
			(xy 79.14132 -433.34813) (xy 79.139772 -433.333638) (xy 79.138122 -433.304538) (xy 79.138018 -433.289964)
			(xy 79.138116 -433.27539) (xy 79.139766 -433.246289) (xy 79.14132 -433.231798) (xy 79.14132 -432.618896)
			(xy 79.141713 -432.606785) (xy 79.149216 -432.583754) (xy 79.163483 -432.564179) (xy 79.183111 -432.549985)
			(xy 79.206169 -432.542568) (xy 79.218282 -432.542188) (xy 80.158082 -432.542188) (xy 80.170175 -432.542624)
			(xy 80.193183 -432.550081) (xy 80.212768 -432.564274) (xy 80.227017 -432.583818) (xy 80.234541 -432.606804)
			(xy 80.235044 -432.618896) (xy 80.235044 -435.16042) (xy 80.234601 -435.172526) (xy 80.227102 -435.195546)
			(xy 80.212845 -435.215115) (xy 80.193232 -435.22931) (xy 80.170189 -435.236739) (xy 80.158082 -435.237128)
			(xy 79.218282 -435.237128) (xy 79.206188 -435.236708) (xy 79.183182 -435.229242) (xy 79.163599 -435.215045)
			(xy 79.14935 -435.195499) (xy 79.141824 -435.172512) (xy 79.14132 -435.16042) (xy 79.14132 -434.548026)
			(xy 79.139772 -434.533534) (xy 79.138122 -434.504434) (xy 79.138018 -434.48986) (xy 78.235048 -434.48986)
			(xy 78.235048 -435.489858) (xy 81.138014 -435.489858) (xy 81.138111 -435.475284) (xy 81.139761 -435.446183)
			(xy 81.141316 -435.431692) (xy 81.141316 -434.348128) (xy 81.139768 -434.333636) (xy 81.138118 -434.304536)
			(xy 81.138014 -434.289962) (xy 81.138112 -434.275388) (xy 81.139761 -434.246287) (xy 81.141316 -434.231796)
			(xy 81.141316 -433.618894) (xy 81.141807 -433.606781) (xy 81.149293 -433.583742) (xy 81.163531 -433.564142)
			(xy 81.183127 -433.5499) (xy 81.206165 -433.542409) (xy 81.218278 -433.541932) (xy 82.158078 -433.541932)
			(xy 82.170199 -433.542379) (xy 82.193256 -433.549864) (xy 82.212871 -433.564109) (xy 82.227123 -433.583719)
			(xy 82.234617 -433.606773) (xy 82.23504 -433.618894) (xy 82.23504 -434.48986) (xy 83.13801 -434.48986)
			(xy 83.138107 -434.475286) (xy 83.139757 -434.446185) (xy 83.141312 -434.431694) (xy 83.141312 -433.34813)
			(xy 83.139764 -433.333638) (xy 83.138114 -433.304538) (xy 83.13801 -433.289964) (xy 83.138108 -433.27539)
			(xy 83.139757 -433.246289) (xy 83.141312 -433.231798) (xy 83.141312 -432.618896) (xy 83.141713 -432.606786)
			(xy 83.149215 -432.583756) (xy 83.16348 -432.564182) (xy 83.183106 -432.549988) (xy 83.206162 -432.542569)
			(xy 83.218274 -432.542188) (xy 84.158074 -432.542188) (xy 84.170167 -432.54263) (xy 84.193175 -432.550086)
			(xy 84.212759 -432.564277) (xy 84.227009 -432.583819) (xy 84.234533 -432.606804) (xy 84.235036 -432.618896)
			(xy 84.235036 -435.16042) (xy 84.234601 -435.172526) (xy 84.227101 -435.195548) (xy 84.212843 -435.215118)
			(xy 84.193227 -435.229313) (xy 84.170182 -435.23674) (xy 84.158074 -435.237128) (xy 83.218274 -435.237128)
			(xy 83.20618 -435.236714) (xy 83.183173 -435.229247) (xy 83.163591 -435.215047) (xy 83.149342 -435.195501)
			(xy 83.141816 -435.172513) (xy 83.141312 -435.16042) (xy 83.141312 -434.548026) (xy 83.139764 -434.533534)
			(xy 83.138114 -434.504434) (xy 83.13801 -434.48986) (xy 82.23504 -434.48986) (xy 82.23504 -435.489858)
			(xy 85.138006 -435.489858) (xy 85.138103 -435.475284) (xy 85.139753 -435.446183) (xy 85.141308 -435.431692)
			(xy 85.141308 -434.348128) (xy 85.13976 -434.333636) (xy 85.13811 -434.304536) (xy 85.138006 -434.289962)
			(xy 85.138104 -434.275388) (xy 85.139753 -434.246287) (xy 85.141308 -434.231796) (xy 85.141308 -433.618894)
			(xy 85.141806 -433.606782) (xy 85.149292 -433.583744) (xy 85.163528 -433.564145) (xy 85.183122 -433.549903)
			(xy 85.206158 -433.54241) (xy 85.21827 -433.541932) (xy 86.15807 -433.541932) (xy 86.170191 -433.542385)
			(xy 86.193247 -433.549869) (xy 86.212863 -433.564112) (xy 86.227115 -433.58372) (xy 86.234609 -433.606774)
			(xy 86.235032 -433.618894) (xy 86.235032 -434.48986) (xy 87.138002 -434.48986) (xy 87.1381 -434.475286)
			(xy 87.139749 -434.446185) (xy 87.141304 -434.431694) (xy 87.141304 -433.34813) (xy 87.139756 -433.333638)
			(xy 87.138106 -433.304538) (xy 87.138002 -433.289964) (xy 87.1381 -433.27539) (xy 87.139749 -433.246289)
			(xy 87.141304 -433.231798) (xy 87.141304 -432.618896) (xy 87.141713 -432.606787) (xy 87.149214 -432.583758)
			(xy 87.163477 -432.564185) (xy 87.183101 -432.549991) (xy 87.206155 -432.542571) (xy 87.218266 -432.542188)
			(xy 88.158066 -432.542188) (xy 88.170159 -432.542637) (xy 88.193166 -432.55009) (xy 88.212751 -432.56428)
			(xy 88.227001 -432.583821) (xy 88.234525 -432.606805) (xy 88.235028 -432.618896) (xy 88.235028 -435.16042)
			(xy 88.234601 -435.172527) (xy 88.2271 -435.19555) (xy 88.21284 -435.215121) (xy 88.193222 -435.229316)
			(xy 88.170174 -435.236741) (xy 88.158066 -435.237128) (xy 87.218266 -435.237128) (xy 87.206171 -435.236721)
			(xy 87.183164 -435.229251) (xy 87.163582 -435.21505) (xy 87.149334 -435.195502) (xy 87.141808 -435.172513)
			(xy 87.141304 -435.16042) (xy 87.141304 -434.548026) (xy 87.139756 -434.533534) (xy 87.138106 -434.504434)
			(xy 87.138002 -434.48986) (xy 86.235032 -434.48986) (xy 86.235032 -435.489858) (xy 89.137998 -435.489858)
			(xy 89.138095 -435.475284) (xy 89.139745 -435.446183) (xy 89.1413 -435.431692) (xy 89.1413 -434.348128)
			(xy 89.139752 -434.333636) (xy 89.138102 -434.304536) (xy 89.137998 -434.289962) (xy 89.138096 -434.275388)
			(xy 89.139745 -434.246287) (xy 89.1413 -434.231796) (xy 89.1413 -433.618894) (xy 89.141806 -433.606783)
			(xy 89.14929 -433.583746) (xy 89.163525 -433.564148) (xy 89.183117 -433.549905) (xy 89.206151 -433.542411)
			(xy 89.218262 -433.541932) (xy 90.158062 -433.541932) (xy 90.170182 -433.542392) (xy 90.193239 -433.549873)
			(xy 90.212854 -433.564115) (xy 90.227107 -433.583722) (xy 90.234601 -433.606774) (xy 90.235024 -433.618894)
			(xy 90.235024 -436.160418) (xy 90.234655 -436.172545) (xy 90.227153 -436.195611) (xy 90.212889 -436.215229)
			(xy 90.193261 -436.229478) (xy 90.17019 -436.236963) (xy 90.158062 -436.23738) (xy 89.218262 -436.23738)
			(xy 89.206147 -436.236921) (xy 89.183106 -436.229425) (xy 89.163506 -436.21518) (xy 89.149265 -436.195576)
			(xy 89.141776 -436.172533) (xy 89.1413 -436.160418) (xy 89.1413 -435.548024) (xy 89.139751 -435.533532)
			(xy 89.138102 -435.504432) (xy 89.137998 -435.489858) (xy 86.235032 -435.489858) (xy 86.235032 -436.160418)
			(xy 86.234655 -436.172545) (xy 86.227154 -436.195609) (xy 86.212892 -436.215226) (xy 86.193266 -436.229476)
			(xy 86.170197 -436.236962) (xy 86.15807 -436.23738) (xy 85.21827 -436.23738) (xy 85.206156 -436.236914)
			(xy 85.183114 -436.229421) (xy 85.163515 -436.215177) (xy 85.149274 -436.195575) (xy 85.141784 -436.172532)
			(xy 85.141308 -436.160418) (xy 85.141308 -435.548024) (xy 85.139759 -435.533532) (xy 85.13811 -435.504432)
			(xy 85.138006 -435.489858) (xy 82.23504 -435.489858) (xy 82.23504 -436.160418) (xy 82.234655 -436.172544)
			(xy 82.227155 -436.195607) (xy 82.212895 -436.215224) (xy 82.193271 -436.229473) (xy 82.170204 -436.236961)
			(xy 82.158078 -436.23738) (xy 81.218278 -436.23738) (xy 81.206164 -436.236907) (xy 81.183123 -436.229416)
			(xy 81.163523 -436.215174) (xy 81.149282 -436.195573) (xy 81.141792 -436.172532) (xy 81.141316 -436.160418)
			(xy 81.141316 -435.548024) (xy 81.139767 -435.533532) (xy 81.138118 -435.504432) (xy 81.138014 -435.489858)
			(xy 78.235048 -435.489858) (xy 78.235048 -436.160418) (xy 78.234604 -436.172535) (xy 78.22711 -436.195581)
			(xy 78.212861 -436.215184) (xy 78.193252 -436.229424) (xy 78.170203 -436.236909) (xy 78.158086 -436.23738)
			(xy 77.218286 -436.23738) (xy 77.206172 -436.236901) (xy 77.183132 -436.229412) (xy 77.163532 -436.215171)
			(xy 77.14929 -436.195572) (xy 77.1418 -436.172531) (xy 77.141324 -436.160418) (xy 77.141324 -435.548024)
			(xy 77.139775 -435.533532) (xy 77.138126 -435.504432) (xy 77.138022 -435.489858) (xy 73.234804 -435.489858)
			(xy 73.234804 -436.160418) (xy 73.234309 -436.172504) (xy 73.226853 -436.195498) (xy 73.212672 -436.215074)
			(xy 73.193147 -436.229325) (xy 73.17018 -436.236865) (xy 73.158096 -436.23738) (xy 72.218296 -436.23738)
			(xy 72.206185 -436.236987) (xy 72.183154 -436.229484) (xy 72.163579 -436.215217) (xy 72.149385 -436.195589)
			(xy 72.141968 -436.172531) (xy 72.141588 -436.160418) (xy 72.141588 -435.550056) (xy 72.139922 -435.535062)
			(xy 72.138142 -435.504944) (xy 72.138032 -435.489858) (xy 69.234812 -435.489858) (xy 69.234812 -436.160418)
			(xy 69.234407 -436.172513) (xy 69.22694 -436.195523) (xy 69.212739 -436.215106) (xy 69.193189 -436.229355)
			(xy 69.170198 -436.236878) (xy 69.158104 -436.23738) (xy 68.218304 -436.23738) (xy 68.206193 -436.23698)
			(xy 68.183163 -436.229479) (xy 68.163588 -436.215214) (xy 68.149394 -436.195588) (xy 68.141976 -436.17253)
			(xy 68.141596 -436.160418) (xy 68.141596 -435.550056) (xy 68.13993 -435.535062) (xy 68.13815 -435.504944)
			(xy 68.13804 -435.489858) (xy 65.23482 -435.489858) (xy 65.23482 -436.160418) (xy 65.234407 -436.172513)
			(xy 65.226941 -436.195521) (xy 65.212742 -436.215104) (xy 65.193194 -436.229352) (xy 65.170205 -436.236877)
			(xy 65.158112 -436.23738) (xy 64.218312 -436.23738) (xy 64.206202 -436.236973) (xy 64.183172 -436.229474)
			(xy 64.163597 -436.215211) (xy 64.149402 -436.195586) (xy 64.141985 -436.17253) (xy 64.141604 -436.160418)
			(xy 64.141604 -435.550056) (xy 64.139938 -435.535062) (xy 64.138158 -435.504944) (xy 64.138048 -435.489858)
			(xy 61.234828 -435.489858) (xy 61.234828 -436.160418) (xy 61.234408 -436.172512) (xy 61.226942 -436.195518)
			(xy 61.212745 -436.215101) (xy 61.193199 -436.22935) (xy 61.170212 -436.236876) (xy 61.15812 -436.23738)
			(xy 60.21832 -436.23738) (xy 60.20621 -436.236966) (xy 60.18318 -436.22947) (xy 60.163605 -436.215208)
			(xy 60.149411 -436.195585) (xy 60.141993 -436.172529) (xy 60.141612 -436.160418) (xy 60.141612 -435.550056)
			(xy 60.139946 -435.535062) (xy 60.138166 -435.504944) (xy 60.138056 -435.489858) (xy 7.00913 -435.489858)
			(xy 7.00913 -438.089802) (xy 58.118502 -438.089802) (xy 58.119024 -438.057222) (xy 58.126997 -437.992552)
			(xy 58.142813 -437.929341) (xy 58.166234 -437.868536) (xy 58.196909 -437.811048) (xy 58.234378 -437.757739)
			(xy 58.27808 -437.709407) (xy 58.302398 -437.68772) (xy 58.382916 -437.523382) (xy 58.387617 -437.512865)
			(xy 58.391107 -437.490107) (xy 58.387622 -437.467348) (xy 58.382916 -437.456834) (xy 58.30189 -437.291734)
			(xy 58.277614 -437.270052) (xy 58.234018 -437.221717) (xy 58.196645 -437.168424) (xy 58.166053 -437.110969)
			(xy 58.1427 -437.05021) (xy 58.126935 -436.987057) (xy 58.118992 -436.922452) (xy 58.118502 -436.889906)
			(xy 58.119238 -436.850581) (xy 58.130837 -436.772791) (xy 58.141616 -436.734966) (xy 58.141616 -436.219092)
			(xy 58.142006 -436.207006) (xy 58.149479 -436.184019) (xy 58.16369 -436.164467) (xy 58.183248 -436.150264)
			(xy 58.206238 -436.142801) (xy 58.218324 -436.142384) (xy 59.158124 -436.142384) (xy 59.170199 -436.142844)
			(xy 59.193166 -436.150312) (xy 59.212701 -436.16451) (xy 59.226895 -436.184049) (xy 59.234359 -436.207017)
			(xy 59.234832 -436.219092) (xy 59.234832 -438.760616) (xy 59.23435 -438.772689) (xy 59.226886 -438.795653)
			(xy 59.212693 -438.815187) (xy 59.19316 -438.829382) (xy 59.170197 -438.836848) (xy 59.158124 -438.837324)
			(xy 58.218324 -438.837324) (xy 58.206244 -438.836867) (xy 58.183265 -438.829408) (xy 58.163716 -438.815213)
			(xy 58.14951 -438.795671) (xy 58.142039 -438.772696) (xy 58.141616 -438.760616) (xy 58.141616 -438.244742)
			(xy 58.130818 -438.20692) (xy 58.11921 -438.129129) (xy 58.118502 -438.089802) (xy 7.00913 -438.089802)
			(xy 7.00913 -439.0898) (xy 60.118498 -439.0898) (xy 60.11902 -439.05722) (xy 60.126993 -438.99255)
			(xy 60.142809 -438.929339) (xy 60.16623 -438.868534) (xy 60.196905 -438.811046) (xy 60.234374 -438.757737)
			(xy 60.278076 -438.709405) (xy 60.302394 -438.687718) (xy 60.382912 -438.52338) (xy 60.387615 -438.512864)
			(xy 60.391104 -438.490105) (xy 60.387618 -438.467346) (xy 60.382912 -438.456832) (xy 60.301886 -438.291732)
			(xy 60.277608 -438.270052) (xy 60.234012 -438.221716) (xy 60.196639 -438.168423) (xy 60.166048 -438.110967)
			(xy 60.142696 -438.050209) (xy 60.12693 -437.987055) (xy 60.118988 -437.92245) (xy 60.118498 -437.889904)
			(xy 60.119234 -437.850579) (xy 60.130833 -437.772789) (xy 60.141612 -437.734964) (xy 60.141612 -437.21909)
			(xy 60.142099 -437.207003) (xy 60.149555 -437.184007) (xy 60.163737 -437.164429) (xy 60.183265 -437.150178)
			(xy 60.206234 -437.142641) (xy 60.21832 -437.142128) (xy 61.15812 -437.142128) (xy 61.170233 -437.1425)
			(xy 61.193265 -437.150008) (xy 61.212841 -437.16428) (xy 61.227034 -437.183913) (xy 61.234449 -437.206976)
			(xy 61.234828 -437.21909) (xy 61.234828 -438.089802) (xy 62.118494 -438.089802) (xy 62.119018 -438.057222)
			(xy 62.126992 -437.992552) (xy 62.142807 -437.929341) (xy 62.166228 -437.868536) (xy 62.196902 -437.811048)
			(xy 62.234371 -437.757739) (xy 62.278072 -437.709407) (xy 62.30239 -437.68772) (xy 62.382908 -437.523382)
			(xy 62.387609 -437.512865) (xy 62.391099 -437.490107) (xy 62.387614 -437.467348) (xy 62.382908 -437.456834)
			(xy 62.301882 -437.291734) (xy 62.277604 -437.270054) (xy 62.234008 -437.221718) (xy 62.196636 -437.168424)
			(xy 62.166045 -437.110969) (xy 62.142692 -437.050211) (xy 62.126927 -436.987057) (xy 62.118984 -436.922452)
			(xy 62.118494 -436.889906) (xy 62.11923 -436.850581) (xy 62.130829 -436.772791) (xy 62.141608 -436.734966)
			(xy 62.141608 -436.219092) (xy 62.142006 -436.207007) (xy 62.149478 -436.184021) (xy 62.163687 -436.16447)
			(xy 62.183243 -436.150267) (xy 62.206231 -436.142802) (xy 62.218316 -436.142384) (xy 63.158116 -436.142384)
			(xy 63.170191 -436.142851) (xy 63.193157 -436.150317) (xy 63.212693 -436.164513) (xy 63.226887 -436.18405)
			(xy 63.234351 -436.207017) (xy 63.234824 -436.219092) (xy 63.234824 -438.760616) (xy 63.23435 -438.77269)
			(xy 63.226885 -438.795655) (xy 63.21269 -438.81519) (xy 63.193155 -438.829385) (xy 63.17019 -438.83685)
			(xy 63.158116 -438.837324) (xy 62.218316 -438.837324) (xy 62.206244 -438.836822) (xy 62.18328 -438.829366)
			(xy 62.163744 -438.815179) (xy 62.149548 -438.795649) (xy 62.142083 -438.772688) (xy 62.141608 -438.760616)
			(xy 62.141608 -438.244742) (xy 62.13081 -438.20692) (xy 62.119202 -438.129129) (xy 62.118494 -438.089802)
			(xy 61.234828 -438.089802) (xy 61.234828 -439.0898) (xy 64.11849 -439.0898) (xy 64.119014 -439.05722)
			(xy 64.126988 -438.99255) (xy 64.142804 -438.929339) (xy 64.166224 -438.868534) (xy 64.196898 -438.811046)
			(xy 64.234367 -438.757737) (xy 64.278068 -438.709405) (xy 64.302386 -438.687718) (xy 64.382904 -438.52338)
			(xy 64.387607 -438.512864) (xy 64.391096 -438.490105) (xy 64.38761 -438.467346) (xy 64.382904 -438.456832)
			(xy 64.301878 -438.291732) (xy 64.277598 -438.270054) (xy 64.234003 -438.221718) (xy 64.196631 -438.168423)
			(xy 64.16604 -438.110968) (xy 64.142687 -438.050209) (xy 64.126922 -437.987055) (xy 64.11898 -437.92245)
			(xy 64.11849 -437.889904) (xy 64.119226 -437.850579) (xy 64.130825 -437.772789) (xy 64.141604 -437.734964)
			(xy 64.141604 -437.21909) (xy 64.142098 -437.207004) (xy 64.149553 -437.184009) (xy 64.163734 -437.164432)
			(xy 64.18326 -437.150181) (xy 64.206227 -437.142643) (xy 64.218312 -437.142128) (xy 65.158112 -437.142128)
			(xy 65.170224 -437.142506) (xy 65.193257 -437.150012) (xy 65.212832 -437.164283) (xy 65.227025 -437.183914)
			(xy 65.234441 -437.206976) (xy 65.23482 -437.21909) (xy 65.23482 -438.089802) (xy 66.118486 -438.089802)
			(xy 66.119013 -438.057222) (xy 66.126986 -437.992553) (xy 66.142802 -437.929342) (xy 66.166222 -437.868537)
			(xy 66.196896 -437.811049) (xy 66.234364 -437.757739) (xy 66.278065 -437.709408) (xy 66.302382 -437.68772)
			(xy 66.3829 -437.523382) (xy 66.387602 -437.512866) (xy 66.391092 -437.490107) (xy 66.387606 -437.467348)
			(xy 66.3829 -437.456834) (xy 66.301874 -437.291734) (xy 66.277594 -437.270056) (xy 66.233999 -437.221719)
			(xy 66.196627 -437.168425) (xy 66.166036 -437.11097) (xy 66.142684 -437.050211) (xy 66.126919 -436.987057)
			(xy 66.118976 -436.922452) (xy 66.118486 -436.889906) (xy 66.119223 -436.850581) (xy 66.130821 -436.772791)
			(xy 66.1416 -436.734966) (xy 66.1416 -436.219092) (xy 66.142058 -436.207016) (xy 66.149523 -436.184047)
			(xy 66.163721 -436.16451) (xy 66.183262 -436.150316) (xy 66.206232 -436.142855) (xy 66.218308 -436.142384)
			(xy 67.158108 -436.142384) (xy 67.170182 -436.142857) (xy 67.193148 -436.150321) (xy 67.212684 -436.164516)
			(xy 67.226879 -436.184052) (xy 67.234343 -436.207018) (xy 67.234816 -436.219092) (xy 67.234816 -438.760616)
			(xy 67.234349 -438.772691) (xy 67.226883 -438.795657) (xy 67.212687 -438.815193) (xy 67.19315 -438.829387)
			(xy 67.170183 -438.836851) (xy 67.158108 -438.837324) (xy 66.218308 -438.837324) (xy 66.206235 -438.836829)
			(xy 66.183271 -438.829371) (xy 66.163735 -438.815182) (xy 66.14954 -438.79565) (xy 66.142075 -438.772688)
			(xy 66.1416 -438.760616) (xy 66.1416 -438.244742) (xy 66.130801 -438.20692) (xy 66.119194 -438.129129)
			(xy 66.118486 -438.089802) (xy 65.23482 -438.089802) (xy 65.23482 -439.0898) (xy 68.118482 -439.0898)
			(xy 68.119009 -439.05722) (xy 68.126983 -438.992551) (xy 68.142798 -438.92934) (xy 68.166218 -438.868535)
			(xy 68.196892 -438.811047) (xy 68.23436 -438.757738) (xy 68.278061 -438.709406) (xy 68.302378 -438.687718)
			(xy 68.382896 -438.52338) (xy 68.387599 -438.512864) (xy 68.391089 -438.490105) (xy 68.387602 -438.467346)
			(xy 68.382896 -438.456832) (xy 68.30187 -438.291732) (xy 68.277609 -438.270033) (xy 68.234009 -438.221703)
			(xy 68.196632 -438.168413) (xy 68.166038 -438.110961) (xy 68.142683 -438.050205) (xy 68.126915 -437.987053)
			(xy 68.118972 -437.922449) (xy 68.118482 -437.889904) (xy 68.119219 -437.850579) (xy 68.130817 -437.772789)
			(xy 68.141596 -437.734964) (xy 68.141596 -437.21909) (xy 68.142098 -437.207004) (xy 68.149552 -437.184011)
			(xy 68.163731 -437.164435) (xy 68.183255 -437.150183) (xy 68.20622 -437.142644) (xy 68.218304 -437.142128)
			(xy 69.158104 -437.142128) (xy 69.170216 -437.142513) (xy 69.193248 -437.150017) (xy 69.212824 -437.164286)
			(xy 69.227017 -437.183916) (xy 69.234433 -437.206977) (xy 69.234812 -437.21909) (xy 69.234812 -438.089802)
			(xy 70.118478 -438.089802) (xy 70.119008 -438.057223) (xy 70.126981 -437.992553) (xy 70.142796 -437.929342)
			(xy 70.166216 -437.868537) (xy 70.196889 -437.811049) (xy 70.234357 -437.75774) (xy 70.278057 -437.709408)
			(xy 70.302374 -437.68772) (xy 70.382892 -437.523382) (xy 70.387594 -437.512866) (xy 70.391085 -437.490107)
			(xy 70.387598 -437.467348) (xy 70.382892 -437.456834) (xy 70.301866 -437.291734) (xy 70.277605 -437.270035)
			(xy 70.234005 -437.221705) (xy 70.196629 -437.168415) (xy 70.166034 -437.110963) (xy 70.142679 -437.050207)
			(xy 70.126912 -436.987055) (xy 70.118968 -436.922451) (xy 70.118478 -436.889906) (xy 70.119215 -436.850581)
			(xy 70.130814 -436.772792) (xy 70.141592 -436.734966) (xy 70.141592 -436.219092) (xy 70.142058 -436.207017)
			(xy 70.149522 -436.18405) (xy 70.163718 -436.164513) (xy 70.183257 -436.150319) (xy 70.206225 -436.142856)
			(xy 70.2183 -436.142384) (xy 71.1581 -436.142384) (xy 71.170174 -436.142864) (xy 71.19314 -436.150326)
			(xy 71.212676 -436.164518) (xy 71.226871 -436.184053) (xy 71.234335 -436.207018) (xy 71.234808 -436.219092)
			(xy 71.234808 -438.760616) (xy 71.234349 -438.772691) (xy 71.226882 -438.795659) (xy 71.212684 -438.815196)
			(xy 71.193145 -438.82939) (xy 71.170175 -438.836852) (xy 71.1581 -438.837324) (xy 70.2183 -438.837324)
			(xy 70.206227 -438.836836) (xy 70.183263 -438.829375) (xy 70.163727 -438.815184) (xy 70.149532 -438.795652)
			(xy 70.142067 -438.772689) (xy 70.141592 -438.760616) (xy 70.141592 -438.244742) (xy 70.130793 -438.20692)
			(xy 70.119186 -438.129129) (xy 70.118478 -438.089802) (xy 69.234812 -438.089802) (xy 69.234812 -439.0898)
			(xy 72.118474 -439.0898) (xy 72.119004 -439.057221) (xy 72.126977 -438.992551) (xy 72.142792 -438.92934)
			(xy 72.166212 -438.868535) (xy 72.196885 -438.811048) (xy 72.234353 -438.757738) (xy 72.278053 -438.709406)
			(xy 72.30237 -438.687718) (xy 72.382888 -438.52338) (xy 72.387592 -438.512864) (xy 72.391082 -438.490105)
			(xy 72.387595 -438.467346) (xy 72.382888 -438.456832) (xy 72.301862 -438.291732) (xy 72.277599 -438.270035)
			(xy 72.234 -438.221704) (xy 72.196624 -438.168414) (xy 72.166029 -438.110962) (xy 72.142674 -438.050206)
			(xy 72.126907 -437.987053) (xy 72.118964 -437.922449) (xy 72.118474 -437.889904) (xy 72.119211 -437.850579)
			(xy 72.130809 -437.772789) (xy 72.141588 -437.734964) (xy 72.141588 -437.21909) (xy 72.142 -437.206995)
			(xy 72.149465 -437.183986) (xy 72.163664 -437.164402) (xy 72.183212 -437.150154) (xy 72.206202 -437.142631)
			(xy 72.218296 -437.142128) (xy 73.158096 -437.142128) (xy 73.170207 -437.14252) (xy 73.193239 -437.150022)
			(xy 73.212815 -437.164288) (xy 73.227009 -437.183917) (xy 73.234425 -437.206977) (xy 73.234804 -437.21909)
			(xy 73.234804 -438.089802) (xy 75.118468 -438.089802) (xy 75.119001 -438.057223) (xy 75.126974 -437.992553)
			(xy 75.142789 -437.929343) (xy 75.166208 -437.868538) (xy 75.196881 -437.81105) (xy 75.234348 -437.75774)
			(xy 75.278047 -437.709408) (xy 75.302364 -437.68772) (xy 75.382882 -437.523382) (xy 75.387585 -437.512866)
			(xy 75.391076 -437.490107) (xy 75.387589 -437.467348) (xy 75.382882 -437.456834) (xy 75.301856 -437.291734)
			(xy 75.277593 -437.270038) (xy 75.233994 -437.221706) (xy 75.196618 -437.168416) (xy 75.166024 -437.110964)
			(xy 75.142669 -437.050208) (xy 75.126902 -436.987055) (xy 75.118958 -436.922451) (xy 75.118468 -436.889906)
			(xy 75.119168 -436.85078) (xy 75.130642 -436.773373) (xy 75.141328 -436.735728) (xy 75.141328 -436.219092)
			(xy 75.14171 -436.20698) (xy 75.149215 -436.183948) (xy 75.163484 -436.164372) (xy 75.183115 -436.150179)
			(xy 75.206176 -436.142763) (xy 75.21829 -436.142384) (xy 76.15809 -436.142384) (xy 76.170183 -436.142817)
			(xy 76.193191 -436.150276) (xy 76.212775 -436.16447) (xy 76.227024 -436.184014) (xy 76.234549 -436.207)
			(xy 76.235052 -436.219092) (xy 76.235052 -438.760616) (xy 76.234598 -438.772721) (xy 76.227101 -438.795739)
			(xy 76.212847 -438.815308) (xy 76.193237 -438.829504) (xy 76.170196 -438.836933) (xy 76.15809 -438.837324)
			(xy 75.21829 -438.837324) (xy 75.206196 -438.8369) (xy 75.183189 -438.829436) (xy 75.163607 -438.81524)
			(xy 75.149358 -438.795695) (xy 75.141832 -438.772708) (xy 75.141328 -438.760616) (xy 75.141328 -438.24398)
			(xy 75.130641 -438.206335) (xy 75.119164 -438.128928) (xy 75.118468 -438.089802) (xy 73.234804 -438.089802)
			(xy 73.234804 -439.0898) (xy 77.118464 -439.0898) (xy 77.118963 -439.057219) (xy 77.126938 -438.992548)
			(xy 77.142756 -438.929335) (xy 77.16618 -438.868529) (xy 77.196859 -438.811041) (xy 77.234333 -438.757733)
			(xy 77.27804 -438.709404) (xy 77.30236 -438.687718) (xy 77.382878 -438.52338) (xy 77.387582 -438.512864)
			(xy 77.391073 -438.490105) (xy 77.387585 -438.467346) (xy 77.382878 -438.456832) (xy 77.301852 -438.291732)
			(xy 77.277587 -438.270037) (xy 77.233988 -438.221706) (xy 77.196612 -438.168415) (xy 77.166019 -438.110963)
			(xy 77.142664 -438.050206) (xy 77.126897 -437.987054) (xy 77.118954 -437.922449) (xy 77.118464 -437.889904)
			(xy 77.119164 -437.850778) (xy 77.130638 -437.773371) (xy 77.141324 -437.735726) (xy 77.141324 -437.21909)
			(xy 77.141803 -437.206976) (xy 77.149291 -437.183935) (xy 77.163532 -437.164335) (xy 77.183132 -437.150093)
			(xy 77.206172 -437.142604) (xy 77.218286 -437.142128) (xy 78.158086 -437.142128) (xy 78.170207 -437.142572)
			(xy 78.193264 -437.150059) (xy 78.212878 -437.164305) (xy 78.22713 -437.183915) (xy 78.234624 -437.206969)
			(xy 78.235048 -437.21909) (xy 78.235048 -438.089802) (xy 79.11846 -438.089802) (xy 79.118962 -438.057221)
			(xy 79.126937 -437.99255) (xy 79.142754 -437.929337) (xy 79.166178 -437.868532) (xy 79.196856 -437.811044)
			(xy 79.234329 -437.757736) (xy 79.278036 -437.709406) (xy 79.302356 -437.68772) (xy 79.382874 -437.523382)
			(xy 79.387577 -437.512866) (xy 79.391068 -437.490107) (xy 79.387581 -437.467348) (xy 79.382874 -437.456834)
			(xy 79.301848 -437.291734) (xy 79.277583 -437.270039) (xy 79.233984 -437.221708) (xy 79.196609 -437.168417)
			(xy 79.166015 -437.110964) (xy 79.14266 -437.050208) (xy 79.126894 -436.987056) (xy 79.11895 -436.922451)
			(xy 79.11846 -436.889906) (xy 79.11916 -436.85078) (xy 79.130635 -436.773373) (xy 79.14132 -436.735728)
			(xy 79.14132 -436.219092) (xy 79.14171 -436.206981) (xy 79.149214 -436.18395) (xy 79.163481 -436.164375)
			(xy 79.18311 -436.150181) (xy 79.206169 -436.142764) (xy 79.218282 -436.142384) (xy 80.158082 -436.142384)
			(xy 80.170175 -436.142824) (xy 80.193182 -436.150281) (xy 80.212766 -436.164473) (xy 80.227016 -436.184015)
			(xy 80.234541 -436.207) (xy 80.235044 -436.219092) (xy 80.235044 -438.760616) (xy 80.234598 -438.772721)
			(xy 80.227099 -438.795742) (xy 80.212844 -438.815311) (xy 80.193232 -438.829506) (xy 80.170189 -438.836935)
			(xy 80.158082 -438.837324) (xy 79.218282 -438.837324) (xy 79.206188 -438.836907) (xy 79.183181 -438.829441)
			(xy 79.163598 -438.815243) (xy 79.149349 -438.795697) (xy 79.141824 -438.772709) (xy 79.14132 -438.760616)
			(xy 79.14132 -438.24398) (xy 79.130633 -438.206335) (xy 79.119156 -438.128928) (xy 79.11846 -438.089802)
			(xy 78.235048 -438.089802) (xy 78.235048 -439.0898) (xy 81.118456 -439.0898) (xy 81.118958 -439.057219)
			(xy 81.126933 -438.992548) (xy 81.142751 -438.929335) (xy 81.166174 -438.86853) (xy 81.196852 -438.811042)
			(xy 81.234326 -438.757734) (xy 81.278032 -438.709404) (xy 81.302352 -438.687718) (xy 81.38287 -438.52338)
			(xy 81.387575 -438.512864) (xy 81.391066 -438.490105) (xy 81.387578 -438.467346) (xy 81.38287 -438.456832)
			(xy 81.301844 -438.291732) (xy 81.277577 -438.270039) (xy 81.233979 -438.221707) (xy 81.196604 -438.168416)
			(xy 81.16601 -438.110963) (xy 81.142656 -438.050206) (xy 81.126889 -437.987054) (xy 81.118946 -437.922449)
			(xy 81.118456 -437.889904) (xy 81.119156 -437.850778) (xy 81.130631 -437.773371) (xy 81.141316 -437.735726)
			(xy 81.141316 -437.21909) (xy 81.141803 -437.206977) (xy 81.14929 -437.183937) (xy 81.163529 -437.164338)
			(xy 81.183127 -437.150096) (xy 81.206165 -437.142605) (xy 81.218278 -437.142128) (xy 82.158078 -437.142128)
			(xy 82.170199 -437.142579) (xy 82.193255 -437.150064) (xy 82.21287 -437.164308) (xy 82.227122 -437.183916)
			(xy 82.234616 -437.20697) (xy 82.23504 -437.21909) (xy 82.23504 -438.089802) (xy 83.118452 -438.089802)
			(xy 83.118957 -438.057222) (xy 83.126931 -437.99255) (xy 83.142749 -437.929338) (xy 83.166172 -437.868532)
			(xy 83.19685 -437.811044) (xy 83.234322 -437.757736) (xy 83.278028 -437.709406) (xy 83.302348 -437.68772)
			(xy 83.382866 -437.523382) (xy 83.387564 -437.512865) (xy 83.391052 -437.490107) (xy 83.387569 -437.467349)
			(xy 83.382866 -437.456834) (xy 83.30184 -437.291734) (xy 83.277574 -437.270041) (xy 83.233975 -437.221709)
			(xy 83.1966 -437.168418) (xy 83.166007 -437.110965) (xy 83.142652 -437.050208) (xy 83.126885 -436.987056)
			(xy 83.118942 -436.922451) (xy 83.118452 -436.889906) (xy 83.119153 -436.85078) (xy 83.130627 -436.773373)
			(xy 83.141312 -436.735728) (xy 83.141312 -436.219092) (xy 83.14171 -436.206981) (xy 83.149213 -436.183952)
			(xy 83.163479 -436.164378) (xy 83.183105 -436.150184) (xy 83.206162 -436.142765) (xy 83.218274 -436.142384)
			(xy 84.158074 -436.142384) (xy 84.170167 -436.14283) (xy 84.193174 -436.150285) (xy 84.212758 -436.164476)
			(xy 84.227008 -436.184017) (xy 84.234533 -436.207001) (xy 84.235036 -436.219092) (xy 84.235036 -438.760616)
			(xy 84.234598 -438.772722) (xy 84.227098 -438.795744) (xy 84.212841 -438.815313) (xy 84.193227 -438.829509)
			(xy 84.170181 -438.836936) (xy 84.158074 -438.837324) (xy 83.218274 -438.837324) (xy 83.206179 -438.836914)
			(xy 83.183172 -438.829446) (xy 83.163589 -438.815246) (xy 83.149341 -438.795698) (xy 83.141816 -438.772709)
			(xy 83.141312 -438.760616) (xy 83.141312 -438.24398) (xy 83.130625 -438.206335) (xy 83.119148 -438.128928)
			(xy 83.118452 -438.089802) (xy 82.23504 -438.089802) (xy 82.23504 -439.0898) (xy 85.118448 -439.0898)
			(xy 85.118953 -439.05722) (xy 85.126928 -438.992548) (xy 85.142745 -438.929336) (xy 85.166168 -438.86853)
			(xy 85.196846 -438.811042) (xy 85.234319 -438.757734) (xy 85.278025 -438.709404) (xy 85.302344 -438.687718)
			(xy 85.382862 -438.52338) (xy 85.387562 -438.512863) (xy 85.391049 -438.490105) (xy 85.387565 -438.467347)
			(xy 85.382862 -438.456832) (xy 85.301836 -438.291732) (xy 85.277568 -438.270041) (xy 85.23397 -438.221708)
			(xy 85.196595 -438.168417) (xy 85.166002 -438.110964) (xy 85.142647 -438.050207) (xy 85.126881 -437.987054)
			(xy 85.118938 -437.922449) (xy 85.118448 -437.889904) (xy 85.119148 -437.850778) (xy 85.130623 -437.773371)
			(xy 85.141308 -437.735726) (xy 85.141308 -437.21909) (xy 85.141803 -437.206978) (xy 85.149289 -437.18394)
			(xy 85.163526 -437.164341) (xy 85.183122 -437.150098) (xy 85.206158 -437.142606) (xy 85.21827 -437.142128)
			(xy 86.15807 -437.142128) (xy 86.17019 -437.142585) (xy 86.193246 -437.150068) (xy 86.212861 -437.16431)
			(xy 86.227114 -437.183918) (xy 86.234608 -437.20697) (xy 86.235032 -437.21909) (xy 86.235032 -438.089802)
			(xy 87.118444 -438.089802) (xy 87.118952 -438.057222) (xy 87.126926 -437.99255) (xy 87.142743 -437.929338)
			(xy 87.166166 -437.868533) (xy 87.196843 -437.811045) (xy 87.234315 -437.757736) (xy 87.278021 -437.709407)
			(xy 87.30234 -437.68772) (xy 87.382858 -437.523382) (xy 87.387557 -437.512865) (xy 87.391044 -437.490107)
			(xy 87.387561 -437.467349) (xy 87.382858 -437.456834) (xy 87.301832 -437.291734) (xy 87.277564 -437.270043)
			(xy 87.233966 -437.22171) (xy 87.196591 -437.168419) (xy 87.165998 -437.110966) (xy 87.142644 -437.050209)
			(xy 87.126877 -436.987056) (xy 87.118934 -436.922451) (xy 87.118444 -436.889906) (xy 87.119145 -436.85078)
			(xy 87.130619 -436.773373) (xy 87.141304 -436.735728) (xy 87.141304 -436.219092) (xy 87.141709 -436.206982)
			(xy 87.149212 -436.183954) (xy 87.163476 -436.164381) (xy 87.1831 -436.150186) (xy 87.206155 -436.142767)
			(xy 87.218266 -436.142384) (xy 88.158066 -436.142384) (xy 88.170158 -436.142837) (xy 88.193165 -436.15029)
			(xy 88.212749 -436.164478) (xy 88.227 -436.184018) (xy 88.234525 -436.207001) (xy 88.235028 -436.219092)
			(xy 88.235028 -438.760616) (xy 88.234598 -438.772723) (xy 88.227097 -438.795746) (xy 88.212838 -438.815316)
			(xy 88.193222 -438.829511) (xy 88.170174 -438.836937) (xy 88.158066 -438.837324) (xy 87.218266 -438.837324)
			(xy 87.206171 -438.836921) (xy 87.183163 -438.829451) (xy 87.163581 -438.815249) (xy 87.149333 -438.7957)
			(xy 87.141808 -438.77271) (xy 87.141304 -438.760616) (xy 87.141304 -438.24398) (xy 87.130617 -438.206335)
			(xy 87.11914 -438.128928) (xy 87.118444 -438.089802) (xy 86.235032 -438.089802) (xy 86.235032 -439.0898)
			(xy 89.11844 -439.0898) (xy 89.118948 -439.05722) (xy 89.126922 -438.992549) (xy 89.142739 -438.929336)
			(xy 89.166162 -438.868531) (xy 89.196839 -438.811043) (xy 89.234312 -438.757735) (xy 89.278017 -438.709405)
			(xy 89.302336 -438.687718) (xy 89.382854 -438.52338) (xy 89.387555 -438.512864) (xy 89.391042 -438.490105)
			(xy 89.387558 -438.467347) (xy 89.382854 -438.456832) (xy 89.301828 -438.291732) (xy 89.277558 -438.270043)
			(xy 89.23396 -438.22171) (xy 89.196586 -438.168418) (xy 89.165993 -438.110964) (xy 89.142639 -438.050207)
			(xy 89.126873 -437.987054) (xy 89.11893 -437.92245) (xy 89.11844 -437.889904) (xy 89.119141 -437.850778)
			(xy 89.130615 -437.773371) (xy 89.1413 -437.735726) (xy 89.1413 -437.21909) (xy 89.141803 -437.206979)
			(xy 89.149288 -437.183942) (xy 89.163524 -437.164343) (xy 89.183117 -437.150101) (xy 89.206151 -437.142607)
			(xy 89.218262 -437.142128) (xy 90.158062 -437.142128) (xy 90.170182 -437.142592) (xy 90.193238 -437.150073)
			(xy 90.212853 -437.164313) (xy 90.227105 -437.183919) (xy 90.2346 -437.20697) (xy 90.235024 -437.21909)
			(xy 90.235024 -439.0898) (xy 127.237998 -439.0898) (xy 127.23809 -439.075226) (xy 127.239744 -439.046125)
			(xy 127.2413 -439.031634) (xy 127.2413 -437.94807) (xy 127.239755 -437.933578) (xy 127.238103 -437.904478)
			(xy 127.237998 -437.889904) (xy 127.238091 -437.87533) (xy 127.239744 -437.846229) (xy 127.2413 -437.831738)
			(xy 127.2413 -437.21909) (xy 127.241803 -437.206979) (xy 127.249288 -437.183942) (xy 127.263524 -437.164343)
			(xy 127.283117 -437.150101) (xy 127.306151 -437.142607) (xy 127.318262 -437.142128) (xy 128.258062 -437.142128)
			(xy 128.270182 -437.142592) (xy 128.293238 -437.150073) (xy 128.312853 -437.164313) (xy 128.327105 -437.183919)
			(xy 128.3346 -437.20697) (xy 128.335024 -437.21909) (xy 128.335024 -438.089802) (xy 129.237994 -438.089802)
			(xy 129.238087 -438.075228) (xy 129.23974 -438.046127) (xy 129.241296 -438.031636) (xy 129.241296 -436.948072)
			(xy 129.239752 -436.93358) (xy 129.238099 -436.90448) (xy 129.237994 -436.889906) (xy 129.238087 -436.875332)
			(xy 129.23974 -436.846231) (xy 129.241296 -436.83174) (xy 129.241296 -436.219092) (xy 129.241709 -436.206983)
			(xy 129.24921 -436.183956) (xy 129.263473 -436.164384) (xy 129.283095 -436.150189) (xy 129.306148 -436.142768)
			(xy 129.318258 -436.142384) (xy 130.258058 -436.142384) (xy 130.27015 -436.142844) (xy 130.293156 -436.150294)
			(xy 130.312741 -436.164481) (xy 130.326991 -436.184019) (xy 130.334516 -436.207002) (xy 130.33502 -436.219092)
			(xy 130.33502 -438.760616) (xy 130.334598 -438.772724) (xy 130.327096 -438.795748) (xy 130.312836 -438.815319)
			(xy 130.293217 -438.829514) (xy 130.270167 -438.836938) (xy 130.258058 -438.837324) (xy 129.318258 -438.837324)
			(xy 129.306163 -438.836928) (xy 129.283155 -438.829455) (xy 129.263572 -438.815252) (xy 129.249324 -438.795701)
			(xy 129.2418 -438.77271) (xy 129.241296 -438.760616) (xy 129.241296 -438.147968) (xy 129.239751 -438.133476)
			(xy 129.238099 -438.104376) (xy 129.237994 -438.089802) (xy 128.335024 -438.089802) (xy 128.335024 -439.0898)
			(xy 131.23799 -439.0898) (xy 131.238082 -439.075226) (xy 131.239736 -439.046125) (xy 131.241292 -439.031634)
			(xy 131.241292 -437.94807) (xy 131.239748 -437.933578) (xy 131.238095 -437.904478) (xy 131.23799 -437.889904)
			(xy 131.238083 -437.87533) (xy 131.239736 -437.846229) (xy 131.241292 -437.831738) (xy 131.241292 -437.21909)
			(xy 131.241803 -437.20698) (xy 131.249287 -437.183944) (xy 131.263521 -437.164346) (xy 131.283112 -437.150104)
			(xy 131.306144 -437.142608) (xy 131.318254 -437.142128) (xy 132.258054 -437.142128) (xy 132.270173 -437.142599)
			(xy 132.293229 -437.150077) (xy 132.312844 -437.164316) (xy 132.327097 -437.183921) (xy 132.334592 -437.206971)
			(xy 132.335016 -437.21909) (xy 132.335016 -438.089802) (xy 133.237986 -438.089802) (xy 133.238079 -438.075228)
			(xy 133.239732 -438.046127) (xy 133.241288 -438.031636) (xy 133.241288 -436.948072) (xy 133.239744 -436.93358)
			(xy 133.238091 -436.90448) (xy 133.237986 -436.889906) (xy 133.238079 -436.875332) (xy 133.239732 -436.846231)
			(xy 133.241288 -436.83174) (xy 133.241288 -436.219092) (xy 133.241709 -436.206984) (xy 133.249209 -436.183958)
			(xy 133.26347 -436.164386) (xy 133.28309 -436.150192) (xy 133.306141 -436.142769) (xy 133.31825 -436.142384)
			(xy 134.25805 -436.142384) (xy 134.270141 -436.142851) (xy 134.293148 -436.150299) (xy 134.312732 -436.164484)
			(xy 134.326983 -436.184021) (xy 134.334508 -436.207002) (xy 134.335012 -436.219092) (xy 134.335012 -438.760616)
			(xy 134.334598 -438.772725) (xy 134.327095 -438.79575) (xy 134.312833 -438.815322) (xy 134.293212 -438.829517)
			(xy 134.27016 -438.836939) (xy 134.25805 -438.837324) (xy 133.31825 -438.837324) (xy 133.306159 -438.836849)
			(xy 133.283154 -438.829402) (xy 133.26357 -438.815219) (xy 133.249319 -438.795684) (xy 133.241793 -438.772705)
			(xy 133.241288 -438.760616) (xy 133.241288 -438.147968) (xy 133.239743 -438.133476) (xy 133.238091 -438.104376)
			(xy 133.237986 -438.089802) (xy 132.335016 -438.089802) (xy 132.335016 -439.0898) (xy 135.237982 -439.0898)
			(xy 135.238075 -439.075226) (xy 135.239728 -439.046125) (xy 135.241284 -439.031634) (xy 135.241284 -437.94807)
			(xy 135.23974 -437.933578) (xy 135.238087 -437.904478) (xy 135.237982 -437.889904) (xy 135.238075 -437.87533)
			(xy 135.239728 -437.846229) (xy 135.241284 -437.831738) (xy 135.241284 -437.21909) (xy 135.241652 -437.206962)
			(xy 135.249153 -437.183895) (xy 135.263416 -437.164276) (xy 135.283045 -437.150027) (xy 135.306118 -437.142544)
			(xy 135.318246 -437.142128) (xy 136.258046 -437.142128) (xy 136.270162 -437.142572) (xy 136.293205 -437.150071)
			(xy 136.312805 -437.164321) (xy 136.327045 -437.183927) (xy 136.334533 -437.206974) (xy 136.335008 -437.21909)
			(xy 136.335008 -438.089802) (xy 137.237978 -438.089802) (xy 137.238071 -438.075228) (xy 137.239724 -438.046127)
			(xy 137.24128 -438.031636) (xy 137.24128 -436.948072) (xy 137.239736 -436.93358) (xy 137.238083 -436.90448)
			(xy 137.237978 -436.889906) (xy 137.238071 -436.875332) (xy 137.239724 -436.846231) (xy 137.24128 -436.83174)
			(xy 137.24128 -436.219092) (xy 137.241709 -436.206985) (xy 137.249208 -436.183961) (xy 137.263467 -436.164389)
			(xy 137.283085 -436.150194) (xy 137.306133 -436.14277) (xy 137.318242 -436.142384) (xy 138.258042 -436.142384)
			(xy 138.270138 -436.142772) (xy 138.293148 -436.150246) (xy 138.312731 -436.164451) (xy 138.326978 -436.184004)
			(xy 138.334501 -436.206997) (xy 138.335004 -436.219092) (xy 138.335004 -438.760616) (xy 138.334597 -438.772725)
			(xy 138.327094 -438.795752) (xy 138.31283 -438.815325) (xy 138.293207 -438.829519) (xy 138.270153 -438.83694)
			(xy 138.258042 -438.837324) (xy 137.318242 -438.837324) (xy 137.306151 -438.836856) (xy 137.283146 -438.829407)
			(xy 137.263562 -438.815222) (xy 137.249311 -438.795686) (xy 137.241785 -438.772705) (xy 137.24128 -438.760616)
			(xy 137.24128 -438.147968) (xy 137.239735 -438.133476) (xy 137.238083 -438.104376) (xy 137.237978 -438.089802)
			(xy 136.335008 -438.089802) (xy 136.335008 -439.0898) (xy 139.237974 -439.0898) (xy 139.238067 -439.075226)
			(xy 139.23972 -439.046125) (xy 139.241276 -439.031634) (xy 139.241276 -437.94807) (xy 139.239732 -437.933578)
			(xy 139.238079 -437.904478) (xy 139.237974 -437.889904) (xy 139.238067 -437.87533) (xy 139.23972 -437.846229)
			(xy 139.241276 -437.831738) (xy 139.241276 -437.21909) (xy 139.241652 -437.206963) (xy 139.249152 -437.183897)
			(xy 139.263413 -437.164279) (xy 139.28304 -437.15003) (xy 139.306111 -437.142545) (xy 139.318238 -437.142128)
			(xy 140.258038 -437.142128) (xy 140.270154 -437.142579) (xy 140.293196 -437.150076) (xy 140.312797 -437.164323)
			(xy 140.327037 -437.183929) (xy 140.334525 -437.206974) (xy 140.335 -437.21909) (xy 140.335 -438.089802)
			(xy 142.237968 -438.089802) (xy 142.238085 -438.074717) (xy 142.239861 -438.044598) (xy 142.241524 -438.029604)
			(xy 142.241524 -436.950104) (xy 142.239854 -436.935111) (xy 142.238076 -436.904992) (xy 142.237968 -436.889906)
			(xy 142.238076 -436.87482) (xy 142.239858 -436.844702) (xy 142.241524 -436.829708) (xy 142.241524 -436.219092)
			(xy 142.241906 -436.207006) (xy 142.24938 -436.184017) (xy 142.263593 -436.164464) (xy 142.283153 -436.150262)
			(xy 142.306145 -436.1428) (xy 142.318232 -436.142384) (xy 143.258032 -436.142384) (xy 143.270107 -436.142837)
			(xy 143.293074 -436.150307) (xy 143.31261 -436.164507) (xy 143.326804 -436.184047) (xy 143.334267 -436.207016)
			(xy 143.33474 -436.219092) (xy 143.33474 -438.760616) (xy 143.33425 -438.772688) (xy 143.326787 -438.79565)
			(xy 143.312596 -438.815184) (xy 143.293065 -438.829379) (xy 143.270104 -438.836847) (xy 143.258032 -438.837324)
			(xy 142.318232 -438.837324) (xy 142.306153 -438.83686) (xy 142.283174 -438.829403) (xy 142.263624 -438.81521)
			(xy 142.249418 -438.795669) (xy 142.241947 -438.772695) (xy 142.241524 -438.760616) (xy 142.241524 -438.15)
			(xy 142.239853 -438.135007) (xy 142.238076 -438.104888) (xy 142.237968 -438.089802) (xy 140.335 -438.089802)
			(xy 140.335 -439.0898) (xy 144.237964 -439.0898) (xy 144.23808 -439.074715) (xy 144.239857 -439.044596)
			(xy 144.24152 -439.029602) (xy 144.24152 -437.950102) (xy 144.239849 -437.935109) (xy 144.238072 -437.90499)
			(xy 144.237964 -437.889904) (xy 144.238081 -437.874819) (xy 144.239857 -437.8447) (xy 144.24152 -437.829706)
			(xy 144.24152 -437.21909) (xy 144.241999 -437.207002) (xy 144.249456 -437.184004) (xy 144.26364 -437.164426)
			(xy 144.28317 -437.150176) (xy 144.306142 -437.14264) (xy 144.318228 -437.142128) (xy 145.258028 -437.142128)
			(xy 145.270141 -437.142493) (xy 145.293174 -437.150003) (xy 145.312749 -437.164277) (xy 145.326942 -437.183911)
			(xy 145.334357 -437.206975) (xy 145.334736 -437.21909) (xy 145.334736 -438.089802) (xy 146.23796 -438.089802)
			(xy 146.238077 -438.074717) (xy 146.239853 -438.044598) (xy 146.241516 -438.029604) (xy 146.241516 -436.950104)
			(xy 146.239846 -436.935111) (xy 146.238068 -436.904992) (xy 146.23796 -436.889906) (xy 146.238068 -436.87482)
			(xy 146.23985 -436.844702) (xy 146.241516 -436.829708) (xy 146.241516 -436.219092) (xy 146.241906 -436.207006)
			(xy 146.249379 -436.184019) (xy 146.26359 -436.164467) (xy 146.283148 -436.150264) (xy 146.306138 -436.142801)
			(xy 146.318224 -436.142384) (xy 147.258024 -436.142384) (xy 147.270099 -436.142844) (xy 147.293066 -436.150312)
			(xy 147.312601 -436.16451) (xy 147.326795 -436.184049) (xy 147.334259 -436.207017) (xy 147.334732 -436.219092)
			(xy 147.334732 -438.760616) (xy 147.33425 -438.772689) (xy 147.326786 -438.795653) (xy 147.312593 -438.815187)
			(xy 147.29306 -438.829382) (xy 147.270097 -438.836848) (xy 147.258024 -438.837324) (xy 146.318224 -438.837324)
			(xy 146.306144 -438.836867) (xy 146.283165 -438.829408) (xy 146.263616 -438.815213) (xy 146.24941 -438.795671)
			(xy 146.241939 -438.772696) (xy 146.241516 -438.760616) (xy 146.241516 -438.15) (xy 146.239845 -438.135007)
			(xy 146.238068 -438.104888) (xy 146.23796 -438.089802) (xy 145.334736 -438.089802) (xy 145.334736 -439.0898)
			(xy 148.237956 -439.0898) (xy 148.238073 -439.074715) (xy 148.239849 -439.044596) (xy 148.241512 -439.029602)
			(xy 148.241512 -437.950102) (xy 148.239841 -437.935109) (xy 148.238064 -437.90499) (xy 148.237956 -437.889904)
			(xy 148.238073 -437.874819) (xy 148.239849 -437.8447) (xy 148.241512 -437.829706) (xy 148.241512 -437.21909)
			(xy 148.241999 -437.207003) (xy 148.249455 -437.184007) (xy 148.263637 -437.164429) (xy 148.283165 -437.150178)
			(xy 148.306134 -437.142641) (xy 148.31822 -437.142128) (xy 149.25802 -437.142128) (xy 149.270133 -437.1425)
			(xy 149.293165 -437.150008) (xy 149.312741 -437.16428) (xy 149.326934 -437.183913) (xy 149.334349 -437.206976)
			(xy 149.334728 -437.21909) (xy 149.334728 -438.089802) (xy 150.237952 -438.089802) (xy 150.238069 -438.074717)
			(xy 150.239845 -438.044598) (xy 150.241508 -438.029604) (xy 150.241508 -436.950104) (xy 150.239838 -436.935111)
			(xy 150.23806 -436.904992) (xy 150.237952 -436.889906) (xy 150.23806 -436.87482) (xy 150.239842 -436.844702)
			(xy 150.241508 -436.829708) (xy 150.241508 -436.219092) (xy 150.241906 -436.207007) (xy 150.249378 -436.184021)
			(xy 150.263587 -436.16447) (xy 150.283143 -436.150267) (xy 150.306131 -436.142802) (xy 150.318216 -436.142384)
			(xy 151.258016 -436.142384) (xy 151.270091 -436.142851) (xy 151.293057 -436.150317) (xy 151.312593 -436.164513)
			(xy 151.326787 -436.18405) (xy 151.334251 -436.207017) (xy 151.334724 -436.219092) (xy 151.334724 -438.760616)
			(xy 151.33425 -438.77269) (xy 151.326785 -438.795655) (xy 151.31259 -438.81519) (xy 151.293055 -438.829385)
			(xy 151.27009 -438.83685) (xy 151.258016 -438.837324) (xy 150.318216 -438.837324) (xy 150.306144 -438.836822)
			(xy 150.28318 -438.829366) (xy 150.263644 -438.815179) (xy 150.249448 -438.795649) (xy 150.241983 -438.772688)
			(xy 150.241508 -438.760616) (xy 150.241508 -438.15) (xy 150.239837 -438.135007) (xy 150.23806 -438.104888)
			(xy 150.237952 -438.089802) (xy 149.334728 -438.089802) (xy 149.334728 -439.0898) (xy 152.237948 -439.0898)
			(xy 152.238065 -439.074715) (xy 152.239841 -439.044596) (xy 152.241504 -439.029602) (xy 152.241504 -437.950102)
			(xy 152.239833 -437.935109) (xy 152.238056 -437.90499) (xy 152.237948 -437.889904) (xy 152.238065 -437.874819)
			(xy 152.239841 -437.8447) (xy 152.241504 -437.829706) (xy 152.241504 -437.21909) (xy 152.241998 -437.207004)
			(xy 152.249453 -437.184009) (xy 152.263634 -437.164432) (xy 152.28316 -437.150181) (xy 152.306127 -437.142643)
			(xy 152.318212 -437.142128) (xy 153.258012 -437.142128) (xy 153.270124 -437.142506) (xy 153.293157 -437.150012)
			(xy 153.312732 -437.164283) (xy 153.326925 -437.183914) (xy 153.334341 -437.206976) (xy 153.33472 -437.21909)
			(xy 153.33472 -438.089802) (xy 154.237944 -438.089802) (xy 154.238061 -438.074717) (xy 154.239837 -438.044598)
			(xy 154.2415 -438.029604) (xy 154.2415 -436.950104) (xy 154.23983 -436.935111) (xy 154.238052 -436.904992)
			(xy 154.237944 -436.889906) (xy 154.238052 -436.87482) (xy 154.239834 -436.844702) (xy 154.2415 -436.829708)
			(xy 154.2415 -436.219092) (xy 154.241958 -436.207016) (xy 154.249423 -436.184047) (xy 154.263621 -436.16451)
			(xy 154.283162 -436.150316) (xy 154.306132 -436.142855) (xy 154.318208 -436.142384) (xy 155.258008 -436.142384)
			(xy 155.270082 -436.142857) (xy 155.293048 -436.150321) (xy 155.312584 -436.164516) (xy 155.326779 -436.184052)
			(xy 155.334243 -436.207018) (xy 155.334716 -436.219092) (xy 155.334716 -438.760616) (xy 155.334249 -438.772691)
			(xy 155.326783 -438.795657) (xy 155.312587 -438.815193) (xy 155.29305 -438.829387) (xy 155.270083 -438.836851)
			(xy 155.258008 -438.837324) (xy 154.318208 -438.837324) (xy 154.306135 -438.836829) (xy 154.283171 -438.829371)
			(xy 154.263635 -438.815182) (xy 154.24944 -438.79565) (xy 154.241975 -438.772688) (xy 154.2415 -438.760616)
			(xy 154.2415 -438.15) (xy 154.239829 -438.135007) (xy 154.238052 -438.104888) (xy 154.237944 -438.089802)
			(xy 153.33472 -438.089802) (xy 153.33472 -439.0898) (xy 156.23794 -439.0898) (xy 156.238057 -439.074715)
			(xy 156.239833 -439.044596) (xy 156.241496 -439.029602) (xy 156.241496 -437.950102) (xy 156.239825 -437.935109)
			(xy 156.238048 -437.90499) (xy 156.23794 -437.889904) (xy 156.238057 -437.874819) (xy 156.239833 -437.8447)
			(xy 156.241496 -437.829706) (xy 156.241496 -437.21909) (xy 156.241998 -437.207004) (xy 156.249452 -437.184011)
			(xy 156.263631 -437.164435) (xy 156.283155 -437.150183) (xy 156.30612 -437.142644) (xy 156.318204 -437.142128)
			(xy 157.258004 -437.142128) (xy 157.270116 -437.142513) (xy 157.293148 -437.150017) (xy 157.312724 -437.164286)
			(xy 157.326917 -437.183916) (xy 157.334333 -437.206977) (xy 157.334712 -437.21909) (xy 157.334712 -438.089802)
			(xy 314.118498 -438.089802) (xy 314.119021 -438.057222) (xy 314.126995 -437.992552) (xy 314.14281 -437.929341)
			(xy 314.166231 -437.868536) (xy 314.196905 -437.811048) (xy 314.234374 -437.757739) (xy 314.278076 -437.709407)
			(xy 314.302394 -437.68772) (xy 314.382912 -437.523382) (xy 314.387613 -437.512866) (xy 314.391103 -437.490107)
			(xy 314.387618 -437.467348) (xy 314.382912 -437.456834) (xy 314.301886 -437.291734) (xy 314.277609 -437.270053)
			(xy 314.234013 -437.221717) (xy 314.19664 -437.168424) (xy 314.166049 -437.110969) (xy 314.142696 -437.050211)
			(xy 314.126931 -436.987057) (xy 314.118988 -436.922452) (xy 314.118498 -436.889906) (xy 314.119234 -436.850581)
			(xy 314.130833 -436.772791) (xy 314.141612 -436.734966) (xy 314.141612 -436.219092) (xy 314.142006 -436.207007)
			(xy 314.149478 -436.18402) (xy 314.163688 -436.164469) (xy 314.183246 -436.150265) (xy 314.206235 -436.142802)
			(xy 314.21832 -436.142384) (xy 315.15812 -436.142384) (xy 315.170195 -436.142847) (xy 315.193161 -436.150314)
			(xy 315.212697 -436.164511) (xy 315.226891 -436.18405) (xy 315.234355 -436.207017) (xy 315.234828 -436.219092)
			(xy 315.234828 -438.760616) (xy 315.23435 -438.772689) (xy 315.226885 -438.795654) (xy 315.212691 -438.815189)
			(xy 315.193157 -438.829383) (xy 315.170193 -438.836849) (xy 315.15812 -438.837324) (xy 314.21832 -438.837324)
			(xy 314.20624 -438.83687) (xy 314.183261 -438.82941) (xy 314.163711 -438.815214) (xy 314.149506 -438.795672)
			(xy 314.142035 -438.772696) (xy 314.141612 -438.760616) (xy 314.141612 -438.244742) (xy 314.130814 -438.20692)
			(xy 314.119206 -438.129129) (xy 314.118498 -438.089802) (xy 157.334712 -438.089802) (xy 157.334712 -439.0898)
			(xy 316.118494 -439.0898) (xy 316.119017 -439.05722) (xy 316.126991 -438.99255) (xy 316.142806 -438.929339)
			(xy 316.166227 -438.868534) (xy 316.196902 -438.811046) (xy 316.234371 -438.757737) (xy 316.278072 -438.709405)
			(xy 316.30239 -438.687718) (xy 316.382908 -438.52338) (xy 316.387611 -438.512864) (xy 316.3911 -438.490105)
			(xy 316.387614 -438.467346) (xy 316.382908 -438.456832) (xy 316.301882 -438.291732) (xy 316.277603 -438.270053)
			(xy 316.234007 -438.221717) (xy 316.196635 -438.168423) (xy 316.166044 -438.110968) (xy 316.142691 -438.050209)
			(xy 316.126926 -437.987055) (xy 316.118984 -437.92245) (xy 316.118494 -437.889904) (xy 316.11923 -437.850579)
			(xy 316.130829 -437.772789) (xy 316.141608 -437.734964) (xy 316.141608 -437.21909) (xy 316.142098 -437.207003)
			(xy 316.149554 -437.184008) (xy 316.163736 -437.164431) (xy 316.183262 -437.150179) (xy 316.206231 -437.142642)
			(xy 316.218316 -437.142128) (xy 317.158116 -437.142128) (xy 317.170229 -437.142503) (xy 317.193261 -437.15001)
			(xy 317.212836 -437.164281) (xy 317.227029 -437.183914) (xy 317.234445 -437.206976) (xy 317.234824 -437.21909)
			(xy 317.234824 -438.089802) (xy 318.11849 -438.089802) (xy 318.119016 -438.057222) (xy 318.126989 -437.992553)
			(xy 318.142804 -437.929341) (xy 318.166225 -437.868536) (xy 318.196899 -437.811048) (xy 318.234367 -437.757739)
			(xy 318.278069 -437.709407) (xy 318.302386 -437.68772) (xy 318.382904 -437.523382) (xy 318.387605 -437.512865)
			(xy 318.391095 -437.490107) (xy 318.38761 -437.467348) (xy 318.382904 -437.456834) (xy 318.301878 -437.291734)
			(xy 318.277599 -437.270055) (xy 318.234004 -437.221719) (xy 318.196631 -437.168425) (xy 318.16604 -437.110969)
			(xy 318.142688 -437.050211) (xy 318.126923 -436.987057) (xy 318.11898 -436.922452) (xy 318.11849 -436.889906)
			(xy 318.119227 -436.850581) (xy 318.130825 -436.772791) (xy 318.141604 -436.734966) (xy 318.141604 -436.219092)
			(xy 318.142006 -436.207008) (xy 318.149477 -436.184023) (xy 318.163686 -436.164471) (xy 318.183241 -436.150268)
			(xy 318.206228 -436.142803) (xy 318.218312 -436.142384) (xy 319.158112 -436.142384) (xy 319.170186 -436.142854)
			(xy 319.193153 -436.150319) (xy 319.212689 -436.164514) (xy 319.226883 -436.184051) (xy 319.234347 -436.207018)
			(xy 319.23482 -436.219092) (xy 319.23482 -438.760616) (xy 319.234349 -438.77269) (xy 319.226884 -438.795656)
			(xy 319.212689 -438.815191) (xy 319.193152 -438.829386) (xy 319.170186 -438.83685) (xy 319.158112 -438.837324)
			(xy 318.218312 -438.837324) (xy 318.20624 -438.836826) (xy 318.183276 -438.829369) (xy 318.16374 -438.81518)
			(xy 318.149544 -438.79565) (xy 318.142079 -438.772688) (xy 318.141604 -438.760616) (xy 318.141604 -438.244742)
			(xy 318.130805 -438.20692) (xy 318.119198 -438.129129) (xy 318.11849 -438.089802) (xy 317.234824 -438.089802)
			(xy 317.234824 -439.0898) (xy 320.118486 -439.0898) (xy 320.119012 -439.05722) (xy 320.126985 -438.992551)
			(xy 320.142801 -438.92934) (xy 320.166221 -438.868535) (xy 320.196895 -438.811047) (xy 320.234363 -438.757737)
			(xy 320.278065 -438.709406) (xy 320.302382 -438.687718) (xy 320.3829 -438.52338) (xy 320.387603 -438.512864)
			(xy 320.391093 -438.490105) (xy 320.387606 -438.467346) (xy 320.3829 -438.456832) (xy 320.301874 -438.291732)
			(xy 320.277593 -438.270055) (xy 320.233998 -438.221718) (xy 320.196626 -438.168424) (xy 320.166035 -438.110968)
			(xy 320.142683 -438.050209) (xy 320.126918 -437.987055) (xy 320.118976 -437.92245) (xy 320.118486 -437.889904)
			(xy 320.119222 -437.850579) (xy 320.130821 -437.772789) (xy 320.1416 -437.734964) (xy 320.1416 -437.21909)
			(xy 320.142098 -437.207004) (xy 320.149553 -437.18401) (xy 320.163733 -437.164434) (xy 320.183257 -437.150182)
			(xy 320.206224 -437.142643) (xy 320.218308 -437.142128) (xy 321.158108 -437.142128) (xy 321.17022 -437.14251)
			(xy 321.193252 -437.150015) (xy 321.212828 -437.164284) (xy 321.227021 -437.183915) (xy 321.234437 -437.206976)
			(xy 321.234816 -437.21909) (xy 321.234816 -438.089802) (xy 322.118482 -438.089802) (xy 322.11901 -438.057222)
			(xy 322.126984 -437.992553) (xy 322.142799 -437.929342) (xy 322.166219 -437.868537) (xy 322.196892 -437.811049)
			(xy 322.23436 -437.75774) (xy 322.278061 -437.709408) (xy 322.302378 -437.68772) (xy 322.382896 -437.523382)
			(xy 322.387598 -437.512866) (xy 322.391088 -437.490107) (xy 322.387602 -437.467348) (xy 322.382896 -437.456834)
			(xy 322.30187 -437.291734) (xy 322.27761 -437.270034) (xy 322.23401 -437.221704) (xy 322.196633 -437.168415)
			(xy 322.166039 -437.110963) (xy 322.142683 -437.050207) (xy 322.126916 -436.987055) (xy 322.118972 -436.922451)
			(xy 322.118482 -436.889906) (xy 322.119219 -436.850581) (xy 322.130817 -436.772791) (xy 322.141596 -436.734966)
			(xy 322.141596 -436.219092) (xy 322.142058 -436.207017) (xy 322.149523 -436.184049) (xy 322.16372 -436.164511)
			(xy 322.183259 -436.150317) (xy 322.206229 -436.142856) (xy 322.218304 -436.142384) (xy 323.158104 -436.142384)
			(xy 323.170178 -436.142861) (xy 323.193144 -436.150323) (xy 323.21268 -436.164517) (xy 323.226875 -436.184053)
			(xy 323.234339 -436.207018) (xy 323.234812 -436.219092) (xy 323.234812 -438.760616) (xy 323.234349 -438.772691)
			(xy 323.226883 -438.795658) (xy 323.212686 -438.815194) (xy 323.193147 -438.829388) (xy 323.170179 -438.836851)
			(xy 323.158104 -438.837324) (xy 322.218304 -438.837324) (xy 322.206231 -438.836833) (xy 322.183267 -438.829373)
			(xy 322.163731 -438.815183) (xy 322.149536 -438.795651) (xy 322.142071 -438.772689) (xy 322.141596 -438.760616)
			(xy 322.141596 -438.244742) (xy 322.130797 -438.20692) (xy 322.11919 -438.129129) (xy 322.118482 -438.089802)
			(xy 321.234816 -438.089802) (xy 321.234816 -439.0898) (xy 324.118478 -439.0898) (xy 324.119006 -439.05722)
			(xy 324.12698 -438.992551) (xy 324.142795 -438.92934) (xy 324.166215 -438.868535) (xy 324.196889 -438.811047)
			(xy 324.234356 -438.757738) (xy 324.278057 -438.709406) (xy 324.302374 -438.687718) (xy 324.382892 -438.52338)
			(xy 324.387595 -438.512864) (xy 324.391085 -438.490105) (xy 324.387599 -438.467346) (xy 324.382892 -438.456832)
			(xy 324.301866 -438.291732) (xy 324.277604 -438.270034) (xy 324.234004 -438.221704) (xy 324.196628 -438.168414)
			(xy 324.166034 -438.110962) (xy 324.142678 -438.050205) (xy 324.126911 -437.987053) (xy 324.118968 -437.922449)
			(xy 324.118478 -437.889904) (xy 324.119215 -437.850579) (xy 324.130813 -437.772789) (xy 324.141592 -437.734964)
			(xy 324.141592 -437.21909) (xy 324.142098 -437.207005) (xy 324.149552 -437.184012) (xy 324.16373 -437.164436)
			(xy 324.183252 -437.150184) (xy 324.206217 -437.142644) (xy 324.2183 -437.142128) (xy 325.1581 -437.142128)
			(xy 325.170212 -437.142516) (xy 325.193244 -437.150019) (xy 325.212819 -437.164287) (xy 325.227013 -437.183916)
			(xy 325.234429 -437.206977) (xy 325.234808 -437.21909) (xy 325.234808 -438.089802) (xy 326.118474 -438.089802)
			(xy 326.119005 -438.057223) (xy 326.126978 -437.992553) (xy 326.142793 -437.929342) (xy 326.166213 -437.868538)
			(xy 326.196886 -437.81105) (xy 326.234353 -437.75774) (xy 326.278053 -437.709408) (xy 326.30237 -437.68772)
			(xy 326.382888 -437.523382) (xy 326.38759 -437.512866) (xy 326.391081 -437.490107) (xy 326.387595 -437.467348)
			(xy 326.382888 -437.456834) (xy 326.301862 -437.291734) (xy 326.2776 -437.270036) (xy 326.234001 -437.221705)
			(xy 326.196624 -437.168416) (xy 326.16603 -437.110963) (xy 326.142675 -437.050207) (xy 326.126908 -436.987055)
			(xy 326.118964 -436.922451) (xy 326.118474 -436.889906) (xy 326.119211 -436.850581) (xy 326.13081 -436.772792)
			(xy 326.141588 -436.734966) (xy 326.141588 -436.219092) (xy 326.142057 -436.207017) (xy 326.149522 -436.184051)
			(xy 326.163717 -436.164514) (xy 326.183254 -436.15032) (xy 326.206221 -436.142857) (xy 326.218296 -436.142384)
			(xy 327.158096 -436.142384) (xy 327.17017 -436.142868) (xy 327.193135 -436.150328) (xy 327.212672 -436.16452)
			(xy 327.226867 -436.184054) (xy 327.234331 -436.207019) (xy 327.234804 -436.219092) (xy 327.234804 -438.760616)
			(xy 327.234349 -438.772692) (xy 327.226882 -438.79566) (xy 327.212683 -438.815197) (xy 327.193142 -438.829391)
			(xy 327.170172 -438.836852) (xy 327.158096 -438.837324) (xy 326.218296 -438.837324) (xy 326.206223 -438.836839)
			(xy 326.183258 -438.829378) (xy 326.163723 -438.815186) (xy 326.149528 -438.795652) (xy 326.142063 -438.772689)
			(xy 326.141588 -438.760616) (xy 326.141588 -438.244742) (xy 326.130789 -438.20692) (xy 326.119182 -438.129129)
			(xy 326.118474 -438.089802) (xy 325.234808 -438.089802) (xy 325.234808 -439.0898) (xy 328.11847 -439.0898)
			(xy 328.119001 -439.057221) (xy 328.126975 -438.992551) (xy 328.142789 -438.929341) (xy 328.166209 -438.868536)
			(xy 328.196882 -438.811048) (xy 328.234349 -438.757738) (xy 328.278049 -438.709406) (xy 328.302366 -438.687718)
			(xy 328.382884 -438.52338) (xy 328.387588 -438.512864) (xy 328.391078 -438.490105) (xy 328.387591 -438.467346)
			(xy 328.382884 -438.456832) (xy 328.301858 -438.291732) (xy 328.277594 -438.270036) (xy 328.233995 -438.221705)
			(xy 328.196619 -438.168415) (xy 328.166025 -438.110962) (xy 328.14267 -438.050206) (xy 328.126903 -437.987054)
			(xy 328.11896 -437.922449) (xy 328.11847 -437.889904) (xy 328.119207 -437.850579) (xy 328.130806 -437.77279)
			(xy 328.141584 -437.734964) (xy 328.141584 -437.21909) (xy 328.142 -437.206996) (xy 328.149465 -437.183987)
			(xy 328.163663 -437.164404) (xy 328.18321 -437.150155) (xy 328.206199 -437.142631) (xy 328.218292 -437.142128)
			(xy 329.158092 -437.142128) (xy 329.170203 -437.142523) (xy 329.193235 -437.150024) (xy 329.212811 -437.16429)
			(xy 329.227005 -437.183918) (xy 329.234421 -437.206977) (xy 329.2348 -437.21909) (xy 329.2348 -438.089802)
			(xy 331.118464 -438.089802) (xy 331.118965 -438.057221) (xy 331.126939 -437.99255) (xy 331.142757 -437.929337)
			(xy 331.166181 -437.868531) (xy 331.196859 -437.811043) (xy 331.234333 -437.757735) (xy 331.27804 -437.709406)
			(xy 331.30236 -437.68772) (xy 331.382878 -437.523382) (xy 331.387581 -437.512866) (xy 331.391072 -437.490107)
			(xy 331.387585 -437.467348) (xy 331.382878 -437.456834) (xy 331.301852 -437.291734) (xy 331.277588 -437.270038)
			(xy 331.233989 -437.221707) (xy 331.196613 -437.168417) (xy 331.166019 -437.110964) (xy 331.142664 -437.050208)
			(xy 331.126898 -436.987056) (xy 331.118954 -436.922451) (xy 331.118464 -436.889906) (xy 331.119164 -436.85078)
			(xy 331.130639 -436.773373) (xy 331.141324 -436.735728) (xy 331.141324 -436.219092) (xy 331.14171 -436.20698)
			(xy 331.149214 -436.183949) (xy 331.163483 -436.164374) (xy 331.183112 -436.15018) (xy 331.206173 -436.142764)
			(xy 331.218286 -436.142384) (xy 332.158086 -436.142384) (xy 332.170179 -436.14282) (xy 332.193187 -436.150278)
			(xy 332.212771 -436.164471) (xy 332.22702 -436.184014) (xy 332.234545 -436.207) (xy 332.235048 -436.219092)
			(xy 332.235048 -438.760616) (xy 332.234598 -438.772721) (xy 332.2271 -438.795741) (xy 332.212845 -438.815309)
			(xy 332.193234 -438.829505) (xy 332.170192 -438.836934) (xy 332.158086 -438.837324) (xy 331.218286 -438.837324)
			(xy 331.206192 -438.836904) (xy 331.183185 -438.829439) (xy 331.163602 -438.815242) (xy 331.149353 -438.795696)
			(xy 331.141828 -438.772709) (xy 331.141324 -438.760616) (xy 331.141324 -438.24398) (xy 331.130637 -438.206335)
			(xy 331.11916 -438.128928) (xy 331.118464 -438.089802) (xy 329.2348 -438.089802) (xy 329.2348 -439.0898)
			(xy 333.11846 -439.0898) (xy 333.118961 -439.057219) (xy 333.126936 -438.992548) (xy 333.142753 -438.929335)
			(xy 333.166177 -438.868529) (xy 333.196856 -438.811042) (xy 333.234329 -438.757734) (xy 333.278036 -438.709404)
			(xy 333.302356 -438.687718) (xy 333.382874 -438.52338) (xy 333.387578 -438.512864) (xy 333.391069 -438.490105)
			(xy 333.387582 -438.467346) (xy 333.382874 -438.456832) (xy 333.301848 -438.291732) (xy 333.277582 -438.270038)
			(xy 333.233984 -438.221706) (xy 333.196608 -438.168416) (xy 333.166014 -438.110963) (xy 333.14266 -438.050206)
			(xy 333.126893 -437.987054) (xy 333.11895 -437.922449) (xy 333.11846 -437.889904) (xy 333.11916 -437.850778)
			(xy 333.130634 -437.773371) (xy 333.14132 -437.735726) (xy 333.14132 -437.21909) (xy 333.141803 -437.206977)
			(xy 333.149291 -437.183936) (xy 333.163531 -437.164336) (xy 333.183129 -437.150095) (xy 333.206169 -437.142604)
			(xy 333.218282 -437.142128) (xy 334.158082 -437.142128) (xy 334.170203 -437.142575) (xy 334.193259 -437.150061)
			(xy 334.212874 -437.164306) (xy 334.227126 -437.183916) (xy 334.23462 -437.206969) (xy 334.235044 -437.21909)
			(xy 334.235044 -438.089802) (xy 335.118456 -438.089802) (xy 335.11896 -438.057221) (xy 335.126934 -437.99255)
			(xy 335.142751 -437.929338) (xy 335.166175 -437.868532) (xy 335.196853 -437.811044) (xy 335.234326 -437.757736)
			(xy 335.278032 -437.709406) (xy 335.302352 -437.68772) (xy 335.38287 -437.523382) (xy 335.387573 -437.512866)
			(xy 335.391065 -437.490107) (xy 335.387578 -437.467348) (xy 335.38287 -437.456834) (xy 335.301844 -437.291734)
			(xy 335.277578 -437.27004) (xy 335.23398 -437.221708) (xy 335.196604 -437.168418) (xy 335.166011 -437.110965)
			(xy 335.142656 -437.050208) (xy 335.12689 -436.987056) (xy 335.118946 -436.922451) (xy 335.118456 -436.889906)
			(xy 335.119156 -436.85078) (xy 335.130631 -436.773373) (xy 335.141316 -436.735728) (xy 335.141316 -436.219092)
			(xy 335.14171 -436.206981) (xy 335.149213 -436.183951) (xy 335.16348 -436.164376) (xy 335.183107 -436.150183)
			(xy 335.206166 -436.142765) (xy 335.218278 -436.142384) (xy 336.158078 -436.142384) (xy 336.170171 -436.142827)
			(xy 336.193178 -436.150283) (xy 336.212762 -436.164474) (xy 336.227012 -436.184016) (xy 336.234537 -436.207001)
			(xy 336.23504 -436.219092) (xy 336.23504 -438.760616) (xy 336.234598 -438.772722) (xy 336.227099 -438.795743)
			(xy 336.212843 -438.815312) (xy 336.193229 -438.829508) (xy 336.170185 -438.836935) (xy 336.158078 -438.837324)
			(xy 335.218278 -438.837324) (xy 335.206184 -438.836911) (xy 335.183176 -438.829444) (xy 335.163594 -438.815245)
			(xy 335.149345 -438.795698) (xy 335.14182 -438.772709) (xy 335.141316 -438.760616) (xy 335.141316 -438.24398)
			(xy 335.130629 -438.206335) (xy 335.119152 -438.128928) (xy 335.118456 -438.089802) (xy 334.235044 -438.089802)
			(xy 334.235044 -439.0898) (xy 337.118452 -439.0898) (xy 337.118956 -439.057219) (xy 337.12693 -438.992548)
			(xy 337.142748 -438.929336) (xy 337.166171 -438.86853) (xy 337.196849 -438.811042) (xy 337.234322 -438.757734)
			(xy 337.278028 -438.709404) (xy 337.302348 -438.687718) (xy 337.382866 -438.52338) (xy 337.387566 -438.512863)
			(xy 337.391052 -438.490105) (xy 337.387569 -438.467347) (xy 337.382866 -438.456832) (xy 337.30184 -438.291732)
			(xy 337.277573 -438.27004) (xy 337.233974 -438.221708) (xy 337.196599 -438.168417) (xy 337.166006 -438.110963)
			(xy 337.142652 -438.050207) (xy 337.126885 -437.987054) (xy 337.118942 -437.922449) (xy 337.118452 -437.889904)
			(xy 337.119152 -437.850778) (xy 337.130627 -437.773371) (xy 337.141312 -437.735726) (xy 337.141312 -437.21909)
			(xy 337.141803 -437.206978) (xy 337.14929 -437.183938) (xy 337.163528 -437.164339) (xy 337.183124 -437.150097)
			(xy 337.206162 -437.142606) (xy 337.218274 -437.142128) (xy 338.158074 -437.142128) (xy 338.170194 -437.142582)
			(xy 338.193251 -437.150066) (xy 338.212865 -437.164309) (xy 338.227118 -437.183917) (xy 338.234612 -437.20697)
			(xy 338.235036 -437.21909) (xy 338.235036 -438.089802) (xy 339.118448 -438.089802) (xy 339.118954 -438.057222)
			(xy 339.126929 -437.99255) (xy 339.142746 -437.929338) (xy 339.166169 -437.868532) (xy 339.196846 -437.811045)
			(xy 339.234319 -437.757736) (xy 339.278025 -437.709406) (xy 339.302344 -437.68772) (xy 339.382862 -437.523382)
			(xy 339.387561 -437.512865) (xy 339.391048 -437.490107) (xy 339.387565 -437.467349) (xy 339.382862 -437.456834)
			(xy 339.301836 -437.291734) (xy 339.277569 -437.270042) (xy 339.233971 -437.22171) (xy 339.196596 -437.168419)
			(xy 339.166002 -437.110965) (xy 339.142648 -437.050208) (xy 339.126881 -436.987056) (xy 339.118938 -436.922451)
			(xy 339.118448 -436.889906) (xy 339.119149 -436.85078) (xy 339.130623 -436.773373) (xy 339.141308 -436.735728)
			(xy 339.141308 -436.219092) (xy 339.141709 -436.206982) (xy 339.149212 -436.183953) (xy 339.163477 -436.164379)
			(xy 339.183102 -436.150185) (xy 339.206158 -436.142766) (xy 339.21827 -436.142384) (xy 340.15807 -436.142384)
			(xy 340.170162 -436.142834) (xy 340.193169 -436.150288) (xy 340.212754 -436.164477) (xy 340.227004 -436.184017)
			(xy 340.234529 -436.207001) (xy 340.235032 -436.219092) (xy 340.235032 -438.760616) (xy 340.234598 -438.772723)
			(xy 340.227098 -438.795745) (xy 340.21284 -438.815315) (xy 340.193224 -438.82951) (xy 340.170178 -438.836936)
			(xy 340.15807 -438.837324) (xy 339.21827 -438.837324) (xy 339.206175 -438.836918) (xy 339.183168 -438.829448)
			(xy 339.163585 -438.815247) (xy 339.149337 -438.795699) (xy 339.141812 -438.77271) (xy 339.141308 -438.760616)
			(xy 339.141308 -438.24398) (xy 339.130621 -438.206335) (xy 339.119144 -438.128928) (xy 339.118448 -438.089802)
			(xy 338.235036 -438.089802) (xy 338.235036 -439.0898) (xy 341.118444 -439.0898) (xy 341.11895 -439.05722)
			(xy 341.126925 -438.992548) (xy 341.142742 -438.929336) (xy 341.166165 -438.868531) (xy 341.196843 -438.811043)
			(xy 341.234315 -438.757734) (xy 341.278021 -438.709405) (xy 341.30234 -438.687718) (xy 341.382858 -438.52338)
			(xy 341.387558 -438.512863) (xy 341.391045 -438.490105) (xy 341.387562 -438.467347) (xy 341.382858 -438.456832)
			(xy 341.301832 -438.291732) (xy 341.277563 -438.270042) (xy 341.233965 -438.221709) (xy 341.19659 -438.168418)
			(xy 341.165997 -438.110964) (xy 341.142643 -438.050207) (xy 341.126877 -437.987054) (xy 341.118934 -437.92245)
			(xy 341.118444 -437.889904) (xy 341.119145 -437.850778) (xy 341.130619 -437.773371) (xy 341.141304 -437.735726)
			(xy 341.141304 -437.21909) (xy 341.141803 -437.206978) (xy 341.149289 -437.183941) (xy 341.163525 -437.164342)
			(xy 341.183119 -437.1501) (xy 341.206154 -437.142607) (xy 341.218266 -437.142128) (xy 342.158066 -437.142128)
			(xy 342.170186 -437.142589) (xy 342.193242 -437.15007) (xy 342.212857 -437.164312) (xy 342.22711 -437.183918)
			(xy 342.234604 -437.20697) (xy 342.235028 -437.21909) (xy 342.235028 -438.089802) (xy 343.11844 -438.089802)
			(xy 343.118949 -438.057222) (xy 343.126923 -437.992551) (xy 343.14274 -437.929339) (xy 343.166163 -437.868533)
			(xy 343.19684 -437.811045) (xy 343.234312 -437.757737) (xy 343.278017 -437.709407) (xy 343.302336 -437.68772)
			(xy 343.382854 -437.523382) (xy 343.387553 -437.512865) (xy 343.391041 -437.490107) (xy 343.387557 -437.467349)
			(xy 343.382854 -437.456834) (xy 343.301828 -437.291734) (xy 343.277559 -437.270044) (xy 343.233961 -437.221711)
			(xy 343.196587 -437.168419) (xy 343.165994 -437.110966) (xy 343.14264 -437.050209) (xy 343.126873 -436.987056)
			(xy 343.11893 -436.922451) (xy 343.11844 -436.889906) (xy 343.119141 -436.85078) (xy 343.130615 -436.773373)
			(xy 343.1413 -436.735728) (xy 343.1413 -436.219092) (xy 343.141709 -436.206983) (xy 343.149211 -436.183955)
			(xy 343.163474 -436.164382) (xy 343.183097 -436.150188) (xy 343.206151 -436.142767) (xy 343.218262 -436.142384)
			(xy 344.158062 -436.142384) (xy 344.170154 -436.142841) (xy 344.193161 -436.150292) (xy 344.212745 -436.16448)
			(xy 344.226995 -436.184019) (xy 344.234521 -436.207002) (xy 344.235024 -436.219092) (xy 344.235024 -438.760616)
			(xy 344.234598 -438.772723) (xy 344.227097 -438.795747) (xy 344.212837 -438.815318) (xy 344.193219 -438.829513)
			(xy 344.170171 -438.836937) (xy 344.158062 -438.837324) (xy 343.218262 -438.837324) (xy 343.206167 -438.836924)
			(xy 343.183159 -438.829453) (xy 343.163577 -438.81525) (xy 343.149329 -438.795701) (xy 343.141804 -438.77271)
			(xy 343.1413 -438.760616) (xy 343.1413 -438.24398) (xy 343.130613 -438.206335) (xy 343.119136 -438.128928)
			(xy 343.11844 -438.089802) (xy 342.235028 -438.089802) (xy 342.235028 -439.0898) (xy 345.118436 -439.0898)
			(xy 345.118945 -439.05722) (xy 345.126919 -438.992549) (xy 345.142736 -438.929337) (xy 345.166159 -438.868531)
			(xy 345.196836 -438.811043) (xy 345.234308 -438.757735) (xy 345.278013 -438.709405) (xy 345.302332 -438.687718)
			(xy 345.38285 -438.52338) (xy 345.387551 -438.512864) (xy 345.391038 -438.490105) (xy 345.387554 -438.467347)
			(xy 345.38285 -438.456832) (xy 345.301824 -438.291732) (xy 345.277553 -438.270044) (xy 345.233956 -438.22171)
			(xy 345.196582 -438.168418) (xy 345.165989 -438.110965) (xy 345.142635 -438.050207) (xy 345.126869 -437.987054)
			(xy 345.118926 -437.92245) (xy 345.118436 -437.889904) (xy 345.119137 -437.850778) (xy 345.130611 -437.773371)
			(xy 345.141296 -437.735726) (xy 345.141296 -437.21909) (xy 345.141803 -437.206979) (xy 345.149288 -437.183943)
			(xy 345.163522 -437.164345) (xy 345.183114 -437.150102) (xy 345.206147 -437.142608) (xy 345.218258 -437.142128)
			(xy 346.158058 -437.142128) (xy 346.170178 -437.142595) (xy 346.193233 -437.150075) (xy 346.212848 -437.164315)
			(xy 346.227101 -437.18392) (xy 346.234596 -437.206971) (xy 346.23502 -437.21909) (xy 346.23502 -439.0898)
			(xy 383.237994 -439.0898) (xy 383.238086 -439.075226) (xy 383.23974 -439.046125) (xy 383.241296 -439.031634)
			(xy 383.241296 -437.94807) (xy 383.239752 -437.933578) (xy 383.238099 -437.904478) (xy 383.237994 -437.889904)
			(xy 383.238087 -437.87533) (xy 383.23974 -437.846229) (xy 383.241296 -437.831738) (xy 383.241296 -437.21909)
			(xy 383.241803 -437.206979) (xy 383.249288 -437.183943) (xy 383.263522 -437.164345) (xy 383.283114 -437.150102)
			(xy 383.306147 -437.142608) (xy 383.318258 -437.142128) (xy 384.258058 -437.142128) (xy 384.270178 -437.142595)
			(xy 384.293233 -437.150075) (xy 384.312848 -437.164315) (xy 384.327101 -437.18392) (xy 384.334596 -437.206971)
			(xy 384.33502 -437.21909) (xy 384.33502 -438.089802) (xy 385.23799 -438.089802) (xy 385.238083 -438.075228)
			(xy 385.239736 -438.046127) (xy 385.241292 -438.031636) (xy 385.241292 -436.948072) (xy 385.239748 -436.93358)
			(xy 385.238095 -436.90448) (xy 385.23799 -436.889906) (xy 385.238083 -436.875332) (xy 385.239736 -436.846231)
			(xy 385.241292 -436.83174) (xy 385.241292 -436.219092) (xy 385.241709 -436.206983) (xy 385.24921 -436.183957)
			(xy 385.263472 -436.164385) (xy 385.283092 -436.15019) (xy 385.306144 -436.142768) (xy 385.318254 -436.142384)
			(xy 386.258054 -436.142384) (xy 386.270146 -436.142847) (xy 386.293152 -436.150297) (xy 386.312737 -436.164483)
			(xy 386.326987 -436.18402) (xy 386.334512 -436.207002) (xy 386.335016 -436.219092) (xy 386.335016 -438.760616)
			(xy 386.334598 -438.772724) (xy 386.327096 -438.795749) (xy 386.312834 -438.815321) (xy 386.293214 -438.829515)
			(xy 386.270163 -438.836939) (xy 386.258054 -438.837324) (xy 385.318254 -438.837324) (xy 385.306158 -438.836931)
			(xy 385.28315 -438.829457) (xy 385.263568 -438.815253) (xy 385.24932 -438.795702) (xy 385.241796 -438.77271)
			(xy 385.241292 -438.760616) (xy 385.241292 -438.147968) (xy 385.239747 -438.133476) (xy 385.238095 -438.104376)
			(xy 385.23799 -438.089802) (xy 384.33502 -438.089802) (xy 384.33502 -439.0898) (xy 387.237986 -439.0898)
			(xy 387.238078 -439.075226) (xy 387.239732 -439.046125) (xy 387.241288 -439.031634) (xy 387.241288 -437.94807)
			(xy 387.239744 -437.933578) (xy 387.238091 -437.904478) (xy 387.237986 -437.889904) (xy 387.238079 -437.87533)
			(xy 387.239732 -437.846229) (xy 387.241288 -437.831738) (xy 387.241288 -437.21909) (xy 387.241803 -437.20698)
			(xy 387.249287 -437.183945) (xy 387.263519 -437.164348) (xy 387.283109 -437.150105) (xy 387.30614 -437.142609)
			(xy 387.31825 -437.142128) (xy 388.25805 -437.142128) (xy 388.270166 -437.142569) (xy 388.293209 -437.150069)
			(xy 388.312809 -437.164319) (xy 388.32705 -437.183927) (xy 388.334537 -437.206974) (xy 388.335012 -437.21909)
			(xy 388.335012 -438.089802) (xy 389.237982 -438.089802) (xy 389.238075 -438.075228) (xy 389.239728 -438.046127)
			(xy 389.241284 -438.031636) (xy 389.241284 -436.948072) (xy 389.23974 -436.93358) (xy 389.238087 -436.90448)
			(xy 389.237982 -436.889906) (xy 389.238075 -436.875332) (xy 389.239728 -436.846231) (xy 389.241284 -436.83174)
			(xy 389.241284 -436.219092) (xy 389.241709 -436.206984) (xy 389.249209 -436.183959) (xy 389.263469 -436.164388)
			(xy 389.283087 -436.150193) (xy 389.306137 -436.142769) (xy 389.318246 -436.142384) (xy 390.258046 -436.142384)
			(xy 390.270142 -436.142769) (xy 390.293152 -436.150244) (xy 390.312735 -436.16445) (xy 390.326982 -436.184003)
			(xy 390.334505 -436.206997) (xy 390.335008 -436.219092) (xy 390.335008 -438.760616) (xy 390.334598 -438.772725)
			(xy 390.327095 -438.795751) (xy 390.312831 -438.815324) (xy 390.293209 -438.829518) (xy 390.270156 -438.83694)
			(xy 390.258046 -438.837324) (xy 389.318246 -438.837324) (xy 389.306155 -438.836853) (xy 389.28315 -438.829404)
			(xy 389.263566 -438.81522) (xy 389.249315 -438.795685) (xy 389.241789 -438.772705) (xy 389.241284 -438.760616)
			(xy 389.241284 -438.147968) (xy 389.239739 -438.133476) (xy 389.238087 -438.104376) (xy 389.237982 -438.089802)
			(xy 388.335012 -438.089802) (xy 388.335012 -439.0898) (xy 391.237978 -439.0898) (xy 391.238071 -439.075226)
			(xy 391.239724 -439.046125) (xy 391.24128 -439.031634) (xy 391.24128 -437.94807) (xy 391.239736 -437.933578)
			(xy 391.238083 -437.904478) (xy 391.237978 -437.889904) (xy 391.238071 -437.87533) (xy 391.239724 -437.846229)
			(xy 391.24128 -437.831738) (xy 391.24128 -437.21909) (xy 391.241652 -437.206963) (xy 391.249152 -437.183896)
			(xy 391.263415 -437.164278) (xy 391.283043 -437.150029) (xy 391.306114 -437.142544) (xy 391.318242 -437.142128)
			(xy 392.258042 -437.142128) (xy 392.270158 -437.142576) (xy 392.293201 -437.150073) (xy 392.312801 -437.164322)
			(xy 392.327041 -437.183928) (xy 392.334529 -437.206974) (xy 392.335004 -437.21909) (xy 392.335004 -438.089802)
			(xy 393.237974 -438.089802) (xy 393.238067 -438.075228) (xy 393.23972 -438.046127) (xy 393.241276 -438.031636)
			(xy 393.241276 -436.948072) (xy 393.239732 -436.93358) (xy 393.238079 -436.90448) (xy 393.237974 -436.889906)
			(xy 393.238067 -436.875332) (xy 393.23972 -436.846231) (xy 393.241276 -436.83174) (xy 393.241276 -436.219092)
			(xy 393.241709 -436.206985) (xy 393.249208 -436.183962) (xy 393.263466 -436.164391) (xy 393.283082 -436.150195)
			(xy 393.30613 -436.142771) (xy 393.318238 -436.142384) (xy 394.258038 -436.142384) (xy 394.270134 -436.142776)
			(xy 394.293143 -436.150248) (xy 394.312726 -436.164453) (xy 394.326974 -436.184004) (xy 394.334497 -436.206997)
			(xy 394.335 -436.219092) (xy 394.335 -438.760616) (xy 394.334597 -438.772726) (xy 394.327094 -438.795754)
			(xy 394.312828 -438.815326) (xy 394.293204 -438.82952) (xy 394.270149 -438.836941) (xy 394.258038 -438.837324)
			(xy 393.318238 -438.837324) (xy 393.306147 -438.83686) (xy 393.283141 -438.829409) (xy 393.263558 -438.815223)
			(xy 393.249307 -438.795686) (xy 393.241781 -438.772706) (xy 393.241276 -438.760616) (xy 393.241276 -438.147968)
			(xy 393.239731 -438.133476) (xy 393.238079 -438.104376) (xy 393.237974 -438.089802) (xy 392.335004 -438.089802)
			(xy 392.335004 -439.0898) (xy 395.23797 -439.0898) (xy 395.238063 -439.075226) (xy 395.239716 -439.046125)
			(xy 395.241272 -439.031634) (xy 395.241272 -437.94807) (xy 395.239728 -437.933578) (xy 395.238075 -437.904478)
			(xy 395.23797 -437.889904) (xy 395.238063 -437.87533) (xy 395.239716 -437.846229) (xy 395.241272 -437.831738)
			(xy 395.241272 -437.21909) (xy 395.241652 -437.206963) (xy 395.249151 -437.183898) (xy 395.263412 -437.164281)
			(xy 395.283038 -437.150031) (xy 395.306107 -437.142545) (xy 395.318234 -437.142128) (xy 396.258034 -437.142128)
			(xy 396.270149 -437.142583) (xy 396.293192 -437.150078) (xy 396.312792 -437.164325) (xy 396.327033 -437.18393)
			(xy 396.334521 -437.206975) (xy 396.334996 -437.21909) (xy 396.334996 -438.089802) (xy 398.237964 -438.089802)
			(xy 398.238081 -438.074717) (xy 398.239857 -438.044598) (xy 398.24152 -438.029604) (xy 398.24152 -436.950104)
			(xy 398.23985 -436.935111) (xy 398.238072 -436.904992) (xy 398.237964 -436.889906) (xy 398.238072 -436.87482)
			(xy 398.239854 -436.844702) (xy 398.24152 -436.829708) (xy 398.24152 -436.219092) (xy 398.241906 -436.207006)
			(xy 398.249379 -436.184018) (xy 398.263591 -436.164466) (xy 398.283151 -436.150263) (xy 398.306142 -436.1428)
			(xy 398.318228 -436.142384) (xy 399.258028 -436.142384) (xy 399.270103 -436.14284) (xy 399.29307 -436.150309)
			(xy 399.312606 -436.164508) (xy 399.3268 -436.184048) (xy 399.334263 -436.207017) (xy 399.334736 -436.219092)
			(xy 399.334736 -438.760616) (xy 399.33425 -438.772689) (xy 399.326786 -438.795651) (xy 399.312594 -438.815186)
			(xy 399.293062 -438.829381) (xy 399.270101 -438.836848) (xy 399.258028 -438.837324) (xy 398.318228 -438.837324)
			(xy 398.306148 -438.836864) (xy 398.283169 -438.829406) (xy 398.26362 -438.815211) (xy 398.249414 -438.79567)
			(xy 398.241943 -438.772695) (xy 398.24152 -438.760616) (xy 398.24152 -438.15) (xy 398.239849 -438.135007)
			(xy 398.238072 -438.104888) (xy 398.237964 -438.089802) (xy 396.334996 -438.089802) (xy 396.334996 -439.0898)
			(xy 400.23796 -439.0898) (xy 400.238077 -439.074715) (xy 400.239853 -439.044596) (xy 400.241516 -439.029602)
			(xy 400.241516 -437.950102) (xy 400.239845 -437.935109) (xy 400.238068 -437.90499) (xy 400.23796 -437.889904)
			(xy 400.238077 -437.874819) (xy 400.239853 -437.8447) (xy 400.241516 -437.829706) (xy 400.241516 -437.21909)
			(xy 400.241999 -437.207002) (xy 400.249455 -437.184006) (xy 400.263639 -437.164428) (xy 400.283167 -437.150177)
			(xy 400.306138 -437.142641) (xy 400.318224 -437.142128) (xy 401.258024 -437.142128) (xy 401.270137 -437.142496)
			(xy 401.29317 -437.150006) (xy 401.312745 -437.164279) (xy 401.326938 -437.183912) (xy 401.334353 -437.206975)
			(xy 401.334732 -437.21909) (xy 401.334732 -438.089802) (xy 402.237956 -438.089802) (xy 402.238073 -438.074717)
			(xy 402.239849 -438.044598) (xy 402.241512 -438.029604) (xy 402.241512 -436.950104) (xy 402.239842 -436.935111)
			(xy 402.238064 -436.904992) (xy 402.237956 -436.889906) (xy 402.238064 -436.87482) (xy 402.239846 -436.844702)
			(xy 402.241512 -436.829708) (xy 402.241512 -436.219092) (xy 402.241906 -436.207007) (xy 402.249378 -436.18402)
			(xy 402.263588 -436.164469) (xy 402.283146 -436.150265) (xy 402.306135 -436.142802) (xy 402.31822 -436.142384)
			(xy 403.25802 -436.142384) (xy 403.270095 -436.142847) (xy 403.293061 -436.150314) (xy 403.312597 -436.164511)
			(xy 403.326791 -436.18405) (xy 403.334255 -436.207017) (xy 403.334728 -436.219092) (xy 403.334728 -438.760616)
			(xy 403.33425 -438.772689) (xy 403.326785 -438.795654) (xy 403.312591 -438.815189) (xy 403.293057 -438.829383)
			(xy 403.270093 -438.836849) (xy 403.25802 -438.837324) (xy 402.31822 -438.837324) (xy 402.30614 -438.83687)
			(xy 402.283161 -438.82941) (xy 402.263611 -438.815214) (xy 402.249406 -438.795672) (xy 402.241935 -438.772696)
			(xy 402.241512 -438.760616) (xy 402.241512 -438.15) (xy 402.239841 -438.135007) (xy 402.238064 -438.104888)
			(xy 402.237956 -438.089802) (xy 401.334732 -438.089802) (xy 401.334732 -439.0898) (xy 404.237952 -439.0898)
			(xy 404.238069 -439.074715) (xy 404.239845 -439.044596) (xy 404.241508 -439.029602) (xy 404.241508 -437.950102)
			(xy 404.239837 -437.935109) (xy 404.23806 -437.90499) (xy 404.237952 -437.889904) (xy 404.238069 -437.874819)
			(xy 404.239845 -437.8447) (xy 404.241508 -437.829706) (xy 404.241508 -437.21909) (xy 404.241998 -437.207003)
			(xy 404.249454 -437.184008) (xy 404.263636 -437.164431) (xy 404.283162 -437.150179) (xy 404.306131 -437.142642)
			(xy 404.318216 -437.142128) (xy 405.258016 -437.142128) (xy 405.270129 -437.142503) (xy 405.293161 -437.15001)
			(xy 405.312736 -437.164281) (xy 405.326929 -437.183914) (xy 405.334345 -437.206976) (xy 405.334724 -437.21909)
			(xy 405.334724 -438.089802) (xy 406.237948 -438.089802) (xy 406.238065 -438.074717) (xy 406.239841 -438.044598)
			(xy 406.241504 -438.029604) (xy 406.241504 -436.950104) (xy 406.239834 -436.935111) (xy 406.238056 -436.904992)
			(xy 406.237948 -436.889906) (xy 406.238056 -436.87482) (xy 406.239838 -436.844702) (xy 406.241504 -436.829708)
			(xy 406.241504 -436.219092) (xy 406.241906 -436.207008) (xy 406.249377 -436.184023) (xy 406.263586 -436.164471)
			(xy 406.283141 -436.150268) (xy 406.306128 -436.142803) (xy 406.318212 -436.142384) (xy 407.258012 -436.142384)
			(xy 407.270086 -436.142854) (xy 407.293053 -436.150319) (xy 407.312589 -436.164514) (xy 407.326783 -436.184051)
			(xy 407.334247 -436.207018) (xy 407.33472 -436.219092) (xy 407.33472 -438.760616) (xy 407.334249 -438.77269)
			(xy 407.326784 -438.795656) (xy 407.312589 -438.815191) (xy 407.293052 -438.829386) (xy 407.270086 -438.83685)
			(xy 407.258012 -438.837324) (xy 406.318212 -438.837324) (xy 406.30614 -438.836826) (xy 406.283176 -438.829369)
			(xy 406.26364 -438.81518) (xy 406.249444 -438.79565) (xy 406.241979 -438.772688) (xy 406.241504 -438.760616)
			(xy 406.241504 -438.15) (xy 406.239833 -438.135007) (xy 406.238056 -438.104888) (xy 406.237948 -438.089802)
			(xy 405.334724 -438.089802) (xy 405.334724 -439.0898) (xy 408.237944 -439.0898) (xy 408.238061 -439.074715)
			(xy 408.239837 -439.044596) (xy 408.2415 -439.029602) (xy 408.2415 -437.950102) (xy 408.239829 -437.935109)
			(xy 408.238052 -437.90499) (xy 408.237944 -437.889904) (xy 408.238061 -437.874819) (xy 408.239837 -437.8447)
			(xy 408.2415 -437.829706) (xy 408.2415 -437.21909) (xy 408.241998 -437.207004) (xy 408.249453 -437.18401)
			(xy 408.263633 -437.164434) (xy 408.283157 -437.150182) (xy 408.306124 -437.142643) (xy 408.318208 -437.142128)
			(xy 409.258008 -437.142128) (xy 409.27012 -437.14251) (xy 409.293152 -437.150015) (xy 409.312728 -437.164284)
			(xy 409.326921 -437.183915) (xy 409.334337 -437.206976) (xy 409.334716 -437.21909) (xy 409.334716 -438.089802)
			(xy 410.23794 -438.089802) (xy 410.238057 -438.074717) (xy 410.239833 -438.044598) (xy 410.241496 -438.029604)
			(xy 410.241496 -436.950104) (xy 410.239826 -436.935111) (xy 410.238048 -436.904992) (xy 410.23794 -436.889906)
			(xy 410.23805 -436.87482) (xy 410.239832 -436.844702) (xy 410.241496 -436.829708) (xy 410.241496 -436.219092)
			(xy 410.241958 -436.207017) (xy 410.249423 -436.184049) (xy 410.26362 -436.164511) (xy 410.283159 -436.150317)
			(xy 410.306129 -436.142856) (xy 410.318204 -436.142384) (xy 411.258004 -436.142384) (xy 411.270078 -436.142861)
			(xy 411.293044 -436.150323) (xy 411.31258 -436.164517) (xy 411.326775 -436.184053) (xy 411.334239 -436.207018)
			(xy 411.334712 -436.219092) (xy 411.334712 -438.760616) (xy 411.334249 -438.772691) (xy 411.326783 -438.795658)
			(xy 411.312586 -438.815194) (xy 411.293047 -438.829388) (xy 411.270079 -438.836851) (xy 411.258004 -438.837324)
			(xy 410.318204 -438.837324) (xy 410.306131 -438.836833) (xy 410.283167 -438.829373) (xy 410.263631 -438.815183)
			(xy 410.249436 -438.795651) (xy 410.241971 -438.772689) (xy 410.241496 -438.760616) (xy 410.241496 -438.15)
			(xy 410.239825 -438.135007) (xy 410.238048 -438.104888) (xy 410.23794 -438.089802) (xy 409.334716 -438.089802)
			(xy 409.334716 -439.0898) (xy 412.237936 -439.0898) (xy 412.238053 -439.074715) (xy 412.239829 -439.044596)
			(xy 412.241492 -439.029602) (xy 412.241492 -437.950102) (xy 412.239821 -437.935109) (xy 412.238044 -437.90499)
			(xy 412.237936 -437.889904) (xy 412.238053 -437.874819) (xy 412.239829 -437.8447) (xy 412.241492 -437.829706)
			(xy 412.241492 -437.21909) (xy 412.241998 -437.207005) (xy 412.249452 -437.184012) (xy 412.26363 -437.164436)
			(xy 412.283152 -437.150184) (xy 412.306117 -437.142644) (xy 412.3182 -437.142128) (xy 413.258 -437.142128)
			(xy 413.270112 -437.142516) (xy 413.293144 -437.150019) (xy 413.312719 -437.164287) (xy 413.326913 -437.183916)
			(xy 413.334329 -437.206977) (xy 413.334708 -437.21909) (xy 413.334708 -439.760614) (xy 413.334206 -439.7727)
			(xy 413.326751 -439.795693) (xy 413.312572 -439.815268) (xy 413.293049 -439.82952) (xy 413.270084 -439.83706)
			(xy 413.258 -439.837576) (xy 412.3182 -439.837576) (xy 412.306089 -439.837184) (xy 412.283057 -439.829681)
			(xy 412.263482 -439.815414) (xy 412.249288 -439.795786) (xy 412.241872 -439.772727) (xy 412.241492 -439.760614)
			(xy 412.241492 -439.149998) (xy 412.239821 -439.135005) (xy 412.238044 -439.104886) (xy 412.237936 -439.0898)
			(xy 409.334716 -439.0898) (xy 409.334716 -439.760614) (xy 409.334304 -439.772709) (xy 409.326838 -439.795717)
			(xy 409.312639 -439.815301) (xy 409.293091 -439.829549) (xy 409.270101 -439.837073) (xy 409.258008 -439.837576)
			(xy 408.318208 -439.837576) (xy 408.306097 -439.837177) (xy 408.283066 -439.829677) (xy 408.263491 -439.815412)
			(xy 408.249296 -439.795785) (xy 408.24188 -439.772726) (xy 408.2415 -439.760614) (xy 408.2415 -439.149998)
			(xy 408.239829 -439.135005) (xy 408.238052 -439.104886) (xy 408.237944 -439.0898) (xy 405.334724 -439.0898)
			(xy 405.334724 -439.760614) (xy 405.334304 -439.772708) (xy 405.326839 -439.795715) (xy 405.312642 -439.815298)
			(xy 405.293096 -439.829547) (xy 405.270109 -439.837072) (xy 405.258016 -439.837576) (xy 404.318216 -439.837576)
			(xy 404.306106 -439.83717) (xy 404.283075 -439.829672) (xy 404.263499 -439.815408) (xy 404.249305 -439.795783)
			(xy 404.241888 -439.772726) (xy 404.241508 -439.760614) (xy 404.241508 -439.149998) (xy 404.239837 -439.135005)
			(xy 404.23806 -439.104886) (xy 404.237952 -439.0898) (xy 401.334732 -439.0898) (xy 401.334732 -439.760614)
			(xy 401.334304 -439.772707) (xy 401.32684 -439.795713) (xy 401.312645 -439.815295) (xy 401.293101 -439.829544)
			(xy 401.270116 -439.837071) (xy 401.258024 -439.837576) (xy 400.318224 -439.837576) (xy 400.306114 -439.837163)
			(xy 400.283083 -439.829667) (xy 400.263508 -439.815406) (xy 400.249313 -439.795781) (xy 400.241896 -439.772725)
			(xy 400.241516 -439.760614) (xy 400.241516 -439.149998) (xy 400.239845 -439.135005) (xy 400.238068 -439.104886)
			(xy 400.23796 -439.0898) (xy 396.334996 -439.0898) (xy 396.334996 -439.760614) (xy 396.334501 -439.772726)
			(xy 396.327014 -439.795764) (xy 396.312777 -439.815363) (xy 396.293182 -439.829605) (xy 396.270146 -439.837098)
			(xy 396.258034 -439.837576) (xy 395.318234 -439.837576) (xy 395.306114 -439.837111) (xy 395.283059 -439.82963)
			(xy 395.263445 -439.81539) (xy 395.249192 -439.795784) (xy 395.241696 -439.772733) (xy 395.241272 -439.760614)
			(xy 395.241272 -439.147966) (xy 395.239727 -439.133474) (xy 395.238075 -439.104374) (xy 395.23797 -439.0898)
			(xy 392.335004 -439.0898) (xy 392.335004 -439.760614) (xy 392.334501 -439.772725) (xy 392.327015 -439.795762)
			(xy 392.31278 -439.81536) (xy 392.293187 -439.829602) (xy 392.270153 -439.837097) (xy 392.258042 -439.837576)
			(xy 391.318242 -439.837576) (xy 391.306123 -439.837105) (xy 391.283068 -439.829626) (xy 391.263453 -439.815387)
			(xy 391.2492 -439.795783) (xy 391.241704 -439.772733) (xy 391.24128 -439.760614) (xy 391.24128 -439.147966)
			(xy 391.239735 -439.133474) (xy 391.238083 -439.104374) (xy 391.237978 -439.0898) (xy 388.335012 -439.0898)
			(xy 388.335012 -439.760614) (xy 388.334501 -439.772724) (xy 388.327016 -439.79576) (xy 388.312782 -439.815357)
			(xy 388.293192 -439.8296) (xy 388.27016 -439.837096) (xy 388.25805 -439.837576) (xy 387.31825 -439.837576)
			(xy 387.306134 -439.837131) (xy 387.283092 -439.829632) (xy 387.263492 -439.815382) (xy 387.249252 -439.795776)
			(xy 387.241763 -439.77273) (xy 387.241288 -439.760614) (xy 387.241288 -439.147966) (xy 387.239743 -439.133474)
			(xy 387.238091 -439.104374) (xy 387.237986 -439.0898) (xy 384.33502 -439.0898) (xy 384.33502 -439.760614)
			(xy 384.334651 -439.772742) (xy 384.32715 -439.795808) (xy 384.312886 -439.815426) (xy 384.293258 -439.829675)
			(xy 384.270186 -439.83716) (xy 384.258058 -439.837576) (xy 383.318258 -439.837576) (xy 383.306143 -439.837124)
			(xy 383.2831 -439.829627) (xy 383.263501 -439.815379) (xy 383.24926 -439.795774) (xy 383.241771 -439.77273)
			(xy 383.241296 -439.760614) (xy 383.241296 -439.147966) (xy 383.239751 -439.133474) (xy 383.238099 -439.104374)
			(xy 383.237994 -439.0898) (xy 346.23502 -439.0898) (xy 346.23502 -439.760614) (xy 346.234651 -439.772742)
			(xy 346.22715 -439.795808) (xy 346.212886 -439.815426) (xy 346.193258 -439.829675) (xy 346.170186 -439.83716)
			(xy 346.158058 -439.837576) (xy 345.218258 -439.837576) (xy 345.206143 -439.837124) (xy 345.1831 -439.829627)
			(xy 345.163501 -439.815379) (xy 345.14926 -439.795774) (xy 345.141771 -439.77273) (xy 345.141296 -439.760614)
			(xy 345.141296 -439.243978) (xy 345.130608 -439.206333) (xy 345.119131 -439.128926) (xy 345.118436 -439.0898)
			(xy 342.235028 -439.0898) (xy 342.235028 -439.760614) (xy 342.234651 -439.772741) (xy 342.227151 -439.795806)
			(xy 342.212889 -439.815424) (xy 342.193263 -439.829673) (xy 342.170193 -439.837159) (xy 342.158066 -439.837576)
			(xy 341.218266 -439.837576) (xy 341.206151 -439.837118) (xy 341.183109 -439.829623) (xy 341.163509 -439.815377)
			(xy 341.149268 -439.795773) (xy 341.141779 -439.772729) (xy 341.141304 -439.760614) (xy 341.141304 -439.243978)
			(xy 341.130616 -439.206333) (xy 341.119139 -439.128926) (xy 341.118444 -439.0898) (xy 338.235036 -439.0898)
			(xy 338.235036 -439.760614) (xy 338.234651 -439.77274) (xy 338.227152 -439.795804) (xy 338.212892 -439.815421)
			(xy 338.193268 -439.82967) (xy 338.1702 -439.837158) (xy 338.158074 -439.837576) (xy 337.218274 -439.837576)
			(xy 337.206159 -439.837111) (xy 337.183118 -439.829618) (xy 337.163518 -439.815374) (xy 337.149276 -439.795772)
			(xy 337.141787 -439.772729) (xy 337.141312 -439.760614) (xy 337.141312 -439.243978) (xy 337.130625 -439.206333)
			(xy 337.119147 -439.128926) (xy 337.118452 -439.0898) (xy 334.235044 -439.0898) (xy 334.235044 -439.760614)
			(xy 334.234651 -439.772739) (xy 334.227153 -439.795802) (xy 334.212895 -439.815418) (xy 334.193273 -439.829668)
			(xy 334.170207 -439.837157) (xy 334.158082 -439.837576) (xy 333.218282 -439.837576) (xy 333.206168 -439.837104)
			(xy 333.183126 -439.829614) (xy 333.163526 -439.815371) (xy 333.149285 -439.79577) (xy 333.141795 -439.772728)
			(xy 333.14132 -439.760614) (xy 333.14132 -439.243978) (xy 333.130633 -439.206333) (xy 333.119156 -439.128926)
			(xy 333.11846 -439.0898) (xy 329.2348 -439.0898) (xy 329.2348 -439.760614) (xy 329.234306 -439.7727)
			(xy 329.22685 -439.795695) (xy 329.212669 -439.815271) (xy 329.193144 -439.829523) (xy 329.170177 -439.837061)
			(xy 329.158092 -439.837576) (xy 328.218292 -439.837576) (xy 328.20618 -439.83719) (xy 328.183149 -439.829686)
			(xy 328.163574 -439.815417) (xy 328.14938 -439.795788) (xy 328.141964 -439.772727) (xy 328.141584 -439.760614)
			(xy 328.141584 -439.24474) (xy 328.130784 -439.206919) (xy 328.119178 -439.129127) (xy 328.11847 -439.0898)
			(xy 325.234808 -439.0898) (xy 325.234808 -439.760614) (xy 325.234306 -439.7727) (xy 325.226851 -439.795693)
			(xy 325.212672 -439.815268) (xy 325.193149 -439.82952) (xy 325.170184 -439.83706) (xy 325.1581 -439.837576)
			(xy 324.2183 -439.837576) (xy 324.206189 -439.837184) (xy 324.183157 -439.829681) (xy 324.163582 -439.815414)
			(xy 324.149388 -439.795786) (xy 324.141972 -439.772727) (xy 324.141592 -439.760614) (xy 324.141592 -439.24474)
			(xy 324.130793 -439.206919) (xy 324.119186 -439.129127) (xy 324.118478 -439.0898) (xy 321.234816 -439.0898)
			(xy 321.234816 -439.760614) (xy 321.234404 -439.772709) (xy 321.226938 -439.795717) (xy 321.212739 -439.815301)
			(xy 321.193191 -439.829549) (xy 321.170201 -439.837073) (xy 321.158108 -439.837576) (xy 320.218308 -439.837576)
			(xy 320.206197 -439.837177) (xy 320.183166 -439.829677) (xy 320.163591 -439.815412) (xy 320.149396 -439.795785)
			(xy 320.14198 -439.772726) (xy 320.1416 -439.760614) (xy 320.1416 -439.24474) (xy 320.130801 -439.206918)
			(xy 320.119194 -439.129127) (xy 320.118486 -439.0898) (xy 317.234824 -439.0898) (xy 317.234824 -439.760614)
			(xy 317.234404 -439.772708) (xy 317.226939 -439.795715) (xy 317.212742 -439.815298) (xy 317.193196 -439.829547)
			(xy 317.170209 -439.837072) (xy 317.158116 -439.837576) (xy 316.218316 -439.837576) (xy 316.206206 -439.83717)
			(xy 316.183175 -439.829672) (xy 316.163599 -439.815408) (xy 316.149405 -439.795783) (xy 316.141988 -439.772726)
			(xy 316.141608 -439.760614) (xy 316.141608 -439.24474) (xy 316.130809 -439.206918) (xy 316.119202 -439.129127)
			(xy 316.118494 -439.0898) (xy 157.334712 -439.0898) (xy 157.334712 -439.760614) (xy 157.334304 -439.772709)
			(xy 157.326838 -439.795718) (xy 157.312637 -439.815302) (xy 157.293089 -439.829551) (xy 157.270098 -439.837074)
			(xy 157.258004 -439.837576) (xy 156.318204 -439.837576) (xy 156.306093 -439.83718) (xy 156.283062 -439.829679)
			(xy 156.263486 -439.815413) (xy 156.249292 -439.795785) (xy 156.241876 -439.772727) (xy 156.241496 -439.760614)
			(xy 156.241496 -439.149998) (xy 156.239825 -439.135005) (xy 156.238048 -439.104886) (xy 156.23794 -439.0898)
			(xy 153.33472 -439.0898) (xy 153.33472 -439.760614) (xy 153.334304 -439.772708) (xy 153.326839 -439.795716)
			(xy 153.31264 -439.815299) (xy 153.293094 -439.829548) (xy 153.270105 -439.837073) (xy 153.258012 -439.837576)
			(xy 152.318212 -439.837576) (xy 152.306101 -439.837173) (xy 152.28307 -439.829674) (xy 152.263495 -439.81541)
			(xy 152.249301 -439.795784) (xy 152.241884 -439.772726) (xy 152.241504 -439.760614) (xy 152.241504 -439.149998)
			(xy 152.239833 -439.135005) (xy 152.238056 -439.104886) (xy 152.237948 -439.0898) (xy 149.334728 -439.0898)
			(xy 149.334728 -439.760614) (xy 149.334304 -439.772708) (xy 149.32684 -439.795714) (xy 149.312643 -439.815297)
			(xy 149.293099 -439.829546) (xy 149.270112 -439.837072) (xy 149.25802 -439.837576) (xy 148.31822 -439.837576)
			(xy 148.30611 -439.837166) (xy 148.283079 -439.829669) (xy 148.263504 -439.815407) (xy 148.249309 -439.795782)
			(xy 148.241892 -439.772726) (xy 148.241512 -439.760614) (xy 148.241512 -439.149998) (xy 148.239841 -439.135005)
			(xy 148.238064 -439.104886) (xy 148.237956 -439.0898) (xy 145.334736 -439.0898) (xy 145.334736 -439.760614)
			(xy 145.334304 -439.772707) (xy 145.326841 -439.795712) (xy 145.312646 -439.815294) (xy 145.293104 -439.829543)
			(xy 145.270119 -439.83707) (xy 145.258028 -439.837576) (xy 144.318228 -439.837576) (xy 144.306118 -439.837159)
			(xy 144.283088 -439.829665) (xy 144.263512 -439.815404) (xy 144.249317 -439.795781) (xy 144.2419 -439.772725)
			(xy 144.24152 -439.760614) (xy 144.24152 -439.149998) (xy 144.239849 -439.135005) (xy 144.238072 -439.104886)
			(xy 144.237964 -439.0898) (xy 140.335 -439.0898) (xy 140.335 -439.760614) (xy 140.334501 -439.772726)
			(xy 140.327015 -439.795763) (xy 140.312778 -439.815361) (xy 140.293184 -439.829604) (xy 140.270149 -439.837097)
			(xy 140.258038 -439.837576) (xy 139.318238 -439.837576) (xy 139.306119 -439.837108) (xy 139.283063 -439.829628)
			(xy 139.263449 -439.815388) (xy 139.249196 -439.795783) (xy 139.2417 -439.772733) (xy 139.241276 -439.760614)
			(xy 139.241276 -439.147966) (xy 139.239731 -439.133474) (xy 139.238079 -439.104374) (xy 139.237974 -439.0898)
			(xy 136.335008 -439.0898) (xy 136.335008 -439.760614) (xy 136.334501 -439.772725) (xy 136.327016 -439.795761)
			(xy 136.312781 -439.815358) (xy 136.293189 -439.829601) (xy 136.270157 -439.837096) (xy 136.258046 -439.837576)
			(xy 135.318246 -439.837576) (xy 135.306127 -439.837101) (xy 135.283072 -439.829623) (xy 135.263457 -439.815385)
			(xy 135.249204 -439.795782) (xy 135.241708 -439.772733) (xy 135.241284 -439.760614) (xy 135.241284 -439.147966)
			(xy 135.239739 -439.133474) (xy 135.238087 -439.104374) (xy 135.237982 -439.0898) (xy 132.335016 -439.0898)
			(xy 132.335016 -439.760614) (xy 132.334651 -439.772742) (xy 132.327149 -439.795809) (xy 132.312885 -439.815428)
			(xy 132.293255 -439.829677) (xy 132.270182 -439.83716) (xy 132.258054 -439.837576) (xy 131.318254 -439.837576)
			(xy 131.306138 -439.837128) (xy 131.283096 -439.82963) (xy 131.263496 -439.815381) (xy 131.249256 -439.795775)
			(xy 131.241767 -439.77273) (xy 131.241292 -439.760614) (xy 131.241292 -439.147966) (xy 131.239747 -439.133474)
			(xy 131.238095 -439.104374) (xy 131.23799 -439.0898) (xy 128.335024 -439.0898) (xy 128.335024 -439.760614)
			(xy 128.334651 -439.772741) (xy 128.32715 -439.795807) (xy 128.312888 -439.815425) (xy 128.29326 -439.829674)
			(xy 128.27019 -439.837159) (xy 128.258062 -439.837576) (xy 127.318262 -439.837576) (xy 127.306147 -439.837121)
			(xy 127.283105 -439.829625) (xy 127.263505 -439.815378) (xy 127.249264 -439.795774) (xy 127.241775 -439.772729)
			(xy 127.2413 -439.760614) (xy 127.2413 -439.147966) (xy 127.239755 -439.133474) (xy 127.238103 -439.104374)
			(xy 127.237998 -439.0898) (xy 90.235024 -439.0898) (xy 90.235024 -439.760614) (xy 90.234651 -439.772741)
			(xy 90.22715 -439.795807) (xy 90.212888 -439.815425) (xy 90.19326 -439.829674) (xy 90.17019 -439.837159)
			(xy 90.158062 -439.837576) (xy 89.218262 -439.837576) (xy 89.206147 -439.837121) (xy 89.183105 -439.829625)
			(xy 89.163505 -439.815378) (xy 89.149264 -439.795774) (xy 89.141775 -439.772729) (xy 89.1413 -439.760614)
			(xy 89.1413 -439.243978) (xy 89.130612 -439.206333) (xy 89.119135 -439.128926) (xy 89.11844 -439.0898)
			(xy 86.235032 -439.0898) (xy 86.235032 -439.760614) (xy 86.234651 -439.77274) (xy 86.227152 -439.795805)
			(xy 86.212891 -439.815422) (xy 86.193265 -439.829672) (xy 86.170197 -439.837158) (xy 86.15807 -439.837576)
			(xy 85.21827 -439.837576) (xy 85.206155 -439.837114) (xy 85.183113 -439.82962) (xy 85.163513 -439.815375)
			(xy 85.149272 -439.795772) (xy 85.141783 -439.772729) (xy 85.141308 -439.760614) (xy 85.141308 -439.243978)
			(xy 85.130621 -439.206333) (xy 85.119143 -439.128926) (xy 85.118448 -439.0898) (xy 82.23504 -439.0898)
			(xy 82.23504 -439.760614) (xy 82.234651 -439.77274) (xy 82.227153 -439.795803) (xy 82.212894 -439.815419)
			(xy 82.19327 -439.829669) (xy 82.170204 -439.837157) (xy 82.158078 -439.837576) (xy 81.218278 -439.837576)
			(xy 81.206164 -439.837107) (xy 81.183122 -439.829616) (xy 81.163522 -439.815372) (xy 81.149281 -439.795771)
			(xy 81.141791 -439.772728) (xy 81.141316 -439.760614) (xy 81.141316 -439.243978) (xy 81.130629 -439.206333)
			(xy 81.119152 -439.128926) (xy 81.118456 -439.0898) (xy 78.235048 -439.0898) (xy 78.235048 -439.760614)
			(xy 78.2346 -439.772731) (xy 78.227107 -439.795777) (xy 78.21286 -439.81538) (xy 78.193252 -439.82962)
			(xy 78.170203 -439.837105) (xy 78.158086 -439.837576) (xy 77.218286 -439.837576) (xy 77.206172 -439.837101)
			(xy 77.183131 -439.829611) (xy 77.16353 -439.81537) (xy 77.149289 -439.795769) (xy 77.141799 -439.772728)
			(xy 77.141324 -439.760614) (xy 77.141324 -439.243978) (xy 77.130637 -439.206333) (xy 77.11916 -439.128926)
			(xy 77.118464 -439.0898) (xy 73.234804 -439.0898) (xy 73.234804 -439.760614) (xy 73.234306 -439.7727)
			(xy 73.22685 -439.795694) (xy 73.21267 -439.81527) (xy 73.193146 -439.829521) (xy 73.17018 -439.837061)
			(xy 73.158096 -439.837576) (xy 72.218296 -439.837576) (xy 72.206185 -439.837187) (xy 72.183153 -439.829683)
			(xy 72.163578 -439.815416) (xy 72.149384 -439.795787) (xy 72.141968 -439.772727) (xy 72.141588 -439.760614)
			(xy 72.141588 -439.24474) (xy 72.130789 -439.206919) (xy 72.119182 -439.129127) (xy 72.118474 -439.0898)
			(xy 69.234812 -439.0898) (xy 69.234812 -439.760614) (xy 69.234404 -439.772709) (xy 69.226938 -439.795718)
			(xy 69.212737 -439.815302) (xy 69.193189 -439.829551) (xy 69.170198 -439.837074) (xy 69.158104 -439.837576)
			(xy 68.218304 -439.837576) (xy 68.206193 -439.83718) (xy 68.183162 -439.829679) (xy 68.163586 -439.815413)
			(xy 68.149392 -439.795785) (xy 68.141976 -439.772727) (xy 68.141596 -439.760614) (xy 68.141596 -439.24474)
			(xy 68.130797 -439.206918) (xy 68.11919 -439.129127) (xy 68.118482 -439.0898) (xy 65.23482 -439.0898)
			(xy 65.23482 -439.760614) (xy 65.234404 -439.772708) (xy 65.226939 -439.795716) (xy 65.21274 -439.815299)
			(xy 65.193194 -439.829548) (xy 65.170205 -439.837073) (xy 65.158112 -439.837576) (xy 64.218312 -439.837576)
			(xy 64.206201 -439.837173) (xy 64.18317 -439.829674) (xy 64.163595 -439.81541) (xy 64.149401 -439.795784)
			(xy 64.141984 -439.772726) (xy 64.141604 -439.760614) (xy 64.141604 -439.24474) (xy 64.130805 -439.206918)
			(xy 64.119198 -439.129127) (xy 64.11849 -439.0898) (xy 61.234828 -439.0898) (xy 61.234828 -439.760614)
			(xy 61.234404 -439.772708) (xy 61.22694 -439.795714) (xy 61.212743 -439.815297) (xy 61.193199 -439.829546)
			(xy 61.170212 -439.837072) (xy 61.15812 -439.837576) (xy 60.21832 -439.837576) (xy 60.20621 -439.837166)
			(xy 60.183179 -439.829669) (xy 60.163604 -439.815407) (xy 60.149409 -439.795782) (xy 60.141992 -439.772726)
			(xy 60.141612 -439.760614) (xy 60.141612 -439.24474) (xy 60.130813 -439.206918) (xy 60.119206 -439.129127)
			(xy 60.118498 -439.0898) (xy 7.00913 -439.0898) (xy 7.00913 -439.989976) (xy 7.009638 -440.045746)
			(xy 7.017973 -440.156973) (xy 7.034597 -440.267266) (xy 7.059417 -440.376009) (xy 7.092293 -440.482593)
			(xy 7.133043 -440.586422) (xy 7.181438 -440.686915) (xy 7.237207 -440.783511) (xy 7.300039 -440.87567)
			(xy 7.369583 -440.962874) (xy 7.445449 -441.044639) (xy 7.527212 -441.120505) (xy 7.614417 -441.190048)
			(xy 7.706575 -441.252881) (xy 7.803171 -441.30865) (xy 7.903664 -441.357045) (xy 8.007493 -441.397795)
			(xy 8.114077 -441.430672) (xy 8.22282 -441.455492) (xy 8.333113 -441.472116) (xy 8.44434 -441.480451)
			(xy 8.50011 -441.480956) (xy 194.495928 -441.480956)
		)
		(stroke
			(width 0)
			(type solid)
		)
		(fill yes)
		(layer "In12.Cu")
		(net "GND")
	)
	(gr_line
		(start 206.17434 -435.523132)
		(end 207.503268 -436.85206)
		(stroke
			(width 0.635)
			(type default)
		)
		(layer "In12.Cu")
	)
	(gr_line
		(start 206.17434 -415.567368)
		(end 206.17434 -435.523132)
		(stroke
			(width 0.635)
			(type default)
		)
		(layer "In12.Cu")
	)
	(gr_line
		(start 207.213708 -414.528)
		(end 206.17434 -415.567368)
		(stroke
			(width 0.635)
			(type default)
		)
		(layer "In12.Cu")
	)
	(gr_line
		(start 207.503268 -436.85206)
		(end 228.909372 -436.85206)
		(stroke
			(width 0.635)
			(type default)
		)
		(layer "In12.Cu")
	)
	(gr_line
		(start 228.909372 -436.85206)
		(end 230.69804 -435.063392)
		(stroke
			(width 0.635)
			(type default)
		)
		(layer "In12.Cu")
	)
	(gr_line
		(start 230.69804 -423.45356)
		(end 230.69804 -435.063392)
		(stroke
			(width 0.635)
			(type default)
		)
		(layer "In12.Cu")
	)
	(gr_line
		(start 232.938828 -414.528)
		(end 207.213708 -414.528)
		(stroke
			(width 0.635)
			(type default)
		)
		(layer "In12.Cu")
	)
	(gr_line
		(start 233.20756 -420.94404)
		(end 230.69804 -423.45356)
		(stroke
			(width 0.635)
			(type default)
		)
		(layer "In12.Cu")
	)
	(gr_line
		(start 239.67694 -402.10994)
		(end 239.86236 -402.29536)
		(stroke
			(width 0.508)
			(type default)
		)
		(layer "In12.Cu")
	)
	(gr_line
		(start 239.67694 -397.53286)
		(end 239.67694 -402.10994)
		(stroke
			(width 0.508)
			(type default)
		)
		(layer "In12.Cu")
	)
	(gr_line
		(start 239.713008 -407.75382)
		(end 232.938828 -414.528)
		(stroke
			(width 0.635)
			(type default)
		)
		(layer "In12.Cu")
	)
	(gr_line
		(start 239.81918 -401.97786)
		(end 239.81918 -397.5608)
		(stroke
			(width 0.2)
			(type default)
		)
		(layer "In12.Cu")
	)
	(gr_line
		(start 239.81918 -397.5608)
		(end 240.07826 -397.30172)
		(stroke
			(width 0.2)
			(type default)
		)
		(layer "In12.Cu")
	)
	(gr_line
		(start 239.86236 -402.29536)
		(end 275.44522 -402.29536)
		(stroke
			(width 0.508)
			(type default)
		)
		(layer "In12.Cu")
	)
	(gr_line
		(start 239.96904 -402.12772)
		(end 239.81918 -401.97786)
		(stroke
			(width 0.2)
			(type default)
		)
		(layer "In12.Cu")
	)
	(gr_line
		(start 240.06556 -397.14424)
		(end 239.67694 -397.53286)
		(stroke
			(width 0.508)
			(type default)
		)
		(layer "In12.Cu")
	)
	(gr_line
		(start 240.07826 -397.30172)
		(end 280.16454 -397.30172)
		(stroke
			(width 0.2)
			(type default)
		)
		(layer "In12.Cu")
	)
	(gr_line
		(start 270.496792 -420.94404)
		(end 233.20756 -420.94404)
		(stroke
			(width 0.635)
			(type default)
		)
		(layer "In12.Cu")
	)
	(gr_line
		(start 275.44522 -402.29536)
		(end 280.32202 -402.29536)
		(stroke
			(width 0.508)
			(type default)
		)
		(layer "In12.Cu")
	)
	(gr_line
		(start 275.680932 -415.7599)
		(end 270.496792 -420.94404)
		(stroke
			(width 0.635)
			(type default)
		)
		(layer "In12.Cu")
	)
	(gr_line
		(start 279.927812 -415.7599)
		(end 275.680932 -415.7599)
		(stroke
			(width 0.635)
			(type default)
		)
		(layer "In12.Cu")
	)
	(gr_line
		(start 279.927812 -415.7599)
		(end 280.51506 -415.172652)
		(stroke
			(width 0.635)
			(type default)
		)
		(layer "In12.Cu")
	)
	(gr_line
		(start 280.100532 -407.75382)
		(end 239.713008 -407.75382)
		(stroke
			(width 0.635)
			(type default)
		)
		(layer "In12.Cu")
	)
	(gr_line
		(start 280.16454 -397.30172)
		(end 280.34742 -397.4846)
		(stroke
			(width 0.2)
			(type default)
		)
		(layer "In12.Cu")
	)
	(gr_line
		(start 280.17978 -402.12772)
		(end 239.96904 -402.12772)
		(stroke
			(width 0.2)
			(type default)
		)
		(layer "In12.Cu")
	)
	(gr_line
		(start 280.24074 -397.14424)
		(end 240.06556 -397.14424)
		(stroke
			(width 0.508)
			(type default)
		)
		(layer "In12.Cu")
	)
	(gr_line
		(start 280.32202 -402.29536)
		(end 280.50998 -402.1074)
		(stroke
			(width 0.508)
			(type default)
		)
		(layer "In12.Cu")
	)
	(gr_line
		(start 280.34742 -401.96008)
		(end 280.17978 -402.12772)
		(stroke
			(width 0.2)
			(type default)
		)
		(layer "In12.Cu")
	)
	(gr_line
		(start 280.34742 -397.4846)
		(end 280.34742 -401.96008)
		(stroke
			(width 0.2)
			(type default)
		)
		(layer "In12.Cu")
	)
	(gr_line
		(start 280.50998 -402.1074)
		(end 280.50998 -397.41348)
		(stroke
			(width 0.508)
			(type default)
		)
		(layer "In12.Cu")
	)
	(gr_line
		(start 280.50998 -397.41348)
		(end 280.24074 -397.14424)
		(stroke
			(width 0.508)
			(type default)
		)
		(layer "In12.Cu")
	)
	(gr_line
		(start 280.51506 -415.172652)
		(end 280.51506 -408.168348)
		(stroke
			(width 0.635)
			(type default)
		)
		(layer "In12.Cu")
	)
	(gr_line
		(start 280.51506 -408.168348)
		(end 280.100532 -407.75382)
		(stroke
			(width 0.635)
			(type default)
		)
		(layer "In12.Cu")
	)
	(gr_poly
		(pts
			(xy 29.542486 -166.656004) (xy 29.542486 -162.998404) (xy 29.491686 -162.947604) (xy 25.834086 -162.947604)
			(xy 25.783286 -162.998404) (xy 25.783286 -166.656004) (xy 25.834086 -166.706804) (xy 29.491686 -166.706804)
		)
		(stroke
			(width 0)
			(type solid)
		)
		(fill yes)
		(layer "In13.Cu")
		(net "GND")
	)
	(gr_poly
		(pts
			(xy 33.94075 -131.462272) (xy 33.94075 -127.804672) (xy 33.88995 -127.753872) (xy 30.23235 -127.753872)
			(xy 30.18155 -127.804672) (xy 30.18155 -131.462272) (xy 30.23235 -131.513072) (xy 33.88995 -131.513072)
		)
		(stroke
			(width 0)
			(type solid)
		)
		(fill yes)
		(layer "In13.Cu")
		(net "GND")
	)
	(gr_poly
		(pts
			(xy 110.813596 -361.032806) (xy 110.813596 -356.664006) (xy 110.762796 -356.613206) (xy 106.393996 -356.613206)
			(xy 106.343196 -356.664006) (xy 106.343196 -361.032806) (xy 106.393996 -361.083606) (xy 110.762796 -361.083606)
		)
		(stroke
			(width 0)
			(type solid)
		)
		(fill yes)
		(layer "In13.Cu")
		(net "GND")
	)
	(gr_poly
		(pts
			(xy 217.33256 -26.947368) (xy 217.33256 -25.212548) (xy 216.7382 -24.618188) (xy 213.22538 -24.618188)
			(xy 213.03488 -24.808688) (xy 213.03488 -27.396948) (xy 213.26856 -27.630628) (xy 216.6493 -27.630628)
		)
		(stroke
			(width 0)
			(type solid)
		)
		(fill yes)
		(layer "In13.Cu")
		(net "GND")
	)
	(gr_poly
		(pts
			(xy 249.511312 -89.374472) (xy 249.511312 -86.478872) (xy 249.333512 -86.301072) (xy 245.970298 -86.301072)
			(xy 245.752112 -86.519258) (xy 245.752112 -89.653872) (xy 245.929912 -89.831672) (xy 249.054112 -89.831672)
		)
		(stroke
			(width 0)
			(type solid)
		)
		(fill yes)
		(layer "In13.Cu")
		(net "GND")
	)
	(gr_poly
		(pts
			(xy 337.936586 -70.187058) (xy 337.936586 -67.25412) (xy 337.568032 -66.885566) (xy 333.806038 -66.885566)
			(xy 333.422244 -67.26936) (xy 333.422244 -70.586092) (xy 333.54518 -70.709028) (xy 337.414616 -70.709028)
		)
		(stroke
			(width 0)
			(type solid)
		)
		(fill yes)
		(layer "In13.Cu")
		(net "GND")
	)
	(gr_poly
		(pts
			(xy 427.559216 -138.21791) (xy 427.559216 -134.61111) (xy 427.508416 -134.56031) (xy 423.901616 -134.56031)
			(xy 423.850816 -134.61111) (xy 423.850816 -138.21791) (xy 423.901616 -138.26871) (xy 427.508416 -138.26871)
		)
		(stroke
			(width 0)
			(type solid)
		)
		(fill yes)
		(layer "In13.Cu")
		(net "GND")
	)
	(gr_poly
		(pts
			(xy 442.47816 -371.7036) (xy 442.47816 -353.90582) (xy 442.01588 -353.44354) (xy 437.72582 -353.44354)
			(xy 437.31942 -353.84994) (xy 437.31942 -371.15242) (xy 438.16016 -371.99316) (xy 442.1886 -371.99316)
		)
		(stroke
			(width 0)
			(type solid)
		)
		(fill yes)
		(layer "In13.Cu")
		(net "P5V")
	)
	(gr_poly
		(pts
			(xy 230.38054 -434.93182) (xy 230.38054 -427.00194) (xy 230.39578 -426.9867) (xy 230.39578 -423.29862)
			(xy 233.04246 -420.65194) (xy 270.33982 -420.65194) (xy 275.73732 -415.25444) (xy 279.9842 -415.25444)
			(xy 280.19756 -415.04108) (xy 280.19756 -408.29992) (xy 279.96896 -408.07132) (xy 239.84458 -408.07132)
			(xy 233.0704 -414.8455) (xy 207.34528 -414.8455) (xy 206.49184 -415.69894) (xy 206.49184 -435.39156)
			(xy 207.63484 -436.53456) (xy 228.7778 -436.53456)
		)
		(stroke
			(width 0)
			(type solid)
		)
		(fill yes)
		(layer "In13.Cu")
		(net "P12V_PSU")
	)
	(gr_poly
		(pts
			(arc
				(start 426.246544 -144.71396)
				(mid 426.340376 -144.651324)
				(end 426.318426 -144.540732)
			)
			(xy 426.25645 -144.478756) (xy 422.58107 -144.478756)
			(arc
				(start 422.519094 -144.540732)
				(mid 422.497258 -144.651277)
				(end 422.590976 -144.71396)
			)
		)
		(stroke
			(width 0)
			(type solid)
		)
		(fill yes)
		(layer "In13.Cu")
		(net "GND")
	)
	(gr_poly
		(pts
			(arc
				(start 150.250652 -39.515288)
				(mid 150.54834 -39.354795)
				(end 150.846028 -39.515288)
			)
			(xy 151.5364 -39.515288) (xy 151.70658 -39.345108) (xy 151.70658 -35.753548) (xy 151.44242 -35.489388)
			(xy 149.11578 -35.489388) (xy 148.80082 -35.804348) (xy 148.80082 -39.345108) (xy 148.971 -39.515288)
		)
		(stroke
			(width 0)
			(type solid)
		)
		(fill yes)
		(layer "In13.Cu")
		(net "GND")
	)
	(gr_poly
		(pts
			(xy 245.0465 -251.765308) (xy 245.0465 -247.246648) (xy 244.6147 -246.814848) (xy 240.54562 -246.814848)
			(xy 240.23574 -247.124728) (xy 240.23574 -249.273568) (xy 240.806222 -249.273568) (xy 240.810293 -249.217946)
			(xy 240.822419 -249.163509) (xy 240.842342 -249.111418) (xy 240.869638 -249.062783) (xy 240.903724 -249.01864)
			(xy 240.943873 -248.979931) (xy 240.989231 -248.94748) (xy 241.038831 -248.921979) (xy 241.091615 -248.903972)
			(xy 241.146458 -248.893842) (xy 241.202192 -248.891805) (xy 241.257629 -248.897905) (xy 241.311586 -248.912011)
			(xy 241.362915 -248.933823) (xy 241.410521 -248.962877) (xy 241.453389 -248.998552) (xy 241.490606 -249.040089)
			(xy 241.521379 -249.086602) (xy 241.545051 -249.137099) (xy 241.561119 -249.190506) (xy 241.569239 -249.245682)
			(xy 241.569748 -249.273568) (xy 241.569239 -249.301454) (xy 241.561119 -249.35663) (xy 241.545051 -249.410037)
			(xy 241.521379 -249.460534) (xy 241.490606 -249.507047) (xy 241.453389 -249.548584) (xy 241.410521 -249.584259)
			(xy 241.362915 -249.613313) (xy 241.311586 -249.635125) (xy 241.257629 -249.649231) (xy 241.202192 -249.655331)
			(xy 241.146458 -249.653294) (xy 241.091615 -249.643164) (xy 241.038831 -249.625157) (xy 240.989231 -249.599656)
			(xy 240.943873 -249.567205) (xy 240.903724 -249.528496) (xy 240.869638 -249.484353) (xy 240.842342 -249.435718)
			(xy 240.822419 -249.383627) (xy 240.810293 -249.32919) (xy 240.806222 -249.273568) (xy 240.23574 -249.273568)
			(xy 240.23574 -251.958348) (xy 240.45672 -252.179328) (xy 244.63248 -252.179328)
		)
		(stroke
			(width 0)
			(type solid)
		)
		(fill yes)
		(layer "In13.Cu")
		(net "GND")
	)
	(gr_poly
		(pts
			(xy 10.35558 -100.975668)
			(arc
				(start 10.35558 -100.736908)
				(mid 10.269496 -100.495608)
				(end 10.35558 -100.254308)
			)
			(arc
				(start 10.35558 -100.03917)
				(mid 10.302076 -99.949675)
				(end 10.197846 -99.954334)
			)
			(arc
				(start 10.197846 -99.954334)
				(mid 10.09724 -100.001603)
				(end 9.98728 -100.017834)
			)
			(arc
				(start 9.98728 -100.017834)
				(mid 9.605772 -99.636326)
				(end 9.98728 -99.254818)
			)
			(arc
				(start 9.98728 -99.254818)
				(mid 10.097231 -99.271082)
				(end 10.197846 -99.318318)
			)
			(arc
				(start 10.197846 -99.318318)
				(mid 10.302135 -99.323088)
				(end 10.35558 -99.233482)
			)
			(xy 10.35558 -98.755962)
			(arc
				(start 10.315702 -98.747072)
				(mid 10.017245 -98.374708)
				(end 10.315702 -98.002344)
			)
			(xy 10.35558 -97.993454) (xy 10.35558 -97.711768) (xy 9.72566 -97.081848) (xy 6.02742 -97.081848)
			(xy 5.44576 -97.663508) (xy 5.44576 -100.912168) (xy 5.91312 -101.379528) (xy 9.95172 -101.379528)
		)
		(stroke
			(width 0)
			(type solid)
		)
		(fill yes)
		(layer "In13.Cu")
		(net "GND")
	)
	(gr_poly
		(pts
			(xy 207.195928 -400.678142) (xy 207.214633 -400.66012) (xy 207.256654 -400.629592) (xy 207.302935 -400.606017)
			(xy 207.352336 -400.589976) (xy 207.403638 -400.581864) (xy 207.429608 -400.581368) (xy 208.388204 -400.581368)
			(xy 208.403203 -400.580835) (xy 208.431908 -400.572128) (xy 208.456852 -400.555465) (xy 208.475886 -400.53228)
			(xy 208.487371 -400.504569) (xy 208.490321 -400.474717) (xy 208.484479 -400.445294) (xy 208.47035 -400.418833)
			(xy 208.460086 -400.407886) (xy 207.62722 -399.57502) (xy 207.54086 -399.57502) (xy 207.54086 -399.632932)
			(xy 207.542638 -399.639536) (xy 207.549399 -399.664974) (xy 207.556668 -399.717105) (xy 207.557116 -399.743422)
			(xy 207.55663 -399.770673) (xy 207.548874 -399.824621) (xy 207.533519 -399.876916) (xy 207.510877 -399.926493)
			(xy 207.481411 -399.972343) (xy 207.44572 -400.013534) (xy 207.404529 -400.049225) (xy 207.358679 -400.078691)
			(xy 207.309102 -400.101333) (xy 207.256807 -400.116688) (xy 207.202859 -400.124444) (xy 207.148357 -400.124444)
			(xy 207.094409 -400.116688) (xy 207.042114 -400.101333) (xy 206.992537 -400.078691) (xy 206.946687 -400.049225)
			(xy 206.905496 -400.013534) (xy 206.869805 -399.972343) (xy 206.840339 -399.926493) (xy 206.817697 -399.876916)
			(xy 206.802342 -399.824621) (xy 206.794586 -399.770673) (xy 206.7941 -399.743422) (xy 206.794192 -399.730172)
			(xy 206.795975 -399.703733) (xy 206.797656 -399.69059) (xy 206.799145 -399.676166) (xy 206.794912 -399.647494)
			(xy 206.782796 -399.621166) (xy 206.763772 -399.5993) (xy 206.739373 -399.583657) (xy 206.711563 -399.575497)
			(xy 206.697072 -399.57502) (xy 204.28712 -399.57502) (xy 203.1746 -400.68754) (xy 203.13777 -400.68754)
			(xy 203.122775 -400.688076) (xy 203.094078 -400.696787) (xy 203.069143 -400.71345) (xy 203.050117 -400.736632)
			(xy 203.040672 -400.759422) (xy 206.03159 -400.759422) (xy 206.035661 -400.7038) (xy 206.047787 -400.649363)
			(xy 206.06771 -400.597272) (xy 206.095006 -400.548637) (xy 206.129092 -400.504494) (xy 206.169241 -400.465785)
			(xy 206.214599 -400.433334) (xy 206.264199 -400.407833) (xy 206.316983 -400.389826) (xy 206.371826 -400.379696)
			(xy 206.42756 -400.377659) (xy 206.482997 -400.383759) (xy 206.536954 -400.397865) (xy 206.588283 -400.419677)
			(xy 206.635889 -400.448731) (xy 206.678757 -400.484406) (xy 206.715974 -400.525943) (xy 206.746747 -400.572456)
			(xy 206.770419 -400.622953) (xy 206.786487 -400.67636) (xy 206.794607 -400.731536) (xy 206.795116 -400.759422)
			(xy 206.794607 -400.787308) (xy 206.786487 -400.842484) (xy 206.770419 -400.895891) (xy 206.746747 -400.946388)
			(xy 206.715974 -400.992901) (xy 206.678757 -401.034438) (xy 206.635889 -401.070113) (xy 206.588283 -401.099167)
			(xy 206.536954 -401.120979) (xy 206.482997 -401.135085) (xy 206.42756 -401.141185) (xy 206.371826 -401.139148)
			(xy 206.316983 -401.129018) (xy 206.264199 -401.111011) (xy 206.214599 -401.08551) (xy 206.169241 -401.053059)
			(xy 206.129092 -401.01435) (xy 206.095006 -400.970207) (xy 206.06771 -400.921572) (xy 206.047787 -400.869481)
			(xy 206.035661 -400.815044) (xy 206.03159 -400.759422) (xy 203.040672 -400.759422) (xy 203.038635 -400.764337)
			(xy 203.035687 -400.794182) (xy 203.041527 -400.823598) (xy 203.05565 -400.850054) (xy 203.065888 -400.861022)
			(xy 203.853288 -401.648422) (xy 203.871306 -401.667142) (xy 203.90187 -401.709155) (xy 203.925496 -401.755427)
			(xy 203.941603 -401.804821) (xy 203.949797 -401.856126) (xy 203.950316 -401.882102) (xy 203.950316 -401.952968)
			(xy 205.921102 -401.952968)
		)
		(stroke
			(width 0)
			(type solid)
		)
		(fill yes)
		(layer "In13.Cu")
		(net "AGND_HSC")
	)
	(gr_poly
		(pts
			(xy 224.991422 -401.990814) (xy 225.015254 -401.978866) (xy 225.065816 -401.961978) (xy 225.118437 -401.953447)
			(xy 225.145092 -401.952968) (xy 227.257102 -401.952968) (xy 228.608128 -400.601942) (xy 228.626833 -400.58392)
			(xy 228.668854 -400.553392) (xy 228.715135 -400.529817) (xy 228.764536 -400.513776) (xy 228.815838 -400.505664)
			(xy 228.841808 -400.505168) (xy 229.736904 -400.505168) (xy 229.751903 -400.504635) (xy 229.780608 -400.495928)
			(xy 229.805552 -400.479265) (xy 229.824586 -400.45608) (xy 229.836071 -400.428369) (xy 229.839021 -400.398517)
			(xy 229.833179 -400.369094) (xy 229.81905 -400.342633) (xy 229.808786 -400.331686) (xy 228.94798 -399.47088)
			(xy 228.882702 -399.47088) (xy 228.871924 -399.471385) (xy 228.852267 -399.480234) (xy 228.837944 -399.496345)
			(xy 228.831458 -399.516904) (xy 228.833942 -399.538318) (xy 228.839014 -399.547842) (xy 228.85184 -399.5701)
			(xy 228.872058 -399.617325) (xy 228.885755 -399.666836) (xy 228.892686 -399.717737) (xy 228.893116 -399.743422)
			(xy 228.89263 -399.770673) (xy 228.884874 -399.824621) (xy 228.869519 -399.876916) (xy 228.846877 -399.926493)
			(xy 228.817411 -399.972343) (xy 228.78172 -400.013534) (xy 228.740529 -400.049225) (xy 228.694679 -400.078691)
			(xy 228.645102 -400.101333) (xy 228.592807 -400.116688) (xy 228.538859 -400.124444) (xy 228.484357 -400.124444)
			(xy 228.430409 -400.116688) (xy 228.378114 -400.101333) (xy 228.328537 -400.078691) (xy 228.282687 -400.049225)
			(xy 228.241496 -400.013534) (xy 228.205805 -399.972343) (xy 228.176339 -399.926493) (xy 228.153697 -399.876916)
			(xy 228.138342 -399.824621) (xy 228.130586 -399.770673) (xy 228.1301 -399.743422) (xy 228.13084 -399.708931)
			(xy 228.143232 -399.641071) (xy 228.154738 -399.608548) (xy 228.159307 -399.595246) (xy 228.161738 -399.567236)
			(xy 228.156434 -399.539625) (xy 228.1438 -399.514508) (xy 228.124792 -399.493791) (xy 228.100853 -399.479046)
			(xy 228.0738 -399.471391) (xy 228.059742 -399.47088) (xy 225.57232 -399.47088) (xy 224.28454 -400.75866)
			(xy 223.954086 -400.75866) (xy 223.939091 -400.759194) (xy 223.93834 -400.759422) (xy 227.36759 -400.759422)
			(xy 227.371661 -400.7038) (xy 227.383787 -400.649363) (xy 227.40371 -400.597272) (xy 227.431006 -400.548637)
			(xy 227.465092 -400.504494) (xy 227.505241 -400.465785) (xy 227.550599 -400.433334) (xy 227.600199 -400.407833)
			(xy 227.652983 -400.389826) (xy 227.707826 -400.379696) (xy 227.76356 -400.377659) (xy 227.818997 -400.383759)
			(xy 227.872954 -400.397865) (xy 227.924283 -400.419677) (xy 227.971889 -400.448731) (xy 228.014757 -400.484406)
			(xy 228.051974 -400.525943) (xy 228.082747 -400.572456) (xy 228.106419 -400.622953) (xy 228.122487 -400.67636)
			(xy 228.130607 -400.731536) (xy 228.131116 -400.759422) (xy 228.130607 -400.787308) (xy 228.122487 -400.842484)
			(xy 228.106419 -400.895891) (xy 228.082747 -400.946388) (xy 228.051974 -400.992901) (xy 228.014757 -401.034438)
			(xy 227.971889 -401.070113) (xy 227.924283 -401.099167) (xy 227.872954 -401.120979) (xy 227.818997 -401.135085)
			(xy 227.76356 -401.141185) (xy 227.707826 -401.139148) (xy 227.652983 -401.129018) (xy 227.600199 -401.111011)
			(xy 227.550599 -401.08551) (xy 227.505241 -401.053059) (xy 227.465092 -401.01435) (xy 227.431006 -400.970207)
			(xy 227.40371 -400.921572) (xy 227.383787 -400.869481) (xy 227.371661 -400.815044) (xy 227.36759 -400.759422)
			(xy 223.93834 -400.759422) (xy 223.910394 -400.767901) (xy 223.885459 -400.784563) (xy 223.866433 -400.807744)
			(xy 223.854953 -400.835449) (xy 223.852008 -400.865293) (xy 223.857851 -400.894708) (xy 223.87198 -400.921161)
			(xy 223.882204 -400.932142) (xy 224.958402 -402.008086)
		)
		(stroke
			(width 0)
			(type solid)
		)
		(fill yes)
		(layer "In13.Cu")
		(net "AGND_HSC")
	)
	(gr_poly
		(pts
			(arc
				(start 214.28837 -402.006054)
				(mid 214.388443 -401.947735)
				(end 214.502492 -401.927568)
			)
			(xy 216.563702 -401.927568)
			(arc
				(start 217.177366 -401.31365)
				(mid 217.198399 -401.200526)
				(end 217.100404 -401.140422)
			)
			(arc
				(start 217.081608 -401.14093)
				(mid 216.811841 -400.489655)
				(end 217.463116 -400.759422)
			)
			(arc
				(start 217.462608 -400.778218)
				(mid 217.522787 -400.876045)
				(end 217.635836 -400.85518)
			)
			(arc
				(start 217.838528 -400.652742)
				(mid 217.945741 -400.581104)
				(end 218.072208 -400.555968)
			)
			(arc
				(start 219.076524 -400.555968)
				(mid 219.17039 -400.493249)
				(end 219.148406 -400.382486)
			)
			(xy 218.34094 -399.57502) (xy 218.20886 -399.57502) (xy 218.20886 -399.632932)
			(arc
				(start 218.210638 -399.639536)
				(mid 218.221469 -399.690979)
				(end 218.225116 -399.743422)
			)
			(arc
				(start 218.225116 -399.743422)
				(mid 217.843608 -400.12493)
				(end 217.4621 -399.743422)
			)
			(arc
				(start 217.4621 -399.743422)
				(mid 217.462967 -399.716945)
				(end 217.465656 -399.69059)
			)
			(arc
				(start 217.465656 -399.69059)
				(mid 217.441658 -399.609935)
				(end 217.365072 -399.57502)
			)
			(xy 214.93226 -399.57502) (xy 213.68004 -400.82724)
			(arc
				(start 213.354666 -400.82724)
				(mid 213.2608 -400.889959)
				(end 213.282784 -401.000722)
			)
		)
		(stroke
			(width 0)
			(type solid)
		)
		(fill yes)
		(layer "In13.Cu")
		(net "AGND_HSC")
	)
	(gr_poly
		(pts
			(xy 226.498912 -410.362654)
			(arc
				(start 226.498912 -410.25699)
				(mid 226.467635 -410.210091)
				(end 226.412298 -410.220922)
			)
			(arc
				(start 226.09048 -410.54274)
				(mid 225.983282 -410.614461)
				(end 225.8568 -410.639768)
			)
			(arc
				(start 217.84564 -410.639768)
				(mid 217.719137 -410.614511)
				(end 217.61196 -410.54274)
			)
			(arc
				(start 217.34272 -410.2735)
				(mid 217.270999 -410.166302)
				(end 217.245692 -410.03982)
			)
			(arc
				(start 217.245692 -408.59964)
				(mid 217.270949 -408.473137)
				(end 217.34272 -408.36596)
			)
			(xy 218.594432 -407.113994) (xy 218.594432 -404.429214) (xy 218.506802 -404.341584)
			(arc
				(start 218.49461 -404.337774)
				(mid 218.335845 -404.242539)
				(end 218.24061 -404.083774)
			)
			(xy 218.2368 -404.071582) (xy 218.099386 -403.934168) (xy 217.098626 -403.934168) (xy 216.286588 -404.746206)
			(arc
				(start 216.286588 -405.642064)
				(mid 216.349224 -405.735896)
				(end 216.459816 -405.713946)
			)
			(xy 217.449146 -404.724616)
			(arc
				(start 217.452956 -404.712424)
				(mid 217.5908 -404.516917)
				(end 217.817954 -404.441914)
			)
			(arc
				(start 217.817954 -404.441914)
				(mid 218.087721 -404.553655)
				(end 218.199462 -404.823422)
			)
			(arc
				(start 218.199462 -404.823422)
				(mid 218.124463 -405.05058)
				(end 217.928952 -405.18842)
			)
			(xy 217.91676 -405.19223) (xy 216.779348 -406.329642)
			(arc
				(start 216.779348 -406.416002)
				(mid 216.825996 -406.501459)
				(end 216.923112 -406.508458)
			)
			(arc
				(start 216.923112 -406.508458)
				(mid 217.0005 -406.482641)
				(end 217.081608 -406.473914)
			)
			(arc
				(start 217.081608 -406.473914)
				(mid 217.463116 -406.855422)
				(end 217.081608 -407.23693)
			)
			(arc
				(start 217.081608 -407.23693)
				(mid 217.000511 -407.228156)
				(end 216.923112 -407.202386)
			)
			(arc
				(start 216.923112 -407.202386)
				(mid 216.825987 -407.209371)
				(end 216.779348 -407.294842)
			)
			(xy 216.779348 -410.497274) (xy 217.202766 -410.920692) (xy 225.940874 -410.920692)
		)
		(stroke
			(width 0)
			(type solid)
		)
		(fill yes)
		(layer "In13.Cu")
		(net "AGND_HSC")
	)
	(gr_poly
		(pts
			(xy 216.117932 -410.497274) (xy 216.117932 -410.079952) (xy 216.117408 -410.064972) (xy 216.108728 -410.036299)
			(xy 216.092099 -410.011379) (xy 216.068954 -409.992358) (xy 216.041284 -409.980873) (xy 216.011472 -409.977913)
			(xy 215.982084 -409.983734) (xy 215.95565 -409.997833) (xy 215.944704 -410.00807) (xy 215.45296 -410.49956)
			(xy 215.43424 -410.517578) (xy 215.392228 -410.548142) (xy 215.345956 -410.571768) (xy 215.296561 -410.587874)
			(xy 215.245256 -410.596066) (xy 215.21928 -410.596588) (xy 207.2386 -410.596588) (xy 207.212619 -410.596088)
			(xy 207.161303 -410.587923) (xy 207.111898 -410.571826) (xy 207.065621 -410.548194) (xy 207.023614 -410.517609)
			(xy 207.00492 -410.49956) (xy 206.75092 -410.24556) (xy 206.732903 -410.22684) (xy 206.70234 -410.184827)
			(xy 206.678716 -410.138555) (xy 206.662611 -410.08916) (xy 206.65442 -410.037856) (xy 206.653892 -410.01188)
			(xy 206.653892 -408.59964) (xy 206.654389 -408.573659) (xy 206.66255 -408.522341) (xy 206.678645 -408.472934)
			(xy 206.702278 -408.426656) (xy 206.732865 -408.38465) (xy 206.75092 -408.36596) (xy 207.944212 -407.172414)
			(xy 207.944212 -404.446994) (xy 207.838802 -404.341584) (xy 207.82661 -404.337774) (xy 207.80117 -404.329568)
			(xy 207.752701 -404.307029) (xy 207.707852 -404.277944) (xy 207.667504 -404.242882) (xy 207.632444 -404.202532)
			(xy 207.603362 -404.157682) (xy 207.580825 -404.109211) (xy 207.57261 -404.083774) (xy 207.5688 -404.071582)
			(xy 207.421226 -403.924008) (xy 206.435706 -403.924008) (xy 205.377288 -404.982426) (xy 205.377288 -405.883364)
			(xy 205.377814 -405.89834) (xy 205.386496 -405.927005) (xy 205.403124 -405.951917) (xy 205.426265 -405.97093)
			(xy 205.453929 -405.98241) (xy 205.483734 -405.985366) (xy 205.513114 -405.979546) (xy 205.539541 -405.965449)
			(xy 205.550516 -405.955246) (xy 206.781146 -404.724616) (xy 206.784956 -404.712424) (xy 206.793275 -404.686681)
			(xy 206.816163 -404.637663) (xy 206.845746 -404.59237) (xy 206.881431 -404.55171) (xy 206.922501 -404.516498)
			(xy 206.968133 -404.48744) (xy 207.017412 -404.465119) (xy 207.06935 -404.449983) (xy 207.122905 -404.442335)
			(xy 207.149954 -404.441914) (xy 207.177208 -404.442374) (xy 207.231163 -404.450126) (xy 207.283465 -404.465478)
			(xy 207.33305 -404.488118) (xy 207.378907 -404.517586) (xy 207.420103 -404.55328) (xy 207.4558 -404.594474)
			(xy 207.48527 -404.640329) (xy 207.507913 -404.689912) (xy 207.523269 -404.742213) (xy 207.531024 -404.796168)
			(xy 207.531462 -404.823422) (xy 207.530989 -404.850468) (xy 207.523344 -404.904017) (xy 207.508212 -404.955949)
			(xy 207.485895 -405.005222) (xy 207.456842 -405.050849) (xy 207.421634 -405.091914) (xy 207.380978 -405.127594)
			(xy 207.33569 -405.157173) (xy 207.286678 -405.180057) (xy 207.260952 -405.18842) (xy 207.24876 -405.19223)
			(xy 205.887828 -406.553162) (xy 205.887828 -406.855422) (xy 206.03159 -406.855422) (xy 206.035661 -406.7998)
			(xy 206.047787 -406.745363) (xy 206.06771 -406.693272) (xy 206.095006 -406.644637) (xy 206.129092 -406.600494)
			(xy 206.169241 -406.561785) (xy 206.214599 -406.529334) (xy 206.264199 -406.503833) (xy 206.316983 -406.485826)
			(xy 206.371826 -406.475696) (xy 206.42756 -406.473659) (xy 206.482997 -406.479759) (xy 206.536954 -406.493865)
			(xy 206.588283 -406.515677) (xy 206.635889 -406.544731) (xy 206.678757 -406.580406) (xy 206.715974 -406.621943)
			(xy 206.746747 -406.668456) (xy 206.770419 -406.718953) (xy 206.786487 -406.77236) (xy 206.794607 -406.827536)
			(xy 206.795116 -406.855422) (xy 206.794607 -406.883308) (xy 206.786487 -406.938484) (xy 206.770419 -406.991891)
			(xy 206.746747 -407.042388) (xy 206.715974 -407.088901) (xy 206.678757 -407.130438) (xy 206.635889 -407.166113)
			(xy 206.588283 -407.195167) (xy 206.536954 -407.216979) (xy 206.482997 -407.231085) (xy 206.42756 -407.237185)
			(xy 206.371826 -407.235148) (xy 206.316983 -407.225018) (xy 206.264199 -407.207011) (xy 206.214599 -407.18151)
			(xy 206.169241 -407.149059) (xy 206.129092 -407.11035) (xy 206.095006 -407.066207) (xy 206.06771 -407.017572)
			(xy 206.047787 -406.965481) (xy 206.035661 -406.911044) (xy 206.03159 -406.855422) (xy 205.887828 -406.855422)
			(xy 205.887828 -410.438854) (xy 206.443326 -410.994352) (xy 215.620854 -410.994352)
		)
		(stroke
			(width 0)
			(type solid)
		)
		(fill yes)
		(layer "In13.Cu")
		(net "AGND_HSC")
	)
	(gr_poly
		(pts
			(xy 198.43496 -113.538762) (xy 198.434485 -113.5241) (xy 198.426171 -113.495981) (xy 198.41021 -113.471384)
			(xy 198.387918 -113.452334) (xy 198.361132 -113.440404) (xy 198.332061 -113.436575) (xy 198.3031 -113.441165)
			(xy 198.289672 -113.447068) (xy 198.263848 -113.458844) (xy 198.209585 -113.475481) (xy 198.153458 -113.483899)
			(xy 198.12508 -113.484406) (xy 198.09783 -113.483919) (xy 198.043885 -113.47616) (xy 197.991592 -113.460803)
			(xy 197.942018 -113.438161) (xy 197.89617 -113.408694) (xy 197.854983 -113.373003) (xy 197.819294 -113.331814)
			(xy 197.789829 -113.285964) (xy 197.76719 -113.236389) (xy 197.751836 -113.184096) (xy 197.74408 -113.13015)
			(xy 197.74408 -113.07565) (xy 197.751836 -113.021704) (xy 197.76719 -112.969411) (xy 197.789829 -112.919836)
			(xy 197.819294 -112.873986) (xy 197.854983 -112.832797) (xy 197.89617 -112.797106) (xy 197.942018 -112.767639)
			(xy 197.991592 -112.744997) (xy 198.043885 -112.72964) (xy 198.09783 -112.721881) (xy 198.12508 -112.72139)
			(xy 198.153458 -112.72191) (xy 198.209586 -112.730317) (xy 198.26385 -112.746949) (xy 198.289672 -112.758728)
			(xy 198.303113 -112.7646) (xy 198.332072 -112.769183) (xy 198.361141 -112.765354) (xy 198.387926 -112.75343)
			(xy 198.410222 -112.73439) (xy 198.426195 -112.709804) (xy 198.43453 -112.681694) (xy 198.43496 -112.667034)
			(xy 198.43496 -112.560862) (xy 198.434485 -112.5462) (xy 198.426171 -112.518081) (xy 198.41021 -112.493484)
			(xy 198.387918 -112.474434) (xy 198.361132 -112.462504) (xy 198.332061 -112.458675) (xy 198.3031 -112.463265)
			(xy 198.289672 -112.469168) (xy 198.263848 -112.480944) (xy 198.209585 -112.497581) (xy 198.153458 -112.505999)
			(xy 198.12508 -112.506506) (xy 198.09783 -112.506019) (xy 198.043885 -112.49826) (xy 197.991592 -112.482903)
			(xy 197.942018 -112.460261) (xy 197.89617 -112.430794) (xy 197.854983 -112.395103) (xy 197.819294 -112.353914)
			(xy 197.789829 -112.308064) (xy 197.76719 -112.258489) (xy 197.751836 -112.206196) (xy 197.74408 -112.15225)
			(xy 197.74408 -112.09775) (xy 197.751836 -112.043804) (xy 197.76719 -111.991511) (xy 197.789829 -111.941936)
			(xy 197.819294 -111.896086) (xy 197.854983 -111.854897) (xy 197.89617 -111.819206) (xy 197.942018 -111.789739)
			(xy 197.991592 -111.767097) (xy 198.043885 -111.75174) (xy 198.09783 -111.743981) (xy 198.12508 -111.74349)
			(xy 198.153458 -111.74401) (xy 198.209586 -111.752417) (xy 198.26385 -111.769049) (xy 198.289672 -111.780828)
			(xy 198.303113 -111.7867) (xy 198.332072 -111.791283) (xy 198.361141 -111.787454) (xy 198.387926 -111.77553)
			(xy 198.410222 -111.75649) (xy 198.426195 -111.731904) (xy 198.43453 -111.703794) (xy 198.43496 -111.689134)
			(xy 198.43496 -111.38535) (xy 197.995286 -110.945676) (xy 194.079876 -110.945676) (xy 194.049053 -110.945016)
			(xy 193.988277 -110.934678) (xy 193.958972 -110.925102) (xy 193.950844 -110.922308) (xy 193.381376 -110.922308)
			(xy 193.367067 -110.922795) (xy 193.339573 -110.930735) (xy 193.315358 -110.945985) (xy 193.296319 -110.967351)
			(xy 193.283949 -110.993157) (xy 193.279219 -111.021381) (xy 193.282497 -111.04981) (xy 193.293529 -111.076216)
			(xy 193.302128 -111.087662) (xy 193.316963 -111.106715) (xy 193.341899 -111.148068) (xy 193.361012 -111.192414)
			(xy 193.373951 -111.238937) (xy 193.380479 -111.286783) (xy 193.380868 -111.310928) (xy 193.38035 -111.338136)
			(xy 193.372067 -111.391917) (xy 193.355696 -111.443812) (xy 193.331621 -111.492611) (xy 193.3004 -111.537179)
			(xy 193.262762 -111.576478) (xy 193.219583 -111.609593) (xy 193.195956 -111.623094) (xy 193.16954 -111.637572)
			(xy 193.16954 -112.048544) (xy 193.213228 -112.05464) (xy 193.240149 -112.058967) (xy 193.292471 -112.074307)
			(xy 193.342077 -112.09694) (xy 193.387955 -112.126404) (xy 193.429171 -112.1621) (xy 193.464887 -112.203299)
			(xy 193.494373 -112.249164) (xy 193.517029 -112.298758) (xy 193.532395 -112.351073) (xy 193.540156 -112.405043)
			(xy 193.540155 -112.459568) (xy 193.532392 -112.513537) (xy 193.517025 -112.565852) (xy 193.494367 -112.615446)
			(xy 193.46488 -112.661309) (xy 193.429164 -112.702508) (xy 193.387946 -112.738202) (xy 193.342067 -112.767665)
			(xy 193.292461 -112.790297) (xy 193.240138 -112.805636) (xy 193.213228 -112.810036) (xy 193.16954 -112.816132)
			(xy 193.16954 -113.514632) (xy 196.46341 -113.514632) (xy 196.467481 -113.45901) (xy 196.479607 -113.404573)
			(xy 196.49953 -113.352482) (xy 196.526826 -113.303847) (xy 196.560912 -113.259704) (xy 196.601061 -113.220995)
			(xy 196.646419 -113.188544) (xy 196.696019 -113.163043) (xy 196.748803 -113.145036) (xy 196.803646 -113.134906)
			(xy 196.85938 -113.132869) (xy 196.914817 -113.138969) (xy 196.968774 -113.153075) (xy 197.020103 -113.174887)
			(xy 197.067709 -113.203941) (xy 197.110577 -113.239616) (xy 197.147794 -113.281153) (xy 197.178567 -113.327666)
			(xy 197.202239 -113.378163) (xy 197.218307 -113.43157) (xy 197.226427 -113.486746) (xy 197.226936 -113.514632)
			(xy 197.226427 -113.542518) (xy 197.218307 -113.597694) (xy 197.202239 -113.651101) (xy 197.178567 -113.701598)
			(xy 197.147794 -113.748111) (xy 197.110577 -113.789648) (xy 197.067709 -113.825323) (xy 197.020103 -113.854377)
			(xy 196.968774 -113.876189) (xy 196.914817 -113.890295) (xy 196.85938 -113.896395) (xy 196.803646 -113.894358)
			(xy 196.748803 -113.884228) (xy 196.696019 -113.866221) (xy 196.646419 -113.84072) (xy 196.601061 -113.808269)
			(xy 196.560912 -113.76956) (xy 196.526826 -113.725417) (xy 196.49953 -113.676782) (xy 196.479607 -113.624691)
			(xy 196.467481 -113.570254) (xy 196.46341 -113.514632) (xy 193.16954 -113.514632) (xy 193.16954 -114.303048)
			(xy 198.43496 -114.303048)
		)
		(stroke
			(width 0)
			(type solid)
		)
		(fill yes)
		(layer "In13.Cu")
		(net "GND")
	)
	(gr_poly
		(pts
			(xy 329.36688 -35.974274) (xy 329.36688 -34.107628) (xy 327.484486 -32.225234) (xy 327.448164 -32.261302)
			(xy 327.426487 -32.282589) (xy 327.377636 -32.318702) (xy 327.323679 -32.346618) (xy 327.26598 -32.365631)
			(xy 327.205997 -32.375261) (xy 327.175622 -32.375856) (xy 327.148368 -32.375372) (xy 327.094416 -32.367618)
			(xy 327.042116 -32.352265) (xy 326.992533 -32.329626) (xy 326.946676 -32.300161) (xy 326.905479 -32.26447)
			(xy 326.869781 -32.22328) (xy 326.840308 -32.177429) (xy 326.817659 -32.12785) (xy 326.802297 -32.075553)
			(xy 326.794533 -32.021601) (xy 326.794114 -31.994348) (xy 326.794699 -31.963971) (xy 326.804321 -31.903983)
			(xy 326.823329 -31.846278) (xy 326.851242 -31.792316) (xy 326.887356 -31.74346) (xy 326.908668 -31.721806)
			(xy 326.944736 -31.685484) (xy 323.643752 -28.3845) (xy 323.250814 -28.3845) (xy 320.671698 -30.963616)
			(xy 320.671698 -32.904176) (xy 321.06489 -33.297368) (xy 326.300082 -33.297368) (xy 326.304153 -33.241746)
			(xy 326.316279 -33.187309) (xy 326.336202 -33.135218) (xy 326.363498 -33.086583) (xy 326.397584 -33.04244)
			(xy 326.437733 -33.003731) (xy 326.483091 -32.97128) (xy 326.532691 -32.945779) (xy 326.585475 -32.927772)
			(xy 326.640318 -32.917642) (xy 326.696052 -32.915605) (xy 326.751489 -32.921705) (xy 326.805446 -32.935811)
			(xy 326.856775 -32.957623) (xy 326.904381 -32.986677) (xy 326.947249 -33.022352) (xy 326.984466 -33.063889)
			(xy 327.015239 -33.110402) (xy 327.038911 -33.160899) (xy 327.054979 -33.214306) (xy 327.063099 -33.269482)
			(xy 327.063608 -33.297368) (xy 327.063099 -33.325254) (xy 327.054979 -33.38043) (xy 327.038911 -33.433837)
			(xy 327.015239 -33.484334) (xy 326.984466 -33.530847) (xy 326.947249 -33.572384) (xy 326.904381 -33.608059)
			(xy 326.856775 -33.637113) (xy 326.805446 -33.658925) (xy 326.751489 -33.673031) (xy 326.696052 -33.679131)
			(xy 326.640318 -33.677094) (xy 326.585475 -33.666964) (xy 326.532691 -33.648957) (xy 326.483091 -33.623456)
			(xy 326.437733 -33.591005) (xy 326.397584 -33.552296) (xy 326.363498 -33.508153) (xy 326.336202 -33.459518)
			(xy 326.316279 -33.407427) (xy 326.304153 -33.35299) (xy 326.300082 -33.297368) (xy 321.06489 -33.297368)
			(xy 322.158614 -34.391092) (xy 325.440038 -34.391092) (xy 325.444109 -34.33547) (xy 325.456235 -34.281033)
			(xy 325.476158 -34.228942) (xy 325.503454 -34.180307) (xy 325.53754 -34.136164) (xy 325.577689 -34.097455)
			(xy 325.623047 -34.065004) (xy 325.672647 -34.039503) (xy 325.725431 -34.021496) (xy 325.780274 -34.011366)
			(xy 325.836008 -34.009329) (xy 325.891445 -34.015429) (xy 325.945402 -34.029535) (xy 325.996731 -34.051347)
			(xy 326.044337 -34.080401) (xy 326.087205 -34.116076) (xy 326.124422 -34.157613) (xy 326.155195 -34.204126)
			(xy 326.178867 -34.254623) (xy 326.194935 -34.30803) (xy 326.203055 -34.363206) (xy 326.203564 -34.391092)
			(xy 326.203055 -34.418978) (xy 326.194935 -34.474154) (xy 326.178867 -34.527561) (xy 326.155195 -34.578058)
			(xy 326.124422 -34.624571) (xy 326.087205 -34.666108) (xy 326.044337 -34.701783) (xy 325.996731 -34.730837)
			(xy 325.945402 -34.752649) (xy 325.891445 -34.766755) (xy 325.836008 -34.772855) (xy 325.780274 -34.770818)
			(xy 325.725431 -34.760688) (xy 325.672647 -34.742681) (xy 325.623047 -34.71718) (xy 325.577689 -34.684729)
			(xy 325.53754 -34.64602) (xy 325.503454 -34.601877) (xy 325.476158 -34.553242) (xy 325.456235 -34.501151)
			(xy 325.444109 -34.446714) (xy 325.440038 -34.391092) (xy 322.158614 -34.391092) (xy 322.754752 -34.98723)
			(xy 327.653394 -34.98723) (xy 327.657465 -34.931608) (xy 327.669591 -34.877171) (xy 327.689514 -34.82508)
			(xy 327.71681 -34.776445) (xy 327.750896 -34.732302) (xy 327.791045 -34.693593) (xy 327.836403 -34.661142)
			(xy 327.886003 -34.635641) (xy 327.938787 -34.617634) (xy 327.99363 -34.607504) (xy 328.049364 -34.605467)
			(xy 328.104801 -34.611567) (xy 328.158758 -34.625673) (xy 328.210087 -34.647485) (xy 328.257693 -34.676539)
			(xy 328.300561 -34.712214) (xy 328.337778 -34.753751) (xy 328.368551 -34.800264) (xy 328.392223 -34.850761)
			(xy 328.408291 -34.904168) (xy 328.416411 -34.959344) (xy 328.41692 -34.98723) (xy 328.416411 -35.015116)
			(xy 328.408291 -35.070292) (xy 328.392223 -35.123699) (xy 328.368551 -35.174196) (xy 328.337778 -35.220709)
			(xy 328.300561 -35.262246) (xy 328.257693 -35.297921) (xy 328.210087 -35.326975) (xy 328.158758 -35.348787)
			(xy 328.104801 -35.362893) (xy 328.049364 -35.368993) (xy 327.99363 -35.366956) (xy 327.938787 -35.356826)
			(xy 327.886003 -35.338819) (xy 327.836403 -35.313318) (xy 327.791045 -35.280867) (xy 327.750896 -35.242158)
			(xy 327.71681 -35.198015) (xy 327.689514 -35.14938) (xy 327.669591 -35.097289) (xy 327.657465 -35.042852)
			(xy 327.653394 -34.98723) (xy 322.754752 -34.98723) (xy 323.50075 -35.733228) (xy 324.184262 -35.733228)
			(xy 324.188333 -35.677606) (xy 324.200459 -35.623169) (xy 324.220382 -35.571078) (xy 324.247678 -35.522443)
			(xy 324.281764 -35.4783) (xy 324.321913 -35.439591) (xy 324.367271 -35.40714) (xy 324.416871 -35.381639)
			(xy 324.469655 -35.363632) (xy 324.524498 -35.353502) (xy 324.580232 -35.351465) (xy 324.635669 -35.357565)
			(xy 324.689626 -35.371671) (xy 324.740955 -35.393483) (xy 324.788561 -35.422537) (xy 324.831429 -35.458212)
			(xy 324.868646 -35.499749) (xy 324.899419 -35.546262) (xy 324.923091 -35.596759) (xy 324.939159 -35.650166)
			(xy 324.947279 -35.705342) (xy 324.947788 -35.733228) (xy 324.947279 -35.761114) (xy 324.939159 -35.81629)
			(xy 324.923091 -35.869697) (xy 324.899419 -35.920194) (xy 324.868646 -35.966707) (xy 324.831429 -36.008244)
			(xy 324.788561 -36.043919) (xy 324.740955 -36.072973) (xy 324.689626 -36.094785) (xy 324.635669 -36.108891)
			(xy 324.580232 -36.114991) (xy 324.524498 -36.112954) (xy 324.469655 -36.102824) (xy 324.416871 -36.084817)
			(xy 324.367271 -36.059316) (xy 324.321913 -36.026865) (xy 324.281764 -35.988156) (xy 324.247678 -35.944013)
			(xy 324.220382 -35.895378) (xy 324.200459 -35.843287) (xy 324.188333 -35.78885) (xy 324.184262 -35.733228)
			(xy 323.50075 -35.733228) (xy 324.474586 -36.707064) (xy 325.015604 -36.707064) (xy 325.019675 -36.651442)
			(xy 325.031801 -36.597005) (xy 325.051724 -36.544914) (xy 325.07902 -36.496279) (xy 325.113106 -36.452136)
			(xy 325.153255 -36.413427) (xy 325.198613 -36.380976) (xy 325.248213 -36.355475) (xy 325.300997 -36.337468)
			(xy 325.35584 -36.327338) (xy 325.411574 -36.325301) (xy 325.467011 -36.331401) (xy 325.520968 -36.345507)
			(xy 325.572297 -36.367319) (xy 325.619903 -36.396373) (xy 325.662771 -36.432048) (xy 325.699988 -36.473585)
			(xy 325.730761 -36.520098) (xy 325.754433 -36.570595) (xy 325.770501 -36.624002) (xy 325.778621 -36.679178)
			(xy 325.77913 -36.707064) (xy 325.778621 -36.73495) (xy 325.770501 -36.790126) (xy 325.754433 -36.843533)
			(xy 325.730761 -36.89403) (xy 325.699988 -36.940543) (xy 325.662771 -36.98208) (xy 325.619903 -37.017755)
			(xy 325.572297 -37.046809) (xy 325.520968 -37.068621) (xy 325.467011 -37.082727) (xy 325.411574 -37.088827)
			(xy 325.35584 -37.08679) (xy 325.300997 -37.07666) (xy 325.248213 -37.058653) (xy 325.198613 -37.033152)
			(xy 325.153255 -37.000701) (xy 325.113106 -36.961992) (xy 325.07902 -36.917849) (xy 325.051724 -36.869214)
			(xy 325.031801 -36.817123) (xy 325.019675 -36.762686) (xy 325.015604 -36.707064) (xy 324.474586 -36.707064)
			(xy 324.994524 -37.227002) (xy 328.114152 -37.227002)
		)
		(stroke
			(width 0)
			(type solid)
		)
		(fill yes)
		(layer "In13.Cu")
		(net "GND")
	)
	(gr_poly
		(pts
			(xy 0.654812 -17.86255)
			(arc
				(start 0.66675 -17.85493)
				(mid 0.827347 -17.756522)
				(end 0.991362 -17.663922)
			)
			(xy 1.017524 -17.61998)
			(arc
				(start 1.017524 -13.780008)
				(mid 1.305283 -13.085295)
				(end 1.999996 -12.797536)
			)
			(arc
				(start 11.102594 -12.797536)
				(mid 13.236139 -11.913635)
				(end 14.11986 -9.780016)
			)
			(xy 14.11986 -3.945382)
			(arc
				(start 14.10081 -3.90779)
				(mid 13.825764 -3.583504)
				(end 13.726922 -3.16992)
			)
			(arc
				(start 13.726922 -3.16992)
				(mid 13.825371 -2.757062)
				(end 14.09954 -2.433066)
			)
			(xy 14.11986 -2.392934) (xy 14.11986 -1.016) (xy 80.684116 -1.016) (xy 80.684116 -2.39141)
			(arc
				(start 80.704944 -2.43205)
				(mid 81.07796 -3.169158)
				(end 80.704944 -3.906266)
			)
			(xy 80.684116 -3.946906)
			(arc
				(start 80.684116 -9.780016)
				(mid 81.568091 -11.91374)
				(end 83.70189 -12.797536)
			)
			(arc
				(start 124.102622 -12.797536)
				(mid 126.236167 -11.913635)
				(end 127.119888 -9.780016)
			)
			(arc
				(start 127.119888 -9.223756)
				(mid 127.113727 -9.202804)
				(end 127.099314 -9.186418)
			)
			(arc
				(start 127.099314 -9.186418)
				(mid 126.839825 -8.890054)
				(end 126.728982 -8.512048)
			)
			(xy 126.700534 -8.46963) (xy 126.687326 -8.463026)
			(arc
				(start 126.66345 -8.457184)
				(mid 126.627619 -8.471973)
				(end 126.61265 -8.50773)
			)
			(arc
				(start 126.61265 -9.780016)
				(mid 125.877331 -11.555233)
				(end 124.102114 -12.290552)
			)
			(arc
				(start 83.70189 -12.290552)
				(mid 81.926673 -11.555233)
				(end 81.191354 -9.780016)
			)
			(xy 81.191354 -1.28524) (xy 81.19364 -1.28524)
			(arc
				(start 81.19364 -0.999998)
				(mid 81.049612 -0.652282)
				(end 80.701896 -0.508254)
			)
			(arc
				(start 14.10208 -0.508254)
				(mid 13.754364 -0.652282)
				(end 13.610336 -0.999998)
			)
			(xy 13.610336 -1.28524) (xy 13.612622 -1.28524)
			(arc
				(start 13.612622 -9.780016)
				(mid 12.877303 -11.555233)
				(end 11.102086 -12.290552)
			)
			(arc
				(start 1.999996 -12.290552)
				(mid 0.946792 -12.726804)
				(end 0.51054 -13.780008)
			)
			(arc
				(start 0.51054 -17.769332)
				(mid 0.517626 -17.795211)
				(end 0.536956 -17.813782)
			)
			(xy 0.62738 -17.863566)
		)
		(stroke
			(width 0)
			(type solid)
		)
		(fill yes)
		(layer "In13.Cu")
		(net "GND")
	)
	(gr_poly
		(pts
			(xy 69.8373 -26.162508) (xy 69.8373 -14.575028) (xy 67.3608 -12.098528) (xy 62.81928 -12.098528)
			(xy 61.95822 -12.959588) (xy 61.95822 -14.69644) (xy 61.958643 -14.709628) (xy 61.965415 -14.73512)
			(xy 61.978496 -14.758023) (xy 61.997012 -14.776808) (xy 62.019725 -14.790218) (xy 62.045117 -14.797356)
			(xy 62.058296 -14.79804) (xy 62.086545 -14.799003) (xy 62.142306 -14.808234) (xy 62.196096 -14.825591)
			(xy 62.246736 -14.850694) (xy 62.293118 -14.882994) (xy 62.334227 -14.921783) (xy 62.369164 -14.966213)
			(xy 62.397163 -15.015311) (xy 62.417612 -15.068003) (xy 62.430063 -15.123135) (xy 62.434244 -15.179501)
			(xy 62.430063 -15.235867) (xy 62.417611 -15.290999) (xy 62.397162 -15.34369) (xy 62.369163 -15.392788)
			(xy 62.334226 -15.437218) (xy 62.293117 -15.476007) (xy 62.246734 -15.508307) (xy 62.196094 -15.533409)
			(xy 62.142305 -15.550766) (xy 62.086543 -15.559997) (xy 62.058296 -15.561056) (xy 62.045111 -15.56167)
			(xy 62.019712 -15.568816) (xy 61.996995 -15.582237) (xy 61.978482 -15.601037) (xy 61.965411 -15.623957)
			(xy 61.958656 -15.649463) (xy 61.95822 -15.662656) (xy 61.95822 -16.809974) (xy 61.958756 -16.824929)
			(xy 61.967433 -16.853555) (xy 61.984021 -16.878445) (xy 62.007103 -16.89747) (xy 62.034703 -16.909001)
			(xy 62.064458 -16.912053) (xy 62.093824 -16.906363) (xy 62.107318 -16.89989) (xy 62.134978 -16.885892)
			(xy 62.193714 -16.866071) (xy 62.254885 -16.856027) (xy 62.28588 -16.85544) (xy 62.31313 -16.855902)
			(xy 62.367077 -16.863656) (xy 62.41937 -16.879008) (xy 62.468947 -16.901646) (xy 62.514797 -16.93111)
			(xy 62.555986 -16.966799) (xy 62.591678 -17.007987) (xy 62.621144 -17.053836) (xy 62.643785 -17.103411)
			(xy 62.65914 -17.155704) (xy 62.666897 -17.20965) (xy 62.666897 -17.26415) (xy 62.65914 -17.318096)
			(xy 62.643785 -17.370389) (xy 62.621144 -17.419964) (xy 62.591678 -17.465813) (xy 62.555986 -17.507001)
			(xy 62.514797 -17.54269) (xy 62.468947 -17.572154) (xy 62.41937 -17.594792) (xy 62.367077 -17.610144)
			(xy 62.31313 -17.617898) (xy 62.28588 -17.618456) (xy 62.254888 -17.617829) (xy 62.193724 -17.607777)
			(xy 62.134984 -17.587988) (xy 62.107318 -17.574006) (xy 62.09384 -17.567471) (xy 62.064454 -17.56174)
			(xy 62.034669 -17.564773) (xy 62.007042 -17.57631) (xy 61.983946 -17.59536) (xy 61.967363 -17.620288)
			(xy 61.958719 -17.648952) (xy 61.95822 -17.663922) (xy 61.95822 -18.280144) (xy 62.539926 -18.280144)
			(xy 62.539926 -18.225651) (xy 62.547682 -18.171712) (xy 62.563034 -18.119426) (xy 62.585671 -18.069856)
			(xy 62.615132 -18.024013) (xy 62.650817 -17.982829) (xy 62.691999 -17.947142) (xy 62.737841 -17.917679)
			(xy 62.787409 -17.89504) (xy 62.839695 -17.879685) (xy 62.893633 -17.871928) (xy 62.92088 -17.87144)
			(xy 62.935864 -17.871546) (xy 62.965744 -17.873838) (xy 62.98057 -17.876012) (xy 62.994395 -17.877749)
			(xy 63.022057 -17.874491) (xy 63.047809 -17.863876) (xy 63.069732 -17.846695) (xy 63.086194 -17.824227)
			(xy 63.09597 -17.798146) (xy 63.09833 -17.770392) (xy 63.09614 -17.756632) (xy 63.09292 -17.738708)
			(xy 63.089488 -17.702452) (xy 63.089282 -17.684242) (xy 63.08971 -17.656985) (xy 63.097462 -17.603026)
			(xy 63.112815 -17.550719) (xy 63.135456 -17.50113) (xy 63.164924 -17.455268) (xy 63.200619 -17.414066)
			(xy 63.241814 -17.378364) (xy 63.287671 -17.348888) (xy 63.337257 -17.326239) (xy 63.389561 -17.310877)
			(xy 63.443519 -17.303115) (xy 63.498032 -17.303111) (xy 63.551991 -17.310866) (xy 63.604297 -17.326221)
			(xy 63.653885 -17.348864) (xy 63.699746 -17.378334) (xy 63.740946 -17.414031) (xy 63.776647 -17.455228)
			(xy 63.80612 -17.501087) (xy 63.828768 -17.550673) (xy 63.844127 -17.602978) (xy 63.851886 -17.656936)
			(xy 63.851888 -17.711449) (xy 63.84413 -17.765408) (xy 63.828773 -17.817713) (xy 63.806127 -17.867301)
			(xy 63.776655 -17.91316) (xy 63.740957 -17.954359) (xy 63.699758 -17.990057) (xy 63.653898 -18.019529)
			(xy 63.604311 -18.042174) (xy 63.552005 -18.057531) (xy 63.498047 -18.065288) (xy 63.47079 -18.06575)
			(xy 63.455806 -18.065635) (xy 63.425926 -18.063349) (xy 63.4111 -18.061178) (xy 63.397278 -18.059423)
			(xy 63.369615 -18.062688) (xy 63.343865 -18.073307) (xy 63.321942 -18.090491) (xy 63.305481 -18.112961)
			(xy 63.295705 -18.139043) (xy 63.293342 -18.166797) (xy 63.29553 -18.180558) (xy 63.298748 -18.198482)
			(xy 63.302181 -18.234739) (xy 63.302388 -18.252948) (xy 63.30187 -18.280195) (xy 63.294109 -18.334133)
			(xy 63.27875 -18.386417) (xy 63.256107 -18.435984) (xy 63.226641 -18.481823) (xy 63.190951 -18.523003)
			(xy 63.149765 -18.558685) (xy 63.103919 -18.588142) (xy 63.054348 -18.610776) (xy 63.002061 -18.626124)
			(xy 62.948121 -18.633876) (xy 62.893628 -18.633872) (xy 62.83969 -18.626114) (xy 62.787404 -18.610758)
			(xy 62.737836 -18.588118) (xy 62.691995 -18.558655) (xy 62.650813 -18.522967) (xy 62.615129 -18.481783)
			(xy 62.585668 -18.435939) (xy 62.563032 -18.386369) (xy 62.54768 -18.334083) (xy 62.539926 -18.280144)
			(xy 61.95822 -18.280144) (xy 61.95822 -19.268948) (xy 62.538862 -19.268948) (xy 62.542933 -19.213326)
			(xy 62.555059 -19.158889) (xy 62.574982 -19.106798) (xy 62.602278 -19.058163) (xy 62.636364 -19.01402)
			(xy 62.676513 -18.975311) (xy 62.721871 -18.94286) (xy 62.771471 -18.917359) (xy 62.824255 -18.899352)
			(xy 62.879098 -18.889222) (xy 62.934832 -18.887185) (xy 62.990269 -18.893285) (xy 63.044226 -18.907391)
			(xy 63.095555 -18.929203) (xy 63.143161 -18.958257) (xy 63.186029 -18.993932) (xy 63.223246 -19.035469)
			(xy 63.254019 -19.081982) (xy 63.277691 -19.132479) (xy 63.293759 -19.185886) (xy 63.301879 -19.241062)
			(xy 63.302388 -19.268948) (xy 63.301879 -19.296834) (xy 63.293759 -19.35201) (xy 63.277691 -19.405417)
			(xy 63.254019 -19.455914) (xy 63.223246 -19.502427) (xy 63.186029 -19.543964) (xy 63.143161 -19.579639)
			(xy 63.095555 -19.608693) (xy 63.044226 -19.630505) (xy 62.990269 -19.644611) (xy 62.934832 -19.650711)
			(xy 62.879098 -19.648674) (xy 62.824255 -19.638544) (xy 62.771471 -19.620537) (xy 62.721871 -19.595036)
			(xy 62.676513 -19.562585) (xy 62.636364 -19.523876) (xy 62.602278 -19.479733) (xy 62.574982 -19.431098)
			(xy 62.555059 -19.379007) (xy 62.542933 -19.32457) (xy 62.538862 -19.268948) (xy 61.95822 -19.268948)
			(xy 61.95822 -23.404322) (xy 62.63462 -23.404322) (xy 62.638691 -23.3487) (xy 62.650817 -23.294263)
			(xy 62.67074 -23.242172) (xy 62.698036 -23.193537) (xy 62.732122 -23.149394) (xy 62.772271 -23.110685)
			(xy 62.817629 -23.078234) (xy 62.867229 -23.052733) (xy 62.920013 -23.034726) (xy 62.974856 -23.024596)
			(xy 63.03059 -23.022559) (xy 63.086027 -23.028659) (xy 63.139984 -23.042765) (xy 63.191313 -23.064577)
			(xy 63.238919 -23.093631) (xy 63.281787 -23.129306) (xy 63.319004 -23.170843) (xy 63.349777 -23.217356)
			(xy 63.373449 -23.267853) (xy 63.389517 -23.32126) (xy 63.397637 -23.376436) (xy 63.398146 -23.404322)
			(xy 63.397637 -23.432208) (xy 63.389517 -23.487384) (xy 63.373449 -23.540791) (xy 63.349777 -23.591288)
			(xy 63.319004 -23.637801) (xy 63.281787 -23.679338) (xy 63.238919 -23.715013) (xy 63.191313 -23.744067)
			(xy 63.139984 -23.765879) (xy 63.086027 -23.779985) (xy 63.03059 -23.786085) (xy 62.974856 -23.784048)
			(xy 62.920013 -23.773918) (xy 62.867229 -23.755911) (xy 62.817629 -23.73041) (xy 62.772271 -23.697959)
			(xy 62.732122 -23.65925) (xy 62.698036 -23.615107) (xy 62.67074 -23.566472) (xy 62.650817 -23.514381)
			(xy 62.638691 -23.459944) (xy 62.63462 -23.404322) (xy 61.95822 -23.404322) (xy 61.95822 -25.537922)
			(xy 62.58382 -25.537922) (xy 62.587891 -25.4823) (xy 62.600017 -25.427863) (xy 62.61994 -25.375772)
			(xy 62.647236 -25.327137) (xy 62.681322 -25.282994) (xy 62.721471 -25.244285) (xy 62.766829 -25.211834)
			(xy 62.816429 -25.186333) (xy 62.869213 -25.168326) (xy 62.924056 -25.158196) (xy 62.97979 -25.156159)
			(xy 63.035227 -25.162259) (xy 63.089184 -25.176365) (xy 63.140513 -25.198177) (xy 63.188119 -25.227231)
			(xy 63.230987 -25.262906) (xy 63.268204 -25.304443) (xy 63.298977 -25.350956) (xy 63.322649 -25.401453)
			(xy 63.338717 -25.45486) (xy 63.346837 -25.510036) (xy 63.347346 -25.537922) (xy 63.346837 -25.565808)
			(xy 63.339727 -25.614122) (xy 63.57442 -25.614122) (xy 63.578491 -25.5585) (xy 63.590617 -25.504063)
			(xy 63.61054 -25.451972) (xy 63.637836 -25.403337) (xy 63.671922 -25.359194) (xy 63.712071 -25.320485)
			(xy 63.757429 -25.288034) (xy 63.807029 -25.262533) (xy 63.859813 -25.244526) (xy 63.914656 -25.234396)
			(xy 63.97039 -25.232359) (xy 64.025827 -25.238459) (xy 64.079784 -25.252565) (xy 64.131113 -25.274377)
			(xy 64.178719 -25.303431) (xy 64.221587 -25.339106) (xy 64.258804 -25.380643) (xy 64.289577 -25.427156)
			(xy 64.313249 -25.477653) (xy 64.329317 -25.53106) (xy 64.337437 -25.586236) (xy 64.337946 -25.614122)
			(xy 64.337437 -25.642008) (xy 64.329317 -25.697184) (xy 64.313249 -25.750591) (xy 64.289577 -25.801088)
			(xy 64.258804 -25.847601) (xy 64.221587 -25.889138) (xy 64.178719 -25.924813) (xy 64.131113 -25.953867)
			(xy 64.079784 -25.975679) (xy 64.025827 -25.989785) (xy 63.97039 -25.995885) (xy 63.914656 -25.993848)
			(xy 63.859813 -25.983718) (xy 63.807029 -25.965711) (xy 63.757429 -25.94021) (xy 63.712071 -25.907759)
			(xy 63.671922 -25.86905) (xy 63.637836 -25.824907) (xy 63.61054 -25.776272) (xy 63.590617 -25.724181)
			(xy 63.578491 -25.669744) (xy 63.57442 -25.614122) (xy 63.339727 -25.614122) (xy 63.338717 -25.620984)
			(xy 63.322649 -25.674391) (xy 63.298977 -25.724888) (xy 63.268204 -25.771401) (xy 63.230987 -25.812938)
			(xy 63.188119 -25.848613) (xy 63.140513 -25.877667) (xy 63.089184 -25.899479) (xy 63.035227 -25.913585)
			(xy 62.97979 -25.919685) (xy 62.924056 -25.917648) (xy 62.869213 -25.907518) (xy 62.816429 -25.889511)
			(xy 62.766829 -25.86401) (xy 62.721471 -25.831559) (xy 62.681322 -25.79285) (xy 62.647236 -25.748707)
			(xy 62.61994 -25.700072) (xy 62.600017 -25.647981) (xy 62.587891 -25.593544) (xy 62.58382 -25.537922)
			(xy 61.95822 -25.537922) (xy 61.95822 -26.289508) (xy 62.28588 -26.617168) (xy 69.38264 -26.617168)
		)
		(stroke
			(width 0)
			(type solid)
		)
		(fill yes)
		(layer "In13.Cu")
		(net "P12V_OCP_V3_2")
	)
	(gr_poly
		(pts
			(xy 408.615134 -184.622948) (xy 408.62996 -184.622449) (xy 408.658368 -184.613949) (xy 408.683136 -184.597646)
			(xy 408.702177 -184.574915) (xy 408.713884 -184.547672) (xy 408.717272 -184.518214) (xy 408.712054 -184.489025)
			(xy 408.69867 -184.462565) (xy 408.688794 -184.451498) (xy 408.669207 -184.430089) (xy 408.636079 -184.382451)
			(xy 408.610544 -184.330347) (xy 408.593191 -184.274978) (xy 408.584421 -184.21762) (xy 408.583892 -184.188608)
			(xy 408.584355 -184.161355) (xy 408.592111 -184.107403) (xy 408.607466 -184.055104) (xy 408.630108 -184.005523)
			(xy 408.659576 -183.959669) (xy 408.69527 -183.918475) (xy 408.736463 -183.882781) (xy 408.782316 -183.853312)
			(xy 408.831897 -183.830669) (xy 408.884195 -183.815313) (xy 408.938147 -183.807555) (xy 408.9654 -183.8071)
			(xy 408.993166 -183.807601) (xy 409.04811 -183.815656) (xy 409.101304 -183.831596) (xy 409.151624 -183.855084)
			(xy 409.198004 -183.885623) (xy 409.239464 -183.922566) (xy 409.275127 -183.965133) (xy 409.304237 -184.012423)
			(xy 409.315666 -184.037732) (xy 409.321721 -184.050569) (xy 409.339703 -184.072516) (xy 409.363025 -184.088673)
			(xy 409.389891 -184.097796) (xy 409.41823 -184.099181) (xy 409.445857 -184.092721) (xy 409.470643 -184.078915)
			(xy 409.48102 -184.069228) (xy 409.53182 -184.018428) (xy 409.53182 -182.739284) (xy 409.507863 -182.72728)
			(xy 409.463277 -182.697559) (xy 409.42329 -182.66189) (xy 409.388688 -182.620976) (xy 409.360152 -182.575622)
			(xy 409.338244 -182.526721) (xy 409.323395 -182.475235) (xy 409.315898 -182.422178) (xy 409.3159 -182.368594)
			(xy 409.323401 -182.315538) (xy 409.338253 -182.264053) (xy 409.360165 -182.215153) (xy 409.388704 -182.169802)
			(xy 409.423309 -182.12889) (xy 409.463299 -182.093224) (xy 409.507887 -182.063506) (xy 409.53182 -182.051452)
			(xy 409.53182 -176.711864) (xy 409.507864 -176.699857) (xy 409.46328 -176.67013) (xy 409.423294 -176.634457)
			(xy 409.388692 -176.593541) (xy 409.360155 -176.548186) (xy 409.338244 -176.499285) (xy 409.32339 -176.447799)
			(xy 409.315886 -176.394741) (xy 409.315412 -176.367948) (xy 409.315929 -176.339208) (xy 409.324546 -176.282376)
			(xy 409.341591 -176.227481) (xy 409.366679 -176.175765) (xy 409.399242 -176.128397) (xy 409.418536 -176.10709)
			(xy 409.428618 -176.095557) (xy 409.441978 -176.068007) (xy 409.446577 -176.037735) (xy 409.441999 -176.00746)
			(xy 409.428658 -175.979901) (xy 409.418536 -175.968406) (xy 409.399262 -175.94708) (xy 409.36669 -175.89972)
			(xy 409.341591 -175.848008) (xy 409.324533 -175.793117) (xy 409.315903 -175.736288) (xy 409.315412 -175.707548)
			(xy 409.315863 -175.680752) (xy 409.323357 -175.627686) (xy 409.338204 -175.576192) (xy 409.360112 -175.527282)
			(xy 409.38865 -175.48192) (xy 409.423255 -175.440998) (xy 409.463247 -175.405322) (xy 409.507839 -175.375595)
			(xy 409.53182 -175.363632) (xy 409.53182 -174.103284) (xy 409.507863 -174.09128) (xy 409.463277 -174.061559)
			(xy 409.42329 -174.02589) (xy 409.388688 -173.984976) (xy 409.360152 -173.939622) (xy 409.338244 -173.890721)
			(xy 409.323395 -173.839235) (xy 409.315898 -173.786178) (xy 409.3159 -173.732594) (xy 409.323401 -173.679538)
			(xy 409.338253 -173.628053) (xy 409.360165 -173.579153) (xy 409.388704 -173.533802) (xy 409.423309 -173.49289)
			(xy 409.463299 -173.457224) (xy 409.507887 -173.427506) (xy 409.53182 -173.415452) (xy 409.53182 -168.075864)
			(xy 409.507864 -168.063857) (xy 409.46328 -168.03413) (xy 409.423294 -167.998457) (xy 409.388692 -167.957541)
			(xy 409.360155 -167.912186) (xy 409.338244 -167.863285) (xy 409.32339 -167.811799) (xy 409.315886 -167.758741)
			(xy 409.315412 -167.731948) (xy 409.315848 -167.705679) (xy 409.323055 -167.653638) (xy 409.337338 -167.603079)
			(xy 409.358428 -167.55496) (xy 409.385924 -167.510192) (xy 409.40228 -167.489632) (xy 409.407917 -167.482096)
			(xy 409.413822 -167.464245) (xy 409.412913 -167.445465) (xy 409.405309 -167.428269) (xy 409.398978 -167.421306)
			(xy 408.71394 -166.736268) (xy 402.871178 -166.736268) (xy 401.237196 -168.37025) (xy 401.264977 -168.401734)
			(xy 401.315294 -168.468961) (xy 401.359237 -168.540518) (xy 401.396435 -168.615801) (xy 401.426575 -168.694177)
			(xy 401.449404 -168.774986) (xy 401.46473 -168.857547) (xy 401.472423 -168.941166) (xy 401.472908 -168.983152)
			(xy 401.472437 -169.02543) (xy 401.464639 -169.109627) (xy 401.449106 -169.192744) (xy 401.425969 -169.274074)
			(xy 401.395427 -169.352922) (xy 401.35774 -169.428615) (xy 401.313229 -169.500508) (xy 401.262274 -169.567987)
			(xy 401.205311 -169.630477) (xy 401.142824 -169.687444) (xy 401.075348 -169.738402) (xy 401.003457 -169.782916)
			(xy 400.927766 -169.820608) (xy 400.848919 -169.851154) (xy 400.767591 -169.874295) (xy 400.684474 -169.889833)
			(xy 400.600278 -169.897635) (xy 400.558 -169.89806) (xy 400.513295 -169.897519) (xy 400.424312 -169.888798)
			(xy 400.336604 -169.871438) (xy 400.251008 -169.845606) (xy 400.168339 -169.811548) (xy 400.089387 -169.769588)
			(xy 400.014905 -169.720127) (xy 399.979896 -169.69232) (xy 399.944336 -169.66311) (xy 399.565876 -170.04157)
			(xy 399.565876 -171.025496) (xy 399.668996 -171.025496) (xy 399.668996 -170.9408) (xy 399.677047 -170.856486)
			(xy 399.693076 -170.77332) (xy 399.716937 -170.692053) (xy 399.748416 -170.613423) (xy 399.787227 -170.538142)
			(xy 399.833017 -170.46689) (xy 399.885373 -170.400314) (xy 399.943821 -170.339016) (xy 400.007831 -170.283551)
			(xy 400.076823 -170.234422) (xy 400.150173 -170.192073) (xy 400.227216 -170.156889) (xy 400.307255 -170.129187)
			(xy 400.389564 -170.109219) (xy 400.473399 -170.097166) (xy 400.558 -170.093136) (xy 400.642601 -170.097166)
			(xy 400.726436 -170.109219) (xy 400.808745 -170.129187) (xy 400.888784 -170.156889) (xy 400.965827 -170.192073)
			(xy 401.039177 -170.234422) (xy 401.108169 -170.283551) (xy 401.172179 -170.339016) (xy 401.230627 -170.400314)
			(xy 401.282983 -170.46689) (xy 401.328773 -170.538142) (xy 401.367584 -170.613423) (xy 401.399063 -170.692053)
			(xy 401.422924 -170.77332) (xy 401.438953 -170.856486) (xy 401.447004 -170.9408) (xy 401.447508 -170.983148)
			(xy 401.447004 -171.025496) (xy 401.438953 -171.10981) (xy 401.422924 -171.192976) (xy 401.399063 -171.274243)
			(xy 401.367584 -171.352873) (xy 401.328773 -171.428154) (xy 401.282983 -171.499406) (xy 401.230627 -171.565982)
			(xy 401.172179 -171.62728) (xy 401.108169 -171.682745) (xy 401.039177 -171.731874) (xy 400.965827 -171.774223)
			(xy 400.888784 -171.809407) (xy 400.808745 -171.837109) (xy 400.726436 -171.857077) (xy 400.642601 -171.86913)
			(xy 400.558 -171.873161) (xy 400.473399 -171.86913) (xy 400.389564 -171.857077) (xy 400.307255 -171.837109)
			(xy 400.227216 -171.809407) (xy 400.150173 -171.774223) (xy 400.076823 -171.731874) (xy 400.007831 -171.682745)
			(xy 399.943821 -171.62728) (xy 399.885373 -171.565982) (xy 399.833017 -171.499406) (xy 399.787227 -171.428154)
			(xy 399.748416 -171.352873) (xy 399.716937 -171.274243) (xy 399.693076 -171.192976) (xy 399.677047 -171.10981)
			(xy 399.668996 -171.025496) (xy 399.565876 -171.025496) (xy 399.565876 -174.715932) (xy 399.566388 -174.730849)
			(xy 399.574993 -174.759414) (xy 399.591487 -174.784273) (xy 399.614464 -174.803302) (xy 399.64196 -174.814877)
			(xy 399.671628 -174.81801) (xy 399.700935 -174.812433) (xy 399.727379 -174.798622) (xy 399.748702 -174.777757)
			(xy 399.756376 -174.764954) (xy 399.778261 -174.726306) (xy 399.828447 -174.653019) (xy 399.885495 -174.584939)
			(xy 399.948871 -174.522705) (xy 400.017977 -174.466904) (xy 400.092164 -174.418059) (xy 400.170734 -174.376631)
			(xy 400.252947 -174.343009) (xy 400.338031 -174.317509) (xy 400.425185 -174.300372) (xy 400.513589 -174.291758)
			(xy 400.558 -174.291244) (xy 400.600278 -174.291732) (xy 400.684474 -174.299534) (xy 400.767592 -174.315071)
			(xy 400.84892 -174.338212) (xy 400.927767 -174.368757) (xy 401.003459 -174.406447) (xy 401.075351 -174.450961)
			(xy 401.142829 -174.501917) (xy 401.205317 -174.558883) (xy 401.262283 -174.621371) (xy 401.313239 -174.688849)
			(xy 401.357753 -174.760741) (xy 401.395443 -174.836433) (xy 401.425988 -174.91528) (xy 401.449129 -174.996608)
			(xy 401.464666 -175.079726) (xy 401.472468 -175.163922) (xy 401.472468 -175.248478) (xy 401.464666 -175.332674)
			(xy 401.449129 -175.415792) (xy 401.425988 -175.49712) (xy 401.395443 -175.575967) (xy 401.357753 -175.651659)
			(xy 401.313239 -175.723551) (xy 401.262283 -175.791029) (xy 401.205317 -175.853517) (xy 401.142829 -175.910483)
			(xy 401.075351 -175.961439) (xy 401.003459 -176.005953) (xy 400.927767 -176.043643) (xy 400.84892 -176.074188)
			(xy 400.767592 -176.097329) (xy 400.684474 -176.112866) (xy 400.600278 -176.120668) (xy 400.558 -176.12106)
			(xy 400.513589 -176.120534) (xy 400.425184 -176.111928) (xy 400.33803 -176.094796) (xy 400.252945 -176.0693)
			(xy 400.170731 -176.03568) (xy 400.092162 -175.994252) (xy 400.017977 -175.945405) (xy 399.948873 -175.889601)
			(xy 399.885502 -175.827363) (xy 399.82846 -175.759278) (xy 399.778283 -175.685986) (xy 399.756376 -175.64735)
			(xy 399.748718 -175.634537) (xy 399.72738 -175.613684) (xy 399.700928 -175.599883) (xy 399.671617 -175.594313)
			(xy 399.641946 -175.597447) (xy 399.614446 -175.609019) (xy 399.591461 -175.628041) (xy 399.574951 -175.652893)
			(xy 399.566325 -175.681454) (xy 399.565876 -175.696372) (xy 399.565876 -177.248496) (xy 399.668996 -177.248496)
			(xy 399.668996 -177.1638) (xy 399.677047 -177.079486) (xy 399.693076 -176.99632) (xy 399.716937 -176.915053)
			(xy 399.748416 -176.836423) (xy 399.787227 -176.761142) (xy 399.833017 -176.68989) (xy 399.885373 -176.623314)
			(xy 399.943821 -176.562016) (xy 400.007831 -176.506551) (xy 400.076823 -176.457422) (xy 400.150173 -176.415073)
			(xy 400.227216 -176.379889) (xy 400.307255 -176.352187) (xy 400.389564 -176.332219) (xy 400.473399 -176.320166)
			(xy 400.558 -176.316136) (xy 400.642601 -176.320166) (xy 400.726436 -176.332219) (xy 400.808745 -176.352187)
			(xy 400.888784 -176.379889) (xy 400.965827 -176.415073) (xy 401.039177 -176.457422) (xy 401.108169 -176.506551)
			(xy 401.172179 -176.562016) (xy 401.230627 -176.623314) (xy 401.282983 -176.68989) (xy 401.328773 -176.761142)
			(xy 401.367584 -176.836423) (xy 401.399063 -176.915053) (xy 401.422924 -176.99632) (xy 401.438953 -177.079486)
			(xy 401.447004 -177.1638) (xy 401.447508 -177.206148) (xy 401.447004 -177.248496) (xy 401.438953 -177.33281)
			(xy 401.422924 -177.415976) (xy 401.399063 -177.497243) (xy 401.367584 -177.575873) (xy 401.328773 -177.651154)
			(xy 401.282983 -177.722406) (xy 401.230627 -177.788982) (xy 401.172179 -177.85028) (xy 401.108169 -177.905745)
			(xy 401.039177 -177.954874) (xy 400.965827 -177.997223) (xy 400.888784 -178.032407) (xy 400.808745 -178.060109)
			(xy 400.726436 -178.080077) (xy 400.642601 -178.09213) (xy 400.558 -178.096161) (xy 400.473399 -178.09213)
			(xy 400.389564 -178.080077) (xy 400.307255 -178.060109) (xy 400.227216 -178.032407) (xy 400.150173 -177.997223)
			(xy 400.076823 -177.954874) (xy 400.007831 -177.905745) (xy 399.943821 -177.85028) (xy 399.885373 -177.788982)
			(xy 399.833017 -177.722406) (xy 399.787227 -177.651154) (xy 399.748416 -177.575873) (xy 399.716937 -177.497243)
			(xy 399.693076 -177.415976) (xy 399.677047 -177.33281) (xy 399.668996 -177.248496) (xy 399.565876 -177.248496)
			(xy 399.565876 -180.938932) (xy 399.566388 -180.953849) (xy 399.574993 -180.982414) (xy 399.591487 -181.007273)
			(xy 399.614464 -181.026302) (xy 399.64196 -181.037877) (xy 399.671628 -181.04101) (xy 399.700935 -181.035433)
			(xy 399.727379 -181.021622) (xy 399.748702 -181.000757) (xy 399.756376 -180.987954) (xy 399.778261 -180.949306)
			(xy 399.828447 -180.876019) (xy 399.885495 -180.807939) (xy 399.948871 -180.745705) (xy 400.017977 -180.689904)
			(xy 400.092164 -180.641059) (xy 400.170734 -180.599631) (xy 400.252947 -180.566009) (xy 400.338031 -180.540509)
			(xy 400.425185 -180.523372) (xy 400.513589 -180.514758) (xy 400.558 -180.514244) (xy 400.600278 -180.514732)
			(xy 400.684474 -180.522534) (xy 400.767592 -180.538071) (xy 400.84892 -180.561212) (xy 400.927767 -180.591757)
			(xy 401.003459 -180.629447) (xy 401.075351 -180.673961) (xy 401.142829 -180.724917) (xy 401.205317 -180.781883)
			(xy 401.262283 -180.844371) (xy 401.313239 -180.911849) (xy 401.357753 -180.983741) (xy 401.395443 -181.059433)
			(xy 401.425988 -181.13828) (xy 401.449129 -181.219608) (xy 401.464666 -181.302726) (xy 401.472468 -181.386922)
			(xy 401.472468 -181.471478) (xy 401.464666 -181.555674) (xy 401.449129 -181.638792) (xy 401.425988 -181.72012)
			(xy 401.395443 -181.798967) (xy 401.357753 -181.874659) (xy 401.313239 -181.946551) (xy 401.262283 -182.014029)
			(xy 401.205317 -182.076517) (xy 401.142829 -182.133483) (xy 401.075351 -182.184439) (xy 401.003459 -182.228953)
			(xy 400.927767 -182.266643) (xy 400.84892 -182.297188) (xy 400.767592 -182.320329) (xy 400.684474 -182.335866)
			(xy 400.600278 -182.343668) (xy 400.558 -182.34406) (xy 400.513589 -182.343534) (xy 400.425184 -182.334928)
			(xy 400.33803 -182.317796) (xy 400.252945 -182.2923) (xy 400.170731 -182.25868) (xy 400.092162 -182.217252)
			(xy 400.017977 -182.168405) (xy 399.948873 -182.112601) (xy 399.885502 -182.050363) (xy 399.82846 -181.982278)
			(xy 399.778283 -181.908986) (xy 399.756376 -181.87035) (xy 399.748718 -181.857537) (xy 399.72738 -181.836684)
			(xy 399.700928 -181.822883) (xy 399.671617 -181.817313) (xy 399.641946 -181.820447) (xy 399.614446 -181.832019)
			(xy 399.591461 -181.851041) (xy 399.574951 -181.875893) (xy 399.566325 -181.904454) (xy 399.565876 -181.919372)
			(xy 399.565876 -183.471496) (xy 399.668996 -183.471496) (xy 399.668996 -183.3868) (xy 399.677047 -183.302486)
			(xy 399.693076 -183.21932) (xy 399.716937 -183.138053) (xy 399.748416 -183.059423) (xy 399.787227 -182.984142)
			(xy 399.833017 -182.91289) (xy 399.885373 -182.846314) (xy 399.943821 -182.785016) (xy 400.007831 -182.729551)
			(xy 400.076823 -182.680422) (xy 400.150173 -182.638073) (xy 400.227216 -182.602889) (xy 400.307255 -182.575187)
			(xy 400.389564 -182.555219) (xy 400.473399 -182.543166) (xy 400.558 -182.539136) (xy 400.642601 -182.543166)
			(xy 400.726436 -182.555219) (xy 400.808745 -182.575187) (xy 400.888784 -182.602889) (xy 400.965827 -182.638073)
			(xy 401.039177 -182.680422) (xy 401.108169 -182.729551) (xy 401.172179 -182.785016) (xy 401.230627 -182.846314)
			(xy 401.282983 -182.91289) (xy 401.328773 -182.984142) (xy 401.367584 -183.059423) (xy 401.399063 -183.138053)
			(xy 401.422924 -183.21932) (xy 401.438953 -183.302486) (xy 401.447004 -183.3868) (xy 401.447508 -183.429148)
			(xy 401.447004 -183.471496) (xy 401.438953 -183.55581) (xy 401.422924 -183.638976) (xy 401.399063 -183.720243)
			(xy 401.367584 -183.798873) (xy 401.328773 -183.874154) (xy 401.282983 -183.945406) (xy 401.230627 -184.011982)
			(xy 401.172179 -184.07328) (xy 401.108169 -184.128745) (xy 401.039177 -184.177874) (xy 400.965827 -184.220223)
			(xy 400.888784 -184.255407) (xy 400.808745 -184.283109) (xy 400.726436 -184.303077) (xy 400.642601 -184.31513)
			(xy 400.558 -184.319161) (xy 400.473399 -184.31513) (xy 400.389564 -184.303077) (xy 400.307255 -184.283109)
			(xy 400.227216 -184.255407) (xy 400.150173 -184.220223) (xy 400.076823 -184.177874) (xy 400.007831 -184.128745)
			(xy 399.943821 -184.07328) (xy 399.885373 -184.011982) (xy 399.833017 -183.945406) (xy 399.787227 -183.874154)
			(xy 399.748416 -183.798873) (xy 399.716937 -183.720243) (xy 399.693076 -183.638976) (xy 399.677047 -183.55581)
			(xy 399.668996 -183.471496) (xy 399.565876 -183.471496) (xy 399.565876 -184.479184) (xy 399.70964 -184.622948)
		)
		(stroke
			(width 0)
			(type solid)
		)
		(fill yes)
		(layer "In13.Cu")
		(net "PVCCINFAON_CPU0")
	)
	(gr_poly
		(pts
			(xy 71.97598 -160.251648) (xy 72.40905 -160.251648) (xy 72.41032 -160.210246) (xy 72.410944 -160.18309)
			(xy 72.418934 -160.129362) (xy 72.434465 -160.07731) (xy 72.457221 -160.027988) (xy 72.486743 -159.982392)
			(xy 72.522433 -159.941444) (xy 72.56357 -159.905972) (xy 72.609323 -159.876694) (xy 72.658766 -159.854201)
			(xy 72.710899 -159.838948) (xy 72.764669 -159.831244) (xy 72.818987 -159.831244) (xy 72.872757 -159.838948)
			(xy 72.92489 -159.854201) (xy 72.974333 -159.876694) (xy 73.020086 -159.905972) (xy 73.061223 -159.941444)
			(xy 73.096913 -159.982392) (xy 73.126435 -160.027988) (xy 73.149191 -160.07731) (xy 73.164722 -160.129362)
			(xy 73.172712 -160.18309) (xy 73.173336 -160.210246) (xy 73.174606 -160.251648) (xy 73.64476 -160.251648)
			(xy 75.95108 -157.945328) (xy 75.95108 -149.780752) (xy 75.950623 -149.766929) (xy 75.94321 -149.740297)
			(xy 75.928916 -149.716635) (xy 75.90879 -149.697683) (xy 75.884313 -149.684834) (xy 75.857284 -149.679033)
			(xy 75.82969 -149.680706) (xy 75.81646 -149.68474) (xy 75.81265 -149.68601) (xy 75.783334 -149.695169)
			(xy 75.722708 -149.704994) (xy 75.692 -149.705568) (xy 75.68819 -149.705568) (xy 75.661118 -149.704824)
			(xy 75.607584 -149.696629) (xy 75.555747 -149.680946) (xy 75.50665 -149.65809) (xy 75.461278 -149.62852)
			(xy 75.420544 -149.59283) (xy 75.385267 -149.551738) (xy 75.356156 -149.50607) (xy 75.333797 -149.456745)
			(xy 75.318638 -149.404752) (xy 75.310984 -149.351139) (xy 75.310492 -149.32406) (xy 75.310834 -149.300903)
			(xy 75.316443 -149.254929) (xy 75.321668 -149.232366) (xy 75.323192 -149.22627) (xy 75.323192 -145.17751)
			(xy 75.154282 -145.17751) (xy 75.139804 -145.190718) (xy 75.109697 -145.217412) (xy 75.044813 -145.265004)
			(xy 74.97528 -145.305503) (xy 74.901872 -145.338459) (xy 74.825402 -145.363507) (xy 74.746722 -145.380367)
			(xy 74.666703 -145.388853) (xy 74.62647 -145.389346) (xy 74.586536 -145.388822) (xy 74.507107 -145.380471)
			(xy 74.428985 -145.363863) (xy 74.353027 -145.339181) (xy 74.280065 -145.306695) (xy 74.210899 -145.266761)
			(xy 74.146285 -145.219816) (xy 74.086932 -145.166374) (xy 74.033489 -145.107022) (xy 73.986544 -145.042408)
			(xy 73.946609 -144.973242) (xy 73.914122 -144.90028) (xy 73.889439 -144.824323) (xy 73.872831 -144.746201)
			(xy 73.864479 -144.666772) (xy 73.863962 -144.626838) (xy 73.864431 -144.588575) (xy 73.872097 -144.512433)
			(xy 73.887355 -144.437442) (xy 73.910052 -144.364359) (xy 73.939959 -144.293918) (xy 73.976775 -144.226828)
			(xy 73.998074 -144.195038) (xy 73.976787 -144.16324) (xy 73.939974 -144.096151) (xy 73.910069 -144.025711)
			(xy 73.887371 -143.952629) (xy 73.87211 -143.877641) (xy 73.864439 -143.801501) (xy 73.863962 -143.763238)
			(xy 73.864451 -143.724593) (xy 73.872271 -143.647699) (xy 73.887829 -143.571991) (xy 73.910967 -143.498245)
			(xy 73.941447 -143.427218) (xy 73.978956 -143.35964) (xy 74.02311 -143.296202) (xy 74.073455 -143.237558)
			(xy 74.129474 -143.184307) (xy 74.190593 -143.136997) (xy 74.256186 -143.096113) (xy 74.325577 -143.062075)
			(xy 74.398057 -143.035232) (xy 74.47288 -143.015859) (xy 74.549279 -143.004155) (xy 74.62647 -143.00024)
			(xy 74.703661 -143.004155) (xy 74.78006 -143.015859) (xy 74.854883 -143.035232) (xy 74.927363 -143.062075)
			(xy 74.996754 -143.096113) (xy 75.062347 -143.136997) (xy 75.123466 -143.184307) (xy 75.179485 -143.237558)
			(xy 75.22983 -143.296202) (xy 75.273984 -143.35964) (xy 75.311493 -143.427218) (xy 75.341973 -143.498245)
			(xy 75.365111 -143.571991) (xy 75.380669 -143.647699) (xy 75.388489 -143.724593) (xy 75.388978 -143.763238)
			(xy 75.388467 -143.803551) (xy 75.379985 -143.88373) (xy 75.363087 -143.962566) (xy 75.337963 -144.039178)
			(xy 75.321922 -144.076166) (xy 75.319636 -144.080992) (xy 75.31735 -144.091406) (xy 75.315562 -144.102668)
			(xy 75.320847 -144.12482) (xy 75.335178 -144.142518) (xy 75.355746 -144.152295) (xy 75.367134 -144.152874)
			(xy 75.432412 -144.152874) (xy 75.95108 -143.634206) (xy 75.95108 -142.514828) (xy 75.5142 -142.077948)
			(xy 63.3222 -142.077948) (xy 63.123572 -142.276576) (xy 63.123572 -144.665192) (xy 71.87641 -144.665192)
			(xy 71.880481 -144.60957) (xy 71.892607 -144.555133) (xy 71.91253 -144.503042) (xy 71.939826 -144.454407)
			(xy 71.973912 -144.410264) (xy 72.014061 -144.371555) (xy 72.059419 -144.339104) (xy 72.109019 -144.313603)
			(xy 72.161803 -144.295596) (xy 72.216646 -144.285466) (xy 72.27238 -144.283429) (xy 72.327817 -144.289529)
			(xy 72.381774 -144.303635) (xy 72.433103 -144.325447) (xy 72.480709 -144.354501) (xy 72.523577 -144.390176)
			(xy 72.560794 -144.431713) (xy 72.591567 -144.478226) (xy 72.615239 -144.528723) (xy 72.631307 -144.58213)
			(xy 72.639427 -144.637306) (xy 72.639936 -144.665192) (xy 72.639427 -144.693078) (xy 72.631307 -144.748254)
			(xy 72.615239 -144.801661) (xy 72.591567 -144.852158) (xy 72.560794 -144.898671) (xy 72.523577 -144.940208)
			(xy 72.480709 -144.975883) (xy 72.433103 -145.004937) (xy 72.381774 -145.026749) (xy 72.327817 -145.040855)
			(xy 72.27238 -145.046955) (xy 72.216646 -145.044918) (xy 72.161803 -145.034788) (xy 72.109019 -145.016781)
			(xy 72.059419 -144.99128) (xy 72.014061 -144.958829) (xy 71.973912 -144.92012) (xy 71.939826 -144.875977)
			(xy 71.91253 -144.827342) (xy 71.892607 -144.775251) (xy 71.880481 -144.720814) (xy 71.87641 -144.665192)
			(xy 63.123572 -144.665192) (xy 63.123572 -146.228308) (xy 69.007995 -146.228308) (xy 69.012017 -146.142588)
			(xy 69.024048 -146.05762) (xy 69.043984 -145.974153) (xy 69.071647 -145.892919) (xy 69.106796 -145.814633)
			(xy 69.149122 -145.739982) (xy 69.198251 -145.669623) (xy 69.253754 -145.604173) (xy 69.315141 -145.544209)
			(xy 69.381874 -145.490256) (xy 69.453366 -145.442789) (xy 69.528988 -145.402225) (xy 69.608077 -145.368921)
			(xy 69.689937 -145.343169) (xy 69.773848 -145.325196) (xy 69.859074 -145.31516) (xy 69.944866 -145.313148)
			(xy 70.030468 -145.319179) (xy 70.11513 -145.333199) (xy 70.198107 -145.355085) (xy 70.27867 -145.384646)
			(xy 70.35611 -145.42162) (xy 70.429749 -145.465684) (xy 70.498937 -145.51645) (xy 70.563068 -145.573471)
			(xy 70.621577 -145.636247) (xy 70.67395 -145.704227) (xy 70.719728 -145.776812) (xy 70.758508 -145.853364)
			(xy 70.789949 -145.933212) (xy 70.813775 -146.015653) (xy 70.829776 -146.099963) (xy 70.837811 -146.185401)
			(xy 70.838314 -146.228308) (xy 70.837811 -146.271215) (xy 70.829776 -146.356653) (xy 70.813775 -146.440963)
			(xy 70.789949 -146.523404) (xy 70.758508 -146.603252) (xy 70.719728 -146.679804) (xy 70.67395 -146.752389)
			(xy 70.621577 -146.820369) (xy 70.563068 -146.883145) (xy 70.498937 -146.940166) (xy 70.429749 -146.990932)
			(xy 70.35611 -147.034996) (xy 70.27867 -147.07197) (xy 70.198107 -147.101531) (xy 70.11513 -147.123417)
			(xy 70.030468 -147.137437) (xy 69.944866 -147.143468) (xy 69.859074 -147.141456) (xy 69.773848 -147.13142)
			(xy 69.689937 -147.113447) (xy 69.608077 -147.087695) (xy 69.528988 -147.054391) (xy 69.453366 -147.013827)
			(xy 69.381874 -146.96636) (xy 69.315141 -146.912407) (xy 69.253754 -146.852443) (xy 69.198251 -146.786993)
			(xy 69.149122 -146.716634) (xy 69.106796 -146.641983) (xy 69.071647 -146.563697) (xy 69.043984 -146.482463)
			(xy 69.024048 -146.398996) (xy 69.012017 -146.314028) (xy 69.007995 -146.228308) (xy 63.123572 -146.228308)
			(xy 63.123572 -148.270652) (xy 69.034402 -148.270652) (xy 69.034402 -148.185956) (xy 69.042453 -148.101642)
			(xy 69.058482 -148.018476) (xy 69.082343 -147.937209) (xy 69.113822 -147.858579) (xy 69.152633 -147.783298)
			(xy 69.198423 -147.712046) (xy 69.250779 -147.64547) (xy 69.309227 -147.584172) (xy 69.373237 -147.528707)
			(xy 69.442229 -147.479578) (xy 69.515579 -147.437229) (xy 69.592622 -147.402045) (xy 69.672661 -147.374343)
			(xy 69.75497 -147.354375) (xy 69.838805 -147.342322) (xy 69.923406 -147.338292) (xy 70.008007 -147.342322)
			(xy 70.091842 -147.354375) (xy 70.174151 -147.374343) (xy 70.25419 -147.402045) (xy 70.331233 -147.437229)
			(xy 70.404583 -147.479578) (xy 70.473575 -147.528707) (xy 70.537585 -147.584172) (xy 70.596033 -147.64547)
			(xy 70.648389 -147.712046) (xy 70.694179 -147.783298) (xy 70.73299 -147.858579) (xy 70.764469 -147.937209)
			(xy 70.78833 -148.018476) (xy 70.804359 -148.101642) (xy 70.81241 -148.185956) (xy 70.812914 -148.228304)
			(xy 70.81241 -148.270652) (xy 70.804359 -148.354966) (xy 70.78833 -148.438132) (xy 70.764469 -148.519399)
			(xy 70.73299 -148.598029) (xy 70.694179 -148.67331) (xy 70.648389 -148.744562) (xy 70.596033 -148.811138)
			(xy 70.537585 -148.872436) (xy 70.473575 -148.927901) (xy 70.404583 -148.97703) (xy 70.331233 -149.019379)
			(xy 70.25419 -149.054563) (xy 70.174151 -149.082265) (xy 70.091842 -149.102233) (xy 70.008007 -149.114286)
			(xy 69.923406 -149.118317) (xy 69.838805 -149.114286) (xy 69.75497 -149.102233) (xy 69.672661 -149.082265)
			(xy 69.592622 -149.054563) (xy 69.515579 -149.019379) (xy 69.442229 -148.97703) (xy 69.373237 -148.927901)
			(xy 69.309227 -148.872436) (xy 69.250779 -148.811138) (xy 69.198423 -148.744562) (xy 69.152633 -148.67331)
			(xy 69.113822 -148.598029) (xy 69.082343 -148.519399) (xy 69.058482 -148.438132) (xy 69.042453 -148.354966)
			(xy 69.034402 -148.270652) (xy 63.123572 -148.270652) (xy 63.123572 -152.364694) (xy 69.007995 -152.364694)
			(xy 69.012017 -152.278974) (xy 69.024048 -152.194006) (xy 69.043984 -152.110539) (xy 69.071647 -152.029305)
			(xy 69.106796 -151.951019) (xy 69.149122 -151.876368) (xy 69.198251 -151.806009) (xy 69.253754 -151.740559)
			(xy 69.315141 -151.680595) (xy 69.381874 -151.626642) (xy 69.453366 -151.579175) (xy 69.528988 -151.538611)
			(xy 69.608077 -151.505307) (xy 69.689937 -151.479555) (xy 69.773848 -151.461582) (xy 69.859074 -151.451546)
			(xy 69.944866 -151.449534) (xy 70.030468 -151.455565) (xy 70.11513 -151.469585) (xy 70.198107 -151.491471)
			(xy 70.27867 -151.521032) (xy 70.35611 -151.558006) (xy 70.429749 -151.60207) (xy 70.498937 -151.652836)
			(xy 70.563068 -151.709857) (xy 70.621577 -151.772633) (xy 70.67395 -151.840613) (xy 70.719728 -151.913198)
			(xy 70.758508 -151.98975) (xy 70.789949 -152.069598) (xy 70.813775 -152.152039) (xy 70.829776 -152.236349)
			(xy 70.837811 -152.321787) (xy 70.838314 -152.364694) (xy 70.837811 -152.407601) (xy 70.829776 -152.493039)
			(xy 70.813775 -152.577349) (xy 70.789949 -152.65979) (xy 70.758508 -152.739638) (xy 70.719728 -152.81619)
			(xy 70.67395 -152.888775) (xy 70.621577 -152.956755) (xy 70.563068 -153.019531) (xy 70.498937 -153.076552)
			(xy 70.429749 -153.127318) (xy 70.35611 -153.171382) (xy 70.27867 -153.208356) (xy 70.198107 -153.237917)
			(xy 70.11513 -153.259803) (xy 70.030468 -153.273823) (xy 69.944866 -153.279854) (xy 69.859074 -153.277842)
			(xy 69.773848 -153.267806) (xy 69.689937 -153.249833) (xy 69.608077 -153.224081) (xy 69.528988 -153.190777)
			(xy 69.453366 -153.150213) (xy 69.381874 -153.102746) (xy 69.315141 -153.048793) (xy 69.253754 -152.988829)
			(xy 69.198251 -152.923379) (xy 69.149122 -152.85302) (xy 69.106796 -152.778369) (xy 69.071647 -152.700083)
			(xy 69.043984 -152.618849) (xy 69.024048 -152.535382) (xy 69.012017 -152.450414) (xy 69.007995 -152.364694)
			(xy 63.123572 -152.364694) (xy 63.123572 -154.407038) (xy 69.034402 -154.407038) (xy 69.034402 -154.322342)
			(xy 69.042453 -154.238028) (xy 69.058482 -154.154862) (xy 69.082343 -154.073595) (xy 69.113822 -153.994965)
			(xy 69.152633 -153.919684) (xy 69.198423 -153.848432) (xy 69.250779 -153.781856) (xy 69.309227 -153.720558)
			(xy 69.373237 -153.665093) (xy 69.442229 -153.615964) (xy 69.515579 -153.573615) (xy 69.592622 -153.538431)
			(xy 69.672661 -153.510729) (xy 69.75497 -153.490761) (xy 69.838805 -153.478708) (xy 69.923406 -153.474678)
			(xy 70.008007 -153.478708) (xy 70.091842 -153.490761) (xy 70.174151 -153.510729) (xy 70.25419 -153.538431)
			(xy 70.331233 -153.573615) (xy 70.404583 -153.615964) (xy 70.473575 -153.665093) (xy 70.537585 -153.720558)
			(xy 70.596033 -153.781856) (xy 70.648389 -153.848432) (xy 70.694179 -153.919684) (xy 70.73299 -153.994965)
			(xy 70.764469 -154.073595) (xy 70.78833 -154.154862) (xy 70.804359 -154.238028) (xy 70.81241 -154.322342)
			(xy 70.812914 -154.36469) (xy 70.81241 -154.407038) (xy 70.804359 -154.491352) (xy 70.78833 -154.574518)
			(xy 70.764469 -154.655785) (xy 70.73299 -154.734415) (xy 70.694179 -154.809696) (xy 70.648389 -154.880948)
			(xy 70.596033 -154.947524) (xy 70.537585 -155.008822) (xy 70.473575 -155.064287) (xy 70.404583 -155.113416)
			(xy 70.331233 -155.155765) (xy 70.25419 -155.190949) (xy 70.174151 -155.218651) (xy 70.091842 -155.238619)
			(xy 70.008007 -155.250672) (xy 69.923406 -155.254703) (xy 69.838805 -155.250672) (xy 69.75497 -155.238619)
			(xy 69.672661 -155.218651) (xy 69.592622 -155.190949) (xy 69.515579 -155.155765) (xy 69.442229 -155.113416)
			(xy 69.373237 -155.064287) (xy 69.309227 -155.008822) (xy 69.250779 -154.947524) (xy 69.198423 -154.880948)
			(xy 69.152633 -154.809696) (xy 69.113822 -154.734415) (xy 69.082343 -154.655785) (xy 69.058482 -154.574518)
			(xy 69.042453 -154.491352) (xy 69.034402 -154.407038) (xy 63.123572 -154.407038) (xy 63.123572 -158.49981)
			(xy 69.007995 -158.49981) (xy 69.012017 -158.41409) (xy 69.024048 -158.329122) (xy 69.043984 -158.245655)
			(xy 69.071647 -158.164421) (xy 69.106796 -158.086135) (xy 69.149122 -158.011484) (xy 69.198251 -157.941125)
			(xy 69.253754 -157.875675) (xy 69.315141 -157.815711) (xy 69.381874 -157.761758) (xy 69.453366 -157.714291)
			(xy 69.528988 -157.673727) (xy 69.608077 -157.640423) (xy 69.689937 -157.614671) (xy 69.773848 -157.596698)
			(xy 69.859074 -157.586662) (xy 69.944866 -157.58465) (xy 70.030468 -157.590681) (xy 70.11513 -157.604701)
			(xy 70.198107 -157.626587) (xy 70.27867 -157.656148) (xy 70.35611 -157.693122) (xy 70.429749 -157.737186)
			(xy 70.498937 -157.787952) (xy 70.563068 -157.844973) (xy 70.621577 -157.907749) (xy 70.67395 -157.975729)
			(xy 70.719728 -158.048314) (xy 70.758508 -158.124866) (xy 70.789949 -158.204714) (xy 70.813775 -158.287155)
			(xy 70.829776 -158.371465) (xy 70.837811 -158.456903) (xy 70.838314 -158.49981) (xy 70.837811 -158.542717)
			(xy 70.829776 -158.628155) (xy 70.813775 -158.712465) (xy 70.789949 -158.794906) (xy 70.758508 -158.874754)
			(xy 70.719728 -158.951306) (xy 70.67395 -159.023891) (xy 70.621577 -159.091871) (xy 70.563068 -159.154647)
			(xy 70.498937 -159.211668) (xy 70.429749 -159.262434) (xy 70.35611 -159.306498) (xy 70.27867 -159.343472)
			(xy 70.198107 -159.373033) (xy 70.11513 -159.394919) (xy 70.030468 -159.408939) (xy 69.944866 -159.41497)
			(xy 69.859074 -159.412958) (xy 69.773848 -159.402922) (xy 69.689937 -159.384949) (xy 69.608077 -159.359197)
			(xy 69.528988 -159.325893) (xy 69.453366 -159.285329) (xy 69.381874 -159.237862) (xy 69.315141 -159.183909)
			(xy 69.253754 -159.123945) (xy 69.198251 -159.058495) (xy 69.149122 -158.988136) (xy 69.106796 -158.913485)
			(xy 69.071647 -158.835199) (xy 69.043984 -158.753965) (xy 69.024048 -158.670498) (xy 69.012017 -158.58553)
			(xy 69.007995 -158.49981) (xy 63.123572 -158.49981) (xy 63.123572 -160.542154) (xy 69.034402 -160.542154)
			(xy 69.034402 -160.457458) (xy 69.042453 -160.373144) (xy 69.058482 -160.289978) (xy 69.082343 -160.208711)
			(xy 69.113822 -160.130081) (xy 69.152633 -160.0548) (xy 69.198423 -159.983548) (xy 69.250779 -159.916972)
			(xy 69.309227 -159.855674) (xy 69.373237 -159.800209) (xy 69.442229 -159.75108) (xy 69.515579 -159.708731)
			(xy 69.592622 -159.673547) (xy 69.672661 -159.645845) (xy 69.75497 -159.625877) (xy 69.838805 -159.613824)
			(xy 69.923406 -159.609794) (xy 70.008007 -159.613824) (xy 70.091842 -159.625877) (xy 70.174151 -159.645845)
			(xy 70.25419 -159.673547) (xy 70.331233 -159.708731) (xy 70.404583 -159.75108) (xy 70.473575 -159.800209)
			(xy 70.537585 -159.855674) (xy 70.596033 -159.916972) (xy 70.648389 -159.983548) (xy 70.694179 -160.0548)
			(xy 70.73299 -160.130081) (xy 70.764469 -160.208711) (xy 70.78833 -160.289978) (xy 70.804359 -160.373144)
			(xy 70.81241 -160.457458) (xy 70.812914 -160.499806) (xy 70.81241 -160.542154) (xy 70.804359 -160.626468)
			(xy 70.78833 -160.709634) (xy 70.764469 -160.790901) (xy 70.73299 -160.869531) (xy 70.694179 -160.944812)
			(xy 70.648389 -161.016064) (xy 70.596033 -161.08264) (xy 70.537585 -161.143938) (xy 70.473575 -161.199403)
			(xy 70.404583 -161.248532) (xy 70.331233 -161.290881) (xy 70.25419 -161.326065) (xy 70.174151 -161.353767)
			(xy 70.091842 -161.373735) (xy 70.008007 -161.385788) (xy 69.923406 -161.389819) (xy 69.838805 -161.385788)
			(xy 69.75497 -161.373735) (xy 69.672661 -161.353767) (xy 69.592622 -161.326065) (xy 69.515579 -161.290881)
			(xy 69.442229 -161.248532) (xy 69.373237 -161.199403) (xy 69.309227 -161.143938) (xy 69.250779 -161.08264)
			(xy 69.198423 -161.016064) (xy 69.152633 -160.944812) (xy 69.113822 -160.869531) (xy 69.082343 -160.790901)
			(xy 69.058482 -160.709634) (xy 69.042453 -160.626468) (xy 69.034402 -160.542154) (xy 63.123572 -160.542154)
			(xy 63.123572 -160.549844) (xy 63.284608 -160.71088) (xy 68.404232 -160.71088) (xy 69.29628 -161.602928)
			(xy 70.6247 -161.602928)
		)
		(stroke
			(width 0)
			(type solid)
		)
		(fill yes)
		(layer "In13.Cu")
		(net "PVCCINFAON_CPU1")
	)
	(gr_poly
		(pts
			(arc
				(start 256.800096 -36.291012)
				(mid 258.932727 -35.407647)
				(end 259.816092 -33.275016)
			)
			(xy 259.817616 -32.275018)
			(arc
				(start 259.817616 -13.780008)
				(mid 260.105375 -13.085295)
				(end 260.800088 -12.797536)
			)
			(arc
				(start 324.247764 -12.797536)
				(mid 324.263841 -12.792794)
				(end 324.277482 -12.783058)
			)
			(arc
				(start 324.521576 -12.538964)
				(mid 324.641113 -12.458936)
				(end 324.78218 -12.43076)
			)
			(arc
				(start 331.96784 -12.43076)
				(mid 332.108909 -12.458932)
				(end 332.228444 -12.538964)
			)
			(arc
				(start 332.472538 -12.783058)
				(mid 332.486184 -12.792784)
				(end 332.502256 -12.797536)
			)
			(arc
				(start 385.601972 -12.797536)
				(mid 387.735681 -11.913725)
				(end 388.619492 -9.780016)
			)
			(xy 388.619492 -3.928364)
			(arc
				(start 388.614158 -3.917442)
				(mid 388.329377 -3.590886)
				(end 388.226808 -3.16992)
			)
			(arc
				(start 388.226808 -3.16992)
				(mid 388.275543 -2.875216)
				(end 388.416546 -2.611882)
			)
			(arc
				(start 388.416546 -2.611882)
				(mid 388.501545 -2.513276)
				(end 388.59968 -2.427732)
			)
			(xy 388.619492 -2.388108) (xy 388.619492 -1.016) (xy 455.184256 -1.016) (xy 455.184256 -2.375154)
			(arc
				(start 455.205338 -2.416048)
				(mid 455.573689 -3.012402)
				(end 455.41184 -3.69443)
			)
			(arc
				(start 455.41184 -3.69443)
				(mid 455.315091 -3.810755)
				(end 455.200512 -3.909568)
			)
			(xy 455.184256 -3.941318)
			(arc
				(start 455.184256 -9.780016)
				(mid 456.068231 -11.91374)
				(end 458.20203 -12.797536)
			)
			(arc
				(start 469.799924 -12.797536)
				(mid 470.494637 -13.085295)
				(end 470.782396 -13.780008)
			)
			(xy 470.782396 -17.620234)
			(arc
				(start 470.808558 -17.664176)
				(mid 470.972568 -17.756784)
				(end 471.13317 -17.855184)
			)
			(arc
				(start 471.13317 -17.855184)
				(mid 471.158695 -17.863037)
				(end 471.184732 -17.856962)
			)
			(arc
				(start 471.262964 -17.814036)
				(mid 471.282207 -17.795414)
				(end 471.28938 -17.769586)
			)
			(arc
				(start 471.28938 -13.780008)
				(mid 470.853128 -12.726804)
				(end 469.799924 -12.290552)
			)
			(arc
				(start 458.20203 -12.290552)
				(mid 456.426813 -11.555233)
				(end 455.691494 -9.780016)
			)
			(xy 455.691494 -1.30556) (xy 455.69378 -1.30556)
			(arc
				(start 455.69378 -0.999998)
				(mid 455.549752 -0.652282)
				(end 455.202036 -0.508254)
			)
			(arc
				(start 388.601966 -0.508254)
				(mid 388.25425 -0.652282)
				(end 388.110222 -0.999998)
			)
			(xy 388.110222 -1.30556) (xy 388.112508 -1.30556)
			(arc
				(start 388.112508 -9.780016)
				(mid 387.377189 -11.555233)
				(end 385.601972 -12.290552)
			)
			(arc
				(start 260.800088 -12.290552)
				(mid 259.746884 -12.726804)
				(end 259.310632 -13.780008)
			)
			(xy 259.310632 -32.275018)
			(arc
				(start 259.310632 -32.300164)
				(mid 259.308759 -32.787588)
				(end 259.308092 -33.275016)
			)
			(arc
				(start 259.308092 -33.275016)
				(mid 258.573517 -35.048437)
				(end 256.800096 -35.783012)
			)
			(arc
				(start 225.300032 -35.783012)
				(mid 223.526611 -35.048437)
				(end 222.792036 -33.275016)
			)
			(arc
				(start 222.792036 -33.275016)
				(mid 222.790131 -32.775019)
				(end 222.789496 -32.275018)
			)
			(arc
				(start 222.789496 -13.780008)
				(mid 222.353244 -12.726804)
				(end 221.30004 -12.290552)
			)
			(arc
				(start 196.701918 -12.290552)
				(mid 194.926701 -11.555233)
				(end 194.191382 -9.780016)
			)
			(xy 194.191382 -6.53796) (xy 194.193668 -6.53796)
			(arc
				(start 194.193668 -6.279896)
				(mid 194.04964 -5.93218)
				(end 193.701924 -5.788152)
			)
			(arc
				(start 127.102108 -5.788152)
				(mid 126.754392 -5.93218)
				(end 126.610364 -6.279896)
			)
			(xy 126.610364 -6.53796) (xy 126.61265 -6.53796)
			(arc
				(start 126.61265 -7.744206)
				(mid 126.627618 -7.779963)
				(end 126.66345 -7.794752)
			)
			(arc
				(start 126.687326 -7.78891)
				(mid 126.774244 -7.75555)
				(end 126.86665 -7.744206)
			)
			(arc
				(start 126.86665 -7.744206)
				(mid 126.931475 -7.749794)
				(end 126.994412 -7.766304)
			)
			(arc
				(start 126.994412 -7.766304)
				(mid 127.020815 -7.768359)
				(end 127.044704 -7.756906)
			)
			(arc
				(start 127.044704 -7.756906)
				(mid 127.071589 -7.734537)
				(end 127.099314 -7.713218)
			)
			(xy 127.119888 -7.672832) (xy 127.119888 -6.295898) (xy 193.684144 -6.295898) (xy 193.684144 -7.673086)
			(arc
				(start 193.704718 -7.713472)
				(mid 194.076604 -8.449818)
				(end 193.704718 -9.186164)
			)
			(xy 193.684144 -9.22655)
			(arc
				(start 193.684144 -9.780016)
				(mid 194.568119 -11.91374)
				(end 196.701918 -12.797536)
			)
			(arc
				(start 221.30004 -12.797536)
				(mid 221.994753 -13.085295)
				(end 222.282512 -13.780008)
			)
			(xy 222.282512 -23.213568)
			(arc
				(start 222.284036 -33.275016)
				(mid 223.167401 -35.407647)
				(end 225.300032 -36.291012)
			)
		)
		(stroke
			(width 0)
			(type solid)
		)
		(fill yes)
		(layer "In13.Cu")
		(net "GND")
	)
	(gr_poly
		(pts
			(xy 191.289686 -131.624578) (xy 191.289686 -131.170172) (xy 191.102996 -130.983736) (xy 187.23991 -130.983736)
			(xy 187.225439 -130.984243) (xy 187.197659 -130.992363) (xy 187.173274 -131.007953) (xy 187.154245 -131.029759)
			(xy 187.1421 -131.05603) (xy 187.137816 -131.084654) (xy 187.141737 -131.113329) (xy 187.1472 -131.126738)
			(xy 187.157791 -131.151403) (xy 187.17272 -131.202963) (xy 187.180263 -131.256109) (xy 187.180728 -131.282948)
			(xy 187.180242 -131.310199) (xy 187.172486 -131.364147) (xy 187.157131 -131.416442) (xy 187.134489 -131.466019)
			(xy 187.105023 -131.511869) (xy 187.069332 -131.55306) (xy 187.028141 -131.588751) (xy 186.982291 -131.618217)
			(xy 186.932714 -131.640859) (xy 186.880419 -131.656214) (xy 186.826471 -131.66397) (xy 186.771969 -131.66397)
			(xy 186.718021 -131.656214) (xy 186.665726 -131.640859) (xy 186.616149 -131.618217) (xy 186.570299 -131.588751)
			(xy 186.529108 -131.55306) (xy 186.493417 -131.511869) (xy 186.463951 -131.466019) (xy 186.441309 -131.416442)
			(xy 186.425954 -131.364147) (xy 186.418198 -131.310199) (xy 186.417712 -131.282948) (xy 186.418191 -131.256111)
			(xy 186.42575 -131.202971) (xy 186.44067 -131.151411) (xy 186.45124 -131.126738) (xy 186.456675 -131.113316)
			(xy 186.460588 -131.084638) (xy 186.456304 -131.056013) (xy 186.444165 -131.029738) (xy 186.425147 -131.007919)
			(xy 186.400774 -130.992309) (xy 186.373001 -130.984158) (xy 186.35853 -130.983736) (xy 181.09184 -130.983736)
			(xy 181.077406 -130.984234) (xy 181.04969 -130.992304) (xy 181.02534 -131.00781) (xy 181.006305 -131.029513)
			(xy 180.994107 -131.055676) (xy 180.98972 -131.084209) (xy 180.993496 -131.112828) (xy 180.998876 -131.12623)
			(xy 181.009154 -131.15062) (xy 181.023641 -131.201526) (xy 181.030954 -131.253945) (xy 181.031388 -131.280408)
			(xy 181.030902 -131.307659) (xy 181.023146 -131.361607) (xy 181.007791 -131.413902) (xy 180.985149 -131.463479)
			(xy 180.955683 -131.509329) (xy 180.919992 -131.55052) (xy 180.878801 -131.586211) (xy 180.832951 -131.615677)
			(xy 180.783374 -131.638319) (xy 180.731079 -131.653674) (xy 180.677131 -131.66143) (xy 180.622629 -131.66143)
			(xy 180.568681 -131.653674) (xy 180.516386 -131.638319) (xy 180.466809 -131.615677) (xy 180.420959 -131.586211)
			(xy 180.379768 -131.55052) (xy 180.344077 -131.509329) (xy 180.314611 -131.463479) (xy 180.291969 -131.413902)
			(xy 180.276614 -131.361607) (xy 180.268858 -131.307659) (xy 180.268372 -131.280408) (xy 180.268822 -131.253945)
			(xy 180.276128 -131.201526) (xy 180.290603 -131.150618) (xy 180.300884 -131.12623) (xy 180.306238 -131.112819)
			(xy 180.31001 -131.084202) (xy 180.305624 -131.055673) (xy 180.29343 -131.029511) (xy 180.274402 -131.007807)
			(xy 180.250061 -130.992294) (xy 180.222352 -130.984212) (xy 180.20792 -130.983736) (xy 179.56784 -130.983736)
			(xy 179.553406 -130.984234) (xy 179.52569 -130.992304) (xy 179.50134 -131.00781) (xy 179.482305 -131.029513)
			(xy 179.470107 -131.055676) (xy 179.46572 -131.084209) (xy 179.469496 -131.112828) (xy 179.474876 -131.12623)
			(xy 179.485154 -131.15062) (xy 179.499641 -131.201526) (xy 179.506954 -131.253945) (xy 179.507388 -131.280408)
			(xy 179.506902 -131.307659) (xy 179.499146 -131.361607) (xy 179.483791 -131.413902) (xy 179.461149 -131.463479)
			(xy 179.431683 -131.509329) (xy 179.395992 -131.55052) (xy 179.354801 -131.586211) (xy 179.308951 -131.615677)
			(xy 179.259374 -131.638319) (xy 179.207079 -131.653674) (xy 179.153131 -131.66143) (xy 179.098629 -131.66143)
			(xy 179.044681 -131.653674) (xy 178.992386 -131.638319) (xy 178.942809 -131.615677) (xy 178.896959 -131.586211)
			(xy 178.855768 -131.55052) (xy 178.820077 -131.509329) (xy 178.790611 -131.463479) (xy 178.767969 -131.413902)
			(xy 178.752614 -131.361607) (xy 178.744858 -131.307659) (xy 178.744372 -131.280408) (xy 178.744822 -131.253945)
			(xy 178.752128 -131.201526) (xy 178.766603 -131.150618) (xy 178.776884 -131.12623) (xy 178.782238 -131.112819)
			(xy 178.78601 -131.084202) (xy 178.781624 -131.055673) (xy 178.76943 -131.029511) (xy 178.750402 -131.007807)
			(xy 178.726061 -130.992294) (xy 178.698352 -130.984212) (xy 178.68392 -130.983736) (xy 177.02784 -130.983736)
			(xy 177.013406 -130.984234) (xy 176.98569 -130.992304) (xy 176.96134 -131.00781) (xy 176.942305 -131.029513)
			(xy 176.930107 -131.055676) (xy 176.92572 -131.084209) (xy 176.929496 -131.112828) (xy 176.934876 -131.12623)
			(xy 176.945154 -131.15062) (xy 176.959641 -131.201526) (xy 176.966954 -131.253945) (xy 176.967388 -131.280408)
			(xy 176.966937 -131.306856) (xy 176.95963 -131.359246) (xy 176.945156 -131.410124) (xy 176.923794 -131.458516)
			(xy 176.895953 -131.503493) (xy 176.862167 -131.544193) (xy 176.842928 -131.562348) (xy 176.832849 -131.572182)
			(xy 176.818057 -131.596132) (xy 176.810367 -131.623211) (xy 176.810363 -131.65136) (xy 176.818045 -131.678441)
			(xy 176.83283 -131.702395) (xy 176.842928 -131.712208) (xy 176.862172 -131.730359) (xy 176.89597 -131.771055)
			(xy 176.923819 -131.816031) (xy 176.945186 -131.864423) (xy 176.95966 -131.915305) (xy 176.966964 -131.967698)
			(xy 176.967388 -131.994148) (xy 176.966902 -132.021399) (xy 176.959146 -132.075347) (xy 176.943791 -132.127642)
			(xy 176.921149 -132.177219) (xy 176.891683 -132.223069) (xy 176.855992 -132.26426) (xy 176.814801 -132.299951)
			(xy 176.768951 -132.329417) (xy 176.719374 -132.352059) (xy 176.667079 -132.367414) (xy 176.613131 -132.37517)
			(xy 176.558629 -132.37517) (xy 176.504681 -132.367414) (xy 176.452386 -132.352059) (xy 176.402809 -132.329417)
			(xy 176.356959 -132.299951) (xy 176.315768 -132.26426) (xy 176.280077 -132.223069) (xy 176.250611 -132.177219)
			(xy 176.227969 -132.127642) (xy 176.212614 -132.075347) (xy 176.204858 -132.021399) (xy 176.204372 -131.994148)
			(xy 176.204826 -131.967701) (xy 176.212138 -131.915313) (xy 176.226615 -131.864438) (xy 176.247979 -131.81605)
			(xy 176.275821 -131.771075) (xy 176.309607 -131.730377) (xy 176.328832 -131.712208) (xy 176.338908 -131.702376)
			(xy 176.353694 -131.67843) (xy 176.361377 -131.651357) (xy 176.361373 -131.623214) (xy 176.353682 -131.596143)
			(xy 176.338889 -131.572201) (xy 176.328832 -131.562348) (xy 176.309592 -131.544195) (xy 176.275802 -131.503497)
			(xy 176.247961 -131.45852) (xy 176.226602 -131.410127) (xy 176.212136 -131.359247) (xy 176.204839 -131.306856)
			(xy 176.204372 -131.280408) (xy 176.204822 -131.253945) (xy 176.212128 -131.201526) (xy 176.226603 -131.150618)
			(xy 176.236884 -131.12623) (xy 176.242238 -131.112819) (xy 176.24601 -131.084202) (xy 176.241624 -131.055673)
			(xy 176.22943 -131.029511) (xy 176.210402 -131.007807) (xy 176.186061 -130.992294) (xy 176.158352 -130.984212)
			(xy 176.14392 -130.983736) (xy 175.75784 -130.983736) (xy 175.743406 -130.984234) (xy 175.71569 -130.992304)
			(xy 175.69134 -131.00781) (xy 175.672305 -131.029513) (xy 175.660107 -131.055676) (xy 175.65572 -131.084209)
			(xy 175.659496 -131.112828) (xy 175.664876 -131.12623) (xy 175.675154 -131.15062) (xy 175.689641 -131.201526)
			(xy 175.696954 -131.253945) (xy 175.697388 -131.280408) (xy 175.696937 -131.306856) (xy 175.68963 -131.359246)
			(xy 175.675156 -131.410124) (xy 175.653794 -131.458516) (xy 175.625953 -131.503493) (xy 175.592167 -131.544193)
			(xy 175.572928 -131.562348) (xy 175.562849 -131.572182) (xy 175.548057 -131.596132) (xy 175.540367 -131.623211)
			(xy 175.540363 -131.65136) (xy 175.548045 -131.678441) (xy 175.56283 -131.702395) (xy 175.572928 -131.712208)
			(xy 175.592172 -131.730359) (xy 175.62597 -131.771055) (xy 175.653819 -131.816031) (xy 175.675186 -131.864423)
			(xy 175.68966 -131.915305) (xy 175.696964 -131.967698) (xy 175.697388 -131.994148) (xy 175.696902 -132.021399)
			(xy 175.689146 -132.075347) (xy 175.673791 -132.127642) (xy 175.651149 -132.177219) (xy 175.621683 -132.223069)
			(xy 175.585992 -132.26426) (xy 175.544801 -132.299951) (xy 175.498951 -132.329417) (xy 175.449374 -132.352059)
			(xy 175.397079 -132.367414) (xy 175.343131 -132.37517) (xy 175.288629 -132.37517) (xy 175.234681 -132.367414)
			(xy 175.182386 -132.352059) (xy 175.132809 -132.329417) (xy 175.086959 -132.299951) (xy 175.045768 -132.26426)
			(xy 175.010077 -132.223069) (xy 174.980611 -132.177219) (xy 174.957969 -132.127642) (xy 174.942614 -132.075347)
			(xy 174.934858 -132.021399) (xy 174.934372 -131.994148) (xy 174.934826 -131.967701) (xy 174.942138 -131.915313)
			(xy 174.956615 -131.864438) (xy 174.977979 -131.81605) (xy 175.005821 -131.771075) (xy 175.039607 -131.730377)
			(xy 175.058832 -131.712208) (xy 175.068908 -131.702376) (xy 175.083694 -131.67843) (xy 175.091377 -131.651357)
			(xy 175.091373 -131.623214) (xy 175.083682 -131.596143) (xy 175.068889 -131.572201) (xy 175.058832 -131.562348)
			(xy 175.039592 -131.544195) (xy 175.005802 -131.503497) (xy 174.977961 -131.45852) (xy 174.956602 -131.410127)
			(xy 174.942136 -131.359247) (xy 174.934839 -131.306856) (xy 174.934372 -131.280408) (xy 174.934822 -131.253945)
			(xy 174.942128 -131.201526) (xy 174.956603 -131.150618) (xy 174.966884 -131.12623) (xy 174.972238 -131.112819)
			(xy 174.97601 -131.084202) (xy 174.971624 -131.055673) (xy 174.95943 -131.029511) (xy 174.940402 -131.007807)
			(xy 174.916061 -130.992294) (xy 174.888352 -130.984212) (xy 174.87392 -130.983736) (xy 173.752002 -130.983736)
			(xy 173.622208 -131.113276) (xy 173.622208 -132.22097) (xy 173.626272 -132.22478) (xy 173.626272 -132.750814)
			(xy 173.757336 -132.881878) (xy 177.928524 -132.881878) (xy 177.942231 -132.881441) (xy 177.968662 -132.874163)
			(xy 177.992202 -132.860113) (xy 178.011153 -132.840303) (xy 178.024146 -132.816164) (xy 178.030246 -132.789437)
			(xy 178.029011 -132.76205) (xy 178.02053 -132.735981) (xy 178.005416 -132.713109) (xy 177.995326 -132.703824)
			(xy 177.975198 -132.685607) (xy 177.939786 -132.644461) (xy 177.910559 -132.598713) (xy 177.888107 -132.549287)
			(xy 177.872883 -132.497179) (xy 177.865194 -132.443439) (xy 177.86477 -132.416296) (xy 177.865256 -132.389045)
			(xy 177.873012 -132.335097) (xy 177.888367 -132.282802) (xy 177.911009 -132.233225) (xy 177.940475 -132.187375)
			(xy 177.976166 -132.146184) (xy 178.017357 -132.110493) (xy 178.063207 -132.081027) (xy 178.112784 -132.058385)
			(xy 178.165079 -132.04303) (xy 178.219027 -132.035274) (xy 178.273529 -132.035274) (xy 178.327477 -132.04303)
			(xy 178.379772 -132.058385) (xy 178.429349 -132.081027) (xy 178.475199 -132.110493) (xy 178.51639 -132.146184)
			(xy 178.552081 -132.187375) (xy 178.581547 -132.233225) (xy 178.604189 -132.282802) (xy 178.619544 -132.335097)
			(xy 178.6273 -132.389045) (xy 178.627786 -132.416296) (xy 178.627626 -132.430962) (xy 178.625334 -132.460204)
			(xy 178.623214 -132.474716) (xy 178.622706 -132.47878) (xy 178.622706 -132.53339) (xy 178.748182 -132.53339)
			(xy 178.748182 -132.479288) (xy 178.747674 -132.475986) (xy 178.74613 -132.463534) (xy 178.744477 -132.438495)
			(xy 178.744372 -132.425948) (xy 178.744858 -132.398697) (xy 178.752614 -132.344749) (xy 178.767969 -132.292454)
			(xy 178.790611 -132.242877) (xy 178.820077 -132.197027) (xy 178.855768 -132.155836) (xy 178.896959 -132.120145)
			(xy 178.942809 -132.090679) (xy 178.992386 -132.068037) (xy 179.044681 -132.052682) (xy 179.098629 -132.044926)
			(xy 179.153131 -132.044926) (xy 179.207079 -132.052682) (xy 179.259374 -132.068037) (xy 179.308951 -132.090679)
			(xy 179.354801 -132.120145) (xy 179.395992 -132.155836) (xy 179.431683 -132.197027) (xy 179.461149 -132.242877)
			(xy 179.483791 -132.292454) (xy 179.499146 -132.344749) (xy 179.506902 -132.398697) (xy 179.507388 -132.425948)
			(xy 179.507388 -132.43052) (xy 179.507629 -132.443956) (xy 179.514308 -132.469975) (xy 179.527543 -132.493352)
			(xy 179.546417 -132.512468) (xy 179.569624 -132.525999) (xy 179.595556 -132.533009) (xy 179.608988 -132.53339)
			(xy 180.039772 -132.53339) (xy 180.053203 -132.532984) (xy 180.079137 -132.525983) (xy 180.102346 -132.512458)
			(xy 180.121223 -132.493347) (xy 180.13446 -132.469973) (xy 180.141141 -132.443955) (xy 180.141372 -132.43052)
			(xy 180.141372 -132.425948) (xy 180.141858 -132.398697) (xy 180.149614 -132.344749) (xy 180.164969 -132.292454)
			(xy 180.187611 -132.242877) (xy 180.217077 -132.197027) (xy 180.252768 -132.155836) (xy 180.293959 -132.120145)
			(xy 180.339809 -132.090679) (xy 180.389386 -132.068037) (xy 180.441681 -132.052682) (xy 180.495629 -132.044926)
			(xy 180.550131 -132.044926) (xy 180.604079 -132.052682) (xy 180.656374 -132.068037) (xy 180.705951 -132.090679)
			(xy 180.751801 -132.120145) (xy 180.792992 -132.155836) (xy 180.828683 -132.197027) (xy 180.858149 -132.242877)
			(xy 180.880791 -132.292454) (xy 180.896146 -132.344749) (xy 180.903902 -132.398697) (xy 180.904388 -132.425948)
			(xy 180.904388 -132.43052) (xy 180.904629 -132.443956) (xy 180.911308 -132.469975) (xy 180.924543 -132.493352)
			(xy 180.943417 -132.512468) (xy 180.966624 -132.525999) (xy 180.992556 -132.533009) (xy 181.005988 -132.53339)
			(xy 181.690772 -132.53339) (xy 181.704203 -132.532984) (xy 181.730137 -132.525983) (xy 181.753346 -132.512458)
			(xy 181.772223 -132.493347) (xy 181.78546 -132.469973) (xy 181.792141 -132.443955) (xy 181.792372 -132.43052)
			(xy 181.792372 -132.425948) (xy 181.792858 -132.398697) (xy 181.800614 -132.344749) (xy 181.815969 -132.292454)
			(xy 181.838611 -132.242877) (xy 181.868077 -132.197027) (xy 181.903768 -132.155836) (xy 181.944959 -132.120145)
			(xy 181.990809 -132.090679) (xy 182.040386 -132.068037) (xy 182.092681 -132.052682) (xy 182.146629 -132.044926)
			(xy 182.201131 -132.044926) (xy 182.255079 -132.052682) (xy 182.307374 -132.068037) (xy 182.356951 -132.090679)
			(xy 182.402801 -132.120145) (xy 182.443992 -132.155836) (xy 182.479683 -132.197027) (xy 182.509149 -132.242877)
			(xy 182.531791 -132.292454) (xy 182.547146 -132.344749) (xy 182.554902 -132.398697) (xy 182.555388 -132.425948)
			(xy 182.555388 -132.43052) (xy 182.555629 -132.443956) (xy 182.562308 -132.469975) (xy 182.575543 -132.493352)
			(xy 182.594417 -132.512468) (xy 182.617624 -132.525999) (xy 182.643556 -132.533009) (xy 182.656988 -132.53339)
			(xy 183.087772 -132.53339) (xy 183.101203 -132.532984) (xy 183.127137 -132.525983) (xy 183.150346 -132.512458)
			(xy 183.169223 -132.493347) (xy 183.18246 -132.469973) (xy 183.189141 -132.443955) (xy 183.189372 -132.43052)
			(xy 183.189372 -132.425948) (xy 183.189858 -132.398697) (xy 183.197614 -132.344749) (xy 183.212969 -132.292454)
			(xy 183.235611 -132.242877) (xy 183.265077 -132.197027) (xy 183.300768 -132.155836) (xy 183.341959 -132.120145)
			(xy 183.387809 -132.090679) (xy 183.437386 -132.068037) (xy 183.489681 -132.052682) (xy 183.543629 -132.044926)
			(xy 183.598131 -132.044926) (xy 183.652079 -132.052682) (xy 183.704374 -132.068037) (xy 183.753951 -132.090679)
			(xy 183.799801 -132.120145) (xy 183.840992 -132.155836) (xy 183.876683 -132.197027) (xy 183.906149 -132.242877)
			(xy 183.928791 -132.292454) (xy 183.944146 -132.344749) (xy 183.951902 -132.398697) (xy 183.952388 -132.425948)
			(xy 184.585862 -132.425948) (xy 184.589933 -132.370326) (xy 184.602059 -132.315889) (xy 184.621982 -132.263798)
			(xy 184.649278 -132.215163) (xy 184.683364 -132.17102) (xy 184.723513 -132.132311) (xy 184.768871 -132.09986)
			(xy 184.818471 -132.074359) (xy 184.871255 -132.056352) (xy 184.926098 -132.046222) (xy 184.981832 -132.044185)
			(xy 185.037269 -132.050285) (xy 185.091226 -132.064391) (xy 185.142555 -132.086203) (xy 185.190161 -132.115257)
			(xy 185.233029 -132.150932) (xy 185.270246 -132.192469) (xy 185.301019 -132.238982) (xy 185.324691 -132.289479)
			(xy 185.340759 -132.342886) (xy 185.348879 -132.398062) (xy 185.349388 -132.425948) (xy 186.351924 -132.425948)
			(xy 186.355995 -132.370326) (xy 186.368121 -132.315889) (xy 186.388044 -132.263798) (xy 186.41534 -132.215163)
			(xy 186.449426 -132.17102) (xy 186.489575 -132.132311) (xy 186.534933 -132.09986) (xy 186.584533 -132.074359)
			(xy 186.637317 -132.056352) (xy 186.69216 -132.046222) (xy 186.747894 -132.044185) (xy 186.803331 -132.050285)
			(xy 186.857288 -132.064391) (xy 186.908617 -132.086203) (xy 186.956223 -132.115257) (xy 186.999091 -132.150932)
			(xy 187.036308 -132.192469) (xy 187.067081 -132.238982) (xy 187.090753 -132.289479) (xy 187.106821 -132.342886)
			(xy 187.114941 -132.398062) (xy 187.11545 -132.425948) (xy 187.114941 -132.453834) (xy 187.106821 -132.50901)
			(xy 187.090753 -132.562417) (xy 187.080903 -132.583428) (xy 187.791342 -132.583428) (xy 187.795413 -132.527806)
			(xy 187.807539 -132.473369) (xy 187.827462 -132.421278) (xy 187.854758 -132.372643) (xy 187.888844 -132.3285)
			(xy 187.928993 -132.289791) (xy 187.974351 -132.25734) (xy 188.023951 -132.231839) (xy 188.076735 -132.213832)
			(xy 188.131578 -132.203702) (xy 188.187312 -132.201665) (xy 188.242749 -132.207765) (xy 188.296706 -132.221871)
			(xy 188.348035 -132.243683) (xy 188.395641 -132.272737) (xy 188.438509 -132.308412) (xy 188.475726 -132.349949)
			(xy 188.506499 -132.396462) (xy 188.530171 -132.446959) (xy 188.546239 -132.500366) (xy 188.554359 -132.555542)
			(xy 188.554868 -132.583428) (xy 188.554359 -132.611314) (xy 188.546239 -132.66649) (xy 188.54219 -132.679948)
			(xy 188.903862 -132.679948) (xy 188.907933 -132.624326) (xy 188.920059 -132.569889) (xy 188.939982 -132.517798)
			(xy 188.967278 -132.469163) (xy 189.001364 -132.42502) (xy 189.041513 -132.386311) (xy 189.086871 -132.35386)
			(xy 189.136471 -132.328359) (xy 189.189255 -132.310352) (xy 189.244098 -132.300222) (xy 189.299832 -132.298185)
			(xy 189.355269 -132.304285) (xy 189.409226 -132.318391) (xy 189.460555 -132.340203) (xy 189.508161 -132.369257)
			(xy 189.551029 -132.404932) (xy 189.588246 -132.446469) (xy 189.619019 -132.492982) (xy 189.642691 -132.543479)
			(xy 189.658759 -132.596886) (xy 189.666879 -132.652062) (xy 189.667388 -132.679948) (xy 189.666879 -132.707834)
			(xy 189.658759 -132.76301) (xy 189.642691 -132.816417) (xy 189.619019 -132.866914) (xy 189.588246 -132.913427)
			(xy 189.551029 -132.954964) (xy 189.508161 -132.990639) (xy 189.460555 -133.019693) (xy 189.409226 -133.041505)
			(xy 189.355269 -133.055611) (xy 189.299832 -133.061711) (xy 189.244098 -133.059674) (xy 189.189255 -133.049544)
			(xy 189.136471 -133.031537) (xy 189.086871 -133.006036) (xy 189.041513 -132.973585) (xy 189.001364 -132.934876)
			(xy 188.967278 -132.890733) (xy 188.939982 -132.842098) (xy 188.920059 -132.790007) (xy 188.907933 -132.73557)
			(xy 188.903862 -132.679948) (xy 188.54219 -132.679948) (xy 188.530171 -132.719897) (xy 188.506499 -132.770394)
			(xy 188.475726 -132.816907) (xy 188.438509 -132.858444) (xy 188.395641 -132.894119) (xy 188.348035 -132.923173)
			(xy 188.296706 -132.944985) (xy 188.242749 -132.959091) (xy 188.187312 -132.965191) (xy 188.131578 -132.963154)
			(xy 188.076735 -132.953024) (xy 188.023951 -132.935017) (xy 187.974351 -132.909516) (xy 187.928993 -132.877065)
			(xy 187.888844 -132.838356) (xy 187.854758 -132.794213) (xy 187.827462 -132.745578) (xy 187.807539 -132.693487)
			(xy 187.795413 -132.63905) (xy 187.791342 -132.583428) (xy 187.080903 -132.583428) (xy 187.067081 -132.612914)
			(xy 187.036308 -132.659427) (xy 186.999091 -132.700964) (xy 186.956223 -132.736639) (xy 186.908617 -132.765693)
			(xy 186.857288 -132.787505) (xy 186.803331 -132.801611) (xy 186.747894 -132.807711) (xy 186.69216 -132.805674)
			(xy 186.637317 -132.795544) (xy 186.584533 -132.777537) (xy 186.534933 -132.752036) (xy 186.489575 -132.719585)
			(xy 186.449426 -132.680876) (xy 186.41534 -132.636733) (xy 186.388044 -132.588098) (xy 186.368121 -132.536007)
			(xy 186.355995 -132.48157) (xy 186.351924 -132.425948) (xy 185.349388 -132.425948) (xy 185.348879 -132.453834)
			(xy 185.340759 -132.50901) (xy 185.324691 -132.562417) (xy 185.301019 -132.612914) (xy 185.270246 -132.659427)
			(xy 185.233029 -132.700964) (xy 185.190161 -132.736639) (xy 185.142555 -132.765693) (xy 185.091226 -132.787505)
			(xy 185.037269 -132.801611) (xy 184.981832 -132.807711) (xy 184.926098 -132.805674) (xy 184.871255 -132.795544)
			(xy 184.818471 -132.777537) (xy 184.768871 -132.752036) (xy 184.723513 -132.719585) (xy 184.683364 -132.680876)
			(xy 184.649278 -132.636733) (xy 184.621982 -132.588098) (xy 184.602059 -132.536007) (xy 184.589933 -132.48157)
			(xy 184.585862 -132.425948) (xy 183.952388 -132.425948) (xy 183.951896 -132.453298) (xy 183.944048 -132.507432)
			(xy 183.928562 -132.559895) (xy 183.91759 -132.584952) (xy 183.902858 -132.616956) (xy 184.643014 -133.357112)
			(xy 189.557152 -133.357112)
		)
		(stroke
			(width 0)
			(type solid)
		)
		(fill yes)
		(layer "In13.Cu")
		(net "P3V3_AUX")
	)
	(gr_poly
		(pts
			(xy 108.7755 -394.50772) (xy 115.6843 -394.50772) (xy 116.44884 -393.74318) (xy 116.91874 -393.74318)
			(xy 117.351302 -393.310618) (xy 117.329966 -393.276582) (xy 117.316473 -393.253866) (xy 117.295189 -393.205507)
			(xy 117.280778 -393.154674) (xy 117.273516 -393.10234) (xy 117.27307 -393.075922) (xy 117.273554 -393.048669)
			(xy 117.281308 -392.994718) (xy 117.296661 -392.942419) (xy 117.319301 -392.892838) (xy 117.348766 -392.846983)
			(xy 117.384457 -392.805788) (xy 117.425648 -392.770092) (xy 117.471499 -392.740622) (xy 117.521078 -392.717977)
			(xy 117.573375 -392.702617) (xy 117.627325 -392.694857) (xy 117.654578 -392.694414) (xy 117.680998 -392.694841)
			(xy 117.733337 -392.702093) (xy 117.784174 -392.716503) (xy 117.832534 -392.737794) (xy 117.855238 -392.75131)
			(xy 117.889274 -392.772646) (xy 141.34846 -369.31346) (xy 141.34846 -367.90122) (xy 141.23162 -367.78438)
			(xy 140.58392 -367.78438) (xy 137.14476 -371.22354) (xy 105.1306 -371.22354) (xy 103.51262 -369.60556)
			(xy 103.51262 -363.41812) (xy 102.616 -362.5215) (xy 102.616 -359.537) (xy 102.30866 -359.22966)
			(xy 99.98456 -359.22966) (xy 99.23526 -359.97896) (xy 99.23526 -360.81716) (xy 99.92614 -361.50804)
			(xy 99.92614 -364.093252) (xy 99.926604 -364.107747) (xy 99.934664 -364.135592) (xy 99.950233 -364.160044)
			(xy 99.972053 -364.179127) (xy 99.998361 -364.191301) (xy 100.027031 -364.195581) (xy 100.041456 -364.19409)
			(xy 100.054282 -364.192429) (xy 100.080086 -364.190651) (xy 100.093018 -364.190534) (xy 100.120269 -364.190999)
			(xy 100.174216 -364.198758) (xy 100.226509 -364.214116) (xy 100.276084 -364.23676) (xy 100.321932 -364.266229)
			(xy 100.363119 -364.301923) (xy 100.398807 -364.343116) (xy 100.428269 -364.388969) (xy 100.450905 -364.438547)
			(xy 100.466255 -364.490843) (xy 100.474006 -364.544791) (xy 100.474526 -364.572042) (xy 100.474054 -364.598556)
			(xy 100.466677 -364.651069) (xy 100.452099 -364.702054) (xy 100.44176 -364.726474) (xy 100.436292 -364.739993)
			(xy 100.432502 -364.768897) (xy 100.437025 -364.797695) (xy 100.449493 -364.824045) (xy 100.468894 -364.845803)
			(xy 100.493647 -364.8612) (xy 100.521741 -364.868982) (xy 100.550888 -364.868517) (xy 100.56495 -364.86465)
			(xy 100.601898 -364.853572) (xy 100.677468 -364.83808) (xy 100.754217 -364.830314) (xy 100.792788 -364.829852)
			(xy 100.831856 -364.830346) (xy 100.909583 -364.838336) (xy 100.986086 -364.854232) (xy 101.060562 -364.877869)
			(xy 101.13223 -364.908998) (xy 101.200339 -364.947293) (xy 101.264175 -364.992352) (xy 101.323068 -365.043704)
			(xy 101.3764 -365.100808) (xy 101.423613 -365.163068) (xy 101.464212 -365.22983) (xy 101.49777 -365.300393)
			(xy 101.523937 -365.374018) (xy 101.542436 -365.449933) (xy 101.553076 -365.527342) (xy 101.555743 -365.605433)
			(xy 101.55041 -365.683388) (xy 101.537133 -365.760388) (xy 101.516051 -365.835627) (xy 101.487385 -365.908315)
			(xy 101.451436 -365.977691) (xy 101.408581 -366.043027) (xy 101.359269 -366.103638) (xy 101.304017 -366.158888)
			(xy 101.243405 -366.208198) (xy 101.178067 -366.251051) (xy 101.10869 -366.286997) (xy 101.036 -366.31566)
			(xy 100.960761 -366.336739) (xy 100.88376 -366.350013) (xy 100.805805 -366.355343) (xy 100.727714 -366.352673)
			(xy 100.650306 -366.342031) (xy 100.574391 -366.323529) (xy 100.500767 -366.29736) (xy 100.430205 -366.263799)
			(xy 100.363445 -366.223198) (xy 100.301187 -366.175982) (xy 100.244084 -366.122647) (xy 100.192735 -366.063753)
			(xy 100.147678 -365.999915) (xy 100.109385 -365.931805) (xy 100.078259 -365.860136) (xy 100.054625 -365.785659)
			(xy 100.038731 -365.709156) (xy 100.030745 -365.631428) (xy 100.03028 -365.59236) (xy 100.030714 -365.555774)
			(xy 100.037728 -365.482938) (xy 100.051686 -365.411109) (xy 100.072461 -365.340947) (xy 100.099862 -365.273098)
			(xy 100.133637 -365.208186) (xy 100.173474 -365.146808) (xy 100.195888 -365.117888) (xy 100.204595 -365.106183)
			(xy 100.215565 -365.079162) (xy 100.218461 -365.050145) (xy 100.213049 -365.021489) (xy 100.199769 -364.995527)
			(xy 100.179701 -364.974368) (xy 100.154476 -364.959735) (xy 100.126146 -364.952817) (xy 100.11156 -364.953042)
			(xy 100.093018 -364.95355) (xy 100.065607 -364.953077) (xy 100.01135 -364.945234) (xy 99.958774 -364.929706)
			(xy 99.908961 -364.906813) (xy 99.862938 -364.877027) (xy 99.821651 -364.840961) (xy 99.803458 -364.820454)
			(xy 99.794014 -364.810166) (xy 99.770746 -364.794742) (xy 99.744174 -364.786184) (xy 99.716278 -364.785129)
			(xy 99.689135 -364.791658) (xy 99.66477 -364.805283) (xy 99.654614 -364.814866) (xy 98.87966 -365.58982)
			(xy 98.87966 -390.558528) (xy 100.442266 -390.558528) (xy 100.446337 -390.502906) (xy 100.458463 -390.448469)
			(xy 100.478386 -390.396378) (xy 100.505682 -390.347743) (xy 100.539768 -390.3036) (xy 100.579917 -390.264891)
			(xy 100.625275 -390.23244) (xy 100.674875 -390.206939) (xy 100.727659 -390.188932) (xy 100.782502 -390.178802)
			(xy 100.838236 -390.176765) (xy 100.893673 -390.182865) (xy 100.94763 -390.196971) (xy 100.998959 -390.218783)
			(xy 101.046565 -390.247837) (xy 101.089433 -390.283512) (xy 101.12665 -390.325049) (xy 101.157423 -390.371562)
			(xy 101.181095 -390.422059) (xy 101.197163 -390.475466) (xy 101.205283 -390.530642) (xy 101.205792 -390.558528)
			(xy 101.205283 -390.586414) (xy 101.197163 -390.64159) (xy 101.181095 -390.694997) (xy 101.157423 -390.745494)
			(xy 101.12665 -390.792007) (xy 101.089433 -390.833544) (xy 101.046565 -390.869219) (xy 100.998959 -390.898273)
			(xy 100.94763 -390.920085) (xy 100.893673 -390.934191) (xy 100.838236 -390.940291) (xy 100.782502 -390.938254)
			(xy 100.727659 -390.928124) (xy 100.674875 -390.910117) (xy 100.625275 -390.884616) (xy 100.579917 -390.852165)
			(xy 100.539768 -390.813456) (xy 100.505682 -390.769313) (xy 100.478386 -390.720678) (xy 100.458463 -390.668587)
			(xy 100.446337 -390.61415) (xy 100.442266 -390.558528) (xy 98.87966 -390.558528) (xy 98.87966 -390.997948)
			(xy 102.467662 -390.997948) (xy 102.471733 -390.942326) (xy 102.483859 -390.887889) (xy 102.503782 -390.835798)
			(xy 102.531078 -390.787163) (xy 102.565164 -390.74302) (xy 102.605313 -390.704311) (xy 102.650671 -390.67186)
			(xy 102.700271 -390.646359) (xy 102.753055 -390.628352) (xy 102.807898 -390.618222) (xy 102.863632 -390.616185)
			(xy 102.919069 -390.622285) (xy 102.973026 -390.636391) (xy 103.024355 -390.658203) (xy 103.071961 -390.687257)
			(xy 103.114829 -390.722932) (xy 103.152046 -390.764469) (xy 103.182819 -390.810982) (xy 103.206491 -390.861479)
			(xy 103.222559 -390.914886) (xy 103.230679 -390.970062) (xy 103.231188 -390.997948) (xy 103.230679 -391.025834)
			(xy 103.222559 -391.08101) (xy 103.206491 -391.134417) (xy 103.182819 -391.184914) (xy 103.152046 -391.231427)
			(xy 103.114829 -391.272964) (xy 103.071961 -391.308639) (xy 103.024355 -391.337693) (xy 102.973026 -391.359505)
			(xy 102.919069 -391.373611) (xy 102.863632 -391.379711) (xy 102.807898 -391.377674) (xy 102.753055 -391.367544)
			(xy 102.700271 -391.349537) (xy 102.650671 -391.324036) (xy 102.605313 -391.291585) (xy 102.565164 -391.252876)
			(xy 102.531078 -391.208733) (xy 102.503782 -391.160098) (xy 102.483859 -391.108007) (xy 102.471733 -391.05357)
			(xy 102.467662 -390.997948) (xy 98.87966 -390.997948) (xy 98.87966 -391.505948) (xy 109.249462 -391.505948)
			(xy 109.253533 -391.450326) (xy 109.265659 -391.395889) (xy 109.285582 -391.343798) (xy 109.312878 -391.295163)
			(xy 109.346964 -391.25102) (xy 109.387113 -391.212311) (xy 109.432471 -391.17986) (xy 109.482071 -391.154359)
			(xy 109.534855 -391.136352) (xy 109.589698 -391.126222) (xy 109.645432 -391.124185) (xy 109.700869 -391.130285)
			(xy 109.754826 -391.144391) (xy 109.806155 -391.166203) (xy 109.853761 -391.195257) (xy 109.896629 -391.230932)
			(xy 109.933846 -391.272469) (xy 109.964619 -391.318982) (xy 109.988291 -391.369479) (xy 110.004359 -391.422886)
			(xy 110.012479 -391.478062) (xy 110.012988 -391.505948) (xy 110.012479 -391.533834) (xy 110.009107 -391.556748)
			(xy 110.595662 -391.556748) (xy 110.599733 -391.501126) (xy 110.611859 -391.446689) (xy 110.631782 -391.394598)
			(xy 110.659078 -391.345963) (xy 110.693164 -391.30182) (xy 110.733313 -391.263111) (xy 110.778671 -391.23066)
			(xy 110.828271 -391.205159) (xy 110.881055 -391.187152) (xy 110.935898 -391.177022) (xy 110.991632 -391.174985)
			(xy 111.047069 -391.181085) (xy 111.101026 -391.195191) (xy 111.152355 -391.217003) (xy 111.199961 -391.246057)
			(xy 111.242829 -391.281732) (xy 111.280046 -391.323269) (xy 111.310819 -391.369782) (xy 111.334491 -391.420279)
			(xy 111.350559 -391.473686) (xy 111.358679 -391.528862) (xy 111.359188 -391.556748) (xy 111.358679 -391.584634)
			(xy 111.350559 -391.63981) (xy 111.334491 -391.693217) (xy 111.310819 -391.743714) (xy 111.280046 -391.790227)
			(xy 111.242829 -391.831764) (xy 111.199961 -391.867439) (xy 111.152355 -391.896493) (xy 111.101026 -391.918305)
			(xy 111.047069 -391.932411) (xy 110.991632 -391.938511) (xy 110.935898 -391.936474) (xy 110.881055 -391.926344)
			(xy 110.828271 -391.908337) (xy 110.778671 -391.882836) (xy 110.733313 -391.850385) (xy 110.693164 -391.811676)
			(xy 110.659078 -391.767533) (xy 110.631782 -391.718898) (xy 110.611859 -391.666807) (xy 110.599733 -391.61237)
			(xy 110.595662 -391.556748) (xy 110.009107 -391.556748) (xy 110.004359 -391.58901) (xy 109.988291 -391.642417)
			(xy 109.964619 -391.692914) (xy 109.933846 -391.739427) (xy 109.896629 -391.780964) (xy 109.853761 -391.816639)
			(xy 109.806155 -391.845693) (xy 109.754826 -391.867505) (xy 109.700869 -391.881611) (xy 109.645432 -391.887711)
			(xy 109.589698 -391.885674) (xy 109.534855 -391.875544) (xy 109.482071 -391.857537) (xy 109.432471 -391.832036)
			(xy 109.387113 -391.799585) (xy 109.346964 -391.760876) (xy 109.312878 -391.716733) (xy 109.285582 -391.668098)
			(xy 109.265659 -391.616007) (xy 109.253533 -391.56157) (xy 109.249462 -391.505948) (xy 98.87966 -391.505948)
			(xy 98.87966 -393.65174) (xy 100.435916 -393.65174) (xy 100.439987 -393.596118) (xy 100.452113 -393.541681)
			(xy 100.472036 -393.48959) (xy 100.499332 -393.440955) (xy 100.533418 -393.396812) (xy 100.573567 -393.358103)
			(xy 100.618925 -393.325652) (xy 100.668525 -393.300151) (xy 100.721309 -393.282144) (xy 100.776152 -393.272014)
			(xy 100.831886 -393.269977) (xy 100.887323 -393.276077) (xy 100.94128 -393.290183) (xy 100.992609 -393.311995)
			(xy 101.040215 -393.341049) (xy 101.083083 -393.376724) (xy 101.1203 -393.418261) (xy 101.151073 -393.464774)
			(xy 101.174745 -393.515271) (xy 101.190813 -393.568678) (xy 101.198933 -393.623854) (xy 101.199442 -393.65174)
			(xy 101.198933 -393.679626) (xy 101.194215 -393.711684) (xy 106.949746 -393.711684) (xy 106.953817 -393.656062)
			(xy 106.965943 -393.601625) (xy 106.985866 -393.549534) (xy 107.013162 -393.500899) (xy 107.047248 -393.456756)
			(xy 107.087397 -393.418047) (xy 107.132755 -393.385596) (xy 107.182355 -393.360095) (xy 107.235139 -393.342088)
			(xy 107.289982 -393.331958) (xy 107.345716 -393.329921) (xy 107.401153 -393.336021) (xy 107.45511 -393.350127)
			(xy 107.506439 -393.371939) (xy 107.554045 -393.400993) (xy 107.596913 -393.436668) (xy 107.63413 -393.478205)
			(xy 107.664903 -393.524718) (xy 107.688575 -393.575215) (xy 107.704643 -393.628622) (xy 107.712763 -393.683798)
			(xy 107.713272 -393.711684) (xy 107.712763 -393.73957) (xy 107.704643 -393.794746) (xy 107.688575 -393.848153)
			(xy 107.664903 -393.89865) (xy 107.63413 -393.945163) (xy 107.596913 -393.9867) (xy 107.554045 -394.022375)
			(xy 107.506439 -394.051429) (xy 107.45511 -394.073241) (xy 107.401153 -394.087347) (xy 107.345716 -394.093447)
			(xy 107.289982 -394.09141) (xy 107.235139 -394.08128) (xy 107.182355 -394.063273) (xy 107.132755 -394.037772)
			(xy 107.087397 -394.005321) (xy 107.047248 -393.966612) (xy 107.013162 -393.922469) (xy 106.985866 -393.873834)
			(xy 106.965943 -393.821743) (xy 106.953817 -393.767306) (xy 106.949746 -393.711684) (xy 101.194215 -393.711684)
			(xy 101.190813 -393.734802) (xy 101.174745 -393.788209) (xy 101.151073 -393.838706) (xy 101.1203 -393.885219)
			(xy 101.083083 -393.926756) (xy 101.040215 -393.962431) (xy 100.992609 -393.991485) (xy 100.94128 -394.013297)
			(xy 100.887323 -394.027403) (xy 100.831886 -394.033503) (xy 100.776152 -394.031466) (xy 100.721309 -394.021336)
			(xy 100.668525 -394.003329) (xy 100.618925 -393.977828) (xy 100.573567 -393.945377) (xy 100.533418 -393.906668)
			(xy 100.499332 -393.862525) (xy 100.472036 -393.81389) (xy 100.452113 -393.761799) (xy 100.439987 -393.707362)
			(xy 100.435916 -393.65174) (xy 98.87966 -393.65174) (xy 98.87966 -394.322808) (xy 102.354632 -394.322808)
			(xy 102.358703 -394.267186) (xy 102.370829 -394.212749) (xy 102.390752 -394.160658) (xy 102.418048 -394.112023)
			(xy 102.452134 -394.06788) (xy 102.492283 -394.029171) (xy 102.537641 -393.99672) (xy 102.587241 -393.971219)
			(xy 102.640025 -393.953212) (xy 102.694868 -393.943082) (xy 102.750602 -393.941045) (xy 102.806039 -393.947145)
			(xy 102.859996 -393.961251) (xy 102.911325 -393.983063) (xy 102.958931 -394.012117) (xy 103.001799 -394.047792)
			(xy 103.039016 -394.089329) (xy 103.069789 -394.135842) (xy 103.093461 -394.186339) (xy 103.109529 -394.239746)
			(xy 103.117649 -394.294922) (xy 103.118158 -394.322808) (xy 103.117649 -394.350694) (xy 103.116034 -394.36167)
			(xy 107.522262 -394.36167) (xy 107.526333 -394.306048) (xy 107.538459 -394.251611) (xy 107.558382 -394.19952)
			(xy 107.585678 -394.150885) (xy 107.619764 -394.106742) (xy 107.659913 -394.068033) (xy 107.705271 -394.035582)
			(xy 107.754871 -394.010081) (xy 107.807655 -393.992074) (xy 107.862498 -393.981944) (xy 107.918232 -393.979907)
			(xy 107.973669 -393.986007) (xy 108.027626 -394.000113) (xy 108.078955 -394.021925) (xy 108.126561 -394.050979)
			(xy 108.169429 -394.086654) (xy 108.206646 -394.128191) (xy 108.237419 -394.174704) (xy 108.261091 -394.225201)
			(xy 108.277159 -394.278608) (xy 108.285279 -394.333784) (xy 108.285788 -394.36167) (xy 108.285279 -394.389556)
			(xy 108.277159 -394.444732) (xy 108.261091 -394.498139) (xy 108.237419 -394.548636) (xy 108.206646 -394.595149)
			(xy 108.169429 -394.636686) (xy 108.126561 -394.672361) (xy 108.078955 -394.701415) (xy 108.027626 -394.723227)
			(xy 107.973669 -394.737333) (xy 107.918232 -394.743433) (xy 107.862498 -394.741396) (xy 107.807655 -394.731266)
			(xy 107.754871 -394.713259) (xy 107.705271 -394.687758) (xy 107.659913 -394.655307) (xy 107.619764 -394.616598)
			(xy 107.585678 -394.572455) (xy 107.558382 -394.52382) (xy 107.538459 -394.471729) (xy 107.526333 -394.417292)
			(xy 107.522262 -394.36167) (xy 103.116034 -394.36167) (xy 103.109529 -394.40587) (xy 103.093461 -394.459277)
			(xy 103.069789 -394.509774) (xy 103.039016 -394.556287) (xy 103.001799 -394.597824) (xy 102.958931 -394.633499)
			(xy 102.911325 -394.662553) (xy 102.859996 -394.684365) (xy 102.806039 -394.698471) (xy 102.750602 -394.704571)
			(xy 102.694868 -394.702534) (xy 102.640025 -394.692404) (xy 102.587241 -394.674397) (xy 102.537641 -394.648896)
			(xy 102.492283 -394.616445) (xy 102.452134 -394.577736) (xy 102.418048 -394.533593) (xy 102.390752 -394.484958)
			(xy 102.370829 -394.432867) (xy 102.358703 -394.37843) (xy 102.354632 -394.322808) (xy 98.87966 -394.322808)
			(xy 98.87966 -395.188948) (xy 106.252262 -395.188948) (xy 106.256333 -395.133326) (xy 106.268459 -395.078889)
			(xy 106.288382 -395.026798) (xy 106.315678 -394.978163) (xy 106.349764 -394.93402) (xy 106.389913 -394.895311)
			(xy 106.435271 -394.86286) (xy 106.484871 -394.837359) (xy 106.537655 -394.819352) (xy 106.592498 -394.809222)
			(xy 106.648232 -394.807185) (xy 106.703669 -394.813285) (xy 106.757626 -394.827391) (xy 106.808955 -394.849203)
			(xy 106.856561 -394.878257) (xy 106.899429 -394.913932) (xy 106.936646 -394.955469) (xy 106.967419 -395.001982)
			(xy 106.991091 -395.052479) (xy 107.007159 -395.105886) (xy 107.015279 -395.161062) (xy 107.015788 -395.188948)
			(xy 107.015279 -395.216834) (xy 107.007159 -395.27201) (xy 106.991091 -395.325417) (xy 106.967419 -395.375914)
			(xy 106.936646 -395.422427) (xy 106.899429 -395.463964) (xy 106.856561 -395.499639) (xy 106.808955 -395.528693)
			(xy 106.757626 -395.550505) (xy 106.703669 -395.564611) (xy 106.648232 -395.570711) (xy 106.592498 -395.568674)
			(xy 106.537655 -395.558544) (xy 106.484871 -395.540537) (xy 106.435271 -395.515036) (xy 106.389913 -395.482585)
			(xy 106.349764 -395.443876) (xy 106.315678 -395.399733) (xy 106.288382 -395.351098) (xy 106.268459 -395.299007)
			(xy 106.256333 -395.24457) (xy 106.252262 -395.188948) (xy 98.87966 -395.188948) (xy 98.87966 -396.44574)
			(xy 100.442266 -396.44574) (xy 100.446337 -396.390118) (xy 100.458463 -396.335681) (xy 100.478386 -396.28359)
			(xy 100.505682 -396.234955) (xy 100.539768 -396.190812) (xy 100.579917 -396.152103) (xy 100.625275 -396.119652)
			(xy 100.674875 -396.094151) (xy 100.727659 -396.076144) (xy 100.782502 -396.066014) (xy 100.838236 -396.063977)
			(xy 100.893673 -396.070077) (xy 100.94763 -396.084183) (xy 100.998959 -396.105995) (xy 101.046565 -396.135049)
			(xy 101.089433 -396.170724) (xy 101.12665 -396.212261) (xy 101.157423 -396.258774) (xy 101.181095 -396.309271)
			(xy 101.197163 -396.362678) (xy 101.205283 -396.417854) (xy 101.205792 -396.44574) (xy 101.205283 -396.473626)
			(xy 101.197163 -396.528802) (xy 101.181095 -396.582209) (xy 101.157423 -396.632706) (xy 101.12665 -396.679219)
			(xy 101.089433 -396.720756) (xy 101.046565 -396.756431) (xy 100.998959 -396.785485) (xy 100.94763 -396.807297)
			(xy 100.893673 -396.821403) (xy 100.838236 -396.827503) (xy 100.782502 -396.825466) (xy 100.727659 -396.815336)
			(xy 100.674875 -396.797329) (xy 100.625275 -396.771828) (xy 100.579917 -396.739377) (xy 100.539768 -396.700668)
			(xy 100.505682 -396.656525) (xy 100.478386 -396.60789) (xy 100.458463 -396.555799) (xy 100.446337 -396.501362)
			(xy 100.442266 -396.44574) (xy 98.87966 -396.44574) (xy 98.87966 -396.75054) (xy 100.0633 -397.93418)
			(xy 102.487982 -397.93418) (xy 102.492053 -397.878558) (xy 102.504179 -397.824121) (xy 102.524102 -397.77203)
			(xy 102.551398 -397.723395) (xy 102.585484 -397.679252) (xy 102.625633 -397.640543) (xy 102.670991 -397.608092)
			(xy 102.720591 -397.582591) (xy 102.773375 -397.564584) (xy 102.828218 -397.554454) (xy 102.883952 -397.552417)
			(xy 102.939389 -397.558517) (xy 102.993346 -397.572623) (xy 103.044675 -397.594435) (xy 103.092281 -397.623489)
			(xy 103.135149 -397.659164) (xy 103.172366 -397.700701) (xy 103.203139 -397.747214) (xy 103.226811 -397.797711)
			(xy 103.242879 -397.851118) (xy 103.250999 -397.906294) (xy 103.251508 -397.93418) (xy 103.250999 -397.962066)
			(xy 103.246804 -397.990568) (xy 103.539542 -397.990568) (xy 103.543613 -397.934946) (xy 103.555739 -397.880509)
			(xy 103.575662 -397.828418) (xy 103.602958 -397.779783) (xy 103.637044 -397.73564) (xy 103.677193 -397.696931)
			(xy 103.722551 -397.66448) (xy 103.772151 -397.638979) (xy 103.824935 -397.620972) (xy 103.879778 -397.610842)
			(xy 103.935512 -397.608805) (xy 103.990949 -397.614905) (xy 104.044906 -397.629011) (xy 104.096235 -397.650823)
			(xy 104.143841 -397.679877) (xy 104.186709 -397.715552) (xy 104.223926 -397.757089) (xy 104.254699 -397.803602)
			(xy 104.278371 -397.854099) (xy 104.294439 -397.907506) (xy 104.302559 -397.962682) (xy 104.303068 -397.990568)
			(xy 104.302559 -398.018454) (xy 104.294439 -398.07363) (xy 104.278371 -398.127037) (xy 104.254699 -398.177534)
			(xy 104.223926 -398.224047) (xy 104.186709 -398.265584) (xy 104.143841 -398.301259) (xy 104.096235 -398.330313)
			(xy 104.044906 -398.352125) (xy 103.990949 -398.366231) (xy 103.935512 -398.372331) (xy 103.879778 -398.370294)
			(xy 103.824935 -398.360164) (xy 103.772151 -398.342157) (xy 103.722551 -398.316656) (xy 103.677193 -398.284205)
			(xy 103.637044 -398.245496) (xy 103.602958 -398.201353) (xy 103.575662 -398.152718) (xy 103.555739 -398.100627)
			(xy 103.543613 -398.04619) (xy 103.539542 -397.990568) (xy 103.246804 -397.990568) (xy 103.242879 -398.017242)
			(xy 103.226811 -398.070649) (xy 103.203139 -398.121146) (xy 103.172366 -398.167659) (xy 103.135149 -398.209196)
			(xy 103.092281 -398.244871) (xy 103.044675 -398.273925) (xy 102.993346 -398.295737) (xy 102.939389 -398.309843)
			(xy 102.883952 -398.315943) (xy 102.828218 -398.313906) (xy 102.773375 -398.303776) (xy 102.720591 -398.285769)
			(xy 102.670991 -398.260268) (xy 102.625633 -398.227817) (xy 102.585484 -398.189108) (xy 102.551398 -398.144965)
			(xy 102.524102 -398.09633) (xy 102.504179 -398.044239) (xy 102.492053 -397.989802) (xy 102.487982 -397.93418)
			(xy 100.0633 -397.93418) (xy 100.60432 -398.4752) (xy 104.80802 -398.4752)
		)
		(stroke
			(width 0)
			(type solid)
		)
		(fill yes)
		(layer "In13.Cu")
		(net "P3V3_AUX")
	)
	(gr_poly
		(pts
			(arc
				(start 194.443604 -441.479432)
				(mid 194.479525 -441.464553)
				(end 194.494404 -441.428632)
			)
			(arc
				(start 194.494404 -441.17006)
				(mid 194.790421 -440.455411)
				(end 195.50507 -440.159394)
			)
			(arc
				(start 276.314916 -440.159394)
				(mid 277.029565 -440.455411)
				(end 277.325582 -441.17006)
			)
			(arc
				(start 277.325582 -441.428632)
				(mid 277.340461 -441.464553)
				(end 277.376382 -441.479432)
			)
			(arc
				(start 463.300064 -441.479432)
				(mid 464.353268 -441.04318)
				(end 464.78952 -439.989976)
			)
			(arc
				(start 464.78952 -409.528264)
				(mid 464.980687 -408.567674)
				(end 465.52485 -407.753312)
			)
			(arc
				(start 467.353396 -405.924766)
				(mid 467.676179 -405.441593)
				(end 467.789514 -404.871682)
			)
			(arc
				(start 467.789514 -82.82813)
				(mid 467.980666 -81.867526)
				(end 468.524844 -81.053178)
			)
			(arc
				(start 470.853262 -78.72476)
				(mid 471.176045 -78.241587)
				(end 471.28938 -77.671676)
			)
			(arc
				(start 471.28938 -26.830528)
				(mid 471.282359 -26.804504)
				(end 471.262964 -26.785824)
			)
			(arc
				(start 471.184732 -26.742898)
				(mid 471.158691 -26.736707)
				(end 471.13317 -26.744676)
			)
			(arc
				(start 471.13317 -26.744676)
				(mid 470.972573 -26.843084)
				(end 470.808558 -26.935684)
			)
			(arc
				(start 470.808558 -26.935684)
				(mid 470.789062 -26.95436)
				(end 470.781888 -26.980388)
			)
			(arc
				(start 470.781888 -77.672184)
				(mid 470.707176 -78.047677)
				(end 470.494614 -78.366112)
			)
			(arc
				(start 468.166196 -80.69453)
				(mid 467.512084 -81.673433)
				(end 467.282276 -82.82813)
			)
			(arc
				(start 467.282276 -115.09883)
				(mid 467.283688 -115.110723)
				(end 467.287864 -115.121944)
			)
			(arc
				(start 467.287864 -115.121944)
				(mid 467.319142 -115.206449)
				(end 467.329774 -115.295934)
			)
			(arc
				(start 467.329774 -115.295934)
				(mid 467.31919 -115.38543)
				(end 467.287864 -115.469924)
			)
			(arc
				(start 467.287864 -115.469924)
				(mid 467.283709 -115.481151)
				(end 467.282276 -115.493038)
			)
			(arc
				(start 467.282276 -358.935274)
				(mid 467.28295 -358.943778)
				(end 467.28507 -358.952038)
			)
			(arc
				(start 467.28507 -358.952038)
				(mid 467.514132 -359.845086)
				(end 467.59114 -360.76382)
			)
			(arc
				(start 467.59114 -360.76382)
				(mid 467.514124 -361.682553)
				(end 467.28507 -362.575602)
			)
			(arc
				(start 467.28507 -362.575602)
				(mid 467.282984 -362.583868)
				(end 467.282276 -362.592366)
			)
			(arc
				(start 467.282276 -404.871936)
				(mid 467.207495 -405.247595)
				(end 466.994748 -405.566118)
			)
			(arc
				(start 465.166202 -407.394664)
				(mid 464.5119 -408.373524)
				(end 464.282028 -409.528264)
			)
			(arc
				(start 464.282028 -439.989976)
				(mid 463.994417 -440.684329)
				(end 463.300064 -440.97194)
			)
			(xy 410.917898 -440.97194)
			(arc
				(start 410.910024 -440.974734)
				(mid 410.831038 -440.993945)
				(end 410.750004 -441.000388)
			)
			(arc
				(start 410.750004 -441.000388)
				(mid 410.668968 -440.993957)
				(end 410.589984 -440.974734)
			)
			(xy 410.58211 -440.97194) (xy 406.917906 -440.97194)
			(arc
				(start 406.910032 -440.974734)
				(mid 406.831046 -440.993945)
				(end 406.750012 -441.000388)
			)
			(arc
				(start 406.750012 -441.000388)
				(mid 406.668976 -440.993957)
				(end 406.589992 -440.974734)
			)
			(xy 406.582118 -440.97194) (xy 402.917914 -440.97194)
			(arc
				(start 402.91004 -440.974734)
				(mid 402.831054 -440.993945)
				(end 402.75002 -441.000388)
			)
			(arc
				(start 402.75002 -441.000388)
				(mid 402.668984 -440.993957)
				(end 402.59 -440.974734)
			)
			(xy 402.582126 -440.97194) (xy 398.917922 -440.97194)
			(arc
				(start 398.910048 -440.974734)
				(mid 398.831062 -440.993945)
				(end 398.750028 -441.000388)
			)
			(arc
				(start 398.750028 -441.000388)
				(mid 398.668992 -440.993957)
				(end 398.590008 -440.974734)
			)
			(xy 398.582134 -440.97194) (xy 393.917932 -440.97194)
			(arc
				(start 393.910058 -440.974734)
				(mid 393.831072 -440.993945)
				(end 393.750038 -441.000388)
			)
			(arc
				(start 393.750038 -441.000388)
				(mid 393.669002 -440.993957)
				(end 393.590018 -440.974734)
			)
			(xy 393.582144 -440.97194) (xy 389.91794 -440.97194)
			(arc
				(start 389.910066 -440.974734)
				(mid 389.83108 -440.993945)
				(end 389.750046 -441.000388)
			)
			(arc
				(start 389.750046 -441.000388)
				(mid 389.66901 -440.993957)
				(end 389.590026 -440.974734)
			)
			(xy 389.582152 -440.97194) (xy 385.917948 -440.97194)
			(arc
				(start 385.910074 -440.974734)
				(mid 385.831088 -440.993945)
				(end 385.750054 -441.000388)
			)
			(arc
				(start 385.750054 -441.000388)
				(mid 385.669018 -440.993957)
				(end 385.590034 -440.974734)
			)
			(xy 385.58216 -440.97194) (xy 381.917956 -440.97194)
			(arc
				(start 381.910082 -440.974734)
				(mid 381.831096 -440.993945)
				(end 381.750062 -441.000388)
			)
			(arc
				(start 381.750062 -441.000388)
				(mid 381.669026 -440.993957)
				(end 381.590042 -440.974734)
			)
			(xy 381.582168 -440.97194) (xy 343.817956 -440.97194)
			(arc
				(start 343.810082 -440.974734)
				(mid 343.731096 -440.993945)
				(end 343.650062 -441.000388)
			)
			(arc
				(start 343.650062 -441.000388)
				(mid 343.569026 -440.993957)
				(end 343.490042 -440.974734)
			)
			(xy 343.482168 -440.97194) (xy 339.817964 -440.97194)
			(arc
				(start 339.81009 -440.974734)
				(mid 339.731104 -440.993945)
				(end 339.65007 -441.000388)
			)
			(arc
				(start 339.65007 -441.000388)
				(mid 339.569034 -440.993957)
				(end 339.49005 -440.974734)
			)
			(xy 339.482176 -440.97194) (xy 335.817972 -440.97194)
			(arc
				(start 335.810098 -440.974734)
				(mid 335.731112 -440.993945)
				(end 335.650078 -441.000388)
			)
			(arc
				(start 335.650078 -441.000388)
				(mid 335.569042 -440.993957)
				(end 335.490058 -440.974734)
			)
			(xy 335.482184 -440.97194) (xy 331.81798 -440.97194)
			(arc
				(start 331.810106 -440.974734)
				(mid 331.73112 -440.993945)
				(end 331.650086 -441.000388)
			)
			(arc
				(start 331.650086 -441.000388)
				(mid 331.56905 -440.993957)
				(end 331.490066 -440.974734)
			)
			(xy 331.482192 -440.97194) (xy 326.81799 -440.97194)
			(arc
				(start 326.810116 -440.974734)
				(mid 326.73113 -440.993945)
				(end 326.650096 -441.000388)
			)
			(arc
				(start 326.650096 -441.000388)
				(mid 326.56906 -440.993957)
				(end 326.490076 -440.974734)
			)
			(xy 326.482202 -440.97194) (xy 322.817998 -440.97194)
			(arc
				(start 322.810124 -440.974734)
				(mid 322.731138 -440.993945)
				(end 322.650104 -441.000388)
			)
			(arc
				(start 322.650104 -441.000388)
				(mid 322.569068 -440.993957)
				(end 322.490084 -440.974734)
			)
			(xy 322.48221 -440.97194) (xy 318.818006 -440.97194)
			(arc
				(start 318.810132 -440.974734)
				(mid 318.731146 -440.993945)
				(end 318.650112 -441.000388)
			)
			(arc
				(start 318.650112 -441.000388)
				(mid 318.569076 -440.993957)
				(end 318.490092 -440.974734)
			)
			(xy 318.482218 -440.97194) (xy 314.818014 -440.97194)
			(arc
				(start 314.81014 -440.974734)
				(mid 314.731154 -440.993945)
				(end 314.65012 -441.000388)
			)
			(arc
				(start 314.65012 -441.000388)
				(mid 314.569084 -440.993957)
				(end 314.4901 -440.974734)
			)
			(xy 314.482226 -440.97194)
			(arc
				(start 277.82012 -440.97194)
				(mid 277.31587 -440.028787)
				(end 276.314916 -439.652156)
			)
			(arc
				(start 195.50507 -439.652156)
				(mid 194.504157 -440.028834)
				(end 193.999866 -440.97194)
			)
			(xy 154.917902 -440.97194)
			(arc
				(start 154.910028 -440.974734)
				(mid 154.831042 -440.993945)
				(end 154.750008 -441.000388)
			)
			(arc
				(start 154.750008 -441.000388)
				(mid 154.668972 -440.993957)
				(end 154.589988 -440.974734)
			)
			(xy 154.582114 -440.97194) (xy 150.91791 -440.97194)
			(arc
				(start 150.910036 -440.974734)
				(mid 150.83105 -440.993945)
				(end 150.750016 -441.000388)
			)
			(arc
				(start 150.750016 -441.000388)
				(mid 150.66898 -440.993957)
				(end 150.589996 -440.974734)
			)
			(xy 150.582122 -440.97194) (xy 146.917918 -440.97194)
			(arc
				(start 146.910044 -440.974734)
				(mid 146.831058 -440.993945)
				(end 146.750024 -441.000388)
			)
			(arc
				(start 146.750024 -441.000388)
				(mid 146.668988 -440.993957)
				(end 146.590004 -440.974734)
			)
			(xy 146.58213 -440.97194) (xy 142.917926 -440.97194)
			(arc
				(start 142.910052 -440.974734)
				(mid 142.831066 -440.993945)
				(end 142.750032 -441.000388)
			)
			(arc
				(start 142.750032 -441.000388)
				(mid 142.668996 -440.993957)
				(end 142.590012 -440.974734)
			)
			(xy 142.582138 -440.97194) (xy 137.917936 -440.97194)
			(arc
				(start 137.910062 -440.974734)
				(mid 137.831076 -440.993945)
				(end 137.750042 -441.000388)
			)
			(arc
				(start 137.750042 -441.000388)
				(mid 137.669006 -440.993957)
				(end 137.590022 -440.974734)
			)
			(xy 137.582148 -440.97194) (xy 133.917944 -440.97194)
			(arc
				(start 133.91007 -440.974734)
				(mid 133.831084 -440.993945)
				(end 133.75005 -441.000388)
			)
			(arc
				(start 133.75005 -441.000388)
				(mid 133.669014 -440.993957)
				(end 133.59003 -440.974734)
			)
			(xy 133.582156 -440.97194) (xy 129.917952 -440.97194)
			(arc
				(start 129.910078 -440.974734)
				(mid 129.831092 -440.993945)
				(end 129.750058 -441.000388)
			)
			(arc
				(start 129.750058 -441.000388)
				(mid 129.669022 -440.993957)
				(end 129.590038 -440.974734)
			)
			(xy 129.582164 -440.97194) (xy 125.91796 -440.97194)
			(arc
				(start 125.910086 -440.974734)
				(mid 125.8311 -440.993945)
				(end 125.750066 -441.000388)
			)
			(arc
				(start 125.750066 -441.000388)
				(mid 125.66903 -440.993957)
				(end 125.590046 -440.974734)
			)
			(xy 125.582172 -440.97194) (xy 87.81796 -440.97194)
			(arc
				(start 87.810086 -440.974734)
				(mid 87.7311 -440.993945)
				(end 87.650066 -441.000388)
			)
			(arc
				(start 87.650066 -441.000388)
				(mid 87.56903 -440.993957)
				(end 87.490046 -440.974734)
			)
			(xy 87.482172 -440.97194) (xy 83.817968 -440.97194)
			(arc
				(start 83.810094 -440.974734)
				(mid 83.731108 -440.993945)
				(end 83.650074 -441.000388)
			)
			(arc
				(start 83.650074 -441.000388)
				(mid 83.569038 -440.993957)
				(end 83.490054 -440.974734)
			)
			(xy 83.48218 -440.97194) (xy 79.817976 -440.97194)
			(arc
				(start 79.810102 -440.974734)
				(mid 79.731116 -440.993945)
				(end 79.650082 -441.000388)
			)
			(arc
				(start 79.650082 -441.000388)
				(mid 79.569046 -440.993957)
				(end 79.490062 -440.974734)
			)
			(xy 79.482188 -440.97194) (xy 75.817984 -440.97194)
			(arc
				(start 75.81011 -440.974734)
				(mid 75.731124 -440.993945)
				(end 75.65009 -441.000388)
			)
			(arc
				(start 75.65009 -441.000388)
				(mid 75.569054 -440.993957)
				(end 75.49007 -440.974734)
			)
			(xy 75.482196 -440.97194) (xy 70.817994 -440.97194)
			(arc
				(start 70.81012 -440.974734)
				(mid 70.731134 -440.993945)
				(end 70.6501 -441.000388)
			)
			(arc
				(start 70.6501 -441.000388)
				(mid 70.569064 -440.993957)
				(end 70.49008 -440.974734)
			)
			(xy 70.482206 -440.97194) (xy 66.818002 -440.97194)
			(arc
				(start 66.810128 -440.974734)
				(mid 66.731142 -440.993945)
				(end 66.650108 -441.000388)
			)
			(arc
				(start 66.650108 -441.000388)
				(mid 66.569072 -440.993957)
				(end 66.490088 -440.974734)
			)
			(xy 66.482214 -440.97194) (xy 62.81801 -440.97194)
			(arc
				(start 62.810136 -440.974734)
				(mid 62.73115 -440.993945)
				(end 62.650116 -441.000388)
			)
			(arc
				(start 62.650116 -441.000388)
				(mid 62.56908 -440.993957)
				(end 62.490096 -440.974734)
			)
			(xy 62.482222 -440.97194) (xy 58.818018 -440.97194)
			(arc
				(start 58.810144 -440.974734)
				(mid 58.731158 -440.993945)
				(end 58.650124 -441.000388)
			)
			(arc
				(start 58.650124 -441.000388)
				(mid 58.569088 -440.993957)
				(end 58.490104 -440.974734)
			)
			(xy 58.48223 -440.97194)
			(arc
				(start 8.50011 -440.97194)
				(mid 7.805667 -440.684345)
				(end 7.517892 -439.989976)
			)
			(arc
				(start 7.517892 -409.528264)
				(mid 7.287997 -408.373534)
				(end 6.633718 -407.394664)
			)
			(arc
				(start 3.305302 -404.066248)
				(mid 3.092701 -403.747829)
				(end 3.018028 -403.37232)
			)
			(arc
				(start 3.018028 -165.19779)
				(mid 3.014127 -165.178267)
				(end 3.003042 -165.161722)
			)
			(arc
				(start 2.910586 -165.069266)
				(mid 2.830694 -164.9497)
				(end 2.802636 -164.808662)
			)
			(arc
				(start 2.802636 -135.781034)
				(mid 2.830691 -135.639994)
				(end 2.910586 -135.52043)
			)
			(arc
				(start 3.003042 -135.427974)
				(mid 3.014153 -135.41144)
				(end 3.018028 -135.391906)
			)
			(arc
				(start 3.018028 -81.32826)
				(mid 2.788133 -80.17353)
				(end 2.133854 -79.19466)
			)
			(arc
				(start 1.305306 -78.366112)
				(mid 1.092705 -78.047693)
				(end 1.018032 -77.672184)
			)
			(arc
				(start 1.018032 -45.522896)
				(mid 1.014131 -45.503373)
				(end 1.003046 -45.486828)
			)
			(arc
				(start 0.688086 -45.171868)
				(mid 0.676975 -45.155334)
				(end 0.6731 -45.1358)
			)
			(arc
				(start 0.6731 -41.861486)
				(mid 0.664045 -41.832538)
				(end 0.64008 -41.813988)
			)
			(arc
				(start 0.64008 -41.813988)
				(mid 0.612888 -41.802522)
				(end 0.58674 -41.788842)
			)
			(arc
				(start 0.58674 -41.788842)
				(mid 0.535974 -41.788822)
				(end 0.51054 -41.832784)
			)
			(arc
				(start 0.51054 -77.671676)
				(mid 0.623884 -78.241583)
				(end 0.946658 -78.72476)
			)
			(arc
				(start 1.775206 -79.553308)
				(mid 2.319424 -80.367648)
				(end 2.510536 -81.32826)
			)
			(arc
				(start 2.510536 -403.371812)
				(mid 2.62388 -403.941719)
				(end 2.946654 -404.424896)
			)
			(arc
				(start 6.27507 -407.753312)
				(mid 6.819424 -408.567623)
				(end 7.010654 -409.528264)
			)
			(arc
				(start 7.010654 -439.989976)
				(mid 7.446906 -441.04318)
				(end 8.50011 -441.479432)
			)
		)
		(stroke
			(width 0)
			(type solid)
		)
		(fill yes)
		(layer "In13.Cu")
		(net "GND")
	)
	(gr_poly
		(pts
			(xy 120.326404 -270.955262) (xy 120.331075 -270.929185) (xy 120.347112 -270.878696) (xy 120.370448 -270.831138)
			(xy 120.400569 -270.78756) (xy 120.43681 -270.748922) (xy 120.478373 -270.716076) (xy 120.524341 -270.689747)
			(xy 120.573701 -270.670514) (xy 120.625365 -270.658802) (xy 120.678194 -270.654869) (xy 120.731023 -270.658802)
			(xy 120.782687 -270.670514) (xy 120.832047 -270.689747) (xy 120.878015 -270.716076) (xy 120.919578 -270.748922)
			(xy 120.955819 -270.78756) (xy 120.98594 -270.831138) (xy 121.009276 -270.878696) (xy 121.025313 -270.929185)
			(xy 121.029984 -270.955262) (xy 121.036588 -270.998188) (xy 121.2596 -270.998188) (xy 121.266204 -270.955262)
			(xy 121.27117 -270.927737) (xy 121.288539 -270.874574) (xy 121.313998 -270.824776) (xy 121.34692 -270.779564)
			(xy 121.386499 -270.740049) (xy 121.431764 -270.707199) (xy 121.481602 -270.68182) (xy 121.534793 -270.664536)
			(xy 121.59003 -270.65577) (xy 121.617994 -270.655288) (xy 121.643904 -270.655754) (xy 121.695176 -270.663266)
			(xy 121.744817 -270.678132) (xy 121.791779 -270.700037) (xy 121.835069 -270.728519) (xy 121.873772 -270.762977)
			(xy 121.907071 -270.802681) (xy 121.934262 -270.846794) (xy 121.944892 -270.870426) (xy 121.950947 -270.883261)
			(xy 121.968927 -270.905202) (xy 121.992247 -270.921355) (xy 122.01911 -270.930472) (xy 122.047443 -270.931853)
			(xy 122.075065 -270.925389) (xy 122.099844 -270.91158) (xy 122.110246 -270.901922) (xy 122.69216 -270.320008)
			(xy 122.68454 -270.29156) (xy 122.678629 -270.268515) (xy 122.672261 -270.221367) (xy 122.67184 -270.19758)
			(xy 122.672273 -270.172451) (xy 122.679343 -270.122691) (xy 122.693341 -270.074421) (xy 122.713987 -270.028598)
			(xy 122.740872 -269.986135) (xy 122.77346 -269.947873) (xy 122.811106 -269.914575) (xy 122.83186 -269.9004)
			(xy 122.83186 -269.807436) (xy 122.831389 -269.793205) (xy 122.823533 -269.765848) (xy 122.808422 -269.741728)
			(xy 122.787234 -269.722724) (xy 122.76162 -269.710315) (xy 122.733573 -269.705468) (xy 122.70528 -269.708561)
			(xy 122.691906 -269.713456) (xy 122.670529 -269.721742) (xy 122.626186 -269.733388) (xy 122.580717 -269.739266)
			(xy 122.557794 -269.739618) (xy 122.531144 -269.73912) (xy 122.47844 -269.731175) (xy 122.427509 -269.715464)
			(xy 122.379488 -269.692338) (xy 122.33545 -269.662313) (xy 122.296379 -269.626059) (xy 122.263148 -269.584388)
			(xy 122.236498 -269.538229) (xy 122.217026 -269.488614) (xy 122.205166 -269.436651) (xy 122.201182 -269.3835)
			(xy 122.205166 -269.330349) (xy 122.217026 -269.278386) (xy 122.236498 -269.228771) (xy 122.263148 -269.182612)
			(xy 122.296379 -269.140941) (xy 122.33545 -269.104687) (xy 122.379488 -269.074662) (xy 122.427509 -269.051536)
			(xy 122.47844 -269.035825) (xy 122.531144 -269.02788) (xy 122.557794 -269.027402) (xy 122.58072 -269.027736)
			(xy 122.626195 -269.033589) (xy 122.670539 -269.04525) (xy 122.691906 -269.053564) (xy 122.705255 -269.058487)
			(xy 122.733533 -269.061528) (xy 122.761551 -269.056649) (xy 122.787137 -269.044229) (xy 122.808303 -269.025232)
			(xy 122.823406 -269.001134) (xy 122.831275 -268.973804) (xy 122.83186 -268.959584) (xy 122.83186 -268.867128)
			(xy 122.809511 -268.851806) (xy 122.769292 -268.815495) (xy 122.735038 -268.773511) (xy 122.707539 -268.726822)
			(xy 122.687432 -268.676506) (xy 122.675178 -268.623725) (xy 122.671063 -268.569697) (xy 122.675179 -268.515668)
			(xy 122.687434 -268.462887) (xy 122.707542 -268.412572) (xy 122.735042 -268.365883) (xy 122.769296 -268.3239)
			(xy 122.809516 -268.28759) (xy 122.83186 -268.27226) (xy 122.83186 -267.238988) (xy 122.809538 -267.223673)
			(xy 122.769369 -267.187385) (xy 122.735158 -267.145432) (xy 122.707695 -267.098783) (xy 122.687613 -267.048513)
			(xy 122.675375 -266.995781) (xy 122.671264 -266.941804) (xy 122.675374 -266.887828) (xy 122.68761 -266.835096)
			(xy 122.707691 -266.784825) (xy 122.735153 -266.738175) (xy 122.769362 -266.696222) (xy 122.809531 -266.659933)
			(xy 122.83186 -266.644628) (xy 122.83186 -266.552172) (xy 122.831393 -266.537937) (xy 122.823543 -266.510572)
			(xy 122.808434 -266.486442) (xy 122.787244 -266.46743) (xy 122.761624 -266.455016) (xy 122.73357 -266.450168)
			(xy 122.70527 -266.453263) (xy 122.691906 -266.458192) (xy 122.67053 -266.466479) (xy 122.626187 -266.478128)
			(xy 122.580718 -266.484006) (xy 122.557794 -266.484354) (xy 122.531142 -266.483856) (xy 122.478432 -266.47591)
			(xy 122.427496 -266.460198) (xy 122.37947 -266.437069) (xy 122.335427 -266.407041) (xy 122.296353 -266.370784)
			(xy 122.263118 -266.329108) (xy 122.236466 -266.282945) (xy 122.216991 -266.233324) (xy 122.20513 -266.181356)
			(xy 122.201146 -266.1282) (xy 122.20513 -266.075044) (xy 122.216991 -266.023076) (xy 122.236466 -265.973455)
			(xy 122.263118 -265.927292) (xy 122.296353 -265.885616) (xy 122.335427 -265.849359) (xy 122.37947 -265.819331)
			(xy 122.427496 -265.796202) (xy 122.478432 -265.78049) (xy 122.531142 -265.772544) (xy 122.557794 -265.772138)
			(xy 122.58072 -265.772471) (xy 122.626196 -265.778323) (xy 122.67054 -265.789982) (xy 122.691906 -265.7983)
			(xy 122.705257 -265.803223) (xy 122.733537 -265.806261) (xy 122.761558 -265.801382) (xy 122.787146 -265.788963)
			(xy 122.808317 -265.769968) (xy 122.823427 -265.745871) (xy 122.831304 -265.718541) (xy 122.83186 -265.70432)
			(xy 122.83186 -265.611356) (xy 122.80954 -265.596041) (xy 122.769376 -265.559753) (xy 122.73517 -265.517802)
			(xy 122.707711 -265.471155) (xy 122.687633 -265.420888) (xy 122.675399 -265.36816) (xy 122.67129 -265.314187)
			(xy 122.675403 -265.260214) (xy 122.687641 -265.207487) (xy 122.707723 -265.157221) (xy 122.735185 -265.110576)
			(xy 122.769394 -265.068627) (xy 122.809561 -265.032343) (xy 122.83186 -265.016996) (xy 122.83186 -264.924286)
			(xy 122.831395 -264.91005) (xy 122.823547 -264.882681) (xy 122.808439 -264.858548) (xy 122.787247 -264.839532)
			(xy 122.761625 -264.827116) (xy 122.733569 -264.822268) (xy 122.705266 -264.825364) (xy 122.691906 -264.830306)
			(xy 122.67053 -264.838593) (xy 122.626187 -264.850241) (xy 122.580718 -264.85612) (xy 122.557794 -264.856468)
			(xy 122.531148 -264.85597) (xy 122.478451 -264.848026) (xy 122.427527 -264.832317) (xy 122.379513 -264.809194)
			(xy 122.335481 -264.779173) (xy 122.296416 -264.742925) (xy 122.263189 -264.701259) (xy 122.236543 -264.655107)
			(xy 122.217074 -264.605499) (xy 122.205215 -264.553543) (xy 122.201233 -264.5004) (xy 122.205215 -264.447257)
			(xy 122.217074 -264.395301) (xy 122.236543 -264.345693) (xy 122.263189 -264.299541) (xy 122.296416 -264.257875)
			(xy 122.335481 -264.221627) (xy 122.379513 -264.191606) (xy 122.427527 -264.168483) (xy 122.478451 -264.152774)
			(xy 122.531148 -264.14483) (xy 122.557794 -264.144252) (xy 122.58072 -264.144585) (xy 122.626196 -264.150437)
			(xy 122.67054 -264.162097) (xy 122.691906 -264.170414) (xy 122.705257 -264.175336) (xy 122.733538 -264.178374)
			(xy 122.76156 -264.173495) (xy 122.78715 -264.161076) (xy 122.808322 -264.142082) (xy 122.823434 -264.117985)
			(xy 122.831315 -264.090655) (xy 122.83186 -264.076434) (xy 122.83186 -263.983978) (xy 122.809507 -263.968656)
			(xy 122.76928 -263.932344) (xy 122.735019 -263.890358) (xy 122.707514 -263.843665) (xy 122.6874 -263.793345)
			(xy 122.675141 -263.740559) (xy 122.671021 -263.686524) (xy 122.675134 -263.632489) (xy 122.687385 -263.579701)
			(xy 122.707493 -263.529378) (xy 122.734992 -263.482682) (xy 122.769247 -263.440691) (xy 122.809469 -263.404374)
			(xy 122.83186 -263.38911) (xy 122.83186 -263.296654) (xy 122.831383 -263.28244) (xy 122.823538 -263.255115)
			(xy 122.808468 -263.231009) (xy 122.78734 -263.211987) (xy 122.76179 -263.199523) (xy 122.733794 -263.194581)
			(xy 122.70552 -263.197543) (xy 122.69216 -263.20242) (xy 122.670783 -263.210704) (xy 122.62644 -263.222346)
			(xy 122.580971 -263.228218) (xy 122.558048 -263.228582) (xy 122.530061 -263.228065) (xy 122.474775 -263.219315)
			(xy 122.421539 -263.202023) (xy 122.371664 -263.176615) (xy 122.326378 -263.143717) (xy 122.286798 -263.104138)
			(xy 122.253896 -263.058855) (xy 122.228485 -263.008981) (xy 122.21119 -262.955746) (xy 122.202437 -262.900461)
			(xy 122.20194 -262.872474) (xy 122.202506 -262.84413) (xy 122.211521 -262.788163) (xy 122.229288 -262.734331)
			(xy 122.255358 -262.683993) (xy 122.27179 -262.660892) (xy 122.297698 -262.625586) (xy 122.087386 -262.415274)
			(xy 122.068082 -262.414258) (xy 122.042171 -262.412327) (xy 121.991272 -262.4019) (xy 121.942428 -262.384187)
			(xy 121.896677 -262.359564) (xy 121.854989 -262.328554) (xy 121.81825 -262.291816) (xy 121.78724 -262.250128)
			(xy 121.762616 -262.204378) (xy 121.744902 -262.155534) (xy 121.734473 -262.104635) (xy 121.732548 -262.078724)
			(xy 121.731532 -262.05942) (xy 121.34596 -261.673848) (xy 121.34596 -261.474712) (xy 121.330161 -261.455339)
			(xy 121.303575 -261.413005) (xy 121.283163 -261.367372) (xy 121.269326 -261.319336) (xy 121.262337 -261.269837)
			(xy 121.261886 -261.244842) (xy 121.262488 -261.215703) (xy 121.272014 -261.158208) (xy 121.290769 -261.10303)
			(xy 121.318253 -261.05164) (xy 121.335546 -261.02818) (xy 121.34596 -261.014464) (xy 121.34596 -260.878828)
			(xy 121.02084 -260.553708) (xy 119.63146 -260.553708) (xy 118.5291 -261.656068) (xy 118.5291 -262.915654)
			(xy 118.529616 -262.930495) (xy 118.538154 -262.958922) (xy 118.554496 -262.983701) (xy 118.577264 -263.002744)
			(xy 118.604542 -263.014446) (xy 118.634032 -263.017823) (xy 118.648734 -263.01573) (xy 118.664532 -263.013011)
			(xy 118.696458 -263.010087) (xy 118.712488 -263.009888) (xy 118.73914 -263.01036) (xy 118.791849 -263.018303)
			(xy 118.842785 -263.034014) (xy 118.890811 -263.05714) (xy 118.934854 -263.087166) (xy 118.973929 -263.123422)
			(xy 119.007164 -263.165096) (xy 119.033816 -263.211258) (xy 119.053291 -263.260878) (xy 119.057108 -263.2776)
			(xy 119.348972 -263.2776) (xy 119.352956 -263.224445) (xy 119.364818 -263.172477) (xy 119.384293 -263.122858)
			(xy 119.410946 -263.076695) (xy 119.444182 -263.035022) (xy 119.483259 -262.998767) (xy 119.527302 -262.968742)
			(xy 119.575329 -262.945617) (xy 119.626266 -262.929908) (xy 119.678976 -262.921967) (xy 119.705628 -262.921496)
			(xy 119.731229 -262.921938) (xy 119.781908 -262.929249) (xy 119.831019 -262.943732) (xy 119.854472 -262.954008)
			(xy 119.867513 -262.959464) (xy 119.89543 -262.963811) (xy 119.923468 -262.960326) (xy 119.949472 -262.949279)
			(xy 119.971444 -262.931516) (xy 119.979948 -262.920226) (xy 119.996783 -262.897377) (xy 120.036466 -262.856805)
			(xy 120.082081 -262.823041) (xy 120.132474 -262.79694) (xy 120.186369 -262.779162) (xy 120.242402 -262.770157)
			(xy 120.270778 -262.769604) (xy 120.297431 -262.770052) (xy 120.350142 -262.777994) (xy 120.401081 -262.793703)
			(xy 120.449109 -262.81683) (xy 120.493154 -262.846857) (xy 120.532231 -262.883113) (xy 120.544999 -262.899123)
			(xy 121.262384 -262.899123) (xy 121.262384 -262.845825) (xy 121.270327 -262.793121) (xy 121.286037 -262.742191)
			(xy 121.309163 -262.69417) (xy 121.339187 -262.650133) (xy 121.375439 -262.611062) (xy 121.41711 -262.577831)
			(xy 121.463268 -262.551182) (xy 121.512882 -262.53171) (xy 121.564844 -262.51985) (xy 121.617994 -262.515867)
			(xy 121.671144 -262.51985) (xy 121.723106 -262.53171) (xy 121.77272 -262.551182) (xy 121.818878 -262.577831)
			(xy 121.860549 -262.611062) (xy 121.896801 -262.650133) (xy 121.926825 -262.69417) (xy 121.949951 -262.742191)
			(xy 121.965661 -262.793121) (xy 121.973604 -262.845825) (xy 121.974102 -262.872474) (xy 121.973604 -262.899123)
			(xy 121.965661 -262.951827) (xy 121.949951 -263.002757) (xy 121.926825 -263.050778) (xy 121.896801 -263.094815)
			(xy 121.860549 -263.133886) (xy 121.818878 -263.167117) (xy 121.77272 -263.193766) (xy 121.723106 -263.213238)
			(xy 121.671144 -263.225098) (xy 121.617994 -263.229082) (xy 121.564844 -263.225098) (xy 121.512882 -263.213238)
			(xy 121.463268 -263.193766) (xy 121.41711 -263.167117) (xy 121.375439 -263.133886) (xy 121.339187 -263.094815)
			(xy 121.309163 -263.050778) (xy 121.286037 -263.002757) (xy 121.270327 -262.951827) (xy 121.262384 -262.899123)
			(xy 120.544999 -262.899123) (xy 120.565468 -262.924788) (xy 120.592122 -262.970952) (xy 120.611598 -263.020573)
			(xy 120.62346 -263.072543) (xy 120.627444 -263.1257) (xy 120.62346 -263.178857) (xy 120.611598 -263.230827)
			(xy 120.592122 -263.280448) (xy 120.565468 -263.326612) (xy 120.532231 -263.368287) (xy 120.493154 -263.404543)
			(xy 120.449109 -263.43457) (xy 120.401081 -263.457697) (xy 120.350142 -263.473406) (xy 120.297431 -263.481348)
			(xy 120.270778 -263.48182) (xy 120.245176 -263.481383) (xy 120.194498 -263.474071) (xy 120.145386 -263.459586)
			(xy 120.121934 -263.449308) (xy 120.108893 -263.443852) (xy 120.080975 -263.439503) (xy 120.052937 -263.442987)
			(xy 120.026932 -263.454035) (xy 120.004961 -263.471799) (xy 119.996458 -263.48309) (xy 119.979625 -263.50594)
			(xy 119.939941 -263.546511) (xy 119.894325 -263.580274) (xy 119.843932 -263.606375) (xy 119.790037 -263.624153)
			(xy 119.734004 -263.633159) (xy 119.705628 -263.633712) (xy 119.678976 -263.633233) (xy 119.626266 -263.625292)
			(xy 119.575329 -263.609583) (xy 119.527302 -263.586458) (xy 119.483259 -263.556433) (xy 119.444182 -263.520178)
			(xy 119.410946 -263.478505) (xy 119.384293 -263.432342) (xy 119.364818 -263.382723) (xy 119.352956 -263.330755)
			(xy 119.348972 -263.2776) (xy 119.057108 -263.2776) (xy 119.065153 -263.312845) (xy 119.069136 -263.366)
			(xy 119.065153 -263.419155) (xy 119.053291 -263.471122) (xy 119.033816 -263.520742) (xy 119.007164 -263.566904)
			(xy 118.973929 -263.608578) (xy 118.934854 -263.644834) (xy 118.890811 -263.67486) (xy 118.842785 -263.697986)
			(xy 118.793483 -263.713193) (xy 121.732538 -263.713193) (xy 121.732538 -263.659895) (xy 121.740481 -263.607191)
			(xy 121.756191 -263.556261) (xy 121.779317 -263.50824) (xy 121.809341 -263.464203) (xy 121.845593 -263.425132)
			(xy 121.887264 -263.391901) (xy 121.933422 -263.365252) (xy 121.983036 -263.34578) (xy 122.034998 -263.33392)
			(xy 122.088148 -263.329937) (xy 122.141298 -263.33392) (xy 122.19326 -263.34578) (xy 122.242874 -263.365252)
			(xy 122.289032 -263.391901) (xy 122.330703 -263.425132) (xy 122.366955 -263.464203) (xy 122.396979 -263.50824)
			(xy 122.420105 -263.556261) (xy 122.435815 -263.607191) (xy 122.443758 -263.659895) (xy 122.444256 -263.686544)
			(xy 122.443758 -263.713193) (xy 122.435815 -263.765897) (xy 122.420105 -263.816827) (xy 122.396979 -263.864848)
			(xy 122.366955 -263.908885) (xy 122.330703 -263.947956) (xy 122.289032 -263.981187) (xy 122.242874 -264.007836)
			(xy 122.19326 -264.027308) (xy 122.141298 -264.039168) (xy 122.088148 -264.043152) (xy 122.034998 -264.039168)
			(xy 121.983036 -264.027308) (xy 121.933422 -264.007836) (xy 121.887264 -263.981187) (xy 121.845593 -263.947956)
			(xy 121.809341 -263.908885) (xy 121.779317 -263.864848) (xy 121.756191 -263.816827) (xy 121.740481 -263.765897)
			(xy 121.732538 -263.713193) (xy 118.793483 -263.713193) (xy 118.791849 -263.713697) (xy 118.73914 -263.72164)
			(xy 118.712488 -263.722104) (xy 118.696458 -263.721906) (xy 118.664532 -263.718981) (xy 118.648734 -263.716262)
			(xy 118.634033 -263.714129) (xy 118.60453 -263.717484) (xy 118.57724 -263.729185) (xy 118.554469 -263.748241)
			(xy 118.538142 -263.773042) (xy 118.529639 -263.801491) (xy 118.5291 -263.816338) (xy 118.5291 -264.074656)
			(xy 118.529558 -264.088818) (xy 118.537326 -264.116056) (xy 118.552276 -264.140112) (xy 118.573259 -264.159137)
			(xy 118.59866 -264.171666) (xy 118.626526 -264.176737) (xy 118.654713 -264.173959) (xy 118.668038 -264.169144)
			(xy 118.688896 -264.161279) (xy 118.732079 -264.150211) (xy 118.776305 -264.144621) (xy 118.798594 -264.144252)
			(xy 118.825248 -264.144725) (xy 118.877962 -264.152669) (xy 118.928903 -264.168382) (xy 118.976933 -264.191511)
			(xy 119.020979 -264.22154) (xy 119.060057 -264.257799) (xy 119.093295 -264.299478) (xy 119.11995 -264.345644)
			(xy 119.139426 -264.395268) (xy 119.151288 -264.44724) (xy 119.155272 -264.5004) (xy 119.153278 -264.527009)
			(xy 119.382784 -264.527009) (xy 119.382784 -264.473711) (xy 119.390727 -264.421007) (xy 119.406437 -264.370077)
			(xy 119.429563 -264.322056) (xy 119.459587 -264.278019) (xy 119.495839 -264.238948) (xy 119.53751 -264.205717)
			(xy 119.583668 -264.179068) (xy 119.633282 -264.159596) (xy 119.685244 -264.147736) (xy 119.738394 -264.143753)
			(xy 119.791544 -264.147736) (xy 119.843506 -264.159596) (xy 119.89312 -264.179068) (xy 119.939278 -264.205717)
			(xy 119.980949 -264.238948) (xy 120.017201 -264.278019) (xy 120.047225 -264.322056) (xy 120.070351 -264.370077)
			(xy 120.086061 -264.421007) (xy 120.094004 -264.473711) (xy 120.094502 -264.50036) (xy 120.094004 -264.527009)
			(xy 120.322584 -264.527009) (xy 120.322584 -264.473711) (xy 120.330527 -264.421007) (xy 120.346237 -264.370077)
			(xy 120.369363 -264.322056) (xy 120.399387 -264.278019) (xy 120.435639 -264.238948) (xy 120.47731 -264.205717)
			(xy 120.523468 -264.179068) (xy 120.573082 -264.159596) (xy 120.625044 -264.147736) (xy 120.678194 -264.143753)
			(xy 120.731344 -264.147736) (xy 120.783306 -264.159596) (xy 120.83292 -264.179068) (xy 120.879078 -264.205717)
			(xy 120.920749 -264.238948) (xy 120.957001 -264.278019) (xy 120.987025 -264.322056) (xy 121.010151 -264.370077)
			(xy 121.025861 -264.421007) (xy 121.033804 -264.473711) (xy 121.034302 -264.50036) (xy 121.033804 -264.527009)
			(xy 121.262384 -264.527009) (xy 121.262384 -264.473711) (xy 121.270327 -264.421007) (xy 121.286037 -264.370077)
			(xy 121.309163 -264.322056) (xy 121.339187 -264.278019) (xy 121.375439 -264.238948) (xy 121.41711 -264.205717)
			(xy 121.463268 -264.179068) (xy 121.512882 -264.159596) (xy 121.564844 -264.147736) (xy 121.617994 -264.143753)
			(xy 121.671144 -264.147736) (xy 121.723106 -264.159596) (xy 121.77272 -264.179068) (xy 121.818878 -264.205717)
			(xy 121.860549 -264.238948) (xy 121.896801 -264.278019) (xy 121.926825 -264.322056) (xy 121.949951 -264.370077)
			(xy 121.965661 -264.421007) (xy 121.973604 -264.473711) (xy 121.974102 -264.50036) (xy 121.973604 -264.527009)
			(xy 121.965661 -264.579713) (xy 121.949951 -264.630643) (xy 121.926825 -264.678664) (xy 121.896801 -264.722701)
			(xy 121.860549 -264.761772) (xy 121.818878 -264.795003) (xy 121.77272 -264.821652) (xy 121.723106 -264.841124)
			(xy 121.671144 -264.852984) (xy 121.617994 -264.856968) (xy 121.564844 -264.852984) (xy 121.512882 -264.841124)
			(xy 121.463268 -264.821652) (xy 121.41711 -264.795003) (xy 121.375439 -264.761772) (xy 121.339187 -264.722701)
			(xy 121.309163 -264.678664) (xy 121.286037 -264.630643) (xy 121.270327 -264.579713) (xy 121.262384 -264.527009)
			(xy 121.033804 -264.527009) (xy 121.025861 -264.579713) (xy 121.010151 -264.630643) (xy 120.987025 -264.678664)
			(xy 120.957001 -264.722701) (xy 120.920749 -264.761772) (xy 120.879078 -264.795003) (xy 120.83292 -264.821652)
			(xy 120.783306 -264.841124) (xy 120.731344 -264.852984) (xy 120.678194 -264.856968) (xy 120.625044 -264.852984)
			(xy 120.573082 -264.841124) (xy 120.523468 -264.821652) (xy 120.47731 -264.795003) (xy 120.435639 -264.761772)
			(xy 120.399387 -264.722701) (xy 120.369363 -264.678664) (xy 120.346237 -264.630643) (xy 120.330527 -264.579713)
			(xy 120.322584 -264.527009) (xy 120.094004 -264.527009) (xy 120.086061 -264.579713) (xy 120.070351 -264.630643)
			(xy 120.047225 -264.678664) (xy 120.017201 -264.722701) (xy 119.980949 -264.761772) (xy 119.939278 -264.795003)
			(xy 119.89312 -264.821652) (xy 119.843506 -264.841124) (xy 119.791544 -264.852984) (xy 119.738394 -264.856968)
			(xy 119.685244 -264.852984) (xy 119.633282 -264.841124) (xy 119.583668 -264.821652) (xy 119.53751 -264.795003)
			(xy 119.495839 -264.761772) (xy 119.459587 -264.722701) (xy 119.429563 -264.678664) (xy 119.406437 -264.630643)
			(xy 119.390727 -264.579713) (xy 119.382784 -264.527009) (xy 119.153278 -264.527009) (xy 119.151288 -264.55356)
			(xy 119.139426 -264.605532) (xy 119.11995 -264.655156) (xy 119.093295 -264.701322) (xy 119.060057 -264.743001)
			(xy 119.020979 -264.77926) (xy 118.976933 -264.809289) (xy 118.928903 -264.832418) (xy 118.877962 -264.848131)
			(xy 118.825248 -264.856075) (xy 118.798594 -264.856468) (xy 118.776306 -264.856103) (xy 118.732081 -264.850503)
			(xy 118.688902 -264.839427) (xy 118.668038 -264.831576) (xy 118.6547 -264.826805) (xy 118.626519 -264.824032)
			(xy 118.59866 -264.829101) (xy 118.573263 -264.841623) (xy 118.552279 -264.860636) (xy 118.53732 -264.88468)
			(xy 118.529537 -264.911906) (xy 118.5291 -264.926064) (xy 118.5291 -265.01979) (xy 118.550883 -265.035191)
			(xy 118.590012 -265.071451) (xy 118.623295 -265.113142) (xy 118.649988 -265.15933) (xy 118.669494 -265.208983)
			(xy 118.681375 -265.260989) (xy 118.685366 -265.314186) (xy 118.68337 -265.340825) (xy 118.913138 -265.340825)
			(xy 118.913138 -265.287527) (xy 118.921081 -265.234823) (xy 118.936791 -265.183893) (xy 118.959917 -265.135872)
			(xy 118.989941 -265.091835) (xy 119.026193 -265.052764) (xy 119.067864 -265.019533) (xy 119.114022 -264.992884)
			(xy 119.163636 -264.973412) (xy 119.215598 -264.961552) (xy 119.268748 -264.957569) (xy 119.321898 -264.961552)
			(xy 119.37386 -264.973412) (xy 119.423474 -264.992884) (xy 119.469632 -265.019533) (xy 119.511303 -265.052764)
			(xy 119.547555 -265.091835) (xy 119.577579 -265.135872) (xy 119.600705 -265.183893) (xy 119.616415 -265.234823)
			(xy 119.624358 -265.287527) (xy 119.624856 -265.314176) (xy 119.624358 -265.340825) (xy 119.852938 -265.340825)
			(xy 119.852938 -265.287527) (xy 119.860881 -265.234823) (xy 119.876591 -265.183893) (xy 119.899717 -265.135872)
			(xy 119.929741 -265.091835) (xy 119.965993 -265.052764) (xy 120.007664 -265.019533) (xy 120.053822 -264.992884)
			(xy 120.103436 -264.973412) (xy 120.155398 -264.961552) (xy 120.208548 -264.957569) (xy 120.261698 -264.961552)
			(xy 120.31366 -264.973412) (xy 120.363274 -264.992884) (xy 120.409432 -265.019533) (xy 120.451103 -265.052764)
			(xy 120.487355 -265.091835) (xy 120.517379 -265.135872) (xy 120.540505 -265.183893) (xy 120.556215 -265.234823)
			(xy 120.564158 -265.287527) (xy 120.564656 -265.314176) (xy 120.564158 -265.340825) (xy 121.732538 -265.340825)
			(xy 121.732538 -265.287527) (xy 121.740481 -265.234823) (xy 121.756191 -265.183893) (xy 121.779317 -265.135872)
			(xy 121.809341 -265.091835) (xy 121.845593 -265.052764) (xy 121.887264 -265.019533) (xy 121.933422 -264.992884)
			(xy 121.983036 -264.973412) (xy 122.034998 -264.961552) (xy 122.088148 -264.957569) (xy 122.141298 -264.961552)
			(xy 122.19326 -264.973412) (xy 122.242874 -264.992884) (xy 122.289032 -265.019533) (xy 122.330703 -265.052764)
			(xy 122.366955 -265.091835) (xy 122.396979 -265.135872) (xy 122.420105 -265.183893) (xy 122.435815 -265.234823)
			(xy 122.443758 -265.287527) (xy 122.444256 -265.314176) (xy 122.443758 -265.340825) (xy 122.435815 -265.393529)
			(xy 122.420105 -265.444459) (xy 122.396979 -265.49248) (xy 122.366955 -265.536517) (xy 122.330703 -265.575588)
			(xy 122.289032 -265.608819) (xy 122.242874 -265.635468) (xy 122.19326 -265.65494) (xy 122.141298 -265.6668)
			(xy 122.088148 -265.670784) (xy 122.034998 -265.6668) (xy 121.983036 -265.65494) (xy 121.933422 -265.635468)
			(xy 121.887264 -265.608819) (xy 121.845593 -265.575588) (xy 121.809341 -265.536517) (xy 121.779317 -265.49248)
			(xy 121.756191 -265.444459) (xy 121.740481 -265.393529) (xy 121.732538 -265.340825) (xy 120.564158 -265.340825)
			(xy 120.556215 -265.393529) (xy 120.540505 -265.444459) (xy 120.517379 -265.49248) (xy 120.487355 -265.536517)
			(xy 120.451103 -265.575588) (xy 120.409432 -265.608819) (xy 120.363274 -265.635468) (xy 120.31366 -265.65494)
			(xy 120.261698 -265.6668) (xy 120.208548 -265.670784) (xy 120.155398 -265.6668) (xy 120.103436 -265.65494)
			(xy 120.053822 -265.635468) (xy 120.007664 -265.608819) (xy 119.965993 -265.575588) (xy 119.929741 -265.536517)
			(xy 119.899717 -265.49248) (xy 119.876591 -265.444459) (xy 119.860881 -265.393529) (xy 119.852938 -265.340825)
			(xy 119.624358 -265.340825) (xy 119.616415 -265.393529) (xy 119.600705 -265.444459) (xy 119.577579 -265.49248)
			(xy 119.547555 -265.536517) (xy 119.511303 -265.575588) (xy 119.469632 -265.608819) (xy 119.423474 -265.635468)
			(xy 119.37386 -265.65494) (xy 119.321898 -265.6668) (xy 119.268748 -265.670784) (xy 119.215598 -265.6668)
			(xy 119.163636 -265.65494) (xy 119.114022 -265.635468) (xy 119.067864 -265.608819) (xy 119.026193 -265.575588)
			(xy 118.989941 -265.536517) (xy 118.959917 -265.49248) (xy 118.936791 -265.444459) (xy 118.921081 -265.393529)
			(xy 118.913138 -265.340825) (xy 118.68337 -265.340825) (xy 118.681379 -265.367384) (xy 118.669502 -265.419392)
			(xy 118.65 -265.469046) (xy 118.623311 -265.515236) (xy 118.59003 -265.556929) (xy 118.550904 -265.593192)
			(xy 118.5291 -265.608562) (xy 118.5291 -265.702796) (xy 118.529563 -265.716954) (xy 118.537337 -265.744181)
			(xy 118.552289 -265.768228) (xy 118.57327 -265.787244) (xy 118.598665 -265.799768) (xy 118.626523 -265.804837)
			(xy 118.654703 -265.802062) (xy 118.668038 -265.797284) (xy 118.688896 -265.789419) (xy 118.732079 -265.778349)
			(xy 118.776305 -265.772758) (xy 118.798594 -265.772392) (xy 118.825245 -265.772865) (xy 118.877953 -265.780808)
			(xy 118.928888 -265.796519) (xy 118.976913 -265.819646) (xy 119.020954 -265.849672) (xy 119.060028 -265.885927)
			(xy 119.093262 -265.9276) (xy 119.119914 -265.973762) (xy 119.139388 -266.02338) (xy 119.151249 -266.075346)
			(xy 119.155232 -266.1285) (xy 119.153254 -266.154895) (xy 119.382784 -266.154895) (xy 119.382784 -266.101597)
			(xy 119.390727 -266.048893) (xy 119.406437 -265.997963) (xy 119.429563 -265.949942) (xy 119.459587 -265.905905)
			(xy 119.495839 -265.866834) (xy 119.53751 -265.833603) (xy 119.583668 -265.806954) (xy 119.633282 -265.787482)
			(xy 119.685244 -265.775622) (xy 119.738394 -265.771639) (xy 119.791544 -265.775622) (xy 119.843506 -265.787482)
			(xy 119.89312 -265.806954) (xy 119.939278 -265.833603) (xy 119.980949 -265.866834) (xy 120.017201 -265.905905)
			(xy 120.047225 -265.949942) (xy 120.070351 -265.997963) (xy 120.086061 -266.048893) (xy 120.094004 -266.101597)
			(xy 120.094502 -266.128246) (xy 120.094004 -266.154895) (xy 120.322584 -266.154895) (xy 120.322584 -266.101597)
			(xy 120.330527 -266.048893) (xy 120.346237 -265.997963) (xy 120.369363 -265.949942) (xy 120.399387 -265.905905)
			(xy 120.435639 -265.866834) (xy 120.47731 -265.833603) (xy 120.523468 -265.806954) (xy 120.573082 -265.787482)
			(xy 120.625044 -265.775622) (xy 120.678194 -265.771639) (xy 120.731344 -265.775622) (xy 120.783306 -265.787482)
			(xy 120.83292 -265.806954) (xy 120.879078 -265.833603) (xy 120.920749 -265.866834) (xy 120.957001 -265.905905)
			(xy 120.987025 -265.949942) (xy 121.010151 -265.997963) (xy 121.025861 -266.048893) (xy 121.033804 -266.101597)
			(xy 121.034302 -266.128246) (xy 121.033804 -266.154895) (xy 121.025861 -266.207599) (xy 121.010151 -266.258529)
			(xy 120.987025 -266.30655) (xy 120.957001 -266.350587) (xy 120.920749 -266.389658) (xy 120.879078 -266.422889)
			(xy 120.83292 -266.449538) (xy 120.783306 -266.46901) (xy 120.731344 -266.48087) (xy 120.678194 -266.484854)
			(xy 120.625044 -266.48087) (xy 120.573082 -266.46901) (xy 120.523468 -266.449538) (xy 120.47731 -266.422889)
			(xy 120.435639 -266.389658) (xy 120.399387 -266.350587) (xy 120.369363 -266.30655) (xy 120.346237 -266.258529)
			(xy 120.330527 -266.207599) (xy 120.322584 -266.154895) (xy 120.094004 -266.154895) (xy 120.086061 -266.207599)
			(xy 120.070351 -266.258529) (xy 120.047225 -266.30655) (xy 120.017201 -266.350587) (xy 119.980949 -266.389658)
			(xy 119.939278 -266.422889) (xy 119.89312 -266.449538) (xy 119.843506 -266.46901) (xy 119.791544 -266.48087)
			(xy 119.738394 -266.484854) (xy 119.685244 -266.48087) (xy 119.633282 -266.46901) (xy 119.583668 -266.449538)
			(xy 119.53751 -266.422889) (xy 119.495839 -266.389658) (xy 119.459587 -266.350587) (xy 119.429563 -266.30655)
			(xy 119.406437 -266.258529) (xy 119.390727 -266.207599) (xy 119.382784 -266.154895) (xy 119.153254 -266.154895)
			(xy 119.151249 -266.181654) (xy 119.139388 -266.23362) (xy 119.119914 -266.283238) (xy 119.093262 -266.3294)
			(xy 119.060028 -266.371073) (xy 119.020954 -266.407328) (xy 118.976913 -266.437354) (xy 118.928888 -266.460481)
			(xy 118.877953 -266.476192) (xy 118.825245 -266.484135) (xy 118.798594 -266.484608) (xy 118.776305 -266.484244)
			(xy 118.732081 -266.478643) (xy 118.688901 -266.467569) (xy 118.668038 -266.459716) (xy 118.654701 -266.454944)
			(xy 118.626524 -266.452169) (xy 118.598667 -266.457238) (xy 118.573273 -266.469761) (xy 118.552294 -266.488776)
			(xy 118.537343 -266.512821) (xy 118.529569 -266.540047) (xy 118.5291 -266.554204) (xy 118.5291 -266.647676)
			(xy 118.550822 -266.6631) (xy 118.589861 -266.699348) (xy 118.623065 -266.741008) (xy 118.649691 -266.787149)
			(xy 118.669146 -266.836742) (xy 118.680995 -266.888681) (xy 118.684974 -266.941805) (xy 118.682977 -266.968457)
			(xy 121.732538 -266.968457) (xy 121.732538 -266.915159) (xy 121.740481 -266.862455) (xy 121.756191 -266.811525)
			(xy 121.779317 -266.763504) (xy 121.809341 -266.719467) (xy 121.845593 -266.680396) (xy 121.887264 -266.647165)
			(xy 121.933422 -266.620516) (xy 121.983036 -266.601044) (xy 122.034998 -266.589184) (xy 122.088148 -266.585201)
			(xy 122.141298 -266.589184) (xy 122.19326 -266.601044) (xy 122.242874 -266.620516) (xy 122.289032 -266.647165)
			(xy 122.330703 -266.680396) (xy 122.366955 -266.719467) (xy 122.396979 -266.763504) (xy 122.420105 -266.811525)
			(xy 122.435815 -266.862455) (xy 122.443758 -266.915159) (xy 122.444256 -266.941808) (xy 122.443758 -266.968457)
			(xy 122.435815 -267.021161) (xy 122.420105 -267.072091) (xy 122.396979 -267.120112) (xy 122.366955 -267.164149)
			(xy 122.330703 -267.20322) (xy 122.289032 -267.236451) (xy 122.242874 -267.2631) (xy 122.19326 -267.282572)
			(xy 122.141298 -267.294432) (xy 122.088148 -267.298416) (xy 122.034998 -267.294432) (xy 121.983036 -267.282572)
			(xy 121.933422 -267.2631) (xy 121.887264 -267.236451) (xy 121.845593 -267.20322) (xy 121.809341 -267.164149)
			(xy 121.779317 -267.120112) (xy 121.756191 -267.072091) (xy 121.740481 -267.021161) (xy 121.732538 -266.968457)
			(xy 118.682977 -266.968457) (xy 118.680994 -266.994928) (xy 118.669143 -267.046866) (xy 118.649687 -267.096459)
			(xy 118.62306 -267.1426) (xy 118.589855 -267.184259) (xy 118.550815 -267.220505) (xy 118.5291 -267.23594)
			(xy 118.5291 -267.782527) (xy 119.382784 -267.782527) (xy 119.382784 -267.729229) (xy 119.390727 -267.676525)
			(xy 119.406437 -267.625595) (xy 119.429563 -267.577574) (xy 119.459587 -267.533537) (xy 119.495839 -267.494466)
			(xy 119.53751 -267.461235) (xy 119.583668 -267.434586) (xy 119.633282 -267.415114) (xy 119.685244 -267.403254)
			(xy 119.738394 -267.399271) (xy 119.791544 -267.403254) (xy 119.843506 -267.415114) (xy 119.89312 -267.434586)
			(xy 119.939278 -267.461235) (xy 119.980949 -267.494466) (xy 120.017201 -267.533537) (xy 120.047225 -267.577574)
			(xy 120.070351 -267.625595) (xy 120.086061 -267.676525) (xy 120.094004 -267.729229) (xy 120.094502 -267.755878)
			(xy 120.094004 -267.782527) (xy 120.086061 -267.835231) (xy 120.070351 -267.886161) (xy 120.047225 -267.934182)
			(xy 120.017201 -267.978219) (xy 119.980949 -268.01729) (xy 119.939278 -268.050521) (xy 119.89312 -268.07717)
			(xy 119.843506 -268.096642) (xy 119.791544 -268.108502) (xy 119.738394 -268.112486) (xy 119.685244 -268.108502)
			(xy 119.633282 -268.096642) (xy 119.583668 -268.07717) (xy 119.53751 -268.050521) (xy 119.495839 -268.01729)
			(xy 119.459587 -267.978219) (xy 119.429563 -267.934182) (xy 119.406437 -267.886161) (xy 119.390727 -267.835231)
			(xy 119.382784 -267.782527) (xy 118.5291 -267.782527) (xy 118.5291 -268.275054) (xy 118.550909 -268.290462)
			(xy 118.590087 -268.326745) (xy 118.623413 -268.368467) (xy 118.65014 -268.414694) (xy 118.66967 -268.464393)
			(xy 118.681567 -268.516448) (xy 118.685562 -268.569697) (xy 118.681568 -268.622945) (xy 118.669672 -268.675001)
			(xy 118.650143 -268.724699) (xy 118.623417 -268.770928) (xy 118.590092 -268.81265) (xy 118.550914 -268.848933)
			(xy 118.5291 -268.864334) (xy 118.5291 -269.410159) (xy 120.322584 -269.410159) (xy 120.322584 -269.356861)
			(xy 120.330527 -269.304157) (xy 120.346237 -269.253227) (xy 120.369363 -269.205206) (xy 120.399387 -269.161169)
			(xy 120.435639 -269.122098) (xy 120.47731 -269.088867) (xy 120.523468 -269.062218) (xy 120.573082 -269.042746)
			(xy 120.625044 -269.030886) (xy 120.678194 -269.026903) (xy 120.731344 -269.030886) (xy 120.783306 -269.042746)
			(xy 120.83292 -269.062218) (xy 120.879078 -269.088867) (xy 120.920749 -269.122098) (xy 120.957001 -269.161169)
			(xy 120.987025 -269.205206) (xy 121.010151 -269.253227) (xy 121.025861 -269.304157) (xy 121.033804 -269.356861)
			(xy 121.034302 -269.38351) (xy 121.033804 -269.410159) (xy 121.025861 -269.462863) (xy 121.010151 -269.513793)
			(xy 120.987025 -269.561814) (xy 120.957001 -269.605851) (xy 120.920749 -269.644922) (xy 120.879078 -269.678153)
			(xy 120.83292 -269.704802) (xy 120.783306 -269.724274) (xy 120.731344 -269.736134) (xy 120.678194 -269.740118)
			(xy 120.625044 -269.736134) (xy 120.573082 -269.724274) (xy 120.523468 -269.704802) (xy 120.47731 -269.678153)
			(xy 120.435639 -269.644922) (xy 120.399387 -269.605851) (xy 120.369363 -269.561814) (xy 120.346237 -269.513793)
			(xy 120.330527 -269.462863) (xy 120.322584 -269.410159) (xy 118.5291 -269.410159) (xy 118.5291 -269.90294)
			(xy 118.552702 -269.919675) (xy 118.594656 -269.959511) (xy 118.629627 -270.0056) (xy 118.656696 -270.05673)
			(xy 118.675154 -270.111561) (xy 118.684516 -270.168653) (xy 118.685056 -270.19758) (xy 118.684568 -270.225079)
			(xy 118.676156 -270.279429) (xy 118.668292 -270.305784) (xy 118.658894 -270.335502) (xy 119.2403 -270.916908)
			(xy 119.250869 -270.926715) (xy 119.276164 -270.940523) (xy 119.304308 -270.946721) (xy 119.333064 -270.944817)
			(xy 119.360145 -270.934962) (xy 119.383399 -270.917939) (xy 119.400977 -270.895101) (xy 119.40667 -270.881856)
			(xy 119.416822 -270.857168) (xy 119.443443 -270.8109) (xy 119.476672 -270.769123) (xy 119.515763 -270.732773)
			(xy 119.559842 -270.702666) (xy 119.607921 -270.679474) (xy 119.658922 -270.663717) (xy 119.711704 -270.65575)
			(xy 119.738394 -270.655288) (xy 119.766362 -270.655827) (xy 119.821612 -270.664554) (xy 119.87482 -270.681809)
			(xy 119.924676 -270.707168) (xy 119.969956 -270.740009) (xy 120.009547 -270.779523) (xy 120.042474 -270.82474)
			(xy 120.067929 -270.874548) (xy 120.085286 -270.927722) (xy 120.090184 -270.955262) (xy 120.096788 -270.998188)
			(xy 120.3198 -270.998188)
		)
		(stroke
			(width 0)
			(type solid)
		)
		(fill yes)
		(layer "In13.Cu")
		(net "PVCCINFAON_CPU1")
	)
	(gr_poly
		(pts
			(xy 368.266472 -270.955262) (xy 368.271143 -270.929185) (xy 368.28718 -270.878696) (xy 368.310516 -270.831138)
			(xy 368.340637 -270.78756) (xy 368.376878 -270.748922) (xy 368.418441 -270.716076) (xy 368.464409 -270.689747)
			(xy 368.513769 -270.670514) (xy 368.565433 -270.658802) (xy 368.618262 -270.654869) (xy 368.671091 -270.658802)
			(xy 368.722755 -270.670514) (xy 368.772115 -270.689747) (xy 368.818083 -270.716076) (xy 368.859646 -270.748922)
			(xy 368.895887 -270.78756) (xy 368.926008 -270.831138) (xy 368.949344 -270.878696) (xy 368.965381 -270.929185)
			(xy 368.970052 -270.955262) (xy 368.976656 -270.998188) (xy 369.199668 -270.998188) (xy 369.206272 -270.955262)
			(xy 369.211239 -270.927739) (xy 369.228609 -270.874581) (xy 369.254069 -270.824788) (xy 369.286993 -270.779583)
			(xy 369.326573 -270.740074) (xy 369.371838 -270.707232) (xy 369.421676 -270.681862) (xy 369.474866 -270.664588)
			(xy 369.5301 -270.655832) (xy 369.558062 -270.655288) (xy 369.583969 -270.655759) (xy 369.635235 -270.663279)
			(xy 369.684869 -270.678151) (xy 369.731823 -270.700062) (xy 369.775104 -270.728547) (xy 369.8138 -270.763005)
			(xy 369.847091 -270.802709) (xy 369.874275 -270.84682) (xy 369.88496 -270.870426) (xy 369.891015 -270.883265)
			(xy 369.908996 -270.905214) (xy 369.932319 -270.921374) (xy 369.959187 -270.930498) (xy 369.987527 -270.931884)
			(xy 370.015156 -270.925425) (xy 370.039945 -270.911617) (xy 370.050314 -270.901922) (xy 370.632228 -270.320008)
			(xy 370.624608 -270.29156) (xy 370.618697 -270.268515) (xy 370.61233 -270.221367) (xy 370.611908 -270.19758)
			(xy 370.612341 -270.17245) (xy 370.619411 -270.12269) (xy 370.633407 -270.074419) (xy 370.654052 -270.028595)
			(xy 370.680936 -269.986129) (xy 370.713523 -269.947866) (xy 370.751167 -269.914564) (xy 370.771928 -269.9004)
			(xy 370.771928 -269.807436) (xy 370.771457 -269.7932) (xy 370.763601 -269.765833) (xy 370.748489 -269.741701)
			(xy 370.727299 -269.722684) (xy 370.701679 -269.710262) (xy 370.673625 -269.705401) (xy 370.64532 -269.70848)
			(xy 370.631974 -269.713456) (xy 370.610597 -269.72174) (xy 370.566254 -269.733382) (xy 370.520785 -269.739256)
			(xy 370.497862 -269.739618) (xy 370.471214 -269.739118) (xy 370.418513 -269.731169) (xy 370.367586 -269.715455)
			(xy 370.319569 -269.692327) (xy 370.275536 -269.662301) (xy 370.236469 -269.626048) (xy 370.203241 -269.584378)
			(xy 370.176594 -269.538221) (xy 370.157124 -269.488608) (xy 370.145265 -269.436647) (xy 370.141282 -269.3835)
			(xy 370.145265 -269.330353) (xy 370.157124 -269.278392) (xy 370.176594 -269.228779) (xy 370.203241 -269.182622)
			(xy 370.236469 -269.140952) (xy 370.275536 -269.104699) (xy 370.319569 -269.074673) (xy 370.367586 -269.051545)
			(xy 370.418513 -269.035831) (xy 370.471214 -269.027882) (xy 370.497862 -269.027402) (xy 370.520787 -269.02774)
			(xy 370.56626 -269.033601) (xy 370.610599 -269.04527) (xy 370.631974 -269.053564) (xy 370.645325 -269.058492)
			(xy 370.67361 -269.061541) (xy 370.701637 -269.056666) (xy 370.727231 -269.044247) (xy 370.748405 -269.025248)
			(xy 370.763515 -269.001145) (xy 370.771387 -268.973808) (xy 370.771928 -268.959584) (xy 370.771928 -268.867128)
			(xy 370.74958 -268.851805) (xy 370.709365 -268.815493) (xy 370.675114 -268.773508) (xy 370.647618 -268.726819)
			(xy 370.627512 -268.676504) (xy 370.61526 -268.623724) (xy 370.611145 -268.569697) (xy 370.615261 -268.51567)
			(xy 370.627514 -268.46289) (xy 370.647621 -268.412575) (xy 370.675118 -268.365887) (xy 370.709369 -268.323903)
			(xy 370.749586 -268.287591) (xy 370.771928 -268.27226) (xy 370.771928 -267.238988) (xy 370.749607 -267.223671)
			(xy 370.709442 -267.187382) (xy 370.675234 -267.145429) (xy 370.647774 -267.098779) (xy 370.627693 -267.04851)
			(xy 370.615457 -266.99578) (xy 370.611346 -266.941804) (xy 370.615456 -266.887829) (xy 370.627691 -266.835098)
			(xy 370.64777 -266.784829) (xy 370.675229 -266.738179) (xy 370.709435 -266.696225) (xy 370.7496 -266.659934)
			(xy 370.771928 -266.644628) (xy 370.771928 -266.552172) (xy 370.771462 -266.537932) (xy 370.763611 -266.510556)
			(xy 370.748501 -266.486416) (xy 370.727308 -266.467391) (xy 370.701683 -266.454963) (xy 370.673622 -266.450101)
			(xy 370.64531 -266.453182) (xy 370.631974 -266.458192) (xy 370.610597 -266.466477) (xy 370.566254 -266.478122)
			(xy 370.520785 -266.483997) (xy 370.497862 -266.484354) (xy 370.471211 -266.483854) (xy 370.418505 -266.475904)
			(xy 370.367573 -266.460189) (xy 370.319551 -266.437058) (xy 370.275513 -266.407029) (xy 370.236442 -266.370773)
			(xy 370.203211 -266.329098) (xy 370.176562 -266.282936) (xy 370.157089 -266.233319) (xy 370.145229 -266.181353)
			(xy 370.141246 -266.1282) (xy 370.145229 -266.075047) (xy 370.157089 -266.023081) (xy 370.176562 -265.973464)
			(xy 370.203211 -265.927302) (xy 370.236442 -265.885627) (xy 370.275513 -265.849371) (xy 370.319551 -265.819342)
			(xy 370.367573 -265.796211) (xy 370.418505 -265.780496) (xy 370.471211 -265.772546) (xy 370.497862 -265.772138)
			(xy 370.520787 -265.772475) (xy 370.56626 -265.778336) (xy 370.610601 -265.790002) (xy 370.631974 -265.7983)
			(xy 370.645327 -265.803228) (xy 370.673614 -265.806274) (xy 370.701643 -265.801399) (xy 370.727241 -265.788982)
			(xy 370.748419 -265.769984) (xy 370.763535 -265.745882) (xy 370.771416 -265.718545) (xy 370.771928 -265.70432)
			(xy 370.771928 -265.611356) (xy 370.74961 -265.596039) (xy 370.709449 -265.559751) (xy 370.675246 -265.517799)
			(xy 370.64779 -265.471152) (xy 370.627714 -265.420885) (xy 370.615481 -265.368158) (xy 370.611373 -265.314187)
			(xy 370.615485 -265.260216) (xy 370.627722 -265.20749) (xy 370.647801 -265.157224) (xy 370.675261 -265.110579)
			(xy 370.709467 -265.06863) (xy 370.749631 -265.032344) (xy 370.771928 -265.016996) (xy 370.771928 -264.924286)
			(xy 370.771464 -264.910045) (xy 370.763615 -264.882665) (xy 370.748506 -264.858521) (xy 370.727312 -264.839493)
			(xy 370.701685 -264.827064) (xy 370.673621 -264.822201) (xy 370.645306 -264.825283) (xy 370.631974 -264.830306)
			(xy 370.610597 -264.838591) (xy 370.566254 -264.850235) (xy 370.520785 -264.85611) (xy 370.497862 -264.856468)
			(xy 370.471218 -264.855967) (xy 370.418525 -264.84802) (xy 370.367604 -264.832308) (xy 370.319595 -264.809183)
			(xy 370.275567 -264.779162) (xy 370.236506 -264.742914) (xy 370.203282 -264.701249) (xy 370.17664 -264.655099)
			(xy 370.157172 -264.605493) (xy 370.145315 -264.55354) (xy 370.141333 -264.5004) (xy 370.145315 -264.44726)
			(xy 370.157172 -264.395307) (xy 370.17664 -264.345701) (xy 370.203282 -264.299551) (xy 370.236506 -264.257886)
			(xy 370.275567 -264.221638) (xy 370.319595 -264.191617) (xy 370.367604 -264.168492) (xy 370.418525 -264.15278)
			(xy 370.471218 -264.144833) (xy 370.497862 -264.144252) (xy 370.520787 -264.144589) (xy 370.56626 -264.15045)
			(xy 370.6106 -264.162117) (xy 370.631974 -264.170414) (xy 370.645327 -264.175341) (xy 370.673615 -264.178387)
			(xy 370.701646 -264.173512) (xy 370.727244 -264.161095) (xy 370.748424 -264.142098) (xy 370.763543 -264.117996)
			(xy 370.771427 -264.090659) (xy 370.771928 -264.076434) (xy 370.771928 -263.983978) (xy 370.749577 -263.968654)
			(xy 370.709354 -263.932341) (xy 370.675095 -263.890354) (xy 370.647593 -263.843662) (xy 370.627481 -263.793343)
			(xy 370.615223 -263.740557) (xy 370.611103 -263.686524) (xy 370.615216 -263.632491) (xy 370.627466 -263.579704)
			(xy 370.647571 -263.529381) (xy 370.675068 -263.482686) (xy 370.70932 -263.440694) (xy 370.749538 -263.404375)
			(xy 370.771928 -263.38911) (xy 370.771928 -263.296654) (xy 370.771451 -263.282442) (xy 370.763606 -263.255122)
			(xy 370.748537 -263.231021) (xy 370.72741 -263.212006) (xy 370.701862 -263.199548) (xy 370.673869 -263.194612)
			(xy 370.645601 -263.19758) (xy 370.632228 -263.20242) (xy 370.610852 -263.210708) (xy 370.566509 -263.222358)
			(xy 370.52104 -263.228239) (xy 370.498116 -263.228582) (xy 370.470131 -263.228063) (xy 370.414849 -263.219309)
			(xy 370.361617 -263.202014) (xy 370.311746 -263.176604) (xy 370.266465 -263.143705) (xy 370.226888 -263.104127)
			(xy 370.193991 -263.058845) (xy 370.168582 -263.008974) (xy 370.151289 -262.955742) (xy 370.142537 -262.900459)
			(xy 370.142008 -262.872474) (xy 370.142574 -262.84413) (xy 370.151589 -262.788163) (xy 370.169354 -262.73433)
			(xy 370.195422 -262.68399) (xy 370.211858 -262.660892) (xy 370.237766 -262.625586) (xy 370.027454 -262.415274)
			(xy 370.00815 -262.414258) (xy 369.982241 -262.412325) (xy 369.931345 -262.401894) (xy 369.882505 -262.384178)
			(xy 369.836758 -262.359554) (xy 369.795074 -262.328543) (xy 369.758339 -262.291805) (xy 369.727331 -262.250119)
			(xy 369.70271 -262.20437) (xy 369.684998 -262.155528) (xy 369.674571 -262.104632) (xy 369.672616 -262.078724)
			(xy 369.6716 -262.05942) (xy 369.286028 -261.673848) (xy 369.286028 -261.474712) (xy 369.270227 -261.45534)
			(xy 369.243635 -261.413008) (xy 369.22322 -261.367375) (xy 369.20938 -261.319338) (xy 369.202389 -261.269838)
			(xy 369.201954 -261.244842) (xy 369.202556 -261.215703) (xy 369.212081 -261.158208) (xy 369.230834 -261.103029)
			(xy 369.258317 -261.051637) (xy 369.275614 -261.02818) (xy 369.286028 -261.014464) (xy 369.286028 -260.878828)
			(xy 368.960908 -260.553708) (xy 367.571528 -260.553708) (xy 366.469168 -261.656068) (xy 366.469168 -262.927084)
			(xy 366.469707 -262.942052) (xy 366.478396 -262.970699) (xy 366.495006 -262.995605) (xy 366.518114 -263.014637)
			(xy 366.545742 -263.026165) (xy 366.575524 -263.029202) (xy 366.590326 -263.026906) (xy 366.60742 -263.023713)
			(xy 366.642026 -263.020277) (xy 366.659414 -263.020048) (xy 366.686066 -263.020547) (xy 366.738774 -263.028493)
			(xy 366.789709 -263.044206) (xy 366.837734 -263.067335) (xy 366.881775 -263.097364) (xy 366.920849 -263.13362)
			(xy 366.954082 -263.175295) (xy 366.980734 -263.221458) (xy 367.000207 -263.271078) (xy 367.001696 -263.2776)
			(xy 367.289096 -263.2776) (xy 367.293079 -263.224451) (xy 367.304939 -263.17249) (xy 367.324411 -263.122877)
			(xy 367.35106 -263.076719) (xy 367.38429 -263.035049) (xy 367.42336 -262.998798) (xy 367.467396 -262.968774)
			(xy 367.515415 -262.945648) (xy 367.566345 -262.929938) (xy 367.619047 -262.921994) (xy 367.645696 -262.921496)
			(xy 367.671297 -262.921949) (xy 367.721975 -262.929256) (xy 367.771087 -262.943734) (xy 367.79454 -262.954008)
			(xy 367.807554 -262.959535) (xy 367.835484 -262.963868) (xy 367.863531 -262.960367) (xy 367.88954 -262.949302)
			(xy 367.911513 -262.931524) (xy 367.920016 -262.920226) (xy 367.936809 -262.897344) (xy 367.976501 -262.856775)
			(xy 368.022125 -262.823014) (xy 368.072526 -262.796918) (xy 368.126429 -262.779148) (xy 368.182468 -262.770152)
			(xy 368.210846 -262.769604) (xy 368.237494 -262.770081) (xy 368.290194 -262.77803) (xy 368.34112 -262.793745)
			(xy 368.389136 -262.816874) (xy 368.433169 -262.8469) (xy 368.472236 -262.883153) (xy 368.48497 -262.899123)
			(xy 369.202452 -262.899123) (xy 369.202452 -262.845825) (xy 369.210395 -262.793121) (xy 369.226105 -262.742191)
			(xy 369.249231 -262.69417) (xy 369.279255 -262.650133) (xy 369.315507 -262.611062) (xy 369.357178 -262.577831)
			(xy 369.403336 -262.551182) (xy 369.45295 -262.53171) (xy 369.504912 -262.51985) (xy 369.558062 -262.515867)
			(xy 369.611212 -262.51985) (xy 369.663174 -262.53171) (xy 369.712788 -262.551182) (xy 369.758946 -262.577831)
			(xy 369.800617 -262.611062) (xy 369.836869 -262.650133) (xy 369.866893 -262.69417) (xy 369.890019 -262.742191)
			(xy 369.905729 -262.793121) (xy 369.913672 -262.845825) (xy 369.91417 -262.872474) (xy 369.913672 -262.899123)
			(xy 369.905729 -262.951827) (xy 369.890019 -263.002757) (xy 369.866893 -263.050778) (xy 369.836869 -263.094815)
			(xy 369.800617 -263.133886) (xy 369.758946 -263.167117) (xy 369.712788 -263.193766) (xy 369.663174 -263.213238)
			(xy 369.611212 -263.225098) (xy 369.558062 -263.229082) (xy 369.504912 -263.225098) (xy 369.45295 -263.213238)
			(xy 369.403336 -263.193766) (xy 369.357178 -263.167117) (xy 369.315507 -263.133886) (xy 369.279255 -263.094815)
			(xy 369.249231 -263.050778) (xy 369.226105 -263.002757) (xy 369.210395 -262.951827) (xy 369.202452 -262.899123)
			(xy 368.48497 -262.899123) (xy 368.505463 -262.924824) (xy 368.532109 -262.97098) (xy 368.551578 -263.020593)
			(xy 368.563437 -263.072553) (xy 368.56742 -263.1257) (xy 368.563437 -263.178847) (xy 368.551578 -263.230807)
			(xy 368.532109 -263.28042) (xy 368.505463 -263.326576) (xy 368.472236 -263.368247) (xy 368.433169 -263.4045)
			(xy 368.389136 -263.434526) (xy 368.34112 -263.457655) (xy 368.290194 -263.47337) (xy 368.237494 -263.481319)
			(xy 368.210846 -263.48182) (xy 368.185244 -263.481394) (xy 368.134565 -263.474078) (xy 368.085454 -263.459588)
			(xy 368.062002 -263.449308) (xy 368.048974 -263.443819) (xy 368.02105 -263.439477) (xy 367.993007 -263.442968)
			(xy 367.967 -263.454024) (xy 367.945029 -263.471795) (xy 367.936526 -263.48309) (xy 367.919712 -263.505956)
			(xy 367.880024 -263.546525) (xy 367.834405 -263.580287) (xy 367.784007 -263.606385) (xy 367.730109 -263.62416)
			(xy 367.674073 -263.633161) (xy 367.645696 -263.633712) (xy 367.619047 -263.633206) (xy 367.566345 -263.625262)
			(xy 367.515415 -263.609552) (xy 367.467396 -263.586426) (xy 367.42336 -263.556402) (xy 367.38429 -263.520151)
			(xy 367.35106 -263.478481) (xy 367.324411 -263.432323) (xy 367.304939 -263.38271) (xy 367.293079 -263.330749)
			(xy 367.289096 -263.2776) (xy 367.001696 -263.2776) (xy 367.012068 -263.323045) (xy 367.016052 -263.3762)
			(xy 367.012068 -263.429355) (xy 367.000207 -263.481322) (xy 366.980734 -263.530942) (xy 366.954082 -263.577105)
			(xy 366.920849 -263.61878) (xy 366.881775 -263.655036) (xy 366.837734 -263.685065) (xy 366.789709 -263.708194)
			(xy 366.773504 -263.713193) (xy 369.672606 -263.713193) (xy 369.672606 -263.659895) (xy 369.680549 -263.607191)
			(xy 369.696259 -263.556261) (xy 369.719385 -263.50824) (xy 369.749409 -263.464203) (xy 369.785661 -263.425132)
			(xy 369.827332 -263.391901) (xy 369.87349 -263.365252) (xy 369.923104 -263.34578) (xy 369.975066 -263.33392)
			(xy 370.028216 -263.329937) (xy 370.081366 -263.33392) (xy 370.133328 -263.34578) (xy 370.182942 -263.365252)
			(xy 370.2291 -263.391901) (xy 370.270771 -263.425132) (xy 370.307023 -263.464203) (xy 370.337047 -263.50824)
			(xy 370.360173 -263.556261) (xy 370.375883 -263.607191) (xy 370.383826 -263.659895) (xy 370.384324 -263.686544)
			(xy 370.383826 -263.713193) (xy 370.375883 -263.765897) (xy 370.360173 -263.816827) (xy 370.337047 -263.864848)
			(xy 370.307023 -263.908885) (xy 370.270771 -263.947956) (xy 370.2291 -263.981187) (xy 370.182942 -264.007836)
			(xy 370.133328 -264.027308) (xy 370.081366 -264.039168) (xy 370.028216 -264.043152) (xy 369.975066 -264.039168)
			(xy 369.923104 -264.027308) (xy 369.87349 -264.007836) (xy 369.827332 -263.981187) (xy 369.785661 -263.947956)
			(xy 369.749409 -263.908885) (xy 369.719385 -263.864848) (xy 369.696259 -263.816827) (xy 369.680549 -263.765897)
			(xy 369.672606 -263.713193) (xy 366.773504 -263.713193) (xy 366.738774 -263.723907) (xy 366.686066 -263.731853)
			(xy 366.659414 -263.732264) (xy 366.642027 -263.732027) (xy 366.607422 -263.728587) (xy 366.590326 -263.725406)
			(xy 366.575519 -263.723032) (xy 366.545694 -263.726026) (xy 366.518021 -263.737544) (xy 366.494882 -263.756597)
			(xy 366.478266 -263.781545) (xy 366.469605 -263.81024) (xy 366.469168 -263.825228) (xy 366.469168 -264.074656)
			(xy 366.469626 -264.08882) (xy 366.477394 -264.116063) (xy 366.492345 -264.140124) (xy 366.513329 -264.159155)
			(xy 366.538732 -264.171691) (xy 366.566602 -264.176768) (xy 366.594794 -264.173997) (xy 366.608106 -264.169144)
			(xy 366.628964 -264.161278) (xy 366.672146 -264.150206) (xy 366.716373 -264.144611) (xy 366.738662 -264.144252)
			(xy 366.765318 -264.144723) (xy 366.818035 -264.152663) (xy 366.86898 -264.168373) (xy 366.917014 -264.1915)
			(xy 366.961064 -264.221529) (xy 367.000147 -264.257788) (xy 367.033388 -264.299468) (xy 367.060046 -264.345636)
			(xy 367.079524 -264.395262) (xy 367.091388 -264.447237) (xy 367.095372 -264.5004) (xy 367.093378 -264.527009)
			(xy 367.322852 -264.527009) (xy 367.322852 -264.473711) (xy 367.330795 -264.421007) (xy 367.346505 -264.370077)
			(xy 367.369631 -264.322056) (xy 367.399655 -264.278019) (xy 367.435907 -264.238948) (xy 367.477578 -264.205717)
			(xy 367.523736 -264.179068) (xy 367.57335 -264.159596) (xy 367.625312 -264.147736) (xy 367.678462 -264.143753)
			(xy 367.731612 -264.147736) (xy 367.783574 -264.159596) (xy 367.833188 -264.179068) (xy 367.879346 -264.205717)
			(xy 367.921017 -264.238948) (xy 367.957269 -264.278019) (xy 367.987293 -264.322056) (xy 368.010419 -264.370077)
			(xy 368.026129 -264.421007) (xy 368.034072 -264.473711) (xy 368.03457 -264.50036) (xy 368.034072 -264.527009)
			(xy 368.262652 -264.527009) (xy 368.262652 -264.473711) (xy 368.270595 -264.421007) (xy 368.286305 -264.370077)
			(xy 368.309431 -264.322056) (xy 368.339455 -264.278019) (xy 368.375707 -264.238948) (xy 368.417378 -264.205717)
			(xy 368.463536 -264.179068) (xy 368.51315 -264.159596) (xy 368.565112 -264.147736) (xy 368.618262 -264.143753)
			(xy 368.671412 -264.147736) (xy 368.723374 -264.159596) (xy 368.772988 -264.179068) (xy 368.819146 -264.205717)
			(xy 368.860817 -264.238948) (xy 368.897069 -264.278019) (xy 368.927093 -264.322056) (xy 368.950219 -264.370077)
			(xy 368.965929 -264.421007) (xy 368.973872 -264.473711) (xy 368.97437 -264.50036) (xy 368.973872 -264.527009)
			(xy 369.202452 -264.527009) (xy 369.202452 -264.473711) (xy 369.210395 -264.421007) (xy 369.226105 -264.370077)
			(xy 369.249231 -264.322056) (xy 369.279255 -264.278019) (xy 369.315507 -264.238948) (xy 369.357178 -264.205717)
			(xy 369.403336 -264.179068) (xy 369.45295 -264.159596) (xy 369.504912 -264.147736) (xy 369.558062 -264.143753)
			(xy 369.611212 -264.147736) (xy 369.663174 -264.159596) (xy 369.712788 -264.179068) (xy 369.758946 -264.205717)
			(xy 369.800617 -264.238948) (xy 369.836869 -264.278019) (xy 369.866893 -264.322056) (xy 369.890019 -264.370077)
			(xy 369.905729 -264.421007) (xy 369.913672 -264.473711) (xy 369.91417 -264.50036) (xy 369.913672 -264.527009)
			(xy 369.905729 -264.579713) (xy 369.890019 -264.630643) (xy 369.866893 -264.678664) (xy 369.836869 -264.722701)
			(xy 369.800617 -264.761772) (xy 369.758946 -264.795003) (xy 369.712788 -264.821652) (xy 369.663174 -264.841124)
			(xy 369.611212 -264.852984) (xy 369.558062 -264.856968) (xy 369.504912 -264.852984) (xy 369.45295 -264.841124)
			(xy 369.403336 -264.821652) (xy 369.357178 -264.795003) (xy 369.315507 -264.761772) (xy 369.279255 -264.722701)
			(xy 369.249231 -264.678664) (xy 369.226105 -264.630643) (xy 369.210395 -264.579713) (xy 369.202452 -264.527009)
			(xy 368.973872 -264.527009) (xy 368.965929 -264.579713) (xy 368.950219 -264.630643) (xy 368.927093 -264.678664)
			(xy 368.897069 -264.722701) (xy 368.860817 -264.761772) (xy 368.819146 -264.795003) (xy 368.772988 -264.821652)
			(xy 368.723374 -264.841124) (xy 368.671412 -264.852984) (xy 368.618262 -264.856968) (xy 368.565112 -264.852984)
			(xy 368.51315 -264.841124) (xy 368.463536 -264.821652) (xy 368.417378 -264.795003) (xy 368.375707 -264.761772)
			(xy 368.339455 -264.722701) (xy 368.309431 -264.678664) (xy 368.286305 -264.630643) (xy 368.270595 -264.579713)
			(xy 368.262652 -264.527009) (xy 368.034072 -264.527009) (xy 368.026129 -264.579713) (xy 368.010419 -264.630643)
			(xy 367.987293 -264.678664) (xy 367.957269 -264.722701) (xy 367.921017 -264.761772) (xy 367.879346 -264.795003)
			(xy 367.833188 -264.821652) (xy 367.783574 -264.841124) (xy 367.731612 -264.852984) (xy 367.678462 -264.856968)
			(xy 367.625312 -264.852984) (xy 367.57335 -264.841124) (xy 367.523736 -264.821652) (xy 367.477578 -264.795003)
			(xy 367.435907 -264.761772) (xy 367.399655 -264.722701) (xy 367.369631 -264.678664) (xy 367.346505 -264.630643)
			(xy 367.330795 -264.579713) (xy 367.322852 -264.527009) (xy 367.093378 -264.527009) (xy 367.091388 -264.553563)
			(xy 367.079524 -264.605538) (xy 367.060046 -264.655164) (xy 367.033388 -264.701332) (xy 367.000147 -264.743012)
			(xy 366.961064 -264.779271) (xy 366.917014 -264.8093) (xy 366.86898 -264.832427) (xy 366.818035 -264.848137)
			(xy 366.765318 -264.856077) (xy 366.738662 -264.856468) (xy 366.716373 -264.856108) (xy 366.672146 -264.850515)
			(xy 366.628963 -264.839446) (xy 366.608106 -264.831576) (xy 366.59477 -264.82681) (xy 366.566596 -264.824045)
			(xy 366.538745 -264.829118) (xy 366.513357 -264.841641) (xy 366.492381 -264.860652) (xy 366.477428 -264.88469)
			(xy 366.469649 -264.91191) (xy 366.469168 -264.926064) (xy 366.469168 -265.01979) (xy 366.490952 -265.03519)
			(xy 366.530085 -265.071449) (xy 366.563371 -265.113138) (xy 366.590067 -265.159327) (xy 366.609574 -265.20898)
			(xy 366.621456 -265.260988) (xy 366.625448 -265.314186) (xy 366.623451 -265.340825) (xy 366.853206 -265.340825)
			(xy 366.853206 -265.287527) (xy 366.861149 -265.234823) (xy 366.876859 -265.183893) (xy 366.899985 -265.135872)
			(xy 366.930009 -265.091835) (xy 366.966261 -265.052764) (xy 367.007932 -265.019533) (xy 367.05409 -264.992884)
			(xy 367.103704 -264.973412) (xy 367.155666 -264.961552) (xy 367.208816 -264.957569) (xy 367.261966 -264.961552)
			(xy 367.313928 -264.973412) (xy 367.363542 -264.992884) (xy 367.4097 -265.019533) (xy 367.451371 -265.052764)
			(xy 367.487623 -265.091835) (xy 367.517647 -265.135872) (xy 367.540773 -265.183893) (xy 367.556483 -265.234823)
			(xy 367.564426 -265.287527) (xy 367.564924 -265.314176) (xy 367.564426 -265.340825) (xy 367.793006 -265.340825)
			(xy 367.793006 -265.287527) (xy 367.800949 -265.234823) (xy 367.816659 -265.183893) (xy 367.839785 -265.135872)
			(xy 367.869809 -265.091835) (xy 367.906061 -265.052764) (xy 367.947732 -265.019533) (xy 367.99389 -264.992884)
			(xy 368.043504 -264.973412) (xy 368.095466 -264.961552) (xy 368.148616 -264.957569) (xy 368.201766 -264.961552)
			(xy 368.253728 -264.973412) (xy 368.303342 -264.992884) (xy 368.3495 -265.019533) (xy 368.391171 -265.052764)
			(xy 368.427423 -265.091835) (xy 368.457447 -265.135872) (xy 368.480573 -265.183893) (xy 368.496283 -265.234823)
			(xy 368.504226 -265.287527) (xy 368.504724 -265.314176) (xy 368.504226 -265.340825) (xy 369.672606 -265.340825)
			(xy 369.672606 -265.287527) (xy 369.680549 -265.234823) (xy 369.696259 -265.183893) (xy 369.719385 -265.135872)
			(xy 369.749409 -265.091835) (xy 369.785661 -265.052764) (xy 369.827332 -265.019533) (xy 369.87349 -264.992884)
			(xy 369.923104 -264.973412) (xy 369.975066 -264.961552) (xy 370.028216 -264.957569) (xy 370.081366 -264.961552)
			(xy 370.133328 -264.973412) (xy 370.182942 -264.992884) (xy 370.2291 -265.019533) (xy 370.270771 -265.052764)
			(xy 370.307023 -265.091835) (xy 370.337047 -265.135872) (xy 370.360173 -265.183893) (xy 370.375883 -265.234823)
			(xy 370.383826 -265.287527) (xy 370.384324 -265.314176) (xy 370.383826 -265.340825) (xy 370.375883 -265.393529)
			(xy 370.360173 -265.444459) (xy 370.337047 -265.49248) (xy 370.307023 -265.536517) (xy 370.270771 -265.575588)
			(xy 370.2291 -265.608819) (xy 370.182942 -265.635468) (xy 370.133328 -265.65494) (xy 370.081366 -265.6668)
			(xy 370.028216 -265.670784) (xy 369.975066 -265.6668) (xy 369.923104 -265.65494) (xy 369.87349 -265.635468)
			(xy 369.827332 -265.608819) (xy 369.785661 -265.575588) (xy 369.749409 -265.536517) (xy 369.719385 -265.49248)
			(xy 369.696259 -265.444459) (xy 369.680549 -265.393529) (xy 369.672606 -265.340825) (xy 368.504226 -265.340825)
			(xy 368.496283 -265.393529) (xy 368.480573 -265.444459) (xy 368.457447 -265.49248) (xy 368.427423 -265.536517)
			(xy 368.391171 -265.575588) (xy 368.3495 -265.608819) (xy 368.303342 -265.635468) (xy 368.253728 -265.65494)
			(xy 368.201766 -265.6668) (xy 368.148616 -265.670784) (xy 368.095466 -265.6668) (xy 368.043504 -265.65494)
			(xy 367.99389 -265.635468) (xy 367.947732 -265.608819) (xy 367.906061 -265.575588) (xy 367.869809 -265.536517)
			(xy 367.839785 -265.49248) (xy 367.816659 -265.444459) (xy 367.800949 -265.393529) (xy 367.793006 -265.340825)
			(xy 367.564426 -265.340825) (xy 367.556483 -265.393529) (xy 367.540773 -265.444459) (xy 367.517647 -265.49248)
			(xy 367.487623 -265.536517) (xy 367.451371 -265.575588) (xy 367.4097 -265.608819) (xy 367.363542 -265.635468)
			(xy 367.313928 -265.65494) (xy 367.261966 -265.6668) (xy 367.208816 -265.670784) (xy 367.155666 -265.6668)
			(xy 367.103704 -265.65494) (xy 367.05409 -265.635468) (xy 367.007932 -265.608819) (xy 366.966261 -265.575588)
			(xy 366.930009 -265.536517) (xy 366.899985 -265.49248) (xy 366.876859 -265.444459) (xy 366.861149 -265.393529)
			(xy 366.853206 -265.340825) (xy 366.623451 -265.340825) (xy 366.62146 -265.367385) (xy 366.609582 -265.419394)
			(xy 366.590078 -265.469049) (xy 366.563387 -265.515239) (xy 366.530103 -265.556932) (xy 366.490974 -265.593193)
			(xy 366.469168 -265.608562) (xy 366.469168 -265.702796) (xy 366.469631 -265.716956) (xy 366.477406 -265.744189)
			(xy 366.492358 -265.76824) (xy 366.513339 -265.787262) (xy 366.538737 -265.799792) (xy 366.566599 -265.804868)
			(xy 366.594783 -265.802099) (xy 366.608106 -265.797284) (xy 366.628964 -265.789417) (xy 366.672146 -265.778344)
			(xy 366.716373 -265.772748) (xy 366.738662 -265.772392) (xy 366.765315 -265.772863) (xy 366.818026 -265.780802)
			(xy 366.868965 -265.79651) (xy 366.916994 -265.819635) (xy 366.961039 -265.84966) (xy 367.000117 -265.885915)
			(xy 367.033355 -265.92759) (xy 367.06001 -265.973753) (xy 367.079486 -266.023374) (xy 367.091348 -266.075343)
			(xy 367.095332 -266.1285) (xy 367.093354 -266.154895) (xy 367.322852 -266.154895) (xy 367.322852 -266.101597)
			(xy 367.330795 -266.048893) (xy 367.346505 -265.997963) (xy 367.369631 -265.949942) (xy 367.399655 -265.905905)
			(xy 367.435907 -265.866834) (xy 367.477578 -265.833603) (xy 367.523736 -265.806954) (xy 367.57335 -265.787482)
			(xy 367.625312 -265.775622) (xy 367.678462 -265.771639) (xy 367.731612 -265.775622) (xy 367.783574 -265.787482)
			(xy 367.833188 -265.806954) (xy 367.879346 -265.833603) (xy 367.921017 -265.866834) (xy 367.957269 -265.905905)
			(xy 367.987293 -265.949942) (xy 368.010419 -265.997963) (xy 368.026129 -266.048893) (xy 368.034072 -266.101597)
			(xy 368.03457 -266.128246) (xy 368.034072 -266.154895) (xy 368.262652 -266.154895) (xy 368.262652 -266.101597)
			(xy 368.270595 -266.048893) (xy 368.286305 -265.997963) (xy 368.309431 -265.949942) (xy 368.339455 -265.905905)
			(xy 368.375707 -265.866834) (xy 368.417378 -265.833603) (xy 368.463536 -265.806954) (xy 368.51315 -265.787482)
			(xy 368.565112 -265.775622) (xy 368.618262 -265.771639) (xy 368.671412 -265.775622) (xy 368.723374 -265.787482)
			(xy 368.772988 -265.806954) (xy 368.819146 -265.833603) (xy 368.860817 -265.866834) (xy 368.897069 -265.905905)
			(xy 368.927093 -265.949942) (xy 368.950219 -265.997963) (xy 368.965929 -266.048893) (xy 368.973872 -266.101597)
			(xy 368.97437 -266.128246) (xy 368.973872 -266.154895) (xy 368.965929 -266.207599) (xy 368.950219 -266.258529)
			(xy 368.927093 -266.30655) (xy 368.897069 -266.350587) (xy 368.860817 -266.389658) (xy 368.819146 -266.422889)
			(xy 368.772988 -266.449538) (xy 368.723374 -266.46901) (xy 368.671412 -266.48087) (xy 368.618262 -266.484854)
			(xy 368.565112 -266.48087) (xy 368.51315 -266.46901) (xy 368.463536 -266.449538) (xy 368.417378 -266.422889)
			(xy 368.375707 -266.389658) (xy 368.339455 -266.350587) (xy 368.309431 -266.30655) (xy 368.286305 -266.258529)
			(xy 368.270595 -266.207599) (xy 368.262652 -266.154895) (xy 368.034072 -266.154895) (xy 368.026129 -266.207599)
			(xy 368.010419 -266.258529) (xy 367.987293 -266.30655) (xy 367.957269 -266.350587) (xy 367.921017 -266.389658)
			(xy 367.879346 -266.422889) (xy 367.833188 -266.449538) (xy 367.783574 -266.46901) (xy 367.731612 -266.48087)
			(xy 367.678462 -266.484854) (xy 367.625312 -266.48087) (xy 367.57335 -266.46901) (xy 367.523736 -266.449538)
			(xy 367.477578 -266.422889) (xy 367.435907 -266.389658) (xy 367.399655 -266.350587) (xy 367.369631 -266.30655)
			(xy 367.346505 -266.258529) (xy 367.330795 -266.207599) (xy 367.322852 -266.154895) (xy 367.093354 -266.154895)
			(xy 367.091348 -266.181657) (xy 367.079486 -266.233626) (xy 367.06001 -266.283247) (xy 367.033355 -266.32941)
			(xy 367.000117 -266.371085) (xy 366.961039 -266.40734) (xy 366.916994 -266.437365) (xy 366.868965 -266.46049)
			(xy 366.818026 -266.476198) (xy 366.765315 -266.484137) (xy 366.738662 -266.484608) (xy 366.716373 -266.484248)
			(xy 366.672146 -266.478656) (xy 366.628962 -266.467588) (xy 366.608106 -266.459716) (xy 366.594772 -266.454949)
			(xy 366.566601 -266.452182) (xy 366.538752 -266.457255) (xy 366.513367 -266.469779) (xy 366.492396 -266.488792)
			(xy 366.477451 -266.512832) (xy 366.46968 -266.540051) (xy 366.469168 -266.554204) (xy 366.469168 -266.647676)
			(xy 366.490891 -266.663099) (xy 366.529934 -266.699345) (xy 366.563141 -266.741004) (xy 366.58977 -266.787146)
			(xy 366.609226 -266.83674) (xy 366.621077 -266.888679) (xy 366.625056 -266.941805) (xy 366.623059 -266.968457)
			(xy 369.672606 -266.968457) (xy 369.672606 -266.915159) (xy 369.680549 -266.862455) (xy 369.696259 -266.811525)
			(xy 369.719385 -266.763504) (xy 369.749409 -266.719467) (xy 369.785661 -266.680396) (xy 369.827332 -266.647165)
			(xy 369.87349 -266.620516) (xy 369.923104 -266.601044) (xy 369.975066 -266.589184) (xy 370.028216 -266.585201)
			(xy 370.081366 -266.589184) (xy 370.133328 -266.601044) (xy 370.182942 -266.620516) (xy 370.2291 -266.647165)
			(xy 370.270771 -266.680396) (xy 370.307023 -266.719467) (xy 370.337047 -266.763504) (xy 370.360173 -266.811525)
			(xy 370.375883 -266.862455) (xy 370.383826 -266.915159) (xy 370.384324 -266.941808) (xy 370.383826 -266.968457)
			(xy 370.375883 -267.021161) (xy 370.360173 -267.072091) (xy 370.337047 -267.120112) (xy 370.307023 -267.164149)
			(xy 370.270771 -267.20322) (xy 370.2291 -267.236451) (xy 370.182942 -267.2631) (xy 370.133328 -267.282572)
			(xy 370.081366 -267.294432) (xy 370.028216 -267.298416) (xy 369.975066 -267.294432) (xy 369.923104 -267.282572)
			(xy 369.87349 -267.2631) (xy 369.827332 -267.236451) (xy 369.785661 -267.20322) (xy 369.749409 -267.164149)
			(xy 369.719385 -267.120112) (xy 369.696259 -267.072091) (xy 369.680549 -267.021161) (xy 369.672606 -266.968457)
			(xy 366.623059 -266.968457) (xy 366.621075 -266.99493) (xy 366.609224 -267.046869) (xy 366.589766 -267.096462)
			(xy 366.563136 -267.142603) (xy 366.529928 -267.184261) (xy 366.490884 -267.220507) (xy 366.469168 -267.23594)
			(xy 366.469168 -267.782527) (xy 367.322852 -267.782527) (xy 367.322852 -267.729229) (xy 367.330795 -267.676525)
			(xy 367.346505 -267.625595) (xy 367.369631 -267.577574) (xy 367.399655 -267.533537) (xy 367.435907 -267.494466)
			(xy 367.477578 -267.461235) (xy 367.523736 -267.434586) (xy 367.57335 -267.415114) (xy 367.625312 -267.403254)
			(xy 367.678462 -267.399271) (xy 367.731612 -267.403254) (xy 367.783574 -267.415114) (xy 367.833188 -267.434586)
			(xy 367.879346 -267.461235) (xy 367.921017 -267.494466) (xy 367.957269 -267.533537) (xy 367.987293 -267.577574)
			(xy 368.010419 -267.625595) (xy 368.026129 -267.676525) (xy 368.034072 -267.729229) (xy 368.03457 -267.755878)
			(xy 368.034072 -267.782527) (xy 368.026129 -267.835231) (xy 368.010419 -267.886161) (xy 367.987293 -267.934182)
			(xy 367.957269 -267.978219) (xy 367.921017 -268.01729) (xy 367.879346 -268.050521) (xy 367.833188 -268.07717)
			(xy 367.783574 -268.096642) (xy 367.731612 -268.108502) (xy 367.678462 -268.112486) (xy 367.625312 -268.108502)
			(xy 367.57335 -268.096642) (xy 367.523736 -268.07717) (xy 367.477578 -268.050521) (xy 367.435907 -268.01729)
			(xy 367.399655 -267.978219) (xy 367.369631 -267.934182) (xy 367.346505 -267.886161) (xy 367.330795 -267.835231)
			(xy 367.322852 -267.782527) (xy 366.469168 -267.782527) (xy 366.469168 -268.275054) (xy 366.490979 -268.290461)
			(xy 366.53016 -268.326742) (xy 366.563489 -268.368464) (xy 366.590219 -268.414691) (xy 366.609751 -268.46439)
			(xy 366.621648 -268.516447) (xy 366.625644 -268.569697) (xy 366.621649 -268.622946) (xy 366.609753 -268.675003)
			(xy 366.590222 -268.724703) (xy 366.563493 -268.770931) (xy 366.530165 -268.812653) (xy 366.490984 -268.848934)
			(xy 366.469168 -268.864334) (xy 366.469168 -269.410159) (xy 368.262652 -269.410159) (xy 368.262652 -269.356861)
			(xy 368.270595 -269.304157) (xy 368.286305 -269.253227) (xy 368.309431 -269.205206) (xy 368.339455 -269.161169)
			(xy 368.375707 -269.122098) (xy 368.417378 -269.088867) (xy 368.463536 -269.062218) (xy 368.51315 -269.042746)
			(xy 368.565112 -269.030886) (xy 368.618262 -269.026903) (xy 368.671412 -269.030886) (xy 368.723374 -269.042746)
			(xy 368.772988 -269.062218) (xy 368.819146 -269.088867) (xy 368.860817 -269.122098) (xy 368.897069 -269.161169)
			(xy 368.927093 -269.205206) (xy 368.950219 -269.253227) (xy 368.965929 -269.304157) (xy 368.973872 -269.356861)
			(xy 368.97437 -269.38351) (xy 368.973872 -269.410159) (xy 368.965929 -269.462863) (xy 368.950219 -269.513793)
			(xy 368.927093 -269.561814) (xy 368.897069 -269.605851) (xy 368.860817 -269.644922) (xy 368.819146 -269.678153)
			(xy 368.772988 -269.704802) (xy 368.723374 -269.724274) (xy 368.671412 -269.736134) (xy 368.618262 -269.740118)
			(xy 368.565112 -269.736134) (xy 368.51315 -269.724274) (xy 368.463536 -269.704802) (xy 368.417378 -269.678153)
			(xy 368.375707 -269.644922) (xy 368.339455 -269.605851) (xy 368.309431 -269.561814) (xy 368.286305 -269.513793)
			(xy 368.270595 -269.462863) (xy 368.262652 -269.410159) (xy 366.469168 -269.410159) (xy 366.469168 -269.90294)
			(xy 366.492772 -269.919673) (xy 366.534729 -269.959508) (xy 366.569703 -270.005596) (xy 366.596776 -270.056727)
			(xy 366.615235 -270.111559) (xy 366.624598 -270.168652) (xy 366.625124 -270.19758) (xy 366.624636 -270.225079)
			(xy 366.616223 -270.279429) (xy 366.60836 -270.305784) (xy 366.598962 -270.335502) (xy 367.180368 -270.916908)
			(xy 367.190938 -270.92672) (xy 367.216237 -270.940537) (xy 367.244388 -270.946742) (xy 367.273152 -270.944843)
			(xy 367.300242 -270.934989) (xy 367.323505 -270.917965) (xy 367.34109 -270.895123) (xy 367.346738 -270.881856)
			(xy 367.356891 -270.85717) (xy 367.383514 -270.810908) (xy 367.416744 -270.769138) (xy 367.455837 -270.732796)
			(xy 367.499916 -270.702696) (xy 367.547994 -270.679513) (xy 367.598995 -270.663766) (xy 367.651774 -270.655808)
			(xy 367.678462 -270.655288) (xy 367.706427 -270.655832) (xy 367.761669 -270.664567) (xy 367.814868 -270.681829)
			(xy 367.864716 -270.707192) (xy 367.909986 -270.740034) (xy 367.949568 -270.779548) (xy 367.982488 -270.824763)
			(xy 368.007937 -270.874567) (xy 368.02529 -270.927736) (xy 368.030252 -270.955262) (xy 368.036856 -270.998188)
			(xy 368.259868 -270.998188)
		)
		(stroke
			(width 0)
			(type solid)
		)
		(fill yes)
		(layer "In13.Cu")
		(net "PVCCINFAON_CPU0")
	)
	(gr_poly
		(pts
			(xy 432.95824 -402.67636) (xy 432.968603 -402.665215) (xy 432.982844 -402.63834) (xy 432.988537 -402.608462)
			(xy 432.985178 -402.578233) (xy 432.973064 -402.550334) (xy 432.963574 -402.538438) (xy 432.946399 -402.517608)
			(xy 432.917472 -402.472024) (xy 432.895255 -402.42282) (xy 432.880191 -402.370976) (xy 432.872581 -402.317528)
			(xy 432.872134 -402.290534) (xy 432.872595 -402.263281) (xy 432.880348 -402.209328) (xy 432.895702 -402.157029)
			(xy 432.918343 -402.107447) (xy 432.947811 -402.061593) (xy 432.983505 -402.020399) (xy 433.024699 -401.984706)
			(xy 433.070554 -401.955239) (xy 433.120136 -401.932599) (xy 433.172436 -401.917247) (xy 433.226389 -401.909494)
			(xy 433.253642 -401.909026) (xy 433.276802 -401.909354) (xy 433.322785 -401.914929) (xy 433.367759 -401.926017)
			(xy 433.389532 -401.933918) (xy 433.402821 -401.938484) (xy 433.430804 -401.940923) (xy 433.458394 -401.935649)
			(xy 433.483504 -401.92306) (xy 433.504237 -401.904108) (xy 433.519024 -401.880226) (xy 433.526747 -401.853219)
			(xy 433.5272 -401.839176) (xy 433.5272 -395.532864) (xy 433.526692 -395.53261) (xy 433.526692 -380.186946)
			(xy 431.3428 -378.0028) (xy 427.1518 -378.0028) (xy 427.130934 -378.020153) (xy 427.085219 -378.049396)
			(xy 427.03582 -378.071862) (xy 426.983734 -378.087097) (xy 426.930014 -378.094791) (xy 426.875746 -378.094791)
			(xy 426.822026 -378.087097) (xy 426.76994 -378.071862) (xy 426.720541 -378.049396) (xy 426.674826 -378.020153)
			(xy 426.65396 -378.0028) (xy 423.1386 -378.0028) (xy 422.3258 -378.8156) (xy 422.3258 -380.329948)
			(xy 422.813224 -380.329948) (xy 422.817295 -380.274326) (xy 422.829421 -380.219889) (xy 422.849344 -380.167798)
			(xy 422.87664 -380.119163) (xy 422.910726 -380.07502) (xy 422.950875 -380.036311) (xy 422.996233 -380.00386)
			(xy 423.045833 -379.978359) (xy 423.098617 -379.960352) (xy 423.15346 -379.950222) (xy 423.209194 -379.948185)
			(xy 423.264631 -379.954285) (xy 423.318588 -379.968391) (xy 423.369917 -379.990203) (xy 423.417523 -380.019257)
			(xy 423.460391 -380.054932) (xy 423.497608 -380.096469) (xy 423.528381 -380.142982) (xy 423.552053 -380.193479)
			(xy 423.568121 -380.246886) (xy 423.576241 -380.302062) (xy 423.57675 -380.329948) (xy 423.576241 -380.357834)
			(xy 423.568121 -380.41301) (xy 423.552053 -380.466417) (xy 423.528381 -380.516914) (xy 423.497608 -380.563427)
			(xy 423.460391 -380.604964) (xy 423.417523 -380.640639) (xy 423.369917 -380.669693) (xy 423.318588 -380.691505)
			(xy 423.264631 -380.705611) (xy 423.209194 -380.711711) (xy 423.15346 -380.709674) (xy 423.098617 -380.699544)
			(xy 423.045833 -380.681537) (xy 422.996233 -380.656036) (xy 422.950875 -380.623585) (xy 422.910726 -380.584876)
			(xy 422.87664 -380.540733) (xy 422.849344 -380.492098) (xy 422.829421 -380.440007) (xy 422.817295 -380.38557)
			(xy 422.813224 -380.329948) (xy 422.3258 -380.329948) (xy 422.3258 -381.218915) (xy 425.916426 -381.218915)
			(xy 425.920614 -381.162495) (xy 425.933089 -381.107313) (xy 425.953578 -381.054578) (xy 425.981631 -381.005449)
			(xy 426.016634 -380.961001) (xy 426.057817 -380.922212) (xy 426.104279 -380.889931) (xy 426.154998 -380.864866)
			(xy 426.181774 -380.855728) (xy 426.195105 -380.851043) (xy 426.21862 -380.835388) (xy 426.236949 -380.813892)
			(xy 426.248689 -380.788197) (xy 426.252943 -380.76027) (xy 426.249385 -380.732245) (xy 426.244258 -380.719076)
			(xy 426.234532 -380.695259) (xy 426.220853 -380.645665) (xy 426.213947 -380.594685) (xy 426.213524 -380.568962)
			(xy 426.21401 -380.541711) (xy 426.221766 -380.487763) (xy 426.237121 -380.435468) (xy 426.259763 -380.385891)
			(xy 426.289229 -380.340041) (xy 426.32492 -380.29885) (xy 426.366111 -380.263159) (xy 426.411961 -380.233693)
			(xy 426.461538 -380.211051) (xy 426.513833 -380.195696) (xy 426.567781 -380.18794) (xy 426.622283 -380.18794)
			(xy 426.676231 -380.195696) (xy 426.728526 -380.211051) (xy 426.778103 -380.233693) (xy 426.823953 -380.263159)
			(xy 426.865144 -380.29885) (xy 426.900835 -380.340041) (xy 426.930301 -380.385891) (xy 426.952943 -380.435468)
			(xy 426.968298 -380.487763) (xy 426.976054 -380.541711) (xy 426.97654 -380.568962) (xy 429.382934 -380.568962)
			(xy 429.387005 -380.51334) (xy 429.399131 -380.458903) (xy 429.419054 -380.406812) (xy 429.44635 -380.358177)
			(xy 429.480436 -380.314034) (xy 429.520585 -380.275325) (xy 429.565943 -380.242874) (xy 429.615543 -380.217373)
			(xy 429.668327 -380.199366) (xy 429.72317 -380.189236) (xy 429.778904 -380.187199) (xy 429.834341 -380.193299)
			(xy 429.888298 -380.207405) (xy 429.939627 -380.229217) (xy 429.987233 -380.258271) (xy 430.030101 -380.293946)
			(xy 430.067318 -380.335483) (xy 430.098091 -380.381996) (xy 430.121763 -380.432493) (xy 430.137831 -380.4859)
			(xy 430.145951 -380.541076) (xy 430.14646 -380.568962) (xy 430.145951 -380.596848) (xy 430.137831 -380.652024)
			(xy 430.121763 -380.705431) (xy 430.098091 -380.755928) (xy 430.067318 -380.802441) (xy 430.030101 -380.843978)
			(xy 429.987233 -380.879653) (xy 429.939627 -380.908707) (xy 429.888298 -380.930519) (xy 429.834341 -380.944625)
			(xy 429.778904 -380.950725) (xy 429.72317 -380.948688) (xy 429.668327 -380.938558) (xy 429.615543 -380.920551)
			(xy 429.565943 -380.89505) (xy 429.520585 -380.862599) (xy 429.480436 -380.82389) (xy 429.44635 -380.779747)
			(xy 429.419054 -380.731112) (xy 429.399131 -380.679021) (xy 429.387005 -380.624584) (xy 429.382934 -380.568962)
			(xy 426.97654 -380.568962) (xy 426.976089 -380.595682) (xy 426.968623 -380.648599) (xy 426.953845 -380.699956)
			(xy 426.932046 -380.748749) (xy 426.903652 -380.794022) (xy 426.869217 -380.83489) (xy 426.829417 -380.870553)
			(xy 426.785029 -380.900313) (xy 426.736923 -380.923588) (xy 426.711618 -380.932182) (xy 426.69833 -380.936971)
			(xy 426.674825 -380.952608) (xy 426.6565 -380.974083) (xy 426.644754 -380.999754) (xy 426.640486 -381.027661)
			(xy 426.644021 -381.055669) (xy 426.649134 -381.068834) (xy 426.658862 -381.09265) (xy 426.672541 -381.142244)
			(xy 426.679446 -381.193225) (xy 426.679868 -381.218948) (xy 426.679466 -381.244673) (xy 426.672571 -381.295657)
			(xy 426.658871 -381.345248) (xy 426.649134 -381.369062) (xy 426.643973 -381.382214) (xy 426.640436 -381.410237)
			(xy 426.644706 -381.438158) (xy 426.656457 -381.463842) (xy 426.674791 -381.485328) (xy 426.698307 -381.500973)
			(xy 426.711618 -381.505714) (xy 426.736932 -381.514285) (xy 426.785045 -381.537555) (xy 426.829438 -381.567314)
			(xy 426.869242 -381.602978) (xy 426.903678 -381.64385) (xy 426.932072 -381.689128) (xy 426.953868 -381.737926)
			(xy 426.968638 -381.78929) (xy 426.976093 -381.842212) (xy 426.97654 -381.868934) (xy 426.976054 -381.896185)
			(xy 426.968298 -381.950133) (xy 426.952943 -382.002428) (xy 426.930301 -382.052005) (xy 426.900835 -382.097855)
			(xy 426.865144 -382.139046) (xy 426.823953 -382.174737) (xy 426.778103 -382.204203) (xy 426.728526 -382.226845)
			(xy 426.676231 -382.2422) (xy 426.622283 -382.249956) (xy 426.567781 -382.249956) (xy 426.513833 -382.2422)
			(xy 426.461538 -382.226845) (xy 426.411961 -382.204203) (xy 426.366111 -382.174737) (xy 426.32492 -382.139046)
			(xy 426.289229 -382.097855) (xy 426.259763 -382.052005) (xy 426.237121 -382.002428) (xy 426.221766 -381.950133)
			(xy 426.21401 -381.896185) (xy 426.213524 -381.868934) (xy 426.21392 -381.843209) (xy 426.220818 -381.792225)
			(xy 426.23452 -381.742634) (xy 426.244258 -381.71882) (xy 426.249444 -381.705677) (xy 426.252979 -381.677649)
			(xy 426.248705 -381.649725) (xy 426.236949 -381.624039) (xy 426.218609 -381.602552) (xy 426.195087 -381.586908)
			(xy 426.181774 -381.582168) (xy 426.155026 -381.572945) (xy 426.104304 -381.547884) (xy 426.05784 -381.515607)
			(xy 426.016654 -381.47682) (xy 425.981648 -381.432376) (xy 425.953591 -381.383248) (xy 425.933097 -381.330515)
			(xy 425.920618 -381.275334) (xy 425.916426 -381.218915) (xy 422.3258 -381.218915) (xy 422.3258 -382.184148)
			(xy 422.809922 -382.184148) (xy 422.813993 -382.128526) (xy 422.826119 -382.074089) (xy 422.846042 -382.021998)
			(xy 422.873338 -381.973363) (xy 422.907424 -381.92922) (xy 422.947573 -381.890511) (xy 422.992931 -381.85806)
			(xy 423.042531 -381.832559) (xy 423.095315 -381.814552) (xy 423.150158 -381.804422) (xy 423.205892 -381.802385)
			(xy 423.261329 -381.808485) (xy 423.315286 -381.822591) (xy 423.366615 -381.844403) (xy 423.414221 -381.873457)
			(xy 423.457089 -381.909132) (xy 423.494306 -381.950669) (xy 423.525079 -381.997182) (xy 423.548751 -382.047679)
			(xy 423.564819 -382.101086) (xy 423.572939 -382.156262) (xy 423.573448 -382.184148) (xy 423.572939 -382.212034)
			(xy 423.564819 -382.26721) (xy 423.548751 -382.320617) (xy 423.525079 -382.371114) (xy 423.494306 -382.417627)
			(xy 423.457089 -382.459164) (xy 423.414221 -382.494839) (xy 423.366615 -382.523893) (xy 423.315286 -382.545705)
			(xy 423.261329 -382.559811) (xy 423.205892 -382.565911) (xy 423.150158 -382.563874) (xy 423.095315 -382.553744)
			(xy 423.042531 -382.535737) (xy 422.992931 -382.510236) (xy 422.947573 -382.477785) (xy 422.907424 -382.439076)
			(xy 422.873338 -382.394933) (xy 422.846042 -382.346298) (xy 422.826119 -382.294207) (xy 422.813993 -382.23977)
			(xy 422.809922 -382.184148) (xy 422.3258 -382.184148) (xy 422.3258 -384.266948) (xy 422.766742 -384.266948)
			(xy 422.770813 -384.211326) (xy 422.782939 -384.156889) (xy 422.802862 -384.104798) (xy 422.830158 -384.056163)
			(xy 422.864244 -384.01202) (xy 422.904393 -383.973311) (xy 422.949751 -383.94086) (xy 422.999351 -383.915359)
			(xy 423.052135 -383.897352) (xy 423.106978 -383.887222) (xy 423.162712 -383.885185) (xy 423.218149 -383.891285)
			(xy 423.272106 -383.905391) (xy 423.323435 -383.927203) (xy 423.371041 -383.956257) (xy 423.413909 -383.991932)
			(xy 423.451126 -384.033469) (xy 423.481899 -384.079982) (xy 423.505571 -384.130479) (xy 423.521639 -384.183886)
			(xy 423.529759 -384.239062) (xy 423.530268 -384.266948) (xy 423.529759 -384.294834) (xy 423.521639 -384.35001)
			(xy 423.505571 -384.403417) (xy 423.481899 -384.453914) (xy 423.451126 -384.500427) (xy 423.413909 -384.541964)
			(xy 423.371041 -384.577639) (xy 423.323435 -384.606693) (xy 423.272106 -384.628505) (xy 423.218149 -384.642611)
			(xy 423.162712 -384.648711) (xy 423.106978 -384.646674) (xy 423.052135 -384.636544) (xy 422.999351 -384.618537)
			(xy 422.949751 -384.593036) (xy 422.904393 -384.560585) (xy 422.864244 -384.521876) (xy 422.830158 -384.477733)
			(xy 422.802862 -384.429098) (xy 422.782939 -384.377007) (xy 422.770813 -384.32257) (xy 422.766742 -384.266948)
			(xy 422.3258 -384.266948) (xy 422.3258 -386.143966) (xy 425.813166 -386.143966) (xy 425.82132 -386.088687)
			(xy 425.837454 -386.03519) (xy 425.861222 -385.98462) (xy 425.892116 -385.93806) (xy 425.929475 -385.896508)
			(xy 425.972497 -385.860852) (xy 426.020262 -385.831856) (xy 426.071748 -385.810142) (xy 426.125851 -385.796174)
			(xy 426.15358 -385.792726) (xy 426.168912 -385.790459) (xy 426.197313 -385.778106) (xy 426.220712 -385.757816)
			(xy 426.236964 -385.731451) (xy 426.244576 -385.701429) (xy 426.24285 -385.670506) (xy 426.237908 -385.65582)
			(xy 426.226531 -385.623532) (xy 426.214263 -385.556188) (xy 426.213524 -385.521962) (xy 426.21401 -385.494711)
			(xy 426.221766 -385.440763) (xy 426.237121 -385.388468) (xy 426.259763 -385.338891) (xy 426.289229 -385.293041)
			(xy 426.32492 -385.25185) (xy 426.366111 -385.216159) (xy 426.411961 -385.186693) (xy 426.461538 -385.164051)
			(xy 426.513833 -385.148696) (xy 426.567781 -385.14094) (xy 426.622283 -385.14094) (xy 426.676231 -385.148696)
			(xy 426.728526 -385.164051) (xy 426.778103 -385.186693) (xy 426.823953 -385.216159) (xy 426.865144 -385.25185)
			(xy 426.900835 -385.293041) (xy 426.930301 -385.338891) (xy 426.952943 -385.388468) (xy 426.968298 -385.440763)
			(xy 426.976054 -385.494711) (xy 426.97654 -385.521962) (xy 429.382934 -385.521962) (xy 429.387005 -385.46634)
			(xy 429.399131 -385.411903) (xy 429.419054 -385.359812) (xy 429.44635 -385.311177) (xy 429.480436 -385.267034)
			(xy 429.520585 -385.228325) (xy 429.565943 -385.195874) (xy 429.615543 -385.170373) (xy 429.668327 -385.152366)
			(xy 429.72317 -385.142236) (xy 429.778904 -385.140199) (xy 429.834341 -385.146299) (xy 429.888298 -385.160405)
			(xy 429.939627 -385.182217) (xy 429.987233 -385.211271) (xy 430.030101 -385.246946) (xy 430.067318 -385.288483)
			(xy 430.098091 -385.334996) (xy 430.121763 -385.385493) (xy 430.137831 -385.4389) (xy 430.145951 -385.494076)
			(xy 430.14646 -385.521962) (xy 430.145951 -385.549848) (xy 430.137831 -385.605024) (xy 430.121763 -385.658431)
			(xy 430.098091 -385.708928) (xy 430.067318 -385.755441) (xy 430.030101 -385.796978) (xy 429.987233 -385.832653)
			(xy 429.939627 -385.861707) (xy 429.888298 -385.883519) (xy 429.834341 -385.897625) (xy 429.778904 -385.903725)
			(xy 429.72317 -385.901688) (xy 429.668327 -385.891558) (xy 429.615543 -385.873551) (xy 429.565943 -385.84805)
			(xy 429.520585 -385.815599) (xy 429.480436 -385.77689) (xy 429.44635 -385.732747) (xy 429.419054 -385.684112)
			(xy 429.399131 -385.632021) (xy 429.387005 -385.577584) (xy 429.382934 -385.521962) (xy 426.97654 -385.521962)
			(xy 426.976045 -385.549904) (xy 426.967919 -385.605193) (xy 426.951806 -385.658703) (xy 426.928052 -385.709286)
			(xy 426.897165 -385.755858) (xy 426.859809 -385.797421) (xy 426.816784 -385.833082) (xy 426.769012 -385.862078)
			(xy 426.717518 -385.883788) (xy 426.663405 -385.897744) (xy 426.635672 -385.901184) (xy 426.620333 -385.903406)
			(xy 426.591932 -385.915772) (xy 426.568534 -385.936072) (xy 426.552285 -385.962445) (xy 426.544676 -385.992473)
			(xy 426.546402 -386.023401) (xy 426.551344 -386.03809) (xy 426.562722 -386.070378) (xy 426.57499 -386.137722)
			(xy 426.575728 -386.171948) (xy 426.574933 -386.206168) (xy 426.562661 -386.273501) (xy 426.551344 -386.305806)
			(xy 426.54643 -386.320498) (xy 426.544735 -386.351415) (xy 426.552355 -386.381426) (xy 426.568593 -386.40779)
			(xy 426.591967 -386.428099) (xy 426.62034 -386.440496) (xy 426.635672 -386.442712) (xy 426.663397 -386.44618)
			(xy 426.717492 -386.460164) (xy 426.768969 -386.48189) (xy 426.816725 -386.510894) (xy 426.859739 -386.546553)
			(xy 426.897091 -386.588107) (xy 426.927982 -386.634664) (xy 426.95175 -386.685231) (xy 426.967887 -386.738723)
			(xy 426.976047 -386.793997) (xy 426.97654 -386.821934) (xy 426.976054 -386.849185) (xy 426.968298 -386.903133)
			(xy 426.952943 -386.955428) (xy 426.930301 -387.005005) (xy 426.900835 -387.050855) (xy 426.865144 -387.092046)
			(xy 426.823953 -387.127737) (xy 426.778103 -387.157203) (xy 426.728526 -387.179845) (xy 426.676231 -387.1952)
			(xy 426.622283 -387.202956) (xy 426.567781 -387.202956) (xy 426.513833 -387.1952) (xy 426.461538 -387.179845)
			(xy 426.411961 -387.157203) (xy 426.366111 -387.127737) (xy 426.32492 -387.092046) (xy 426.289229 -387.050855)
			(xy 426.259763 -387.005005) (xy 426.237121 -386.955428) (xy 426.221766 -386.903133) (xy 426.21401 -386.849185)
			(xy 426.213524 -386.821934) (xy 426.214317 -386.787714) (xy 426.226591 -386.720381) (xy 426.237908 -386.688076)
			(xy 426.242883 -386.673401) (xy 426.244576 -386.642471) (xy 426.236949 -386.61245) (xy 426.220698 -386.586079)
			(xy 426.197308 -386.56577) (xy 426.168919 -386.55338) (xy 426.15358 -386.55117) (xy 426.125861 -386.547628)
			(xy 426.071757 -386.533661) (xy 426.020271 -386.511948) (xy 425.972505 -386.482954) (xy 425.929482 -386.447299)
			(xy 425.892123 -386.405748) (xy 425.861227 -386.359189) (xy 425.837458 -386.308619) (xy 425.821322 -386.255123)
			(xy 425.813167 -386.199844) (xy 425.813166 -386.143966) (xy 422.3258 -386.143966) (xy 422.3258 -387.314948)
			(xy 422.813224 -387.314948) (xy 422.817295 -387.259326) (xy 422.829421 -387.204889) (xy 422.849344 -387.152798)
			(xy 422.87664 -387.104163) (xy 422.910726 -387.06002) (xy 422.950875 -387.021311) (xy 422.996233 -386.98886)
			(xy 423.045833 -386.963359) (xy 423.098617 -386.945352) (xy 423.15346 -386.935222) (xy 423.209194 -386.933185)
			(xy 423.264631 -386.939285) (xy 423.318588 -386.953391) (xy 423.369917 -386.975203) (xy 423.417523 -387.004257)
			(xy 423.460391 -387.039932) (xy 423.497608 -387.081469) (xy 423.528381 -387.127982) (xy 423.552053 -387.178479)
			(xy 423.568121 -387.231886) (xy 423.576241 -387.287062) (xy 423.57675 -387.314948) (xy 423.576241 -387.342834)
			(xy 423.568121 -387.39801) (xy 423.552053 -387.451417) (xy 423.528381 -387.501914) (xy 423.497608 -387.548427)
			(xy 423.460391 -387.589964) (xy 423.417523 -387.625639) (xy 423.369917 -387.654693) (xy 423.318588 -387.676505)
			(xy 423.264631 -387.690611) (xy 423.209194 -387.696711) (xy 423.15346 -387.694674) (xy 423.098617 -387.684544)
			(xy 423.045833 -387.666537) (xy 422.996233 -387.641036) (xy 422.950875 -387.608585) (xy 422.910726 -387.569876)
			(xy 422.87664 -387.525733) (xy 422.849344 -387.477098) (xy 422.829421 -387.425007) (xy 422.817295 -387.37057)
			(xy 422.813224 -387.314948) (xy 422.3258 -387.314948) (xy 422.3258 -390.616948) (xy 422.813224 -390.616948)
			(xy 422.817295 -390.561326) (xy 422.829421 -390.506889) (xy 422.849344 -390.454798) (xy 422.87664 -390.406163)
			(xy 422.910726 -390.36202) (xy 422.950875 -390.323311) (xy 422.996233 -390.29086) (xy 423.045833 -390.265359)
			(xy 423.098617 -390.247352) (xy 423.15346 -390.237222) (xy 423.209194 -390.235185) (xy 423.264631 -390.241285)
			(xy 423.318588 -390.255391) (xy 423.369917 -390.277203) (xy 423.417523 -390.306257) (xy 423.460391 -390.341932)
			(xy 423.497608 -390.383469) (xy 423.528381 -390.429982) (xy 423.552053 -390.480479) (xy 423.568121 -390.533886)
			(xy 423.576241 -390.589062) (xy 423.57675 -390.616948) (xy 423.576241 -390.644834) (xy 423.568121 -390.70001)
			(xy 423.552053 -390.753417) (xy 423.528381 -390.803914) (xy 423.497608 -390.850427) (xy 423.460391 -390.891964)
			(xy 423.417523 -390.927639) (xy 423.369917 -390.956693) (xy 423.318588 -390.978505) (xy 423.264631 -390.992611)
			(xy 423.209194 -390.998711) (xy 423.15346 -390.996674) (xy 423.098617 -390.986544) (xy 423.045833 -390.968537)
			(xy 422.996233 -390.943036) (xy 422.950875 -390.910585) (xy 422.910726 -390.871876) (xy 422.87664 -390.827733)
			(xy 422.849344 -390.779098) (xy 422.829421 -390.727007) (xy 422.817295 -390.67257) (xy 422.813224 -390.616948)
			(xy 422.3258 -390.616948) (xy 422.3258 -391.632948) (xy 422.813224 -391.632948) (xy 422.817295 -391.577326)
			(xy 422.829421 -391.522889) (xy 422.849344 -391.470798) (xy 422.87664 -391.422163) (xy 422.910726 -391.37802)
			(xy 422.950875 -391.339311) (xy 422.996233 -391.30686) (xy 423.045833 -391.281359) (xy 423.098617 -391.263352)
			(xy 423.15346 -391.253222) (xy 423.209194 -391.251185) (xy 423.264631 -391.257285) (xy 423.318588 -391.271391)
			(xy 423.369917 -391.293203) (xy 423.417523 -391.322257) (xy 423.460391 -391.357932) (xy 423.497608 -391.399469)
			(xy 423.528381 -391.445982) (xy 423.552053 -391.496479) (xy 423.554892 -391.505915) (xy 425.916426 -391.505915)
			(xy 425.920614 -391.449495) (xy 425.933089 -391.394313) (xy 425.953578 -391.341578) (xy 425.981631 -391.292449)
			(xy 426.016634 -391.248001) (xy 426.057817 -391.209212) (xy 426.104279 -391.176931) (xy 426.154998 -391.151866)
			(xy 426.181774 -391.142728) (xy 426.195105 -391.138043) (xy 426.21862 -391.122388) (xy 426.236949 -391.100892)
			(xy 426.248689 -391.075197) (xy 426.252943 -391.04727) (xy 426.249385 -391.019245) (xy 426.244258 -391.006076)
			(xy 426.234532 -390.982259) (xy 426.220853 -390.932665) (xy 426.213947 -390.881685) (xy 426.213524 -390.855962)
			(xy 426.21401 -390.828711) (xy 426.221766 -390.774763) (xy 426.237121 -390.722468) (xy 426.259763 -390.672891)
			(xy 426.289229 -390.627041) (xy 426.32492 -390.58585) (xy 426.366111 -390.550159) (xy 426.411961 -390.520693)
			(xy 426.461538 -390.498051) (xy 426.513833 -390.482696) (xy 426.567781 -390.47494) (xy 426.622283 -390.47494)
			(xy 426.676231 -390.482696) (xy 426.728526 -390.498051) (xy 426.778103 -390.520693) (xy 426.823953 -390.550159)
			(xy 426.865144 -390.58585) (xy 426.900835 -390.627041) (xy 426.930301 -390.672891) (xy 426.952943 -390.722468)
			(xy 426.968298 -390.774763) (xy 426.976054 -390.828711) (xy 426.97654 -390.855962) (xy 429.382934 -390.855962)
			(xy 429.387005 -390.80034) (xy 429.399131 -390.745903) (xy 429.419054 -390.693812) (xy 429.44635 -390.645177)
			(xy 429.480436 -390.601034) (xy 429.520585 -390.562325) (xy 429.565943 -390.529874) (xy 429.615543 -390.504373)
			(xy 429.668327 -390.486366) (xy 429.72317 -390.476236) (xy 429.778904 -390.474199) (xy 429.834341 -390.480299)
			(xy 429.888298 -390.494405) (xy 429.939627 -390.516217) (xy 429.987233 -390.545271) (xy 430.030101 -390.580946)
			(xy 430.067318 -390.622483) (xy 430.098091 -390.668996) (xy 430.121763 -390.719493) (xy 430.137831 -390.7729)
			(xy 430.145951 -390.828076) (xy 430.14646 -390.855962) (xy 430.145951 -390.883848) (xy 430.137831 -390.939024)
			(xy 430.121763 -390.992431) (xy 430.098091 -391.042928) (xy 430.067318 -391.089441) (xy 430.030101 -391.130978)
			(xy 429.987233 -391.166653) (xy 429.939627 -391.195707) (xy 429.888298 -391.217519) (xy 429.834341 -391.231625)
			(xy 429.778904 -391.237725) (xy 429.72317 -391.235688) (xy 429.668327 -391.225558) (xy 429.615543 -391.207551)
			(xy 429.565943 -391.18205) (xy 429.520585 -391.149599) (xy 429.480436 -391.11089) (xy 429.44635 -391.066747)
			(xy 429.419054 -391.018112) (xy 429.399131 -390.966021) (xy 429.387005 -390.911584) (xy 429.382934 -390.855962)
			(xy 426.97654 -390.855962) (xy 426.976089 -390.882682) (xy 426.968623 -390.935599) (xy 426.953845 -390.986956)
			(xy 426.932046 -391.035749) (xy 426.903652 -391.081022) (xy 426.869217 -391.12189) (xy 426.829417 -391.157553)
			(xy 426.785029 -391.187313) (xy 426.736923 -391.210588) (xy 426.711618 -391.219182) (xy 426.69833 -391.223971)
			(xy 426.674825 -391.239608) (xy 426.6565 -391.261083) (xy 426.644754 -391.286754) (xy 426.640486 -391.314661)
			(xy 426.644021 -391.342669) (xy 426.649134 -391.355834) (xy 426.658862 -391.37965) (xy 426.672541 -391.429244)
			(xy 426.679446 -391.480225) (xy 426.679868 -391.505948) (xy 426.679466 -391.531673) (xy 426.672571 -391.582657)
			(xy 426.658871 -391.632248) (xy 426.649134 -391.656062) (xy 426.643973 -391.669214) (xy 426.640436 -391.697237)
			(xy 426.644706 -391.725158) (xy 426.656457 -391.750842) (xy 426.674791 -391.772328) (xy 426.698307 -391.787973)
			(xy 426.711618 -391.792714) (xy 426.736932 -391.801285) (xy 426.785045 -391.824555) (xy 426.829438 -391.854314)
			(xy 426.869242 -391.889978) (xy 426.903678 -391.93085) (xy 426.932072 -391.976128) (xy 426.953868 -392.024926)
			(xy 426.968638 -392.07629) (xy 426.976093 -392.129212) (xy 426.97654 -392.155934) (xy 426.976054 -392.183185)
			(xy 426.968298 -392.237133) (xy 426.952943 -392.289428) (xy 426.930301 -392.339005) (xy 426.900835 -392.384855)
			(xy 426.865144 -392.426046) (xy 426.823953 -392.461737) (xy 426.778103 -392.491203) (xy 426.728526 -392.513845)
			(xy 426.676231 -392.5292) (xy 426.622283 -392.536956) (xy 426.567781 -392.536956) (xy 426.513833 -392.5292)
			(xy 426.461538 -392.513845) (xy 426.411961 -392.491203) (xy 426.366111 -392.461737) (xy 426.32492 -392.426046)
			(xy 426.289229 -392.384855) (xy 426.259763 -392.339005) (xy 426.237121 -392.289428) (xy 426.221766 -392.237133)
			(xy 426.21401 -392.183185) (xy 426.213524 -392.155934) (xy 426.21392 -392.130209) (xy 426.220818 -392.079225)
			(xy 426.23452 -392.029634) (xy 426.244258 -392.00582) (xy 426.249444 -391.992677) (xy 426.252979 -391.964649)
			(xy 426.248705 -391.936725) (xy 426.236949 -391.911039) (xy 426.218609 -391.889552) (xy 426.195087 -391.873908)
			(xy 426.181774 -391.869168) (xy 426.155026 -391.859945) (xy 426.104304 -391.834884) (xy 426.05784 -391.802607)
			(xy 426.016654 -391.76382) (xy 425.981648 -391.719376) (xy 425.953591 -391.670248) (xy 425.933097 -391.617515)
			(xy 425.920618 -391.562334) (xy 425.916426 -391.505915) (xy 423.554892 -391.505915) (xy 423.568121 -391.549886)
			(xy 423.576241 -391.605062) (xy 423.57675 -391.632948) (xy 423.576241 -391.660834) (xy 423.568121 -391.71601)
			(xy 423.552053 -391.769417) (xy 423.528381 -391.819914) (xy 423.497608 -391.866427) (xy 423.460391 -391.907964)
			(xy 423.417523 -391.943639) (xy 423.369917 -391.972693) (xy 423.318588 -391.994505) (xy 423.264631 -392.008611)
			(xy 423.209194 -392.014711) (xy 423.15346 -392.012674) (xy 423.098617 -392.002544) (xy 423.045833 -391.984537)
			(xy 422.996233 -391.959036) (xy 422.950875 -391.926585) (xy 422.910726 -391.887876) (xy 422.87664 -391.843733)
			(xy 422.849344 -391.795098) (xy 422.829421 -391.743007) (xy 422.817295 -391.68857) (xy 422.813224 -391.632948)
			(xy 422.3258 -391.632948) (xy 422.3258 -393.90701) (xy 424.222924 -393.90701) (xy 424.226995 -393.851388)
			(xy 424.239121 -393.796951) (xy 424.259044 -393.74486) (xy 424.28634 -393.696225) (xy 424.320426 -393.652082)
			(xy 424.360575 -393.613373) (xy 424.405933 -393.580922) (xy 424.455533 -393.555421) (xy 424.508317 -393.537414)
			(xy 424.56316 -393.527284) (xy 424.618894 -393.525247) (xy 424.674331 -393.531347) (xy 424.728288 -393.545453)
			(xy 424.779617 -393.567265) (xy 424.827223 -393.596319) (xy 424.870091 -393.631994) (xy 424.907308 -393.673531)
			(xy 424.938081 -393.720044) (xy 424.961753 -393.770541) (xy 424.977821 -393.823948) (xy 424.985941 -393.879124)
			(xy 424.98645 -393.90701) (xy 424.985941 -393.934896) (xy 424.977821 -393.990072) (xy 424.961753 -394.043479)
			(xy 424.938081 -394.093976) (xy 424.907308 -394.140489) (xy 424.870091 -394.182026) (xy 424.827223 -394.217701)
			(xy 424.779617 -394.246755) (xy 424.728288 -394.268567) (xy 424.674331 -394.282673) (xy 424.618894 -394.288773)
			(xy 424.56316 -394.286736) (xy 424.508317 -394.276606) (xy 424.455533 -394.258599) (xy 424.405933 -394.233098)
			(xy 424.360575 -394.200647) (xy 424.320426 -394.161938) (xy 424.28634 -394.117795) (xy 424.259044 -394.06916)
			(xy 424.239121 -394.017069) (xy 424.226995 -393.962632) (xy 424.222924 -393.90701) (xy 422.3258 -393.90701)
			(xy 422.3258 -394.603478) (xy 422.813224 -394.603478) (xy 422.817295 -394.547856) (xy 422.829421 -394.493419)
			(xy 422.849344 -394.441328) (xy 422.87664 -394.392693) (xy 422.910726 -394.34855) (xy 422.950875 -394.309841)
			(xy 422.996233 -394.27739) (xy 423.045833 -394.251889) (xy 423.098617 -394.233882) (xy 423.15346 -394.223752)
			(xy 423.209194 -394.221715) (xy 423.264631 -394.227815) (xy 423.318588 -394.241921) (xy 423.369917 -394.263733)
			(xy 423.417523 -394.292787) (xy 423.460391 -394.328462) (xy 423.497608 -394.369999) (xy 423.528381 -394.416512)
			(xy 423.552053 -394.467009) (xy 423.568121 -394.520416) (xy 423.576241 -394.575592) (xy 423.57675 -394.603478)
			(xy 423.576241 -394.631364) (xy 423.568121 -394.68654) (xy 423.552053 -394.739947) (xy 423.528381 -394.790444)
			(xy 423.497608 -394.836957) (xy 423.460391 -394.878494) (xy 423.417523 -394.914169) (xy 423.369917 -394.943223)
			(xy 423.318588 -394.965035) (xy 423.264631 -394.979141) (xy 423.209194 -394.985241) (xy 423.15346 -394.983204)
			(xy 423.098617 -394.973074) (xy 423.045833 -394.955067) (xy 422.996233 -394.929566) (xy 422.950875 -394.897115)
			(xy 422.910726 -394.858406) (xy 422.87664 -394.814263) (xy 422.849344 -394.765628) (xy 422.829421 -394.713537)
			(xy 422.817295 -394.6591) (xy 422.813224 -394.603478) (xy 422.3258 -394.603478) (xy 422.3258 -395.798548)
			(xy 429.382934 -395.798548) (xy 429.387005 -395.742926) (xy 429.399131 -395.688489) (xy 429.419054 -395.636398)
			(xy 429.44635 -395.587763) (xy 429.480436 -395.54362) (xy 429.520585 -395.504911) (xy 429.565943 -395.47246)
			(xy 429.615543 -395.446959) (xy 429.668327 -395.428952) (xy 429.72317 -395.418822) (xy 429.778904 -395.416785)
			(xy 429.834341 -395.422885) (xy 429.888298 -395.436991) (xy 429.939627 -395.458803) (xy 429.987233 -395.487857)
			(xy 430.030101 -395.523532) (xy 430.067318 -395.565069) (xy 430.098091 -395.611582) (xy 430.121763 -395.662079)
			(xy 430.137831 -395.715486) (xy 430.145951 -395.770662) (xy 430.14646 -395.798548) (xy 430.145951 -395.826434)
			(xy 430.137831 -395.88161) (xy 430.121763 -395.935017) (xy 430.098091 -395.985514) (xy 430.067318 -396.032027)
			(xy 430.030101 -396.073564) (xy 429.987233 -396.109239) (xy 429.939627 -396.138293) (xy 429.888298 -396.160105)
			(xy 429.834341 -396.174211) (xy 429.778904 -396.180311) (xy 429.72317 -396.178274) (xy 429.668327 -396.168144)
			(xy 429.615543 -396.150137) (xy 429.565943 -396.124636) (xy 429.520585 -396.092185) (xy 429.480436 -396.053476)
			(xy 429.44635 -396.009333) (xy 429.419054 -395.960698) (xy 429.399131 -395.908607) (xy 429.387005 -395.85417)
			(xy 429.382934 -395.798548) (xy 422.3258 -395.798548) (xy 422.3258 -397.09852) (xy 426.213014 -397.09852)
			(xy 426.217085 -397.042898) (xy 426.229211 -396.988461) (xy 426.249134 -396.93637) (xy 426.27643 -396.887735)
			(xy 426.310516 -396.843592) (xy 426.350665 -396.804883) (xy 426.396023 -396.772432) (xy 426.445623 -396.746931)
			(xy 426.498407 -396.728924) (xy 426.55325 -396.718794) (xy 426.608984 -396.716757) (xy 426.664421 -396.722857)
			(xy 426.718378 -396.736963) (xy 426.769707 -396.758775) (xy 426.817313 -396.787829) (xy 426.860181 -396.823504)
			(xy 426.897398 -396.865041) (xy 426.928171 -396.911554) (xy 426.951843 -396.962051) (xy 426.967911 -397.015458)
			(xy 426.976031 -397.070634) (xy 426.97654 -397.09852) (xy 426.976031 -397.126406) (xy 426.967911 -397.181582)
			(xy 426.951843 -397.234989) (xy 426.928171 -397.285486) (xy 426.897398 -397.331999) (xy 426.860181 -397.373536)
			(xy 426.817313 -397.409211) (xy 426.769707 -397.438265) (xy 426.718378 -397.460077) (xy 426.664421 -397.474183)
			(xy 426.608984 -397.480283) (xy 426.55325 -397.478246) (xy 426.498407 -397.468116) (xy 426.445623 -397.450109)
			(xy 426.396023 -397.424608) (xy 426.350665 -397.392157) (xy 426.310516 -397.353448) (xy 426.27643 -397.309305)
			(xy 426.249134 -397.26067) (xy 426.229211 -397.208579) (xy 426.217085 -397.154142) (xy 426.213014 -397.09852)
			(xy 422.3258 -397.09852) (xy 422.3258 -397.651478) (xy 422.832274 -397.651478) (xy 422.836345 -397.595856)
			(xy 422.848471 -397.541419) (xy 422.868394 -397.489328) (xy 422.89569 -397.440693) (xy 422.929776 -397.39655)
			(xy 422.969925 -397.357841) (xy 423.015283 -397.32539) (xy 423.064883 -397.299889) (xy 423.117667 -397.281882)
			(xy 423.17251 -397.271752) (xy 423.228244 -397.269715) (xy 423.283681 -397.275815) (xy 423.337638 -397.289921)
			(xy 423.388967 -397.311733) (xy 423.436573 -397.340787) (xy 423.479441 -397.376462) (xy 423.516658 -397.417999)
			(xy 423.547431 -397.464512) (xy 423.571103 -397.515009) (xy 423.587171 -397.568416) (xy 423.595291 -397.623592)
			(xy 423.5958 -397.651478) (xy 423.595291 -397.679364) (xy 423.587171 -397.73454) (xy 423.571103 -397.787947)
			(xy 423.547431 -397.838444) (xy 423.516658 -397.884957) (xy 423.479441 -397.926494) (xy 423.436573 -397.962169)
			(xy 423.388967 -397.991223) (xy 423.337638 -398.013035) (xy 423.283681 -398.027141) (xy 423.228244 -398.033241)
			(xy 423.17251 -398.031204) (xy 423.117667 -398.021074) (xy 423.064883 -398.003067) (xy 423.015283 -397.977566)
			(xy 422.969925 -397.945115) (xy 422.929776 -397.906406) (xy 422.89569 -397.862263) (xy 422.868394 -397.813628)
			(xy 422.848471 -397.761537) (xy 422.836345 -397.7071) (xy 422.832274 -397.651478) (xy 422.3258 -397.651478)
			(xy 422.3258 -398.630648) (xy 424.219622 -398.630648) (xy 424.223693 -398.575026) (xy 424.235819 -398.520589)
			(xy 424.255742 -398.468498) (xy 424.283038 -398.419863) (xy 424.317124 -398.37572) (xy 424.357273 -398.337011)
			(xy 424.402631 -398.30456) (xy 424.452231 -398.279059) (xy 424.505015 -398.261052) (xy 424.559858 -398.250922)
			(xy 424.615592 -398.248885) (xy 424.671029 -398.254985) (xy 424.724986 -398.269091) (xy 424.776315 -398.290903)
			(xy 424.823921 -398.319957) (xy 424.866789 -398.355632) (xy 424.904006 -398.397169) (xy 424.934779 -398.443682)
			(xy 424.958451 -398.494179) (xy 424.974519 -398.547586) (xy 424.982639 -398.602762) (xy 424.983148 -398.630648)
			(xy 424.982639 -398.658534) (xy 424.974519 -398.71371) (xy 424.958451 -398.767117) (xy 424.934779 -398.817614)
			(xy 424.904006 -398.864127) (xy 424.866789 -398.905664) (xy 424.823921 -398.941339) (xy 424.776315 -398.970393)
			(xy 424.724986 -398.992205) (xy 424.671029 -399.006311) (xy 424.615592 -399.012411) (xy 424.559858 -399.010374)
			(xy 424.505015 -399.000244) (xy 424.452231 -398.982237) (xy 424.402631 -398.956736) (xy 424.357273 -398.924285)
			(xy 424.317124 -398.885576) (xy 424.283038 -398.841433) (xy 424.255742 -398.792798) (xy 424.235819 -398.740707)
			(xy 424.223693 -398.68627) (xy 424.219622 -398.630648) (xy 422.3258 -398.630648) (xy 422.3258 -402.671534)
			(xy 422.832274 -402.671534) (xy 422.836345 -402.615912) (xy 422.848471 -402.561475) (xy 422.868394 -402.509384)
			(xy 422.89569 -402.460749) (xy 422.929776 -402.416606) (xy 422.969925 -402.377897) (xy 423.015283 -402.345446)
			(xy 423.064883 -402.319945) (xy 423.117667 -402.301938) (xy 423.17251 -402.291808) (xy 423.228244 -402.289771)
			(xy 423.283681 -402.295871) (xy 423.337638 -402.309977) (xy 423.388967 -402.331789) (xy 423.436573 -402.360843)
			(xy 423.479441 -402.396518) (xy 423.516658 -402.438055) (xy 423.547431 -402.484568) (xy 423.571103 -402.535065)
			(xy 423.587171 -402.588472) (xy 423.595291 -402.643648) (xy 423.5958 -402.671534) (xy 424.869862 -402.671534)
			(xy 424.873933 -402.615912) (xy 424.886059 -402.561475) (xy 424.905982 -402.509384) (xy 424.933278 -402.460749)
			(xy 424.967364 -402.416606) (xy 425.007513 -402.377897) (xy 425.052871 -402.345446) (xy 425.102471 -402.319945)
			(xy 425.155255 -402.301938) (xy 425.210098 -402.291808) (xy 425.265832 -402.289771) (xy 425.321269 -402.295871)
			(xy 425.358177 -402.30552) (xy 426.213014 -402.30552) (xy 426.217085 -402.249898) (xy 426.229211 -402.195461)
			(xy 426.249134 -402.14337) (xy 426.27643 -402.094735) (xy 426.310516 -402.050592) (xy 426.350665 -402.011883)
			(xy 426.396023 -401.979432) (xy 426.445623 -401.953931) (xy 426.498407 -401.935924) (xy 426.55325 -401.925794)
			(xy 426.608984 -401.923757) (xy 426.664421 -401.929857) (xy 426.718378 -401.943963) (xy 426.769707 -401.965775)
			(xy 426.817313 -401.994829) (xy 426.860181 -402.030504) (xy 426.897398 -402.072041) (xy 426.928171 -402.118554)
			(xy 426.951843 -402.169051) (xy 426.967911 -402.222458) (xy 426.976031 -402.277634) (xy 426.97654 -402.30552)
			(xy 426.976031 -402.333406) (xy 426.967911 -402.388582) (xy 426.951843 -402.441989) (xy 426.928171 -402.492486)
			(xy 426.897398 -402.538999) (xy 426.860181 -402.580536) (xy 426.817313 -402.616211) (xy 426.769707 -402.645265)
			(xy 426.718378 -402.667077) (xy 426.664421 -402.681183) (xy 426.608984 -402.687283) (xy 426.55325 -402.685246)
			(xy 426.498407 -402.675116) (xy 426.445623 -402.657109) (xy 426.396023 -402.631608) (xy 426.350665 -402.599157)
			(xy 426.310516 -402.560448) (xy 426.27643 -402.516305) (xy 426.249134 -402.46767) (xy 426.229211 -402.415579)
			(xy 426.217085 -402.361142) (xy 426.213014 -402.30552) (xy 425.358177 -402.30552) (xy 425.375226 -402.309977)
			(xy 425.426555 -402.331789) (xy 425.474161 -402.360843) (xy 425.517029 -402.396518) (xy 425.554246 -402.438055)
			(xy 425.585019 -402.484568) (xy 425.608691 -402.535065) (xy 425.624759 -402.588472) (xy 425.632879 -402.643648)
			(xy 425.633388 -402.671534) (xy 425.632879 -402.69942) (xy 425.624759 -402.754596) (xy 425.608691 -402.808003)
			(xy 425.585019 -402.8585) (xy 425.554246 -402.905013) (xy 425.517029 -402.94655) (xy 425.474161 -402.982225)
			(xy 425.426555 -403.011279) (xy 425.375226 -403.033091) (xy 425.321269 -403.047197) (xy 425.265832 -403.053297)
			(xy 425.210098 -403.05126) (xy 425.155255 -403.04113) (xy 425.102471 -403.023123) (xy 425.052871 -402.997622)
			(xy 425.007513 -402.965171) (xy 424.967364 -402.926462) (xy 424.933278 -402.882319) (xy 424.905982 -402.833684)
			(xy 424.886059 -402.781593) (xy 424.873933 -402.727156) (xy 424.869862 -402.671534) (xy 423.5958 -402.671534)
			(xy 423.595291 -402.69942) (xy 423.587171 -402.754596) (xy 423.571103 -402.808003) (xy 423.547431 -402.8585)
			(xy 423.516658 -402.905013) (xy 423.479441 -402.94655) (xy 423.436573 -402.982225) (xy 423.388967 -403.011279)
			(xy 423.337638 -403.033091) (xy 423.283681 -403.047197) (xy 423.228244 -403.053297) (xy 423.17251 -403.05126)
			(xy 423.117667 -403.04113) (xy 423.064883 -403.023123) (xy 423.015283 -402.997622) (xy 422.969925 -402.965171)
			(xy 422.929776 -402.926462) (xy 422.89569 -402.882319) (xy 422.868394 -402.833684) (xy 422.848471 -402.781593)
			(xy 422.836345 -402.727156) (xy 422.832274 -402.671534) (xy 422.3258 -402.671534) (xy 422.3258 -403.1742)
			(xy 422.529 -403.3774) (xy 432.2572 -403.3774)
		)
		(stroke
			(width 0)
			(type solid)
		)
		(fill yes)
		(layer "In13.Cu")
		(net "P3V3_AUX")
	)
	(gr_poly
		(pts
			(xy 465.316316 -395.996414) (xy 466.935312 -394.377418) (xy 466.935312 -378.9934) (xy 465.741258 -377.799346)
			(xy 434.8734 -377.799346) (xy 434.8607 -377.8123) (xy 434.3527 -377.8123) (xy 433.7812 -378.3838)
			(xy 433.7812 -378.526548) (xy 438.052462 -378.526548) (xy 438.056533 -378.470926) (xy 438.068659 -378.416489)
			(xy 438.088582 -378.364398) (xy 438.115878 -378.315763) (xy 438.149964 -378.27162) (xy 438.190113 -378.232911)
			(xy 438.235471 -378.20046) (xy 438.285071 -378.174959) (xy 438.337855 -378.156952) (xy 438.392698 -378.146822)
			(xy 438.448432 -378.144785) (xy 438.503869 -378.150885) (xy 438.557826 -378.164991) (xy 438.609155 -378.186803)
			(xy 438.656761 -378.215857) (xy 438.699629 -378.251532) (xy 438.736846 -378.293069) (xy 438.767619 -378.339582)
			(xy 438.791291 -378.390079) (xy 438.807359 -378.443486) (xy 438.815479 -378.498662) (xy 438.815988 -378.526548)
			(xy 438.815479 -378.554434) (xy 438.807359 -378.60961) (xy 438.791291 -378.663017) (xy 438.767619 -378.713514)
			(xy 438.736846 -378.760027) (xy 438.699629 -378.801564) (xy 438.656761 -378.837239) (xy 438.609155 -378.866293)
			(xy 438.557826 -378.888105) (xy 438.503869 -378.902211) (xy 438.448432 -378.908311) (xy 438.392698 -378.906274)
			(xy 438.337855 -378.896144) (xy 438.285071 -378.878137) (xy 438.235471 -378.852636) (xy 438.190113 -378.820185)
			(xy 438.149964 -378.781476) (xy 438.115878 -378.737333) (xy 438.088582 -378.688698) (xy 438.068659 -378.636607)
			(xy 438.056533 -378.58217) (xy 438.052462 -378.526548) (xy 433.7812 -378.526548) (xy 433.7812 -379.669548)
			(xy 460.297782 -379.669548) (xy 460.301853 -379.613926) (xy 460.313979 -379.559489) (xy 460.333902 -379.507398)
			(xy 460.361198 -379.458763) (xy 460.395284 -379.41462) (xy 460.435433 -379.375911) (xy 460.480791 -379.34346)
			(xy 460.530391 -379.317959) (xy 460.583175 -379.299952) (xy 460.638018 -379.289822) (xy 460.693752 -379.287785)
			(xy 460.749189 -379.293885) (xy 460.803146 -379.307991) (xy 460.854475 -379.329803) (xy 460.902081 -379.358857)
			(xy 460.944949 -379.394532) (xy 460.982166 -379.436069) (xy 461.012939 -379.482582) (xy 461.036611 -379.533079)
			(xy 461.052679 -379.586486) (xy 461.060799 -379.641662) (xy 461.061308 -379.669548) (xy 461.060799 -379.697434)
			(xy 461.052679 -379.75261) (xy 461.036611 -379.806017) (xy 461.012939 -379.856514) (xy 460.982166 -379.903027)
			(xy 460.944949 -379.944564) (xy 460.902081 -379.980239) (xy 460.854475 -380.009293) (xy 460.803146 -380.031105)
			(xy 460.749189 -380.045211) (xy 460.693752 -380.051311) (xy 460.638018 -380.049274) (xy 460.583175 -380.039144)
			(xy 460.530391 -380.021137) (xy 460.480791 -379.995636) (xy 460.435433 -379.963185) (xy 460.395284 -379.924476)
			(xy 460.361198 -379.880333) (xy 460.333902 -379.831698) (xy 460.313979 -379.779607) (xy 460.301853 -379.72517)
			(xy 460.297782 -379.669548) (xy 433.7812 -379.669548) (xy 433.7812 -380.05258) (xy 438.059828 -380.05258)
			(xy 438.063899 -379.996958) (xy 438.076025 -379.942521) (xy 438.095948 -379.89043) (xy 438.123244 -379.841795)
			(xy 438.15733 -379.797652) (xy 438.197479 -379.758943) (xy 438.242837 -379.726492) (xy 438.292437 -379.700991)
			(xy 438.345221 -379.682984) (xy 438.400064 -379.672854) (xy 438.455798 -379.670817) (xy 438.511235 -379.676917)
			(xy 438.565192 -379.691023) (xy 438.616521 -379.712835) (xy 438.664127 -379.741889) (xy 438.706995 -379.777564)
			(xy 438.744212 -379.819101) (xy 438.774985 -379.865614) (xy 438.798657 -379.916111) (xy 438.814725 -379.969518)
			(xy 438.822845 -380.024694) (xy 438.823354 -380.05258) (xy 438.822845 -380.080466) (xy 438.814725 -380.135642)
			(xy 438.798657 -380.189049) (xy 438.774985 -380.239546) (xy 438.744212 -380.286059) (xy 438.706995 -380.327596)
			(xy 438.664127 -380.363271) (xy 438.616521 -380.392325) (xy 438.565192 -380.414137) (xy 438.511235 -380.428243)
			(xy 438.455798 -380.434343) (xy 438.400064 -380.432306) (xy 438.345221 -380.422176) (xy 438.292437 -380.404169)
			(xy 438.242837 -380.378668) (xy 438.197479 -380.346217) (xy 438.15733 -380.307508) (xy 438.123244 -380.263365)
			(xy 438.095948 -380.21473) (xy 438.076025 -380.162639) (xy 438.063899 -380.108202) (xy 438.059828 -380.05258)
			(xy 433.7812 -380.05258) (xy 433.7812 -381.404114) (xy 461.463388 -381.404114) (xy 461.467459 -381.348492)
			(xy 461.479585 -381.294055) (xy 461.499508 -381.241964) (xy 461.526804 -381.193329) (xy 461.56089 -381.149186)
			(xy 461.601039 -381.110477) (xy 461.646397 -381.078026) (xy 461.695997 -381.052525) (xy 461.748781 -381.034518)
			(xy 461.803624 -381.024388) (xy 461.859358 -381.022351) (xy 461.914795 -381.028451) (xy 461.968752 -381.042557)
			(xy 462.020081 -381.064369) (xy 462.067687 -381.093423) (xy 462.110555 -381.129098) (xy 462.147772 -381.170635)
			(xy 462.178545 -381.217148) (xy 462.202217 -381.267645) (xy 462.218285 -381.321052) (xy 462.226405 -381.376228)
			(xy 462.226914 -381.404114) (xy 462.226405 -381.432) (xy 462.218285 -381.487176) (xy 462.202217 -381.540583)
			(xy 462.193558 -381.559054) (xy 463.166712 -381.559054) (xy 463.170783 -381.503432) (xy 463.182909 -381.448995)
			(xy 463.202832 -381.396904) (xy 463.230128 -381.348269) (xy 463.264214 -381.304126) (xy 463.304363 -381.265417)
			(xy 463.349721 -381.232966) (xy 463.399321 -381.207465) (xy 463.452105 -381.189458) (xy 463.506948 -381.179328)
			(xy 463.562682 -381.177291) (xy 463.618119 -381.183391) (xy 463.672076 -381.197497) (xy 463.689681 -381.204978)
			(xy 464.315048 -381.204978) (xy 464.315541 -381.17613) (xy 464.324227 -381.119091) (xy 464.341412 -381.064014)
			(xy 464.366703 -381.012157) (xy 464.399522 -380.964704) (xy 464.418934 -380.943358) (xy 464.429105 -380.931769)
			(xy 464.442652 -380.904088) (xy 464.447314 -380.873626) (xy 464.442667 -380.843161) (xy 464.429135 -380.815473)
			(xy 464.418934 -380.803912) (xy 464.399513 -380.782577) (xy 464.366716 -380.735113) (xy 464.341441 -380.683251)
			(xy 464.324264 -380.628174) (xy 464.315577 -380.571139) (xy 464.315048 -380.542292) (xy 464.31557 -380.515043)
			(xy 464.323327 -380.461098) (xy 464.338681 -380.408807) (xy 464.361319 -380.359233) (xy 464.390782 -380.313384)
			(xy 464.42647 -380.272195) (xy 464.467656 -380.236504) (xy 464.513501 -380.207037) (xy 464.563073 -380.184393)
			(xy 464.615363 -380.169034) (xy 464.669307 -380.161273) (xy 464.696556 -380.160784) (xy 464.725296 -380.161278)
			(xy 464.782124 -380.169908) (xy 464.837015 -380.186966) (xy 464.888727 -380.212064) (xy 464.936088 -380.244635)
			(xy 464.957414 -380.263908) (xy 464.968948 -380.27398) (xy 464.996494 -380.287322) (xy 465.026756 -380.291907)
			(xy 465.057018 -380.287322) (xy 465.084564 -380.27398) (xy 465.096098 -380.263908) (xy 465.117398 -380.244606)
			(xy 465.164768 -380.212045) (xy 465.216486 -380.186959) (xy 465.271383 -380.169916) (xy 465.328215 -380.161301)
			(xy 465.356956 -380.160784) (xy 465.384207 -380.161296) (xy 465.438156 -380.169047) (xy 465.490453 -380.184397)
			(xy 465.540032 -380.207034) (xy 465.585885 -380.236496) (xy 465.627078 -380.272185) (xy 465.662772 -380.313373)
			(xy 465.692241 -380.359222) (xy 465.714885 -380.408799) (xy 465.730242 -380.461093) (xy 465.738 -380.515041)
			(xy 465.738464 -380.542292) (xy 465.737949 -380.571139) (xy 465.729268 -380.628177) (xy 465.712088 -380.683254)
			(xy 465.686802 -380.735112) (xy 465.653988 -380.782565) (xy 465.634578 -380.803912) (xy 465.624387 -380.815468)
			(xy 465.610927 -380.843173) (xy 465.606307 -380.873626) (xy 465.610943 -380.904076) (xy 465.624416 -380.931774)
			(xy 465.634578 -380.943358) (xy 465.653987 -380.964704) (xy 465.686785 -381.012165) (xy 465.712063 -381.064025)
			(xy 465.729243 -381.119099) (xy 465.737933 -381.176132) (xy 465.738464 -381.204978) (xy 465.738024 -381.232232)
			(xy 465.730269 -381.286186) (xy 465.714913 -381.338487) (xy 465.69227 -381.38807) (xy 465.662801 -381.433926)
			(xy 465.627104 -381.47512) (xy 465.585908 -381.510814) (xy 465.540051 -381.540281) (xy 465.490467 -381.562921)
			(xy 465.438165 -381.578274) (xy 465.38421 -381.586026) (xy 465.356956 -381.586486) (xy 465.328217 -381.585966)
			(xy 465.271391 -381.577339) (xy 465.216501 -381.560287) (xy 465.164789 -381.535195) (xy 465.117426 -381.502631)
			(xy 465.096098 -381.483362) (xy 465.084564 -381.47329) (xy 465.057018 -381.459948) (xy 465.026756 -381.455363)
			(xy 464.996494 -381.459948) (xy 464.968948 -381.47329) (xy 464.957414 -381.483362) (xy 464.936105 -381.502654)
			(xy 464.888738 -381.535217) (xy 464.837022 -381.560305) (xy 464.782127 -381.577351) (xy 464.725296 -381.585968)
			(xy 464.696556 -381.586486) (xy 464.669303 -381.586063) (xy 464.615352 -381.5783) (xy 464.563054 -381.562938)
			(xy 464.513475 -381.54029) (xy 464.467624 -381.510817) (xy 464.426434 -381.475119) (xy 464.390743 -381.433923)
			(xy 464.361278 -381.388067) (xy 464.338639 -381.338484) (xy 464.323286 -381.286184) (xy 464.315532 -381.232231)
			(xy 464.315048 -381.204978) (xy 463.689681 -381.204978) (xy 463.723405 -381.219309) (xy 463.771011 -381.248363)
			(xy 463.813879 -381.284038) (xy 463.851096 -381.325575) (xy 463.881869 -381.372088) (xy 463.905541 -381.422585)
			(xy 463.921609 -381.475992) (xy 463.929729 -381.531168) (xy 463.930238 -381.559054) (xy 463.929729 -381.58694)
			(xy 463.921609 -381.642116) (xy 463.905541 -381.695523) (xy 463.881869 -381.74602) (xy 463.851096 -381.792533)
			(xy 463.813879 -381.83407) (xy 463.771011 -381.869745) (xy 463.723405 -381.898799) (xy 463.672076 -381.920611)
			(xy 463.618119 -381.934717) (xy 463.562682 -381.940817) (xy 463.506948 -381.93878) (xy 463.452105 -381.92865)
			(xy 463.399321 -381.910643) (xy 463.349721 -381.885142) (xy 463.304363 -381.852691) (xy 463.264214 -381.813982)
			(xy 463.230128 -381.769839) (xy 463.202832 -381.721204) (xy 463.182909 -381.669113) (xy 463.170783 -381.614676)
			(xy 463.166712 -381.559054) (xy 462.193558 -381.559054) (xy 462.178545 -381.59108) (xy 462.147772 -381.637593)
			(xy 462.110555 -381.67913) (xy 462.067687 -381.714805) (xy 462.020081 -381.743859) (xy 461.968752 -381.765671)
			(xy 461.914795 -381.779777) (xy 461.859358 -381.785877) (xy 461.803624 -381.78384) (xy 461.748781 -381.77371)
			(xy 461.695997 -381.755703) (xy 461.646397 -381.730202) (xy 461.601039 -381.697751) (xy 461.56089 -381.659042)
			(xy 461.526804 -381.614899) (xy 461.499508 -381.566264) (xy 461.479585 -381.514173) (xy 461.467459 -381.459736)
			(xy 461.463388 -381.404114) (xy 433.7812 -381.404114) (xy 433.7812 -382.524553) (xy 437.679785 -382.524553)
			(xy 437.679785 -382.470047) (xy 437.687543 -382.416096) (xy 437.7029 -382.363799) (xy 437.725544 -382.31422)
			(xy 437.755014 -382.268368) (xy 437.79071 -382.227177) (xy 437.831905 -382.191487) (xy 437.87776 -382.162022)
			(xy 437.927342 -382.139384) (xy 437.979641 -382.124033) (xy 438.033593 -382.116282) (xy 438.060846 -382.115822)
			(xy 438.090076 -382.11638) (xy 438.147851 -382.125317) (xy 438.203586 -382.142959) (xy 438.25598 -382.168894)
			(xy 438.303805 -382.202516) (xy 438.345945 -382.243038) (xy 438.364122 -382.265936) (xy 438.37256 -382.276333)
			(xy 438.393764 -382.29267) (xy 438.418483 -382.302943) (xy 438.445021 -382.306448) (xy 438.471559 -382.302943)
			(xy 438.496278 -382.29267) (xy 438.517482 -382.276333) (xy 438.52592 -382.265936) (xy 438.544107 -382.243043)
			(xy 438.586231 -382.2025) (xy 438.634051 -382.168863) (xy 438.686444 -382.14292) (xy 438.742184 -382.125279)
			(xy 438.799964 -382.116353) (xy 438.829196 -382.115822) (xy 438.856451 -382.116225) (xy 438.910407 -382.123982)
			(xy 438.962709 -382.139339) (xy 439.012294 -382.161983) (xy 439.058151 -382.191453) (xy 439.099348 -382.227149)
			(xy 439.135045 -382.268346) (xy 439.164515 -382.314203) (xy 439.171008 -382.32842) (xy 456.932282 -382.32842)
			(xy 456.936353 -382.272798) (xy 456.948479 -382.218361) (xy 456.968402 -382.16627) (xy 456.995698 -382.117635)
			(xy 457.029784 -382.073492) (xy 457.069933 -382.034783) (xy 457.115291 -382.002332) (xy 457.164891 -381.976831)
			(xy 457.217675 -381.958824) (xy 457.272518 -381.948694) (xy 457.328252 -381.946657) (xy 457.383689 -381.952757)
			(xy 457.437646 -381.966863) (xy 457.488975 -381.988675) (xy 457.536581 -382.017729) (xy 457.579449 -382.053404)
			(xy 457.616666 -382.094941) (xy 457.647439 -382.141454) (xy 457.671111 -382.191951) (xy 457.687179 -382.245358)
			(xy 457.695299 -382.300534) (xy 457.695808 -382.32842) (xy 457.695299 -382.356306) (xy 457.687179 -382.411482)
			(xy 457.678163 -382.44145) (xy 458.634082 -382.44145) (xy 458.638153 -382.385828) (xy 458.650279 -382.331391)
			(xy 458.670202 -382.2793) (xy 458.697498 -382.230665) (xy 458.731584 -382.186522) (xy 458.771733 -382.147813)
			(xy 458.817091 -382.115362) (xy 458.866691 -382.089861) (xy 458.919475 -382.071854) (xy 458.974318 -382.061724)
			(xy 459.030052 -382.059687) (xy 459.085489 -382.065787) (xy 459.139446 -382.079893) (xy 459.190775 -382.101705)
			(xy 459.238381 -382.130759) (xy 459.281249 -382.166434) (xy 459.318466 -382.207971) (xy 459.349239 -382.254484)
			(xy 459.372911 -382.304981) (xy 459.388979 -382.358388) (xy 459.389017 -382.358646) (xy 459.737458 -382.358646)
			(xy 459.741529 -382.303024) (xy 459.753655 -382.248587) (xy 459.773578 -382.196496) (xy 459.800874 -382.147861)
			(xy 459.83496 -382.103718) (xy 459.875109 -382.065009) (xy 459.920467 -382.032558) (xy 459.970067 -382.007057)
			(xy 460.022851 -381.98905) (xy 460.077694 -381.97892) (xy 460.133428 -381.976883) (xy 460.188865 -381.982983)
			(xy 460.242822 -381.997089) (xy 460.294151 -382.018901) (xy 460.341757 -382.047955) (xy 460.384625 -382.08363)
			(xy 460.421842 -382.125167) (xy 460.452615 -382.17168) (xy 460.476287 -382.222177) (xy 460.492355 -382.275584)
			(xy 460.500475 -382.33076) (xy 460.500984 -382.358646) (xy 460.500475 -382.386532) (xy 460.492355 -382.441708)
			(xy 460.476287 -382.495115) (xy 460.452615 -382.545612) (xy 460.421842 -382.592125) (xy 460.384625 -382.633662)
			(xy 460.341757 -382.669337) (xy 460.294151 -382.698391) (xy 460.242822 -382.720203) (xy 460.188865 -382.734309)
			(xy 460.133428 -382.740409) (xy 460.077694 -382.738372) (xy 460.022851 -382.728242) (xy 459.970067 -382.710235)
			(xy 459.920467 -382.684734) (xy 459.875109 -382.652283) (xy 459.83496 -382.613574) (xy 459.800874 -382.569431)
			(xy 459.773578 -382.520796) (xy 459.753655 -382.468705) (xy 459.741529 -382.414268) (xy 459.737458 -382.358646)
			(xy 459.389017 -382.358646) (xy 459.397099 -382.413564) (xy 459.397608 -382.44145) (xy 459.397099 -382.469336)
			(xy 459.388979 -382.524512) (xy 459.372911 -382.577919) (xy 459.349239 -382.628416) (xy 459.318466 -382.674929)
			(xy 459.281249 -382.716466) (xy 459.238381 -382.752141) (xy 459.190775 -382.781195) (xy 459.139446 -382.803007)
			(xy 459.085489 -382.817113) (xy 459.030052 -382.823213) (xy 458.974318 -382.821176) (xy 458.919475 -382.811046)
			(xy 458.866691 -382.793039) (xy 458.817091 -382.767538) (xy 458.771733 -382.735087) (xy 458.731584 -382.696378)
			(xy 458.697498 -382.652235) (xy 458.670202 -382.6036) (xy 458.650279 -382.551509) (xy 458.638153 -382.497072)
			(xy 458.634082 -382.44145) (xy 457.678163 -382.44145) (xy 457.671111 -382.464889) (xy 457.647439 -382.515386)
			(xy 457.616666 -382.561899) (xy 457.579449 -382.603436) (xy 457.536581 -382.639111) (xy 457.488975 -382.668165)
			(xy 457.437646 -382.689977) (xy 457.383689 -382.704083) (xy 457.328252 -382.710183) (xy 457.272518 -382.708146)
			(xy 457.217675 -382.698016) (xy 457.164891 -382.680009) (xy 457.115291 -382.654508) (xy 457.069933 -382.622057)
			(xy 457.029784 -382.583348) (xy 456.995698 -382.539205) (xy 456.968402 -382.49057) (xy 456.948479 -382.438479)
			(xy 456.936353 -382.384042) (xy 456.932282 -382.32842) (xy 439.171008 -382.32842) (xy 439.18716 -382.363787)
			(xy 439.202517 -382.416089) (xy 439.210275 -382.470045) (xy 439.210275 -382.524555) (xy 439.202517 -382.578511)
			(xy 439.18716 -382.630813) (xy 439.164515 -382.680397) (xy 439.135045 -382.726254) (xy 439.099348 -382.767451)
			(xy 439.058151 -382.803147) (xy 439.012294 -382.832617) (xy 438.962709 -382.855261) (xy 438.910407 -382.870618)
			(xy 438.856451 -382.878375) (xy 438.829196 -382.878838) (xy 438.799966 -382.878266) (xy 438.742192 -382.869334)
			(xy 438.686456 -382.851696) (xy 438.634062 -382.825763) (xy 438.586236 -382.792143) (xy 438.544097 -382.751622)
			(xy 438.52592 -382.728724) (xy 438.517509 -382.718283) (xy 438.496323 -382.701865) (xy 438.471591 -382.691536)
			(xy 438.445021 -382.688012) (xy 438.418451 -382.691536) (xy 438.393719 -382.701865) (xy 438.372533 -382.718283)
			(xy 438.364122 -382.728724) (xy 438.345962 -382.751639) (xy 438.303829 -382.792173) (xy 438.256003 -382.825801)
			(xy 438.203604 -382.851735) (xy 438.14786 -382.869367) (xy 438.090079 -382.878283) (xy 438.060846 -382.878838)
			(xy 438.033593 -382.878318) (xy 437.979641 -382.870567) (xy 437.927342 -382.855216) (xy 437.87776 -382.832578)
			(xy 437.831905 -382.803113) (xy 437.79071 -382.767423) (xy 437.755014 -382.726232) (xy 437.725544 -382.68038)
			(xy 437.7029 -382.630801) (xy 437.687543 -382.578504) (xy 437.679785 -382.524553) (xy 433.7812 -382.524553)
			(xy 433.7812 -382.903853) (xy 442.76693 -382.903853) (xy 442.76693 -382.849347) (xy 442.774686 -382.795396)
			(xy 442.790041 -382.743098) (xy 442.812682 -382.693518) (xy 442.842148 -382.647664) (xy 442.87784 -382.606469)
			(xy 442.91903 -382.570773) (xy 442.964881 -382.541302) (xy 443.014459 -382.518656) (xy 443.066755 -382.503295)
			(xy 443.120705 -382.495533) (xy 443.147958 -382.495044) (xy 443.176875 -382.495576) (xy 443.234046 -382.5043)
			(xy 443.289245 -382.521554) (xy 443.341207 -382.546943) (xy 443.388742 -382.579885) (xy 443.430758 -382.619625)
			(xy 443.448948 -382.64211) (xy 443.458845 -382.653915) (xy 443.484169 -382.671434) (xy 443.513562 -382.68061)
			(xy 443.544354 -382.68061) (xy 443.573747 -382.671434) (xy 443.599071 -382.653915) (xy 443.608968 -382.64211)
			(xy 443.62718 -382.619644) (xy 443.669195 -382.579907) (xy 443.716725 -382.546966) (xy 443.768683 -382.521574)
			(xy 443.823877 -382.504314) (xy 443.881043 -382.495581) (xy 443.909958 -382.495044) (xy 443.937209 -382.4956)
			(xy 443.991158 -382.503351) (xy 444.043454 -382.518702) (xy 444.093034 -382.541339) (xy 444.138886 -382.570802)
			(xy 444.180079 -382.606492) (xy 444.215772 -382.64768) (xy 444.245241 -382.69353) (xy 444.267883 -382.743106)
			(xy 444.28324 -382.795401) (xy 444.290997 -382.849349) (xy 444.290997 -382.903851) (xy 444.28324 -382.957799)
			(xy 444.26958 -383.004314) (xy 460.372458 -383.004314) (xy 460.376529 -382.948692) (xy 460.388655 -382.894255)
			(xy 460.408578 -382.842164) (xy 460.435874 -382.793529) (xy 460.46996 -382.749386) (xy 460.510109 -382.710677)
			(xy 460.555467 -382.678226) (xy 460.605067 -382.652725) (xy 460.657851 -382.634718) (xy 460.712694 -382.624588)
			(xy 460.768428 -382.622551) (xy 460.823865 -382.628651) (xy 460.877822 -382.642757) (xy 460.929151 -382.664569)
			(xy 460.976757 -382.693623) (xy 461.019625 -382.729298) (xy 461.056842 -382.770835) (xy 461.087615 -382.817348)
			(xy 461.111287 -382.867845) (xy 461.127355 -382.921252) (xy 461.135475 -382.976428) (xy 461.135984 -383.004314)
			(xy 461.135475 -383.0322) (xy 461.127355 -383.087376) (xy 461.111287 -383.140783) (xy 461.087615 -383.19128)
			(xy 461.056842 -383.237793) (xy 461.019625 -383.27933) (xy 460.976757 -383.315005) (xy 460.929151 -383.344059)
			(xy 460.877822 -383.365871) (xy 460.823865 -383.379977) (xy 460.768428 -383.386077) (xy 460.712694 -383.38404)
			(xy 460.657851 -383.37391) (xy 460.605067 -383.355903) (xy 460.555467 -383.330402) (xy 460.510109 -383.297951)
			(xy 460.46996 -383.259242) (xy 460.435874 -383.215099) (xy 460.408578 -383.166464) (xy 460.388655 -383.114373)
			(xy 460.376529 -383.059936) (xy 460.372458 -383.004314) (xy 444.26958 -383.004314) (xy 444.267883 -383.010094)
			(xy 444.245241 -383.05967) (xy 444.215772 -383.10552) (xy 444.180079 -383.146708) (xy 444.138886 -383.182398)
			(xy 444.093034 -383.211861) (xy 444.043454 -383.234498) (xy 443.991158 -383.249849) (xy 443.937209 -383.2576)
			(xy 443.909958 -383.25806) (xy 443.881042 -383.257515) (xy 443.823871 -383.248794) (xy 443.768672 -383.231542)
			(xy 443.71671 -383.206156) (xy 443.669176 -383.173216) (xy 443.627158 -383.133478) (xy 443.608968 -383.110994)
			(xy 443.599071 -383.099189) (xy 443.573747 -383.08167) (xy 443.544354 -383.072494) (xy 443.513562 -383.072494)
			(xy 443.484169 -383.08167) (xy 443.458845 -383.099189) (xy 443.448948 -383.110994) (xy 443.430728 -383.133453)
			(xy 443.388715 -383.17319) (xy 443.341186 -383.206132) (xy 443.28923 -383.231525) (xy 443.234038 -383.248786)
			(xy 443.176872 -383.257522) (xy 443.147958 -383.25806) (xy 443.120705 -383.257667) (xy 443.066755 -383.249905)
			(xy 443.014459 -383.234544) (xy 442.964881 -383.211898) (xy 442.91903 -383.182427) (xy 442.87784 -383.146731)
			(xy 442.842148 -383.105536) (xy 442.812682 -383.059682) (xy 442.790041 -383.010102) (xy 442.774686 -382.957804)
			(xy 442.76693 -382.903853) (xy 433.7812 -382.903853) (xy 433.7812 -384.569253) (xy 437.679785 -384.569253)
			(xy 437.679785 -384.514747) (xy 437.687543 -384.460796) (xy 437.7029 -384.408499) (xy 437.725544 -384.35892)
			(xy 437.755014 -384.313068) (xy 437.79071 -384.271877) (xy 437.831905 -384.236187) (xy 437.87776 -384.206722)
			(xy 437.927342 -384.184084) (xy 437.979641 -384.168733) (xy 438.033593 -384.160982) (xy 438.060846 -384.160522)
			(xy 438.090076 -384.16108) (xy 438.147851 -384.170017) (xy 438.203586 -384.187659) (xy 438.25598 -384.213594)
			(xy 438.303805 -384.247216) (xy 438.345945 -384.287738) (xy 438.364122 -384.310636) (xy 438.37256 -384.321033)
			(xy 438.393764 -384.33737) (xy 438.418483 -384.347643) (xy 438.445021 -384.351148) (xy 438.471559 -384.347643)
			(xy 438.496278 -384.33737) (xy 438.517482 -384.321033) (xy 438.52592 -384.310636) (xy 438.544107 -384.287743)
			(xy 438.586231 -384.2472) (xy 438.634051 -384.213563) (xy 438.686444 -384.18762) (xy 438.742184 -384.169979)
			(xy 438.799964 -384.161053) (xy 438.829196 -384.160522) (xy 438.856451 -384.160925) (xy 438.910407 -384.168682)
			(xy 438.962709 -384.184039) (xy 439.012294 -384.206683) (xy 439.058151 -384.236153) (xy 439.099348 -384.271849)
			(xy 439.135045 -384.313046) (xy 439.164515 -384.358903) (xy 439.18716 -384.408487) (xy 439.202517 -384.460789)
			(xy 439.210275 -384.514745) (xy 439.210275 -384.569255) (xy 439.202517 -384.623211) (xy 439.18716 -384.675513)
			(xy 439.164515 -384.725097) (xy 439.135045 -384.770954) (xy 439.099348 -384.812151) (xy 439.058151 -384.847847)
			(xy 439.012294 -384.877317) (xy 438.962709 -384.899961) (xy 438.910407 -384.915318) (xy 438.856451 -384.923075)
			(xy 438.829196 -384.923538) (xy 438.799966 -384.922966) (xy 438.742192 -384.914034) (xy 438.686456 -384.896396)
			(xy 438.634062 -384.870463) (xy 438.586236 -384.836843) (xy 438.544097 -384.796322) (xy 438.52592 -384.773424)
			(xy 438.517509 -384.762983) (xy 438.496323 -384.746565) (xy 438.471591 -384.736236) (xy 438.445021 -384.732712)
			(xy 438.418451 -384.736236) (xy 438.393719 -384.746565) (xy 438.372533 -384.762983) (xy 438.364122 -384.773424)
			(xy 438.345962 -384.796339) (xy 438.303829 -384.836873) (xy 438.256003 -384.870501) (xy 438.203604 -384.896435)
			(xy 438.14786 -384.914067) (xy 438.090079 -384.922983) (xy 438.060846 -384.923538) (xy 438.033593 -384.923018)
			(xy 437.979641 -384.915267) (xy 437.927342 -384.899916) (xy 437.87776 -384.877278) (xy 437.831905 -384.847813)
			(xy 437.79071 -384.812123) (xy 437.755014 -384.770932) (xy 437.725544 -384.72508) (xy 437.7029 -384.675501)
			(xy 437.687543 -384.623204) (xy 437.679785 -384.569253) (xy 433.7812 -384.569253) (xy 433.7812 -386.348858)
			(xy 438.101609 -386.348858) (xy 438.101609 -386.294342) (xy 438.109368 -386.240381) (xy 438.124728 -386.188074)
			(xy 438.147376 -386.138485) (xy 438.176851 -386.092624) (xy 438.212554 -386.051425) (xy 438.253756 -386.015727)
			(xy 438.29962 -385.986257) (xy 438.349211 -385.963614) (xy 438.40152 -385.94826) (xy 438.455482 -385.940506)
			(xy 438.48274 -385.940046) (xy 438.511656 -385.94059) (xy 438.568827 -385.949311) (xy 438.624026 -385.966563)
			(xy 438.675988 -385.991949) (xy 438.723523 -386.024889) (xy 438.76554 -386.064628) (xy 438.78373 -386.087112)
			(xy 438.793627 -386.098917) (xy 438.818951 -386.116436) (xy 438.848344 -386.125612) (xy 438.879136 -386.125612)
			(xy 438.908529 -386.116436) (xy 438.933853 -386.098917) (xy 438.94375 -386.087112) (xy 438.960503 -386.066329)
			(xy 438.998857 -386.029199) (xy 439.042011 -385.997777) (xy 439.089125 -385.972678) (xy 439.139277 -385.954392)
			(xy 439.191488 -385.943275) (xy 439.24474 -385.939545) (xy 439.297992 -385.943275) (xy 439.350203 -385.954392)
			(xy 439.400355 -385.972678) (xy 439.447469 -385.997777) (xy 439.490623 -386.029199) (xy 439.528977 -386.066329)
			(xy 439.54573 -386.087112) (xy 439.555627 -386.098917) (xy 439.580951 -386.116436) (xy 439.610344 -386.125612)
			(xy 439.641136 -386.125612) (xy 439.670529 -386.116436) (xy 439.695853 -386.098917) (xy 439.70575 -386.087112)
			(xy 439.722503 -386.066329) (xy 439.760857 -386.029199) (xy 439.804011 -385.997777) (xy 439.851125 -385.972678)
			(xy 439.901277 -385.954392) (xy 439.953488 -385.943275) (xy 440.00674 -385.939545) (xy 440.059992 -385.943275)
			(xy 440.112203 -385.954392) (xy 440.162355 -385.972678) (xy 440.209469 -385.997777) (xy 440.252623 -386.029199)
			(xy 440.290977 -386.066329) (xy 440.30773 -386.087112) (xy 440.317627 -386.098917) (xy 440.342951 -386.116436)
			(xy 440.372344 -386.125612) (xy 440.403136 -386.125612) (xy 440.432529 -386.116436) (xy 440.457853 -386.098917)
			(xy 440.46775 -386.087112) (xy 440.485972 -386.064655) (xy 440.527985 -386.024918) (xy 440.575513 -385.991975)
			(xy 440.627469 -385.966582) (xy 440.682661 -385.94932) (xy 440.739826 -385.940585) (xy 440.76874 -385.940046)
			(xy 440.795986 -385.940627) (xy 440.849923 -385.948387) (xy 440.902206 -385.963744) (xy 440.951773 -385.986384)
			(xy 440.997612 -386.015848) (xy 441.038793 -386.051535) (xy 441.074476 -386.09272) (xy 441.103935 -386.138563)
			(xy 441.12657 -386.188131) (xy 441.141921 -386.240416) (xy 441.149676 -386.294354) (xy 441.149676 -386.348846)
			(xy 441.141921 -386.402784) (xy 441.12657 -386.455069) (xy 441.103935 -386.504637) (xy 441.074476 -386.55048)
			(xy 441.038793 -386.591665) (xy 440.997612 -386.627352) (xy 440.951773 -386.656816) (xy 440.902206 -386.679456)
			(xy 440.849923 -386.694813) (xy 440.795986 -386.702573) (xy 440.76874 -386.703062) (xy 440.739823 -386.702529)
			(xy 440.682652 -386.693805) (xy 440.627453 -386.676551) (xy 440.575491 -386.651162) (xy 440.527957 -386.618221)
			(xy 440.48594 -386.578481) (xy 440.46775 -386.555996) (xy 440.457853 -386.544191) (xy 440.432529 -386.526672)
			(xy 440.403136 -386.517496) (xy 440.372344 -386.517496) (xy 440.342951 -386.526672) (xy 440.317627 -386.544191)
			(xy 440.30773 -386.555996) (xy 440.290977 -386.576779) (xy 440.252623 -386.613909) (xy 440.209469 -386.645331)
			(xy 440.162355 -386.67043) (xy 440.112203 -386.688716) (xy 440.059992 -386.699833) (xy 440.00674 -386.703563)
			(xy 439.953488 -386.699833) (xy 439.901277 -386.688716) (xy 439.851125 -386.67043) (xy 439.804011 -386.645331)
			(xy 439.760857 -386.613909) (xy 439.722503 -386.576779) (xy 439.70575 -386.555996) (xy 439.695853 -386.544191)
			(xy 439.670529 -386.526672) (xy 439.641136 -386.517496) (xy 439.610344 -386.517496) (xy 439.580951 -386.526672)
			(xy 439.555627 -386.544191) (xy 439.54573 -386.555996) (xy 439.528977 -386.576779) (xy 439.490623 -386.613909)
			(xy 439.447469 -386.645331) (xy 439.400355 -386.67043) (xy 439.350203 -386.688716) (xy 439.297992 -386.699833)
			(xy 439.24474 -386.703563) (xy 439.191488 -386.699833) (xy 439.139277 -386.688716) (xy 439.089125 -386.67043)
			(xy 439.042011 -386.645331) (xy 438.998857 -386.613909) (xy 438.960503 -386.576779) (xy 438.94375 -386.555996)
			(xy 438.933853 -386.544191) (xy 438.908529 -386.526672) (xy 438.879136 -386.517496) (xy 438.848344 -386.517496)
			(xy 438.818951 -386.526672) (xy 438.793627 -386.544191) (xy 438.78373 -386.555996) (xy 438.765521 -386.578464)
			(xy 438.723505 -386.618201) (xy 438.675974 -386.651142) (xy 438.624016 -386.676533) (xy 438.568822 -386.693792)
			(xy 438.511655 -386.702525) (xy 438.48274 -386.703062) (xy 438.455482 -386.702694) (xy 438.40152 -386.69494)
			(xy 438.349211 -386.679586) (xy 438.29962 -386.656943) (xy 438.253756 -386.627473) (xy 438.212554 -386.591775)
			(xy 438.176851 -386.550576) (xy 438.147376 -386.504715) (xy 438.124728 -386.455126) (xy 438.109368 -386.402819)
			(xy 438.101609 -386.348858) (xy 433.7812 -386.348858) (xy 433.7812 -387.371153) (xy 442.672159 -387.371153)
			(xy 442.672159 -387.316647) (xy 442.679917 -387.262695) (xy 442.695273 -387.210396) (xy 442.717917 -387.160816)
			(xy 442.747386 -387.114962) (xy 442.783081 -387.07377) (xy 442.824275 -387.038076) (xy 442.87013 -387.008609)
			(xy 442.919711 -386.985968) (xy 442.972011 -386.970613) (xy 443.025963 -386.962858) (xy 443.053216 -386.962396)
			(xy 443.082132 -386.962938) (xy 443.139304 -386.971657) (xy 443.194504 -386.988908) (xy 443.246467 -387.014295)
			(xy 443.294001 -387.047236) (xy 443.336017 -387.086977) (xy 443.354206 -387.109462) (xy 443.364103 -387.121267)
			(xy 443.389427 -387.138786) (xy 443.41882 -387.147962) (xy 443.449612 -387.147962) (xy 443.479005 -387.138786)
			(xy 443.504329 -387.121267) (xy 443.514226 -387.109462) (xy 443.532393 -387.086958) (xy 443.574419 -387.047226)
			(xy 443.621959 -387.01429) (xy 443.673925 -386.988906) (xy 443.729126 -386.971654) (xy 443.786299 -386.962929)
			(xy 443.815216 -386.962396) (xy 443.842467 -386.962875) (xy 443.896413 -386.970633) (xy 443.948707 -386.98599)
			(xy 443.998282 -387.008632) (xy 444.044131 -387.038099) (xy 444.08532 -387.073791) (xy 444.12101 -387.114981)
			(xy 444.150475 -387.160832) (xy 444.173116 -387.210408) (xy 444.18847 -387.262702) (xy 444.191125 -387.281166)
			(xy 455.690476 -387.281166) (xy 455.694547 -387.225544) (xy 455.706673 -387.171107) (xy 455.726596 -387.119016)
			(xy 455.753892 -387.070381) (xy 455.787978 -387.026238) (xy 455.828127 -386.987529) (xy 455.873485 -386.955078)
			(xy 455.923085 -386.929577) (xy 455.975869 -386.91157) (xy 456.030712 -386.90144) (xy 456.086446 -386.899403)
			(xy 456.141883 -386.905503) (xy 456.19584 -386.919609) (xy 456.247169 -386.941421) (xy 456.294775 -386.970475)
			(xy 456.337643 -387.00615) (xy 456.37486 -387.047687) (xy 456.405633 -387.0942) (xy 456.429305 -387.144697)
			(xy 456.445373 -387.198104) (xy 456.453493 -387.25328) (xy 456.454002 -387.281166) (xy 456.453493 -387.309052)
			(xy 456.445373 -387.364228) (xy 456.429305 -387.417635) (xy 456.405633 -387.468132) (xy 456.37486 -387.514645)
			(xy 456.337643 -387.556182) (xy 456.294775 -387.591857) (xy 456.247169 -387.620911) (xy 456.19584 -387.642723)
			(xy 456.141883 -387.656829) (xy 456.086446 -387.662929) (xy 456.030712 -387.660892) (xy 455.975869 -387.650762)
			(xy 455.923085 -387.632755) (xy 455.873485 -387.607254) (xy 455.828127 -387.574803) (xy 455.787978 -387.536094)
			(xy 455.753892 -387.491951) (xy 455.726596 -387.443316) (xy 455.706673 -387.391225) (xy 455.694547 -387.336788)
			(xy 455.690476 -387.281166) (xy 444.191125 -387.281166) (xy 444.196226 -387.316649) (xy 444.196226 -387.371151)
			(xy 444.18847 -387.425098) (xy 444.173116 -387.477392) (xy 444.150475 -387.526968) (xy 444.12101 -387.572819)
			(xy 444.08532 -387.614009) (xy 444.044131 -387.649701) (xy 443.998282 -387.679168) (xy 443.948707 -387.70181)
			(xy 443.896413 -387.717167) (xy 443.842467 -387.724925) (xy 443.815216 -387.725412) (xy 443.786298 -387.724916)
			(xy 443.729124 -387.716187) (xy 443.673923 -387.698927) (xy 443.621961 -387.673531) (xy 443.574428 -387.640582)
			(xy 443.532414 -387.600835) (xy 443.514226 -387.578346) (xy 443.504329 -387.566541) (xy 443.479005 -387.549022)
			(xy 443.449612 -387.539846) (xy 443.41882 -387.539846) (xy 443.389427 -387.549022) (xy 443.364103 -387.566541)
			(xy 443.354206 -387.578346) (xy 443.336023 -387.600836) (xy 443.294 -387.640569) (xy 443.246463 -387.673506)
			(xy 443.194501 -387.698893) (xy 443.139302 -387.716148) (xy 443.082132 -387.724877) (xy 443.053216 -387.725412)
			(xy 443.025963 -387.724942) (xy 442.972011 -387.717187) (xy 442.919711 -387.701832) (xy 442.87013 -387.679191)
			(xy 442.824275 -387.649724) (xy 442.783081 -387.61403) (xy 442.747386 -387.572838) (xy 442.717917 -387.526984)
			(xy 442.695273 -387.477404) (xy 442.679917 -387.425105) (xy 442.672159 -387.371153) (xy 433.7812 -387.371153)
			(xy 433.7812 -388.760253) (xy 438.101685 -388.760253) (xy 438.101685 -388.705747) (xy 438.109443 -388.651797)
			(xy 438.1248 -388.5995) (xy 438.147443 -388.549921) (xy 438.176913 -388.50407) (xy 438.212608 -388.46288)
			(xy 438.253802 -388.427189) (xy 438.299657 -388.397724) (xy 438.349238 -388.375086) (xy 438.401536 -388.359734)
			(xy 438.455487 -388.351983) (xy 438.48274 -388.351522) (xy 438.511656 -388.352075) (xy 438.568826 -388.360796)
			(xy 438.624024 -388.378046) (xy 438.675986 -388.403431) (xy 438.723521 -388.436369) (xy 438.765539 -388.476105)
			(xy 438.78373 -388.498588) (xy 438.793627 -388.510393) (xy 438.818951 -388.527912) (xy 438.848344 -388.537088)
			(xy 438.879136 -388.537088) (xy 438.908529 -388.527912) (xy 438.933853 -388.510393) (xy 438.94375 -388.498588)
			(xy 438.960503 -388.477805) (xy 438.998857 -388.440675) (xy 439.042011 -388.409253) (xy 439.089125 -388.384154)
			(xy 439.139277 -388.365868) (xy 439.191488 -388.354751) (xy 439.24474 -388.351021) (xy 439.297992 -388.354751)
			(xy 439.350203 -388.365868) (xy 439.400355 -388.384154) (xy 439.447469 -388.409253) (xy 439.490623 -388.440675)
			(xy 439.528977 -388.477805) (xy 439.54573 -388.498588) (xy 439.555627 -388.510393) (xy 439.580951 -388.527912)
			(xy 439.610344 -388.537088) (xy 439.641136 -388.537088) (xy 439.670529 -388.527912) (xy 439.695853 -388.510393)
			(xy 439.70575 -388.498588) (xy 439.722503 -388.477805) (xy 439.760857 -388.440675) (xy 439.804011 -388.409253)
			(xy 439.851125 -388.384154) (xy 439.901277 -388.365868) (xy 439.953488 -388.354751) (xy 440.00674 -388.351021)
			(xy 440.059992 -388.354751) (xy 440.112203 -388.365868) (xy 440.162355 -388.384154) (xy 440.209469 -388.409253)
			(xy 440.252623 -388.440675) (xy 440.290977 -388.477805) (xy 440.30773 -388.498588) (xy 440.317627 -388.510393)
			(xy 440.342951 -388.527912) (xy 440.372344 -388.537088) (xy 440.403136 -388.537088) (xy 440.432529 -388.527912)
			(xy 440.457853 -388.510393) (xy 440.46775 -388.498588) (xy 440.485966 -388.476126) (xy 440.527981 -388.43639)
			(xy 440.575511 -388.403449) (xy 440.627467 -388.378057) (xy 440.68266 -388.360796) (xy 440.739826 -388.352061)
			(xy 440.76874 -388.351522) (xy 440.795992 -388.351951) (xy 440.849939 -388.359712) (xy 440.902233 -388.375072)
			(xy 440.951809 -388.397717) (xy 440.997658 -388.427187) (xy 441.038847 -388.462881) (xy 441.074537 -388.504074)
			(xy 441.104002 -388.549926) (xy 441.126642 -388.599504) (xy 441.141996 -388.6518) (xy 441.149752 -388.705748)
			(xy 441.149752 -388.760252) (xy 441.141996 -388.8142) (xy 441.126642 -388.866496) (xy 441.104002 -388.916074)
			(xy 441.074537 -388.961926) (xy 441.038847 -389.003119) (xy 440.997658 -389.038813) (xy 440.951809 -389.068283)
			(xy 440.902233 -389.090928) (xy 440.849939 -389.106288) (xy 440.795992 -389.114049) (xy 440.76874 -389.114538)
			(xy 440.739823 -389.114015) (xy 440.682651 -389.10529) (xy 440.627451 -389.088035) (xy 440.575489 -389.062644)
			(xy 440.527955 -389.0297) (xy 440.485939 -388.989958) (xy 440.46775 -388.967472) (xy 440.457853 -388.955667)
			(xy 440.432529 -388.938148) (xy 440.403136 -388.928972) (xy 440.372344 -388.928972) (xy 440.342951 -388.938148)
			(xy 440.317627 -388.955667) (xy 440.30773 -388.967472) (xy 440.290977 -388.988255) (xy 440.252623 -389.025385)
			(xy 440.209469 -389.056807) (xy 440.162355 -389.081906) (xy 440.112203 -389.100192) (xy 440.059992 -389.111309)
			(xy 440.00674 -389.115039) (xy 439.953488 -389.111309) (xy 439.901277 -389.100192) (xy 439.851125 -389.081906)
			(xy 439.804011 -389.056807) (xy 439.760857 -389.025385) (xy 439.722503 -388.988255) (xy 439.70575 -388.967472)
			(xy 439.695853 -388.955667) (xy 439.670529 -388.938148) (xy 439.641136 -388.928972) (xy 439.610344 -388.928972)
			(xy 439.580951 -388.938148) (xy 439.555627 -388.955667) (xy 439.54573 -388.967472) (xy 439.528977 -388.988255)
			(xy 439.490623 -389.025385) (xy 439.447469 -389.056807) (xy 439.400355 -389.081906) (xy 439.350203 -389.100192)
			(xy 439.297992 -389.111309) (xy 439.24474 -389.115039) (xy 439.191488 -389.111309) (xy 439.139277 -389.100192)
			(xy 439.089125 -389.081906) (xy 439.042011 -389.056807) (xy 438.998857 -389.025385) (xy 438.960503 -388.988255)
			(xy 438.94375 -388.967472) (xy 438.933853 -388.955667) (xy 438.908529 -388.938148) (xy 438.879136 -388.928972)
			(xy 438.848344 -388.928972) (xy 438.818951 -388.938148) (xy 438.793627 -388.955667) (xy 438.78373 -388.967472)
			(xy 438.765515 -388.989935) (xy 438.723501 -389.029673) (xy 438.675971 -389.062615) (xy 438.624015 -389.088007)
			(xy 438.568821 -389.105268) (xy 438.511655 -389.114001) (xy 438.48274 -389.114538) (xy 438.455487 -389.114017)
			(xy 438.401536 -389.106266) (xy 438.349238 -389.090914) (xy 438.299657 -389.068276) (xy 438.253802 -389.038811)
			(xy 438.212608 -389.00312) (xy 438.176913 -388.96193) (xy 438.147443 -388.916079) (xy 438.1248 -388.8665)
			(xy 438.109443 -388.814203) (xy 438.101685 -388.760253) (xy 433.7812 -388.760253) (xy 433.7812 -395.4272)
			(xy 434.365146 -396.011146) (xy 465.30133 -396.011146)
		)
		(stroke
			(width 0)
			(type solid)
		)
		(fill yes)
		(layer "In13.Cu")
		(net "GND")
	)
	(gr_poly
		(pts
			(xy 260.30428 -58.346086) (xy 260.88848 -57.761886) (xy 260.88848 -49.047146) (xy 260.02488 -48.183546)
			(xy 259.716016 -48.183546) (xy 259.700897 -48.184095) (xy 259.671983 -48.192945) (xy 259.646927 -48.209874)
			(xy 259.627927 -48.233397) (xy 259.616648 -48.261453) (xy 259.614078 -48.291581) (xy 259.616702 -48.306482)
			(xy 259.620726 -48.326304) (xy 259.625055 -48.366521) (xy 259.625338 -48.386746) (xy 259.624852 -48.413997)
			(xy 259.617096 -48.467945) (xy 259.601741 -48.52024) (xy 259.579099 -48.569817) (xy 259.549633 -48.615667)
			(xy 259.513942 -48.656858) (xy 259.472751 -48.692549) (xy 259.426901 -48.722015) (xy 259.377324 -48.744657)
			(xy 259.325029 -48.760012) (xy 259.271081 -48.767768) (xy 259.216579 -48.767768) (xy 259.162631 -48.760012)
			(xy 259.110336 -48.744657) (xy 259.060759 -48.722015) (xy 259.014909 -48.692549) (xy 258.973718 -48.656858)
			(xy 258.938027 -48.615667) (xy 258.908561 -48.569817) (xy 258.885919 -48.52024) (xy 258.870564 -48.467945)
			(xy 258.862808 -48.413997) (xy 258.862322 -48.386746) (xy 258.862614 -48.366522) (xy 258.86694 -48.326305)
			(xy 258.870958 -48.306482) (xy 258.873586 -48.291588) (xy 258.870993 -48.261473) (xy 258.859703 -48.233433)
			(xy 258.840704 -48.209923) (xy 258.815658 -48.193) (xy 258.786757 -48.184145) (xy 258.771644 -48.183546)
			(xy 250.860052 -48.183546) (xy 250.846539 -48.18396) (xy 250.820458 -48.191042) (xy 250.797151 -48.204724)
			(xy 250.778253 -48.224044) (xy 250.765091 -48.247648) (xy 250.758587 -48.27388) (xy 250.759199 -48.300898)
			(xy 250.766883 -48.326809) (xy 250.773692 -48.338486) (xy 250.787189 -48.361201) (xy 250.808479 -48.40956)
			(xy 250.822895 -48.460392) (xy 250.830163 -48.512727) (xy 250.830588 -48.539146) (xy 250.830102 -48.566397)
			(xy 250.822346 -48.620345) (xy 250.806991 -48.67264) (xy 250.784349 -48.722217) (xy 250.754883 -48.768067)
			(xy 250.719192 -48.809258) (xy 250.710834 -48.8165) (xy 253.187506 -48.8165) (xy 253.191489 -48.763355)
			(xy 253.203347 -48.711398) (xy 253.222817 -48.661788) (xy 253.249462 -48.615633) (xy 253.282689 -48.573965)
			(xy 253.321754 -48.537715) (xy 253.365786 -48.507691) (xy 253.4138 -48.484565) (xy 253.464725 -48.468853)
			(xy 253.517423 -48.460906) (xy 253.54407 -48.460406) (xy 253.57139 -48.460944) (xy 253.625391 -48.469278)
			(xy 253.677487 -48.485754) (xy 253.726459 -48.509989) (xy 253.771159 -48.541412) (xy 253.791212 -48.559974)
			(xy 253.802834 -48.570371) (xy 253.830768 -48.584195) (xy 253.86157 -48.588951) (xy 253.892372 -48.584195)
			(xy 253.920306 -48.570371) (xy 253.931928 -48.559974) (xy 253.951933 -48.541352) (xy 253.996629 -48.509898)
			(xy 254.04561 -48.485651) (xy 254.097723 -48.469181) (xy 254.151742 -48.460877) (xy 254.17907 -48.460406)
			(xy 254.205724 -48.460849) (xy 254.258436 -48.46879) (xy 254.309376 -48.484499) (xy 254.357406 -48.507625)
			(xy 254.401452 -48.537652) (xy 254.44053 -48.573909) (xy 254.473768 -48.615585) (xy 254.500423 -48.661749)
			(xy 254.5199 -48.711371) (xy 254.531762 -48.763342) (xy 254.535746 -48.8165) (xy 254.531762 -48.869658)
			(xy 254.5199 -48.921629) (xy 254.500423 -48.971251) (xy 254.473768 -49.017415) (xy 254.44053 -49.059091)
			(xy 254.401452 -49.095348) (xy 254.357406 -49.125375) (xy 254.309376 -49.148501) (xy 254.258436 -49.16421)
			(xy 254.205724 -49.172151) (xy 254.17907 -49.172622) (xy 254.151749 -49.172113) (xy 254.097747 -49.163771)
			(xy 254.045651 -49.147287) (xy 253.996679 -49.123047) (xy 253.95198 -49.091618) (xy 253.931928 -49.073054)
			(xy 253.920306 -49.062657) (xy 253.892372 -49.048833) (xy 253.86157 -49.044077) (xy 253.830768 -49.048833)
			(xy 253.802834 -49.062657) (xy 253.791212 -49.073054) (xy 253.771179 -49.091645) (xy 253.726492 -49.123106)
			(xy 253.677519 -49.14736) (xy 253.625411 -49.163837) (xy 253.571396 -49.172148) (xy 253.54407 -49.172622)
			(xy 253.517423 -49.172094) (xy 253.464725 -49.164147) (xy 253.4138 -49.148435) (xy 253.365786 -49.125309)
			(xy 253.321754 -49.095285) (xy 253.282689 -49.059035) (xy 253.249462 -49.017367) (xy 253.222817 -48.971212)
			(xy 253.203347 -48.921602) (xy 253.191489 -48.869645) (xy 253.187506 -48.8165) (xy 250.710834 -48.8165)
			(xy 250.678001 -48.844949) (xy 250.632151 -48.874415) (xy 250.582574 -48.897057) (xy 250.530279 -48.912412)
			(xy 250.476331 -48.920168) (xy 250.421829 -48.920168) (xy 250.367881 -48.912412) (xy 250.315586 -48.897057)
			(xy 250.266009 -48.874415) (xy 250.220159 -48.844949) (xy 250.178968 -48.809258) (xy 250.143277 -48.768067)
			(xy 250.113811 -48.722217) (xy 250.091169 -48.67264) (xy 250.075814 -48.620345) (xy 250.068058 -48.566397)
			(xy 250.067572 -48.539146) (xy 250.068005 -48.512727) (xy 250.075265 -48.460392) (xy 250.089682 -48.40956)
			(xy 250.110978 -48.361205) (xy 250.124468 -48.338486) (xy 250.131206 -48.326773) (xy 250.138873 -48.300871)
			(xy 250.139478 -48.273864) (xy 250.13298 -48.247645) (xy 250.119833 -48.224047) (xy 250.100957 -48.204723)
			(xy 250.077674 -48.191025) (xy 250.051614 -48.183913) (xy 250.038108 -48.183546) (xy 249.58548 -48.183546)
			(xy 248.313679 -49.455347) (xy 250.398324 -49.455347) (xy 250.398324 -49.400853) (xy 250.406079 -49.346914)
			(xy 250.421431 -49.294627) (xy 250.444068 -49.245057) (xy 250.473529 -49.199213) (xy 250.509214 -49.158028)
			(xy 250.550397 -49.122341) (xy 250.596239 -49.092878) (xy 250.645808 -49.070238) (xy 250.698094 -49.054883)
			(xy 250.752033 -49.047126) (xy 250.77928 -49.046638) (xy 250.807178 -49.04716) (xy 250.862382 -49.055264)
			(xy 250.915814 -49.07133) (xy 250.966333 -49.095015) (xy 251.012859 -49.125813) (xy 251.054397 -49.163065)
			(xy 251.090059 -49.205976) (xy 251.119083 -49.253628) (xy 251.14085 -49.305003) (xy 251.148342 -49.33188)
			(xy 251.15221 -49.345218) (xy 251.166121 -49.369242) (xy 251.185996 -49.388625) (xy 251.210362 -49.40193)
			(xy 251.237414 -49.40817) (xy 251.265146 -49.406884) (xy 251.291503 -49.398167) (xy 251.303282 -49.390808)
			(xy 251.326979 -49.375506) (xy 251.377927 -49.351298) (xy 251.431885 -49.334859) (xy 251.487677 -49.326548)
			(xy 251.51588 -49.326038) (xy 251.543137 -49.326408) (xy 251.597097 -49.334163) (xy 251.649403 -49.349519)
			(xy 251.698992 -49.372163) (xy 251.744853 -49.401635) (xy 251.786053 -49.437333) (xy 251.821753 -49.478531)
			(xy 251.851227 -49.52439) (xy 251.873874 -49.573978) (xy 251.889233 -49.626284) (xy 251.896991 -49.680243)
			(xy 251.896991 -49.7167) (xy 253.187482 -49.7167) (xy 253.191465 -49.663552) (xy 253.203324 -49.611591)
			(xy 253.222795 -49.561977) (xy 253.249442 -49.51582) (xy 253.282671 -49.474149) (xy 253.321739 -49.437896)
			(xy 253.365774 -49.40787) (xy 253.413792 -49.384742) (xy 253.46472 -49.369029) (xy 253.517421 -49.361082)
			(xy 253.54407 -49.360582) (xy 253.57139 -49.361126) (xy 253.62539 -49.36946) (xy 253.677486 -49.385935)
			(xy 253.726458 -49.410168) (xy 253.771159 -49.441589) (xy 253.791212 -49.46015) (xy 253.802834 -49.470547)
			(xy 253.830768 -49.484371) (xy 253.86157 -49.489127) (xy 253.892372 -49.484371) (xy 253.920306 -49.470547)
			(xy 253.931928 -49.46015) (xy 253.951945 -49.441541) (xy 253.996636 -49.410082) (xy 254.045613 -49.385831)
			(xy 254.097725 -49.369359) (xy 254.151743 -49.361053) (xy 254.17907 -49.360582) (xy 254.205722 -49.361073)
			(xy 254.258431 -49.369014) (xy 254.309367 -49.384722) (xy 254.357394 -49.407846) (xy 254.401437 -49.437871)
			(xy 254.440513 -49.474125) (xy 254.473748 -49.515798) (xy 254.500402 -49.56196) (xy 254.519877 -49.611578)
			(xy 254.531738 -49.663545) (xy 254.535722 -49.7167) (xy 254.531738 -49.769855) (xy 254.519877 -49.821822)
			(xy 254.500402 -49.87144) (xy 254.473748 -49.917602) (xy 254.440513 -49.959275) (xy 254.401437 -49.995529)
			(xy 254.357394 -50.025554) (xy 254.309367 -50.048678) (xy 254.258431 -50.064386) (xy 254.205722 -50.072327)
			(xy 254.17907 -50.072798) (xy 254.151749 -50.072296) (xy 254.097746 -50.063953) (xy 254.045649 -50.047468)
			(xy 253.996678 -50.023226) (xy 253.95198 -49.991795) (xy 253.931928 -49.97323) (xy 253.920306 -49.962833)
			(xy 253.892372 -49.949009) (xy 253.86157 -49.944253) (xy 253.830768 -49.949009) (xy 253.802834 -49.962833)
			(xy 253.791212 -49.97323) (xy 253.771191 -49.991834) (xy 253.7265 -50.02329) (xy 253.677523 -50.047541)
			(xy 253.625413 -50.064015) (xy 253.571396 -50.072324) (xy 253.54407 -50.072798) (xy 253.517421 -50.072318)
			(xy 253.46472 -50.064371) (xy 253.413792 -50.048658) (xy 253.365774 -50.02553) (xy 253.321739 -49.995504)
			(xy 253.282671 -49.959251) (xy 253.249442 -49.91758) (xy 253.222795 -49.871423) (xy 253.203324 -49.821809)
			(xy 253.191465 -49.769848) (xy 253.187482 -49.7167) (xy 251.896991 -49.7167) (xy 251.896991 -49.734757)
			(xy 251.889233 -49.788716) (xy 251.873874 -49.841022) (xy 251.851227 -49.89061) (xy 251.821753 -49.936469)
			(xy 251.786053 -49.977667) (xy 251.744853 -50.013365) (xy 251.698992 -50.042837) (xy 251.649403 -50.065481)
			(xy 251.597097 -50.080837) (xy 251.543137 -50.088592) (xy 251.51588 -50.089054) (xy 251.487981 -50.088574)
			(xy 251.432775 -50.080464) (xy 251.379341 -50.064393) (xy 251.328821 -50.040702) (xy 251.282296 -50.009899)
			(xy 251.240759 -49.972641) (xy 251.205097 -49.929726) (xy 251.176074 -49.88207) (xy 251.154309 -49.830691)
			(xy 251.146818 -49.803812) (xy 251.14287 -49.790502) (xy 251.128968 -49.766488) (xy 251.109107 -49.747111)
			(xy 251.084757 -49.733806) (xy 251.057721 -49.72756) (xy 251.030003 -49.728834) (xy 251.003654 -49.737534)
			(xy 250.991878 -49.744884) (xy 250.968191 -49.760202) (xy 250.917239 -49.784406) (xy 250.863278 -49.800841)
			(xy 250.807484 -49.809147) (xy 250.77928 -49.809654) (xy 250.752033 -49.809074) (xy 250.698094 -49.801317)
			(xy 250.645808 -49.785962) (xy 250.596239 -49.763322) (xy 250.550397 -49.733859) (xy 250.509214 -49.698172)
			(xy 250.473529 -49.656987) (xy 250.444068 -49.611143) (xy 250.421431 -49.561573) (xy 250.406079 -49.509286)
			(xy 250.398324 -49.455347) (xy 248.313679 -49.455347) (xy 247.424679 -50.344347) (xy 250.398324 -50.344347)
			(xy 250.398324 -50.289853) (xy 250.406079 -50.235914) (xy 250.421431 -50.183627) (xy 250.444068 -50.134057)
			(xy 250.473529 -50.088213) (xy 250.509214 -50.047028) (xy 250.550397 -50.011341) (xy 250.596239 -49.981878)
			(xy 250.645808 -49.959238) (xy 250.698094 -49.943883) (xy 250.752033 -49.936126) (xy 250.77928 -49.935638)
			(xy 250.807178 -49.93616) (xy 250.862382 -49.944264) (xy 250.915814 -49.96033) (xy 250.966333 -49.984015)
			(xy 251.012859 -50.014813) (xy 251.054397 -50.052065) (xy 251.090059 -50.094976) (xy 251.119083 -50.142628)
			(xy 251.14085 -50.194003) (xy 251.148342 -50.22088) (xy 251.15221 -50.234218) (xy 251.166121 -50.258242)
			(xy 251.185996 -50.277625) (xy 251.210362 -50.29093) (xy 251.237414 -50.29717) (xy 251.265146 -50.295884)
			(xy 251.291503 -50.287167) (xy 251.303282 -50.279808) (xy 251.326979 -50.264506) (xy 251.377927 -50.240298)
			(xy 251.431885 -50.223859) (xy 251.487677 -50.215548) (xy 251.51588 -50.215038) (xy 251.543137 -50.215408)
			(xy 251.597097 -50.223163) (xy 251.649403 -50.238519) (xy 251.698992 -50.261163) (xy 251.744853 -50.290635)
			(xy 251.786053 -50.326333) (xy 251.821753 -50.367531) (xy 251.851227 -50.41339) (xy 251.873874 -50.462978)
			(xy 251.889233 -50.515284) (xy 251.896991 -50.569243) (xy 251.896991 -50.6166) (xy 253.187504 -50.6166)
			(xy 253.191487 -50.563455) (xy 253.203345 -50.511497) (xy 253.222815 -50.461887) (xy 253.249461 -50.415732)
			(xy 253.282687 -50.374064) (xy 253.321753 -50.337813) (xy 253.365785 -50.307789) (xy 253.4138 -50.284663)
			(xy 253.464725 -50.268951) (xy 253.517423 -50.261004) (xy 253.54407 -50.260504) (xy 253.57139 -50.261042)
			(xy 253.625391 -50.269376) (xy 253.677487 -50.285853) (xy 253.726459 -50.310087) (xy 253.771159 -50.34151)
			(xy 253.791212 -50.360072) (xy 253.802834 -50.370469) (xy 253.830768 -50.384293) (xy 253.86157 -50.389049)
			(xy 253.892372 -50.384293) (xy 253.920306 -50.370469) (xy 253.931928 -50.360072) (xy 253.951933 -50.341449)
			(xy 253.996628 -50.309995) (xy 254.045609 -50.285748) (xy 254.097723 -50.269279) (xy 254.151742 -50.260975)
			(xy 254.17907 -50.260504) (xy 254.205724 -50.260951) (xy 254.258436 -50.268892) (xy 254.309375 -50.284601)
			(xy 254.357405 -50.307727) (xy 254.40145 -50.337754) (xy 254.43235 -50.366422) (xy 255.680462 -50.366422)
			(xy 255.684533 -50.3108) (xy 255.696659 -50.256363) (xy 255.716582 -50.204272) (xy 255.743878 -50.155637)
			(xy 255.777964 -50.111494) (xy 255.818113 -50.072785) (xy 255.863471 -50.040334) (xy 255.913071 -50.014833)
			(xy 255.965855 -49.996826) (xy 256.020698 -49.986696) (xy 256.076432 -49.984659) (xy 256.131869 -49.990759)
			(xy 256.185826 -50.004865) (xy 256.237155 -50.026677) (xy 256.284761 -50.055731) (xy 256.327629 -50.091406)
			(xy 256.364846 -50.132943) (xy 256.395619 -50.179456) (xy 256.419291 -50.229953) (xy 256.435359 -50.28336)
			(xy 256.443479 -50.338536) (xy 256.443988 -50.366422) (xy 256.443479 -50.394308) (xy 256.435359 -50.449484)
			(xy 256.419291 -50.502891) (xy 256.395619 -50.553388) (xy 256.364846 -50.599901) (xy 256.327629 -50.641438)
			(xy 256.284761 -50.677113) (xy 256.237155 -50.706167) (xy 256.185826 -50.727979) (xy 256.131869 -50.742085)
			(xy 256.076432 -50.748185) (xy 256.020698 -50.746148) (xy 255.965855 -50.736018) (xy 255.913071 -50.718011)
			(xy 255.863471 -50.69251) (xy 255.818113 -50.660059) (xy 255.777964 -50.62135) (xy 255.743878 -50.577207)
			(xy 255.716582 -50.528572) (xy 255.696659 -50.476481) (xy 255.684533 -50.422044) (xy 255.680462 -50.366422)
			(xy 254.43235 -50.366422) (xy 254.440529 -50.37401) (xy 254.473767 -50.415686) (xy 254.500421 -50.46185)
			(xy 254.519898 -50.511472) (xy 254.53176 -50.563442) (xy 254.535744 -50.6166) (xy 254.53176 -50.669758)
			(xy 254.519898 -50.721728) (xy 254.500421 -50.77135) (xy 254.473767 -50.817514) (xy 254.440529 -50.85919)
			(xy 254.40145 -50.895446) (xy 254.357405 -50.925473) (xy 254.309375 -50.948599) (xy 254.258436 -50.964308)
			(xy 254.205724 -50.972249) (xy 254.17907 -50.97272) (xy 254.151749 -50.972212) (xy 254.097747 -50.96387)
			(xy 254.045651 -50.947386) (xy 253.996679 -50.923145) (xy 253.95198 -50.891716) (xy 253.931928 -50.873152)
			(xy 253.920306 -50.862755) (xy 253.892372 -50.848931) (xy 253.86157 -50.844175) (xy 253.830768 -50.848931)
			(xy 253.802834 -50.862755) (xy 253.791212 -50.873152) (xy 253.771179 -50.891743) (xy 253.726492 -50.923204)
			(xy 253.677519 -50.947458) (xy 253.625411 -50.963935) (xy 253.571396 -50.972246) (xy 253.54407 -50.97272)
			(xy 253.517423 -50.972196) (xy 253.464725 -50.964249) (xy 253.4138 -50.948537) (xy 253.365785 -50.925411)
			(xy 253.321753 -50.895387) (xy 253.282687 -50.859136) (xy 253.249461 -50.817468) (xy 253.222815 -50.771313)
			(xy 253.203345 -50.721703) (xy 253.191487 -50.669745) (xy 253.187504 -50.6166) (xy 251.896991 -50.6166)
			(xy 251.896991 -50.623757) (xy 251.889233 -50.677716) (xy 251.873874 -50.730022) (xy 251.851227 -50.77961)
			(xy 251.821753 -50.825469) (xy 251.786053 -50.866667) (xy 251.744853 -50.902365) (xy 251.698992 -50.931837)
			(xy 251.649403 -50.954481) (xy 251.597097 -50.969837) (xy 251.543137 -50.977592) (xy 251.51588 -50.978054)
			(xy 251.487981 -50.977574) (xy 251.432775 -50.969464) (xy 251.379341 -50.953393) (xy 251.328821 -50.929702)
			(xy 251.282296 -50.898899) (xy 251.240759 -50.861641) (xy 251.205097 -50.818726) (xy 251.176074 -50.77107)
			(xy 251.154309 -50.719691) (xy 251.146818 -50.692812) (xy 251.14287 -50.679502) (xy 251.128968 -50.655488)
			(xy 251.109107 -50.636111) (xy 251.084757 -50.622806) (xy 251.057721 -50.61656) (xy 251.030003 -50.617834)
			(xy 251.003654 -50.626534) (xy 250.991878 -50.633884) (xy 250.968191 -50.649202) (xy 250.917239 -50.673406)
			(xy 250.863278 -50.689841) (xy 250.807484 -50.698147) (xy 250.77928 -50.698654) (xy 250.752033 -50.698074)
			(xy 250.698094 -50.690317) (xy 250.645808 -50.674962) (xy 250.596239 -50.652322) (xy 250.550397 -50.622859)
			(xy 250.509214 -50.587172) (xy 250.473529 -50.545987) (xy 250.444068 -50.500143) (xy 250.421431 -50.450573)
			(xy 250.406079 -50.398286) (xy 250.398324 -50.344347) (xy 247.424679 -50.344347) (xy 247.04548 -50.723546)
			(xy 242.175538 -50.723546) (xy 242.16233 -50.75428) (xy 242.152754 -50.775566) (xy 242.128999 -50.815743)
			(xy 242.10036 -50.852599) (xy 242.084098 -50.869342) (xy 241.798094 -51.155346) (xy 247.831862 -51.155346)
			(xy 247.835933 -51.099724) (xy 247.848059 -51.045287) (xy 247.867982 -50.993196) (xy 247.895278 -50.944561)
			(xy 247.929364 -50.900418) (xy 247.969513 -50.861709) (xy 248.014871 -50.829258) (xy 248.064471 -50.803757)
			(xy 248.117255 -50.78575) (xy 248.172098 -50.77562) (xy 248.227832 -50.773583) (xy 248.283269 -50.779683)
			(xy 248.337226 -50.793789) (xy 248.388555 -50.815601) (xy 248.436161 -50.844655) (xy 248.479029 -50.88033)
			(xy 248.516246 -50.921867) (xy 248.547019 -50.96838) (xy 248.570691 -51.018877) (xy 248.586759 -51.072284)
			(xy 248.594879 -51.12746) (xy 248.595388 -51.155346) (xy 248.594879 -51.183232) (xy 248.587504 -51.233347)
			(xy 250.398324 -51.233347) (xy 250.398324 -51.178853) (xy 250.406079 -51.124914) (xy 250.421431 -51.072627)
			(xy 250.444068 -51.023057) (xy 250.473529 -50.977213) (xy 250.509214 -50.936028) (xy 250.550397 -50.900341)
			(xy 250.596239 -50.870878) (xy 250.645808 -50.848238) (xy 250.698094 -50.832883) (xy 250.752033 -50.825126)
			(xy 250.77928 -50.824638) (xy 250.807178 -50.82516) (xy 250.862382 -50.833264) (xy 250.915814 -50.84933)
			(xy 250.966333 -50.873015) (xy 251.012859 -50.903813) (xy 251.054397 -50.941065) (xy 251.090059 -50.983976)
			(xy 251.119083 -51.031628) (xy 251.14085 -51.083003) (xy 251.148342 -51.10988) (xy 251.15221 -51.123218)
			(xy 251.166121 -51.147242) (xy 251.185996 -51.166625) (xy 251.210362 -51.17993) (xy 251.237414 -51.18617)
			(xy 251.265146 -51.184884) (xy 251.291503 -51.176167) (xy 251.303282 -51.168808) (xy 251.326979 -51.153506)
			(xy 251.377927 -51.129298) (xy 251.431885 -51.112859) (xy 251.487677 -51.104548) (xy 251.51588 -51.104038)
			(xy 251.543137 -51.104408) (xy 251.597097 -51.112163) (xy 251.649403 -51.127519) (xy 251.698992 -51.150163)
			(xy 251.744853 -51.179635) (xy 251.786053 -51.215333) (xy 251.821753 -51.256531) (xy 251.851227 -51.30239)
			(xy 251.873874 -51.351978) (xy 251.889233 -51.404284) (xy 251.896991 -51.458243) (xy 251.896991 -51.512757)
			(xy 251.896453 -51.5165) (xy 253.187527 -51.5165) (xy 253.191509 -51.463358) (xy 253.203367 -51.411404)
			(xy 253.222835 -51.361797) (xy 253.249479 -51.315645) (xy 253.282704 -51.273979) (xy 253.321767 -51.237731)
			(xy 253.365796 -51.207709) (xy 253.413808 -51.184584) (xy 253.46473 -51.168873) (xy 253.517425 -51.160926)
			(xy 253.54407 -51.160426) (xy 253.57139 -51.160958) (xy 253.625392 -51.169293) (xy 253.677488 -51.18577)
			(xy 253.72646 -51.210006) (xy 253.77116 -51.241431) (xy 253.791212 -51.259994) (xy 253.802834 -51.270391)
			(xy 253.830768 -51.284215) (xy 253.86157 -51.288971) (xy 253.892372 -51.284215) (xy 253.920306 -51.270391)
			(xy 253.931928 -51.259994) (xy 253.951936 -51.241375) (xy 253.99663 -51.20992) (xy 254.045611 -51.185672)
			(xy 254.097724 -51.169202) (xy 254.151743 -51.160897) (xy 254.17907 -51.160426) (xy 254.205725 -51.160829)
			(xy 254.258441 -51.168771) (xy 254.309383 -51.184481) (xy 254.357416 -51.207608) (xy 254.401464 -51.237637)
			(xy 254.440545 -51.273895) (xy 254.473785 -51.315573) (xy 254.494197 -51.350926) (xy 256.493262 -51.350926)
			(xy 256.497333 -51.295304) (xy 256.509459 -51.240867) (xy 256.529382 -51.188776) (xy 256.556678 -51.140141)
			(xy 256.590764 -51.095998) (xy 256.630913 -51.057289) (xy 256.676271 -51.024838) (xy 256.725871 -50.999337)
			(xy 256.778655 -50.98133) (xy 256.833498 -50.9712) (xy 256.889232 -50.969163) (xy 256.944669 -50.975263)
			(xy 256.998626 -50.989369) (xy 257.049955 -51.011181) (xy 257.097561 -51.040235) (xy 257.140429 -51.07591)
			(xy 257.177646 -51.117447) (xy 257.208419 -51.16396) (xy 257.232091 -51.214457) (xy 257.248159 -51.267864)
			(xy 257.256279 -51.32304) (xy 257.256788 -51.350926) (xy 257.256279 -51.378812) (xy 257.248159 -51.433988)
			(xy 257.232091 -51.487395) (xy 257.208419 -51.537892) (xy 257.177646 -51.584405) (xy 257.140429 -51.625942)
			(xy 257.097561 -51.661617) (xy 257.049955 -51.690671) (xy 256.998626 -51.712483) (xy 256.944669 -51.726589)
			(xy 256.889232 -51.732689) (xy 256.833498 -51.730652) (xy 256.778655 -51.720522) (xy 256.725871 -51.702515)
			(xy 256.676271 -51.677014) (xy 256.630913 -51.644563) (xy 256.590764 -51.605854) (xy 256.556678 -51.561711)
			(xy 256.529382 -51.513076) (xy 256.509459 -51.460985) (xy 256.497333 -51.406548) (xy 256.493262 -51.350926)
			(xy 254.494197 -51.350926) (xy 254.500441 -51.361741) (xy 254.519919 -51.411365) (xy 254.531782 -51.463339)
			(xy 254.535766 -51.5165) (xy 254.531782 -51.569661) (xy 254.519919 -51.621635) (xy 254.500441 -51.671259)
			(xy 254.473785 -51.717427) (xy 254.440545 -51.759105) (xy 254.401464 -51.795363) (xy 254.357416 -51.825392)
			(xy 254.309383 -51.848519) (xy 254.258441 -51.864229) (xy 254.205725 -51.872171) (xy 254.17907 -51.872642)
			(xy 254.151748 -51.872156) (xy 254.097744 -51.863811) (xy 254.045646 -51.847323) (xy 253.996675 -51.823077)
			(xy 253.951978 -51.791642) (xy 253.931928 -51.773074) (xy 253.920306 -51.762677) (xy 253.892372 -51.748853)
			(xy 253.86157 -51.744097) (xy 253.830768 -51.748853) (xy 253.802834 -51.762677) (xy 253.791212 -51.773074)
			(xy 253.771182 -51.791668) (xy 253.726494 -51.823128) (xy 253.67752 -51.847382) (xy 253.625411 -51.863857)
			(xy 253.571396 -51.872168) (xy 253.54407 -51.872642) (xy 253.517425 -51.872074) (xy 253.46473 -51.864127)
			(xy 253.413808 -51.848416) (xy 253.365796 -51.825291) (xy 253.321767 -51.795269) (xy 253.282704 -51.759021)
			(xy 253.249479 -51.717355) (xy 253.222835 -51.671203) (xy 253.203367 -51.621596) (xy 253.191509 -51.569642)
			(xy 253.187527 -51.5165) (xy 251.896453 -51.5165) (xy 251.889233 -51.566716) (xy 251.873874 -51.619022)
			(xy 251.851227 -51.66861) (xy 251.821753 -51.714469) (xy 251.786053 -51.755667) (xy 251.744853 -51.791365)
			(xy 251.698992 -51.820837) (xy 251.649403 -51.843481) (xy 251.597097 -51.858837) (xy 251.543137 -51.866592)
			(xy 251.51588 -51.867054) (xy 251.487981 -51.866574) (xy 251.432775 -51.858464) (xy 251.379341 -51.842393)
			(xy 251.328821 -51.818702) (xy 251.282296 -51.787899) (xy 251.240759 -51.750641) (xy 251.205097 -51.707726)
			(xy 251.176074 -51.66007) (xy 251.154309 -51.608691) (xy 251.146818 -51.581812) (xy 251.14287 -51.568502)
			(xy 251.128968 -51.544488) (xy 251.109107 -51.525111) (xy 251.084757 -51.511806) (xy 251.057721 -51.50556)
			(xy 251.030003 -51.506834) (xy 251.003654 -51.515534) (xy 250.991878 -51.522884) (xy 250.968191 -51.538202)
			(xy 250.917239 -51.562406) (xy 250.863278 -51.578841) (xy 250.807484 -51.587147) (xy 250.77928 -51.587654)
			(xy 250.752033 -51.587074) (xy 250.698094 -51.579317) (xy 250.645808 -51.563962) (xy 250.596239 -51.541322)
			(xy 250.550397 -51.511859) (xy 250.509214 -51.476172) (xy 250.473529 -51.434987) (xy 250.444068 -51.389143)
			(xy 250.421431 -51.339573) (xy 250.406079 -51.287286) (xy 250.398324 -51.233347) (xy 248.587504 -51.233347)
			(xy 248.586759 -51.238408) (xy 248.570691 -51.291815) (xy 248.547019 -51.342312) (xy 248.516246 -51.388825)
			(xy 248.479029 -51.430362) (xy 248.436161 -51.466037) (xy 248.388555 -51.495091) (xy 248.337226 -51.516903)
			(xy 248.283269 -51.531009) (xy 248.227832 -51.537109) (xy 248.172098 -51.535072) (xy 248.117255 -51.524942)
			(xy 248.064471 -51.506935) (xy 248.014871 -51.481434) (xy 247.969513 -51.448983) (xy 247.929364 -51.410274)
			(xy 247.895278 -51.366131) (xy 247.867982 -51.317496) (xy 247.848059 -51.265405) (xy 247.835933 -51.210968)
			(xy 247.831862 -51.155346) (xy 241.798094 -51.155346) (xy 241.120676 -51.832764) (xy 241.099827 -51.852891)
			(xy 241.052978 -51.886995) (xy 241.001369 -51.913349) (xy 240.946273 -51.931302) (xy 240.889045 -51.940412)
			(xy 240.860072 -51.940968) (xy 240.74628 -51.940968) (xy 240.74628 -52.90185) (xy 241.926872 -52.90185)
			(xy 241.926872 -52.03825) (xy 241.927358 -52.010999) (xy 241.935114 -51.957051) (xy 241.950469 -51.904756)
			(xy 241.973111 -51.855179) (xy 242.002577 -51.809329) (xy 242.038268 -51.768138) (xy 242.079459 -51.732447)
			(xy 242.125309 -51.702981) (xy 242.174886 -51.680339) (xy 242.227181 -51.664984) (xy 242.281129 -51.657228)
			(xy 242.335631 -51.657228) (xy 242.389579 -51.664984) (xy 242.441874 -51.680339) (xy 242.491451 -51.702981)
			(xy 242.537301 -51.732447) (xy 242.578492 -51.768138) (xy 242.614183 -51.809329) (xy 242.643649 -51.855179)
			(xy 242.666291 -51.904756) (xy 242.681646 -51.957051) (xy 242.689402 -52.010999) (xy 242.689888 -52.03825)
			(xy 242.689888 -52.90185) (xy 242.689402 -52.929101) (xy 242.687879 -52.939696) (xy 256.159252 -52.939696)
			(xy 256.163323 -52.884074) (xy 256.175449 -52.829637) (xy 256.195372 -52.777546) (xy 256.222668 -52.728911)
			(xy 256.256754 -52.684768) (xy 256.296903 -52.646059) (xy 256.342261 -52.613608) (xy 256.391861 -52.588107)
			(xy 256.444645 -52.5701) (xy 256.499488 -52.55997) (xy 256.555222 -52.557933) (xy 256.610659 -52.564033)
			(xy 256.664616 -52.578139) (xy 256.715945 -52.599951) (xy 256.763551 -52.629005) (xy 256.806419 -52.66468)
			(xy 256.843636 -52.706217) (xy 256.874409 -52.75273) (xy 256.898081 -52.803227) (xy 256.914149 -52.856634)
			(xy 256.922269 -52.91181) (xy 256.922778 -52.939696) (xy 256.922269 -52.967582) (xy 256.914149 -53.022758)
			(xy 256.898081 -53.076165) (xy 256.874409 -53.126662) (xy 256.843636 -53.173175) (xy 256.806419 -53.214712)
			(xy 256.763551 -53.250387) (xy 256.715945 -53.279441) (xy 256.664616 -53.301253) (xy 256.610659 -53.315359)
			(xy 256.555222 -53.321459) (xy 256.499488 -53.319422) (xy 256.444645 -53.309292) (xy 256.391861 -53.291285)
			(xy 256.342261 -53.265784) (xy 256.296903 -53.233333) (xy 256.256754 -53.194624) (xy 256.222668 -53.150481)
			(xy 256.195372 -53.101846) (xy 256.175449 -53.049755) (xy 256.163323 -52.995318) (xy 256.159252 -52.939696)
			(xy 242.687879 -52.939696) (xy 242.681646 -52.983049) (xy 242.666291 -53.035344) (xy 242.643649 -53.084921)
			(xy 242.614183 -53.130771) (xy 242.578492 -53.171962) (xy 242.537301 -53.207653) (xy 242.491451 -53.237119)
			(xy 242.441874 -53.259761) (xy 242.389579 -53.275116) (xy 242.335631 -53.282872) (xy 242.281129 -53.282872)
			(xy 242.227181 -53.275116) (xy 242.174886 -53.259761) (xy 242.125309 -53.237119) (xy 242.079459 -53.207653)
			(xy 242.038268 -53.171962) (xy 242.002577 -53.130771) (xy 241.973111 -53.084921) (xy 241.950469 -53.035344)
			(xy 241.935114 -52.983049) (xy 241.927358 -52.929101) (xy 241.926872 -52.90185) (xy 240.74628 -52.90185)
			(xy 240.74628 -53.472842) (xy 240.781332 -53.484018) (xy 240.806587 -53.492659) (xy 240.854587 -53.516009)
			(xy 240.898866 -53.545818) (xy 240.938561 -53.581505) (xy 240.957381 -53.603906) (xy 253.772922 -53.603906)
			(xy 253.776993 -53.548284) (xy 253.789119 -53.493847) (xy 253.809042 -53.441756) (xy 253.836338 -53.393121)
			(xy 253.870424 -53.348978) (xy 253.910573 -53.310269) (xy 253.955931 -53.277818) (xy 254.005531 -53.252317)
			(xy 254.058315 -53.23431) (xy 254.113158 -53.22418) (xy 254.168892 -53.222143) (xy 254.224329 -53.228243)
			(xy 254.278286 -53.242349) (xy 254.329615 -53.264161) (xy 254.377221 -53.293215) (xy 254.420089 -53.32889)
			(xy 254.457306 -53.370427) (xy 254.488079 -53.41694) (xy 254.511751 -53.467437) (xy 254.527819 -53.520844)
			(xy 254.535939 -53.57602) (xy 254.536123 -53.586126) (xy 255.050542 -53.586126) (xy 255.054613 -53.530504)
			(xy 255.066739 -53.476067) (xy 255.086662 -53.423976) (xy 255.113958 -53.375341) (xy 255.148044 -53.331198)
			(xy 255.188193 -53.292489) (xy 255.233551 -53.260038) (xy 255.283151 -53.234537) (xy 255.335935 -53.21653)
			(xy 255.390778 -53.2064) (xy 255.446512 -53.204363) (xy 255.501949 -53.210463) (xy 255.555906 -53.224569)
			(xy 255.607235 -53.246381) (xy 255.654841 -53.275435) (xy 255.697709 -53.31111) (xy 255.734926 -53.352647)
			(xy 255.765699 -53.39916) (xy 255.789371 -53.449657) (xy 255.805439 -53.503064) (xy 255.813559 -53.55824)
			(xy 255.814068 -53.586126) (xy 255.813559 -53.614012) (xy 255.805439 -53.669188) (xy 255.789371 -53.722595)
			(xy 255.765699 -53.773092) (xy 255.734926 -53.819605) (xy 255.697709 -53.861142) (xy 255.654841 -53.896817)
			(xy 255.607235 -53.925871) (xy 255.555906 -53.947683) (xy 255.501949 -53.961789) (xy 255.446512 -53.967889)
			(xy 255.390778 -53.965852) (xy 255.335935 -53.955722) (xy 255.283151 -53.937715) (xy 255.233551 -53.912214)
			(xy 255.188193 -53.879763) (xy 255.148044 -53.841054) (xy 255.113958 -53.796911) (xy 255.086662 -53.748276)
			(xy 255.066739 -53.696185) (xy 255.054613 -53.641748) (xy 255.050542 -53.586126) (xy 254.536123 -53.586126)
			(xy 254.536448 -53.603906) (xy 254.535939 -53.631792) (xy 254.527819 -53.686968) (xy 254.511751 -53.740375)
			(xy 254.488079 -53.790872) (xy 254.457306 -53.837385) (xy 254.420089 -53.878922) (xy 254.377221 -53.914597)
			(xy 254.329615 -53.943651) (xy 254.278286 -53.965463) (xy 254.224329 -53.979569) (xy 254.168892 -53.985669)
			(xy 254.113158 -53.983632) (xy 254.058315 -53.973502) (xy 254.005531 -53.955495) (xy 253.955931 -53.929994)
			(xy 253.910573 -53.897543) (xy 253.870424 -53.858834) (xy 253.836338 -53.814691) (xy 253.809042 -53.766056)
			(xy 253.789119 -53.713965) (xy 253.776993 -53.659528) (xy 253.772922 -53.603906) (xy 240.957381 -53.603906)
			(xy 240.972896 -53.622374) (xy 241.001203 -53.667627) (xy 241.02293 -53.716383) (xy 241.037652 -53.767691)
			(xy 241.045083 -53.820549) (xy 241.045492 -53.847238) (xy 241.045492 -54.381146) (xy 258.64769 -54.381146)
			(xy 258.651761 -54.325524) (xy 258.663887 -54.271087) (xy 258.68381 -54.218996) (xy 258.711106 -54.170361)
			(xy 258.745192 -54.126218) (xy 258.785341 -54.087509) (xy 258.830699 -54.055058) (xy 258.880299 -54.029557)
			(xy 258.933083 -54.01155) (xy 258.987926 -54.00142) (xy 259.04366 -53.999383) (xy 259.099097 -54.005483)
			(xy 259.153054 -54.019589) (xy 259.204383 -54.041401) (xy 259.251989 -54.070455) (xy 259.294857 -54.10613)
			(xy 259.332074 -54.147667) (xy 259.362847 -54.19418) (xy 259.386519 -54.244677) (xy 259.402587 -54.298084)
			(xy 259.410707 -54.35326) (xy 259.411216 -54.381146) (xy 259.410707 -54.409032) (xy 259.402587 -54.464208)
			(xy 259.386519 -54.517615) (xy 259.362847 -54.568112) (xy 259.332074 -54.614625) (xy 259.294857 -54.656162)
			(xy 259.251989 -54.691837) (xy 259.204383 -54.720891) (xy 259.153054 -54.742703) (xy 259.099097 -54.756809)
			(xy 259.04366 -54.762909) (xy 258.987926 -54.760872) (xy 258.933083 -54.750742) (xy 258.880299 -54.732735)
			(xy 258.830699 -54.707234) (xy 258.785341 -54.674783) (xy 258.745192 -54.636074) (xy 258.711106 -54.591931)
			(xy 258.68381 -54.543296) (xy 258.663887 -54.491205) (xy 258.651761 -54.436768) (xy 258.64769 -54.381146)
			(xy 241.045492 -54.381146) (xy 241.045492 -54.553358) (xy 241.514376 -55.022242) (xy 248.993912 -55.022242)
			(xy 248.997983 -54.96662) (xy 249.010109 -54.912183) (xy 249.030032 -54.860092) (xy 249.057328 -54.811457)
			(xy 249.091414 -54.767314) (xy 249.131563 -54.728605) (xy 249.176921 -54.696154) (xy 249.226521 -54.670653)
			(xy 249.279305 -54.652646) (xy 249.334148 -54.642516) (xy 249.389882 -54.640479) (xy 249.445319 -54.646579)
			(xy 249.499276 -54.660685) (xy 249.550605 -54.682497) (xy 249.598211 -54.711551) (xy 249.641079 -54.747226)
			(xy 249.678296 -54.788763) (xy 249.709069 -54.835276) (xy 249.732741 -54.885773) (xy 249.748809 -54.93918)
			(xy 249.756929 -54.994356) (xy 249.757438 -55.022242) (xy 249.756929 -55.050128) (xy 249.753557 -55.073042)
			(xy 251.127512 -55.073042) (xy 251.131583 -55.01742) (xy 251.143709 -54.962983) (xy 251.163632 -54.910892)
			(xy 251.190928 -54.862257) (xy 251.225014 -54.818114) (xy 251.265163 -54.779405) (xy 251.310521 -54.746954)
			(xy 251.360121 -54.721453) (xy 251.412905 -54.703446) (xy 251.467748 -54.693316) (xy 251.523482 -54.691279)
			(xy 251.578919 -54.697379) (xy 251.632876 -54.711485) (xy 251.684205 -54.733297) (xy 251.731811 -54.762351)
			(xy 251.774679 -54.798026) (xy 251.811896 -54.839563) (xy 251.842669 -54.886076) (xy 251.866341 -54.936573)
			(xy 251.882409 -54.98998) (xy 251.890529 -55.045156) (xy 251.891038 -55.073042) (xy 251.890529 -55.100928)
			(xy 251.882409 -55.156104) (xy 251.866341 -55.209511) (xy 251.842669 -55.260008) (xy 251.811896 -55.306521)
			(xy 251.774679 -55.348058) (xy 251.731811 -55.383733) (xy 251.684205 -55.412787) (xy 251.632876 -55.434599)
			(xy 251.578919 -55.448705) (xy 251.523482 -55.454805) (xy 251.467748 -55.452768) (xy 251.412905 -55.442638)
			(xy 251.360121 -55.424631) (xy 251.310521 -55.39913) (xy 251.265163 -55.366679) (xy 251.225014 -55.32797)
			(xy 251.190928 -55.283827) (xy 251.163632 -55.235192) (xy 251.143709 -55.183101) (xy 251.131583 -55.128664)
			(xy 251.127512 -55.073042) (xy 249.753557 -55.073042) (xy 249.748809 -55.105304) (xy 249.732741 -55.158711)
			(xy 249.709069 -55.209208) (xy 249.678296 -55.255721) (xy 249.641079 -55.297258) (xy 249.598211 -55.332933)
			(xy 249.550605 -55.361987) (xy 249.499276 -55.383799) (xy 249.445319 -55.397905) (xy 249.389882 -55.404005)
			(xy 249.334148 -55.401968) (xy 249.279305 -55.391838) (xy 249.226521 -55.373831) (xy 249.176921 -55.34833)
			(xy 249.131563 -55.315879) (xy 249.091414 -55.27717) (xy 249.057328 -55.233027) (xy 249.030032 -55.184392)
			(xy 249.010109 -55.132301) (xy 248.997983 -55.077864) (xy 248.993912 -55.022242) (xy 241.514376 -55.022242)
			(xy 242.346226 -55.854092) (xy 253.921512 -55.854092) (xy 253.925583 -55.79847) (xy 253.937709 -55.744033)
			(xy 253.957632 -55.691942) (xy 253.984928 -55.643307) (xy 254.019014 -55.599164) (xy 254.059163 -55.560455)
			(xy 254.104521 -55.528004) (xy 254.154121 -55.502503) (xy 254.206905 -55.484496) (xy 254.261748 -55.474366)
			(xy 254.317482 -55.472329) (xy 254.372919 -55.478429) (xy 254.376794 -55.479442) (xy 258.534152 -55.479442)
			(xy 258.538223 -55.42382) (xy 258.550349 -55.369383) (xy 258.570272 -55.317292) (xy 258.597568 -55.268657)
			(xy 258.631654 -55.224514) (xy 258.671803 -55.185805) (xy 258.717161 -55.153354) (xy 258.766761 -55.127853)
			(xy 258.819545 -55.109846) (xy 258.874388 -55.099716) (xy 258.930122 -55.097679) (xy 258.985559 -55.103779)
			(xy 259.039516 -55.117885) (xy 259.090845 -55.139697) (xy 259.138451 -55.168751) (xy 259.181319 -55.204426)
			(xy 259.218536 -55.245963) (xy 259.249309 -55.292476) (xy 259.272981 -55.342973) (xy 259.289049 -55.39638)
			(xy 259.297169 -55.451556) (xy 259.297678 -55.479442) (xy 259.297169 -55.507328) (xy 259.289049 -55.562504)
			(xy 259.272981 -55.615911) (xy 259.249309 -55.666408) (xy 259.218536 -55.712921) (xy 259.181319 -55.754458)
			(xy 259.138451 -55.790133) (xy 259.090845 -55.819187) (xy 259.039516 -55.840999) (xy 258.985559 -55.855105)
			(xy 258.930122 -55.861205) (xy 258.874388 -55.859168) (xy 258.819545 -55.849038) (xy 258.766761 -55.831031)
			(xy 258.717161 -55.80553) (xy 258.671803 -55.773079) (xy 258.631654 -55.73437) (xy 258.597568 -55.690227)
			(xy 258.570272 -55.641592) (xy 258.550349 -55.589501) (xy 258.538223 -55.535064) (xy 258.534152 -55.479442)
			(xy 254.376794 -55.479442) (xy 254.426876 -55.492535) (xy 254.478205 -55.514347) (xy 254.525811 -55.543401)
			(xy 254.568679 -55.579076) (xy 254.605896 -55.620613) (xy 254.636669 -55.667126) (xy 254.660341 -55.717623)
			(xy 254.676409 -55.77103) (xy 254.684529 -55.826206) (xy 254.685038 -55.854092) (xy 254.684529 -55.881978)
			(xy 254.676409 -55.937154) (xy 254.660341 -55.990561) (xy 254.636669 -56.041058) (xy 254.605896 -56.087571)
			(xy 254.568679 -56.129108) (xy 254.525811 -56.164783) (xy 254.478205 -56.193837) (xy 254.426876 -56.215649)
			(xy 254.372919 -56.229755) (xy 254.317482 -56.235855) (xy 254.261748 -56.233818) (xy 254.206905 -56.223688)
			(xy 254.154121 -56.205681) (xy 254.104521 -56.18018) (xy 254.059163 -56.147729) (xy 254.019014 -56.10902)
			(xy 253.984928 -56.064877) (xy 253.957632 -56.016242) (xy 253.937709 -55.964151) (xy 253.925583 -55.909714)
			(xy 253.921512 -55.854092) (xy 242.346226 -55.854092) (xy 242.987576 -56.495442) (xy 258.534152 -56.495442)
			(xy 258.538223 -56.43982) (xy 258.550349 -56.385383) (xy 258.570272 -56.333292) (xy 258.597568 -56.284657)
			(xy 258.631654 -56.240514) (xy 258.671803 -56.201805) (xy 258.717161 -56.169354) (xy 258.766761 -56.143853)
			(xy 258.819545 -56.125846) (xy 258.874388 -56.115716) (xy 258.930122 -56.113679) (xy 258.985559 -56.119779)
			(xy 259.039516 -56.133885) (xy 259.090845 -56.155697) (xy 259.138451 -56.184751) (xy 259.181319 -56.220426)
			(xy 259.218536 -56.261963) (xy 259.249309 -56.308476) (xy 259.272981 -56.358973) (xy 259.289049 -56.41238)
			(xy 259.297169 -56.467556) (xy 259.297678 -56.495442) (xy 259.297169 -56.523328) (xy 259.289049 -56.578504)
			(xy 259.272981 -56.631911) (xy 259.249309 -56.682408) (xy 259.218536 -56.728921) (xy 259.181319 -56.770458)
			(xy 259.138451 -56.806133) (xy 259.090845 -56.835187) (xy 259.039516 -56.856999) (xy 258.985559 -56.871105)
			(xy 258.930122 -56.877205) (xy 258.874388 -56.875168) (xy 258.819545 -56.865038) (xy 258.766761 -56.847031)
			(xy 258.717161 -56.82153) (xy 258.671803 -56.789079) (xy 258.631654 -56.75037) (xy 258.597568 -56.706227)
			(xy 258.570272 -56.657592) (xy 258.550349 -56.605501) (xy 258.538223 -56.551064) (xy 258.534152 -56.495442)
			(xy 242.987576 -56.495442) (xy 244.003576 -57.511442) (xy 258.578602 -57.511442) (xy 258.582673 -57.45582)
			(xy 258.594799 -57.401383) (xy 258.614722 -57.349292) (xy 258.642018 -57.300657) (xy 258.676104 -57.256514)
			(xy 258.716253 -57.217805) (xy 258.761611 -57.185354) (xy 258.811211 -57.159853) (xy 258.863995 -57.141846)
			(xy 258.918838 -57.131716) (xy 258.974572 -57.129679) (xy 259.030009 -57.135779) (xy 259.083966 -57.149885)
			(xy 259.135295 -57.171697) (xy 259.182901 -57.200751) (xy 259.225769 -57.236426) (xy 259.262986 -57.277963)
			(xy 259.293759 -57.324476) (xy 259.317431 -57.374973) (xy 259.333499 -57.42838) (xy 259.341619 -57.483556)
			(xy 259.342128 -57.511442) (xy 259.341619 -57.539328) (xy 259.333499 -57.594504) (xy 259.317431 -57.647911)
			(xy 259.293759 -57.698408) (xy 259.262986 -57.744921) (xy 259.225769 -57.786458) (xy 259.182901 -57.822133)
			(xy 259.135295 -57.851187) (xy 259.083966 -57.872999) (xy 259.030009 -57.887105) (xy 258.974572 -57.893205)
			(xy 258.918838 -57.891168) (xy 258.863995 -57.881038) (xy 258.811211 -57.863031) (xy 258.761611 -57.83753)
			(xy 258.716253 -57.805079) (xy 258.676104 -57.76637) (xy 258.642018 -57.722227) (xy 258.614722 -57.673592)
			(xy 258.594799 -57.621501) (xy 258.582673 -57.567064) (xy 258.578602 -57.511442) (xy 244.003576 -57.511442)
			(xy 245.040681 -58.548547) (xy 254.919524 -58.548547) (xy 254.919524 -58.494053) (xy 254.927279 -58.440114)
			(xy 254.942631 -58.387827) (xy 254.965268 -58.338257) (xy 254.994729 -58.292413) (xy 255.030414 -58.251228)
			(xy 255.071597 -58.215541) (xy 255.117439 -58.186078) (xy 255.167008 -58.163438) (xy 255.219294 -58.148083)
			(xy 255.273233 -58.140326) (xy 255.30048 -58.139838) (xy 255.325411 -58.140271) (xy 255.37485 -58.146749)
			(xy 255.423024 -58.159611) (xy 255.469112 -58.178637) (xy 255.51233 -58.203504) (xy 255.532382 -58.218324)
			(xy 255.543442 -58.226213) (xy 255.568586 -58.236467) (xy 255.595544 -58.239725) (xy 255.622407 -58.235758)
			(xy 255.647272 -58.224845) (xy 255.668379 -58.20776) (xy 255.676654 -58.196988) (xy 255.692073 -58.176275)
			(xy 255.727596 -58.138799) (xy 255.767852 -58.106459) (xy 255.812103 -58.079846) (xy 255.859541 -58.059448)
			(xy 255.909297 -58.045638) (xy 255.960461 -58.038668) (xy 255.98628 -58.038238) (xy 256.013537 -58.038608)
			(xy 256.067497 -58.046363) (xy 256.119803 -58.061719) (xy 256.169392 -58.084363) (xy 256.215253 -58.113835)
			(xy 256.256453 -58.149533) (xy 256.292153 -58.190731) (xy 256.321627 -58.23659) (xy 256.344274 -58.286178)
			(xy 256.359633 -58.338484) (xy 256.360361 -58.343546) (xy 256.594862 -58.343546) (xy 256.598933 -58.287924)
			(xy 256.611059 -58.233487) (xy 256.630982 -58.181396) (xy 256.658278 -58.132761) (xy 256.692364 -58.088618)
			(xy 256.732513 -58.049909) (xy 256.777871 -58.017458) (xy 256.827471 -57.991957) (xy 256.880255 -57.97395)
			(xy 256.935098 -57.96382) (xy 256.990832 -57.961783) (xy 257.046269 -57.967883) (xy 257.100226 -57.981989)
			(xy 257.151555 -58.003801) (xy 257.199161 -58.032855) (xy 257.242029 -58.06853) (xy 257.279246 -58.110067)
			(xy 257.310019 -58.15658) (xy 257.333691 -58.207077) (xy 257.349759 -58.260484) (xy 257.357879 -58.31566)
			(xy 257.358388 -58.343546) (xy 257.357879 -58.371432) (xy 257.349759 -58.426608) (xy 257.333691 -58.480015)
			(xy 257.310019 -58.530512) (xy 257.279246 -58.577025) (xy 257.242029 -58.618562) (xy 257.199161 -58.654237)
			(xy 257.151555 -58.683291) (xy 257.100226 -58.705103) (xy 257.046269 -58.719209) (xy 256.990832 -58.725309)
			(xy 256.935098 -58.723272) (xy 256.880255 -58.713142) (xy 256.827471 -58.695135) (xy 256.777871 -58.669634)
			(xy 256.732513 -58.637183) (xy 256.692364 -58.598474) (xy 256.658278 -58.554331) (xy 256.630982 -58.505696)
			(xy 256.611059 -58.453605) (xy 256.598933 -58.399168) (xy 256.594862 -58.343546) (xy 256.360361 -58.343546)
			(xy 256.367391 -58.392443) (xy 256.367391 -58.446957) (xy 256.359633 -58.500916) (xy 256.344274 -58.553222)
			(xy 256.321627 -58.60281) (xy 256.292153 -58.648669) (xy 256.256453 -58.689867) (xy 256.215253 -58.725565)
			(xy 256.169392 -58.755037) (xy 256.119803 -58.777681) (xy 256.067497 -58.793037) (xy 256.013537 -58.800792)
			(xy 255.98628 -58.801254) (xy 255.961348 -58.800845) (xy 255.911909 -58.794361) (xy 255.863734 -58.781494)
			(xy 255.817646 -58.762462) (xy 255.774429 -58.737591) (xy 255.754378 -58.722768) (xy 255.743346 -58.714837)
			(xy 255.718192 -58.704589) (xy 255.691227 -58.701338) (xy 255.664358 -58.705314) (xy 255.63949 -58.716235)
			(xy 255.618382 -58.733328) (xy 255.610106 -58.744104) (xy 255.594648 -58.764787) (xy 255.559132 -58.802265)
			(xy 255.518883 -58.834607) (xy 255.474638 -58.861223) (xy 255.427207 -58.881626) (xy 255.377456 -58.895443)
			(xy 255.326297 -58.90242) (xy 255.30048 -58.902854) (xy 255.273233 -58.902274) (xy 255.219294 -58.894517)
			(xy 255.167008 -58.879162) (xy 255.117439 -58.856522) (xy 255.071597 -58.827059) (xy 255.030414 -58.791372)
			(xy 254.994729 -58.750187) (xy 254.965268 -58.704343) (xy 254.942631 -58.654773) (xy 254.927279 -58.602486)
			(xy 254.919524 -58.548547) (xy 245.040681 -58.548547) (xy 245.95963 -59.467496) (xy 254.66675 -59.467496)
		)
		(stroke
			(width 0)
			(type solid)
		)
		(fill yes)
		(layer "In13.Cu")
		(net "GND")
	)
	(gr_poly
		(pts
			(xy 114.324384 -271.567148) (xy 114.34436 -271.548853) (xy 114.388814 -271.517906) (xy 114.437443 -271.494048)
			(xy 114.489124 -271.47783) (xy 114.542665 -271.469627) (xy 114.596831 -271.469627) (xy 114.650372 -271.47783)
			(xy 114.702053 -271.494048) (xy 114.750682 -271.517906) (xy 114.795136 -271.548853) (xy 114.815112 -271.567148)
			(xy 115.264184 -271.567148) (xy 115.28416 -271.548853) (xy 115.328614 -271.517906) (xy 115.377243 -271.494048)
			(xy 115.428924 -271.47783) (xy 115.482465 -271.469627) (xy 115.536631 -271.469627) (xy 115.590172 -271.47783)
			(xy 115.641853 -271.494048) (xy 115.690482 -271.517906) (xy 115.734936 -271.548853) (xy 115.754912 -271.567148)
			(xy 116.203476 -271.567148) (xy 116.223453 -271.548854) (xy 116.267908 -271.517906) (xy 116.316536 -271.494047)
			(xy 116.368216 -271.477825) (xy 116.421757 -271.469614) (xy 116.44884 -271.469104) (xy 116.468174 -271.469359)
			(xy 116.506614 -271.473564) (xy 116.525548 -271.477486) (xy 116.552726 -271.483582) (xy 116.648738 -271.38757)
			(xy 116.659278 -271.376304) (xy 116.673623 -271.349008) (xy 116.679165 -271.318675) (xy 116.675399 -271.28807)
			(xy 116.662668 -271.259984) (xy 116.652802 -271.248124) (xy 116.635954 -271.228449) (xy 116.607532 -271.185144)
			(xy 116.585678 -271.138182) (xy 116.570853 -271.08855) (xy 116.563369 -271.037295) (xy 116.562886 -271.011396)
			(xy 116.563435 -270.983413) (xy 116.572191 -270.928136) (xy 116.589486 -270.874909) (xy 116.614894 -270.825043)
			(xy 116.64779 -270.779765) (xy 116.687364 -270.740191) (xy 116.732641 -270.707295) (xy 116.782507 -270.681886)
			(xy 116.835734 -270.664591) (xy 116.891011 -270.655835) (xy 116.918994 -270.655288) (xy 116.944896 -270.655733)
			(xy 116.996158 -270.663203) (xy 117.045795 -270.67803) (xy 117.092755 -270.6999) (xy 117.136047 -270.728351)
			(xy 117.155722 -270.745204) (xy 117.167582 -270.75507) (xy 117.195668 -270.767801) (xy 117.226273 -270.771568)
			(xy 117.256607 -270.766026) (xy 117.283904 -270.751682) (xy 117.295168 -270.74114) (xy 117.328696 -270.707612)
			(xy 117.338934 -270.696619) (xy 117.353075 -270.670132) (xy 117.358903 -270.640678) (xy 117.355913 -270.610802)
			(xy 117.344363 -270.583088) (xy 117.325253 -270.55993) (xy 117.300233 -270.54333) (xy 117.286024 -270.538448)
			(xy 117.261948 -270.530714) (xy 117.216095 -270.509394) (xy 117.173719 -270.481802) (xy 117.135671 -270.448495)
			(xy 117.102717 -270.41014) (xy 117.075519 -270.36751) (xy 117.054624 -270.321462) (xy 117.040452 -270.272921)
			(xy 117.033289 -270.222864) (xy 117.032786 -270.19758) (xy 117.033336 -270.169598) (xy 117.042094 -270.114323)
			(xy 117.05939 -270.061098) (xy 117.084799 -270.011234) (xy 117.117696 -269.965959) (xy 117.157269 -269.926386)
			(xy 117.202546 -269.893492) (xy 117.252411 -269.868085) (xy 117.305636 -269.850791) (xy 117.360912 -269.842035)
			(xy 117.388894 -269.841472) (xy 117.41418 -269.841915) (xy 117.464242 -269.849073) (xy 117.512788 -269.863244)
			(xy 117.558838 -269.884144) (xy 117.601467 -269.911352) (xy 117.639816 -269.944319) (xy 117.673112 -269.982383)
			(xy 117.700685 -270.024777) (xy 117.72198 -270.070646) (xy 117.729762 -270.09471) (xy 117.7346 -270.108926)
			(xy 117.751227 -270.133913) (xy 117.774395 -270.152995) (xy 117.802105 -270.164526) (xy 117.83197 -270.167513)
			(xy 117.861416 -270.161698) (xy 117.887903 -270.147581) (xy 117.898926 -270.137382) (xy 118.025926 -270.010382)
			(xy 118.028974 -270.005556) (xy 118.047185 -269.97851) (xy 118.091786 -269.93096) (xy 118.11762 -269.911068)
			(xy 118.11762 -269.813532) (xy 118.117175 -269.799574) (xy 118.109599 -269.772706) (xy 118.095032 -269.748893)
			(xy 118.074561 -269.729912) (xy 118.049717 -269.717183) (xy 118.022354 -269.711655) (xy 117.994516 -269.713742)
			(xy 117.981222 -269.718028) (xy 117.951695 -269.728128) (xy 117.890248 -269.738993) (xy 117.859048 -269.739618)
			(xy 117.832394 -269.739148) (xy 117.77968 -269.731209) (xy 117.728738 -269.715502) (xy 117.680707 -269.692377)
			(xy 117.636659 -269.662351) (xy 117.597578 -269.626095) (xy 117.564339 -269.584419) (xy 117.537683 -269.538254)
			(xy 117.518205 -269.488631) (xy 117.506342 -269.436659) (xy 117.502358 -269.3835) (xy 117.506342 -269.330341)
			(xy 117.518205 -269.278369) (xy 117.537683 -269.228746) (xy 117.564339 -269.182581) (xy 117.597578 -269.140905)
			(xy 117.636659 -269.104649) (xy 117.680707 -269.074623) (xy 117.728738 -269.051498) (xy 117.77968 -269.035791)
			(xy 117.832394 -269.027852) (xy 117.859048 -269.027402) (xy 117.890246 -269.028049) (xy 117.951692 -269.038906)
			(xy 117.981222 -269.048992) (xy 117.994495 -269.053361) (xy 118.02235 -269.055453) (xy 118.04973 -269.049921)
			(xy 118.074588 -269.037179) (xy 118.095064 -269.01818) (xy 118.109629 -268.994344) (xy 118.117193 -268.967455)
			(xy 118.11762 -268.953488) (xy 118.11762 -268.856206) (xy 118.095581 -268.839306) (xy 118.056529 -268.79982)
			(xy 118.024086 -268.754747) (xy 117.999038 -268.705181) (xy 117.981994 -268.652326) (xy 117.973367 -268.597464)
			(xy 117.973368 -268.541929) (xy 117.981995 -268.487068) (xy 117.999041 -268.434213) (xy 118.024089 -268.384647)
			(xy 118.056534 -268.339574) (xy 118.095586 -268.300089) (xy 118.11762 -268.283182) (xy 118.11762 -268.185646)
			(xy 118.117151 -268.171701) (xy 118.109538 -268.144867) (xy 118.094951 -268.121093) (xy 118.074475 -268.102152)
			(xy 118.04964 -268.089456) (xy 118.022295 -268.083951) (xy 117.994482 -268.08605) (xy 117.981222 -268.090396)
			(xy 117.951634 -268.100513) (xy 117.890058 -268.111379) (xy 117.858794 -268.111986) (xy 117.832147 -268.111487)
			(xy 117.779447 -268.103544) (xy 117.728521 -268.087834) (xy 117.680504 -268.06471) (xy 117.63647 -268.034687)
			(xy 117.597403 -267.998437) (xy 117.564174 -267.95677) (xy 117.537527 -267.910615) (xy 117.518057 -267.861004)
			(xy 117.506198 -267.809046) (xy 117.502215 -267.7559) (xy 117.506198 -267.702754) (xy 117.518057 -267.650796)
			(xy 117.537527 -267.601185) (xy 117.564174 -267.55503) (xy 117.597403 -267.513363) (xy 117.63647 -267.477113)
			(xy 117.680504 -267.44709) (xy 117.728521 -267.423966) (xy 117.779447 -267.408256) (xy 117.832147 -267.400313)
			(xy 117.858794 -267.39977) (xy 117.890056 -267.4004) (xy 117.951631 -267.411256) (xy 117.981222 -267.42136)
			(xy 117.994476 -267.425726) (xy 118.022291 -267.427826) (xy 118.049638 -267.422321) (xy 118.074474 -267.409622)
			(xy 118.094948 -267.390675) (xy 118.109531 -267.366895) (xy 118.117134 -267.340057) (xy 118.11762 -267.32611)
			(xy 118.11762 -267.228828) (xy 118.09718 -267.21326) (xy 118.060569 -267.177213) (xy 118.029517 -267.136279)
			(xy 118.004671 -267.091307) (xy 117.986545 -267.043231) (xy 117.975517 -266.99305) (xy 117.971815 -266.941805)
			(xy 117.975516 -266.890559) (xy 117.986543 -266.840378) (xy 118.004667 -266.792302) (xy 118.029512 -266.747329)
			(xy 118.060562 -266.706394) (xy 118.097173 -266.670346) (xy 118.11762 -266.654788) (xy 118.11762 -266.558014)
			(xy 118.117147 -266.544072) (xy 118.109529 -266.517246) (xy 118.09494 -266.49348) (xy 118.074467 -266.474546)
			(xy 118.049635 -266.461854) (xy 118.022297 -266.456351) (xy 117.994489 -266.458448) (xy 117.981222 -266.462764)
			(xy 117.951634 -266.472882) (xy 117.890058 -266.483748) (xy 117.858794 -266.484354) (xy 117.832142 -266.483856)
			(xy 117.779432 -266.47591) (xy 117.728496 -266.460198) (xy 117.68047 -266.437069) (xy 117.636427 -266.407041)
			(xy 117.597353 -266.370784) (xy 117.564118 -266.329108) (xy 117.537466 -266.282945) (xy 117.517991 -266.233324)
			(xy 117.50613 -266.181356) (xy 117.502146 -266.1282) (xy 117.50613 -266.075044) (xy 117.517991 -266.023076)
			(xy 117.537466 -265.973455) (xy 117.564118 -265.927292) (xy 117.597353 -265.885616) (xy 117.636427 -265.849359)
			(xy 117.68047 -265.819331) (xy 117.728496 -265.796202) (xy 117.779432 -265.78049) (xy 117.832142 -265.772544)
			(xy 117.858794 -265.772138) (xy 117.890056 -265.772768) (xy 117.951631 -265.783623) (xy 117.981222 -265.793728)
			(xy 117.994474 -265.798095) (xy 118.022288 -265.800196) (xy 118.049632 -265.794691) (xy 118.074466 -265.78199)
			(xy 118.094935 -265.763043) (xy 118.109512 -265.739262) (xy 118.117108 -265.712424) (xy 118.11762 -265.698478)
			(xy 118.11762 -265.600942) (xy 118.095553 -265.584034) (xy 118.05645 -265.544521) (xy 118.023963 -265.499412)
			(xy 117.998881 -265.449801) (xy 117.981815 -265.396896) (xy 117.973177 -265.341981) (xy 117.97318 -265.286391)
			(xy 117.981821 -265.231476) (xy 117.998892 -265.178572) (xy 118.023978 -265.128964) (xy 118.056468 -265.083857)
			(xy 118.095574 -265.044347) (xy 118.11762 -265.02741) (xy 118.11762 -264.930128) (xy 118.117149 -264.916185)
			(xy 118.109533 -264.889355) (xy 118.094945 -264.865586) (xy 118.074471 -264.846648) (xy 118.049637 -264.833955)
			(xy 118.022296 -264.828451) (xy 117.994486 -264.830549) (xy 117.981222 -264.834878) (xy 117.951634 -264.844995)
			(xy 117.890058 -264.855862) (xy 117.858794 -264.856468) (xy 117.832148 -264.85597) (xy 117.779451 -264.848026)
			(xy 117.728527 -264.832317) (xy 117.680513 -264.809194) (xy 117.636481 -264.779173) (xy 117.597416 -264.742925)
			(xy 117.564189 -264.701259) (xy 117.537543 -264.655107) (xy 117.518074 -264.605499) (xy 117.506215 -264.553543)
			(xy 117.502233 -264.5004) (xy 117.506215 -264.447257) (xy 117.518074 -264.395301) (xy 117.537543 -264.345693)
			(xy 117.564189 -264.299541) (xy 117.597416 -264.257875) (xy 117.636481 -264.221627) (xy 117.680513 -264.191606)
			(xy 117.728527 -264.168483) (xy 117.779451 -264.152774) (xy 117.832148 -264.14483) (xy 117.858794 -264.144252)
			(xy 117.890056 -264.144882) (xy 117.951631 -264.155738) (xy 117.981222 -264.165842) (xy 117.994475 -264.170209)
			(xy 118.022289 -264.17231) (xy 118.049635 -264.166804) (xy 118.07447 -264.154104) (xy 118.094941 -264.135157)
			(xy 118.10952 -264.111377) (xy 118.11712 -264.084538) (xy 118.11762 -264.070592) (xy 118.11762 -262.301228)
			(xy 117.65788 -261.841488) (xy 116.04244 -261.841488) (xy 115.7605 -262.123428) (xy 115.7605 -263.433814)
			(xy 115.77831 -263.452139) (xy 115.809032 -263.492974) (xy 115.833605 -263.53778) (xy 115.851525 -263.585636)
			(xy 115.862424 -263.635561) (xy 115.866079 -263.686531) (xy 115.862415 -263.737501) (xy 115.851507 -263.787424)
			(xy 115.833579 -263.835277) (xy 115.808998 -263.880078) (xy 115.778269 -263.920907) (xy 115.7605 -263.939274)
			(xy 115.7605 -264.057892) (xy 115.760929 -264.071188) (xy 115.767791 -264.096879) (xy 115.781053 -264.119929)
			(xy 115.799815 -264.138773) (xy 115.822806 -264.152136) (xy 115.848467 -264.159112) (xy 115.875059 -264.159226)
			(xy 115.888008 -264.15619) (xy 115.910392 -264.150621) (xy 115.95613 -264.144636) (xy 115.979194 -264.144252)
			(xy 116.005848 -264.144725) (xy 116.058562 -264.152669) (xy 116.109503 -264.168382) (xy 116.157533 -264.191511)
			(xy 116.201579 -264.22154) (xy 116.240657 -264.257799) (xy 116.273895 -264.299478) (xy 116.30055 -264.345644)
			(xy 116.320026 -264.395268) (xy 116.331888 -264.44724) (xy 116.335872 -264.5004) (xy 116.333878 -264.527009)
			(xy 116.563384 -264.527009) (xy 116.563384 -264.473711) (xy 116.571327 -264.421007) (xy 116.587037 -264.370077)
			(xy 116.610163 -264.322056) (xy 116.640187 -264.278019) (xy 116.676439 -264.238948) (xy 116.71811 -264.205717)
			(xy 116.764268 -264.179068) (xy 116.813882 -264.159596) (xy 116.865844 -264.147736) (xy 116.918994 -264.143753)
			(xy 116.972144 -264.147736) (xy 117.024106 -264.159596) (xy 117.07372 -264.179068) (xy 117.119878 -264.205717)
			(xy 117.161549 -264.238948) (xy 117.197801 -264.278019) (xy 117.227825 -264.322056) (xy 117.250951 -264.370077)
			(xy 117.266661 -264.421007) (xy 117.274604 -264.473711) (xy 117.275102 -264.50036) (xy 117.274604 -264.527009)
			(xy 117.266661 -264.579713) (xy 117.250951 -264.630643) (xy 117.227825 -264.678664) (xy 117.197801 -264.722701)
			(xy 117.161549 -264.761772) (xy 117.119878 -264.795003) (xy 117.07372 -264.821652) (xy 117.024106 -264.841124)
			(xy 116.972144 -264.852984) (xy 116.918994 -264.856968) (xy 116.865844 -264.852984) (xy 116.813882 -264.841124)
			(xy 116.764268 -264.821652) (xy 116.71811 -264.795003) (xy 116.676439 -264.761772) (xy 116.640187 -264.722701)
			(xy 116.610163 -264.678664) (xy 116.587037 -264.630643) (xy 116.571327 -264.579713) (xy 116.563384 -264.527009)
			(xy 116.333878 -264.527009) (xy 116.331888 -264.55356) (xy 116.320026 -264.605532) (xy 116.30055 -264.655156)
			(xy 116.273895 -264.701322) (xy 116.240657 -264.743001) (xy 116.201579 -264.77926) (xy 116.157533 -264.809289)
			(xy 116.109503 -264.832418) (xy 116.058562 -264.848131) (xy 116.005848 -264.856075) (xy 115.979194 -264.856468)
			(xy 115.952287 -264.855976) (xy 115.899086 -264.847884) (xy 115.847706 -264.831885) (xy 115.799316 -264.808343)
			(xy 115.755015 -264.777793) (xy 115.7351 -264.759694) (xy 115.723282 -264.749368) (xy 115.694999 -264.735805)
			(xy 115.663938 -264.731443) (xy 115.633013 -264.73669) (xy 115.605129 -264.751056) (xy 115.593622 -264.761726)
			(xy 115.555268 -264.80008) (xy 115.544835 -264.811211) (xy 115.530569 -264.838164) (xy 115.524902 -264.868128)
			(xy 115.52834 -264.898429) (xy 115.540576 -264.926361) (xy 115.560518 -264.949433) (xy 115.586386 -264.965583)
			(xy 115.600988 -264.970006) (xy 115.625946 -264.977125) (xy 115.673638 -264.997596) (xy 115.717853 -265.024773)
			(xy 115.757656 -265.058079) (xy 115.792202 -265.09681) (xy 115.820762 -265.140144) (xy 115.842729 -265.187165)
			(xy 115.857638 -265.236877) (xy 115.865175 -265.288226) (xy 115.865656 -265.314176) (xy 115.865135 -265.340825)
			(xy 116.093738 -265.340825) (xy 116.093738 -265.287527) (xy 116.101681 -265.234823) (xy 116.117391 -265.183893)
			(xy 116.140517 -265.135872) (xy 116.170541 -265.091835) (xy 116.206793 -265.052764) (xy 116.248464 -265.019533)
			(xy 116.294622 -264.992884) (xy 116.344236 -264.973412) (xy 116.396198 -264.961552) (xy 116.449348 -264.957569)
			(xy 116.502498 -264.961552) (xy 116.55446 -264.973412) (xy 116.604074 -264.992884) (xy 116.650232 -265.019533)
			(xy 116.691903 -265.052764) (xy 116.728155 -265.091835) (xy 116.758179 -265.135872) (xy 116.781305 -265.183893)
			(xy 116.797015 -265.234823) (xy 116.804958 -265.287527) (xy 116.805456 -265.314176) (xy 116.804958 -265.340825)
			(xy 117.033538 -265.340825) (xy 117.033538 -265.287527) (xy 117.041481 -265.234823) (xy 117.057191 -265.183893)
			(xy 117.080317 -265.135872) (xy 117.110341 -265.091835) (xy 117.146593 -265.052764) (xy 117.188264 -265.019533)
			(xy 117.234422 -264.992884) (xy 117.284036 -264.973412) (xy 117.335998 -264.961552) (xy 117.389148 -264.957569)
			(xy 117.442298 -264.961552) (xy 117.49426 -264.973412) (xy 117.543874 -264.992884) (xy 117.590032 -265.019533)
			(xy 117.631703 -265.052764) (xy 117.667955 -265.091835) (xy 117.697979 -265.135872) (xy 117.721105 -265.183893)
			(xy 117.736815 -265.234823) (xy 117.744758 -265.287527) (xy 117.745256 -265.314176) (xy 117.744758 -265.340825)
			(xy 117.736815 -265.393529) (xy 117.721105 -265.444459) (xy 117.697979 -265.49248) (xy 117.667955 -265.536517)
			(xy 117.631703 -265.575588) (xy 117.590032 -265.608819) (xy 117.543874 -265.635468) (xy 117.49426 -265.65494)
			(xy 117.442298 -265.6668) (xy 117.389148 -265.670784) (xy 117.335998 -265.6668) (xy 117.284036 -265.65494)
			(xy 117.234422 -265.635468) (xy 117.188264 -265.608819) (xy 117.146593 -265.575588) (xy 117.110341 -265.536517)
			(xy 117.080317 -265.49248) (xy 117.057191 -265.444459) (xy 117.041481 -265.393529) (xy 117.033538 -265.340825)
			(xy 116.804958 -265.340825) (xy 116.797015 -265.393529) (xy 116.781305 -265.444459) (xy 116.758179 -265.49248)
			(xy 116.728155 -265.536517) (xy 116.691903 -265.575588) (xy 116.650232 -265.608819) (xy 116.604074 -265.635468)
			(xy 116.55446 -265.65494) (xy 116.502498 -265.6668) (xy 116.449348 -265.670784) (xy 116.396198 -265.6668)
			(xy 116.344236 -265.65494) (xy 116.294622 -265.635468) (xy 116.248464 -265.608819) (xy 116.206793 -265.575588)
			(xy 116.170541 -265.536517) (xy 116.140517 -265.49248) (xy 116.117391 -265.444459) (xy 116.101681 -265.393529)
			(xy 116.093738 -265.340825) (xy 115.865135 -265.340825) (xy 115.865109 -265.342162) (xy 115.856357 -265.397445)
			(xy 115.839065 -265.450678) (xy 115.813659 -265.500551) (xy 115.780764 -265.545836) (xy 115.741191 -265.585418)
			(xy 115.695912 -265.618322) (xy 115.646045 -265.643738) (xy 115.592815 -265.66104) (xy 115.537534 -265.669803)
			(xy 115.509548 -265.670284) (xy 115.483596 -265.669818) (xy 115.432241 -265.662289) (xy 115.382523 -265.647384)
			(xy 115.335496 -265.625419) (xy 115.292156 -265.59686) (xy 115.253421 -265.56231) (xy 115.220113 -265.522503)
			(xy 115.192937 -265.478282) (xy 115.172469 -265.430584) (xy 115.165378 -265.405616) (xy 115.160895 -265.391058)
			(xy 115.144709 -265.365273) (xy 115.121646 -265.345399) (xy 115.093752 -265.3332) (xy 115.063503 -265.329757)
			(xy 115.033582 -265.335377) (xy 115.006643 -265.349561) (xy 114.995452 -265.359896) (xy 114.893852 -265.461496)
			(xy 114.890042 -265.46937) (xy 114.876514 -265.495932) (xy 114.841973 -265.544509) (xy 114.799828 -265.586658)
			(xy 114.751253 -265.621202) (xy 114.724688 -265.634724) (xy 114.716814 -265.638534) (xy 114.408204 -265.947144)
			(xy 114.422936 -265.979148) (xy 114.433271 -266.002632) (xy 114.447858 -266.051822) (xy 114.455253 -266.102593)
			(xy 114.455702 -266.128246) (xy 114.455176 -266.154895) (xy 114.683784 -266.154895) (xy 114.683784 -266.101597)
			(xy 114.691727 -266.048893) (xy 114.707437 -265.997963) (xy 114.730563 -265.949942) (xy 114.760587 -265.905905)
			(xy 114.796839 -265.866834) (xy 114.83851 -265.833603) (xy 114.884668 -265.806954) (xy 114.934282 -265.787482)
			(xy 114.986244 -265.775622) (xy 115.039394 -265.771639) (xy 115.092544 -265.775622) (xy 115.144506 -265.787482)
			(xy 115.19412 -265.806954) (xy 115.240278 -265.833603) (xy 115.281949 -265.866834) (xy 115.318201 -265.905905)
			(xy 115.348225 -265.949942) (xy 115.371351 -265.997963) (xy 115.387061 -266.048893) (xy 115.395004 -266.101597)
			(xy 115.395502 -266.128246) (xy 115.395004 -266.154895) (xy 115.623584 -266.154895) (xy 115.623584 -266.101597)
			(xy 115.631527 -266.048893) (xy 115.647237 -265.997963) (xy 115.670363 -265.949942) (xy 115.700387 -265.905905)
			(xy 115.736639 -265.866834) (xy 115.77831 -265.833603) (xy 115.824468 -265.806954) (xy 115.874082 -265.787482)
			(xy 115.926044 -265.775622) (xy 115.979194 -265.771639) (xy 116.032344 -265.775622) (xy 116.084306 -265.787482)
			(xy 116.13392 -265.806954) (xy 116.180078 -265.833603) (xy 116.221749 -265.866834) (xy 116.258001 -265.905905)
			(xy 116.288025 -265.949942) (xy 116.311151 -265.997963) (xy 116.326861 -266.048893) (xy 116.334804 -266.101597)
			(xy 116.335302 -266.128246) (xy 116.334804 -266.154895) (xy 116.334766 -266.155149) (xy 116.563384 -266.155149)
			(xy 116.563384 -266.101851) (xy 116.571327 -266.049147) (xy 116.587037 -265.998217) (xy 116.610163 -265.950196)
			(xy 116.640187 -265.906159) (xy 116.676439 -265.867088) (xy 116.71811 -265.833857) (xy 116.764268 -265.807208)
			(xy 116.813882 -265.787736) (xy 116.865844 -265.775876) (xy 116.918994 -265.771893) (xy 116.972144 -265.775876)
			(xy 117.024106 -265.787736) (xy 117.07372 -265.807208) (xy 117.119878 -265.833857) (xy 117.161549 -265.867088)
			(xy 117.197801 -265.906159) (xy 117.227825 -265.950196) (xy 117.250951 -265.998217) (xy 117.266661 -266.049147)
			(xy 117.274604 -266.101851) (xy 117.275102 -266.1285) (xy 117.274604 -266.155149) (xy 117.266661 -266.207853)
			(xy 117.250951 -266.258783) (xy 117.227825 -266.306804) (xy 117.197801 -266.350841) (xy 117.161549 -266.389912)
			(xy 117.119878 -266.423143) (xy 117.07372 -266.449792) (xy 117.024106 -266.469264) (xy 116.972144 -266.481124)
			(xy 116.918994 -266.485108) (xy 116.865844 -266.481124) (xy 116.813882 -266.469264) (xy 116.764268 -266.449792)
			(xy 116.71811 -266.423143) (xy 116.676439 -266.389912) (xy 116.640187 -266.350841) (xy 116.610163 -266.306804)
			(xy 116.587037 -266.258783) (xy 116.571327 -266.207853) (xy 116.563384 -266.155149) (xy 116.334766 -266.155149)
			(xy 116.326861 -266.207599) (xy 116.311151 -266.258529) (xy 116.288025 -266.30655) (xy 116.258001 -266.350587)
			(xy 116.221749 -266.389658) (xy 116.180078 -266.422889) (xy 116.13392 -266.449538) (xy 116.084306 -266.46901)
			(xy 116.032344 -266.48087) (xy 115.979194 -266.484854) (xy 115.926044 -266.48087) (xy 115.874082 -266.46901)
			(xy 115.824468 -266.449538) (xy 115.77831 -266.422889) (xy 115.736639 -266.389658) (xy 115.700387 -266.350587)
			(xy 115.670363 -266.30655) (xy 115.647237 -266.258529) (xy 115.631527 -266.207599) (xy 115.623584 -266.154895)
			(xy 115.395004 -266.154895) (xy 115.387061 -266.207599) (xy 115.371351 -266.258529) (xy 115.348225 -266.30655)
			(xy 115.318201 -266.350587) (xy 115.281949 -266.389658) (xy 115.240278 -266.422889) (xy 115.19412 -266.449538)
			(xy 115.144506 -266.46901) (xy 115.092544 -266.48087) (xy 115.039394 -266.484854) (xy 114.986244 -266.48087)
			(xy 114.934282 -266.46901) (xy 114.884668 -266.449538) (xy 114.83851 -266.422889) (xy 114.796839 -266.389658)
			(xy 114.760587 -266.350587) (xy 114.730563 -266.30655) (xy 114.707437 -266.258529) (xy 114.691727 -266.207599)
			(xy 114.683784 -266.154895) (xy 114.455176 -266.154895) (xy 114.45515 -266.156227) (xy 114.446389 -266.211498)
			(xy 114.42909 -266.264718) (xy 114.40368 -266.314578) (xy 114.370782 -266.359849) (xy 114.331209 -266.399416)
			(xy 114.285933 -266.432307) (xy 114.23607 -266.45771) (xy 114.182847 -266.475001) (xy 114.127575 -266.483754)
			(xy 114.099594 -266.484354) (xy 114.073939 -266.483909) (xy 114.023162 -266.476539) (xy 113.973974 -266.461939)
			(xy 113.950496 -266.451588) (xy 113.918492 -266.436856) (xy 113.85804 -266.497308) (xy 113.85804 -266.668504)
			(xy 113.87767 -266.685519) (xy 113.912273 -266.724263) (xy 113.940879 -266.767624) (xy 113.962882 -266.814681)
			(xy 113.977815 -266.864436) (xy 113.985362 -266.915832) (xy 113.985361 -266.967779) (xy 113.985261 -266.968457)
			(xy 114.214138 -266.968457) (xy 114.214138 -266.915159) (xy 114.222081 -266.862455) (xy 114.237791 -266.811525)
			(xy 114.260917 -266.763504) (xy 114.290941 -266.719467) (xy 114.327193 -266.680396) (xy 114.368864 -266.647165)
			(xy 114.415022 -266.620516) (xy 114.464636 -266.601044) (xy 114.516598 -266.589184) (xy 114.569748 -266.585201)
			(xy 114.622898 -266.589184) (xy 114.67486 -266.601044) (xy 114.724474 -266.620516) (xy 114.770632 -266.647165)
			(xy 114.812303 -266.680396) (xy 114.848555 -266.719467) (xy 114.878579 -266.763504) (xy 114.901705 -266.811525)
			(xy 114.917415 -266.862455) (xy 114.925358 -266.915159) (xy 114.925856 -266.941808) (xy 114.925358 -266.968457)
			(xy 115.153938 -266.968457) (xy 115.153938 -266.915159) (xy 115.161881 -266.862455) (xy 115.177591 -266.811525)
			(xy 115.200717 -266.763504) (xy 115.230741 -266.719467) (xy 115.266993 -266.680396) (xy 115.308664 -266.647165)
			(xy 115.354822 -266.620516) (xy 115.404436 -266.601044) (xy 115.456398 -266.589184) (xy 115.509548 -266.585201)
			(xy 115.562698 -266.589184) (xy 115.61466 -266.601044) (xy 115.664274 -266.620516) (xy 115.710432 -266.647165)
			(xy 115.752103 -266.680396) (xy 115.788355 -266.719467) (xy 115.818379 -266.763504) (xy 115.841505 -266.811525)
			(xy 115.857215 -266.862455) (xy 115.865158 -266.915159) (xy 115.865656 -266.941808) (xy 115.865158 -266.968457)
			(xy 116.09323 -266.968457) (xy 116.09323 -266.915159) (xy 116.101173 -266.862455) (xy 116.116883 -266.811525)
			(xy 116.140009 -266.763504) (xy 116.170033 -266.719467) (xy 116.206285 -266.680396) (xy 116.247956 -266.647165)
			(xy 116.294114 -266.620516) (xy 116.343728 -266.601044) (xy 116.39569 -266.589184) (xy 116.44884 -266.585201)
			(xy 116.50199 -266.589184) (xy 116.553952 -266.601044) (xy 116.603566 -266.620516) (xy 116.649724 -266.647165)
			(xy 116.691395 -266.680396) (xy 116.727647 -266.719467) (xy 116.757671 -266.763504) (xy 116.780797 -266.811525)
			(xy 116.796507 -266.862455) (xy 116.80445 -266.915159) (xy 116.804948 -266.941808) (xy 116.80445 -266.968457)
			(xy 117.033538 -266.968457) (xy 117.033538 -266.915159) (xy 117.041481 -266.862455) (xy 117.057191 -266.811525)
			(xy 117.080317 -266.763504) (xy 117.110341 -266.719467) (xy 117.146593 -266.680396) (xy 117.188264 -266.647165)
			(xy 117.234422 -266.620516) (xy 117.284036 -266.601044) (xy 117.335998 -266.589184) (xy 117.389148 -266.585201)
			(xy 117.442298 -266.589184) (xy 117.49426 -266.601044) (xy 117.543874 -266.620516) (xy 117.590032 -266.647165)
			(xy 117.631703 -266.680396) (xy 117.667955 -266.719467) (xy 117.697979 -266.763504) (xy 117.721105 -266.811525)
			(xy 117.736815 -266.862455) (xy 117.744758 -266.915159) (xy 117.745256 -266.941808) (xy 117.744758 -266.968457)
			(xy 117.736815 -267.021161) (xy 117.721105 -267.072091) (xy 117.697979 -267.120112) (xy 117.667955 -267.164149)
			(xy 117.631703 -267.20322) (xy 117.590032 -267.236451) (xy 117.543874 -267.2631) (xy 117.49426 -267.282572)
			(xy 117.442298 -267.294432) (xy 117.389148 -267.298416) (xy 117.335998 -267.294432) (xy 117.284036 -267.282572)
			(xy 117.234422 -267.2631) (xy 117.188264 -267.236451) (xy 117.146593 -267.20322) (xy 117.110341 -267.164149)
			(xy 117.080317 -267.120112) (xy 117.057191 -267.072091) (xy 117.041481 -267.021161) (xy 117.033538 -266.968457)
			(xy 116.80445 -266.968457) (xy 116.796507 -267.021161) (xy 116.780797 -267.072091) (xy 116.757671 -267.120112)
			(xy 116.727647 -267.164149) (xy 116.691395 -267.20322) (xy 116.649724 -267.236451) (xy 116.603566 -267.2631)
			(xy 116.553952 -267.282572) (xy 116.50199 -267.294432) (xy 116.44884 -267.298416) (xy 116.39569 -267.294432)
			(xy 116.343728 -267.282572) (xy 116.294114 -267.2631) (xy 116.247956 -267.236451) (xy 116.206285 -267.20322)
			(xy 116.170033 -267.164149) (xy 116.140009 -267.120112) (xy 116.116883 -267.072091) (xy 116.101173 -267.021161)
			(xy 116.09323 -266.968457) (xy 115.865158 -266.968457) (xy 115.857215 -267.021161) (xy 115.841505 -267.072091)
			(xy 115.818379 -267.120112) (xy 115.788355 -267.164149) (xy 115.752103 -267.20322) (xy 115.710432 -267.236451)
			(xy 115.664274 -267.2631) (xy 115.61466 -267.282572) (xy 115.562698 -267.294432) (xy 115.509548 -267.298416)
			(xy 115.456398 -267.294432) (xy 115.404436 -267.282572) (xy 115.354822 -267.2631) (xy 115.308664 -267.236451)
			(xy 115.266993 -267.20322) (xy 115.230741 -267.164149) (xy 115.200717 -267.120112) (xy 115.177591 -267.072091)
			(xy 115.161881 -267.021161) (xy 115.153938 -266.968457) (xy 114.925358 -266.968457) (xy 114.917415 -267.021161)
			(xy 114.901705 -267.072091) (xy 114.878579 -267.120112) (xy 114.848555 -267.164149) (xy 114.812303 -267.20322)
			(xy 114.770632 -267.236451) (xy 114.724474 -267.2631) (xy 114.67486 -267.282572) (xy 114.622898 -267.294432)
			(xy 114.569748 -267.298416) (xy 114.516598 -267.294432) (xy 114.464636 -267.282572) (xy 114.415022 -267.2631)
			(xy 114.368864 -267.236451) (xy 114.327193 -267.20322) (xy 114.290941 -267.164149) (xy 114.260917 -267.120112)
			(xy 114.237791 -267.072091) (xy 114.222081 -267.021161) (xy 114.214138 -266.968457) (xy 113.985261 -266.968457)
			(xy 113.977813 -267.019174) (xy 113.962878 -267.068928) (xy 113.940874 -267.115985) (xy 113.912266 -267.159345)
			(xy 113.877663 -267.198089) (xy 113.85804 -267.215112) (xy 113.85804 -267.320014) (xy 113.858483 -267.333688)
			(xy 113.865744 -267.360055) (xy 113.87974 -267.38355) (xy 113.899469 -267.402489) (xy 113.923517 -267.415514)
			(xy 113.950158 -267.421691) (xy 113.977484 -267.420578) (xy 113.990628 -267.416788) (xy 114.017165 -267.408836)
			(xy 114.071896 -267.400289) (xy 114.099594 -267.39977) (xy 114.126247 -267.400243) (xy 114.178958 -267.408187)
			(xy 114.229896 -267.423898) (xy 114.277924 -267.447027) (xy 114.321967 -267.477055) (xy 114.361044 -267.513312)
			(xy 114.39428 -267.554988) (xy 114.420933 -267.601152) (xy 114.440409 -267.650773) (xy 114.45227 -267.702743)
			(xy 114.456254 -267.7559) (xy 114.454258 -267.782527) (xy 114.683784 -267.782527) (xy 114.683784 -267.729229)
			(xy 114.691727 -267.676525) (xy 114.707437 -267.625595) (xy 114.730563 -267.577574) (xy 114.760587 -267.533537)
			(xy 114.796839 -267.494466) (xy 114.83851 -267.461235) (xy 114.884668 -267.434586) (xy 114.934282 -267.415114)
			(xy 114.986244 -267.403254) (xy 115.039394 -267.399271) (xy 115.092544 -267.403254) (xy 115.144506 -267.415114)
			(xy 115.19412 -267.434586) (xy 115.240278 -267.461235) (xy 115.281949 -267.494466) (xy 115.318201 -267.533537)
			(xy 115.348225 -267.577574) (xy 115.371351 -267.625595) (xy 115.387061 -267.676525) (xy 115.395004 -267.729229)
			(xy 115.395502 -267.755878) (xy 115.395004 -267.782527) (xy 115.623584 -267.782527) (xy 115.623584 -267.729229)
			(xy 115.631527 -267.676525) (xy 115.647237 -267.625595) (xy 115.670363 -267.577574) (xy 115.700387 -267.533537)
			(xy 115.736639 -267.494466) (xy 115.77831 -267.461235) (xy 115.824468 -267.434586) (xy 115.874082 -267.415114)
			(xy 115.926044 -267.403254) (xy 115.979194 -267.399271) (xy 116.032344 -267.403254) (xy 116.084306 -267.415114)
			(xy 116.13392 -267.434586) (xy 116.180078 -267.461235) (xy 116.221749 -267.494466) (xy 116.258001 -267.533537)
			(xy 116.288025 -267.577574) (xy 116.311151 -267.625595) (xy 116.326861 -267.676525) (xy 116.334804 -267.729229)
			(xy 116.335302 -267.755878) (xy 116.334804 -267.782527) (xy 116.563638 -267.782527) (xy 116.563638 -267.729229)
			(xy 116.571581 -267.676525) (xy 116.587291 -267.625595) (xy 116.610417 -267.577574) (xy 116.640441 -267.533537)
			(xy 116.676693 -267.494466) (xy 116.718364 -267.461235) (xy 116.764522 -267.434586) (xy 116.814136 -267.415114)
			(xy 116.866098 -267.403254) (xy 116.919248 -267.399271) (xy 116.972398 -267.403254) (xy 117.02436 -267.415114)
			(xy 117.073974 -267.434586) (xy 117.120132 -267.461235) (xy 117.161803 -267.494466) (xy 117.198055 -267.533537)
			(xy 117.228079 -267.577574) (xy 117.251205 -267.625595) (xy 117.266915 -267.676525) (xy 117.274858 -267.729229)
			(xy 117.275356 -267.755878) (xy 117.274858 -267.782527) (xy 117.266915 -267.835231) (xy 117.251205 -267.886161)
			(xy 117.228079 -267.934182) (xy 117.198055 -267.978219) (xy 117.161803 -268.01729) (xy 117.120132 -268.050521)
			(xy 117.073974 -268.07717) (xy 117.02436 -268.096642) (xy 116.972398 -268.108502) (xy 116.919248 -268.112486)
			(xy 116.866098 -268.108502) (xy 116.814136 -268.096642) (xy 116.764522 -268.07717) (xy 116.718364 -268.050521)
			(xy 116.676693 -268.01729) (xy 116.640441 -267.978219) (xy 116.610417 -267.934182) (xy 116.587291 -267.886161)
			(xy 116.571581 -267.835231) (xy 116.563638 -267.782527) (xy 116.334804 -267.782527) (xy 116.326861 -267.835231)
			(xy 116.311151 -267.886161) (xy 116.288025 -267.934182) (xy 116.258001 -267.978219) (xy 116.221749 -268.01729)
			(xy 116.180078 -268.050521) (xy 116.13392 -268.07717) (xy 116.084306 -268.096642) (xy 116.032344 -268.108502)
			(xy 115.979194 -268.112486) (xy 115.926044 -268.108502) (xy 115.874082 -268.096642) (xy 115.824468 -268.07717)
			(xy 115.77831 -268.050521) (xy 115.736639 -268.01729) (xy 115.700387 -267.978219) (xy 115.670363 -267.934182)
			(xy 115.647237 -267.886161) (xy 115.631527 -267.835231) (xy 115.623584 -267.782527) (xy 115.395004 -267.782527)
			(xy 115.387061 -267.835231) (xy 115.371351 -267.886161) (xy 115.348225 -267.934182) (xy 115.318201 -267.978219)
			(xy 115.281949 -268.01729) (xy 115.240278 -268.050521) (xy 115.19412 -268.07717) (xy 115.144506 -268.096642)
			(xy 115.092544 -268.108502) (xy 115.039394 -268.112486) (xy 114.986244 -268.108502) (xy 114.934282 -268.096642)
			(xy 114.884668 -268.07717) (xy 114.83851 -268.050521) (xy 114.796839 -268.01729) (xy 114.760587 -267.978219)
			(xy 114.730563 -267.934182) (xy 114.707437 -267.886161) (xy 114.691727 -267.835231) (xy 114.683784 -267.782527)
			(xy 114.454258 -267.782527) (xy 114.45227 -267.809057) (xy 114.440409 -267.861027) (xy 114.420933 -267.910648)
			(xy 114.39428 -267.956812) (xy 114.361044 -267.998488) (xy 114.321967 -268.034745) (xy 114.277924 -268.064773)
			(xy 114.229896 -268.087902) (xy 114.178958 -268.103613) (xy 114.126247 -268.111557) (xy 114.099594 -268.111986)
			(xy 114.071895 -268.111479) (xy 114.017163 -268.102929) (xy 113.990628 -268.094968) (xy 113.97747 -268.091213)
			(xy 113.950141 -268.090075) (xy 113.923492 -268.096237) (xy 113.899436 -268.109254) (xy 113.879701 -268.128193)
			(xy 113.865704 -268.151693) (xy 113.858451 -268.178066) (xy 113.85804 -268.191742) (xy 113.85804 -268.29639)
			(xy 113.877671 -268.313405) (xy 113.912276 -268.35215) (xy 113.940884 -268.395511) (xy 113.962889 -268.442569)
			(xy 113.977824 -268.492325) (xy 113.985372 -268.543722) (xy 113.985372 -268.59567) (xy 113.985273 -268.596343)
			(xy 114.214138 -268.596343) (xy 114.214138 -268.543045) (xy 114.222081 -268.490341) (xy 114.237791 -268.439411)
			(xy 114.260917 -268.39139) (xy 114.290941 -268.347353) (xy 114.327193 -268.308282) (xy 114.368864 -268.275051)
			(xy 114.415022 -268.248402) (xy 114.464636 -268.22893) (xy 114.516598 -268.21707) (xy 114.569748 -268.213087)
			(xy 114.622898 -268.21707) (xy 114.67486 -268.22893) (xy 114.724474 -268.248402) (xy 114.770632 -268.275051)
			(xy 114.812303 -268.308282) (xy 114.848555 -268.347353) (xy 114.878579 -268.39139) (xy 114.901705 -268.439411)
			(xy 114.917415 -268.490341) (xy 114.925358 -268.543045) (xy 114.925856 -268.569694) (xy 114.925358 -268.596343)
			(xy 115.153938 -268.596343) (xy 115.153938 -268.543045) (xy 115.161881 -268.490341) (xy 115.177591 -268.439411)
			(xy 115.200717 -268.39139) (xy 115.230741 -268.347353) (xy 115.266993 -268.308282) (xy 115.308664 -268.275051)
			(xy 115.354822 -268.248402) (xy 115.404436 -268.22893) (xy 115.456398 -268.21707) (xy 115.509548 -268.213087)
			(xy 115.562698 -268.21707) (xy 115.61466 -268.22893) (xy 115.664274 -268.248402) (xy 115.710432 -268.275051)
			(xy 115.752103 -268.308282) (xy 115.788355 -268.347353) (xy 115.818379 -268.39139) (xy 115.841505 -268.439411)
			(xy 115.857215 -268.490341) (xy 115.865158 -268.543045) (xy 115.865656 -268.569694) (xy 115.865158 -268.596343)
			(xy 116.093738 -268.596343) (xy 116.093738 -268.543045) (xy 116.101681 -268.490341) (xy 116.117391 -268.439411)
			(xy 116.140517 -268.39139) (xy 116.170541 -268.347353) (xy 116.206793 -268.308282) (xy 116.248464 -268.275051)
			(xy 116.294622 -268.248402) (xy 116.344236 -268.22893) (xy 116.396198 -268.21707) (xy 116.449348 -268.213087)
			(xy 116.502498 -268.21707) (xy 116.55446 -268.22893) (xy 116.604074 -268.248402) (xy 116.650232 -268.275051)
			(xy 116.691903 -268.308282) (xy 116.728155 -268.347353) (xy 116.758179 -268.39139) (xy 116.781305 -268.439411)
			(xy 116.797015 -268.490341) (xy 116.804958 -268.543045) (xy 116.805456 -268.569694) (xy 116.804958 -268.596343)
			(xy 117.033284 -268.596343) (xy 117.033284 -268.543045) (xy 117.041227 -268.490341) (xy 117.056937 -268.439411)
			(xy 117.080063 -268.39139) (xy 117.110087 -268.347353) (xy 117.146339 -268.308282) (xy 117.18801 -268.275051)
			(xy 117.234168 -268.248402) (xy 117.283782 -268.22893) (xy 117.335744 -268.21707) (xy 117.388894 -268.213087)
			(xy 117.442044 -268.21707) (xy 117.494006 -268.22893) (xy 117.54362 -268.248402) (xy 117.589778 -268.275051)
			(xy 117.631449 -268.308282) (xy 117.667701 -268.347353) (xy 117.697725 -268.39139) (xy 117.720851 -268.439411)
			(xy 117.736561 -268.490341) (xy 117.744504 -268.543045) (xy 117.745002 -268.569694) (xy 117.744504 -268.596343)
			(xy 117.736561 -268.649047) (xy 117.720851 -268.699977) (xy 117.697725 -268.747998) (xy 117.667701 -268.792035)
			(xy 117.631449 -268.831106) (xy 117.589778 -268.864337) (xy 117.54362 -268.890986) (xy 117.494006 -268.910458)
			(xy 117.442044 -268.922318) (xy 117.388894 -268.926302) (xy 117.335744 -268.922318) (xy 117.283782 -268.910458)
			(xy 117.234168 -268.890986) (xy 117.18801 -268.864337) (xy 117.146339 -268.831106) (xy 117.110087 -268.792035)
			(xy 117.080063 -268.747998) (xy 117.056937 -268.699977) (xy 117.041227 -268.649047) (xy 117.033284 -268.596343)
			(xy 116.804958 -268.596343) (xy 116.797015 -268.649047) (xy 116.781305 -268.699977) (xy 116.758179 -268.747998)
			(xy 116.728155 -268.792035) (xy 116.691903 -268.831106) (xy 116.650232 -268.864337) (xy 116.604074 -268.890986)
			(xy 116.55446 -268.910458) (xy 116.502498 -268.922318) (xy 116.449348 -268.926302) (xy 116.396198 -268.922318)
			(xy 116.344236 -268.910458) (xy 116.294622 -268.890986) (xy 116.248464 -268.864337) (xy 116.206793 -268.831106)
			(xy 116.170541 -268.792035) (xy 116.140517 -268.747998) (xy 116.117391 -268.699977) (xy 116.101681 -268.649047)
			(xy 116.093738 -268.596343) (xy 115.865158 -268.596343) (xy 115.857215 -268.649047) (xy 115.841505 -268.699977)
			(xy 115.818379 -268.747998) (xy 115.788355 -268.792035) (xy 115.752103 -268.831106) (xy 115.710432 -268.864337)
			(xy 115.664274 -268.890986) (xy 115.61466 -268.910458) (xy 115.562698 -268.922318) (xy 115.509548 -268.926302)
			(xy 115.456398 -268.922318) (xy 115.404436 -268.910458) (xy 115.354822 -268.890986) (xy 115.308664 -268.864337)
			(xy 115.266993 -268.831106) (xy 115.230741 -268.792035) (xy 115.200717 -268.747998) (xy 115.177591 -268.699977)
			(xy 115.161881 -268.649047) (xy 115.153938 -268.596343) (xy 114.925358 -268.596343) (xy 114.917415 -268.649047)
			(xy 114.901705 -268.699977) (xy 114.878579 -268.747998) (xy 114.848555 -268.792035) (xy 114.812303 -268.831106)
			(xy 114.770632 -268.864337) (xy 114.724474 -268.890986) (xy 114.67486 -268.910458) (xy 114.622898 -268.922318)
			(xy 114.569748 -268.926302) (xy 114.516598 -268.922318) (xy 114.464636 -268.910458) (xy 114.415022 -268.890986)
			(xy 114.368864 -268.864337) (xy 114.327193 -268.831106) (xy 114.290941 -268.792035) (xy 114.260917 -268.747998)
			(xy 114.237791 -268.699977) (xy 114.222081 -268.649047) (xy 114.214138 -268.596343) (xy 113.985273 -268.596343)
			(xy 113.977825 -268.647068) (xy 113.962892 -268.696824) (xy 113.940888 -268.743882) (xy 113.91228 -268.787244)
			(xy 113.877677 -268.82599) (xy 113.85804 -268.842998) (xy 113.85804 -268.9479) (xy 113.858496 -268.96159)
			(xy 113.865788 -268.987981) (xy 113.879823 -269.01149) (xy 113.899594 -269.030431) (xy 113.923683 -269.043447)
			(xy 113.950362 -269.049602) (xy 113.977718 -269.048456) (xy 113.990882 -269.044674) (xy 114.017472 -269.036645)
			(xy 114.072332 -269.027972) (xy 114.100102 -269.027402) (xy 114.12675 -269.0279) (xy 114.179452 -269.035844)
			(xy 114.230381 -269.051553) (xy 114.2784 -269.074678) (xy 114.322436 -269.104702) (xy 114.361505 -269.140953)
			(xy 114.394735 -269.182622) (xy 114.421383 -269.228779) (xy 114.440855 -269.278391) (xy 114.452715 -269.330352)
			(xy 114.456698 -269.3835) (xy 114.4547 -269.410159) (xy 114.683784 -269.410159) (xy 114.683784 -269.356861)
			(xy 114.691727 -269.304157) (xy 114.707437 -269.253227) (xy 114.730563 -269.205206) (xy 114.760587 -269.161169)
			(xy 114.796839 -269.122098) (xy 114.83851 -269.088867) (xy 114.884668 -269.062218) (xy 114.934282 -269.042746)
			(xy 114.986244 -269.030886) (xy 115.039394 -269.026903) (xy 115.092544 -269.030886) (xy 115.144506 -269.042746)
			(xy 115.19412 -269.062218) (xy 115.240278 -269.088867) (xy 115.281949 -269.122098) (xy 115.318201 -269.161169)
			(xy 115.348225 -269.205206) (xy 115.371351 -269.253227) (xy 115.387061 -269.304157) (xy 115.395004 -269.356861)
			(xy 115.395502 -269.38351) (xy 115.395004 -269.410159) (xy 115.623584 -269.410159) (xy 115.623584 -269.356861)
			(xy 115.631527 -269.304157) (xy 115.647237 -269.253227) (xy 115.670363 -269.205206) (xy 115.700387 -269.161169)
			(xy 115.736639 -269.122098) (xy 115.77831 -269.088867) (xy 115.824468 -269.062218) (xy 115.874082 -269.042746)
			(xy 115.926044 -269.030886) (xy 115.979194 -269.026903) (xy 116.032344 -269.030886) (xy 116.084306 -269.042746)
			(xy 116.13392 -269.062218) (xy 116.180078 -269.088867) (xy 116.221749 -269.122098) (xy 116.258001 -269.161169)
			(xy 116.288025 -269.205206) (xy 116.311151 -269.253227) (xy 116.326861 -269.304157) (xy 116.334804 -269.356861)
			(xy 116.335302 -269.38351) (xy 116.334804 -269.410159) (xy 116.563384 -269.410159) (xy 116.563384 -269.356861)
			(xy 116.571327 -269.304157) (xy 116.587037 -269.253227) (xy 116.610163 -269.205206) (xy 116.640187 -269.161169)
			(xy 116.676439 -269.122098) (xy 116.71811 -269.088867) (xy 116.764268 -269.062218) (xy 116.813882 -269.042746)
			(xy 116.865844 -269.030886) (xy 116.918994 -269.026903) (xy 116.972144 -269.030886) (xy 117.024106 -269.042746)
			(xy 117.07372 -269.062218) (xy 117.119878 -269.088867) (xy 117.161549 -269.122098) (xy 117.197801 -269.161169)
			(xy 117.227825 -269.205206) (xy 117.250951 -269.253227) (xy 117.266661 -269.304157) (xy 117.274604 -269.356861)
			(xy 117.275102 -269.38351) (xy 117.274604 -269.410159) (xy 117.266661 -269.462863) (xy 117.250951 -269.513793)
			(xy 117.227825 -269.561814) (xy 117.197801 -269.605851) (xy 117.161549 -269.644922) (xy 117.119878 -269.678153)
			(xy 117.07372 -269.704802) (xy 117.024106 -269.724274) (xy 116.972144 -269.736134) (xy 116.918994 -269.740118)
			(xy 116.865844 -269.736134) (xy 116.813882 -269.724274) (xy 116.764268 -269.704802) (xy 116.71811 -269.678153)
			(xy 116.676439 -269.644922) (xy 116.640187 -269.605851) (xy 116.610163 -269.561814) (xy 116.587037 -269.513793)
			(xy 116.571327 -269.462863) (xy 116.563384 -269.410159) (xy 116.334804 -269.410159) (xy 116.326861 -269.462863)
			(xy 116.311151 -269.513793) (xy 116.288025 -269.561814) (xy 116.258001 -269.605851) (xy 116.221749 -269.644922)
			(xy 116.180078 -269.678153) (xy 116.13392 -269.704802) (xy 116.084306 -269.724274) (xy 116.032344 -269.736134)
			(xy 115.979194 -269.740118) (xy 115.926044 -269.736134) (xy 115.874082 -269.724274) (xy 115.824468 -269.704802)
			(xy 115.77831 -269.678153) (xy 115.736639 -269.644922) (xy 115.700387 -269.605851) (xy 115.670363 -269.561814)
			(xy 115.647237 -269.513793) (xy 115.631527 -269.462863) (xy 115.623584 -269.410159) (xy 115.395004 -269.410159)
			(xy 115.387061 -269.462863) (xy 115.371351 -269.513793) (xy 115.348225 -269.561814) (xy 115.318201 -269.605851)
			(xy 115.281949 -269.644922) (xy 115.240278 -269.678153) (xy 115.19412 -269.704802) (xy 115.144506 -269.724274)
			(xy 115.092544 -269.736134) (xy 115.039394 -269.740118) (xy 114.986244 -269.736134) (xy 114.934282 -269.724274)
			(xy 114.884668 -269.704802) (xy 114.83851 -269.678153) (xy 114.796839 -269.644922) (xy 114.760587 -269.605851)
			(xy 114.730563 -269.561814) (xy 114.707437 -269.513793) (xy 114.691727 -269.462863) (xy 114.683784 -269.410159)
			(xy 114.4547 -269.410159) (xy 114.452715 -269.436648) (xy 114.440855 -269.488609) (xy 114.421383 -269.538221)
			(xy 114.394735 -269.584378) (xy 114.361505 -269.626047) (xy 114.322436 -269.662298) (xy 114.2784 -269.692322)
			(xy 114.230381 -269.715447) (xy 114.179452 -269.731156) (xy 114.12675 -269.7391) (xy 114.100102 -269.739618)
			(xy 114.072331 -269.739065) (xy 114.01747 -269.730385) (xy 113.990882 -269.722346) (xy 113.977709 -269.718552)
			(xy 113.950333 -269.717354) (xy 113.923625 -269.723482) (xy 113.89951 -269.736496) (xy 113.879726 -269.755455)
			(xy 113.865699 -269.778995) (xy 113.85844 -269.805418) (xy 113.85804 -269.81912) (xy 113.85804 -269.924276)
			(xy 113.877672 -269.941291) (xy 113.912279 -269.980036) (xy 113.940889 -270.023398) (xy 113.962896 -270.070457)
			(xy 113.977832 -270.120213) (xy 113.985382 -270.171612) (xy 113.985384 -270.223562) (xy 113.985286 -270.224229)
			(xy 116.093738 -270.224229) (xy 116.093738 -270.170931) (xy 116.101681 -270.118227) (xy 116.117391 -270.067297)
			(xy 116.140517 -270.019276) (xy 116.170541 -269.975239) (xy 116.206793 -269.936168) (xy 116.248464 -269.902937)
			(xy 116.294622 -269.876288) (xy 116.344236 -269.856816) (xy 116.396198 -269.844956) (xy 116.449348 -269.840973)
			(xy 116.502498 -269.844956) (xy 116.55446 -269.856816) (xy 116.604074 -269.876288) (xy 116.650232 -269.902937)
			(xy 116.691903 -269.936168) (xy 116.728155 -269.975239) (xy 116.758179 -270.019276) (xy 116.781305 -270.067297)
			(xy 116.797015 -270.118227) (xy 116.804958 -270.170931) (xy 116.805456 -270.19758) (xy 116.804958 -270.224229)
			(xy 116.797015 -270.276933) (xy 116.781305 -270.327863) (xy 116.758179 -270.375884) (xy 116.728155 -270.419921)
			(xy 116.691903 -270.458992) (xy 116.650232 -270.492223) (xy 116.604074 -270.518872) (xy 116.55446 -270.538344)
			(xy 116.502498 -270.550204) (xy 116.449348 -270.554188) (xy 116.396198 -270.550204) (xy 116.344236 -270.538344)
			(xy 116.294622 -270.518872) (xy 116.248464 -270.492223) (xy 116.206793 -270.458992) (xy 116.170541 -270.419921)
			(xy 116.140517 -270.375884) (xy 116.117391 -270.327863) (xy 116.101681 -270.276933) (xy 116.093738 -270.224229)
			(xy 113.985286 -270.224229) (xy 113.977838 -270.274961) (xy 113.962905 -270.324719) (xy 113.940901 -270.371779)
			(xy 113.912294 -270.415144) (xy 113.877691 -270.453892) (xy 113.85804 -270.470884) (xy 113.85804 -271.343628)
			(xy 114.08156 -271.567148)
		)
		(stroke
			(width 0)
			(type solid)
		)
		(fill yes)
		(layer "In13.Cu")
		(net "PVPP_HBM_CPU1")
	)
	(gr_poly
		(pts
			(xy 362.264452 -271.567148) (xy 362.284428 -271.548853) (xy 362.328882 -271.517906) (xy 362.377511 -271.494048)
			(xy 362.429192 -271.47783) (xy 362.482733 -271.469627) (xy 362.536899 -271.469627) (xy 362.59044 -271.47783)
			(xy 362.642121 -271.494048) (xy 362.69075 -271.517906) (xy 362.735204 -271.548853) (xy 362.75518 -271.567148)
			(xy 363.204252 -271.567148) (xy 363.224228 -271.548853) (xy 363.268682 -271.517906) (xy 363.317311 -271.494048)
			(xy 363.368992 -271.47783) (xy 363.422533 -271.469627) (xy 363.476699 -271.469627) (xy 363.53024 -271.47783)
			(xy 363.581921 -271.494048) (xy 363.63055 -271.517906) (xy 363.675004 -271.548853) (xy 363.69498 -271.567148)
			(xy 364.143544 -271.567148) (xy 364.16352 -271.548852) (xy 364.207974 -271.517901) (xy 364.256602 -271.494036)
			(xy 364.308283 -271.47781) (xy 364.361824 -271.469595) (xy 364.388908 -271.469104) (xy 364.408243 -271.469357)
			(xy 364.446683 -271.473559) (xy 364.465616 -271.477486) (xy 364.492794 -271.483582) (xy 364.588806 -271.38757)
			(xy 364.599349 -271.376306) (xy 364.613698 -271.34901) (xy 364.619242 -271.318675) (xy 364.615475 -271.288068)
			(xy 364.60274 -271.259982) (xy 364.59287 -271.248124) (xy 364.576023 -271.228448) (xy 364.547603 -271.185143)
			(xy 364.525752 -271.13818) (xy 364.510928 -271.088549) (xy 364.503445 -271.037295) (xy 364.502954 -271.011396)
			(xy 364.503503 -270.983412) (xy 364.512259 -270.928133) (xy 364.529553 -270.874904) (xy 364.554961 -270.825036)
			(xy 364.587856 -270.779756) (xy 364.62743 -270.740178) (xy 364.672707 -270.707278) (xy 364.722573 -270.681866)
			(xy 364.7758 -270.664566) (xy 364.831078 -270.655806) (xy 364.859062 -270.655288) (xy 364.884965 -270.655731)
			(xy 364.936229 -270.663197) (xy 364.985868 -270.67802) (xy 365.032832 -270.699888) (xy 365.076127 -270.728336)
			(xy 365.09579 -270.745204) (xy 365.107651 -270.755075) (xy 365.135739 -270.767815) (xy 365.16635 -270.77159)
			(xy 365.196692 -270.766054) (xy 365.223998 -270.751712) (xy 365.235236 -270.74114) (xy 365.268764 -270.707612)
			(xy 365.279004 -270.69662) (xy 365.29315 -270.670135) (xy 365.29898 -270.640681) (xy 365.29599 -270.610804)
			(xy 365.284438 -270.583089) (xy 365.265323 -270.559933) (xy 365.240299 -270.543339) (xy 365.226092 -270.538448)
			(xy 365.202013 -270.530718) (xy 365.156152 -270.509403) (xy 365.113768 -270.481815) (xy 365.075713 -270.448509)
			(xy 365.042752 -270.410155) (xy 365.015548 -270.367523) (xy 364.994649 -270.321472) (xy 364.980474 -270.272927)
			(xy 364.973308 -270.222866) (xy 364.972854 -270.19758) (xy 364.973404 -270.169597) (xy 364.982162 -270.11432)
			(xy 364.999458 -270.061093) (xy 365.024866 -270.011227) (xy 365.057762 -269.965949) (xy 365.097335 -269.926374)
			(xy 365.142611 -269.893476) (xy 365.192476 -269.868064) (xy 365.245702 -269.850766) (xy 365.300979 -269.842006)
			(xy 365.328962 -269.841472) (xy 365.354249 -269.841913) (xy 365.404315 -269.849067) (xy 365.452864 -269.863235)
			(xy 365.498918 -269.884133) (xy 365.541551 -269.911339) (xy 365.579903 -269.944307) (xy 365.613202 -269.982371)
			(xy 365.640778 -270.024765) (xy 365.662076 -270.070636) (xy 365.66983 -270.09471) (xy 365.674667 -270.10893)
			(xy 365.691296 -270.133925) (xy 365.714466 -270.153015) (xy 365.742182 -270.164553) (xy 365.772054 -270.167545)
			(xy 365.801507 -270.161734) (xy 365.828004 -270.147619) (xy 365.838994 -270.137382) (xy 365.966248 -270.010128)
			(xy 365.978474 -269.991103) (xy 366.006989 -269.956002) (xy 366.039702 -269.924777) (xy 366.057688 -269.911068)
			(xy 366.057688 -269.813532) (xy 366.057243 -269.79957) (xy 366.049667 -269.772691) (xy 366.035099 -269.748867)
			(xy 366.014627 -269.729874) (xy 365.989778 -269.717132) (xy 365.962408 -269.71159) (xy 365.93456 -269.713663)
			(xy 365.92129 -269.718028) (xy 365.891763 -269.728125) (xy 365.830316 -269.738984) (xy 365.799116 -269.739618)
			(xy 365.772463 -269.739146) (xy 365.719753 -269.731203) (xy 365.668815 -269.715493) (xy 365.620788 -269.692366)
			(xy 365.576745 -269.66234) (xy 365.537668 -269.626084) (xy 365.504432 -269.584409) (xy 365.477779 -269.538245)
			(xy 365.458304 -269.488625) (xy 365.446442 -269.436656) (xy 365.442458 -269.3835) (xy 365.446442 -269.330344)
			(xy 365.458304 -269.278375) (xy 365.477779 -269.228755) (xy 365.504432 -269.182591) (xy 365.537668 -269.140916)
			(xy 365.576745 -269.10466) (xy 365.620788 -269.074634) (xy 365.668815 -269.051507) (xy 365.719753 -269.035797)
			(xy 365.772463 -269.027854) (xy 365.799116 -269.027402) (xy 365.830315 -269.028046) (xy 365.891762 -269.038898)
			(xy 365.92129 -269.048992) (xy 365.934565 -269.053366) (xy 365.962427 -269.055465) (xy 365.989815 -269.049938)
			(xy 366.014681 -269.037197) (xy 366.035166 -269.018195) (xy 366.049737 -268.994355) (xy 366.057303 -268.967458)
			(xy 366.057688 -268.953488) (xy 366.057688 -268.856206) (xy 366.03565 -268.839305) (xy 365.996602 -268.799818)
			(xy 365.964162 -268.754744) (xy 365.939116 -268.705178) (xy 365.922074 -268.652324) (xy 365.913448 -268.597463)
			(xy 365.913449 -268.541929) (xy 365.922075 -268.487069) (xy 365.939119 -268.434215) (xy 365.964165 -268.38465)
			(xy 365.996607 -268.339577) (xy 366.035656 -268.30009) (xy 366.057688 -268.283182) (xy 366.057688 -268.185646)
			(xy 366.05722 -268.171696) (xy 366.049607 -268.144852) (xy 366.035018 -268.121067) (xy 366.014541 -268.102114)
			(xy 365.989701 -268.089405) (xy 365.96235 -268.083886) (xy 365.934525 -268.08597) (xy 365.92129 -268.090396)
			(xy 365.891701 -268.10051) (xy 365.830126 -268.11137) (xy 365.798862 -268.111986) (xy 365.772216 -268.111485)
			(xy 365.719521 -268.103537) (xy 365.668598 -268.087825) (xy 365.620586 -268.064699) (xy 365.576556 -268.034676)
			(xy 365.537492 -267.998426) (xy 365.504267 -267.95676) (xy 365.477623 -267.910607) (xy 365.458155 -267.860998)
			(xy 365.446297 -267.809043) (xy 365.442315 -267.7559) (xy 365.446297 -267.702757) (xy 365.458155 -267.650802)
			(xy 365.477623 -267.601193) (xy 365.504267 -267.55504) (xy 365.537492 -267.513374) (xy 365.576556 -267.477124)
			(xy 365.620586 -267.447101) (xy 365.668598 -267.423975) (xy 365.719521 -267.408263) (xy 365.772216 -267.400315)
			(xy 365.798862 -267.39977) (xy 365.830125 -267.400397) (xy 365.891701 -267.411248) (xy 365.92129 -267.42136)
			(xy 365.934546 -267.425731) (xy 365.962368 -267.427839) (xy 365.989723 -267.422338) (xy 366.014568 -267.409639)
			(xy 366.035049 -267.39069) (xy 366.049638 -267.366906) (xy 366.057245 -267.34006) (xy 366.057688 -267.32611)
			(xy 366.057688 -267.228828) (xy 366.03725 -267.213259) (xy 366.000641 -267.17721) (xy 365.969593 -267.136276)
			(xy 365.944749 -267.091304) (xy 365.926625 -267.043229) (xy 365.915598 -266.993049) (xy 365.911896 -266.941805)
			(xy 365.915596 -266.89056) (xy 365.926622 -266.84038) (xy 365.944745 -266.792304) (xy 365.969588 -266.747332)
			(xy 366.000635 -266.706397) (xy 366.037243 -266.670348) (xy 366.057688 -266.654788) (xy 366.057688 -266.558014)
			(xy 366.057216 -266.544067) (xy 366.049598 -266.517231) (xy 366.035008 -266.493454) (xy 366.014532 -266.474508)
			(xy 365.989697 -266.461803) (xy 365.962352 -266.456286) (xy 365.934533 -266.458368) (xy 365.92129 -266.462764)
			(xy 365.891701 -266.472879) (xy 365.830126 -266.48374) (xy 365.798862 -266.484354) (xy 365.772211 -266.483854)
			(xy 365.719505 -266.475904) (xy 365.668573 -266.460189) (xy 365.620551 -266.437058) (xy 365.576513 -266.407029)
			(xy 365.537442 -266.370773) (xy 365.504211 -266.329098) (xy 365.477562 -266.282936) (xy 365.458089 -266.233319)
			(xy 365.446229 -266.181353) (xy 365.442246 -266.1282) (xy 365.446229 -266.075047) (xy 365.458089 -266.023081)
			(xy 365.477562 -265.973464) (xy 365.504211 -265.927302) (xy 365.537442 -265.885627) (xy 365.576513 -265.849371)
			(xy 365.620551 -265.819342) (xy 365.668573 -265.796211) (xy 365.719505 -265.780496) (xy 365.772211 -265.772546)
			(xy 365.798862 -265.772138) (xy 365.830125 -265.772765) (xy 365.891702 -265.783615) (xy 365.92129 -265.793728)
			(xy 365.934544 -265.7981) (xy 365.962365 -265.800209) (xy 365.989717 -265.794708) (xy 366.01456 -265.782009)
			(xy 366.035037 -265.763058) (xy 366.04962 -265.739273) (xy 366.057219 -265.712427) (xy 366.057688 -265.698478)
			(xy 366.057688 -265.600942) (xy 366.035622 -265.584033) (xy 365.996523 -265.544519) (xy 365.964039 -265.499409)
			(xy 365.93896 -265.449799) (xy 365.921895 -265.396894) (xy 365.913258 -265.34198) (xy 365.913261 -265.286391)
			(xy 365.921901 -265.231478) (xy 365.938971 -265.178575) (xy 365.964054 -265.128967) (xy 365.996541 -265.083859)
			(xy 366.035644 -265.044349) (xy 366.057688 -265.02741) (xy 366.057688 -264.930128) (xy 366.057217 -264.91618)
			(xy 366.049602 -264.88934) (xy 366.035012 -264.86556) (xy 366.014536 -264.84661) (xy 365.989699 -264.833904)
			(xy 365.962351 -264.828386) (xy 365.93453 -264.830469) (xy 365.92129 -264.834878) (xy 365.891701 -264.844993)
			(xy 365.830126 -264.855853) (xy 365.798862 -264.856468) (xy 365.772218 -264.855967) (xy 365.719525 -264.84802)
			(xy 365.668604 -264.832308) (xy 365.620595 -264.809183) (xy 365.576567 -264.779162) (xy 365.537506 -264.742914)
			(xy 365.504282 -264.701249) (xy 365.47764 -264.655099) (xy 365.458172 -264.605493) (xy 365.446315 -264.55354)
			(xy 365.442333 -264.5004) (xy 365.446315 -264.44726) (xy 365.458172 -264.395307) (xy 365.47764 -264.345701)
			(xy 365.504282 -264.299551) (xy 365.537506 -264.257886) (xy 365.576567 -264.221638) (xy 365.620595 -264.191617)
			(xy 365.668604 -264.168492) (xy 365.719525 -264.15278) (xy 365.772218 -264.144833) (xy 365.798862 -264.144252)
			(xy 365.830125 -264.144879) (xy 365.891701 -264.15573) (xy 365.92129 -264.165842) (xy 365.934545 -264.170213)
			(xy 365.962366 -264.172322) (xy 365.98972 -264.166821) (xy 366.014563 -264.154122) (xy 366.035042 -264.135172)
			(xy 366.049628 -264.111387) (xy 366.05723 -264.084542) (xy 366.057688 -264.070592) (xy 366.057688 -262.301228)
			(xy 365.597948 -261.841488) (xy 363.982508 -261.841488) (xy 363.700568 -262.123428) (xy 363.700568 -263.433814)
			(xy 363.71838 -263.452139) (xy 363.749104 -263.492973) (xy 363.773679 -263.537778) (xy 363.791601 -263.585634)
			(xy 363.802501 -263.63556) (xy 363.806157 -263.686531) (xy 363.802492 -263.737502) (xy 363.791583 -263.787426)
			(xy 363.773653 -263.835279) (xy 363.74907 -263.880079) (xy 363.718339 -263.920908) (xy 363.700568 -263.939274)
			(xy 363.700568 -264.057892) (xy 363.700998 -264.071184) (xy 363.70786 -264.096866) (xy 363.721122 -264.119906)
			(xy 363.739883 -264.138739) (xy 363.762871 -264.152089) (xy 363.788527 -264.159051) (xy 363.815111 -264.159151)
			(xy 363.828076 -264.15619) (xy 363.85046 -264.150619) (xy 363.896198 -264.14463) (xy 363.919262 -264.144252)
			(xy 363.945918 -264.144723) (xy 363.998635 -264.152663) (xy 364.04958 -264.168373) (xy 364.097614 -264.1915)
			(xy 364.141664 -264.221529) (xy 364.180747 -264.257788) (xy 364.213988 -264.299468) (xy 364.240646 -264.345636)
			(xy 364.260124 -264.395262) (xy 364.271988 -264.447237) (xy 364.275972 -264.5004) (xy 364.273978 -264.527009)
			(xy 364.503452 -264.527009) (xy 364.503452 -264.473711) (xy 364.511395 -264.421007) (xy 364.527105 -264.370077)
			(xy 364.550231 -264.322056) (xy 364.580255 -264.278019) (xy 364.616507 -264.238948) (xy 364.658178 -264.205717)
			(xy 364.704336 -264.179068) (xy 364.75395 -264.159596) (xy 364.805912 -264.147736) (xy 364.859062 -264.143753)
			(xy 364.912212 -264.147736) (xy 364.964174 -264.159596) (xy 365.013788 -264.179068) (xy 365.059946 -264.205717)
			(xy 365.101617 -264.238948) (xy 365.137869 -264.278019) (xy 365.167893 -264.322056) (xy 365.191019 -264.370077)
			(xy 365.206729 -264.421007) (xy 365.214672 -264.473711) (xy 365.21517 -264.50036) (xy 365.214672 -264.527009)
			(xy 365.206729 -264.579713) (xy 365.191019 -264.630643) (xy 365.167893 -264.678664) (xy 365.137869 -264.722701)
			(xy 365.101617 -264.761772) (xy 365.059946 -264.795003) (xy 365.013788 -264.821652) (xy 364.964174 -264.841124)
			(xy 364.912212 -264.852984) (xy 364.859062 -264.856968) (xy 364.805912 -264.852984) (xy 364.75395 -264.841124)
			(xy 364.704336 -264.821652) (xy 364.658178 -264.795003) (xy 364.616507 -264.761772) (xy 364.580255 -264.722701)
			(xy 364.550231 -264.678664) (xy 364.527105 -264.630643) (xy 364.511395 -264.579713) (xy 364.503452 -264.527009)
			(xy 364.273978 -264.527009) (xy 364.271988 -264.553563) (xy 364.260124 -264.605538) (xy 364.240646 -264.655164)
			(xy 364.213988 -264.701332) (xy 364.180747 -264.743012) (xy 364.141664 -264.779271) (xy 364.097614 -264.8093)
			(xy 364.04958 -264.832427) (xy 363.998635 -264.848137) (xy 363.945918 -264.856077) (xy 363.919262 -264.856468)
			(xy 363.892356 -264.855974) (xy 363.839157 -264.847878) (xy 363.78778 -264.831875) (xy 363.739393 -264.80833)
			(xy 363.695096 -264.777778) (xy 363.675168 -264.759694) (xy 363.663351 -264.749372) (xy 363.635071 -264.735819)
			(xy 363.604015 -264.731465) (xy 363.573098 -264.736718) (xy 363.545224 -264.751087) (xy 363.53369 -264.761726)
			(xy 363.495336 -264.80008) (xy 363.484905 -264.811213) (xy 363.470643 -264.838167) (xy 363.464979 -264.86813)
			(xy 363.468416 -264.898431) (xy 363.48065 -264.926364) (xy 363.500588 -264.949437) (xy 363.526452 -264.965593)
			(xy 363.541056 -264.970006) (xy 363.566016 -264.977123) (xy 363.613711 -264.997592) (xy 363.65793 -265.024766)
			(xy 363.697736 -265.058072) (xy 363.732286 -265.096802) (xy 363.760849 -265.140138) (xy 363.782818 -265.18716)
			(xy 363.797729 -265.236874) (xy 363.805266 -265.288225) (xy 363.805724 -265.314176) (xy 363.805231 -265.340825)
			(xy 364.033806 -265.340825) (xy 364.033806 -265.287527) (xy 364.041749 -265.234823) (xy 364.057459 -265.183893)
			(xy 364.080585 -265.135872) (xy 364.110609 -265.091835) (xy 364.146861 -265.052764) (xy 364.188532 -265.019533)
			(xy 364.23469 -264.992884) (xy 364.284304 -264.973412) (xy 364.336266 -264.961552) (xy 364.389416 -264.957569)
			(xy 364.442566 -264.961552) (xy 364.494528 -264.973412) (xy 364.544142 -264.992884) (xy 364.5903 -265.019533)
			(xy 364.631971 -265.052764) (xy 364.668223 -265.091835) (xy 364.698247 -265.135872) (xy 364.721373 -265.183893)
			(xy 364.737083 -265.234823) (xy 364.745026 -265.287527) (xy 364.745524 -265.314176) (xy 364.745026 -265.340825)
			(xy 364.973606 -265.340825) (xy 364.973606 -265.287527) (xy 364.981549 -265.234823) (xy 364.997259 -265.183893)
			(xy 365.020385 -265.135872) (xy 365.050409 -265.091835) (xy 365.086661 -265.052764) (xy 365.128332 -265.019533)
			(xy 365.17449 -264.992884) (xy 365.224104 -264.973412) (xy 365.276066 -264.961552) (xy 365.329216 -264.957569)
			(xy 365.382366 -264.961552) (xy 365.434328 -264.973412) (xy 365.483942 -264.992884) (xy 365.5301 -265.019533)
			(xy 365.571771 -265.052764) (xy 365.608023 -265.091835) (xy 365.638047 -265.135872) (xy 365.661173 -265.183893)
			(xy 365.676883 -265.234823) (xy 365.684826 -265.287527) (xy 365.685324 -265.314176) (xy 365.684826 -265.340825)
			(xy 365.676883 -265.393529) (xy 365.661173 -265.444459) (xy 365.638047 -265.49248) (xy 365.608023 -265.536517)
			(xy 365.571771 -265.575588) (xy 365.5301 -265.608819) (xy 365.483942 -265.635468) (xy 365.434328 -265.65494)
			(xy 365.382366 -265.6668) (xy 365.329216 -265.670784) (xy 365.276066 -265.6668) (xy 365.224104 -265.65494)
			(xy 365.17449 -265.635468) (xy 365.128332 -265.608819) (xy 365.086661 -265.575588) (xy 365.050409 -265.536517)
			(xy 365.020385 -265.49248) (xy 364.997259 -265.444459) (xy 364.981549 -265.393529) (xy 364.973606 -265.340825)
			(xy 364.745026 -265.340825) (xy 364.737083 -265.393529) (xy 364.721373 -265.444459) (xy 364.698247 -265.49248)
			(xy 364.668223 -265.536517) (xy 364.631971 -265.575588) (xy 364.5903 -265.608819) (xy 364.544142 -265.635468)
			(xy 364.494528 -265.65494) (xy 364.442566 -265.6668) (xy 364.389416 -265.670784) (xy 364.336266 -265.6668)
			(xy 364.284304 -265.65494) (xy 364.23469 -265.635468) (xy 364.188532 -265.608819) (xy 364.146861 -265.575588)
			(xy 364.110609 -265.536517) (xy 364.080585 -265.49248) (xy 364.057459 -265.444459) (xy 364.041749 -265.393529)
			(xy 364.033806 -265.340825) (xy 363.805231 -265.340825) (xy 363.805206 -265.342163) (xy 363.796453 -265.397449)
			(xy 363.779159 -265.450684) (xy 363.753751 -265.500559) (xy 363.720853 -265.545845) (xy 363.681275 -265.585427)
			(xy 363.635993 -265.61833) (xy 363.586121 -265.643744) (xy 363.532888 -265.661044) (xy 363.477603 -265.669803)
			(xy 363.449616 -265.670284) (xy 363.423665 -265.669816) (xy 363.372313 -265.662283) (xy 363.322599 -265.647375)
			(xy 363.275576 -265.625408) (xy 363.23224 -265.596847) (xy 363.193509 -265.562298) (xy 363.160204 -265.522491)
			(xy 363.133032 -265.478271) (xy 363.112566 -265.430575) (xy 363.105446 -265.405616) (xy 363.100963 -265.391062)
			(xy 363.084778 -265.365284) (xy 363.061718 -265.345418) (xy 363.033829 -265.333226) (xy 363.003587 -265.329789)
			(xy 362.973673 -265.335413) (xy 362.946744 -265.349599) (xy 362.93552 -265.359896) (xy 362.83392 -265.461496)
			(xy 362.83011 -265.46937) (xy 362.81658 -265.495931) (xy 362.782038 -265.544505) (xy 362.739891 -265.58665)
			(xy 362.691315 -265.62119) (xy 362.664756 -265.634724) (xy 362.656882 -265.638534) (xy 362.348272 -265.947144)
			(xy 362.363004 -265.979148) (xy 362.373338 -266.002632) (xy 362.387921 -266.051822) (xy 362.395314 -266.102593)
			(xy 362.39577 -266.128246) (xy 362.395244 -266.154895) (xy 362.623852 -266.154895) (xy 362.623852 -266.101597)
			(xy 362.631795 -266.048893) (xy 362.647505 -265.997963) (xy 362.670631 -265.949942) (xy 362.700655 -265.905905)
			(xy 362.736907 -265.866834) (xy 362.778578 -265.833603) (xy 362.824736 -265.806954) (xy 362.87435 -265.787482)
			(xy 362.926312 -265.775622) (xy 362.979462 -265.771639) (xy 363.032612 -265.775622) (xy 363.084574 -265.787482)
			(xy 363.134188 -265.806954) (xy 363.180346 -265.833603) (xy 363.222017 -265.866834) (xy 363.258269 -265.905905)
			(xy 363.288293 -265.949942) (xy 363.311419 -265.997963) (xy 363.327129 -266.048893) (xy 363.335072 -266.101597)
			(xy 363.33557 -266.128246) (xy 363.335072 -266.154895) (xy 363.563652 -266.154895) (xy 363.563652 -266.101597)
			(xy 363.571595 -266.048893) (xy 363.587305 -265.997963) (xy 363.610431 -265.949942) (xy 363.640455 -265.905905)
			(xy 363.676707 -265.866834) (xy 363.718378 -265.833603) (xy 363.764536 -265.806954) (xy 363.81415 -265.787482)
			(xy 363.866112 -265.775622) (xy 363.919262 -265.771639) (xy 363.972412 -265.775622) (xy 364.024374 -265.787482)
			(xy 364.073988 -265.806954) (xy 364.120146 -265.833603) (xy 364.161817 -265.866834) (xy 364.198069 -265.905905)
			(xy 364.228093 -265.949942) (xy 364.251219 -265.997963) (xy 364.266929 -266.048893) (xy 364.274872 -266.101597)
			(xy 364.27537 -266.128246) (xy 364.274872 -266.154895) (xy 364.274834 -266.155149) (xy 364.503452 -266.155149)
			(xy 364.503452 -266.101851) (xy 364.511395 -266.049147) (xy 364.527105 -265.998217) (xy 364.550231 -265.950196)
			(xy 364.580255 -265.906159) (xy 364.616507 -265.867088) (xy 364.658178 -265.833857) (xy 364.704336 -265.807208)
			(xy 364.75395 -265.787736) (xy 364.805912 -265.775876) (xy 364.859062 -265.771893) (xy 364.912212 -265.775876)
			(xy 364.964174 -265.787736) (xy 365.013788 -265.807208) (xy 365.059946 -265.833857) (xy 365.101617 -265.867088)
			(xy 365.137869 -265.906159) (xy 365.167893 -265.950196) (xy 365.191019 -265.998217) (xy 365.206729 -266.049147)
			(xy 365.214672 -266.101851) (xy 365.21517 -266.1285) (xy 365.214672 -266.155149) (xy 365.206729 -266.207853)
			(xy 365.191019 -266.258783) (xy 365.167893 -266.306804) (xy 365.137869 -266.350841) (xy 365.101617 -266.389912)
			(xy 365.059946 -266.423143) (xy 365.013788 -266.449792) (xy 364.964174 -266.469264) (xy 364.912212 -266.481124)
			(xy 364.859062 -266.485108) (xy 364.805912 -266.481124) (xy 364.75395 -266.469264) (xy 364.704336 -266.449792)
			(xy 364.658178 -266.423143) (xy 364.616507 -266.389912) (xy 364.580255 -266.350841) (xy 364.550231 -266.306804)
			(xy 364.527105 -266.258783) (xy 364.511395 -266.207853) (xy 364.503452 -266.155149) (xy 364.274834 -266.155149)
			(xy 364.266929 -266.207599) (xy 364.251219 -266.258529) (xy 364.228093 -266.30655) (xy 364.198069 -266.350587)
			(xy 364.161817 -266.389658) (xy 364.120146 -266.422889) (xy 364.073988 -266.449538) (xy 364.024374 -266.46901)
			(xy 363.972412 -266.48087) (xy 363.919262 -266.484854) (xy 363.866112 -266.48087) (xy 363.81415 -266.46901)
			(xy 363.764536 -266.449538) (xy 363.718378 -266.422889) (xy 363.676707 -266.389658) (xy 363.640455 -266.350587)
			(xy 363.610431 -266.30655) (xy 363.587305 -266.258529) (xy 363.571595 -266.207599) (xy 363.563652 -266.154895)
			(xy 363.335072 -266.154895) (xy 363.327129 -266.207599) (xy 363.311419 -266.258529) (xy 363.288293 -266.30655)
			(xy 363.258269 -266.350587) (xy 363.222017 -266.389658) (xy 363.180346 -266.422889) (xy 363.134188 -266.449538)
			(xy 363.084574 -266.46901) (xy 363.032612 -266.48087) (xy 362.979462 -266.484854) (xy 362.926312 -266.48087)
			(xy 362.87435 -266.46901) (xy 362.824736 -266.449538) (xy 362.778578 -266.422889) (xy 362.736907 -266.389658)
			(xy 362.700655 -266.350587) (xy 362.670631 -266.30655) (xy 362.647505 -266.258529) (xy 362.631795 -266.207599)
			(xy 362.623852 -266.154895) (xy 362.395244 -266.154895) (xy 362.395218 -266.156226) (xy 362.386457 -266.211495)
			(xy 362.369158 -266.264713) (xy 362.343746 -266.314571) (xy 362.310849 -266.359839) (xy 362.271275 -266.399403)
			(xy 362.225999 -266.43229) (xy 362.176136 -266.45769) (xy 362.122913 -266.474976) (xy 362.067642 -266.483724)
			(xy 362.039662 -266.484354) (xy 362.014008 -266.483907) (xy 361.963232 -266.476533) (xy 361.914046 -266.461929)
			(xy 361.890564 -266.451588) (xy 361.85856 -266.436856) (xy 361.798108 -266.497308) (xy 361.798108 -266.668504)
			(xy 361.81774 -266.685518) (xy 361.852345 -266.724261) (xy 361.880954 -266.767622) (xy 361.902959 -266.814679)
			(xy 361.917894 -266.864434) (xy 361.925441 -266.915831) (xy 361.92544 -266.967779) (xy 361.92534 -266.968457)
			(xy 362.153952 -266.968457) (xy 362.153952 -266.915159) (xy 362.161895 -266.862455) (xy 362.177605 -266.811525)
			(xy 362.200731 -266.763504) (xy 362.230755 -266.719467) (xy 362.267007 -266.680396) (xy 362.308678 -266.647165)
			(xy 362.354836 -266.620516) (xy 362.40445 -266.601044) (xy 362.456412 -266.589184) (xy 362.509562 -266.585201)
			(xy 362.562712 -266.589184) (xy 362.614674 -266.601044) (xy 362.664288 -266.620516) (xy 362.710446 -266.647165)
			(xy 362.752117 -266.680396) (xy 362.788369 -266.719467) (xy 362.818393 -266.763504) (xy 362.841519 -266.811525)
			(xy 362.857229 -266.862455) (xy 362.865172 -266.915159) (xy 362.86567 -266.941808) (xy 362.865172 -266.968457)
			(xy 363.093752 -266.968457) (xy 363.093752 -266.915159) (xy 363.101695 -266.862455) (xy 363.117405 -266.811525)
			(xy 363.140531 -266.763504) (xy 363.170555 -266.719467) (xy 363.206807 -266.680396) (xy 363.248478 -266.647165)
			(xy 363.294636 -266.620516) (xy 363.34425 -266.601044) (xy 363.396212 -266.589184) (xy 363.449362 -266.585201)
			(xy 363.502512 -266.589184) (xy 363.554474 -266.601044) (xy 363.604088 -266.620516) (xy 363.650246 -266.647165)
			(xy 363.691917 -266.680396) (xy 363.728169 -266.719467) (xy 363.758193 -266.763504) (xy 363.781319 -266.811525)
			(xy 363.797029 -266.862455) (xy 363.804972 -266.915159) (xy 363.80547 -266.941808) (xy 363.804972 -266.968457)
			(xy 364.033552 -266.968457) (xy 364.033552 -266.915159) (xy 364.041495 -266.862455) (xy 364.057205 -266.811525)
			(xy 364.080331 -266.763504) (xy 364.110355 -266.719467) (xy 364.146607 -266.680396) (xy 364.188278 -266.647165)
			(xy 364.234436 -266.620516) (xy 364.28405 -266.601044) (xy 364.336012 -266.589184) (xy 364.389162 -266.585201)
			(xy 364.442312 -266.589184) (xy 364.494274 -266.601044) (xy 364.543888 -266.620516) (xy 364.590046 -266.647165)
			(xy 364.631717 -266.680396) (xy 364.667969 -266.719467) (xy 364.697993 -266.763504) (xy 364.721119 -266.811525)
			(xy 364.736829 -266.862455) (xy 364.744772 -266.915159) (xy 364.74527 -266.941808) (xy 364.744772 -266.968457)
			(xy 364.973606 -266.968457) (xy 364.973606 -266.915159) (xy 364.981549 -266.862455) (xy 364.997259 -266.811525)
			(xy 365.020385 -266.763504) (xy 365.050409 -266.719467) (xy 365.086661 -266.680396) (xy 365.128332 -266.647165)
			(xy 365.17449 -266.620516) (xy 365.224104 -266.601044) (xy 365.276066 -266.589184) (xy 365.329216 -266.585201)
			(xy 365.382366 -266.589184) (xy 365.434328 -266.601044) (xy 365.483942 -266.620516) (xy 365.5301 -266.647165)
			(xy 365.571771 -266.680396) (xy 365.608023 -266.719467) (xy 365.638047 -266.763504) (xy 365.661173 -266.811525)
			(xy 365.676883 -266.862455) (xy 365.684826 -266.915159) (xy 365.685324 -266.941808) (xy 365.684826 -266.968457)
			(xy 365.676883 -267.021161) (xy 365.661173 -267.072091) (xy 365.638047 -267.120112) (xy 365.608023 -267.164149)
			(xy 365.571771 -267.20322) (xy 365.5301 -267.236451) (xy 365.483942 -267.2631) (xy 365.434328 -267.282572)
			(xy 365.382366 -267.294432) (xy 365.329216 -267.298416) (xy 365.276066 -267.294432) (xy 365.224104 -267.282572)
			(xy 365.17449 -267.2631) (xy 365.128332 -267.236451) (xy 365.086661 -267.20322) (xy 365.050409 -267.164149)
			(xy 365.020385 -267.120112) (xy 364.997259 -267.072091) (xy 364.981549 -267.021161) (xy 364.973606 -266.968457)
			(xy 364.744772 -266.968457) (xy 364.736829 -267.021161) (xy 364.721119 -267.072091) (xy 364.697993 -267.120112)
			(xy 364.667969 -267.164149) (xy 364.631717 -267.20322) (xy 364.590046 -267.236451) (xy 364.543888 -267.2631)
			(xy 364.494274 -267.282572) (xy 364.442312 -267.294432) (xy 364.389162 -267.298416) (xy 364.336012 -267.294432)
			(xy 364.28405 -267.282572) (xy 364.234436 -267.2631) (xy 364.188278 -267.236451) (xy 364.146607 -267.20322)
			(xy 364.110355 -267.164149) (xy 364.080331 -267.120112) (xy 364.057205 -267.072091) (xy 364.041495 -267.021161)
			(xy 364.033552 -266.968457) (xy 363.804972 -266.968457) (xy 363.797029 -267.021161) (xy 363.781319 -267.072091)
			(xy 363.758193 -267.120112) (xy 363.728169 -267.164149) (xy 363.691917 -267.20322) (xy 363.650246 -267.236451)
			(xy 363.604088 -267.2631) (xy 363.554474 -267.282572) (xy 363.502512 -267.294432) (xy 363.449362 -267.298416)
			(xy 363.396212 -267.294432) (xy 363.34425 -267.282572) (xy 363.294636 -267.2631) (xy 363.248478 -267.236451)
			(xy 363.206807 -267.20322) (xy 363.170555 -267.164149) (xy 363.140531 -267.120112) (xy 363.117405 -267.072091)
			(xy 363.101695 -267.021161) (xy 363.093752 -266.968457) (xy 362.865172 -266.968457) (xy 362.857229 -267.021161)
			(xy 362.841519 -267.072091) (xy 362.818393 -267.120112) (xy 362.788369 -267.164149) (xy 362.752117 -267.20322)
			(xy 362.710446 -267.236451) (xy 362.664288 -267.2631) (xy 362.614674 -267.282572) (xy 362.562712 -267.294432)
			(xy 362.509562 -267.298416) (xy 362.456412 -267.294432) (xy 362.40445 -267.282572) (xy 362.354836 -267.2631)
			(xy 362.308678 -267.236451) (xy 362.267007 -267.20322) (xy 362.230755 -267.164149) (xy 362.200731 -267.120112)
			(xy 362.177605 -267.072091) (xy 362.161895 -267.021161) (xy 362.153952 -266.968457) (xy 361.92534 -266.968457)
			(xy 361.917892 -267.019176) (xy 361.902956 -267.068931) (xy 361.880949 -267.115987) (xy 361.852339 -267.159347)
			(xy 361.817732 -267.19809) (xy 361.798108 -267.215112) (xy 361.798108 -267.320014) (xy 361.798552 -267.333683)
			(xy 361.805812 -267.360041) (xy 361.819808 -267.383526) (xy 361.839536 -267.402453) (xy 361.86358 -267.415465)
			(xy 361.890216 -267.421628) (xy 361.917531 -267.4205) (xy 361.930696 -267.416788) (xy 361.957232 -267.408833)
			(xy 362.011964 -267.400282) (xy 362.039662 -267.39977) (xy 362.066317 -267.400241) (xy 362.119031 -267.408181)
			(xy 362.169973 -267.42389) (xy 362.218005 -267.447016) (xy 362.262053 -267.477043) (xy 362.301134 -267.5133)
			(xy 362.334373 -267.554978) (xy 362.361029 -267.601144) (xy 362.380507 -267.650767) (xy 362.39237 -267.70274)
			(xy 362.396354 -267.7559) (xy 362.394358 -267.782527) (xy 362.623852 -267.782527) (xy 362.623852 -267.729229)
			(xy 362.631795 -267.676525) (xy 362.647505 -267.625595) (xy 362.670631 -267.577574) (xy 362.700655 -267.533537)
			(xy 362.736907 -267.494466) (xy 362.778578 -267.461235) (xy 362.824736 -267.434586) (xy 362.87435 -267.415114)
			(xy 362.926312 -267.403254) (xy 362.979462 -267.399271) (xy 363.032612 -267.403254) (xy 363.084574 -267.415114)
			(xy 363.134188 -267.434586) (xy 363.180346 -267.461235) (xy 363.222017 -267.494466) (xy 363.258269 -267.533537)
			(xy 363.288293 -267.577574) (xy 363.311419 -267.625595) (xy 363.327129 -267.676525) (xy 363.335072 -267.729229)
			(xy 363.33557 -267.755878) (xy 363.335072 -267.782527) (xy 363.563652 -267.782527) (xy 363.563652 -267.729229)
			(xy 363.571595 -267.676525) (xy 363.587305 -267.625595) (xy 363.610431 -267.577574) (xy 363.640455 -267.533537)
			(xy 363.676707 -267.494466) (xy 363.718378 -267.461235) (xy 363.764536 -267.434586) (xy 363.81415 -267.415114)
			(xy 363.866112 -267.403254) (xy 363.919262 -267.399271) (xy 363.972412 -267.403254) (xy 364.024374 -267.415114)
			(xy 364.073988 -267.434586) (xy 364.120146 -267.461235) (xy 364.161817 -267.494466) (xy 364.198069 -267.533537)
			(xy 364.228093 -267.577574) (xy 364.251219 -267.625595) (xy 364.266929 -267.676525) (xy 364.274872 -267.729229)
			(xy 364.27537 -267.755878) (xy 364.274872 -267.782527) (xy 364.503706 -267.782527) (xy 364.503706 -267.729229)
			(xy 364.511649 -267.676525) (xy 364.527359 -267.625595) (xy 364.550485 -267.577574) (xy 364.580509 -267.533537)
			(xy 364.616761 -267.494466) (xy 364.658432 -267.461235) (xy 364.70459 -267.434586) (xy 364.754204 -267.415114)
			(xy 364.806166 -267.403254) (xy 364.859316 -267.399271) (xy 364.912466 -267.403254) (xy 364.964428 -267.415114)
			(xy 365.014042 -267.434586) (xy 365.0602 -267.461235) (xy 365.101871 -267.494466) (xy 365.138123 -267.533537)
			(xy 365.168147 -267.577574) (xy 365.191273 -267.625595) (xy 365.206983 -267.676525) (xy 365.214926 -267.729229)
			(xy 365.215424 -267.755878) (xy 365.214926 -267.782527) (xy 365.206983 -267.835231) (xy 365.191273 -267.886161)
			(xy 365.168147 -267.934182) (xy 365.138123 -267.978219) (xy 365.101871 -268.01729) (xy 365.0602 -268.050521)
			(xy 365.014042 -268.07717) (xy 364.964428 -268.096642) (xy 364.912466 -268.108502) (xy 364.859316 -268.112486)
			(xy 364.806166 -268.108502) (xy 364.754204 -268.096642) (xy 364.70459 -268.07717) (xy 364.658432 -268.050521)
			(xy 364.616761 -268.01729) (xy 364.580509 -267.978219) (xy 364.550485 -267.934182) (xy 364.527359 -267.886161)
			(xy 364.511649 -267.835231) (xy 364.503706 -267.782527) (xy 364.274872 -267.782527) (xy 364.266929 -267.835231)
			(xy 364.251219 -267.886161) (xy 364.228093 -267.934182) (xy 364.198069 -267.978219) (xy 364.161817 -268.01729)
			(xy 364.120146 -268.050521) (xy 364.073988 -268.07717) (xy 364.024374 -268.096642) (xy 363.972412 -268.108502)
			(xy 363.919262 -268.112486) (xy 363.866112 -268.108502) (xy 363.81415 -268.096642) (xy 363.764536 -268.07717)
			(xy 363.718378 -268.050521) (xy 363.676707 -268.01729) (xy 363.640455 -267.978219) (xy 363.610431 -267.934182)
			(xy 363.587305 -267.886161) (xy 363.571595 -267.835231) (xy 363.563652 -267.782527) (xy 363.335072 -267.782527)
			(xy 363.327129 -267.835231) (xy 363.311419 -267.886161) (xy 363.288293 -267.934182) (xy 363.258269 -267.978219)
			(xy 363.222017 -268.01729) (xy 363.180346 -268.050521) (xy 363.134188 -268.07717) (xy 363.084574 -268.096642)
			(xy 363.032612 -268.108502) (xy 362.979462 -268.112486) (xy 362.926312 -268.108502) (xy 362.87435 -268.096642)
			(xy 362.824736 -268.07717) (xy 362.778578 -268.050521) (xy 362.736907 -268.01729) (xy 362.700655 -267.978219)
			(xy 362.670631 -267.934182) (xy 362.647505 -267.886161) (xy 362.631795 -267.835231) (xy 362.623852 -267.782527)
			(xy 362.394358 -267.782527) (xy 362.39237 -267.80906) (xy 362.380507 -267.861033) (xy 362.361029 -267.910656)
			(xy 362.334373 -267.956822) (xy 362.301134 -267.9985) (xy 362.262053 -268.034757) (xy 362.218005 -268.064784)
			(xy 362.169973 -268.08791) (xy 362.119031 -268.103619) (xy 362.066317 -268.111559) (xy 362.039662 -268.111986)
			(xy 362.011962 -268.111484) (xy 361.957227 -268.102944) (xy 361.930696 -268.094968) (xy 361.91754 -268.091217)
			(xy 361.890218 -268.090087) (xy 361.863577 -268.096253) (xy 361.839529 -268.109271) (xy 361.819802 -268.128207)
			(xy 361.80581 -268.151702) (xy 361.79856 -268.178069) (xy 361.798108 -268.191742) (xy 361.798108 -268.29639)
			(xy 361.817741 -268.313404) (xy 361.852348 -268.352148) (xy 361.880959 -268.395509) (xy 361.902966 -268.442567)
			(xy 361.917902 -268.492323) (xy 361.925451 -268.543721) (xy 361.925452 -268.595671) (xy 361.925353 -268.596343)
			(xy 362.154206 -268.596343) (xy 362.154206 -268.543045) (xy 362.162149 -268.490341) (xy 362.177859 -268.439411)
			(xy 362.200985 -268.39139) (xy 362.231009 -268.347353) (xy 362.267261 -268.308282) (xy 362.308932 -268.275051)
			(xy 362.35509 -268.248402) (xy 362.404704 -268.22893) (xy 362.456666 -268.21707) (xy 362.509816 -268.213087)
			(xy 362.562966 -268.21707) (xy 362.614928 -268.22893) (xy 362.664542 -268.248402) (xy 362.7107 -268.275051)
			(xy 362.752371 -268.308282) (xy 362.788623 -268.347353) (xy 362.818647 -268.39139) (xy 362.841773 -268.439411)
			(xy 362.857483 -268.490341) (xy 362.865426 -268.543045) (xy 362.865924 -268.569694) (xy 362.865426 -268.596343)
			(xy 363.094006 -268.596343) (xy 363.094006 -268.543045) (xy 363.101949 -268.490341) (xy 363.117659 -268.439411)
			(xy 363.140785 -268.39139) (xy 363.170809 -268.347353) (xy 363.207061 -268.308282) (xy 363.248732 -268.275051)
			(xy 363.29489 -268.248402) (xy 363.344504 -268.22893) (xy 363.396466 -268.21707) (xy 363.449616 -268.213087)
			(xy 363.502766 -268.21707) (xy 363.554728 -268.22893) (xy 363.604342 -268.248402) (xy 363.6505 -268.275051)
			(xy 363.692171 -268.308282) (xy 363.728423 -268.347353) (xy 363.758447 -268.39139) (xy 363.781573 -268.439411)
			(xy 363.797283 -268.490341) (xy 363.805226 -268.543045) (xy 363.805724 -268.569694) (xy 363.805226 -268.596343)
			(xy 364.033806 -268.596343) (xy 364.033806 -268.543045) (xy 364.041749 -268.490341) (xy 364.057459 -268.439411)
			(xy 364.080585 -268.39139) (xy 364.110609 -268.347353) (xy 364.146861 -268.308282) (xy 364.188532 -268.275051)
			(xy 364.23469 -268.248402) (xy 364.284304 -268.22893) (xy 364.336266 -268.21707) (xy 364.389416 -268.213087)
			(xy 364.442566 -268.21707) (xy 364.494528 -268.22893) (xy 364.544142 -268.248402) (xy 364.5903 -268.275051)
			(xy 364.631971 -268.308282) (xy 364.668223 -268.347353) (xy 364.698247 -268.39139) (xy 364.721373 -268.439411)
			(xy 364.737083 -268.490341) (xy 364.745026 -268.543045) (xy 364.745524 -268.569694) (xy 364.745026 -268.596343)
			(xy 364.973352 -268.596343) (xy 364.973352 -268.543045) (xy 364.981295 -268.490341) (xy 364.997005 -268.439411)
			(xy 365.020131 -268.39139) (xy 365.050155 -268.347353) (xy 365.086407 -268.308282) (xy 365.128078 -268.275051)
			(xy 365.174236 -268.248402) (xy 365.22385 -268.22893) (xy 365.275812 -268.21707) (xy 365.328962 -268.213087)
			(xy 365.382112 -268.21707) (xy 365.434074 -268.22893) (xy 365.483688 -268.248402) (xy 365.529846 -268.275051)
			(xy 365.571517 -268.308282) (xy 365.607769 -268.347353) (xy 365.637793 -268.39139) (xy 365.660919 -268.439411)
			(xy 365.676629 -268.490341) (xy 365.684572 -268.543045) (xy 365.68507 -268.569694) (xy 365.684572 -268.596343)
			(xy 365.676629 -268.649047) (xy 365.660919 -268.699977) (xy 365.637793 -268.747998) (xy 365.607769 -268.792035)
			(xy 365.571517 -268.831106) (xy 365.529846 -268.864337) (xy 365.483688 -268.890986) (xy 365.434074 -268.910458)
			(xy 365.382112 -268.922318) (xy 365.328962 -268.926302) (xy 365.275812 -268.922318) (xy 365.22385 -268.910458)
			(xy 365.174236 -268.890986) (xy 365.128078 -268.864337) (xy 365.086407 -268.831106) (xy 365.050155 -268.792035)
			(xy 365.020131 -268.747998) (xy 364.997005 -268.699977) (xy 364.981295 -268.649047) (xy 364.973352 -268.596343)
			(xy 364.745026 -268.596343) (xy 364.737083 -268.649047) (xy 364.721373 -268.699977) (xy 364.698247 -268.747998)
			(xy 364.668223 -268.792035) (xy 364.631971 -268.831106) (xy 364.5903 -268.864337) (xy 364.544142 -268.890986)
			(xy 364.494528 -268.910458) (xy 364.442566 -268.922318) (xy 364.389416 -268.926302) (xy 364.336266 -268.922318)
			(xy 364.284304 -268.910458) (xy 364.23469 -268.890986) (xy 364.188532 -268.864337) (xy 364.146861 -268.831106)
			(xy 364.110609 -268.792035) (xy 364.080585 -268.747998) (xy 364.057459 -268.699977) (xy 364.041749 -268.649047)
			(xy 364.033806 -268.596343) (xy 363.805226 -268.596343) (xy 363.797283 -268.649047) (xy 363.781573 -268.699977)
			(xy 363.758447 -268.747998) (xy 363.728423 -268.792035) (xy 363.692171 -268.831106) (xy 363.6505 -268.864337)
			(xy 363.604342 -268.890986) (xy 363.554728 -268.910458) (xy 363.502766 -268.922318) (xy 363.449616 -268.926302)
			(xy 363.396466 -268.922318) (xy 363.344504 -268.910458) (xy 363.29489 -268.890986) (xy 363.248732 -268.864337)
			(xy 363.207061 -268.831106) (xy 363.170809 -268.792035) (xy 363.140785 -268.747998) (xy 363.117659 -268.699977)
			(xy 363.101949 -268.649047) (xy 363.094006 -268.596343) (xy 362.865426 -268.596343) (xy 362.857483 -268.649047)
			(xy 362.841773 -268.699977) (xy 362.818647 -268.747998) (xy 362.788623 -268.792035) (xy 362.752371 -268.831106)
			(xy 362.7107 -268.864337) (xy 362.664542 -268.890986) (xy 362.614928 -268.910458) (xy 362.562966 -268.922318)
			(xy 362.509816 -268.926302) (xy 362.456666 -268.922318) (xy 362.404704 -268.910458) (xy 362.35509 -268.890986)
			(xy 362.308932 -268.864337) (xy 362.267261 -268.831106) (xy 362.231009 -268.792035) (xy 362.200985 -268.747998)
			(xy 362.177859 -268.699977) (xy 362.162149 -268.649047) (xy 362.154206 -268.596343) (xy 361.925353 -268.596343)
			(xy 361.917904 -268.647069) (xy 361.902969 -268.696826) (xy 361.880963 -268.743884) (xy 361.852353 -268.787246)
			(xy 361.817746 -268.825991) (xy 361.798108 -268.842998) (xy 361.798108 -268.9479) (xy 361.798564 -268.961585)
			(xy 361.805857 -268.987967) (xy 361.819891 -269.011465) (xy 361.839661 -269.030395) (xy 361.863746 -269.043397)
			(xy 361.890419 -269.049538) (xy 361.917766 -269.048378) (xy 361.93095 -269.044674) (xy 361.95754 -269.036643)
			(xy 362.0124 -269.027965) (xy 362.04017 -269.027402) (xy 362.066822 -269.027873) (xy 362.119531 -269.035814)
			(xy 362.170467 -269.051522) (xy 362.218494 -269.074646) (xy 362.262537 -269.104671) (xy 362.301613 -269.140925)
			(xy 362.334848 -269.182598) (xy 362.361502 -269.22876) (xy 362.380977 -269.278378) (xy 362.392838 -269.330345)
			(xy 362.396822 -269.3835) (xy 362.394824 -269.410159) (xy 362.623852 -269.410159) (xy 362.623852 -269.356861)
			(xy 362.631795 -269.304157) (xy 362.647505 -269.253227) (xy 362.670631 -269.205206) (xy 362.700655 -269.161169)
			(xy 362.736907 -269.122098) (xy 362.778578 -269.088867) (xy 362.824736 -269.062218) (xy 362.87435 -269.042746)
			(xy 362.926312 -269.030886) (xy 362.979462 -269.026903) (xy 363.032612 -269.030886) (xy 363.084574 -269.042746)
			(xy 363.134188 -269.062218) (xy 363.180346 -269.088867) (xy 363.222017 -269.122098) (xy 363.258269 -269.161169)
			(xy 363.288293 -269.205206) (xy 363.311419 -269.253227) (xy 363.327129 -269.304157) (xy 363.335072 -269.356861)
			(xy 363.33557 -269.38351) (xy 363.335072 -269.410159) (xy 363.563652 -269.410159) (xy 363.563652 -269.356861)
			(xy 363.571595 -269.304157) (xy 363.587305 -269.253227) (xy 363.610431 -269.205206) (xy 363.640455 -269.161169)
			(xy 363.676707 -269.122098) (xy 363.718378 -269.088867) (xy 363.764536 -269.062218) (xy 363.81415 -269.042746)
			(xy 363.866112 -269.030886) (xy 363.919262 -269.026903) (xy 363.972412 -269.030886) (xy 364.024374 -269.042746)
			(xy 364.073988 -269.062218) (xy 364.120146 -269.088867) (xy 364.161817 -269.122098) (xy 364.198069 -269.161169)
			(xy 364.228093 -269.205206) (xy 364.251219 -269.253227) (xy 364.266929 -269.304157) (xy 364.274872 -269.356861)
			(xy 364.27537 -269.38351) (xy 364.274872 -269.410159) (xy 364.503452 -269.410159) (xy 364.503452 -269.356861)
			(xy 364.511395 -269.304157) (xy 364.527105 -269.253227) (xy 364.550231 -269.205206) (xy 364.580255 -269.161169)
			(xy 364.616507 -269.122098) (xy 364.658178 -269.088867) (xy 364.704336 -269.062218) (xy 364.75395 -269.042746)
			(xy 364.805912 -269.030886) (xy 364.859062 -269.026903) (xy 364.912212 -269.030886) (xy 364.964174 -269.042746)
			(xy 365.013788 -269.062218) (xy 365.059946 -269.088867) (xy 365.101617 -269.122098) (xy 365.137869 -269.161169)
			(xy 365.167893 -269.205206) (xy 365.191019 -269.253227) (xy 365.206729 -269.304157) (xy 365.214672 -269.356861)
			(xy 365.21517 -269.38351) (xy 365.214672 -269.410159) (xy 365.206729 -269.462863) (xy 365.191019 -269.513793)
			(xy 365.167893 -269.561814) (xy 365.137869 -269.605851) (xy 365.101617 -269.644922) (xy 365.059946 -269.678153)
			(xy 365.013788 -269.704802) (xy 364.964174 -269.724274) (xy 364.912212 -269.736134) (xy 364.859062 -269.740118)
			(xy 364.805912 -269.736134) (xy 364.75395 -269.724274) (xy 364.704336 -269.704802) (xy 364.658178 -269.678153)
			(xy 364.616507 -269.644922) (xy 364.580255 -269.605851) (xy 364.550231 -269.561814) (xy 364.527105 -269.513793)
			(xy 364.511395 -269.462863) (xy 364.503452 -269.410159) (xy 364.274872 -269.410159) (xy 364.266929 -269.462863)
			(xy 364.251219 -269.513793) (xy 364.228093 -269.561814) (xy 364.198069 -269.605851) (xy 364.161817 -269.644922)
			(xy 364.120146 -269.678153) (xy 364.073988 -269.704802) (xy 364.024374 -269.724274) (xy 363.972412 -269.736134)
			(xy 363.919262 -269.740118) (xy 363.866112 -269.736134) (xy 363.81415 -269.724274) (xy 363.764536 -269.704802)
			(xy 363.718378 -269.678153) (xy 363.676707 -269.644922) (xy 363.640455 -269.605851) (xy 363.610431 -269.561814)
			(xy 363.587305 -269.513793) (xy 363.571595 -269.462863) (xy 363.563652 -269.410159) (xy 363.335072 -269.410159)
			(xy 363.327129 -269.462863) (xy 363.311419 -269.513793) (xy 363.288293 -269.561814) (xy 363.258269 -269.605851)
			(xy 363.222017 -269.644922) (xy 363.180346 -269.678153) (xy 363.134188 -269.704802) (xy 363.084574 -269.724274)
			(xy 363.032612 -269.736134) (xy 362.979462 -269.740118) (xy 362.926312 -269.736134) (xy 362.87435 -269.724274)
			(xy 362.824736 -269.704802) (xy 362.778578 -269.678153) (xy 362.736907 -269.644922) (xy 362.700655 -269.605851)
			(xy 362.670631 -269.561814) (xy 362.647505 -269.513793) (xy 362.631795 -269.462863) (xy 362.623852 -269.410159)
			(xy 362.394824 -269.410159) (xy 362.392838 -269.436655) (xy 362.380977 -269.488622) (xy 362.361502 -269.53824)
			(xy 362.334848 -269.584402) (xy 362.301613 -269.626075) (xy 362.262537 -269.662329) (xy 362.218494 -269.692354)
			(xy 362.170467 -269.715478) (xy 362.119531 -269.731186) (xy 362.066822 -269.739127) (xy 362.04017 -269.739618)
			(xy 362.012398 -269.739071) (xy 361.957534 -269.7304) (xy 361.93095 -269.722346) (xy 361.91778 -269.718556)
			(xy 361.89041 -269.717366) (xy 361.86371 -269.723499) (xy 361.839603 -269.736512) (xy 361.819827 -269.75547)
			(xy 361.805805 -269.779005) (xy 361.798549 -269.805422) (xy 361.798108 -269.81912) (xy 361.798108 -269.924276)
			(xy 361.817742 -269.94129) (xy 361.852351 -269.980034) (xy 361.880964 -270.023396) (xy 361.902973 -270.070455)
			(xy 361.917911 -270.120212) (xy 361.925461 -270.171612) (xy 361.925463 -270.223563) (xy 361.925365 -270.224229)
			(xy 364.033806 -270.224229) (xy 364.033806 -270.170931) (xy 364.041749 -270.118227) (xy 364.057459 -270.067297)
			(xy 364.080585 -270.019276) (xy 364.110609 -269.975239) (xy 364.146861 -269.936168) (xy 364.188532 -269.902937)
			(xy 364.23469 -269.876288) (xy 364.284304 -269.856816) (xy 364.336266 -269.844956) (xy 364.389416 -269.840973)
			(xy 364.442566 -269.844956) (xy 364.494528 -269.856816) (xy 364.544142 -269.876288) (xy 364.5903 -269.902937)
			(xy 364.631971 -269.936168) (xy 364.668223 -269.975239) (xy 364.698247 -270.019276) (xy 364.721373 -270.067297)
			(xy 364.737083 -270.118227) (xy 364.745026 -270.170931) (xy 364.745524 -270.19758) (xy 364.745026 -270.224229)
			(xy 364.737083 -270.276933) (xy 364.721373 -270.327863) (xy 364.698247 -270.375884) (xy 364.668223 -270.419921)
			(xy 364.631971 -270.458992) (xy 364.5903 -270.492223) (xy 364.544142 -270.518872) (xy 364.494528 -270.538344)
			(xy 364.442566 -270.550204) (xy 364.389416 -270.554188) (xy 364.336266 -270.550204) (xy 364.284304 -270.538344)
			(xy 364.23469 -270.518872) (xy 364.188532 -270.492223) (xy 364.146861 -270.458992) (xy 364.110609 -270.419921)
			(xy 364.080585 -270.375884) (xy 364.057459 -270.327863) (xy 364.041749 -270.276933) (xy 364.033806 -270.224229)
			(xy 361.925365 -270.224229) (xy 361.917917 -270.274963) (xy 361.902982 -270.324721) (xy 361.880977 -270.371782)
			(xy 361.852367 -270.415146) (xy 361.81776 -270.453892) (xy 361.798108 -270.470884) (xy 361.798108 -271.343628)
			(xy 362.021628 -271.567148)
		)
		(stroke
			(width 0)
			(type solid)
		)
		(fill yes)
		(layer "In13.Cu")
		(net "PVPP_HBM_CPU0")
	)
	(gr_poly
		(pts
			(xy 374.777 -415.29) (xy 374.777 -413.527494) (xy 374.011444 -411.679644) (xy 373.6086 -411.2768)
			(xy 371.7544 -411.2768) (xy 370.5098 -410.0322) (xy 370.5098 -398.001744) (xy 370.509349 -397.987983)
			(xy 370.501994 -397.961464) (xy 370.487809 -397.93788) (xy 370.467829 -397.918954) (xy 370.443513 -397.906066)
			(xy 370.416634 -397.900157) (xy 370.402866 -397.900398) (xy 370.3828 -397.900906) (xy 370.355549 -397.90042)
			(xy 370.301601 -397.892664) (xy 370.249307 -397.877309) (xy 370.19973 -397.854668) (xy 370.15388 -397.825202)
			(xy 370.11269 -397.78951) (xy 370.076998 -397.74832) (xy 370.047532 -397.70247) (xy 370.024891 -397.652893)
			(xy 370.009536 -397.600599) (xy 370.00178 -397.546651) (xy 370.00178 -397.492149) (xy 370.009536 -397.438201)
			(xy 370.024891 -397.385907) (xy 370.047532 -397.33633) (xy 370.076998 -397.29048) (xy 370.11269 -397.24929)
			(xy 370.15388 -397.213598) (xy 370.19973 -397.184132) (xy 370.249307 -397.161491) (xy 370.301601 -397.146136)
			(xy 370.355549 -397.13838) (xy 370.3828 -397.13789) (xy 370.402866 -397.138398) (xy 370.416621 -397.138655)
			(xy 370.443467 -397.132691) (xy 370.467747 -397.119779) (xy 370.487701 -397.100855) (xy 370.501882 -397.077293)
			(xy 370.50926 -397.050801) (xy 370.5098 -397.037052) (xy 370.5098 -396.731744) (xy 370.509349 -396.717983)
			(xy 370.501994 -396.691464) (xy 370.487809 -396.66788) (xy 370.467829 -396.648954) (xy 370.443513 -396.636066)
			(xy 370.416634 -396.630157) (xy 370.402866 -396.630398) (xy 370.3828 -396.630906) (xy 370.355549 -396.63042)
			(xy 370.301601 -396.622664) (xy 370.249307 -396.607309) (xy 370.19973 -396.584668) (xy 370.15388 -396.555202)
			(xy 370.11269 -396.51951) (xy 370.076998 -396.47832) (xy 370.047532 -396.43247) (xy 370.024891 -396.382893)
			(xy 370.009536 -396.330599) (xy 370.00178 -396.276651) (xy 370.00178 -396.222149) (xy 370.009536 -396.168201)
			(xy 370.024891 -396.115907) (xy 370.047532 -396.06633) (xy 370.076998 -396.02048) (xy 370.11269 -395.97929)
			(xy 370.15388 -395.943598) (xy 370.19973 -395.914132) (xy 370.249307 -395.891491) (xy 370.301601 -395.876136)
			(xy 370.355549 -395.86838) (xy 370.3828 -395.86789) (xy 370.402866 -395.868398) (xy 370.416621 -395.868655)
			(xy 370.443467 -395.862691) (xy 370.467747 -395.849779) (xy 370.487701 -395.830855) (xy 370.501882 -395.807293)
			(xy 370.50926 -395.780801) (xy 370.5098 -395.767052) (xy 370.5098 -385.9784) (xy 368.5032 -383.9718)
			(xy 356.4128 -383.9718) (xy 355.21011 -385.17449) (xy 356.068882 -385.17449) (xy 356.072953 -385.118868)
			(xy 356.085079 -385.064431) (xy 356.105002 -385.01234) (xy 356.132298 -384.963705) (xy 356.166384 -384.919562)
			(xy 356.206533 -384.880853) (xy 356.251891 -384.848402) (xy 356.301491 -384.822901) (xy 356.354275 -384.804894)
			(xy 356.409118 -384.794764) (xy 356.464852 -384.792727) (xy 356.520289 -384.798827) (xy 356.574246 -384.812933)
			(xy 356.625575 -384.834745) (xy 356.673181 -384.863799) (xy 356.716049 -384.899474) (xy 356.753266 -384.941011)
			(xy 356.784039 -384.987524) (xy 356.807711 -385.038021) (xy 356.823779 -385.091428) (xy 356.831899 -385.146604)
			(xy 356.832408 -385.17449) (xy 356.831899 -385.202376) (xy 356.823779 -385.257552) (xy 356.807711 -385.310959)
			(xy 356.784039 -385.361456) (xy 356.753266 -385.407969) (xy 356.716049 -385.449506) (xy 356.673181 -385.485181)
			(xy 356.625575 -385.514235) (xy 356.574246 -385.536047) (xy 356.520289 -385.550153) (xy 356.464852 -385.556253)
			(xy 356.409118 -385.554216) (xy 356.354275 -385.544086) (xy 356.301491 -385.526079) (xy 356.251891 -385.500578)
			(xy 356.206533 -385.468127) (xy 356.166384 -385.429418) (xy 356.132298 -385.385275) (xy 356.105002 -385.33664)
			(xy 356.085079 -385.284549) (xy 356.072953 -385.230112) (xy 356.068882 -385.17449) (xy 355.21011 -385.17449)
			(xy 355.0158 -385.3688) (xy 355.0158 -385.790948) (xy 355.273862 -385.790948) (xy 355.277933 -385.735326)
			(xy 355.290059 -385.680889) (xy 355.309982 -385.628798) (xy 355.337278 -385.580163) (xy 355.371364 -385.53602)
			(xy 355.411513 -385.497311) (xy 355.456871 -385.46486) (xy 355.506471 -385.439359) (xy 355.559255 -385.421352)
			(xy 355.614098 -385.411222) (xy 355.669832 -385.409185) (xy 355.725269 -385.415285) (xy 355.779226 -385.429391)
			(xy 355.830555 -385.451203) (xy 355.878161 -385.480257) (xy 355.921029 -385.515932) (xy 355.958246 -385.557469)
			(xy 355.989019 -385.603982) (xy 356.012691 -385.654479) (xy 356.028759 -385.707886) (xy 356.036879 -385.763062)
			(xy 356.037388 -385.790948) (xy 356.036879 -385.818834) (xy 356.028759 -385.87401) (xy 356.012691 -385.927417)
			(xy 355.989019 -385.977914) (xy 355.958246 -386.024427) (xy 355.921029 -386.065964) (xy 355.878161 -386.101639)
			(xy 355.830555 -386.130693) (xy 355.779226 -386.152505) (xy 355.725269 -386.166611) (xy 355.669832 -386.172711)
			(xy 355.614098 -386.170674) (xy 355.559255 -386.160544) (xy 355.506471 -386.142537) (xy 355.456871 -386.117036)
			(xy 355.411513 -386.084585) (xy 355.371364 -386.045876) (xy 355.337278 -386.001733) (xy 355.309982 -385.953098)
			(xy 355.290059 -385.901007) (xy 355.277933 -385.84657) (xy 355.273862 -385.790948) (xy 355.0158 -385.790948)
			(xy 355.0158 -386.41909) (xy 356.068882 -386.41909) (xy 356.072953 -386.363468) (xy 356.085079 -386.309031)
			(xy 356.105002 -386.25694) (xy 356.132298 -386.208305) (xy 356.166384 -386.164162) (xy 356.206533 -386.125453)
			(xy 356.251891 -386.093002) (xy 356.301491 -386.067501) (xy 356.354275 -386.049494) (xy 356.409118 -386.039364)
			(xy 356.464852 -386.037327) (xy 356.520289 -386.043427) (xy 356.574246 -386.057533) (xy 356.625575 -386.079345)
			(xy 356.673181 -386.108399) (xy 356.716049 -386.144074) (xy 356.753266 -386.185611) (xy 356.784039 -386.232124)
			(xy 356.807711 -386.282621) (xy 356.823779 -386.336028) (xy 356.831899 -386.391204) (xy 356.832408 -386.41909)
			(xy 356.831899 -386.446976) (xy 356.828527 -386.46989) (xy 361.827062 -386.46989) (xy 361.831133 -386.414268)
			(xy 361.843259 -386.359831) (xy 361.863182 -386.30774) (xy 361.890478 -386.259105) (xy 361.924564 -386.214962)
			(xy 361.964713 -386.176253) (xy 362.010071 -386.143802) (xy 362.059671 -386.118301) (xy 362.112455 -386.100294)
			(xy 362.167298 -386.090164) (xy 362.223032 -386.088127) (xy 362.278469 -386.094227) (xy 362.332426 -386.108333)
			(xy 362.383755 -386.130145) (xy 362.431361 -386.159199) (xy 362.474229 -386.194874) (xy 362.511446 -386.236411)
			(xy 362.542219 -386.282924) (xy 362.565891 -386.333421) (xy 362.577681 -386.372608) (xy 364.445802 -386.372608)
			(xy 364.449873 -386.316986) (xy 364.461999 -386.262549) (xy 364.481922 -386.210458) (xy 364.509218 -386.161823)
			(xy 364.543304 -386.11768) (xy 364.583453 -386.078971) (xy 364.628811 -386.04652) (xy 364.678411 -386.021019)
			(xy 364.731195 -386.003012) (xy 364.786038 -385.992882) (xy 364.841772 -385.990845) (xy 364.897209 -385.996945)
			(xy 364.951166 -386.011051) (xy 365.002495 -386.032863) (xy 365.050101 -386.061917) (xy 365.092969 -386.097592)
			(xy 365.130186 -386.139129) (xy 365.160959 -386.185642) (xy 365.184631 -386.236139) (xy 365.200699 -386.289546)
			(xy 365.208819 -386.344722) (xy 365.209328 -386.372608) (xy 365.208819 -386.400494) (xy 365.200699 -386.45567)
			(xy 365.184631 -386.509077) (xy 365.160959 -386.559574) (xy 365.130186 -386.606087) (xy 365.092969 -386.647624)
			(xy 365.050101 -386.683299) (xy 365.002495 -386.712353) (xy 364.951166 -386.734165) (xy 364.897209 -386.748271)
			(xy 364.841772 -386.754371) (xy 364.786038 -386.752334) (xy 364.731195 -386.742204) (xy 364.678411 -386.724197)
			(xy 364.628811 -386.698696) (xy 364.583453 -386.666245) (xy 364.543304 -386.627536) (xy 364.509218 -386.583393)
			(xy 364.481922 -386.534758) (xy 364.461999 -386.482667) (xy 364.449873 -386.42823) (xy 364.445802 -386.372608)
			(xy 362.577681 -386.372608) (xy 362.581959 -386.386828) (xy 362.590079 -386.442004) (xy 362.590588 -386.46989)
			(xy 362.590079 -386.497776) (xy 362.581959 -386.552952) (xy 362.565891 -386.606359) (xy 362.542219 -386.656856)
			(xy 362.511446 -386.703369) (xy 362.474229 -386.744906) (xy 362.431361 -386.780581) (xy 362.383755 -386.809635)
			(xy 362.332426 -386.831447) (xy 362.278469 -386.845553) (xy 362.223032 -386.851653) (xy 362.167298 -386.849616)
			(xy 362.112455 -386.839486) (xy 362.059671 -386.821479) (xy 362.010071 -386.795978) (xy 361.964713 -386.763527)
			(xy 361.924564 -386.724818) (xy 361.890478 -386.680675) (xy 361.863182 -386.63204) (xy 361.843259 -386.579949)
			(xy 361.831133 -386.525512) (xy 361.827062 -386.46989) (xy 356.828527 -386.46989) (xy 356.823779 -386.502152)
			(xy 356.807711 -386.555559) (xy 356.784039 -386.606056) (xy 356.753266 -386.652569) (xy 356.716049 -386.694106)
			(xy 356.673181 -386.729781) (xy 356.625575 -386.758835) (xy 356.574246 -386.780647) (xy 356.520289 -386.794753)
			(xy 356.464852 -386.800853) (xy 356.409118 -386.798816) (xy 356.354275 -386.788686) (xy 356.301491 -386.770679)
			(xy 356.251891 -386.745178) (xy 356.206533 -386.712727) (xy 356.166384 -386.674018) (xy 356.132298 -386.629875)
			(xy 356.105002 -386.58124) (xy 356.085079 -386.529149) (xy 356.072953 -386.474712) (xy 356.068882 -386.41909)
			(xy 355.0158 -386.41909) (xy 355.0158 -388.330948) (xy 357.566974 -388.330948) (xy 357.571045 -388.275326)
			(xy 357.583171 -388.220889) (xy 357.603094 -388.168798) (xy 357.63039 -388.120163) (xy 357.664476 -388.07602)
			(xy 357.704625 -388.037311) (xy 357.749983 -388.00486) (xy 357.799583 -387.979359) (xy 357.852367 -387.961352)
			(xy 357.90721 -387.951222) (xy 357.962944 -387.949185) (xy 358.018381 -387.955285) (xy 358.072338 -387.969391)
			(xy 358.123667 -387.991203) (xy 358.171273 -388.020257) (xy 358.214141 -388.055932) (xy 358.251358 -388.097469)
			(xy 358.282131 -388.143982) (xy 358.305803 -388.194479) (xy 358.321871 -388.247886) (xy 358.329991 -388.303062)
			(xy 358.3305 -388.330948) (xy 358.329991 -388.358834) (xy 358.321871 -388.41401) (xy 358.305803 -388.467417)
			(xy 358.282131 -388.517914) (xy 358.251358 -388.564427) (xy 358.214141 -388.605964) (xy 358.171273 -388.641639)
			(xy 358.123667 -388.670693) (xy 358.072338 -388.692505) (xy 358.018381 -388.706611) (xy 357.962944 -388.712711)
			(xy 357.90721 -388.710674) (xy 357.852367 -388.700544) (xy 357.799583 -388.682537) (xy 357.749983 -388.657036)
			(xy 357.704625 -388.624585) (xy 357.664476 -388.585876) (xy 357.63039 -388.541733) (xy 357.603094 -388.493098)
			(xy 357.583171 -388.441007) (xy 357.571045 -388.38657) (xy 357.566974 -388.330948) (xy 355.0158 -388.330948)
			(xy 355.0158 -389.19277) (xy 356.129842 -389.19277) (xy 356.133913 -389.137148) (xy 356.146039 -389.082711)
			(xy 356.165962 -389.03062) (xy 356.193258 -388.981985) (xy 356.227344 -388.937842) (xy 356.267493 -388.899133)
			(xy 356.312851 -388.866682) (xy 356.362451 -388.841181) (xy 356.415235 -388.823174) (xy 356.470078 -388.813044)
			(xy 356.525812 -388.811007) (xy 356.581249 -388.817107) (xy 356.635206 -388.831213) (xy 356.686535 -388.853025)
			(xy 356.734141 -388.882079) (xy 356.777009 -388.917754) (xy 356.814226 -388.959291) (xy 356.844999 -389.005804)
			(xy 356.868671 -389.056301) (xy 356.884739 -389.109708) (xy 356.892859 -389.164884) (xy 356.893368 -389.19277)
			(xy 356.892859 -389.220656) (xy 356.884739 -389.275832) (xy 356.868671 -389.329239) (xy 356.844999 -389.379736)
			(xy 356.814226 -389.426249) (xy 356.777009 -389.467786) (xy 356.734141 -389.503461) (xy 356.686535 -389.532515)
			(xy 356.635206 -389.554327) (xy 356.581249 -389.568433) (xy 356.525812 -389.574533) (xy 356.470078 -389.572496)
			(xy 356.415235 -389.562366) (xy 356.362451 -389.544359) (xy 356.312851 -389.518858) (xy 356.267493 -389.486407)
			(xy 356.227344 -389.447698) (xy 356.193258 -389.403555) (xy 356.165962 -389.35492) (xy 356.146039 -389.302829)
			(xy 356.133913 -389.248392) (xy 356.129842 -389.19277) (xy 355.0158 -389.19277) (xy 355.0158 -390.43737)
			(xy 356.129842 -390.43737) (xy 356.133913 -390.381748) (xy 356.146039 -390.327311) (xy 356.165962 -390.27522)
			(xy 356.193258 -390.226585) (xy 356.227344 -390.182442) (xy 356.267493 -390.143733) (xy 356.312851 -390.111282)
			(xy 356.362451 -390.085781) (xy 356.415235 -390.067774) (xy 356.470078 -390.057644) (xy 356.525812 -390.055607)
			(xy 356.581249 -390.061707) (xy 356.635206 -390.075813) (xy 356.686535 -390.097625) (xy 356.734141 -390.126679)
			(xy 356.777009 -390.162354) (xy 356.814226 -390.203891) (xy 356.844999 -390.250404) (xy 356.868671 -390.300901)
			(xy 356.884739 -390.354308) (xy 356.892859 -390.409484) (xy 356.893368 -390.43737) (xy 356.892859 -390.465256)
			(xy 356.889487 -390.48817) (xy 362.106462 -390.48817) (xy 362.110533 -390.432548) (xy 362.122659 -390.378111)
			(xy 362.142582 -390.32602) (xy 362.169878 -390.277385) (xy 362.203964 -390.233242) (xy 362.244113 -390.194533)
			(xy 362.289471 -390.162082) (xy 362.339071 -390.136581) (xy 362.391855 -390.118574) (xy 362.446698 -390.108444)
			(xy 362.502432 -390.106407) (xy 362.557869 -390.112507) (xy 362.611826 -390.126613) (xy 362.663155 -390.148425)
			(xy 362.710761 -390.177479) (xy 362.753629 -390.213154) (xy 362.790846 -390.254691) (xy 362.821619 -390.301204)
			(xy 362.845291 -390.351701) (xy 362.857081 -390.390888) (xy 364.506762 -390.390888) (xy 364.510833 -390.335266)
			(xy 364.522959 -390.280829) (xy 364.542882 -390.228738) (xy 364.570178 -390.180103) (xy 364.604264 -390.13596)
			(xy 364.644413 -390.097251) (xy 364.689771 -390.0648) (xy 364.739371 -390.039299) (xy 364.792155 -390.021292)
			(xy 364.846998 -390.011162) (xy 364.902732 -390.009125) (xy 364.958169 -390.015225) (xy 365.012126 -390.029331)
			(xy 365.063455 -390.051143) (xy 365.111061 -390.080197) (xy 365.153929 -390.115872) (xy 365.191146 -390.157409)
			(xy 365.221919 -390.203922) (xy 365.245591 -390.254419) (xy 365.261659 -390.307826) (xy 365.269779 -390.363002)
			(xy 365.270288 -390.390888) (xy 365.269779 -390.418774) (xy 365.261659 -390.47395) (xy 365.245591 -390.527357)
			(xy 365.221919 -390.577854) (xy 365.191146 -390.624367) (xy 365.153929 -390.665904) (xy 365.111061 -390.701579)
			(xy 365.063455 -390.730633) (xy 365.012126 -390.752445) (xy 364.958169 -390.766551) (xy 364.902732 -390.772651)
			(xy 364.846998 -390.770614) (xy 364.792155 -390.760484) (xy 364.739371 -390.742477) (xy 364.689771 -390.716976)
			(xy 364.644413 -390.684525) (xy 364.604264 -390.645816) (xy 364.570178 -390.601673) (xy 364.542882 -390.553038)
			(xy 364.522959 -390.500947) (xy 364.510833 -390.44651) (xy 364.506762 -390.390888) (xy 362.857081 -390.390888)
			(xy 362.861359 -390.405108) (xy 362.869479 -390.460284) (xy 362.869988 -390.48817) (xy 362.869479 -390.516056)
			(xy 362.861359 -390.571232) (xy 362.845291 -390.624639) (xy 362.821619 -390.675136) (xy 362.790846 -390.721649)
			(xy 362.753629 -390.763186) (xy 362.710761 -390.798861) (xy 362.663155 -390.827915) (xy 362.611826 -390.849727)
			(xy 362.557869 -390.863833) (xy 362.502432 -390.869933) (xy 362.446698 -390.867896) (xy 362.391855 -390.857766)
			(xy 362.339071 -390.839759) (xy 362.289471 -390.814258) (xy 362.244113 -390.781807) (xy 362.203964 -390.743098)
			(xy 362.169878 -390.698955) (xy 362.142582 -390.65032) (xy 362.122659 -390.598229) (xy 362.110533 -390.543792)
			(xy 362.106462 -390.48817) (xy 356.889487 -390.48817) (xy 356.884739 -390.520432) (xy 356.868671 -390.573839)
			(xy 356.844999 -390.624336) (xy 356.814226 -390.670849) (xy 356.777009 -390.712386) (xy 356.734141 -390.748061)
			(xy 356.686535 -390.777115) (xy 356.635206 -390.798927) (xy 356.581249 -390.813033) (xy 356.525812 -390.819133)
			(xy 356.470078 -390.817096) (xy 356.415235 -390.806966) (xy 356.362451 -390.788959) (xy 356.312851 -390.763458)
			(xy 356.267493 -390.731007) (xy 356.227344 -390.692298) (xy 356.193258 -390.648155) (xy 356.165962 -390.59952)
			(xy 356.146039 -390.547429) (xy 356.133913 -390.492992) (xy 356.129842 -390.43737) (xy 355.0158 -390.43737)
			(xy 355.0158 -392.008868) (xy 355.258622 -392.008868) (xy 355.262693 -391.953246) (xy 355.274819 -391.898809)
			(xy 355.294742 -391.846718) (xy 355.322038 -391.798083) (xy 355.356124 -391.75394) (xy 355.396273 -391.715231)
			(xy 355.441631 -391.68278) (xy 355.491231 -391.657279) (xy 355.544015 -391.639272) (xy 355.598858 -391.629142)
			(xy 355.654592 -391.627105) (xy 355.710029 -391.633205) (xy 355.763986 -391.647311) (xy 355.815315 -391.669123)
			(xy 355.862921 -391.698177) (xy 355.905789 -391.733852) (xy 355.943006 -391.775389) (xy 355.973779 -391.821902)
			(xy 355.997451 -391.872399) (xy 356.013519 -391.925806) (xy 356.021639 -391.980982) (xy 356.022148 -392.008868)
			(xy 356.021639 -392.036754) (xy 356.020771 -392.04265) (xy 356.167942 -392.04265) (xy 356.172013 -391.987028)
			(xy 356.184139 -391.932591) (xy 356.204062 -391.8805) (xy 356.231358 -391.831865) (xy 356.265444 -391.787722)
			(xy 356.305593 -391.749013) (xy 356.350951 -391.716562) (xy 356.400551 -391.691061) (xy 356.453335 -391.673054)
			(xy 356.508178 -391.662924) (xy 356.563912 -391.660887) (xy 356.619349 -391.666987) (xy 356.673306 -391.681093)
			(xy 356.724635 -391.702905) (xy 356.772241 -391.731959) (xy 356.815109 -391.767634) (xy 356.852326 -391.809171)
			(xy 356.883099 -391.855684) (xy 356.906771 -391.906181) (xy 356.922839 -391.959588) (xy 356.930959 -392.014764)
			(xy 356.931468 -392.04265) (xy 356.930959 -392.070536) (xy 356.922839 -392.125712) (xy 356.906771 -392.179119)
			(xy 356.883099 -392.229616) (xy 356.852326 -392.276129) (xy 356.815109 -392.317666) (xy 356.772241 -392.353341)
			(xy 356.724635 -392.382395) (xy 356.673306 -392.404207) (xy 356.619349 -392.418313) (xy 356.563912 -392.424413)
			(xy 356.508178 -392.422376) (xy 356.453335 -392.412246) (xy 356.400551 -392.394239) (xy 356.350951 -392.368738)
			(xy 356.305593 -392.336287) (xy 356.265444 -392.297578) (xy 356.231358 -392.253435) (xy 356.204062 -392.2048)
			(xy 356.184139 -392.152709) (xy 356.172013 -392.098272) (xy 356.167942 -392.04265) (xy 356.020771 -392.04265)
			(xy 356.013519 -392.09193) (xy 355.997451 -392.145337) (xy 355.973779 -392.195834) (xy 355.943006 -392.242347)
			(xy 355.905789 -392.283884) (xy 355.862921 -392.319559) (xy 355.815315 -392.348613) (xy 355.763986 -392.370425)
			(xy 355.710029 -392.384531) (xy 355.654592 -392.390631) (xy 355.598858 -392.388594) (xy 355.544015 -392.378464)
			(xy 355.491231 -392.360457) (xy 355.441631 -392.334956) (xy 355.396273 -392.302505) (xy 355.356124 -392.263796)
			(xy 355.322038 -392.219653) (xy 355.294742 -392.171018) (xy 355.274819 -392.118927) (xy 355.262693 -392.06449)
			(xy 355.258622 -392.008868) (xy 355.0158 -392.008868) (xy 355.0158 -393.28725) (xy 356.167942 -393.28725)
			(xy 356.172013 -393.231628) (xy 356.184139 -393.177191) (xy 356.204062 -393.1251) (xy 356.231358 -393.076465)
			(xy 356.265444 -393.032322) (xy 356.305593 -392.993613) (xy 356.350951 -392.961162) (xy 356.400551 -392.935661)
			(xy 356.453335 -392.917654) (xy 356.508178 -392.907524) (xy 356.563912 -392.905487) (xy 356.619349 -392.911587)
			(xy 356.673306 -392.925693) (xy 356.724635 -392.947505) (xy 356.772241 -392.976559) (xy 356.815109 -393.012234)
			(xy 356.852326 -393.053771) (xy 356.883099 -393.100284) (xy 356.906771 -393.150781) (xy 356.922839 -393.204188)
			(xy 356.930959 -393.259364) (xy 356.931468 -393.28725) (xy 356.930959 -393.315136) (xy 356.927587 -393.33805)
			(xy 362.157262 -393.33805) (xy 362.161333 -393.282428) (xy 362.173459 -393.227991) (xy 362.193382 -393.1759)
			(xy 362.220678 -393.127265) (xy 362.254764 -393.083122) (xy 362.294913 -393.044413) (xy 362.340271 -393.011962)
			(xy 362.389871 -392.986461) (xy 362.442655 -392.968454) (xy 362.497498 -392.958324) (xy 362.553232 -392.956287)
			(xy 362.608669 -392.962387) (xy 362.662626 -392.976493) (xy 362.713955 -392.998305) (xy 362.761561 -393.027359)
			(xy 362.804429 -393.063034) (xy 362.841646 -393.104571) (xy 362.872419 -393.151084) (xy 362.896091 -393.201581)
			(xy 362.907881 -393.240768) (xy 364.544862 -393.240768) (xy 364.548933 -393.185146) (xy 364.561059 -393.130709)
			(xy 364.580982 -393.078618) (xy 364.608278 -393.029983) (xy 364.642364 -392.98584) (xy 364.682513 -392.947131)
			(xy 364.727871 -392.91468) (xy 364.777471 -392.889179) (xy 364.830255 -392.871172) (xy 364.885098 -392.861042)
			(xy 364.940832 -392.859005) (xy 364.996269 -392.865105) (xy 365.050226 -392.879211) (xy 365.101555 -392.901023)
			(xy 365.149161 -392.930077) (xy 365.192029 -392.965752) (xy 365.229246 -393.007289) (xy 365.260019 -393.053802)
			(xy 365.283691 -393.104299) (xy 365.299759 -393.157706) (xy 365.307879 -393.212882) (xy 365.308388 -393.240768)
			(xy 365.307879 -393.268654) (xy 365.299759 -393.32383) (xy 365.283691 -393.377237) (xy 365.260019 -393.427734)
			(xy 365.229246 -393.474247) (xy 365.192029 -393.515784) (xy 365.149161 -393.551459) (xy 365.101555 -393.580513)
			(xy 365.050226 -393.602325) (xy 364.996269 -393.616431) (xy 364.940832 -393.622531) (xy 364.885098 -393.620494)
			(xy 364.830255 -393.610364) (xy 364.777471 -393.592357) (xy 364.727871 -393.566856) (xy 364.682513 -393.534405)
			(xy 364.642364 -393.495696) (xy 364.608278 -393.451553) (xy 364.580982 -393.402918) (xy 364.561059 -393.350827)
			(xy 364.548933 -393.29639) (xy 364.544862 -393.240768) (xy 362.907881 -393.240768) (xy 362.912159 -393.254988)
			(xy 362.920279 -393.310164) (xy 362.920788 -393.33805) (xy 362.920279 -393.365936) (xy 362.912159 -393.421112)
			(xy 362.896091 -393.474519) (xy 362.872419 -393.525016) (xy 362.841646 -393.571529) (xy 362.804429 -393.613066)
			(xy 362.761561 -393.648741) (xy 362.713955 -393.677795) (xy 362.662626 -393.699607) (xy 362.608669 -393.713713)
			(xy 362.553232 -393.719813) (xy 362.497498 -393.717776) (xy 362.442655 -393.707646) (xy 362.389871 -393.689639)
			(xy 362.340271 -393.664138) (xy 362.294913 -393.631687) (xy 362.254764 -393.592978) (xy 362.220678 -393.548835)
			(xy 362.193382 -393.5002) (xy 362.173459 -393.448109) (xy 362.161333 -393.393672) (xy 362.157262 -393.33805)
			(xy 356.927587 -393.33805) (xy 356.922839 -393.370312) (xy 356.906771 -393.423719) (xy 356.883099 -393.474216)
			(xy 356.852326 -393.520729) (xy 356.815109 -393.562266) (xy 356.772241 -393.597941) (xy 356.724635 -393.626995)
			(xy 356.673306 -393.648807) (xy 356.619349 -393.662913) (xy 356.563912 -393.669013) (xy 356.508178 -393.666976)
			(xy 356.453335 -393.656846) (xy 356.400551 -393.638839) (xy 356.350951 -393.613338) (xy 356.305593 -393.580887)
			(xy 356.265444 -393.542178) (xy 356.231358 -393.498035) (xy 356.204062 -393.4494) (xy 356.184139 -393.397309)
			(xy 356.172013 -393.342872) (xy 356.167942 -393.28725) (xy 355.0158 -393.28725) (xy 355.0158 -395.618208)
			(xy 357.107742 -395.618208) (xy 357.111813 -395.562586) (xy 357.123939 -395.508149) (xy 357.143862 -395.456058)
			(xy 357.171158 -395.407423) (xy 357.205244 -395.36328) (xy 357.245393 -395.324571) (xy 357.290751 -395.29212)
			(xy 357.340351 -395.266619) (xy 357.393135 -395.248612) (xy 357.447978 -395.238482) (xy 357.503712 -395.236445)
			(xy 357.559149 -395.242545) (xy 357.613106 -395.256651) (xy 357.664435 -395.278463) (xy 357.712041 -395.307517)
			(xy 357.754909 -395.343192) (xy 357.792126 -395.384729) (xy 357.797034 -395.392148) (xy 361.725462 -395.392148)
			(xy 361.729533 -395.336526) (xy 361.741659 -395.282089) (xy 361.761582 -395.229998) (xy 361.788878 -395.181363)
			(xy 361.822964 -395.13722) (xy 361.863113 -395.098511) (xy 361.908471 -395.06606) (xy 361.958071 -395.040559)
			(xy 362.010855 -395.022552) (xy 362.065698 -395.012422) (xy 362.121432 -395.010385) (xy 362.176869 -395.016485)
			(xy 362.230826 -395.030591) (xy 362.282155 -395.052403) (xy 362.329761 -395.081457) (xy 362.372629 -395.117132)
			(xy 362.409846 -395.158669) (xy 362.440619 -395.205182) (xy 362.464291 -395.255679) (xy 362.46714 -395.265148)
			(xy 367.567462 -395.265148) (xy 367.571533 -395.209526) (xy 367.583659 -395.155089) (xy 367.603582 -395.102998)
			(xy 367.630878 -395.054363) (xy 367.664964 -395.01022) (xy 367.705113 -394.971511) (xy 367.750471 -394.93906)
			(xy 367.800071 -394.913559) (xy 367.852855 -394.895552) (xy 367.907698 -394.885422) (xy 367.963432 -394.883385)
			(xy 368.018869 -394.889485) (xy 368.072826 -394.903591) (xy 368.124155 -394.925403) (xy 368.171761 -394.954457)
			(xy 368.214629 -394.990132) (xy 368.251846 -395.031669) (xy 368.282619 -395.078182) (xy 368.306291 -395.128679)
			(xy 368.322359 -395.182086) (xy 368.330479 -395.237262) (xy 368.330988 -395.265148) (xy 368.330479 -395.293034)
			(xy 368.322359 -395.34821) (xy 368.306291 -395.401617) (xy 368.282619 -395.452114) (xy 368.251846 -395.498627)
			(xy 368.214629 -395.540164) (xy 368.171761 -395.575839) (xy 368.124155 -395.604893) (xy 368.072826 -395.626705)
			(xy 368.018869 -395.640811) (xy 367.963432 -395.646911) (xy 367.907698 -395.644874) (xy 367.852855 -395.634744)
			(xy 367.800071 -395.616737) (xy 367.750471 -395.591236) (xy 367.705113 -395.558785) (xy 367.664964 -395.520076)
			(xy 367.630878 -395.475933) (xy 367.603582 -395.427298) (xy 367.583659 -395.375207) (xy 367.571533 -395.32077)
			(xy 367.567462 -395.265148) (xy 362.46714 -395.265148) (xy 362.480359 -395.309086) (xy 362.488479 -395.364262)
			(xy 362.488988 -395.392148) (xy 362.488479 -395.420034) (xy 362.480359 -395.47521) (xy 362.464291 -395.528617)
			(xy 362.440619 -395.579114) (xy 362.409846 -395.625627) (xy 362.372629 -395.667164) (xy 362.329761 -395.702839)
			(xy 362.282155 -395.731893) (xy 362.230826 -395.753705) (xy 362.176869 -395.767811) (xy 362.121432 -395.773911)
			(xy 362.065698 -395.771874) (xy 362.010855 -395.761744) (xy 361.958071 -395.743737) (xy 361.908471 -395.718236)
			(xy 361.863113 -395.685785) (xy 361.822964 -395.647076) (xy 361.788878 -395.602933) (xy 361.761582 -395.554298)
			(xy 361.741659 -395.502207) (xy 361.729533 -395.44777) (xy 361.725462 -395.392148) (xy 357.797034 -395.392148)
			(xy 357.822899 -395.431242) (xy 357.846571 -395.481739) (xy 357.862639 -395.535146) (xy 357.870759 -395.590322)
			(xy 357.871268 -395.618208) (xy 357.870759 -395.646094) (xy 357.862639 -395.70127) (xy 357.846571 -395.754677)
			(xy 357.822899 -395.805174) (xy 357.792126 -395.851687) (xy 357.754909 -395.893224) (xy 357.712041 -395.928899)
			(xy 357.664435 -395.957953) (xy 357.613106 -395.979765) (xy 357.559149 -395.993871) (xy 357.503712 -395.999971)
			(xy 357.447978 -395.997934) (xy 357.393135 -395.987804) (xy 357.340351 -395.969797) (xy 357.290751 -395.944296)
			(xy 357.245393 -395.911845) (xy 357.205244 -395.873136) (xy 357.171158 -395.828993) (xy 357.143862 -395.780358)
			(xy 357.123939 -395.728267) (xy 357.111813 -395.67383) (xy 357.107742 -395.618208) (xy 355.0158 -395.618208)
			(xy 355.0158 -397.519398) (xy 355.399592 -397.519398) (xy 355.403663 -397.463776) (xy 355.415789 -397.409339)
			(xy 355.435712 -397.357248) (xy 355.463008 -397.308613) (xy 355.497094 -397.26447) (xy 355.537243 -397.225761)
			(xy 355.582601 -397.19331) (xy 355.632201 -397.167809) (xy 355.684985 -397.149802) (xy 355.739828 -397.139672)
			(xy 355.795562 -397.137635) (xy 355.850999 -397.143735) (xy 355.904956 -397.157841) (xy 355.956285 -397.179653)
			(xy 356.003891 -397.208707) (xy 356.046759 -397.244382) (xy 356.083976 -397.285919) (xy 356.114749 -397.332432)
			(xy 356.138421 -397.382929) (xy 356.154489 -397.436336) (xy 356.160171 -397.474948) (xy 359.485182 -397.474948)
			(xy 359.489253 -397.419326) (xy 359.501379 -397.364889) (xy 359.521302 -397.312798) (xy 359.548598 -397.264163)
			(xy 359.582684 -397.22002) (xy 359.622833 -397.181311) (xy 359.668191 -397.14886) (xy 359.717791 -397.123359)
			(xy 359.770575 -397.105352) (xy 359.825418 -397.095222) (xy 359.881152 -397.093185) (xy 359.936589 -397.099285)
			(xy 359.990546 -397.113391) (xy 360.041875 -397.135203) (xy 360.089481 -397.164257) (xy 360.132349 -397.199932)
			(xy 360.169566 -397.241469) (xy 360.200339 -397.287982) (xy 360.224011 -397.338479) (xy 360.240079 -397.391886)
			(xy 360.248199 -397.447062) (xy 360.248708 -397.474948) (xy 360.248199 -397.502834) (xy 360.240079 -397.55801)
			(xy 360.224011 -397.611417) (xy 360.200339 -397.661914) (xy 360.169566 -397.708427) (xy 360.132349 -397.749964)
			(xy 360.089481 -397.785639) (xy 360.041875 -397.814693) (xy 359.990546 -397.836505) (xy 359.936589 -397.850611)
			(xy 359.881152 -397.856711) (xy 359.825418 -397.854674) (xy 359.770575 -397.844544) (xy 359.717791 -397.826537)
			(xy 359.668191 -397.801036) (xy 359.622833 -397.768585) (xy 359.582684 -397.729876) (xy 359.548598 -397.685733)
			(xy 359.521302 -397.637098) (xy 359.501379 -397.585007) (xy 359.489253 -397.53057) (xy 359.485182 -397.474948)
			(xy 356.160171 -397.474948) (xy 356.162609 -397.491512) (xy 356.163118 -397.519398) (xy 356.162609 -397.547284)
			(xy 356.154489 -397.60246) (xy 356.138421 -397.655867) (xy 356.114749 -397.706364) (xy 356.083976 -397.752877)
			(xy 356.046759 -397.794414) (xy 356.003891 -397.830089) (xy 355.956285 -397.859143) (xy 355.904956 -397.880955)
			(xy 355.850999 -397.895061) (xy 355.795562 -397.901161) (xy 355.739828 -397.899124) (xy 355.684985 -397.888994)
			(xy 355.632201 -397.870987) (xy 355.582601 -397.845486) (xy 355.537243 -397.813035) (xy 355.497094 -397.774326)
			(xy 355.463008 -397.730183) (xy 355.435712 -397.681548) (xy 355.415789 -397.629457) (xy 355.403663 -397.57502)
			(xy 355.399592 -397.519398) (xy 355.0158 -397.519398) (xy 355.0158 -397.95704) (xy 355.231446 -398.172686)
			(xy 355.248773 -398.190693) (xy 355.27816 -398.231108) (xy 355.300862 -398.275622) (xy 355.316322 -398.32314)
			(xy 355.324158 -398.372491) (xy 355.324664 -398.397476) (xy 355.324664 -398.456912) (xy 355.325209 -398.472075)
			(xy 355.33409 -398.50107) (xy 355.351095 -398.526178) (xy 355.374724 -398.545185) (xy 355.402893 -398.556414)
			(xy 355.433117 -398.558875) (xy 355.462732 -398.552351) (xy 355.489124 -398.537417) (xy 355.499924 -398.526762)
			(xy 355.517991 -398.508336) (xy 355.558229 -398.476029) (xy 355.602459 -398.449446) (xy 355.64987 -398.429072)
			(xy 355.699596 -398.41528) (xy 355.750728 -398.408323) (xy 355.77653 -398.40789) (xy 355.80378 -398.408378)
			(xy 355.857724 -398.416138) (xy 355.910016 -398.431495) (xy 355.959589 -398.454138) (xy 356.005436 -398.483605)
			(xy 356.046623 -398.519297) (xy 356.082311 -398.560486) (xy 356.111775 -398.606335) (xy 356.134414 -398.655911)
			(xy 356.149768 -398.708203) (xy 356.151399 -398.719548) (xy 363.782862 -398.719548) (xy 363.786933 -398.663926)
			(xy 363.799059 -398.609489) (xy 363.818982 -398.557398) (xy 363.846278 -398.508763) (xy 363.880364 -398.46462)
			(xy 363.920513 -398.425911) (xy 363.965871 -398.39346) (xy 364.015471 -398.367959) (xy 364.068255 -398.349952)
			(xy 364.123098 -398.339822) (xy 364.178832 -398.337785) (xy 364.234269 -398.343885) (xy 364.288226 -398.357991)
			(xy 364.339555 -398.379803) (xy 364.387161 -398.408857) (xy 364.430029 -398.444532) (xy 364.467246 -398.486069)
			(xy 364.498019 -398.532582) (xy 364.521691 -398.583079) (xy 364.537759 -398.636486) (xy 364.545879 -398.691662)
			(xy 364.546388 -398.719548) (xy 364.545879 -398.747434) (xy 364.537759 -398.80261) (xy 364.521691 -398.856017)
			(xy 364.498019 -398.906514) (xy 364.467246 -398.953027) (xy 364.430029 -398.994564) (xy 364.387161 -399.030239)
			(xy 364.339555 -399.059293) (xy 364.288226 -399.081105) (xy 364.234269 -399.095211) (xy 364.178832 -399.101311)
			(xy 364.123098 -399.099274) (xy 364.068255 -399.089144) (xy 364.015471 -399.071137) (xy 363.965871 -399.045636)
			(xy 363.920513 -399.013185) (xy 363.880364 -398.974476) (xy 363.846278 -398.930333) (xy 363.818982 -398.881698)
			(xy 363.799059 -398.829607) (xy 363.786933 -398.77517) (xy 363.782862 -398.719548) (xy 356.151399 -398.719548)
			(xy 356.157524 -398.762148) (xy 356.158038 -398.789398) (xy 356.157525 -398.817582) (xy 356.149215 -398.873335)
			(xy 356.13279 -398.927257) (xy 356.108608 -398.978175) (xy 356.077197 -399.02498) (xy 356.039239 -399.066652)
			(xy 355.995561 -399.102285) (xy 355.947115 -399.131101) (xy 355.894956 -399.152474) (xy 355.867716 -399.15973)
			(xy 355.854719 -399.163323) (xy 355.831115 -399.176338) (xy 355.811748 -399.195087) (xy 355.797973 -399.218256)
			(xy 355.790753 -399.244226) (xy 355.790594 -399.271181) (xy 355.797507 -399.297235) (xy 355.811007 -399.320565)
			(xy 355.820218 -399.330418) (xy 356.520131 -400.030188) (xy 359.297222 -400.030188) (xy 359.301293 -399.974566)
			(xy 359.313419 -399.920129) (xy 359.333342 -399.868038) (xy 359.360638 -399.819403) (xy 359.394724 -399.77526)
			(xy 359.434873 -399.736551) (xy 359.480231 -399.7041) (xy 359.529831 -399.678599) (xy 359.582615 -399.660592)
			(xy 359.637458 -399.650462) (xy 359.693192 -399.648425) (xy 359.748629 -399.654525) (xy 359.802586 -399.668631)
			(xy 359.853915 -399.690443) (xy 359.901521 -399.719497) (xy 359.944389 -399.755172) (xy 359.981606 -399.796709)
			(xy 360.012379 -399.843222) (xy 360.036051 -399.893719) (xy 360.052119 -399.947126) (xy 360.060239 -400.002302)
			(xy 360.060748 -400.030188) (xy 360.060239 -400.058074) (xy 360.052119 -400.11325) (xy 360.043485 -400.141948)
			(xy 360.842812 -400.141948) (xy 360.846883 -400.086326) (xy 360.859009 -400.031889) (xy 360.878932 -399.979798)
			(xy 360.906228 -399.931163) (xy 360.940314 -399.88702) (xy 360.980463 -399.848311) (xy 361.025821 -399.81586)
			(xy 361.075421 -399.790359) (xy 361.128205 -399.772352) (xy 361.183048 -399.762222) (xy 361.238782 -399.760185)
			(xy 361.294219 -399.766285) (xy 361.348176 -399.780391) (xy 361.399505 -399.802203) (xy 361.447111 -399.831257)
			(xy 361.489979 -399.866932) (xy 361.527196 -399.908469) (xy 361.557969 -399.954982) (xy 361.581641 -400.005479)
			(xy 361.597709 -400.058886) (xy 361.605829 -400.114062) (xy 361.606338 -400.141948) (xy 361.605829 -400.169834)
			(xy 361.597709 -400.22501) (xy 361.581641 -400.278417) (xy 361.568219 -400.307048) (xy 364.651542 -400.307048)
			(xy 364.655613 -400.251426) (xy 364.667739 -400.196989) (xy 364.687662 -400.144898) (xy 364.714958 -400.096263)
			(xy 364.749044 -400.05212) (xy 364.789193 -400.013411) (xy 364.834551 -399.98096) (xy 364.884151 -399.955459)
			(xy 364.936935 -399.937452) (xy 364.991778 -399.927322) (xy 365.047512 -399.925285) (xy 365.102949 -399.931385)
			(xy 365.156906 -399.945491) (xy 365.208235 -399.967303) (xy 365.255841 -399.996357) (xy 365.298709 -400.032032)
			(xy 365.335926 -400.073569) (xy 365.366699 -400.120082) (xy 365.390371 -400.170579) (xy 365.406439 -400.223986)
			(xy 365.414559 -400.279162) (xy 365.415068 -400.307048) (xy 365.414559 -400.334934) (xy 365.406439 -400.39011)
			(xy 365.390371 -400.443517) (xy 365.366699 -400.494014) (xy 365.335926 -400.540527) (xy 365.298709 -400.582064)
			(xy 365.255841 -400.617739) (xy 365.208235 -400.646793) (xy 365.156906 -400.668605) (xy 365.102949 -400.682711)
			(xy 365.047512 -400.688811) (xy 364.991778 -400.686774) (xy 364.936935 -400.676644) (xy 364.884151 -400.658637)
			(xy 364.834551 -400.633136) (xy 364.789193 -400.600685) (xy 364.749044 -400.561976) (xy 364.714958 -400.517833)
			(xy 364.687662 -400.469198) (xy 364.667739 -400.417107) (xy 364.655613 -400.36267) (xy 364.651542 -400.307048)
			(xy 361.568219 -400.307048) (xy 361.557969 -400.328914) (xy 361.527196 -400.375427) (xy 361.489979 -400.416964)
			(xy 361.447111 -400.452639) (xy 361.399505 -400.481693) (xy 361.348176 -400.503505) (xy 361.294219 -400.517611)
			(xy 361.238782 -400.523711) (xy 361.183048 -400.521674) (xy 361.128205 -400.511544) (xy 361.075421 -400.493537)
			(xy 361.025821 -400.468036) (xy 360.980463 -400.435585) (xy 360.940314 -400.396876) (xy 360.906228 -400.352733)
			(xy 360.878932 -400.304098) (xy 360.859009 -400.252007) (xy 360.846883 -400.19757) (xy 360.842812 -400.141948)
			(xy 360.043485 -400.141948) (xy 360.036051 -400.166657) (xy 360.012379 -400.217154) (xy 359.981606 -400.263667)
			(xy 359.944389 -400.305204) (xy 359.901521 -400.340879) (xy 359.853915 -400.369933) (xy 359.802586 -400.391745)
			(xy 359.748629 -400.405851) (xy 359.693192 -400.411951) (xy 359.637458 -400.409914) (xy 359.582615 -400.399784)
			(xy 359.529831 -400.381777) (xy 359.480231 -400.356276) (xy 359.434873 -400.323825) (xy 359.394724 -400.285116)
			(xy 359.360638 -400.240973) (xy 359.333342 -400.192338) (xy 359.313419 -400.140247) (xy 359.301293 -400.08581)
			(xy 359.297222 -400.030188) (xy 356.520131 -400.030188) (xy 357.060246 -400.570192) (xy 360.39552 -400.570192)
			(xy 360.42051 -400.570653) (xy 360.469874 -400.57847) (xy 360.517403 -400.593925) (xy 360.561924 -400.616636)
			(xy 360.602338 -400.646041) (xy 360.62031 -400.66341) (xy 360.7943 -400.8374) (xy 361.4674 -400.8374)
			(xy 361.9246 -401.2946) (xy 361.9246 -401.670012) (xy 362.432344 -401.670012) (xy 362.436415 -401.61439)
			(xy 362.448541 -401.559953) (xy 362.468464 -401.507862) (xy 362.49576 -401.459227) (xy 362.529846 -401.415084)
			(xy 362.569995 -401.376375) (xy 362.615353 -401.343924) (xy 362.664953 -401.318423) (xy 362.717737 -401.300416)
			(xy 362.77258 -401.290286) (xy 362.828314 -401.288249) (xy 362.883751 -401.294349) (xy 362.937708 -401.308455)
			(xy 362.989037 -401.330267) (xy 363.036643 -401.359321) (xy 363.079511 -401.394996) (xy 363.116728 -401.436533)
			(xy 363.147501 -401.483046) (xy 363.171173 -401.533543) (xy 363.187241 -401.58695) (xy 363.195361 -401.642126)
			(xy 363.19587 -401.670012) (xy 363.195361 -401.697898) (xy 363.187241 -401.753074) (xy 363.171173 -401.806481)
			(xy 363.147501 -401.856978) (xy 363.116728 -401.903491) (xy 363.079511 -401.945028) (xy 363.036643 -401.980703)
			(xy 362.989037 -402.009757) (xy 362.937708 -402.031569) (xy 362.883751 -402.045675) (xy 362.828314 -402.051775)
			(xy 362.77258 -402.049738) (xy 362.717737 -402.039608) (xy 362.664953 -402.021601) (xy 362.615353 -401.9961)
			(xy 362.569995 -401.963649) (xy 362.529846 -401.92494) (xy 362.49576 -401.880797) (xy 362.468464 -401.832162)
			(xy 362.448541 -401.780071) (xy 362.436415 -401.725634) (xy 362.432344 -401.670012) (xy 361.9246 -401.670012)
			(xy 361.9246 -402.082) (xy 361.188 -402.8186) (xy 360.553 -402.8186) (xy 360.461052 -402.910548)
			(xy 369.472462 -402.910548) (xy 369.476533 -402.854926) (xy 369.488659 -402.800489) (xy 369.508582 -402.748398)
			(xy 369.535878 -402.699763) (xy 369.569964 -402.65562) (xy 369.610113 -402.616911) (xy 369.655471 -402.58446)
			(xy 369.705071 -402.558959) (xy 369.757855 -402.540952) (xy 369.812698 -402.530822) (xy 369.868432 -402.528785)
			(xy 369.923869 -402.534885) (xy 369.977826 -402.548991) (xy 370.029155 -402.570803) (xy 370.076761 -402.599857)
			(xy 370.119629 -402.635532) (xy 370.156846 -402.677069) (xy 370.187619 -402.723582) (xy 370.211291 -402.774079)
			(xy 370.227359 -402.827486) (xy 370.235479 -402.882662) (xy 370.235988 -402.910548) (xy 370.235479 -402.938434)
			(xy 370.227359 -402.99361) (xy 370.211291 -403.047017) (xy 370.187619 -403.097514) (xy 370.156846 -403.144027)
			(xy 370.119629 -403.185564) (xy 370.076761 -403.221239) (xy 370.029155 -403.250293) (xy 369.977826 -403.272105)
			(xy 369.923869 -403.286211) (xy 369.868432 -403.292311) (xy 369.812698 -403.290274) (xy 369.757855 -403.280144)
			(xy 369.705071 -403.262137) (xy 369.655471 -403.236636) (xy 369.610113 -403.204185) (xy 369.569964 -403.165476)
			(xy 369.535878 -403.121333) (xy 369.508582 -403.072698) (xy 369.488659 -403.020607) (xy 369.476533 -402.96617)
			(xy 369.472462 -402.910548) (xy 360.461052 -402.910548) (xy 359.9942 -403.3774) (xy 359.9942 -405.204168)
			(xy 360.021632 -405.2316) (xy 367.054892 -405.2316) (xy 367.055378 -405.204349) (xy 367.063134 -405.150401)
			(xy 367.078489 -405.098106) (xy 367.101131 -405.048529) (xy 367.130597 -405.002679) (xy 367.166288 -404.961488)
			(xy 367.207479 -404.925797) (xy 367.253329 -404.896331) (xy 367.302906 -404.873689) (xy 367.355201 -404.858334)
			(xy 367.409149 -404.850578) (xy 367.463651 -404.850578) (xy 367.517599 -404.858334) (xy 367.569894 -404.873689)
			(xy 367.619471 -404.896331) (xy 367.665321 -404.925797) (xy 367.706512 -404.961488) (xy 367.742203 -405.002679)
			(xy 367.771669 -405.048529) (xy 367.794311 -405.098106) (xy 367.809666 -405.150401) (xy 367.817422 -405.204349)
			(xy 367.817908 -405.2316) (xy 367.817427 -405.259463) (xy 367.811742 -405.298148) (xy 368.832382 -405.298148)
			(xy 368.836453 -405.242526) (xy 368.848579 -405.188089) (xy 368.868502 -405.135998) (xy 368.895798 -405.087363)
			(xy 368.929884 -405.04322) (xy 368.970033 -405.004511) (xy 369.015391 -404.97206) (xy 369.064991 -404.946559)
			(xy 369.117775 -404.928552) (xy 369.172618 -404.918422) (xy 369.228352 -404.916385) (xy 369.283789 -404.922485)
			(xy 369.337746 -404.936591) (xy 369.389075 -404.958403) (xy 369.436681 -404.987457) (xy 369.479549 -405.023132)
			(xy 369.516766 -405.064669) (xy 369.547539 -405.111182) (xy 369.571211 -405.161679) (xy 369.587279 -405.215086)
			(xy 369.595399 -405.270262) (xy 369.595908 -405.298148) (xy 369.595399 -405.326034) (xy 369.587279 -405.38121)
			(xy 369.571211 -405.434617) (xy 369.547539 -405.485114) (xy 369.516766 -405.531627) (xy 369.479549 -405.573164)
			(xy 369.436681 -405.608839) (xy 369.389075 -405.637893) (xy 369.337746 -405.659705) (xy 369.283789 -405.673811)
			(xy 369.228352 -405.679911) (xy 369.172618 -405.677874) (xy 369.117775 -405.667744) (xy 369.064991 -405.649737)
			(xy 369.015391 -405.624236) (xy 368.970033 -405.591785) (xy 368.929884 -405.553076) (xy 368.895798 -405.508933)
			(xy 368.868502 -405.460298) (xy 368.848579 -405.408207) (xy 368.836453 -405.35377) (xy 368.832382 -405.298148)
			(xy 367.811742 -405.298148) (xy 367.809325 -405.314596) (xy 367.793293 -405.367965) (xy 367.769671 -405.418436)
			(xy 367.738962 -405.464937) (xy 367.701818 -405.506478) (xy 367.680748 -405.524716) (xy 367.669232 -405.535019)
			(xy 367.65246 -405.560952) (xy 367.644208 -405.590714) (xy 367.645232 -405.621581) (xy 367.655439 -405.65073)
			(xy 367.673893 -405.675494) (xy 367.686082 -405.68499) (xy 367.706621 -405.700426) (xy 367.743754 -405.735937)
			(xy 367.775785 -405.776111) (xy 367.802135 -405.82022) (xy 367.822326 -405.867466) (xy 367.835993 -405.916995)
			(xy 367.842889 -405.96791) (xy 367.843308 -405.9936) (xy 367.842822 -406.020851) (xy 367.835066 -406.074799)
			(xy 367.819711 -406.127094) (xy 367.797069 -406.176671) (xy 367.767603 -406.222521) (xy 367.731912 -406.263712)
			(xy 367.690721 -406.299403) (xy 367.644871 -406.328869) (xy 367.595294 -406.351511) (xy 367.542999 -406.366866)
			(xy 367.489051 -406.374622) (xy 367.434549 -406.374622) (xy 367.380601 -406.366866) (xy 367.328306 -406.351511)
			(xy 367.278729 -406.328869) (xy 367.232879 -406.299403) (xy 367.191688 -406.263712) (xy 367.155997 -406.222521)
			(xy 367.126531 -406.176671) (xy 367.103889 -406.127094) (xy 367.088534 -406.074799) (xy 367.080778 -406.020851)
			(xy 367.080292 -405.9936) (xy 367.080773 -405.965737) (xy 367.088875 -405.910604) (xy 367.104907 -405.857235)
			(xy 367.128529 -405.806764) (xy 367.159238 -405.760263) (xy 367.196382 -405.718722) (xy 367.217452 -405.700484)
			(xy 367.228968 -405.690181) (xy 367.24574 -405.664248) (xy 367.253992 -405.634486) (xy 367.252968 -405.603619)
			(xy 367.242761 -405.57447) (xy 367.224307 -405.549706) (xy 367.212118 -405.54021) (xy 367.191579 -405.524774)
			(xy 367.154446 -405.489263) (xy 367.122415 -405.449089) (xy 367.096065 -405.40498) (xy 367.075874 -405.357734)
			(xy 367.062207 -405.308205) (xy 367.055311 -405.25729) (xy 367.054892 -405.2316) (xy 360.021632 -405.2316)
			(xy 360.783632 -405.9936) (xy 364.946182 -405.9936) (xy 364.950253 -405.937978) (xy 364.962379 -405.883541)
			(xy 364.982302 -405.83145) (xy 365.009598 -405.782815) (xy 365.043684 -405.738672) (xy 365.083833 -405.699963)
			(xy 365.129191 -405.667512) (xy 365.178791 -405.642011) (xy 365.231575 -405.624004) (xy 365.286418 -405.613874)
			(xy 365.342152 -405.611837) (xy 365.397589 -405.617937) (xy 365.451546 -405.632043) (xy 365.502875 -405.653855)
			(xy 365.550481 -405.682909) (xy 365.593349 -405.718584) (xy 365.630566 -405.760121) (xy 365.661339 -405.806634)
			(xy 365.685011 -405.857131) (xy 365.701079 -405.910538) (xy 365.709199 -405.965714) (xy 365.709708 -405.9936)
			(xy 365.709199 -406.021486) (xy 365.701079 -406.076662) (xy 365.685011 -406.130069) (xy 365.661339 -406.180566)
			(xy 365.630566 -406.227079) (xy 365.593349 -406.268616) (xy 365.550481 -406.304291) (xy 365.502875 -406.333345)
			(xy 365.451546 -406.355157) (xy 365.397589 -406.369263) (xy 365.342152 -406.375363) (xy 365.286418 -406.373326)
			(xy 365.231575 -406.363196) (xy 365.178791 -406.345189) (xy 365.129191 -406.319688) (xy 365.083833 -406.287237)
			(xy 365.043684 -406.248528) (xy 365.009598 -406.204385) (xy 364.982302 -406.15575) (xy 364.962379 -406.103659)
			(xy 364.950253 -406.049222) (xy 364.946182 -405.9936) (xy 360.783632 -405.9936) (xy 361.873292 -407.08326)
			(xy 361.88332 -407.092655) (xy 361.907217 -407.106199) (xy 361.933862 -407.112874) (xy 361.961323 -407.112197)
			(xy 361.987606 -407.104216) (xy 362.010807 -407.08951) (xy 362.029241 -407.069147) (xy 362.035852 -407.057098)
			(xy 362.048088 -407.033749) (xy 362.078027 -406.990361) (xy 362.113655 -406.951509) (xy 362.154294 -406.917934)
			(xy 362.199171 -406.890276) (xy 362.247428 -406.869062) (xy 362.298148 -406.854697) (xy 362.350363 -406.847453)
			(xy 362.37672 -406.84704) (xy 362.403971 -406.847505) (xy 362.457917 -406.855264) (xy 362.51021 -406.870623)
			(xy 362.559784 -406.893267) (xy 362.605631 -406.922736) (xy 362.646818 -406.95843) (xy 362.682505 -406.999623)
			(xy 362.711966 -407.045476) (xy 362.734601 -407.095054) (xy 362.74995 -407.14735) (xy 362.7577 -407.201297)
			(xy 362.758228 -407.228548) (xy 362.757656 -407.258727) (xy 362.748141 -407.318329) (xy 362.729341 -407.375684)
			(xy 362.716064 -407.402792) (xy 362.709763 -407.41625) (xy 362.70443 -407.44547) (xy 362.707731 -407.474988)
			(xy 362.719386 -407.502309) (xy 362.738409 -407.52512) (xy 362.763191 -407.541493) (xy 362.791637 -407.550043)
			(xy 362.806488 -407.55062) (xy 363.79912 -407.55062) (xy 363.825007 -407.551175) (xy 363.876085 -407.559641)
			(xy 363.925123 -407.576251) (xy 363.948218 -407.587958) (xy 363.959394 -407.5938) (xy 364.2106 -407.5938)
			(xy 365.125 -408.5082) (xy 365.125 -408.721814) (xy 365.125553 -408.736933) (xy 365.134407 -408.765846)
			(xy 365.151337 -408.790901) (xy 365.174858 -408.809904) (xy 365.202912 -408.82119) (xy 365.23304 -408.823771)
			(xy 365.247936 -408.821128) (xy 365.267758 -408.817106) (xy 365.307976 -408.812783) (xy 365.3282 -408.812492)
			(xy 365.355451 -408.812978) (xy 365.409399 -408.820734) (xy 365.461694 -408.836089) (xy 365.511271 -408.858731)
			(xy 365.557121 -408.888197) (xy 365.598312 -408.923888) (xy 365.634003 -408.965079) (xy 365.663469 -409.010929)
			(xy 365.686111 -409.060506) (xy 365.698384 -409.102306) (xy 367.101626 -409.102306) (xy 367.105697 -409.046684)
			(xy 367.117823 -408.992247) (xy 367.137746 -408.940156) (xy 367.165042 -408.891521) (xy 367.199128 -408.847378)
			(xy 367.239277 -408.808669) (xy 367.284635 -408.776218) (xy 367.334235 -408.750717) (xy 367.387019 -408.73271)
			(xy 367.441862 -408.72258) (xy 367.497596 -408.720543) (xy 367.553033 -408.726643) (xy 367.60699 -408.740749)
			(xy 367.658319 -408.762561) (xy 367.705925 -408.791615) (xy 367.748793 -408.82729) (xy 367.78601 -408.868827)
			(xy 367.816783 -408.91534) (xy 367.840455 -408.965837) (xy 367.856523 -409.019244) (xy 367.864643 -409.07442)
			(xy 367.865152 -409.102306) (xy 367.864643 -409.130192) (xy 367.856523 -409.185368) (xy 367.840455 -409.238775)
			(xy 367.816783 -409.289272) (xy 367.78601 -409.335785) (xy 367.748793 -409.377322) (xy 367.705925 -409.412997)
			(xy 367.658319 -409.442051) (xy 367.60699 -409.463863) (xy 367.553033 -409.477969) (xy 367.497596 -409.484069)
			(xy 367.441862 -409.482032) (xy 367.387019 -409.471902) (xy 367.334235 -409.453895) (xy 367.284635 -409.428394)
			(xy 367.239277 -409.395943) (xy 367.199128 -409.357234) (xy 367.165042 -409.313091) (xy 367.137746 -409.264456)
			(xy 367.117823 -409.212365) (xy 367.105697 -409.157928) (xy 367.101626 -409.102306) (xy 365.698384 -409.102306)
			(xy 365.701466 -409.112801) (xy 365.709222 -409.166749) (xy 365.709222 -409.221251) (xy 365.701466 -409.275199)
			(xy 365.686111 -409.327494) (xy 365.663469 -409.377071) (xy 365.634003 -409.422921) (xy 365.598312 -409.464112)
			(xy 365.557121 -409.499803) (xy 365.511271 -409.529269) (xy 365.461694 -409.551911) (xy 365.409399 -409.567266)
			(xy 365.355451 -409.575022) (xy 365.3282 -409.575508) (xy 365.307976 -409.575213) (xy 365.26776 -409.570883)
			(xy 365.247936 -409.566872) (xy 365.233039 -409.564235) (xy 365.202913 -409.566816) (xy 365.174861 -409.578101)
			(xy 365.151341 -409.597103) (xy 365.134413 -409.622157) (xy 365.125559 -409.651068) (xy 365.125 -409.666186)
			(xy 365.125 -410.334968) (xy 365.143014 -410.353064) (xy 365.173603 -410.393944) (xy 365.197259 -410.43919)
			(xy 365.213373 -410.487638) (xy 365.22153 -410.538039) (xy 365.222028 -410.563568) (xy 365.222028 -411.5562)
			(xy 365.835182 -411.5562) (xy 365.839253 -411.500578) (xy 365.851379 -411.446141) (xy 365.871302 -411.39405)
			(xy 365.898598 -411.345415) (xy 365.932684 -411.301272) (xy 365.972833 -411.262563) (xy 366.018191 -411.230112)
			(xy 366.067791 -411.204611) (xy 366.120575 -411.186604) (xy 366.175418 -411.176474) (xy 366.231152 -411.174437)
			(xy 366.286589 -411.180537) (xy 366.340546 -411.194643) (xy 366.391875 -411.216455) (xy 366.439481 -411.245509)
			(xy 366.482349 -411.281184) (xy 366.519566 -411.322721) (xy 366.550339 -411.369234) (xy 366.574011 -411.419731)
			(xy 366.590079 -411.473138) (xy 366.598199 -411.528314) (xy 366.598708 -411.5562) (xy 366.598199 -411.584086)
			(xy 366.590079 -411.639262) (xy 366.574011 -411.692669) (xy 366.550339 -411.743166) (xy 366.519566 -411.789679)
			(xy 366.482349 -411.831216) (xy 366.439481 -411.866891) (xy 366.391875 -411.895945) (xy 366.340546 -411.917757)
			(xy 366.286589 -411.931863) (xy 366.231152 -411.937963) (xy 366.175418 -411.935926) (xy 366.120575 -411.925796)
			(xy 366.067791 -411.907789) (xy 366.018191 -411.882288) (xy 365.972833 -411.849837) (xy 365.932684 -411.811128)
			(xy 365.898598 -411.766985) (xy 365.871302 -411.71835) (xy 365.851379 -411.666259) (xy 365.839253 -411.611822)
			(xy 365.835182 -411.5562) (xy 365.222028 -411.5562) (xy 365.222028 -413.50946) (xy 368.319302 -413.50946)
			(xy 368.323373 -413.453838) (xy 368.335499 -413.399401) (xy 368.355422 -413.34731) (xy 368.382718 -413.298675)
			(xy 368.416804 -413.254532) (xy 368.456953 -413.215823) (xy 368.502311 -413.183372) (xy 368.551911 -413.157871)
			(xy 368.604695 -413.139864) (xy 368.659538 -413.129734) (xy 368.715272 -413.127697) (xy 368.770709 -413.133797)
			(xy 368.824666 -413.147903) (xy 368.875995 -413.169715) (xy 368.923601 -413.198769) (xy 368.966469 -413.234444)
			(xy 369.003686 -413.275981) (xy 369.034459 -413.322494) (xy 369.058131 -413.372991) (xy 369.074199 -413.426398)
			(xy 369.082319 -413.481574) (xy 369.082828 -413.50946) (xy 369.082319 -413.537346) (xy 369.074199 -413.592522)
			(xy 369.058131 -413.645929) (xy 369.034459 -413.696426) (xy 369.003686 -413.742939) (xy 368.966469 -413.784476)
			(xy 368.923601 -413.820151) (xy 368.875995 -413.849205) (xy 368.824666 -413.871017) (xy 368.770709 -413.885123)
			(xy 368.715272 -413.891223) (xy 368.659538 -413.889186) (xy 368.604695 -413.879056) (xy 368.551911 -413.861049)
			(xy 368.502311 -413.835548) (xy 368.456953 -413.803097) (xy 368.416804 -413.764388) (xy 368.382718 -413.720245)
			(xy 368.355422 -413.67161) (xy 368.335499 -413.619519) (xy 368.323373 -413.565082) (xy 368.319302 -413.50946)
			(xy 365.222028 -413.50946) (xy 365.222028 -414.7566) (xy 365.835182 -414.7566) (xy 365.839253 -414.700978)
			(xy 365.851379 -414.646541) (xy 365.871302 -414.59445) (xy 365.898598 -414.545815) (xy 365.932684 -414.501672)
			(xy 365.972833 -414.462963) (xy 366.018191 -414.430512) (xy 366.067791 -414.405011) (xy 366.120575 -414.387004)
			(xy 366.175418 -414.376874) (xy 366.231152 -414.374837) (xy 366.286589 -414.380937) (xy 366.340546 -414.395043)
			(xy 366.391875 -414.416855) (xy 366.439481 -414.445909) (xy 366.482349 -414.481584) (xy 366.519566 -414.523121)
			(xy 366.550339 -414.569634) (xy 366.574011 -414.620131) (xy 366.590079 -414.673538) (xy 366.598199 -414.728714)
			(xy 366.598708 -414.7566) (xy 366.598199 -414.784486) (xy 366.590079 -414.839662) (xy 366.574011 -414.893069)
			(xy 366.550339 -414.943566) (xy 366.519566 -414.990079) (xy 366.482349 -415.031616) (xy 366.439481 -415.067291)
			(xy 366.391875 -415.096345) (xy 366.340546 -415.118157) (xy 366.286589 -415.132263) (xy 366.231152 -415.138363)
			(xy 366.175418 -415.136326) (xy 366.120575 -415.126196) (xy 366.067791 -415.108189) (xy 366.018191 -415.082688)
			(xy 365.972833 -415.050237) (xy 365.932684 -415.011528) (xy 365.898598 -414.967385) (xy 365.871302 -414.91875)
			(xy 365.851379 -414.866659) (xy 365.839253 -414.812222) (xy 365.835182 -414.7566) (xy 365.222028 -414.7566)
			(xy 365.222028 -416.809174) (xy 365.2774 -416.8648) (xy 373.2022 -416.8648)
		)
		(stroke
			(width 0)
			(type solid)
		)
		(fill yes)
		(layer "In13.Cu")
		(net "P3V3_AUX")
	)
	(gr_poly
		(pts
			(xy 266.40028 -132.908548) (xy 266.40028 -126.329948) (xy 265.84148 -125.771148) (xy 250.72848 -125.771148)
			(xy 246.820944 -121.863612) (xy 246.81097 -121.854245) (xy 246.7872 -121.840716) (xy 246.760688 -121.833991)
			(xy 246.733343 -121.834555) (xy 246.707131 -121.842368) (xy 246.683939 -121.856866) (xy 246.674386 -121.86666)
			(xy 246.656262 -121.885721) (xy 246.61568 -121.919177) (xy 246.570883 -121.946736) (xy 246.522722 -121.967874)
			(xy 246.472112 -121.982189) (xy 246.420014 -121.98941) (xy 246.393716 -121.98985) (xy 246.37873 -121.989596)
			(xy 246.368185 -121.989698) (xy 246.348566 -121.997369) (xy 246.33367 -122.012264) (xy 246.325998 -122.031883)
			(xy 246.325898 -122.042428) (xy 246.326152 -122.057414) (xy 246.326152 -122.921014) (xy 246.325898 -122.936)
			(xy 246.326005 -122.946541) (xy 246.333682 -122.966149) (xy 246.348576 -122.981034) (xy 246.368188 -122.9887)
			(xy 246.37873 -122.988832) (xy 246.393716 -122.988578) (xy 246.420967 -122.989065) (xy 246.474915 -122.996824)
			(xy 246.52721 -123.012181) (xy 246.576787 -123.034824) (xy 246.622637 -123.064291) (xy 246.663827 -123.099984)
			(xy 246.699518 -123.141175) (xy 246.728984 -123.187027) (xy 246.751625 -123.236605) (xy 246.76698 -123.2889)
			(xy 246.774736 -123.342848) (xy 246.774736 -123.397352) (xy 246.76698 -123.4513) (xy 246.751625 -123.503595)
			(xy 246.728984 -123.553173) (xy 246.699518 -123.599025) (xy 246.663827 -123.640216) (xy 246.622637 -123.675909)
			(xy 246.576787 -123.705376) (xy 246.52721 -123.728019) (xy 246.474915 -123.743376) (xy 246.420968 -123.751135)
			(xy 246.393716 -123.751594) (xy 246.365047 -123.751086) (xy 246.308352 -123.742518) (xy 246.25358 -123.725557)
			(xy 246.201964 -123.700586) (xy 246.15467 -123.668168) (xy 246.112762 -123.629034) (xy 246.077187 -123.584067)
			(xy 246.048746 -123.534279) (xy 246.028081 -123.480794) (xy 246.015657 -123.424818) (xy 246.013224 -123.396248)
			(xy 246.011761 -123.381699) (xy 246.00161 -123.354289) (xy 245.98411 -123.330878) (xy 245.960696 -123.313382)
			(xy 245.933284 -123.303235) (xy 245.918736 -123.30176) (xy 245.890158 -123.299273) (xy 245.834164 -123.286812)
			(xy 245.780663 -123.266116) (xy 245.730861 -123.237651) (xy 245.685876 -123.202056) (xy 245.646722 -123.160133)
			(xy 245.614279 -123.112825) (xy 245.589277 -123.061196) (xy 245.572279 -123.006409) (xy 245.563667 -122.949696)
			(xy 245.563136 -122.921014) (xy 245.563136 -122.057414) (xy 245.563644 -122.028724) (xy 245.572219 -121.97199)
			(xy 245.589192 -121.917179) (xy 245.614181 -121.865527) (xy 245.646622 -121.818199) (xy 245.685784 -121.776262)
			(xy 245.730783 -121.740662) (xy 245.780606 -121.712201) (xy 245.834129 -121.691521) (xy 245.890145 -121.679089)
			(xy 245.918736 -121.676668) (xy 245.933289 -121.675208) (xy 245.960708 -121.665061) (xy 245.98413 -121.647563)
			(xy 246.001638 -121.624149) (xy 246.011798 -121.596735) (xy 246.013224 -121.58218) (xy 246.015744 -121.553351)
			(xy 246.028385 -121.496882) (xy 246.049404 -121.442967) (xy 246.078318 -121.392842) (xy 246.114466 -121.347654)
			(xy 246.135398 -121.327672) (xy 246.145144 -121.318081) (xy 246.159601 -121.294885) (xy 246.167395 -121.268688)
			(xy 246.167968 -121.241361) (xy 246.16128 -121.21486) (xy 246.147808 -121.191078) (xy 246.138446 -121.181114)
			(xy 244.96268 -120.005348) (xy 236.189774 -120.005348) (xy 236.17936 -120.042432) (xy 236.171227 -120.0694)
			(xy 236.148131 -120.120775) (xy 236.117741 -120.1682) (xy 236.099604 -120.189752) (xy 236.09036 -120.201079)
			(xy 236.07817 -120.227641) (xy 236.073986 -120.256565) (xy 236.07815 -120.285492) (xy 236.090323 -120.312062)
			(xy 236.099604 -120.323356) (xy 236.117243 -120.344288) (xy 236.146962 -120.390256) (xy 236.169797 -120.440004)
			(xy 236.18528 -120.492507) (xy 236.19309 -120.546685) (xy 236.193584 -120.574054) (xy 236.193098 -120.601305)
			(xy 236.185342 -120.655253) (xy 236.169987 -120.707548) (xy 236.147345 -120.757125) (xy 236.117879 -120.802975)
			(xy 236.082188 -120.844166) (xy 236.040997 -120.879857) (xy 235.995147 -120.909323) (xy 235.94557 -120.931965)
			(xy 235.893275 -120.94732) (xy 235.839327 -120.955076) (xy 235.784825 -120.955076) (xy 235.730877 -120.94732)
			(xy 235.678582 -120.931965) (xy 235.629005 -120.909323) (xy 235.583155 -120.879857) (xy 235.541964 -120.844166)
			(xy 235.506273 -120.802975) (xy 235.476807 -120.757125) (xy 235.454165 -120.707548) (xy 235.43881 -120.655253)
			(xy 235.431054 -120.601305) (xy 235.430568 -120.574054) (xy 235.431043 -120.546686) (xy 235.438874 -120.492511)
			(xy 235.454368 -120.440013) (xy 235.477208 -120.390269) (xy 235.506924 -120.3443) (xy 235.524548 -120.323356)
			(xy 235.533775 -120.312027) (xy 235.545933 -120.285473) (xy 235.550093 -120.256565) (xy 235.545914 -120.22766)
			(xy 235.533737 -120.201114) (xy 235.524548 -120.189752) (xy 235.506408 -120.168202) (xy 235.476011 -120.12078)
			(xy 235.452922 -120.069402) (xy 235.444792 -120.042432) (xy 235.434378 -120.005348) (xy 233.63428 -120.005348)
			(xy 232.66908 -119.040148) (xy 229.16388 -119.040148) (xy 228.899466 -119.304562) (xy 228.92258 -119.339106)
			(xy 228.937709 -119.362726) (xy 228.961625 -119.413464) (xy 228.977861 -119.467154) (xy 228.986068 -119.522642)
			(xy 228.986588 -119.550688) (xy 228.986073 -119.579254) (xy 228.97754 -119.635746) (xy 228.960679 -119.690334)
			(xy 228.935865 -119.741798) (xy 228.903654 -119.788985) (xy 228.864767 -119.830841) (xy 228.820072 -119.86643)
			(xy 228.79558 -119.881142) (xy 228.79558 -120.112536) (xy 228.812616 -120.133312) (xy 228.841296 -120.178743)
			(xy 228.863317 -120.227749) (xy 228.875205 -120.268852) (xy 230.553246 -120.268852) (xy 230.553246 -120.214348)
			(xy 230.561002 -120.1604) (xy 230.576356 -120.108104) (xy 230.598996 -120.058525) (xy 230.628461 -120.012673)
			(xy 230.664152 -119.97148) (xy 230.705341 -119.935785) (xy 230.75119 -119.906316) (xy 230.800766 -119.88367)
			(xy 230.85306 -119.86831) (xy 230.907008 -119.860549) (xy 230.93426 -119.86006) (xy 230.961757 -119.86056)
			(xy 231.016184 -119.868447) (xy 231.068915 -119.884062) (xy 231.11886 -119.907083) (xy 231.164983 -119.937033)
			(xy 231.185974 -119.954802) (xy 231.197437 -119.964222) (xy 231.224443 -119.976489) (xy 231.253833 -119.980492)
			(xy 231.283136 -119.975896) (xy 231.309889 -119.963086) (xy 231.331842 -119.943139) (xy 231.34715 -119.917733)
			(xy 231.351328 -119.903494) (xy 231.358763 -119.876448) (xy 231.38035 -119.824681) (xy 231.409284 -119.776633)
			(xy 231.444941 -119.733339) (xy 231.486554 -119.695733) (xy 231.533224 -119.664624) (xy 231.583946 -119.640685)
			(xy 231.637626 -119.624431) (xy 231.693108 -119.616211) (xy 231.721152 -119.615712) (xy 231.748409 -119.616132)
			(xy 231.802368 -119.623883) (xy 231.854674 -119.639236) (xy 231.904263 -119.661877) (xy 231.950124 -119.691345)
			(xy 231.991325 -119.727041) (xy 232.027026 -119.768237) (xy 232.0565 -119.814095) (xy 232.079147 -119.863681)
			(xy 232.094506 -119.915985) (xy 232.102265 -119.969944) (xy 232.102265 -120.024456) (xy 232.094506 -120.078415)
			(xy 232.079147 -120.130719) (xy 232.0565 -120.180305) (xy 232.027026 -120.226163) (xy 231.991325 -120.267359)
			(xy 231.950124 -120.303055) (xy 231.904263 -120.332523) (xy 231.854674 -120.355164) (xy 231.802368 -120.370517)
			(xy 231.748409 -120.378268) (xy 231.721152 -120.378728) (xy 231.693653 -120.378282) (xy 231.639224 -120.370383)
			(xy 231.586492 -120.354755) (xy 231.536548 -120.331722) (xy 231.490427 -120.30176) (xy 231.469438 -120.283986)
			(xy 231.45796 -120.274587) (xy 231.430958 -120.262321) (xy 231.401573 -120.258316) (xy 231.372274 -120.26291)
			(xy 231.345524 -120.275716) (xy 231.323572 -120.295657) (xy 231.308263 -120.321058) (xy 231.304084 -120.335294)
			(xy 231.296787 -120.362381) (xy 231.275182 -120.414152) (xy 231.246229 -120.462201) (xy 231.210553 -120.505494)
			(xy 231.168923 -120.543097) (xy 231.122236 -120.574199) (xy 231.071499 -120.598131) (xy 231.017804 -120.614375)
			(xy 230.962309 -120.622583) (xy 230.93426 -120.623076) (xy 230.907008 -120.622651) (xy 230.85306 -120.61489)
			(xy 230.800766 -120.59953) (xy 230.75119 -120.576884) (xy 230.705341 -120.547415) (xy 230.664152 -120.51172)
			(xy 230.628461 -120.470527) (xy 230.598996 -120.424675) (xy 230.576356 -120.375096) (xy 230.561002 -120.3228)
			(xy 230.553246 -120.268852) (xy 228.875205 -120.268852) (xy 228.878244 -120.27936) (xy 228.88578 -120.332555)
			(xy 228.885778 -120.386281) (xy 228.878236 -120.439476) (xy 228.863304 -120.491086) (xy 228.841279 -120.54009)
			(xy 228.812594 -120.585518) (xy 228.79558 -120.606312) (xy 228.79558 -120.965468) (xy 243.793262 -120.965468)
			(xy 243.797333 -120.909846) (xy 243.809459 -120.855409) (xy 243.829382 -120.803318) (xy 243.856678 -120.754683)
			(xy 243.890764 -120.71054) (xy 243.930913 -120.671831) (xy 243.976271 -120.63938) (xy 244.025871 -120.613879)
			(xy 244.078655 -120.595872) (xy 244.133498 -120.585742) (xy 244.189232 -120.583705) (xy 244.244669 -120.589805)
			(xy 244.298626 -120.603911) (xy 244.349955 -120.625723) (xy 244.397561 -120.654777) (xy 244.440429 -120.690452)
			(xy 244.477646 -120.731989) (xy 244.508419 -120.778502) (xy 244.532091 -120.828999) (xy 244.548159 -120.882406)
			(xy 244.556279 -120.937582) (xy 244.556788 -120.965468) (xy 244.556279 -120.993354) (xy 244.548159 -121.04853)
			(xy 244.532091 -121.101937) (xy 244.508419 -121.152434) (xy 244.477646 -121.198947) (xy 244.440429 -121.240484)
			(xy 244.397561 -121.276159) (xy 244.349955 -121.305213) (xy 244.298626 -121.327025) (xy 244.244669 -121.341131)
			(xy 244.189232 -121.347231) (xy 244.133498 -121.345194) (xy 244.078655 -121.335064) (xy 244.025871 -121.317057)
			(xy 243.976271 -121.291556) (xy 243.930913 -121.259105) (xy 243.890764 -121.220396) (xy 243.856678 -121.176253)
			(xy 243.829382 -121.127618) (xy 243.809459 -121.075527) (xy 243.797333 -121.02109) (xy 243.793262 -120.965468)
			(xy 228.79558 -120.965468) (xy 228.79558 -121.821448) (xy 229.46868 -122.494548) (xy 235.18368 -122.494548)
			(xy 235.92917 -123.240038) (xy 238.019334 -123.240038) (xy 238.023405 -123.184416) (xy 238.035531 -123.129979)
			(xy 238.055454 -123.077888) (xy 238.08275 -123.029253) (xy 238.116836 -122.98511) (xy 238.156985 -122.946401)
			(xy 238.202343 -122.91395) (xy 238.251943 -122.888449) (xy 238.304727 -122.870442) (xy 238.35957 -122.860312)
			(xy 238.415304 -122.858275) (xy 238.470741 -122.864375) (xy 238.524698 -122.878481) (xy 238.576027 -122.900293)
			(xy 238.623633 -122.929347) (xy 238.666501 -122.965022) (xy 238.703718 -123.006559) (xy 238.734491 -123.053072)
			(xy 238.758163 -123.103569) (xy 238.774231 -123.156976) (xy 238.782351 -123.212152) (xy 238.78286 -123.240038)
			(xy 238.782351 -123.267924) (xy 238.774231 -123.3231) (xy 238.758163 -123.376507) (xy 238.734491 -123.427004)
			(xy 238.703718 -123.473517) (xy 238.666501 -123.515054) (xy 238.623633 -123.550729) (xy 238.576027 -123.579783)
			(xy 238.524698 -123.601595) (xy 238.470741 -123.615701) (xy 238.415304 -123.621801) (xy 238.35957 -123.619764)
			(xy 238.304727 -123.609634) (xy 238.251943 -123.591627) (xy 238.202343 -123.566126) (xy 238.156985 -123.533675)
			(xy 238.116836 -123.494966) (xy 238.08275 -123.450823) (xy 238.055454 -123.402188) (xy 238.035531 -123.350097)
			(xy 238.023405 -123.29566) (xy 238.019334 -123.240038) (xy 235.92917 -123.240038) (xy 238.10468 -125.415548)
			(xy 238.10468 -126.656592) (xy 238.529366 -126.656592) (xy 238.533437 -126.60097) (xy 238.545563 -126.546533)
			(xy 238.565486 -126.494442) (xy 238.592782 -126.445807) (xy 238.626868 -126.401664) (xy 238.667017 -126.362955)
			(xy 238.712375 -126.330504) (xy 238.761975 -126.305003) (xy 238.814759 -126.286996) (xy 238.869602 -126.276866)
			(xy 238.925336 -126.274829) (xy 238.980773 -126.280929) (xy 239.03473 -126.295035) (xy 239.086059 -126.316847)
			(xy 239.133665 -126.345901) (xy 239.176533 -126.381576) (xy 239.21375 -126.423113) (xy 239.244523 -126.469626)
			(xy 239.268195 -126.520123) (xy 239.284263 -126.57353) (xy 239.292383 -126.628706) (xy 239.292892 -126.656592)
			(xy 239.292383 -126.684478) (xy 239.284263 -126.739654) (xy 239.268195 -126.793061) (xy 239.244523 -126.843558)
			(xy 239.21375 -126.890071) (xy 239.176533 -126.931608) (xy 239.133665 -126.967283) (xy 239.086059 -126.996337)
			(xy 239.03473 -127.018149) (xy 238.980773 -127.032255) (xy 238.925336 -127.038355) (xy 238.869602 -127.036318)
			(xy 238.814759 -127.026188) (xy 238.761975 -127.008181) (xy 238.712375 -126.98268) (xy 238.667017 -126.950229)
			(xy 238.626868 -126.91152) (xy 238.592782 -126.867377) (xy 238.565486 -126.818742) (xy 238.545563 -126.766651)
			(xy 238.533437 -126.712214) (xy 238.529366 -126.656592) (xy 238.10468 -126.656592) (xy 238.10468 -126.964948)
			(xy 238.27994 -127.140208) (xy 242.041172 -127.140208) (xy 242.041172 -126.276608) (xy 242.04169 -126.247925)
			(xy 242.0503 -126.19121) (xy 242.067297 -126.13642) (xy 242.092299 -126.084789) (xy 242.124743 -126.03748)
			(xy 242.1639 -125.995556) (xy 242.208887 -125.959961) (xy 242.258692 -125.931497) (xy 242.312196 -125.910803)
			(xy 242.368192 -125.898346) (xy 242.396772 -125.895862) (xy 242.411321 -125.894396) (xy 242.43873 -125.884242)
			(xy 242.462142 -125.866744) (xy 242.479641 -125.843332) (xy 242.489796 -125.815923) (xy 242.49126 -125.801374)
			(xy 242.493775 -125.772813) (xy 242.506193 -125.716843) (xy 242.526851 -125.663363) (xy 242.555283 -125.613579)
			(xy 242.590849 -125.568612) (xy 242.632747 -125.529478) (xy 242.680031 -125.497058) (xy 242.731637 -125.472084)
			(xy 242.7864 -125.455117) (xy 242.843086 -125.446541) (xy 242.871752 -125.446028) (xy 242.89901 -125.446416)
			(xy 242.952971 -125.454168) (xy 243.00528 -125.469521) (xy 243.05487 -125.492163) (xy 243.100734 -125.521633)
			(xy 243.141936 -125.55733) (xy 243.177639 -125.598528) (xy 243.207114 -125.644387) (xy 243.229762 -125.693975)
			(xy 243.245122 -125.746282) (xy 243.252881 -125.800242) (xy 243.252881 -125.854758) (xy 243.245122 -125.908718)
			(xy 243.229762 -125.961025) (xy 243.207114 -126.010613) (xy 243.177639 -126.056472) (xy 243.141936 -126.09767)
			(xy 243.100734 -126.133367) (xy 243.05487 -126.162837) (xy 243.00528 -126.185479) (xy 242.952971 -126.200832)
			(xy 242.89901 -126.208584) (xy 242.871752 -126.209044) (xy 242.856766 -126.20879) (xy 242.846223 -126.20893)
			(xy 242.826607 -126.216588) (xy 242.811711 -126.231471) (xy 242.804038 -126.251081) (xy 242.803934 -126.261622)
			(xy 242.804188 -126.276608) (xy 242.804188 -126.738147) (xy 255.071926 -126.738147) (xy 255.071926 -126.683653)
			(xy 255.079681 -126.629714) (xy 255.095033 -126.577427) (xy 255.11767 -126.527858) (xy 255.147131 -126.482014)
			(xy 255.182816 -126.44083) (xy 255.223998 -126.405143) (xy 255.26984 -126.37568) (xy 255.319409 -126.35304)
			(xy 255.371694 -126.337685) (xy 255.425633 -126.329928) (xy 255.45288 -126.32944) (xy 255.481938 -126.329992)
			(xy 255.539381 -126.338823) (xy 255.594819 -126.356266) (xy 255.646968 -126.381919) (xy 255.69462 -126.415188)
			(xy 255.716024 -126.43485) (xy 255.726042 -126.443864) (xy 255.749736 -126.456688) (xy 255.775959 -126.462873)
			(xy 255.802886 -126.461989) (xy 255.828647 -126.454098) (xy 255.851449 -126.439748) (xy 255.869708 -126.419936)
			(xy 255.876298 -126.40818) (xy 255.888709 -126.385276) (xy 255.918773 -126.342735) (xy 255.954345 -126.304681)
			(xy 255.994766 -126.271822) (xy 256.039282 -126.244769) (xy 256.087065 -126.224025) (xy 256.137227 -126.209977)
			(xy 256.188834 -126.202885) (xy 256.21488 -126.20244) (xy 256.242137 -126.202806) (xy 256.296097 -126.210561)
			(xy 256.348404 -126.225917) (xy 256.397993 -126.248562) (xy 256.443854 -126.278033) (xy 256.485055 -126.313731)
			(xy 256.520755 -126.35493) (xy 256.550229 -126.400789) (xy 256.572876 -126.450377) (xy 256.588235 -126.502683)
			(xy 256.595993 -126.556643) (xy 256.595993 -126.611157) (xy 256.588235 -126.665117) (xy 256.572876 -126.717423)
			(xy 256.550229 -126.767011) (xy 256.520755 -126.81287) (xy 256.485055 -126.854069) (xy 256.443854 -126.889767)
			(xy 256.397993 -126.919238) (xy 256.348404 -126.941883) (xy 256.296097 -126.957239) (xy 256.242137 -126.964994)
			(xy 256.21488 -126.965456) (xy 256.185821 -126.964929) (xy 256.128377 -126.956093) (xy 256.072939 -126.938643)
			(xy 256.02079 -126.912984) (xy 255.973139 -126.87971) (xy 255.951736 -126.860046) (xy 255.94166 -126.851101)
			(xy 255.917982 -126.838274) (xy 255.891773 -126.832082) (xy 255.864858 -126.832955) (xy 255.839106 -126.840834)
			(xy 255.816309 -126.85517) (xy 255.798052 -126.874967) (xy 255.791462 -126.886716) (xy 255.779079 -126.909636)
			(xy 255.749012 -126.952177) (xy 255.713435 -126.990231) (xy 255.673011 -127.02309) (xy 255.62849 -127.050141)
			(xy 255.580703 -127.070882) (xy 255.530537 -127.084927) (xy 255.478927 -127.092014) (xy 255.45288 -127.092456)
			(xy 255.425633 -127.091872) (xy 255.371694 -127.084115) (xy 255.319409 -127.06876) (xy 255.26984 -127.04612)
			(xy 255.223998 -127.016657) (xy 255.182816 -126.98097) (xy 255.147131 -126.939786) (xy 255.11767 -126.893942)
			(xy 255.095033 -126.844373) (xy 255.079681 -126.792086) (xy 255.071926 -126.738147) (xy 242.804188 -126.738147)
			(xy 242.804188 -127.140208) (xy 242.803934 -127.155194) (xy 242.803979 -127.165743) (xy 242.811664 -127.185371)
			(xy 242.826578 -127.200267) (xy 242.846214 -127.207931) (xy 242.856766 -127.208026) (xy 242.871752 -127.207772)
			(xy 242.899006 -127.208272) (xy 242.952959 -127.216023) (xy 243.00526 -127.231374) (xy 243.054843 -127.254013)
			(xy 243.1007 -127.283478) (xy 243.141896 -127.31917) (xy 243.14309 -127.320548) (xy 244.56212 -127.320548)
			(xy 244.566191 -127.264926) (xy 244.578317 -127.210489) (xy 244.59824 -127.158398) (xy 244.625536 -127.109763)
			(xy 244.659622 -127.06562) (xy 244.699771 -127.026911) (xy 244.745129 -126.99446) (xy 244.794729 -126.968959)
			(xy 244.847513 -126.950952) (xy 244.902356 -126.940822) (xy 244.95809 -126.938785) (xy 245.013527 -126.944885)
			(xy 245.067484 -126.958991) (xy 245.118813 -126.980803) (xy 245.166419 -127.009857) (xy 245.209287 -127.045532)
			(xy 245.246504 -127.087069) (xy 245.277277 -127.133582) (xy 245.300949 -127.184079) (xy 245.317017 -127.237486)
			(xy 245.325137 -127.292662) (xy 245.325498 -127.31242) (xy 246.198134 -127.31242) (xy 246.202205 -127.256798)
			(xy 246.214331 -127.202361) (xy 246.234254 -127.15027) (xy 246.26155 -127.101635) (xy 246.295636 -127.057492)
			(xy 246.335785 -127.018783) (xy 246.381143 -126.986332) (xy 246.430743 -126.960831) (xy 246.483527 -126.942824)
			(xy 246.53837 -126.932694) (xy 246.594104 -126.930657) (xy 246.649541 -126.936757) (xy 246.703498 -126.950863)
			(xy 246.754827 -126.972675) (xy 246.802433 -127.001729) (xy 246.845301 -127.037404) (xy 246.882518 -127.078941)
			(xy 246.913291 -127.125454) (xy 246.936963 -127.175951) (xy 246.953031 -127.229358) (xy 246.961151 -127.284534)
			(xy 246.96166 -127.31242) (xy 246.961151 -127.340306) (xy 246.953031 -127.395482) (xy 246.936963 -127.448889)
			(xy 246.913291 -127.499386) (xy 246.882518 -127.545899) (xy 246.845301 -127.587436) (xy 246.802433 -127.623111)
			(xy 246.754827 -127.652165) (xy 246.703498 -127.673977) (xy 246.649541 -127.688083) (xy 246.594104 -127.694183)
			(xy 246.53837 -127.692146) (xy 246.483527 -127.682016) (xy 246.430743 -127.664009) (xy 246.381143 -127.638508)
			(xy 246.335785 -127.606057) (xy 246.295636 -127.567348) (xy 246.26155 -127.523205) (xy 246.234254 -127.47457)
			(xy 246.214331 -127.422479) (xy 246.202205 -127.368042) (xy 246.198134 -127.31242) (xy 245.325498 -127.31242)
			(xy 245.325646 -127.320548) (xy 245.325137 -127.348434) (xy 245.317017 -127.40361) (xy 245.300949 -127.457017)
			(xy 245.277277 -127.507514) (xy 245.246504 -127.554027) (xy 245.209287 -127.595564) (xy 245.166419 -127.631239)
			(xy 245.118813 -127.660293) (xy 245.067484 -127.682105) (xy 245.013527 -127.696211) (xy 244.95809 -127.702311)
			(xy 244.902356 -127.700274) (xy 244.847513 -127.690144) (xy 244.794729 -127.672137) (xy 244.745129 -127.646636)
			(xy 244.699771 -127.614185) (xy 244.659622 -127.575476) (xy 244.625536 -127.531333) (xy 244.59824 -127.482698)
			(xy 244.578317 -127.430607) (xy 244.566191 -127.37617) (xy 244.56212 -127.320548) (xy 243.14309 -127.320548)
			(xy 243.177593 -127.360361) (xy 243.207064 -127.406214) (xy 243.229709 -127.455795) (xy 243.245067 -127.508094)
			(xy 243.252825 -127.562046) (xy 243.252825 -127.616554) (xy 243.245067 -127.670506) (xy 243.229709 -127.722805)
			(xy 243.207064 -127.772386) (xy 243.181089 -127.8128) (xy 250.163582 -127.8128) (xy 250.167653 -127.757178)
			(xy 250.179779 -127.702741) (xy 250.199702 -127.65065) (xy 250.226998 -127.602015) (xy 250.261084 -127.557872)
			(xy 250.301233 -127.519163) (xy 250.346591 -127.486712) (xy 250.396191 -127.461211) (xy 250.448975 -127.443204)
			(xy 250.503818 -127.433074) (xy 250.559552 -127.431037) (xy 250.614989 -127.437137) (xy 250.668946 -127.451243)
			(xy 250.720275 -127.473055) (xy 250.767881 -127.502109) (xy 250.810749 -127.537784) (xy 250.847966 -127.579321)
			(xy 250.878739 -127.625834) (xy 250.902411 -127.676331) (xy 250.918479 -127.729738) (xy 250.926599 -127.784914)
			(xy 250.927108 -127.8128) (xy 250.926599 -127.840686) (xy 250.918479 -127.895862) (xy 250.902411 -127.949269)
			(xy 250.892204 -127.971042) (xy 258.480812 -127.971042) (xy 258.484883 -127.91542) (xy 258.497009 -127.860983)
			(xy 258.516932 -127.808892) (xy 258.544228 -127.760257) (xy 258.578314 -127.716114) (xy 258.618463 -127.677405)
			(xy 258.663821 -127.644954) (xy 258.713421 -127.619453) (xy 258.766205 -127.601446) (xy 258.821048 -127.591316)
			(xy 258.876782 -127.589279) (xy 258.932219 -127.595379) (xy 258.986176 -127.609485) (xy 259.037505 -127.631297)
			(xy 259.085111 -127.660351) (xy 259.127979 -127.696026) (xy 259.165196 -127.737563) (xy 259.195969 -127.784076)
			(xy 259.219641 -127.834573) (xy 259.235709 -127.88798) (xy 259.238177 -127.904748) (xy 260.315962 -127.904748)
			(xy 260.320033 -127.849126) (xy 260.332159 -127.794689) (xy 260.352082 -127.742598) (xy 260.379378 -127.693963)
			(xy 260.413464 -127.64982) (xy 260.453613 -127.611111) (xy 260.498971 -127.57866) (xy 260.548571 -127.553159)
			(xy 260.601355 -127.535152) (xy 260.656198 -127.525022) (xy 260.711932 -127.522985) (xy 260.767369 -127.529085)
			(xy 260.821326 -127.543191) (xy 260.872655 -127.565003) (xy 260.920261 -127.594057) (xy 260.963129 -127.629732)
			(xy 261.000346 -127.671269) (xy 261.031119 -127.717782) (xy 261.054791 -127.768279) (xy 261.070859 -127.821686)
			(xy 261.078979 -127.876862) (xy 261.079488 -127.904748) (xy 261.078979 -127.932634) (xy 261.070859 -127.98781)
			(xy 261.054791 -128.041217) (xy 261.031119 -128.091714) (xy 261.000346 -128.138227) (xy 260.963129 -128.179764)
			(xy 260.920261 -128.215439) (xy 260.872655 -128.244493) (xy 260.821326 -128.266305) (xy 260.767369 -128.280411)
			(xy 260.711932 -128.286511) (xy 260.656198 -128.284474) (xy 260.601355 -128.274344) (xy 260.548571 -128.256337)
			(xy 260.498971 -128.230836) (xy 260.453613 -128.198385) (xy 260.413464 -128.159676) (xy 260.379378 -128.115533)
			(xy 260.352082 -128.066898) (xy 260.332159 -128.014807) (xy 260.320033 -127.96037) (xy 260.315962 -127.904748)
			(xy 259.238177 -127.904748) (xy 259.243829 -127.943156) (xy 259.244338 -127.971042) (xy 259.243829 -127.998928)
			(xy 259.235709 -128.054104) (xy 259.219641 -128.107511) (xy 259.195969 -128.158008) (xy 259.165196 -128.204521)
			(xy 259.127979 -128.246058) (xy 259.085111 -128.281733) (xy 259.037505 -128.310787) (xy 258.986176 -128.332599)
			(xy 258.932219 -128.346705) (xy 258.876782 -128.352805) (xy 258.821048 -128.350768) (xy 258.766205 -128.340638)
			(xy 258.713421 -128.322631) (xy 258.663821 -128.29713) (xy 258.618463 -128.264679) (xy 258.578314 -128.22597)
			(xy 258.544228 -128.181827) (xy 258.516932 -128.133192) (xy 258.497009 -128.081101) (xy 258.484883 -128.026664)
			(xy 258.480812 -127.971042) (xy 250.892204 -127.971042) (xy 250.878739 -127.999766) (xy 250.847966 -128.046279)
			(xy 250.810749 -128.087816) (xy 250.767881 -128.123491) (xy 250.720275 -128.152545) (xy 250.668946 -128.174357)
			(xy 250.614989 -128.188463) (xy 250.559552 -128.194563) (xy 250.503818 -128.192526) (xy 250.448975 -128.182396)
			(xy 250.396191 -128.164389) (xy 250.346591 -128.138888) (xy 250.301233 -128.106437) (xy 250.261084 -128.067728)
			(xy 250.226998 -128.023585) (xy 250.199702 -127.97495) (xy 250.179779 -127.922859) (xy 250.167653 -127.868422)
			(xy 250.163582 -127.8128) (xy 243.181089 -127.8128) (xy 243.177593 -127.818239) (xy 243.141896 -127.85943)
			(xy 243.1007 -127.895122) (xy 243.054843 -127.924587) (xy 243.00526 -127.947226) (xy 242.952959 -127.962577)
			(xy 242.899006 -127.970328) (xy 242.871752 -127.970788) (xy 242.843088 -127.97031) (xy 242.786411 -127.961698)
			(xy 242.731659 -127.944707) (xy 242.680065 -127.919717) (xy 242.632789 -127.887291) (xy 242.590894 -127.848159)
			(xy 242.555324 -127.803201) (xy 242.526878 -127.753429) (xy 242.506196 -127.699962) (xy 242.493745 -127.644003)
			(xy 242.49126 -127.615442) (xy 242.489784 -127.600894) (xy 242.479634 -127.573485) (xy 242.462138 -127.550073)
			(xy 242.438728 -127.532573) (xy 242.41132 -127.522419) (xy 242.396772 -127.520954) (xy 242.368186 -127.518481)
			(xy 242.312173 -127.506054) (xy 242.258652 -127.485381) (xy 242.20883 -127.456926) (xy 242.163831 -127.421332)
			(xy 242.124668 -127.379401) (xy 242.092226 -127.332079) (xy 242.067235 -127.280432) (xy 242.05026 -127.225626)
			(xy 242.041682 -127.168896) (xy 242.041172 -127.140208) (xy 238.27994 -127.140208) (xy 239.913668 -128.773936)
			(xy 239.924651 -128.784112) (xy 239.951075 -128.798159) (xy 239.980436 -128.803947) (xy 240.010214 -128.800978)
			(xy 240.037855 -128.789508) (xy 240.060986 -128.770521) (xy 240.077623 -128.745645) (xy 240.086338 -128.717016)
			(xy 240.086896 -128.702054) (xy 240.086896 -128.156208) (xy 240.08742 -128.127512) (xy 240.096026 -128.070769)
			(xy 240.11303 -128.015954) (xy 240.13805 -127.964302) (xy 240.17052 -127.916978) (xy 240.209709 -127.875049)
			(xy 240.254734 -127.839459) (xy 240.304579 -127.811011) (xy 240.358122 -127.790347) (xy 240.414156 -127.777932)
			(xy 240.44275 -127.775462) (xy 240.457301 -127.774001) (xy 240.484716 -127.76385) (xy 240.508134 -127.746352)
			(xy 240.525638 -127.722939) (xy 240.535795 -127.695526) (xy 240.537238 -127.680974) (xy 240.539722 -127.652415)
			(xy 240.552173 -127.596459) (xy 240.572854 -127.542994) (xy 240.601301 -127.493226) (xy 240.636872 -127.448273)
			(xy 240.678768 -127.409146) (xy 240.726045 -127.376728) (xy 240.77764 -127.351746) (xy 240.832392 -127.334764)
			(xy 240.889068 -127.326163) (xy 240.91773 -127.325628) (xy 240.944977 -127.326116) (xy 240.998917 -127.333875)
			(xy 241.051203 -127.349232) (xy 241.100771 -127.371872) (xy 241.146614 -127.401337) (xy 241.187796 -127.437025)
			(xy 241.223481 -127.47821) (xy 241.252942 -127.524055) (xy 241.275579 -127.573625) (xy 241.290931 -127.625913)
			(xy 241.298686 -127.679853) (xy 241.298686 -127.734347) (xy 241.290931 -127.788287) (xy 241.275579 -127.840575)
			(xy 241.252942 -127.890145) (xy 241.223481 -127.93599) (xy 241.187796 -127.977175) (xy 241.146614 -128.012863)
			(xy 241.100771 -128.042328) (xy 241.051203 -128.064968) (xy 240.998917 -128.080325) (xy 240.944977 -128.088084)
			(xy 240.91773 -128.088644) (xy 240.902744 -128.08839) (xy 240.892196 -128.088489) (xy 240.872571 -128.096157)
			(xy 240.857669 -128.111053) (xy 240.849992 -128.130675) (xy 240.849912 -128.141222) (xy 240.85042 -128.156208)
			(xy 240.85042 -128.929384) (xy 240.850862 -128.942978) (xy 240.858056 -128.969199) (xy 240.871911 -128.992593)
			(xy 240.891447 -129.011504) (xy 240.915279 -129.024591) (xy 240.941719 -129.030929) (xy 240.955322 -129.030984)
			(xy 240.968022 -129.03073) (xy 240.995273 -129.031195) (xy 241.049219 -129.038955) (xy 241.101512 -129.054313)
			(xy 241.151087 -129.076957) (xy 241.196935 -129.106426) (xy 241.238122 -129.142121) (xy 241.27381 -129.183313)
			(xy 241.303272 -129.229165) (xy 241.325908 -129.278744) (xy 241.341258 -129.331039) (xy 241.349009 -129.384987)
			(xy 241.34953 -129.412238) (xy 241.349003 -129.440748) (xy 241.340522 -129.497132) (xy 241.32374 -129.551625)
			(xy 241.299031 -129.603012) (xy 241.266946 -129.650147) (xy 241.2282 -129.691979) (xy 241.183657 -129.727576)
			(xy 241.134311 -129.756143) (xy 241.107976 -129.767076) (xy 241.094755 -129.772811) (xy 241.071956 -129.790417)
			(xy 241.054975 -129.813686) (xy 241.045161 -129.840768) (xy 241.043294 -129.869513) (xy 241.049521 -129.897638)
			(xy 241.063349 -129.922908) (xy 241.073178 -129.933446) (xy 241.99469 -130.854958) (xy 242.048538 -130.80111)
			(xy 242.044982 -130.775964) (xy 242.043175 -130.762448) (xy 242.041268 -130.735244) (xy 242.041172 -130.721608)
			(xy 242.041172 -129.858008) (xy 242.041681 -129.82932) (xy 242.050256 -129.772587) (xy 242.067231 -129.717779)
			(xy 242.09222 -129.66613) (xy 242.124662 -129.618806) (xy 242.163825 -129.576873) (xy 242.208825 -129.541277)
			(xy 242.258648 -129.512821) (xy 242.31217 -129.492147) (xy 242.368185 -129.47972) (xy 242.396772 -129.477262)
			(xy 242.411321 -129.475798) (xy 242.438731 -129.465644) (xy 242.462143 -129.448145) (xy 242.479643 -129.424733)
			(xy 242.489797 -129.397323) (xy 242.49126 -129.382774) (xy 242.493743 -129.354213) (xy 242.506193 -129.298252)
			(xy 242.526874 -129.244782) (xy 242.555319 -129.195008) (xy 242.590889 -129.150048) (xy 242.632784 -129.110914)
			(xy 242.680061 -129.078487) (xy 242.731656 -129.053496) (xy 242.786409 -129.036503) (xy 242.843088 -129.027891)
			(xy 242.871752 -129.027428) (xy 242.899005 -129.027888) (xy 242.952956 -129.035639) (xy 243.005254 -129.050989)
			(xy 243.054836 -129.073627) (xy 243.100691 -129.103091) (xy 243.141885 -129.138781) (xy 243.177581 -129.179971)
			(xy 243.20705 -129.225822) (xy 243.229694 -129.275401) (xy 243.245051 -129.327697) (xy 243.252809 -129.381648)
			(xy 243.252809 -129.403348) (xy 243.615462 -129.403348) (xy 243.619533 -129.347726) (xy 243.631659 -129.293289)
			(xy 243.651582 -129.241198) (xy 243.678878 -129.192563) (xy 243.712964 -129.14842) (xy 243.753113 -129.109711)
			(xy 243.798471 -129.07726) (xy 243.848071 -129.051759) (xy 243.900855 -129.033752) (xy 243.955698 -129.023622)
			(xy 244.011432 -129.021585) (xy 244.066869 -129.027685) (xy 244.120826 -129.041791) (xy 244.172155 -129.063603)
			(xy 244.219761 -129.092657) (xy 244.262629 -129.128332) (xy 244.299846 -129.169869) (xy 244.330619 -129.216382)
			(xy 244.354291 -129.266879) (xy 244.370359 -129.320286) (xy 244.376639 -129.362962) (xy 246.602248 -129.362962)
			(xy 246.606319 -129.30734) (xy 246.618445 -129.252903) (xy 246.638368 -129.200812) (xy 246.665664 -129.152177)
			(xy 246.69975 -129.108034) (xy 246.739899 -129.069325) (xy 246.785257 -129.036874) (xy 246.834857 -129.011373)
			(xy 246.887641 -128.993366) (xy 246.942484 -128.983236) (xy 246.998218 -128.981199) (xy 247.053655 -128.987299)
			(xy 247.107612 -129.001405) (xy 247.158941 -129.023217) (xy 247.206547 -129.052271) (xy 247.249415 -129.087946)
			(xy 247.286632 -129.129483) (xy 247.317405 -129.175996) (xy 247.341077 -129.226493) (xy 247.357145 -129.2799)
			(xy 247.365265 -129.335076) (xy 247.365774 -129.362962) (xy 247.365265 -129.390848) (xy 247.357145 -129.446024)
			(xy 247.341077 -129.499431) (xy 247.317405 -129.549928) (xy 247.286632 -129.596441) (xy 247.249415 -129.637978)
			(xy 247.206547 -129.673653) (xy 247.158941 -129.702707) (xy 247.107612 -129.724519) (xy 247.053655 -129.738625)
			(xy 246.998218 -129.744725) (xy 246.942484 -129.742688) (xy 246.887641 -129.732558) (xy 246.834857 -129.714551)
			(xy 246.785257 -129.68905) (xy 246.739899 -129.656599) (xy 246.69975 -129.61789) (xy 246.665664 -129.573747)
			(xy 246.638368 -129.525112) (xy 246.618445 -129.473021) (xy 246.606319 -129.418584) (xy 246.602248 -129.362962)
			(xy 244.376639 -129.362962) (xy 244.378479 -129.375462) (xy 244.378988 -129.403348) (xy 244.378479 -129.431234)
			(xy 244.370359 -129.48641) (xy 244.354291 -129.539817) (xy 244.330619 -129.590314) (xy 244.299846 -129.636827)
			(xy 244.262629 -129.678364) (xy 244.219761 -129.714039) (xy 244.172155 -129.743093) (xy 244.120826 -129.764905)
			(xy 244.066869 -129.779011) (xy 244.011432 -129.785111) (xy 243.955698 -129.783074) (xy 243.900855 -129.772944)
			(xy 243.848071 -129.754937) (xy 243.798471 -129.729436) (xy 243.753113 -129.696985) (xy 243.712964 -129.658276)
			(xy 243.678878 -129.614133) (xy 243.651582 -129.565498) (xy 243.631659 -129.513407) (xy 243.619533 -129.45897)
			(xy 243.615462 -129.403348) (xy 243.252809 -129.403348) (xy 243.252809 -129.436152) (xy 243.245051 -129.490103)
			(xy 243.229694 -129.542399) (xy 243.20705 -129.591978) (xy 243.177581 -129.637829) (xy 243.141885 -129.679019)
			(xy 243.100691 -129.714709) (xy 243.054836 -129.744173) (xy 243.005254 -129.766811) (xy 242.952956 -129.782161)
			(xy 242.899005 -129.789912) (xy 242.871752 -129.790444) (xy 242.856766 -129.79019) (xy 242.846215 -129.790285)
			(xy 242.826582 -129.797949) (xy 242.811672 -129.812846) (xy 242.803992 -129.832473) (xy 242.803934 -129.843022)
			(xy 242.804188 -129.858008) (xy 242.804188 -129.913147) (xy 245.165926 -129.913147) (xy 245.165926 -129.858653)
			(xy 245.173681 -129.804714) (xy 245.189033 -129.752427) (xy 245.21167 -129.702858) (xy 245.241131 -129.657014)
			(xy 245.276816 -129.61583) (xy 245.317998 -129.580143) (xy 245.36384 -129.55068) (xy 245.413409 -129.52804)
			(xy 245.465694 -129.512685) (xy 245.519633 -129.504928) (xy 245.54688 -129.50444) (xy 245.576014 -129.50501)
			(xy 245.633601 -129.513894) (xy 245.689168 -129.531429) (xy 245.741424 -129.557206) (xy 245.789155 -129.590627)
			(xy 245.831251 -129.630915) (xy 245.866734 -129.677133) (xy 245.894779 -129.728208) (xy 245.905274 -129.755392)
			(xy 245.910602 -129.768656) (xy 245.927391 -129.791772) (xy 245.949928 -129.809332) (xy 245.976448 -129.819961)
			(xy 246.004874 -129.822826) (xy 246.032982 -129.817703) (xy 246.04599 -129.81178) (xy 246.072432 -129.799317)
			(xy 246.128163 -129.781684) (xy 246.185928 -129.772737) (xy 246.215154 -129.772156) (xy 246.242406 -129.772688)
			(xy 246.296357 -129.780439) (xy 246.348656 -129.79579) (xy 246.398237 -129.818427) (xy 246.444091 -129.847891)
			(xy 246.485286 -129.883582) (xy 246.520981 -129.924772) (xy 246.550451 -129.970623) (xy 246.573094 -130.020201)
			(xy 246.588451 -130.072498) (xy 246.596209 -130.126448) (xy 246.596209 -130.167147) (xy 248.721926 -130.167147)
			(xy 248.721926 -130.112653) (xy 248.729681 -130.058714) (xy 248.745033 -130.006427) (xy 248.76767 -129.956858)
			(xy 248.797131 -129.911014) (xy 248.832816 -129.86983) (xy 248.873998 -129.834143) (xy 248.91984 -129.80468)
			(xy 248.969409 -129.78204) (xy 249.021694 -129.766685) (xy 249.075633 -129.758928) (xy 249.10288 -129.75844)
			(xy 249.131797 -129.758958) (xy 249.188969 -129.767685) (xy 249.244169 -129.784942) (xy 249.296131 -129.810333)
			(xy 249.343664 -129.843278) (xy 249.38568 -129.88302) (xy 249.40387 -129.905506) (xy 249.413767 -129.917311)
			(xy 249.439091 -129.93483) (xy 249.468484 -129.944006) (xy 249.499276 -129.944006) (xy 249.528669 -129.93483)
			(xy 249.553993 -129.917311) (xy 249.56389 -129.905506) (xy 249.582088 -129.883029) (xy 249.624106 -129.843293)
			(xy 249.67164 -129.810353) (xy 249.7236 -129.784963) (xy 249.778796 -129.767706) (xy 249.835964 -129.758976)
			(xy 249.86488 -129.75844) (xy 249.892137 -129.758806) (xy 249.946097 -129.766561) (xy 249.998404 -129.781917)
			(xy 250.047993 -129.804562) (xy 250.093854 -129.834033) (xy 250.135055 -129.869731) (xy 250.170755 -129.91093)
			(xy 250.200229 -129.956789) (xy 250.222876 -130.006377) (xy 250.238235 -130.058683) (xy 250.245993 -130.112643)
			(xy 250.245993 -130.167157) (xy 250.238235 -130.221117) (xy 250.224777 -130.266948) (xy 253.546862 -130.266948)
			(xy 253.550933 -130.211326) (xy 253.563059 -130.156889) (xy 253.582982 -130.104798) (xy 253.610278 -130.056163)
			(xy 253.644364 -130.01202) (xy 253.684513 -129.973311) (xy 253.729871 -129.94086) (xy 253.779471 -129.915359)
			(xy 253.832255 -129.897352) (xy 253.887098 -129.887222) (xy 253.942832 -129.885185) (xy 253.998269 -129.891285)
			(xy 254.052226 -129.905391) (xy 254.103555 -129.927203) (xy 254.151161 -129.956257) (xy 254.194029 -129.991932)
			(xy 254.231246 -130.033469) (xy 254.262019 -130.079982) (xy 254.285691 -130.130479) (xy 254.301759 -130.183886)
			(xy 254.309879 -130.239062) (xy 254.310388 -130.266948) (xy 254.309892 -130.294144) (xy 254.436926 -130.294144)
			(xy 254.436926 -130.239651) (xy 254.444682 -130.185712) (xy 254.460034 -130.133426) (xy 254.482671 -130.083856)
			(xy 254.512132 -130.038013) (xy 254.547817 -129.996829) (xy 254.588999 -129.961142) (xy 254.634841 -129.931679)
			(xy 254.684409 -129.90904) (xy 254.736695 -129.893685) (xy 254.790633 -129.885928) (xy 254.81788 -129.88544)
			(xy 254.838035 -129.885679) (xy 254.878124 -129.889878) (xy 254.89789 -129.893822) (xy 254.913077 -129.896635)
			(xy 254.943826 -129.893839) (xy 254.972338 -129.881989) (xy 254.996011 -129.862166) (xy 255.012686 -129.83618)
			(xy 255.020841 -129.8064) (xy 255.020826 -129.790952) (xy 255.020572 -129.776728) (xy 255.021025 -129.749472)
			(xy 255.028779 -129.695515) (xy 255.044133 -129.643211) (xy 255.066775 -129.593625) (xy 255.096243 -129.547765)
			(xy 255.131938 -129.506566) (xy 255.173133 -129.470867) (xy 255.21899 -129.441394) (xy 255.268574 -129.418747)
			(xy 255.320876 -129.403387) (xy 255.374832 -129.395628) (xy 255.429344 -129.395626) (xy 255.4833 -129.403382)
			(xy 255.535604 -129.418739) (xy 255.585189 -129.441382) (xy 255.631048 -129.470853) (xy 255.672245 -129.506549)
			(xy 255.707942 -129.547746) (xy 255.737414 -129.593604) (xy 255.760058 -129.643189) (xy 255.775416 -129.695492)
			(xy 255.783173 -129.749448) (xy 255.783173 -129.80396) (xy 255.775414 -129.857916) (xy 255.760056 -129.910219)
			(xy 255.73741 -129.959803) (xy 255.707938 -130.00566) (xy 255.672239 -130.046856) (xy 255.631041 -130.082552)
			(xy 255.585182 -130.112021) (xy 255.535596 -130.134664) (xy 255.483292 -130.150019) (xy 255.429336 -130.157774)
			(xy 255.40208 -130.158236) (xy 255.381925 -130.158004) (xy 255.341836 -130.1538) (xy 255.32207 -130.149854)
			(xy 255.306871 -130.147129) (xy 255.276133 -130.149909) (xy 255.247628 -130.161742) (xy 255.223958 -130.181547)
			(xy 255.207282 -130.207518) (xy 255.199122 -130.237283) (xy 255.199134 -130.252724) (xy 255.199388 -130.266948)
			(xy 255.19887 -130.294195) (xy 255.191109 -130.348133) (xy 255.17575 -130.400417) (xy 255.153107 -130.449984)
			(xy 255.123641 -130.495823) (xy 255.087951 -130.537003) (xy 255.046765 -130.572685) (xy 255.000919 -130.602142)
			(xy 254.951348 -130.624776) (xy 254.899061 -130.640124) (xy 254.845121 -130.647876) (xy 254.790628 -130.647872)
			(xy 254.73669 -130.640114) (xy 254.684404 -130.624758) (xy 254.634836 -130.602118) (xy 254.588995 -130.572655)
			(xy 254.547813 -130.536967) (xy 254.512129 -130.495783) (xy 254.482668 -130.449939) (xy 254.460032 -130.400369)
			(xy 254.44468 -130.348083) (xy 254.436926 -130.294144) (xy 254.309892 -130.294144) (xy 254.309879 -130.294834)
			(xy 254.301759 -130.35001) (xy 254.285691 -130.403417) (xy 254.262019 -130.453914) (xy 254.231246 -130.500427)
			(xy 254.194029 -130.541964) (xy 254.151161 -130.577639) (xy 254.103555 -130.606693) (xy 254.052226 -130.628505)
			(xy 253.998269 -130.642611) (xy 253.942832 -130.648711) (xy 253.887098 -130.646674) (xy 253.832255 -130.636544)
			(xy 253.779471 -130.618537) (xy 253.729871 -130.593036) (xy 253.684513 -130.560585) (xy 253.644364 -130.521876)
			(xy 253.610278 -130.477733) (xy 253.582982 -130.429098) (xy 253.563059 -130.377007) (xy 253.550933 -130.32257)
			(xy 253.546862 -130.266948) (xy 250.224777 -130.266948) (xy 250.222876 -130.273423) (xy 250.200229 -130.323011)
			(xy 250.170755 -130.36887) (xy 250.135055 -130.410069) (xy 250.093854 -130.445767) (xy 250.047993 -130.475238)
			(xy 249.998404 -130.497883) (xy 249.946097 -130.513239) (xy 249.892137 -130.520994) (xy 249.86488 -130.521456)
			(xy 249.835964 -130.520897) (xy 249.778794 -130.512178) (xy 249.723596 -130.49493) (xy 249.671633 -130.469546)
			(xy 249.624099 -130.436609) (xy 249.582081 -130.396873) (xy 249.56389 -130.37439) (xy 249.553993 -130.362585)
			(xy 249.528669 -130.345066) (xy 249.499276 -130.33589) (xy 249.468484 -130.33589) (xy 249.439091 -130.345066)
			(xy 249.413767 -130.362585) (xy 249.40387 -130.37439) (xy 249.385693 -130.396886) (xy 249.343671 -130.436621)
			(xy 249.296133 -130.469559) (xy 249.244169 -130.494945) (xy 249.188969 -130.512198) (xy 249.131797 -130.520923)
			(xy 249.10288 -130.521456) (xy 249.075633 -130.520872) (xy 249.021694 -130.513115) (xy 248.969409 -130.49776)
			(xy 248.91984 -130.47512) (xy 248.873998 -130.445657) (xy 248.832816 -130.40997) (xy 248.797131 -130.368786)
			(xy 248.76767 -130.322942) (xy 248.745033 -130.273373) (xy 248.729681 -130.221086) (xy 248.721926 -130.167147)
			(xy 246.596209 -130.167147) (xy 246.596209 -130.180952) (xy 246.588451 -130.234902) (xy 246.573094 -130.287199)
			(xy 246.550451 -130.336777) (xy 246.520981 -130.382628) (xy 246.485286 -130.423818) (xy 246.444091 -130.459509)
			(xy 246.398237 -130.488973) (xy 246.348656 -130.51161) (xy 246.296357 -130.526961) (xy 246.242406 -130.534712)
			(xy 246.215154 -130.535172) (xy 246.186022 -130.534565) (xy 246.128437 -130.525686) (xy 246.072871 -130.508157)
			(xy 246.020615 -130.482385) (xy 245.972884 -130.448969) (xy 245.930787 -130.408686) (xy 245.895303 -130.362472)
			(xy 245.867256 -130.311402) (xy 245.85676 -130.28422) (xy 245.851508 -130.270922) (xy 245.834705 -130.247797)
			(xy 245.812152 -130.230235) (xy 245.785615 -130.219611) (xy 245.757174 -130.216757) (xy 245.729055 -130.221898)
			(xy 245.716044 -130.227832) (xy 245.689597 -130.240284) (xy 245.633869 -130.257921) (xy 245.576106 -130.266873)
			(xy 245.54688 -130.267456) (xy 245.519633 -130.266872) (xy 245.465694 -130.259115) (xy 245.413409 -130.24376)
			(xy 245.36384 -130.22112) (xy 245.317998 -130.191657) (xy 245.276816 -130.15597) (xy 245.241131 -130.114786)
			(xy 245.21167 -130.068942) (xy 245.189033 -130.019373) (xy 245.173681 -129.967086) (xy 245.165926 -129.913147)
			(xy 242.804188 -129.913147) (xy 242.804188 -130.721608) (xy 242.803934 -130.736594) (xy 242.80404 -130.747133)
			(xy 242.811717 -130.766736) (xy 242.826612 -130.781615) (xy 242.846224 -130.789269) (xy 242.856766 -130.789426)
			(xy 242.871752 -130.789172) (xy 242.899008 -130.789632) (xy 242.952965 -130.797383) (xy 243.00527 -130.812735)
			(xy 243.054857 -130.835374) (xy 243.100718 -130.86484) (xy 243.141918 -130.900534) (xy 243.177619 -130.941728)
			(xy 243.207093 -130.987583) (xy 243.229742 -131.037166) (xy 243.245103 -131.089469) (xy 243.252864 -131.143424)
			(xy 243.25326 -131.17068) (xy 243.252642 -131.201384) (xy 243.242812 -131.262002) (xy 243.233702 -131.29133)
			(xy 243.229763 -131.304527) (xy 243.228314 -131.332017) (xy 243.234259 -131.358897) (xy 243.247168 -131.383212)
			(xy 243.266101 -131.403196) (xy 243.289685 -131.417397) (xy 243.316204 -131.424784) (xy 243.329968 -131.425188)
			(xy 257.1496 -131.425188) (xy 259.840476 -128.734058) (xy 259.85846 -128.716704) (xy 259.898873 -128.687303)
			(xy 259.943391 -128.664595) (xy 259.990918 -128.649142) (xy 260.040278 -128.641324) (xy 260.065266 -128.64084)
			(xy 260.970014 -128.64084) (xy 260.994997 -128.641352) (xy 261.044344 -128.649205) (xy 261.052982 -128.652016)
			(xy 263.344658 -128.652016) (xy 263.348729 -128.596394) (xy 263.360855 -128.541957) (xy 263.380778 -128.489866)
			(xy 263.408074 -128.441231) (xy 263.44216 -128.397088) (xy 263.482309 -128.358379) (xy 263.527667 -128.325928)
			(xy 263.577267 -128.300427) (xy 263.630051 -128.28242) (xy 263.684894 -128.27229) (xy 263.740628 -128.270253)
			(xy 263.796065 -128.276353) (xy 263.850022 -128.290459) (xy 263.901351 -128.312271) (xy 263.948957 -128.341325)
			(xy 263.991825 -128.377) (xy 264.029042 -128.418537) (xy 264.059815 -128.46505) (xy 264.083487 -128.515547)
			(xy 264.099555 -128.568954) (xy 264.107675 -128.62413) (xy 264.108184 -128.652016) (xy 264.107675 -128.679902)
			(xy 264.099555 -128.735078) (xy 264.083487 -128.788485) (xy 264.059815 -128.838982) (xy 264.029042 -128.885495)
			(xy 263.991825 -128.927032) (xy 263.948957 -128.962707) (xy 263.901351 -128.991761) (xy 263.850022 -129.013573)
			(xy 263.796065 -129.027679) (xy 263.740628 -129.033779) (xy 263.684894 -129.031742) (xy 263.630051 -129.021612)
			(xy 263.577267 -129.003605) (xy 263.527667 -128.978104) (xy 263.482309 -128.945653) (xy 263.44216 -128.906944)
			(xy 263.408074 -128.862801) (xy 263.380778 -128.814166) (xy 263.360855 -128.762075) (xy 263.348729 -128.707638)
			(xy 263.344658 -128.652016) (xy 261.052982 -128.652016) (xy 261.091858 -128.664668) (xy 261.136374 -128.687362)
			(xy 261.1768 -128.71673) (xy 261.194804 -128.734058) (xy 261.711948 -129.251202) (xy 261.722517 -129.261067)
			(xy 261.747847 -129.274976) (xy 261.776056 -129.281242) (xy 261.804892 -129.279365) (xy 261.832052 -129.269495)
			(xy 261.855365 -129.25242) (xy 261.864602 -129.241296) (xy 261.882769 -129.218469) (xy 261.924865 -129.17808)
			(xy 261.97262 -129.144572) (xy 262.024921 -129.118728) (xy 262.080547 -129.101149) (xy 262.138201 -129.092246)
			(xy 262.16737 -129.09169) (xy 262.194624 -129.092151) (xy 262.248579 -129.099905) (xy 262.300881 -129.115258)
			(xy 262.350465 -129.137899) (xy 262.396322 -129.167367) (xy 262.437518 -129.20306) (xy 262.473215 -129.244254)
			(xy 262.502686 -129.290109) (xy 262.525331 -129.339691) (xy 262.540689 -129.391992) (xy 262.548447 -129.445946)
			(xy 262.548447 -129.500454) (xy 262.540689 -129.554408) (xy 262.525331 -129.606709) (xy 262.502686 -129.656291)
			(xy 262.473215 -129.702146) (xy 262.437518 -129.74334) (xy 262.396322 -129.779033) (xy 262.350465 -129.808501)
			(xy 262.300881 -129.831142) (xy 262.248579 -129.846495) (xy 262.194624 -129.854249) (xy 262.16737 -129.854706)
			(xy 262.143113 -129.854325) (xy 262.094992 -129.848164) (xy 262.048041 -129.835946) (xy 262.025384 -129.827274)
			(xy 262.01205 -129.822467) (xy 261.983862 -129.819623) (xy 261.955976 -129.82463) (xy 261.930538 -129.837105)
			(xy 261.909505 -129.856087) (xy 261.894494 -129.880115) (xy 261.886661 -129.907343) (xy 261.886192 -129.921508)
			(xy 261.886192 -130.51155) (xy 261.885677 -130.536532) (xy 261.87782 -130.585876) (xy 261.862354 -130.633388)
			(xy 261.839659 -130.677902) (xy 261.810291 -130.718326) (xy 261.792974 -130.73634) (xy 260.802628 -131.726686)
			(xy 260.802628 -131.77393) (xy 260.809994 -131.786122) (xy 260.823306 -131.808693) (xy 260.844293 -131.856709)
			(xy 260.858506 -131.907147) (xy 260.865675 -131.959057) (xy 260.866128 -131.985258) (xy 260.865642 -132.012509)
			(xy 260.857886 -132.066457) (xy 260.851523 -132.088128) (xy 261.039862 -132.088128) (xy 261.043933 -132.032506)
			(xy 261.056059 -131.978069) (xy 261.075982 -131.925978) (xy 261.103278 -131.877343) (xy 261.137364 -131.8332)
			(xy 261.177513 -131.794491) (xy 261.222871 -131.76204) (xy 261.272471 -131.736539) (xy 261.325255 -131.718532)
			(xy 261.380098 -131.708402) (xy 261.435832 -131.706365) (xy 261.491269 -131.712465) (xy 261.545226 -131.726571)
			(xy 261.596555 -131.748383) (xy 261.644161 -131.777437) (xy 261.687029 -131.813112) (xy 261.724246 -131.854649)
			(xy 261.755019 -131.901162) (xy 261.778691 -131.951659) (xy 261.794759 -132.005066) (xy 261.800254 -132.042408)
			(xy 262.010142 -132.042408) (xy 262.014213 -131.986786) (xy 262.026339 -131.932349) (xy 262.046262 -131.880258)
			(xy 262.073558 -131.831623) (xy 262.107644 -131.78748) (xy 262.147793 -131.748771) (xy 262.193151 -131.71632)
			(xy 262.242751 -131.690819) (xy 262.295535 -131.672812) (xy 262.350378 -131.662682) (xy 262.406112 -131.660645)
			(xy 262.461549 -131.666745) (xy 262.504287 -131.677918) (xy 263.303002 -131.677918) (xy 263.307073 -131.622296)
			(xy 263.319199 -131.567859) (xy 263.339122 -131.515768) (xy 263.366418 -131.467133) (xy 263.400504 -131.42299)
			(xy 263.440653 -131.384281) (xy 263.486011 -131.35183) (xy 263.535611 -131.326329) (xy 263.588395 -131.308322)
			(xy 263.643238 -131.298192) (xy 263.698972 -131.296155) (xy 263.754409 -131.302255) (xy 263.808366 -131.316361)
			(xy 263.859695 -131.338173) (xy 263.907301 -131.367227) (xy 263.950169 -131.402902) (xy 263.987386 -131.444439)
			(xy 264.018159 -131.490952) (xy 264.041831 -131.541449) (xy 264.057899 -131.594856) (xy 264.066019 -131.650032)
			(xy 264.066528 -131.677918) (xy 264.066019 -131.705804) (xy 264.057899 -131.76098) (xy 264.041831 -131.814387)
			(xy 264.018159 -131.864884) (xy 263.987386 -131.911397) (xy 263.950169 -131.952934) (xy 263.907301 -131.988609)
			(xy 263.859695 -132.017663) (xy 263.808366 -132.039475) (xy 263.754409 -132.053581) (xy 263.698972 -132.059681)
			(xy 263.643238 -132.057644) (xy 263.588395 -132.047514) (xy 263.535611 -132.029507) (xy 263.486011 -132.004006)
			(xy 263.440653 -131.971555) (xy 263.400504 -131.932846) (xy 263.366418 -131.888703) (xy 263.339122 -131.840068)
			(xy 263.319199 -131.787977) (xy 263.307073 -131.73354) (xy 263.303002 -131.677918) (xy 262.504287 -131.677918)
			(xy 262.515506 -131.680851) (xy 262.566835 -131.702663) (xy 262.614441 -131.731717) (xy 262.657309 -131.767392)
			(xy 262.694526 -131.808929) (xy 262.725299 -131.855442) (xy 262.748971 -131.905939) (xy 262.765039 -131.959346)
			(xy 262.773159 -132.014522) (xy 262.773668 -132.042408) (xy 262.773159 -132.070294) (xy 262.765039 -132.12547)
			(xy 262.748971 -132.178877) (xy 262.725299 -132.229374) (xy 262.694526 -132.275887) (xy 262.657309 -132.317424)
			(xy 262.614441 -132.353099) (xy 262.566835 -132.382153) (xy 262.515506 -132.403965) (xy 262.461549 -132.418071)
			(xy 262.406112 -132.424171) (xy 262.350378 -132.422134) (xy 262.295535 -132.412004) (xy 262.242751 -132.393997)
			(xy 262.193151 -132.368496) (xy 262.147793 -132.336045) (xy 262.107644 -132.297336) (xy 262.073558 -132.253193)
			(xy 262.046262 -132.204558) (xy 262.026339 -132.152467) (xy 262.014213 -132.09803) (xy 262.010142 -132.042408)
			(xy 261.800254 -132.042408) (xy 261.802879 -132.060242) (xy 261.803388 -132.088128) (xy 261.802879 -132.116014)
			(xy 261.794759 -132.17119) (xy 261.778691 -132.224597) (xy 261.755019 -132.275094) (xy 261.724246 -132.321607)
			(xy 261.687029 -132.363144) (xy 261.644161 -132.398819) (xy 261.596555 -132.427873) (xy 261.545226 -132.449685)
			(xy 261.491269 -132.463791) (xy 261.435832 -132.469891) (xy 261.380098 -132.467854) (xy 261.325255 -132.457724)
			(xy 261.272471 -132.439717) (xy 261.222871 -132.414216) (xy 261.177513 -132.381765) (xy 261.137364 -132.343056)
			(xy 261.103278 -132.298913) (xy 261.075982 -132.250278) (xy 261.056059 -132.198187) (xy 261.043933 -132.14375)
			(xy 261.039862 -132.088128) (xy 260.851523 -132.088128) (xy 260.842531 -132.118752) (xy 260.819889 -132.168329)
			(xy 260.790423 -132.214179) (xy 260.754732 -132.25537) (xy 260.713541 -132.291061) (xy 260.667691 -132.320527)
			(xy 260.618114 -132.343169) (xy 260.565819 -132.358524) (xy 260.511871 -132.36628) (xy 260.457369 -132.36628)
			(xy 260.403421 -132.358524) (xy 260.351126 -132.343169) (xy 260.301549 -132.320527) (xy 260.255699 -132.291061)
			(xy 260.214508 -132.25537) (xy 260.178817 -132.214179) (xy 260.149351 -132.168329) (xy 260.126709 -132.118752)
			(xy 260.111354 -132.066457) (xy 260.103598 -132.012509) (xy 260.103112 -131.985258) (xy 260.103589 -131.957295)
			(xy 260.111723 -131.901963) (xy 260.12784 -131.848409) (xy 260.151596 -131.797779) (xy 260.166612 -131.774184)
			(xy 260.166612 -131.595114) (xy 260.16713 -131.570133) (xy 260.174991 -131.520792) (xy 260.190462 -131.473284)
			(xy 260.21316 -131.428774) (xy 260.242531 -131.388355) (xy 260.25983 -131.370324) (xy 261.250176 -130.379978)
			(xy 261.250176 -130.128518) (xy 261.249669 -130.113286) (xy 261.240687 -130.084177) (xy 261.223518 -130.059013)
			(xy 261.199689 -130.040034) (xy 261.171321 -130.028929) (xy 261.140941 -130.026687) (xy 261.11125 -130.033507)
			(xy 261.097776 -130.040634) (xy 261.075877 -130.052886) (xy 261.029551 -130.072172) (xy 260.981097 -130.08522)
			(xy 260.93135 -130.091805) (xy 260.90626 -130.092196) (xy 260.878592 -130.091708) (xy 260.823835 -130.083724)
			(xy 260.770805 -130.067915) (xy 260.720615 -130.044612) (xy 260.674317 -130.014304) (xy 260.632883 -129.977626)
			(xy 260.59718 -129.935349) (xy 260.582156 -129.91211) (xy 260.57353 -129.899292) (xy 260.550112 -129.879162)
			(xy 260.521747 -129.86695) (xy 260.49103 -129.863773) (xy 260.460767 -129.86992) (xy 260.433724 -129.884831)
			(xy 260.422644 -129.8956) (xy 260.403431 -129.914989) (xy 260.360446 -129.94863) (xy 260.313109 -129.975808)
			(xy 260.262384 -129.995968) (xy 260.235954 -130.002788) (xy 260.221984 -130.006344) (xy 257.98653 -132.241798)
			(xy 258.288536 -132.543804) (xy 258.79755 -132.543804) (xy 258.801621 -132.488182) (xy 258.813747 -132.433745)
			(xy 258.83367 -132.381654) (xy 258.860966 -132.333019) (xy 258.895052 -132.288876) (xy 258.935201 -132.250167)
			(xy 258.980559 -132.217716) (xy 259.030159 -132.192215) (xy 259.082943 -132.174208) (xy 259.137786 -132.164078)
			(xy 259.19352 -132.162041) (xy 259.248957 -132.168141) (xy 259.302914 -132.182247) (xy 259.354243 -132.204059)
			(xy 259.401849 -132.233113) (xy 259.444717 -132.268788) (xy 259.481934 -132.310325) (xy 259.512707 -132.356838)
			(xy 259.536379 -132.407335) (xy 259.552447 -132.460742) (xy 259.560567 -132.515918) (xy 259.561076 -132.543804)
			(xy 259.560567 -132.57169) (xy 259.552447 -132.626866) (xy 259.536379 -132.680273) (xy 259.512707 -132.73077)
			(xy 259.481934 -132.777283) (xy 259.444717 -132.81882) (xy 259.401849 -132.854495) (xy 259.354243 -132.883549)
			(xy 259.302914 -132.905361) (xy 259.248957 -132.919467) (xy 259.19352 -132.925567) (xy 259.137786 -132.92353)
			(xy 259.082943 -132.9134) (xy 259.030159 -132.895393) (xy 258.980559 -132.869892) (xy 258.935201 -132.837441)
			(xy 258.895052 -132.798732) (xy 258.860966 -132.754589) (xy 258.83367 -132.705954) (xy 258.813747 -132.653863)
			(xy 258.801621 -132.599426) (xy 258.79755 -132.543804) (xy 258.288536 -132.543804) (xy 259.00888 -133.264148)
			(xy 266.04468 -133.264148)
		)
		(stroke
			(width 0)
			(type solid)
		)
		(fill yes)
		(layer "In13.Cu")
		(net "P3V3")
	)
	(gr_poly
		(pts
			(xy 410.18968 -134.681976) (xy 410.190211 -134.696974) (xy 410.198921 -134.725676) (xy 410.215596 -134.750608)
			(xy 410.238797 -134.769619) (xy 410.266522 -134.781066) (xy 410.296377 -134.783962) (xy 410.325785 -134.778057)
			(xy 410.352207 -134.763861) (xy 410.363162 -134.753604) (xy 414.996884 -130.120136) (xy 415.003234 -130.113786)
			(xy 415.104834 -130.012186) (xy 415.248344 -130.012186) (xy 415.257488 -130.011932) (xy 424.350434 -130.011932)
			(xy 424.965876 -129.396744) (xy 424.97248 -129.39014) (xy 425.073826 -129.288794) (xy 425.214796 -129.288794)
			(xy 425.22648 -129.28854) (xy 431.673 -129.28854) (xy 431.684684 -129.288794) (xy 431.825654 -129.288794)
			(xy 431.927 -129.39014) (xy 431.933604 -129.396744) (xy 432.022504 -129.48539) (xy 432.054254 -129.51714)
			(xy 434.415946 -129.51714) (xy 437.419496 -126.513844) (xy 437.425846 -126.507494) (xy 437.527446 -126.405894)
			(xy 437.668416 -126.405894) (xy 437.6801 -126.40564) (xy 442.607446 -126.40564) (xy 443.526672 -125.486414)
			(xy 443.526672 -118.456202) (xy 443.475618 -118.404894) (xy 443.454316 -118.392092) (xy 443.41491 -118.361807)
			(xy 443.379769 -118.326663) (xy 443.349488 -118.287254) (xy 443.33668 -118.265956) (xy 443.298326 -118.227602)
			(xy 443.298326 -118.1735) (xy 443.292276 -118.149312) (xy 443.28578 -118.099878) (xy 443.285372 -118.074948)
			(xy 443.285725 -118.051528) (xy 443.291452 -118.005041) (xy 443.296802 -117.982238) (xy 443.298326 -117.976142)
			(xy 443.298326 -117.922294) (xy 443.336426 -117.884194) (xy 443.339728 -117.878606) (xy 443.345917 -117.868464)
			(xy 443.359389 -117.848892) (xy 443.366652 -117.83949) (xy 443.388085 -117.813292) (xy 443.438551 -117.768195)
			(xy 443.466982 -117.749828) (xy 443.478848 -117.740938) (xy 443.497276 -117.717728) (xy 443.508277 -117.69021)
			(xy 443.510927 -117.660693) (xy 443.505005 -117.631655) (xy 443.491006 -117.605533) (xy 443.480952 -117.594634)
			(xy 442.3283 -116.441982) (xy 442.317316 -116.431793) (xy 442.290881 -116.417723) (xy 442.261502 -116.411919)
			(xy 442.231703 -116.414881) (xy 442.204041 -116.426353) (xy 442.180892 -116.44535) (xy 442.164243 -116.470242)
			(xy 442.155525 -116.498891) (xy 442.155072 -116.513864) (xy 442.155072 -122.060716) (xy 442.156596 -122.066812)
			(xy 442.161827 -122.089373) (xy 442.167428 -122.135349) (xy 442.167772 -122.158506) (xy 442.167286 -122.185757)
			(xy 442.15953 -122.239705) (xy 442.144175 -122.292) (xy 442.121533 -122.341577) (xy 442.092067 -122.387427)
			(xy 442.056376 -122.428618) (xy 442.015185 -122.464309) (xy 441.969335 -122.493775) (xy 441.919758 -122.516417)
			(xy 441.867463 -122.531772) (xy 441.813515 -122.539528) (xy 441.759013 -122.539528) (xy 441.705065 -122.531772)
			(xy 441.65277 -122.516417) (xy 441.603193 -122.493775) (xy 441.557343 -122.464309) (xy 441.516152 -122.428618)
			(xy 441.480461 -122.387427) (xy 441.450995 -122.341577) (xy 441.428353 -122.292) (xy 441.412998 -122.239705)
			(xy 441.405242 -122.185757) (xy 441.404756 -122.158506) (xy 441.405096 -122.135348) (xy 441.410698 -122.089373)
			(xy 441.415932 -122.066812) (xy 441.417456 -122.060716) (xy 441.417456 -116.142262) (xy 440.245754 -114.97056)
			(xy 437.632856 -114.97056) (xy 437.618958 -114.971038) (xy 437.592194 -114.978546) (xy 437.568446 -114.992993)
			(xy 437.549474 -115.013308) (xy 437.536684 -115.037988) (xy 437.531022 -115.065202) (xy 437.532909 -115.092935)
			(xy 437.537098 -115.106196) (xy 437.547135 -115.136198) (xy 437.557992 -115.198519) (xy 437.558688 -115.230148)
			(xy 437.558688 -116.32565) (xy 437.559958 -116.331746) (xy 437.56528 -116.354425) (xy 437.571012 -116.400656)
			(xy 437.571388 -116.423948) (xy 437.570902 -116.451199) (xy 437.563146 -116.505147) (xy 437.547791 -116.557442)
			(xy 437.525149 -116.607019) (xy 437.495683 -116.652869) (xy 437.459992 -116.69406) (xy 437.418801 -116.729751)
			(xy 437.372951 -116.759217) (xy 437.323374 -116.781859) (xy 437.271079 -116.797214) (xy 437.217131 -116.80497)
			(xy 437.162629 -116.80497) (xy 437.108681 -116.797214) (xy 437.056386 -116.781859) (xy 437.006809 -116.759217)
			(xy 436.960959 -116.729751) (xy 436.919768 -116.69406) (xy 436.884077 -116.652869) (xy 436.854611 -116.607019)
			(xy 436.831969 -116.557442) (xy 436.816614 -116.505147) (xy 436.808858 -116.451199) (xy 436.808372 -116.423948)
			(xy 436.808753 -116.400656) (xy 436.814486 -116.354426) (xy 436.819802 -116.331746) (xy 436.821072 -116.32565)
			(xy 436.821072 -115.382802) (xy 436.40883 -114.97056) (xy 428.437548 -114.97056) (xy 428.090584 -115.317524)
			(xy 428.080399 -115.328507) (xy 428.066336 -115.354938) (xy 428.060537 -115.38431) (xy 428.063501 -115.414102)
			(xy 428.074973 -115.441757) (xy 428.093967 -115.464899) (xy 428.118854 -115.481542) (xy 428.147497 -115.490258)
			(xy 428.162466 -115.490752) (xy 429.206152 -115.490752) (xy 429.231134 -115.491267) (xy 429.280477 -115.499125)
			(xy 429.327987 -115.514593) (xy 429.372499 -115.537291) (xy 429.41292 -115.566662) (xy 429.430942 -115.58397)
			(xy 429.652938 -115.80622) (xy 429.663377 -115.815973) (xy 429.688374 -115.829779) (xy 429.716216 -115.836131)
			(xy 429.744727 -115.83453) (xy 429.771683 -115.825103) (xy 429.794977 -115.808585) (xy 429.812792 -115.786267)
			(xy 429.823736 -115.759891) (xy 429.825912 -115.745768) (xy 429.829562 -115.718197) (xy 429.843819 -115.664442)
			(xy 429.865728 -115.613326) (xy 429.894827 -115.565932) (xy 429.930498 -115.523265) (xy 429.971985 -115.486229)
			(xy 430.018409 -115.455608) (xy 430.068787 -115.432051) (xy 430.122051 -115.416058) (xy 430.177073 -115.407966)
			(xy 430.20488 -115.40744) (xy 430.232133 -115.407902) (xy 430.286083 -115.415657) (xy 430.338381 -115.431012)
			(xy 430.38796 -115.453654) (xy 430.433812 -115.483122) (xy 430.475003 -115.518816) (xy 430.510695 -115.56001)
			(xy 430.54016 -115.605864) (xy 430.562798 -115.655446) (xy 430.578149 -115.707744) (xy 430.5859 -115.761695)
			(xy 430.586388 -115.788948) (xy 430.585885 -115.816203) (xy 430.578094 -115.870155) (xy 430.562707 -115.922449)
			(xy 430.540037 -115.972023) (xy 430.525682 -115.995196) (xy 430.518692 -116.006887) (xy 430.51056 -116.032874)
			(xy 430.509586 -116.060085) (xy 430.515839 -116.086587) (xy 430.528873 -116.110493) (xy 430.547763 -116.130105)
			(xy 430.571164 -116.144026) (xy 430.597412 -116.151268) (xy 430.611026 -116.15166) (xy 430.687734 -116.15166)
			(xy 430.701331 -116.151184) (xy 430.727541 -116.14392) (xy 430.750904 -116.129997) (xy 430.769764 -116.110402)
			(xy 430.782785 -116.086524) (xy 430.789042 -116.060056) (xy 430.788093 -116.032875) (xy 430.780004 -116.006909)
			(xy 430.773078 -115.995196) (xy 430.758715 -115.972026) (xy 430.736036 -115.922455) (xy 430.720648 -115.870159)
			(xy 430.712864 -115.816204) (xy 430.712372 -115.788948) (xy 430.712858 -115.761697) (xy 430.720614 -115.707749)
			(xy 430.735969 -115.655454) (xy 430.758611 -115.605877) (xy 430.788077 -115.560027) (xy 430.823768 -115.518836)
			(xy 430.864959 -115.483145) (xy 430.910809 -115.453679) (xy 430.960386 -115.431037) (xy 431.012681 -115.415682)
			(xy 431.066629 -115.407926) (xy 431.121131 -115.407926) (xy 431.175079 -115.415682) (xy 431.227374 -115.431037)
			(xy 431.276951 -115.453679) (xy 431.322801 -115.483145) (xy 431.363992 -115.518836) (xy 431.399683 -115.560027)
			(xy 431.429149 -115.605877) (xy 431.451791 -115.655454) (xy 431.467146 -115.707749) (xy 431.474902 -115.761697)
			(xy 431.475388 -115.788948) (xy 431.474885 -115.816203) (xy 431.467094 -115.870155) (xy 431.451707 -115.922449)
			(xy 431.429037 -115.972023) (xy 431.414682 -115.995196) (xy 431.407692 -116.006887) (xy 431.39956 -116.032874)
			(xy 431.398586 -116.060085) (xy 431.404839 -116.086587) (xy 431.417873 -116.110493) (xy 431.436763 -116.130105)
			(xy 431.460164 -116.144026) (xy 431.486412 -116.151268) (xy 431.500026 -116.15166) (xy 433.869084 -116.15166)
			(xy 433.892607 -116.136647) (xy 433.943115 -116.11292) (xy 433.996543 -116.096813) (xy 434.051748 -116.088668)
			(xy 434.07965 -116.08816) (xy 434.080158 -116.08816) (xy 434.107415 -116.08862) (xy 434.161375 -116.096373)
			(xy 434.213683 -116.111727) (xy 434.263272 -116.134369) (xy 434.309134 -116.163838) (xy 434.350336 -116.199535)
			(xy 434.386037 -116.240732) (xy 434.415511 -116.286591) (xy 434.438159 -116.336178) (xy 434.453518 -116.388484)
			(xy 434.461277 -116.442443) (xy 434.461277 -116.496957) (xy 434.453518 -116.550916) (xy 434.438159 -116.603222)
			(xy 434.415511 -116.652809) (xy 434.386037 -116.698668) (xy 434.350336 -116.739865) (xy 434.309134 -116.775562)
			(xy 434.263272 -116.805031) (xy 434.213683 -116.827673) (xy 434.161375 -116.843027) (xy 434.107415 -116.85078)
			(xy 434.080158 -116.851176) (xy 434.07965 -116.851176) (xy 434.051753 -116.850642) (xy 433.996558 -116.842472)
			(xy 433.94314 -116.826356) (xy 433.892636 -116.802638) (xy 433.869084 -116.787676) (xy 433.487576 -116.787676)
			(xy 433.477554 -116.788083) (xy 433.45903 -116.795737) (xy 433.444853 -116.809905) (xy 433.437189 -116.828425)
			(xy 433.437207 -116.848468) (xy 433.444905 -116.866973) (xy 433.451762 -116.87429) (xy 433.549806 -116.972588)
			(xy 434.415946 -116.972588) (xy 435.032404 -116.35613) (xy 435.032404 -116.323872) (xy 435.017326 -116.300303)
			(xy 434.993493 -116.249683) (xy 434.977314 -116.196123) (xy 434.969137 -116.140773) (xy 434.96865 -116.112798)
			(xy 434.969136 -116.085547) (xy 434.976892 -116.031599) (xy 434.992247 -115.979304) (xy 435.014889 -115.929727)
			(xy 435.044355 -115.883877) (xy 435.080046 -115.842686) (xy 435.121237 -115.806995) (xy 435.167087 -115.777529)
			(xy 435.216664 -115.754887) (xy 435.268959 -115.739532) (xy 435.322907 -115.731776) (xy 435.377409 -115.731776)
			(xy 435.431357 -115.739532) (xy 435.483652 -115.754887) (xy 435.533229 -115.777529) (xy 435.579079 -115.806995)
			(xy 435.62027 -115.842686) (xy 435.655961 -115.883877) (xy 435.685427 -115.929727) (xy 435.708069 -115.979304)
			(xy 435.723424 -116.031599) (xy 435.73118 -116.085547) (xy 435.731666 -116.112798) (xy 435.731232 -116.139)
			(xy 435.724057 -116.190911) (xy 435.709842 -116.24135) (xy 435.688854 -116.289368) (xy 435.675532 -116.311934)
			(xy 435.667912 -116.324126) (xy 435.667912 -116.487956) (xy 435.667452 -116.512909) (xy 435.659651 -116.562201)
			(xy 435.644236 -116.609666) (xy 435.621585 -116.654134) (xy 435.592257 -116.694512) (xy 435.574948 -116.712492)
			(xy 434.772308 -117.515132) (xy 434.75431 -117.532416) (xy 434.713926 -117.561723) (xy 434.66946 -117.58436)
			(xy 434.622003 -117.599772) (xy 434.57272 -117.60758) (xy 434.547772 -117.608096) (xy 433.41798 -117.608096)
			(xy 433.393026 -117.607638) (xy 433.343732 -117.599843) (xy 433.296264 -117.584431) (xy 433.251792 -117.561782)
			(xy 433.21141 -117.532455) (xy 433.193444 -117.515132) (xy 432.915568 -117.237256) (xy 429.68926 -117.237256)
			(xy 429.664278 -117.236742) (xy 429.614933 -117.228886) (xy 429.567422 -117.21342) (xy 429.522908 -117.190723)
			(xy 429.482486 -117.161353) (xy 429.46447 -117.144038) (xy 428.90948 -116.589048) (xy 426.81906 -116.589048)
			(xy 425.798472 -117.60962) (xy 427.592742 -117.60962) (xy 427.596813 -117.553998) (xy 427.608939 -117.499561)
			(xy 427.628862 -117.44747) (xy 427.656158 -117.398835) (xy 427.690244 -117.354692) (xy 427.730393 -117.315983)
			(xy 427.775751 -117.283532) (xy 427.825351 -117.258031) (xy 427.878135 -117.240024) (xy 427.932978 -117.229894)
			(xy 427.988712 -117.227857) (xy 428.044149 -117.233957) (xy 428.098106 -117.248063) (xy 428.149435 -117.269875)
			(xy 428.197041 -117.298929) (xy 428.239909 -117.334604) (xy 428.277126 -117.376141) (xy 428.307899 -117.422654)
			(xy 428.331571 -117.473151) (xy 428.342826 -117.51056) (xy 428.648112 -117.51056) (xy 428.652183 -117.454938)
			(xy 428.664309 -117.400501) (xy 428.684232 -117.34841) (xy 428.711528 -117.299775) (xy 428.745614 -117.255632)
			(xy 428.785763 -117.216923) (xy 428.831121 -117.184472) (xy 428.880721 -117.158971) (xy 428.933505 -117.140964)
			(xy 428.988348 -117.130834) (xy 429.044082 -117.128797) (xy 429.099519 -117.134897) (xy 429.153476 -117.149003)
			(xy 429.204805 -117.170815) (xy 429.252411 -117.199869) (xy 429.295279 -117.235544) (xy 429.332496 -117.277081)
			(xy 429.363269 -117.323594) (xy 429.386941 -117.374091) (xy 429.403009 -117.427498) (xy 429.411129 -117.482674)
			(xy 429.411638 -117.51056) (xy 429.411129 -117.538446) (xy 429.403009 -117.593622) (xy 429.386941 -117.647029)
			(xy 429.363269 -117.697526) (xy 429.332496 -117.744039) (xy 429.295279 -117.785576) (xy 429.252411 -117.821251)
			(xy 429.204805 -117.850305) (xy 429.153476 -117.872117) (xy 429.099519 -117.886223) (xy 429.044082 -117.892323)
			(xy 428.988348 -117.890286) (xy 428.933505 -117.880156) (xy 428.880721 -117.862149) (xy 428.831121 -117.836648)
			(xy 428.785763 -117.804197) (xy 428.745614 -117.765488) (xy 428.711528 -117.721345) (xy 428.684232 -117.67271)
			(xy 428.664309 -117.620619) (xy 428.652183 -117.566182) (xy 428.648112 -117.51056) (xy 428.342826 -117.51056)
			(xy 428.347639 -117.526558) (xy 428.355759 -117.581734) (xy 428.356268 -117.60962) (xy 428.355759 -117.637506)
			(xy 428.347639 -117.692682) (xy 428.331571 -117.746089) (xy 428.307899 -117.796586) (xy 428.277126 -117.843099)
			(xy 428.239909 -117.884636) (xy 428.197041 -117.920311) (xy 428.149435 -117.949365) (xy 428.098106 -117.971177)
			(xy 428.044149 -117.985283) (xy 427.988712 -117.991383) (xy 427.932978 -117.989346) (xy 427.878135 -117.979216)
			(xy 427.825351 -117.961209) (xy 427.775751 -117.935708) (xy 427.730393 -117.903257) (xy 427.690244 -117.864548)
			(xy 427.656158 -117.820405) (xy 427.628862 -117.77177) (xy 427.608939 -117.719679) (xy 427.596813 -117.665242)
			(xy 427.592742 -117.60962) (xy 425.798472 -117.60962) (xy 424.353444 -119.054626) (xy 431.95824 -119.054626)
			(xy 431.962311 -118.999004) (xy 431.974437 -118.944567) (xy 431.99436 -118.892476) (xy 432.021656 -118.843841)
			(xy 432.055742 -118.799698) (xy 432.095891 -118.760989) (xy 432.141249 -118.728538) (xy 432.190849 -118.703037)
			(xy 432.243633 -118.68503) (xy 432.298476 -118.6749) (xy 432.35421 -118.672863) (xy 432.409647 -118.678963)
			(xy 432.463604 -118.693069) (xy 432.514933 -118.714881) (xy 432.562539 -118.743935) (xy 432.605407 -118.77961)
			(xy 432.642624 -118.821147) (xy 432.673397 -118.86766) (xy 432.697069 -118.918157) (xy 432.713137 -118.971564)
			(xy 432.721257 -119.02674) (xy 432.721766 -119.054626) (xy 432.721257 -119.082512) (xy 432.713137 -119.137688)
			(xy 432.697069 -119.191095) (xy 432.696269 -119.192802) (xy 436.989726 -119.192802) (xy 436.993797 -119.13718)
			(xy 437.005923 -119.082743) (xy 437.025846 -119.030652) (xy 437.053142 -118.982017) (xy 437.087228 -118.937874)
			(xy 437.127377 -118.899165) (xy 437.172735 -118.866714) (xy 437.222335 -118.841213) (xy 437.275119 -118.823206)
			(xy 437.329962 -118.813076) (xy 437.385696 -118.811039) (xy 437.441133 -118.817139) (xy 437.49509 -118.831245)
			(xy 437.546419 -118.853057) (xy 437.594025 -118.882111) (xy 437.636893 -118.917786) (xy 437.67411 -118.959323)
			(xy 437.704883 -119.005836) (xy 437.728555 -119.056333) (xy 437.744623 -119.10974) (xy 437.752743 -119.164916)
			(xy 437.753252 -119.192802) (xy 437.752743 -119.220688) (xy 437.744623 -119.275864) (xy 437.728555 -119.329271)
			(xy 437.704883 -119.379768) (xy 437.67411 -119.426281) (xy 437.636893 -119.467818) (xy 437.594025 -119.503493)
			(xy 437.546419 -119.532547) (xy 437.49509 -119.554359) (xy 437.441133 -119.568465) (xy 437.385696 -119.574565)
			(xy 437.329962 -119.572528) (xy 437.275119 -119.562398) (xy 437.222335 -119.544391) (xy 437.172735 -119.51889)
			(xy 437.127377 -119.486439) (xy 437.087228 -119.44773) (xy 437.053142 -119.403587) (xy 437.025846 -119.354952)
			(xy 437.005923 -119.302861) (xy 436.993797 -119.248424) (xy 436.989726 -119.192802) (xy 432.696269 -119.192802)
			(xy 432.673397 -119.241592) (xy 432.642624 -119.288105) (xy 432.605407 -119.329642) (xy 432.562539 -119.365317)
			(xy 432.514933 -119.394371) (xy 432.463604 -119.416183) (xy 432.409647 -119.430289) (xy 432.35421 -119.436389)
			(xy 432.298476 -119.434352) (xy 432.243633 -119.424222) (xy 432.190849 -119.406215) (xy 432.141249 -119.380714)
			(xy 432.095891 -119.348263) (xy 432.055742 -119.309554) (xy 432.021656 -119.265411) (xy 431.99436 -119.216776)
			(xy 431.974437 -119.164685) (xy 431.962311 -119.110248) (xy 431.95824 -119.054626) (xy 424.353444 -119.054626)
			(xy 423.823846 -119.584216) (xy 433.69814 -119.584216) (xy 433.702211 -119.528594) (xy 433.714337 -119.474157)
			(xy 433.73426 -119.422066) (xy 433.761556 -119.373431) (xy 433.795642 -119.329288) (xy 433.835791 -119.290579)
			(xy 433.881149 -119.258128) (xy 433.930749 -119.232627) (xy 433.983533 -119.21462) (xy 434.038376 -119.20449)
			(xy 434.09411 -119.202453) (xy 434.149547 -119.208553) (xy 434.203504 -119.222659) (xy 434.254833 -119.244471)
			(xy 434.302439 -119.273525) (xy 434.345307 -119.3092) (xy 434.382524 -119.350737) (xy 434.413297 -119.39725)
			(xy 434.436969 -119.447747) (xy 434.453037 -119.501154) (xy 434.461157 -119.55633) (xy 434.461666 -119.584216)
			(xy 434.96814 -119.584216) (xy 434.972211 -119.528594) (xy 434.984337 -119.474157) (xy 435.00426 -119.422066)
			(xy 435.031556 -119.373431) (xy 435.065642 -119.329288) (xy 435.105791 -119.290579) (xy 435.151149 -119.258128)
			(xy 435.200749 -119.232627) (xy 435.253533 -119.21462) (xy 435.308376 -119.20449) (xy 435.36411 -119.202453)
			(xy 435.419547 -119.208553) (xy 435.473504 -119.222659) (xy 435.524833 -119.244471) (xy 435.572439 -119.273525)
			(xy 435.615307 -119.3092) (xy 435.652524 -119.350737) (xy 435.683297 -119.39725) (xy 435.706969 -119.447747)
			(xy 435.723037 -119.501154) (xy 435.731157 -119.55633) (xy 435.731666 -119.584216) (xy 435.731157 -119.612102)
			(xy 435.723037 -119.667278) (xy 435.706969 -119.720685) (xy 435.683297 -119.771182) (xy 435.652524 -119.817695)
			(xy 435.615307 -119.859232) (xy 435.572439 -119.894907) (xy 435.524833 -119.923961) (xy 435.473504 -119.945773)
			(xy 435.419547 -119.959879) (xy 435.36411 -119.965979) (xy 435.308376 -119.963942) (xy 435.253533 -119.953812)
			(xy 435.200749 -119.935805) (xy 435.151149 -119.910304) (xy 435.105791 -119.877853) (xy 435.065642 -119.839144)
			(xy 435.031556 -119.795001) (xy 435.00426 -119.746366) (xy 434.984337 -119.694275) (xy 434.972211 -119.639838)
			(xy 434.96814 -119.584216) (xy 434.461666 -119.584216) (xy 434.461157 -119.612102) (xy 434.453037 -119.667278)
			(xy 434.436969 -119.720685) (xy 434.413297 -119.771182) (xy 434.382524 -119.817695) (xy 434.345307 -119.859232)
			(xy 434.302439 -119.894907) (xy 434.254833 -119.923961) (xy 434.203504 -119.945773) (xy 434.149547 -119.959879)
			(xy 434.09411 -119.965979) (xy 434.038376 -119.963942) (xy 433.983533 -119.953812) (xy 433.930749 -119.935805)
			(xy 433.881149 -119.910304) (xy 433.835791 -119.877853) (xy 433.795642 -119.839144) (xy 433.761556 -119.795001)
			(xy 433.73426 -119.746366) (xy 433.714337 -119.694275) (xy 433.702211 -119.639838) (xy 433.69814 -119.584216)
			(xy 423.823846 -119.584216) (xy 423.354955 -120.0531) (xy 429.699926 -120.0531) (xy 429.703997 -119.997478)
			(xy 429.716123 -119.943041) (xy 429.736046 -119.89095) (xy 429.763342 -119.842315) (xy 429.797428 -119.798172)
			(xy 429.837577 -119.759463) (xy 429.882935 -119.727012) (xy 429.932535 -119.701511) (xy 429.985319 -119.683504)
			(xy 430.040162 -119.673374) (xy 430.095896 -119.671337) (xy 430.151333 -119.677437) (xy 430.20529 -119.691543)
			(xy 430.256619 -119.713355) (xy 430.304225 -119.742409) (xy 430.347093 -119.778084) (xy 430.38431 -119.819621)
			(xy 430.415083 -119.866134) (xy 430.438755 -119.916631) (xy 430.454823 -119.970038) (xy 430.462943 -120.025214)
			(xy 430.463452 -120.0531) (xy 430.462943 -120.080986) (xy 430.454823 -120.136162) (xy 430.438755 -120.189569)
			(xy 430.415083 -120.240066) (xy 430.38431 -120.286579) (xy 430.347093 -120.328116) (xy 430.304225 -120.363791)
			(xy 430.256619 -120.392845) (xy 430.20529 -120.414657) (xy 430.151333 -120.428763) (xy 430.095896 -120.434863)
			(xy 430.040162 -120.432826) (xy 429.985319 -120.422696) (xy 429.932535 -120.404689) (xy 429.882935 -120.379188)
			(xy 429.837577 -120.346737) (xy 429.797428 -120.308028) (xy 429.763342 -120.263885) (xy 429.736046 -120.21525)
			(xy 429.716123 -120.163159) (xy 429.703997 -120.108722) (xy 429.699926 -120.0531) (xy 423.354955 -120.0531)
			(xy 422.910702 -120.497346) (xy 435.408576 -120.497346) (xy 435.412647 -120.441724) (xy 435.424773 -120.387287)
			(xy 435.444696 -120.335196) (xy 435.471992 -120.286561) (xy 435.506078 -120.242418) (xy 435.546227 -120.203709)
			(xy 435.591585 -120.171258) (xy 435.641185 -120.145757) (xy 435.693969 -120.12775) (xy 435.748812 -120.11762)
			(xy 435.804546 -120.115583) (xy 435.859983 -120.121683) (xy 435.91394 -120.135789) (xy 435.965269 -120.157601)
			(xy 436.012875 -120.186655) (xy 436.055743 -120.22233) (xy 436.09296 -120.263867) (xy 436.123733 -120.31038)
			(xy 436.147405 -120.360877) (xy 436.163473 -120.414284) (xy 436.171593 -120.46946) (xy 436.172102 -120.497346)
			(xy 436.171593 -120.525232) (xy 436.163473 -120.580408) (xy 436.147405 -120.633815) (xy 436.123733 -120.684312)
			(xy 436.09296 -120.730825) (xy 436.055743 -120.772362) (xy 436.012875 -120.808037) (xy 435.965269 -120.837091)
			(xy 435.91394 -120.858903) (xy 435.859983 -120.873009) (xy 435.804546 -120.879109) (xy 435.748812 -120.877072)
			(xy 435.693969 -120.866942) (xy 435.641185 -120.848935) (xy 435.591585 -120.823434) (xy 435.546227 -120.790983)
			(xy 435.506078 -120.752274) (xy 435.471992 -120.708131) (xy 435.444696 -120.659496) (xy 435.424773 -120.607405)
			(xy 435.412647 -120.552968) (xy 435.408576 -120.497346) (xy 422.910702 -120.497346) (xy 421.330798 -122.077226)
			(xy 421.87952 -122.077226) (xy 421.883591 -122.021604) (xy 421.895717 -121.967167) (xy 421.91564 -121.915076)
			(xy 421.942936 -121.866441) (xy 421.977022 -121.822298) (xy 422.017171 -121.783589) (xy 422.062529 -121.751138)
			(xy 422.112129 -121.725637) (xy 422.164913 -121.70763) (xy 422.219756 -121.6975) (xy 422.27549 -121.695463)
			(xy 422.330927 -121.701563) (xy 422.384884 -121.715669) (xy 422.436213 -121.737481) (xy 422.44561 -121.743216)
			(xy 428.864014 -121.743216) (xy 428.8645 -121.715965) (xy 428.872256 -121.662017) (xy 428.887611 -121.609722)
			(xy 428.910253 -121.560145) (xy 428.939719 -121.514295) (xy 428.97541 -121.473104) (xy 429.016601 -121.437413)
			(xy 429.062451 -121.407947) (xy 429.112028 -121.385305) (xy 429.164323 -121.36995) (xy 429.218271 -121.362194)
			(xy 429.272773 -121.362194) (xy 429.326721 -121.36995) (xy 429.379016 -121.385305) (xy 429.428593 -121.407947)
			(xy 429.474443 -121.437413) (xy 429.515634 -121.473104) (xy 429.551325 -121.514295) (xy 429.557897 -121.524522)
			(xy 435.516018 -121.524522) (xy 435.520089 -121.4689) (xy 435.532215 -121.414463) (xy 435.552138 -121.362372)
			(xy 435.579434 -121.313737) (xy 435.61352 -121.269594) (xy 435.653669 -121.230885) (xy 435.699027 -121.198434)
			(xy 435.748627 -121.172933) (xy 435.801411 -121.154926) (xy 435.856254 -121.144796) (xy 435.911988 -121.142759)
			(xy 435.967425 -121.148859) (xy 436.021382 -121.162965) (xy 436.072711 -121.184777) (xy 436.120317 -121.213831)
			(xy 436.163185 -121.249506) (xy 436.200402 -121.291043) (xy 436.231175 -121.337556) (xy 436.254847 -121.388053)
			(xy 436.26679 -121.427748) (xy 439.280298 -121.427748) (xy 439.284369 -121.372126) (xy 439.296495 -121.317689)
			(xy 439.316418 -121.265598) (xy 439.343714 -121.216963) (xy 439.3778 -121.17282) (xy 439.417949 -121.134111)
			(xy 439.463307 -121.10166) (xy 439.512907 -121.076159) (xy 439.565691 -121.058152) (xy 439.620534 -121.048022)
			(xy 439.676268 -121.045985) (xy 439.731705 -121.052085) (xy 439.785662 -121.066191) (xy 439.836991 -121.088003)
			(xy 439.884597 -121.117057) (xy 439.927465 -121.152732) (xy 439.964682 -121.194269) (xy 439.995455 -121.240782)
			(xy 440.019127 -121.291279) (xy 440.035195 -121.344686) (xy 440.043315 -121.399862) (xy 440.043824 -121.427748)
			(xy 440.043315 -121.455634) (xy 440.035195 -121.51081) (xy 440.019127 -121.564217) (xy 439.995455 -121.614714)
			(xy 439.964682 -121.661227) (xy 439.927465 -121.702764) (xy 439.884597 -121.738439) (xy 439.836991 -121.767493)
			(xy 439.785662 -121.789305) (xy 439.731705 -121.803411) (xy 439.676268 -121.809511) (xy 439.620534 -121.807474)
			(xy 439.565691 -121.797344) (xy 439.512907 -121.779337) (xy 439.463307 -121.753836) (xy 439.417949 -121.721385)
			(xy 439.3778 -121.682676) (xy 439.343714 -121.638533) (xy 439.316418 -121.589898) (xy 439.296495 -121.537807)
			(xy 439.284369 -121.48337) (xy 439.280298 -121.427748) (xy 436.26679 -121.427748) (xy 436.270915 -121.44146)
			(xy 436.279035 -121.496636) (xy 436.279544 -121.524522) (xy 436.279035 -121.552408) (xy 436.270915 -121.607584)
			(xy 436.254847 -121.660991) (xy 436.231175 -121.711488) (xy 436.200402 -121.758001) (xy 436.163185 -121.799538)
			(xy 436.120317 -121.835213) (xy 436.072711 -121.864267) (xy 436.021382 -121.886079) (xy 435.967425 -121.900185)
			(xy 435.911988 -121.906285) (xy 435.856254 -121.904248) (xy 435.801411 -121.894118) (xy 435.748627 -121.876111)
			(xy 435.699027 -121.85061) (xy 435.653669 -121.818159) (xy 435.61352 -121.77945) (xy 435.579434 -121.735307)
			(xy 435.552138 -121.686672) (xy 435.532215 -121.634581) (xy 435.520089 -121.580144) (xy 435.516018 -121.524522)
			(xy 429.557897 -121.524522) (xy 429.580791 -121.560145) (xy 429.603433 -121.609722) (xy 429.618788 -121.662017)
			(xy 429.626544 -121.715965) (xy 429.62703 -121.743216) (xy 429.626439 -121.773043) (xy 429.617165 -121.831972)
			(xy 429.598829 -121.888738) (xy 429.57188 -121.941957) (xy 429.554894 -121.966482) (xy 429.546539 -121.97895)
			(xy 429.536807 -122.007326) (xy 429.535742 -122.037306) (xy 429.543437 -122.066301) (xy 429.559226 -122.091808)
			(xy 429.570134 -122.102118) (xy 429.590087 -122.120342) (xy 429.625216 -122.161399) (xy 429.654204 -122.207001)
			(xy 429.67647 -122.256236) (xy 429.691569 -122.308119) (xy 429.6992 -122.361612) (xy 429.699674 -122.38863)
			(xy 429.699188 -122.415881) (xy 429.691432 -122.469829) (xy 429.676077 -122.522124) (xy 429.653435 -122.571701)
			(xy 429.623969 -122.617551) (xy 429.588278 -122.658742) (xy 429.547087 -122.694433) (xy 429.501237 -122.723899)
			(xy 429.45166 -122.746541) (xy 429.399365 -122.761896) (xy 429.345417 -122.769652) (xy 429.290915 -122.769652)
			(xy 429.236967 -122.761896) (xy 429.184672 -122.746541) (xy 429.135095 -122.723899) (xy 429.089245 -122.694433)
			(xy 429.048054 -122.658742) (xy 429.012363 -122.617551) (xy 428.982897 -122.571701) (xy 428.960255 -122.522124)
			(xy 428.9449 -122.469829) (xy 428.937144 -122.415881) (xy 428.936658 -122.38863) (xy 428.937205 -122.358801)
			(xy 428.94649 -122.29987) (xy 428.964838 -122.243103) (xy 428.991801 -122.189886) (xy 429.008794 -122.165364)
			(xy 429.017104 -122.152868) (xy 429.026844 -122.124503) (xy 429.027919 -122.094532) (xy 429.020235 -122.065542)
			(xy 429.004456 -122.040038) (xy 428.993554 -122.029728) (xy 428.973573 -122.011534) (xy 428.938446 -121.97047)
			(xy 428.909463 -121.924862) (xy 428.887201 -121.875621) (xy 428.872108 -121.823733) (xy 428.864484 -121.770235)
			(xy 428.864014 -121.743216) (xy 422.44561 -121.743216) (xy 422.483819 -121.766535) (xy 422.526687 -121.80221)
			(xy 422.563904 -121.843747) (xy 422.594677 -121.89026) (xy 422.618349 -121.940757) (xy 422.634417 -121.994164)
			(xy 422.642537 -122.04934) (xy 422.643046 -122.077226) (xy 422.642537 -122.105112) (xy 422.634417 -122.160288)
			(xy 422.618349 -122.213695) (xy 422.594677 -122.264192) (xy 422.563904 -122.310705) (xy 422.526687 -122.352242)
			(xy 422.483819 -122.387917) (xy 422.436213 -122.416971) (xy 422.384884 -122.438783) (xy 422.330927 -122.452889)
			(xy 422.27549 -122.458989) (xy 422.219756 -122.456952) (xy 422.164913 -122.446822) (xy 422.112129 -122.428815)
			(xy 422.062529 -122.403314) (xy 422.017171 -122.370863) (xy 421.977022 -122.332154) (xy 421.942936 -122.288011)
			(xy 421.91564 -122.239376) (xy 421.895717 -122.187285) (xy 421.883591 -122.132848) (xy 421.87952 -122.077226)
			(xy 421.330798 -122.077226) (xy 420.543132 -122.86488) (xy 435.519574 -122.86488) (xy 435.523645 -122.809258)
			(xy 435.535771 -122.754821) (xy 435.555694 -122.70273) (xy 435.58299 -122.654095) (xy 435.617076 -122.609952)
			(xy 435.657225 -122.571243) (xy 435.702583 -122.538792) (xy 435.752183 -122.513291) (xy 435.804967 -122.495284)
			(xy 435.85981 -122.485154) (xy 435.915544 -122.483117) (xy 435.970981 -122.489217) (xy 436.024938 -122.503323)
			(xy 436.076267 -122.525135) (xy 436.123873 -122.554189) (xy 436.166741 -122.589864) (xy 436.203958 -122.631401)
			(xy 436.21542 -122.648726) (xy 437.90057 -122.648726) (xy 437.904641 -122.593104) (xy 437.916767 -122.538667)
			(xy 437.93669 -122.486576) (xy 437.963986 -122.437941) (xy 437.998072 -122.393798) (xy 438.038221 -122.355089)
			(xy 438.083579 -122.322638) (xy 438.133179 -122.297137) (xy 438.185963 -122.27913) (xy 438.240806 -122.269)
			(xy 438.29654 -122.266963) (xy 438.351977 -122.273063) (xy 438.405934 -122.287169) (xy 438.457263 -122.308981)
			(xy 438.504869 -122.338035) (xy 438.547737 -122.37371) (xy 438.584954 -122.415247) (xy 438.615727 -122.46176)
			(xy 438.639399 -122.512257) (xy 438.655467 -122.565664) (xy 438.663587 -122.62084) (xy 438.664096 -122.648726)
			(xy 438.663587 -122.676612) (xy 438.655467 -122.731788) (xy 438.639399 -122.785195) (xy 438.615727 -122.835692)
			(xy 438.584954 -122.882205) (xy 438.547737 -122.923742) (xy 438.504869 -122.959417) (xy 438.457263 -122.988471)
			(xy 438.405934 -123.010283) (xy 438.351977 -123.024389) (xy 438.29654 -123.030489) (xy 438.240806 -123.028452)
			(xy 438.185963 -123.018322) (xy 438.133179 -123.000315) (xy 438.083579 -122.974814) (xy 438.038221 -122.942363)
			(xy 437.998072 -122.903654) (xy 437.963986 -122.859511) (xy 437.93669 -122.810876) (xy 437.916767 -122.758785)
			(xy 437.904641 -122.704348) (xy 437.90057 -122.648726) (xy 436.21542 -122.648726) (xy 436.234731 -122.677914)
			(xy 436.258403 -122.728411) (xy 436.274471 -122.781818) (xy 436.282591 -122.836994) (xy 436.2831 -122.86488)
			(xy 436.282591 -122.892766) (xy 436.274471 -122.947942) (xy 436.258403 -123.001349) (xy 436.234731 -123.051846)
			(xy 436.203958 -123.098359) (xy 436.166741 -123.139896) (xy 436.123873 -123.175571) (xy 436.076267 -123.204625)
			(xy 436.024938 -123.226437) (xy 435.970981 -123.240543) (xy 435.915544 -123.246643) (xy 435.85981 -123.244606)
			(xy 435.804967 -123.234476) (xy 435.752183 -123.216469) (xy 435.702583 -123.190968) (xy 435.657225 -123.158517)
			(xy 435.617076 -123.119808) (xy 435.58299 -123.075665) (xy 435.555694 -123.02703) (xy 435.535771 -122.974939)
			(xy 435.523645 -122.920502) (xy 435.519574 -122.86488) (xy 420.543132 -122.86488) (xy 420.092021 -123.315984)
			(xy 428.176434 -123.315984) (xy 428.180505 -123.260362) (xy 428.192631 -123.205925) (xy 428.212554 -123.153834)
			(xy 428.23985 -123.105199) (xy 428.273936 -123.061056) (xy 428.314085 -123.022347) (xy 428.359443 -122.989896)
			(xy 428.409043 -122.964395) (xy 428.461827 -122.946388) (xy 428.51667 -122.936258) (xy 428.572404 -122.934221)
			(xy 428.627841 -122.940321) (xy 428.681798 -122.954427) (xy 428.733127 -122.976239) (xy 428.780733 -123.005293)
			(xy 428.823601 -123.040968) (xy 428.860818 -123.082505) (xy 428.891591 -123.129018) (xy 428.915263 -123.179515)
			(xy 428.931331 -123.232922) (xy 428.939451 -123.288098) (xy 428.93996 -123.315984) (xy 428.939451 -123.34387)
			(xy 428.931331 -123.399046) (xy 428.915263 -123.452453) (xy 428.891591 -123.50295) (xy 428.860818 -123.549463)
			(xy 428.823601 -123.591) (xy 428.780733 -123.626675) (xy 428.733127 -123.655729) (xy 428.681798 -123.677541)
			(xy 428.627841 -123.691647) (xy 428.572404 -123.697747) (xy 428.51667 -123.69571) (xy 428.461827 -123.68558)
			(xy 428.409043 -123.667573) (xy 428.359443 -123.642072) (xy 428.314085 -123.609621) (xy 428.273936 -123.570912)
			(xy 428.23985 -123.526769) (xy 428.212554 -123.478134) (xy 428.192631 -123.426043) (xy 428.180505 -123.371606)
			(xy 428.176434 -123.315984) (xy 420.092021 -123.315984) (xy 419.536007 -123.87199) (xy 435.521606 -123.87199)
			(xy 435.525677 -123.816368) (xy 435.537803 -123.761931) (xy 435.557726 -123.70984) (xy 435.585022 -123.661205)
			(xy 435.619108 -123.617062) (xy 435.659257 -123.578353) (xy 435.704615 -123.545902) (xy 435.754215 -123.520401)
			(xy 435.806999 -123.502394) (xy 435.861842 -123.492264) (xy 435.917576 -123.490227) (xy 435.973013 -123.496327)
			(xy 436.02697 -123.510433) (xy 436.078299 -123.532245) (xy 436.125905 -123.561299) (xy 436.168773 -123.596974)
			(xy 436.20599 -123.638511) (xy 436.223334 -123.664726) (xy 439.889898 -123.664726) (xy 439.893969 -123.609104)
			(xy 439.906095 -123.554667) (xy 439.926018 -123.502576) (xy 439.953314 -123.453941) (xy 439.9874 -123.409798)
			(xy 440.027549 -123.371089) (xy 440.072907 -123.338638) (xy 440.122507 -123.313137) (xy 440.175291 -123.29513)
			(xy 440.230134 -123.285) (xy 440.285868 -123.282963) (xy 440.341305 -123.289063) (xy 440.395262 -123.303169)
			(xy 440.446591 -123.324981) (xy 440.494197 -123.354035) (xy 440.537065 -123.38971) (xy 440.574282 -123.431247)
			(xy 440.605055 -123.47776) (xy 440.628727 -123.528257) (xy 440.644795 -123.581664) (xy 440.652915 -123.63684)
			(xy 440.653424 -123.664726) (xy 440.652915 -123.692612) (xy 440.644795 -123.747788) (xy 440.628727 -123.801195)
			(xy 440.605055 -123.851692) (xy 440.574282 -123.898205) (xy 440.537065 -123.939742) (xy 440.494197 -123.975417)
			(xy 440.446591 -124.004471) (xy 440.395262 -124.026283) (xy 440.341305 -124.040389) (xy 440.285868 -124.046489)
			(xy 440.230134 -124.044452) (xy 440.175291 -124.034322) (xy 440.122507 -124.016315) (xy 440.072907 -123.990814)
			(xy 440.027549 -123.958363) (xy 439.9874 -123.919654) (xy 439.953314 -123.875511) (xy 439.926018 -123.826876)
			(xy 439.906095 -123.774785) (xy 439.893969 -123.720348) (xy 439.889898 -123.664726) (xy 436.223334 -123.664726)
			(xy 436.236763 -123.685024) (xy 436.260435 -123.735521) (xy 436.276503 -123.788928) (xy 436.284623 -123.844104)
			(xy 436.285132 -123.87199) (xy 436.284623 -123.899876) (xy 436.276503 -123.955052) (xy 436.260435 -124.008459)
			(xy 436.236763 -124.058956) (xy 436.20599 -124.105469) (xy 436.168773 -124.147006) (xy 436.125905 -124.182681)
			(xy 436.078299 -124.211735) (xy 436.02697 -124.233547) (xy 435.973013 -124.247653) (xy 435.917576 -124.253753)
			(xy 435.861842 -124.251716) (xy 435.806999 -124.241586) (xy 435.754215 -124.223579) (xy 435.704615 -124.198078)
			(xy 435.659257 -124.165627) (xy 435.619108 -124.126918) (xy 435.585022 -124.082775) (xy 435.557726 -124.03414)
			(xy 435.537803 -123.982049) (xy 435.525677 -123.927612) (xy 435.521606 -123.87199) (xy 419.536007 -123.87199)
			(xy 418.635563 -124.77242) (xy 427.805848 -124.77242) (xy 427.809919 -124.716798) (xy 427.822045 -124.662361)
			(xy 427.841968 -124.61027) (xy 427.869264 -124.561635) (xy 427.90335 -124.517492) (xy 427.943499 -124.478783)
			(xy 427.988857 -124.446332) (xy 428.038457 -124.420831) (xy 428.091241 -124.402824) (xy 428.146084 -124.392694)
			(xy 428.201818 -124.390657) (xy 428.257255 -124.396757) (xy 428.311212 -124.410863) (xy 428.362541 -124.432675)
			(xy 428.410147 -124.461729) (xy 428.453015 -124.497404) (xy 428.490232 -124.538941) (xy 428.521005 -124.585454)
			(xy 428.544677 -124.635951) (xy 428.560745 -124.689358) (xy 428.568865 -124.744534) (xy 428.569374 -124.77242)
			(xy 428.568865 -124.800306) (xy 428.560745 -124.855482) (xy 428.551652 -124.885704) (xy 435.552594 -124.885704)
			(xy 435.556665 -124.830082) (xy 435.568791 -124.775645) (xy 435.588714 -124.723554) (xy 435.61601 -124.674919)
			(xy 435.650096 -124.630776) (xy 435.690245 -124.592067) (xy 435.735603 -124.559616) (xy 435.785203 -124.534115)
			(xy 435.837987 -124.516108) (xy 435.89283 -124.505978) (xy 435.948564 -124.503941) (xy 436.004001 -124.510041)
			(xy 436.057958 -124.524147) (xy 436.109287 -124.545959) (xy 436.156893 -124.575013) (xy 436.199761 -124.610688)
			(xy 436.236978 -124.652225) (xy 436.255834 -124.680726) (xy 439.889898 -124.680726) (xy 439.893969 -124.625104)
			(xy 439.906095 -124.570667) (xy 439.926018 -124.518576) (xy 439.953314 -124.469941) (xy 439.9874 -124.425798)
			(xy 440.027549 -124.387089) (xy 440.072907 -124.354638) (xy 440.122507 -124.329137) (xy 440.175291 -124.31113)
			(xy 440.230134 -124.301) (xy 440.285868 -124.298963) (xy 440.341305 -124.305063) (xy 440.395262 -124.319169)
			(xy 440.446591 -124.340981) (xy 440.494197 -124.370035) (xy 440.537065 -124.40571) (xy 440.574282 -124.447247)
			(xy 440.605055 -124.49376) (xy 440.628727 -124.544257) (xy 440.644795 -124.597664) (xy 440.652915 -124.65284)
			(xy 440.653424 -124.680726) (xy 440.652915 -124.708612) (xy 440.644795 -124.763788) (xy 440.628727 -124.817195)
			(xy 440.605055 -124.867692) (xy 440.574282 -124.914205) (xy 440.537065 -124.955742) (xy 440.494197 -124.991417)
			(xy 440.446591 -125.020471) (xy 440.395262 -125.042283) (xy 440.341305 -125.056389) (xy 440.285868 -125.062489)
			(xy 440.230134 -125.060452) (xy 440.175291 -125.050322) (xy 440.122507 -125.032315) (xy 440.072907 -125.006814)
			(xy 440.027549 -124.974363) (xy 439.9874 -124.935654) (xy 439.953314 -124.891511) (xy 439.926018 -124.842876)
			(xy 439.906095 -124.790785) (xy 439.893969 -124.736348) (xy 439.889898 -124.680726) (xy 436.255834 -124.680726)
			(xy 436.267751 -124.698738) (xy 436.291423 -124.749235) (xy 436.307491 -124.802642) (xy 436.315611 -124.857818)
			(xy 436.31612 -124.885704) (xy 436.315611 -124.91359) (xy 436.307491 -124.968766) (xy 436.291423 -125.022173)
			(xy 436.267751 -125.07267) (xy 436.236978 -125.119183) (xy 436.199761 -125.16072) (xy 436.156893 -125.196395)
			(xy 436.109287 -125.225449) (xy 436.057958 -125.247261) (xy 436.004001 -125.261367) (xy 435.948564 -125.267467)
			(xy 435.89283 -125.26543) (xy 435.837987 -125.2553) (xy 435.785203 -125.237293) (xy 435.735603 -125.211792)
			(xy 435.690245 -125.179341) (xy 435.650096 -125.140632) (xy 435.61601 -125.096489) (xy 435.588714 -125.047854)
			(xy 435.568791 -124.995763) (xy 435.556665 -124.941326) (xy 435.552594 -124.885704) (xy 428.551652 -124.885704)
			(xy 428.544677 -124.908889) (xy 428.521005 -124.959386) (xy 428.490232 -125.005899) (xy 428.453015 -125.047436)
			(xy 428.410147 -125.083111) (xy 428.362541 -125.112165) (xy 428.311212 -125.133977) (xy 428.257255 -125.148083)
			(xy 428.201818 -125.154183) (xy 428.146084 -125.152146) (xy 428.091241 -125.142016) (xy 428.038457 -125.124009)
			(xy 427.988857 -125.098508) (xy 427.943499 -125.066057) (xy 427.90335 -125.027348) (xy 427.869264 -124.983205)
			(xy 427.841968 -124.93457) (xy 427.822045 -124.882479) (xy 427.809919 -124.828042) (xy 427.805848 -124.77242)
			(xy 418.635563 -124.77242) (xy 418.013761 -125.394212) (xy 429.170336 -125.394212) (xy 429.174407 -125.33859)
			(xy 429.186533 -125.284153) (xy 429.206456 -125.232062) (xy 429.233752 -125.183427) (xy 429.267838 -125.139284)
			(xy 429.307987 -125.100575) (xy 429.353345 -125.068124) (xy 429.402945 -125.042623) (xy 429.455729 -125.024616)
			(xy 429.510572 -125.014486) (xy 429.566306 -125.012449) (xy 429.621743 -125.018549) (xy 429.6757 -125.032655)
			(xy 429.727029 -125.054467) (xy 429.774635 -125.083521) (xy 429.817503 -125.119196) (xy 429.85472 -125.160733)
			(xy 429.885493 -125.207246) (xy 429.909165 -125.257743) (xy 429.925233 -125.31115) (xy 429.933353 -125.366326)
			(xy 429.933862 -125.394212) (xy 429.933353 -125.422098) (xy 429.925233 -125.477274) (xy 429.909165 -125.530681)
			(xy 429.885493 -125.581178) (xy 429.85472 -125.627691) (xy 429.817503 -125.669228) (xy 429.774635 -125.704903)
			(xy 429.727029 -125.733957) (xy 429.6757 -125.755769) (xy 429.621743 -125.769875) (xy 429.566306 -125.775975)
			(xy 429.510572 -125.773938) (xy 429.455729 -125.763808) (xy 429.402945 -125.745801) (xy 429.353345 -125.7203)
			(xy 429.307987 -125.687849) (xy 429.267838 -125.64914) (xy 429.233752 -125.604997) (xy 429.206456 -125.556362)
			(xy 429.186533 -125.504271) (xy 429.174407 -125.449834) (xy 429.170336 -125.394212) (xy 418.013761 -125.394212)
			(xy 417.604307 -125.80366) (xy 426.7995 -125.80366) (xy 426.803571 -125.748038) (xy 426.815697 -125.693601)
			(xy 426.83562 -125.64151) (xy 426.862916 -125.592875) (xy 426.897002 -125.548732) (xy 426.937151 -125.510023)
			(xy 426.982509 -125.477572) (xy 427.032109 -125.452071) (xy 427.084893 -125.434064) (xy 427.139736 -125.423934)
			(xy 427.19547 -125.421897) (xy 427.250907 -125.427997) (xy 427.304864 -125.442103) (xy 427.356193 -125.463915)
			(xy 427.403799 -125.492969) (xy 427.446667 -125.528644) (xy 427.483884 -125.570181) (xy 427.514657 -125.616694)
			(xy 427.538329 -125.667191) (xy 427.554397 -125.720598) (xy 427.562517 -125.775774) (xy 427.563026 -125.80366)
			(xy 427.562517 -125.831546) (xy 427.554397 -125.886722) (xy 427.55073 -125.89891) (xy 435.50408 -125.89891)
			(xy 435.508151 -125.843288) (xy 435.520277 -125.788851) (xy 435.5402 -125.73676) (xy 435.567496 -125.688125)
			(xy 435.601582 -125.643982) (xy 435.641731 -125.605273) (xy 435.687089 -125.572822) (xy 435.736689 -125.547321)
			(xy 435.789473 -125.529314) (xy 435.844316 -125.519184) (xy 435.90005 -125.517147) (xy 435.955487 -125.523247)
			(xy 436.009444 -125.537353) (xy 436.060773 -125.559165) (xy 436.108379 -125.588219) (xy 436.151247 -125.623894)
			(xy 436.188464 -125.665431) (xy 436.219237 -125.711944) (xy 436.242909 -125.762441) (xy 436.258977 -125.815848)
			(xy 436.267097 -125.871024) (xy 436.267606 -125.89891) (xy 436.267097 -125.926796) (xy 436.258977 -125.981972)
			(xy 436.242909 -126.035379) (xy 436.219237 -126.085876) (xy 436.188464 -126.132389) (xy 436.151247 -126.173926)
			(xy 436.108379 -126.209601) (xy 436.060773 -126.238655) (xy 436.009444 -126.260467) (xy 435.955487 -126.274573)
			(xy 435.90005 -126.280673) (xy 435.844316 -126.278636) (xy 435.789473 -126.268506) (xy 435.736689 -126.250499)
			(xy 435.687089 -126.224998) (xy 435.641731 -126.192547) (xy 435.601582 -126.153838) (xy 435.567496 -126.109695)
			(xy 435.5402 -126.06106) (xy 435.520277 -126.008969) (xy 435.508151 -125.954532) (xy 435.50408 -125.89891)
			(xy 427.55073 -125.89891) (xy 427.538329 -125.940129) (xy 427.514657 -125.990626) (xy 427.483884 -126.037139)
			(xy 427.446667 -126.078676) (xy 427.403799 -126.114351) (xy 427.356193 -126.143405) (xy 427.304864 -126.165217)
			(xy 427.250907 -126.179323) (xy 427.19547 -126.185423) (xy 427.139736 -126.183386) (xy 427.084893 -126.173256)
			(xy 427.032109 -126.155249) (xy 426.982509 -126.129748) (xy 426.937151 -126.097297) (xy 426.897002 -126.058588)
			(xy 426.862916 -126.014445) (xy 426.83562 -125.96581) (xy 426.815697 -125.913719) (xy 426.803571 -125.859282)
			(xy 426.7995 -125.80366) (xy 417.604307 -125.80366) (xy 415.949695 -127.458247) (xy 429.165816 -127.458247)
			(xy 429.165816 -127.403753) (xy 429.173571 -127.349814) (xy 429.188923 -127.297527) (xy 429.211559 -127.247957)
			(xy 429.241019 -127.202113) (xy 429.276704 -127.160928) (xy 429.317886 -127.12524) (xy 429.363727 -127.095775)
			(xy 429.413295 -127.073135) (xy 429.46558 -127.057778) (xy 429.519519 -127.050019) (xy 429.546766 -127.04953)
			(xy 429.576816 -127.050124) (xy 429.636173 -127.059554) (xy 429.693318 -127.078172) (xy 429.746838 -127.105515)
			(xy 429.795411 -127.14091) (xy 429.817022 -127.161798) (xy 429.827948 -127.171991) (xy 429.85427 -127.186102)
			(xy 429.883548 -127.192005) (xy 429.913282 -127.189196) (xy 429.940936 -127.177914) (xy 429.96415 -127.159121)
			(xy 429.972978 -127.147066) (xy 429.986745 -127.127393) (xy 430.018464 -127.091344) (xy 430.036224 -127.075184)
			(xy 430.045506 -127.066504) (xy 430.059824 -127.045517) (xy 430.068508 -127.021642) (xy 430.07102 -126.996361)
			(xy 430.069498 -126.983744) (xy 430.042506 -126.973126) (xy 429.991838 -126.944899) (xy 429.94602 -126.909337)
			(xy 429.906104 -126.867256) (xy 429.87301 -126.819624) (xy 429.847497 -126.767536) (xy 429.830153 -126.71219)
			(xy 429.821375 -126.654858) (xy 429.820832 -126.625858) (xy 429.821285 -126.598588) (xy 429.829053 -126.544603)
			(xy 429.844423 -126.492274) (xy 429.867084 -126.442664) (xy 429.896573 -126.396783) (xy 429.932292 -126.355566)
			(xy 429.973512 -126.319852) (xy 430.019395 -126.290366) (xy 430.069007 -126.26771) (xy 430.121339 -126.252345)
			(xy 430.175324 -126.244583) (xy 430.202594 -126.244096) (xy 430.220543 -126.244286) (xy 430.256289 -126.247591)
			(xy 430.273968 -126.2507) (xy 430.28362 -126.2507) (xy 430.310872 -126.251159) (xy 430.364821 -126.258919)
			(xy 430.417117 -126.274277) (xy 430.466695 -126.296921) (xy 430.512545 -126.32639) (xy 430.553736 -126.362084)
			(xy 430.589427 -126.403277) (xy 430.618893 -126.44913) (xy 430.641533 -126.498709) (xy 430.656887 -126.551006)
			(xy 430.664643 -126.604956) (xy 430.665128 -126.632208) (xy 430.664654 -126.659166) (xy 430.657062 -126.712545)
			(xy 430.642031 -126.764323) (xy 430.61986 -126.813469) (xy 430.59099 -126.859005) (xy 430.555998 -126.900022)
			(xy 430.536096 -126.918212) (xy 430.525502 -126.928164) (xy 430.509944 -126.952701) (xy 430.501935 -126.980629)
			(xy 430.502124 -127.009682) (xy 430.510495 -127.037504) (xy 430.52637 -127.061838) (xy 430.537112 -127.071628)
			(xy 430.544805 -127.078327) (xy 430.559545 -127.092432) (xy 430.566576 -127.099822) (xy 430.577044 -127.110092)
			(xy 430.602417 -127.124763) (xy 430.63091 -127.131636) (xy 430.660182 -127.130146) (xy 430.687829 -127.120415)
			(xy 430.711582 -127.103243) (xy 430.729488 -127.080039) (xy 430.735232 -127.066548) (xy 430.746045 -127.039951)
			(xy 430.774487 -126.990078) (xy 430.810079 -126.945029) (xy 430.852019 -126.90582) (xy 430.899358 -126.873337)
			(xy 430.95103 -126.848312) (xy 431.005868 -126.83131) (xy 431.062634 -126.822715) (xy 431.09134 -126.8222)
			(xy 431.091848 -126.8222) (xy 431.10222 -126.822278) (xy 431.122932 -126.823423) (xy 431.13325 -126.824486)
			(xy 431.146494 -126.82561) (xy 431.172767 -126.821628) (xy 431.197115 -126.810984) (xy 431.21788 -126.794402)
			(xy 431.233649 -126.773013) (xy 431.243346 -126.748272) (xy 431.246312 -126.721864) (xy 431.244756 -126.708662)
			(xy 431.242843 -126.694707) (xy 431.240806 -126.666612) (xy 431.240692 -126.652528) (xy 431.241181 -126.625276)
			(xy 431.248935 -126.571326) (xy 431.264287 -126.519028) (xy 431.286926 -126.469448) (xy 431.316391 -126.423595)
			(xy 431.352082 -126.382402) (xy 431.393273 -126.346708) (xy 431.439124 -126.31724) (xy 431.488702 -126.294597)
			(xy 431.540998 -126.27924) (xy 431.594948 -126.271483) (xy 431.6222 -126.27102) (xy 431.646145 -126.271364)
			(xy 431.693659 -126.277356) (xy 431.716942 -126.282958) (xy 431.730331 -126.285959) (xy 431.757756 -126.285459)
			(xy 431.784058 -126.277672) (xy 431.807335 -126.263162) (xy 431.825907 -126.242975) (xy 431.838431 -126.218572)
			(xy 431.841656 -126.205234) (xy 431.848089 -126.176987) (xy 431.868334 -126.122708) (xy 431.896552 -126.072114)
			(xy 431.932094 -126.026367) (xy 431.974143 -125.986519) (xy 432.021733 -125.953486) (xy 432.07377 -125.928026)
			(xy 432.129057 -125.910725) (xy 432.186324 -125.901981) (xy 432.21529 -125.90145) (xy 432.24254 -125.901997)
			(xy 432.296486 -125.909752) (xy 432.34878 -125.925105) (xy 432.398356 -125.947744) (xy 432.444205 -125.977209)
			(xy 432.485394 -126.012899) (xy 432.521085 -126.054087) (xy 432.550551 -126.099936) (xy 432.573192 -126.149511)
			(xy 432.588546 -126.201804) (xy 432.596303 -126.25575) (xy 432.596303 -126.31025) (xy 432.588546 -126.364196)
			(xy 432.573192 -126.416489) (xy 432.550551 -126.466064) (xy 432.521085 -126.511913) (xy 432.485394 -126.553101)
			(xy 432.444205 -126.588791) (xy 432.398356 -126.618256) (xy 432.34878 -126.640895) (xy 432.296486 -126.656248)
			(xy 432.24254 -126.664003) (xy 432.21529 -126.664466) (xy 432.191346 -126.664106) (xy 432.143832 -126.658124)
			(xy 432.120548 -126.652528) (xy 432.107159 -126.649527) (xy 432.079735 -126.65003) (xy 432.053435 -126.657818)
			(xy 432.030158 -126.672328) (xy 432.011586 -126.692513) (xy 431.99906 -126.716915) (xy 431.995834 -126.730252)
			(xy 431.994462 -126.736348) (xy 433.246782 -126.736348) (xy 433.250853 -126.680726) (xy 433.262979 -126.626289)
			(xy 433.282902 -126.574198) (xy 433.310198 -126.525563) (xy 433.344284 -126.48142) (xy 433.384433 -126.442711)
			(xy 433.429791 -126.41026) (xy 433.479391 -126.384759) (xy 433.532175 -126.366752) (xy 433.587018 -126.356622)
			(xy 433.642752 -126.354585) (xy 433.698189 -126.360685) (xy 433.752146 -126.374791) (xy 433.803475 -126.396603)
			(xy 433.851081 -126.425657) (xy 433.893949 -126.461332) (xy 433.931166 -126.502869) (xy 433.961939 -126.549382)
			(xy 433.985611 -126.599879) (xy 434.001679 -126.653286) (xy 434.009799 -126.708462) (xy 434.010308 -126.736348)
			(xy 434.009799 -126.764234) (xy 434.001679 -126.81941) (xy 433.985611 -126.872817) (xy 433.961939 -126.923314)
			(xy 433.931166 -126.969827) (xy 433.893949 -127.011364) (xy 433.851081 -127.047039) (xy 433.803475 -127.076093)
			(xy 433.752146 -127.097905) (xy 433.698189 -127.112011) (xy 433.642752 -127.118111) (xy 433.587018 -127.116074)
			(xy 433.532175 -127.105944) (xy 433.479391 -127.087937) (xy 433.429791 -127.062436) (xy 433.384433 -127.029985)
			(xy 433.344284 -126.991276) (xy 433.310198 -126.947133) (xy 433.282902 -126.898498) (xy 433.262979 -126.846407)
			(xy 433.250853 -126.79197) (xy 433.246782 -126.736348) (xy 431.994462 -126.736348) (xy 431.989471 -126.758516)
			(xy 431.969213 -126.812795) (xy 431.940984 -126.863387) (xy 431.905432 -126.909132) (xy 431.863374 -126.948978)
			(xy 431.815776 -126.982009) (xy 431.763733 -127.007466) (xy 431.70844 -127.024764) (xy 431.651168 -127.033506)
			(xy 431.6222 -127.034036) (xy 431.621692 -127.034036) (xy 431.61132 -127.033955) (xy 431.590608 -127.032812)
			(xy 431.58029 -127.03175) (xy 431.567042 -127.030739) (xy 431.540783 -127.034709) (xy 431.516446 -127.045337)
			(xy 431.495687 -127.0619) (xy 431.479918 -127.083269) (xy 431.470215 -127.107989) (xy 431.467237 -127.134379)
			(xy 431.468784 -127.147574) (xy 431.470701 -127.161528) (xy 431.472736 -127.189623) (xy 431.472848 -127.203708)
			(xy 431.47233 -127.230958) (xy 431.464573 -127.284902) (xy 431.44993 -127.334772) (xy 431.877976 -127.334772)
			(xy 431.882047 -127.27915) (xy 431.894173 -127.224713) (xy 431.914096 -127.172622) (xy 431.941392 -127.123987)
			(xy 431.975478 -127.079844) (xy 432.015627 -127.041135) (xy 432.060985 -127.008684) (xy 432.110585 -126.983183)
			(xy 432.163369 -126.965176) (xy 432.218212 -126.955046) (xy 432.273946 -126.953009) (xy 432.329383 -126.959109)
			(xy 432.38334 -126.973215) (xy 432.434669 -126.995027) (xy 432.482275 -127.024081) (xy 432.525143 -127.059756)
			(xy 432.56236 -127.101293) (xy 432.593133 -127.147806) (xy 432.616805 -127.198303) (xy 432.632873 -127.25171)
			(xy 432.640993 -127.306886) (xy 432.641502 -127.334772) (xy 432.640993 -127.362658) (xy 432.632873 -127.417834)
			(xy 432.616805 -127.471241) (xy 432.593133 -127.521738) (xy 432.56236 -127.568251) (xy 432.525143 -127.609788)
			(xy 432.482275 -127.645463) (xy 432.434669 -127.674517) (xy 432.38334 -127.696329) (xy 432.329383 -127.710435)
			(xy 432.273946 -127.716535) (xy 432.218212 -127.714498) (xy 432.163369 -127.704368) (xy 432.110585 -127.686361)
			(xy 432.060985 -127.66086) (xy 432.015627 -127.628409) (xy 431.975478 -127.5897) (xy 431.941392 -127.545557)
			(xy 431.914096 -127.496922) (xy 431.894173 -127.444831) (xy 431.882047 -127.390394) (xy 431.877976 -127.334772)
			(xy 431.44993 -127.334772) (xy 431.449219 -127.337194) (xy 431.42658 -127.386768) (xy 431.397117 -127.432617)
			(xy 431.361429 -127.473806) (xy 431.320242 -127.509497) (xy 431.274397 -127.538965) (xy 431.224824 -127.561608)
			(xy 431.172533 -127.576966) (xy 431.11859 -127.584727) (xy 431.09134 -127.585216) (xy 431.065389 -127.584758)
			(xy 431.013967 -127.577715) (xy 430.963974 -127.563767) (xy 430.916333 -127.543172) (xy 430.871923 -127.51631)
			(xy 430.831564 -127.483676) (xy 430.813464 -127.465074) (xy 430.803058 -127.454737) (xy 430.777668 -127.440069)
			(xy 430.74916 -127.433203) (xy 430.719876 -127.434703) (xy 430.69222 -127.444446) (xy 430.668461 -127.461632)
			(xy 430.650552 -127.48485) (xy 430.644808 -127.498348) (xy 430.634042 -127.524966) (xy 430.605595 -127.574841)
			(xy 430.569997 -127.619891) (xy 430.528051 -127.659099) (xy 430.480704 -127.69158) (xy 430.429025 -127.716602)
			(xy 430.37418 -127.733598) (xy 430.317409 -127.742185) (xy 430.2887 -127.742696) (xy 430.258649 -127.742116)
			(xy 430.199292 -127.732681) (xy 430.142148 -127.71406) (xy 430.088628 -127.686714) (xy 430.040055 -127.651317)
			(xy 430.018444 -127.630428) (xy 430.007554 -127.620193) (xy 429.981221 -127.60608) (xy 429.951932 -127.60018)
			(xy 429.922189 -127.602997) (xy 429.894529 -127.614291) (xy 429.871314 -127.633097) (xy 429.862488 -127.64516)
			(xy 429.847183 -127.666891) (xy 429.811542 -127.706322) (xy 429.77077 -127.740421) (xy 429.725659 -127.768527)
			(xy 429.677081 -127.790097) (xy 429.625978 -127.804711) (xy 429.573342 -127.812088) (xy 429.546766 -127.812546)
			(xy 429.519519 -127.811981) (xy 429.46558 -127.804222) (xy 429.413295 -127.788865) (xy 429.363727 -127.766225)
			(xy 429.317886 -127.73676) (xy 429.276704 -127.701072) (xy 429.241019 -127.659887) (xy 429.211559 -127.614043)
			(xy 429.188923 -127.564473) (xy 429.173571 -127.512186) (xy 429.165816 -127.458247) (xy 415.949695 -127.458247)
			(xy 414.698249 -128.709674) (xy 433.3367 -128.709674) (xy 433.33715 -128.683295) (xy 433.344406 -128.631037)
			(xy 433.35879 -128.580278) (xy 433.380028 -128.531982) (xy 433.407715 -128.487073) (xy 433.441324 -128.446404)
			(xy 433.480213 -128.410752) (xy 433.523642 -128.380795) (xy 433.547012 -128.368552) (xy 433.559389 -128.361886)
			(xy 433.580112 -128.3429) (xy 433.594866 -128.31898) (xy 433.602533 -128.291941) (xy 433.60253 -128.263836)
			(xy 433.594857 -128.236799) (xy 433.580097 -128.212882) (xy 433.55937 -128.193901) (xy 433.547012 -128.187196)
			(xy 433.523634 -128.174968) (xy 433.480208 -128.145005) (xy 433.441322 -128.109349) (xy 433.407716 -128.068677)
			(xy 433.38003 -128.023766) (xy 433.358791 -127.975471) (xy 433.344404 -127.924711) (xy 433.337143 -127.872454)
			(xy 433.3367 -127.846074) (xy 433.337186 -127.818823) (xy 433.344942 -127.764875) (xy 433.360297 -127.71258)
			(xy 433.382939 -127.663003) (xy 433.412405 -127.617153) (xy 433.448096 -127.575962) (xy 433.489287 -127.540271)
			(xy 433.535137 -127.510805) (xy 433.584714 -127.488163) (xy 433.637009 -127.472808) (xy 433.690957 -127.465052)
			(xy 433.745459 -127.465052) (xy 433.799407 -127.472808) (xy 433.851702 -127.488163) (xy 433.901279 -127.510805)
			(xy 433.947129 -127.540271) (xy 433.98832 -127.575962) (xy 434.024011 -127.617153) (xy 434.053477 -127.663003)
			(xy 434.076119 -127.71258) (xy 434.091474 -127.764875) (xy 434.09923 -127.818823) (xy 434.099716 -127.846074)
			(xy 434.099297 -127.872454) (xy 434.092035 -127.924712) (xy 434.077645 -127.975473) (xy 434.056402 -128.023768)
			(xy 434.028711 -128.068677) (xy 433.995099 -128.109345) (xy 433.956207 -128.144997) (xy 433.912775 -128.174953)
			(xy 433.889404 -128.187196) (xy 433.877071 -128.193938) (xy 433.856351 -128.21291) (xy 433.841595 -128.236816)
			(xy 433.833924 -128.263842) (xy 433.833921 -128.291935) (xy 433.841586 -128.318963) (xy 433.856336 -128.342872)
			(xy 433.877052 -128.361848) (xy 433.889404 -128.368552) (xy 433.912764 -128.380812) (xy 433.956188 -128.410771)
			(xy 433.995074 -128.446424) (xy 434.028681 -128.487091) (xy 434.056369 -128.531997) (xy 434.077611 -128.580288)
			(xy 434.092002 -128.631043) (xy 434.099269 -128.683296) (xy 434.099716 -128.709674) (xy 434.09923 -128.736925)
			(xy 434.091474 -128.790873) (xy 434.076119 -128.843168) (xy 434.053477 -128.892745) (xy 434.024011 -128.938595)
			(xy 433.98832 -128.979786) (xy 433.947129 -129.015477) (xy 433.901279 -129.044943) (xy 433.851702 -129.067585)
			(xy 433.799407 -129.08294) (xy 433.745459 -129.090696) (xy 433.690957 -129.090696) (xy 433.637009 -129.08294)
			(xy 433.584714 -129.067585) (xy 433.535137 -129.044943) (xy 433.489287 -129.015477) (xy 433.448096 -128.979786)
			(xy 433.412405 -128.938595) (xy 433.382939 -128.892745) (xy 433.360297 -128.843168) (xy 433.344942 -128.790873)
			(xy 433.337186 -128.736925) (xy 433.3367 -128.709674) (xy 414.698249 -128.709674) (xy 410.18968 -133.218174)
		)
		(stroke
			(width 0)
			(type solid)
		)
		(fill yes)
		(layer "In13.Cu")
		(net "GND")
	)
	(gr_poly
		(pts
			(xy 336.311494 -63.031878) (xy 336.794094 -63.031878) (xy 336.802222 -63.029084) (xy 336.832987 -63.018929)
			(xy 336.896832 -63.007954) (xy 336.929222 -63.00724) (xy 336.961613 -63.007943) (xy 337.02546 -63.018918)
			(xy 337.056222 -63.029084) (xy 337.06435 -63.031878) (xy 337.09483 -63.031878) (xy 342.471756 -57.654952)
			(xy 342.471756 -56.63819) (xy 342.455931 -56.616491) (xy 342.430789 -56.569037) (xy 342.413651 -56.518142)
			(xy 342.404968 -56.465145) (xy 342.404969 -56.411442) (xy 342.413654 -56.358446) (xy 342.430794 -56.307552)
			(xy 342.455938 -56.260098) (xy 342.471756 -56.238394) (xy 342.471756 -55.69839) (xy 342.455931 -55.676691)
			(xy 342.430789 -55.629237) (xy 342.413651 -55.578342) (xy 342.404968 -55.525345) (xy 342.404969 -55.471642)
			(xy 342.413654 -55.418646) (xy 342.430794 -55.367752) (xy 342.455938 -55.320298) (xy 342.471756 -55.298594)
			(xy 342.471756 -54.75859) (xy 342.455931 -54.736891) (xy 342.430789 -54.689437) (xy 342.413651 -54.638542)
			(xy 342.404968 -54.585545) (xy 342.404969 -54.531842) (xy 342.413654 -54.478846) (xy 342.430794 -54.427952)
			(xy 342.455938 -54.380498) (xy 342.471756 -54.358794) (xy 342.471756 -53.81879) (xy 342.455931 -53.797091)
			(xy 342.430789 -53.749637) (xy 342.413651 -53.698742) (xy 342.404968 -53.645745) (xy 342.404969 -53.592042)
			(xy 342.413654 -53.539046) (xy 342.430794 -53.488152) (xy 342.455938 -53.440698) (xy 342.471756 -53.418994)
			(xy 342.471756 -50.996088) (xy 342.456514 -50.974611) (xy 342.432317 -50.927838) (xy 342.415838 -50.877821)
			(xy 342.407494 -50.825824) (xy 342.407495 -50.773163) (xy 342.415841 -50.721167) (xy 342.432322 -50.671151)
			(xy 342.456521 -50.624378) (xy 342.471756 -50.602896) (xy 342.471756 -50.05959) (xy 342.455931 -50.037891)
			(xy 342.430789 -49.990437) (xy 342.413651 -49.939542) (xy 342.404968 -49.886545) (xy 342.404969 -49.832842)
			(xy 342.413654 -49.779846) (xy 342.430794 -49.728952) (xy 342.455938 -49.681498) (xy 342.471756 -49.659794)
			(xy 342.471756 -49.11979) (xy 342.455931 -49.098091) (xy 342.430789 -49.050636) (xy 342.413651 -48.999741)
			(xy 342.404968 -48.946744) (xy 342.404446 -48.919892) (xy 342.404901 -48.894929) (xy 342.412404 -48.845568)
			(xy 342.427238 -48.797896) (xy 342.449067 -48.752994) (xy 342.462866 -48.732186) (xy 342.471756 -48.719232)
			(xy 342.471756 -48.613822) (xy 342.39327 -48.535336) (xy 342.382704 -48.525531) (xy 342.357414 -48.511725)
			(xy 342.329275 -48.505531) (xy 342.300526 -48.507439) (xy 342.273453 -48.517299) (xy 342.25021 -48.534326)
			(xy 342.232646 -48.557166) (xy 342.2269 -48.570388) (xy 342.217477 -48.593325) (xy 342.192761 -48.636313)
			(xy 342.161905 -48.675129) (xy 342.125599 -48.708903) (xy 342.084657 -48.736878) (xy 342.039998 -48.758427)
			(xy 341.992622 -48.773067) (xy 341.943591 -48.78047) (xy 341.918798 -48.780954) (xy 341.89281 -48.780444)
			(xy 341.841473 -48.772314) (xy 341.792039 -48.756253) (xy 341.745727 -48.732658) (xy 341.703675 -48.702109)
			(xy 341.66692 -48.665358) (xy 341.636365 -48.623311) (xy 341.612764 -48.577001) (xy 341.596696 -48.52757)
			(xy 341.588559 -48.476234) (xy 341.58809 -48.450246) (xy 341.58853 -48.425449) (xy 341.595928 -48.376409)
			(xy 341.610567 -48.329024) (xy 341.632117 -48.284356) (xy 341.660096 -48.243407) (xy 341.693876 -48.207095)
			(xy 341.732699 -48.176234) (xy 341.775695 -48.151516) (xy 341.798656 -48.142144) (xy 341.811929 -48.136463)
			(xy 341.834844 -48.118922) (xy 341.85193 -48.095665) (xy 341.86182 -48.068555) (xy 341.863722 -48.039759)
			(xy 341.857485 -48.011583) (xy 341.843607 -47.986281) (xy 341.833708 -47.975774) (xy 341.212678 -47.354744)
			(xy 341.184992 -47.361602) (xy 341.165552 -47.366094) (xy 341.125947 -47.370939) (xy 341.105998 -47.371254)
			(xy 341.08001 -47.370744) (xy 341.028673 -47.362614) (xy 340.979239 -47.346553) (xy 340.932927 -47.322958)
			(xy 340.890875 -47.292409) (xy 340.85412 -47.255658) (xy 340.823565 -47.213611) (xy 340.799964 -47.167301)
			(xy 340.783896 -47.11787) (xy 340.775759 -47.066534) (xy 340.77529 -47.040546) (xy 340.775713 -47.01669)
			(xy 340.782581 -46.969476) (xy 340.796167 -46.92374) (xy 340.816187 -46.880432) (xy 340.842227 -46.840453)
			(xy 340.873745 -46.804634) (xy 340.891622 -46.788832) (xy 340.891622 -46.35246) (xy 340.873722 -46.336683)
			(xy 340.842204 -46.30086) (xy 340.816166 -46.260877) (xy 340.796151 -46.217564) (xy 340.782574 -46.171822)
			(xy 340.775718 -46.124603) (xy 340.77529 -46.100746) (xy 340.77537 -46.091071) (xy 340.776516 -46.071755)
			(xy 340.777576 -46.062138) (xy 340.738384 -46.0474) (xy 340.662492 -46.012007) (xy 340.589973 -45.970134)
			(xy 340.521381 -45.922099) (xy 340.489032 -45.895514) (xy 340.467417 -45.911033) (xy 340.42027 -45.935695)
			(xy 340.369785 -45.952496) (xy 340.317262 -45.961003) (xy 340.290658 -45.961554) (xy 340.264672 -45.961041)
			(xy 340.21334 -45.952906) (xy 340.163912 -45.936842) (xy 340.117605 -45.913244) (xy 340.075558 -45.882695)
			(xy 340.038808 -45.845945) (xy 340.008258 -45.803899) (xy 339.98466 -45.757592) (xy 339.968595 -45.708164)
			(xy 339.960459 -45.656832) (xy 339.95995 -45.630846) (xy 339.960394 -45.606688) (xy 339.967431 -45.558888)
			(xy 339.981349 -45.51262) (xy 340.00185 -45.468869) (xy 340.028498 -45.428567) (xy 340.060726 -45.392571)
			(xy 340.097849 -45.361647) (xy 340.139077 -45.336453) (xy 340.161118 -45.326554) (xy 340.154352 -45.285486)
			(xy 340.147107 -45.202565) (xy 340.14664 -45.160946) (xy 340.146962 -45.127623) (xy 340.151669 -45.061141)
			(xy 340.156038 -45.028104) (xy 340.130779 -45.020046) (xy 340.083023 -44.997022) (xy 340.039551 -44.966674)
			(xy 340.001478 -44.929779) (xy 339.969778 -44.887284) (xy 339.945264 -44.840275) (xy 339.928563 -44.789958)
			(xy 339.920104 -44.73762) (xy 339.919564 -44.711112) (xy 339.919792 -44.692604) (xy 339.923862 -44.655814)
			(xy 339.927692 -44.637706) (xy 339.934042 -44.610528) (xy 339.748114 -44.4246) (xy 338.908898 -44.4246)
			(xy 338.5947 -44.738798) (xy 338.5947 -48.006333) (xy 340.7758 -48.006333) (xy 340.7758 -47.954359)
			(xy 340.78393 -47.903024) (xy 340.799991 -47.853594) (xy 340.823587 -47.807284) (xy 340.854137 -47.765236)
			(xy 340.890888 -47.728485) (xy 340.932936 -47.697935) (xy 340.979246 -47.674339) (xy 341.028676 -47.658278)
			(xy 341.080011 -47.650148) (xy 341.131985 -47.650148) (xy 341.18332 -47.658278) (xy 341.23275 -47.674339)
			(xy 341.27906 -47.697935) (xy 341.321108 -47.728485) (xy 341.357859 -47.765236) (xy 341.388409 -47.807284)
			(xy 341.412005 -47.853594) (xy 341.428066 -47.903024) (xy 341.436196 -47.954359) (xy 341.436706 -47.980346)
			(xy 341.436196 -48.006333) (xy 341.428066 -48.057668) (xy 341.412005 -48.107098) (xy 341.388409 -48.153408)
			(xy 341.357859 -48.195456) (xy 341.321108 -48.232207) (xy 341.27906 -48.262757) (xy 341.23275 -48.286353)
			(xy 341.18332 -48.302414) (xy 341.131985 -48.310544) (xy 341.080011 -48.310544) (xy 341.028676 -48.302414)
			(xy 340.979246 -48.286353) (xy 340.932936 -48.262757) (xy 340.890888 -48.232207) (xy 340.854137 -48.195456)
			(xy 340.823587 -48.153408) (xy 340.799991 -48.107098) (xy 340.78393 -48.057668) (xy 340.7758 -48.006333)
			(xy 338.5947 -48.006333) (xy 338.5947 -48.476233) (xy 339.96046 -48.476233) (xy 339.96046 -48.424259)
			(xy 339.96859 -48.372924) (xy 339.984651 -48.323494) (xy 340.008247 -48.277184) (xy 340.038797 -48.235136)
			(xy 340.075548 -48.198385) (xy 340.117596 -48.167835) (xy 340.163906 -48.144239) (xy 340.213336 -48.128178)
			(xy 340.264671 -48.120048) (xy 340.316645 -48.120048) (xy 340.36798 -48.128178) (xy 340.41741 -48.144239)
			(xy 340.46372 -48.167835) (xy 340.505768 -48.198385) (xy 340.542519 -48.235136) (xy 340.573069 -48.277184)
			(xy 340.596665 -48.323494) (xy 340.612726 -48.372924) (xy 340.620856 -48.424259) (xy 340.621366 -48.450246)
			(xy 340.620856 -48.476233) (xy 340.612726 -48.527568) (xy 340.596665 -48.576998) (xy 340.573069 -48.623308)
			(xy 340.542519 -48.665356) (xy 340.505768 -48.702107) (xy 340.46372 -48.732657) (xy 340.41741 -48.756253)
			(xy 340.36798 -48.772314) (xy 340.316645 -48.780444) (xy 340.264671 -48.780444) (xy 340.213336 -48.772314)
			(xy 340.163906 -48.756253) (xy 340.117596 -48.732657) (xy 340.075548 -48.702107) (xy 340.038797 -48.665356)
			(xy 340.008247 -48.623308) (xy 339.984651 -48.576998) (xy 339.96859 -48.527568) (xy 339.96046 -48.476233)
			(xy 338.5947 -48.476233) (xy 338.5947 -48.801528) (xy 338.450095 -48.946133) (xy 340.7758 -48.946133)
			(xy 340.7758 -48.894159) (xy 340.78393 -48.842824) (xy 340.799991 -48.793394) (xy 340.823587 -48.747084)
			(xy 340.854137 -48.705036) (xy 340.890888 -48.668285) (xy 340.932936 -48.637735) (xy 340.979246 -48.614139)
			(xy 341.028676 -48.598078) (xy 341.080011 -48.589948) (xy 341.131985 -48.589948) (xy 341.18332 -48.598078)
			(xy 341.23275 -48.614139) (xy 341.27906 -48.637735) (xy 341.321108 -48.668285) (xy 341.357859 -48.705036)
			(xy 341.388409 -48.747084) (xy 341.412005 -48.793394) (xy 341.428066 -48.842824) (xy 341.436196 -48.894159)
			(xy 341.436706 -48.920146) (xy 341.436196 -48.946133) (xy 341.428066 -48.997468) (xy 341.412005 -49.046898)
			(xy 341.388409 -49.093208) (xy 341.357859 -49.135256) (xy 341.321108 -49.172007) (xy 341.27906 -49.202557)
			(xy 341.23275 -49.226153) (xy 341.18332 -49.242214) (xy 341.131985 -49.250344) (xy 341.080011 -49.250344)
			(xy 341.028676 -49.242214) (xy 340.979246 -49.226153) (xy 340.932936 -49.202557) (xy 340.890888 -49.172007)
			(xy 340.854137 -49.135256) (xy 340.823587 -49.093208) (xy 340.799991 -49.046898) (xy 340.78393 -48.997468)
			(xy 340.7758 -48.946133) (xy 338.450095 -48.946133) (xy 338.378038 -49.01819) (xy 338.378038 -49.47158)
			(xy 338.392203 -49.494583) (xy 338.41366 -49.544156) (xy 338.426767 -49.596559) (xy 338.431176 -49.650397)
			(xy 338.429048 -49.676383) (xy 338.56981 -49.676383) (xy 338.56981 -49.624409) (xy 338.57794 -49.573074)
			(xy 338.594001 -49.523644) (xy 338.617597 -49.477334) (xy 338.648147 -49.435286) (xy 338.684898 -49.398535)
			(xy 338.726946 -49.367985) (xy 338.773256 -49.344389) (xy 338.822686 -49.328328) (xy 338.874021 -49.320198)
			(xy 338.925995 -49.320198) (xy 338.97733 -49.328328) (xy 339.02676 -49.344389) (xy 339.07307 -49.367985)
			(xy 339.115118 -49.398535) (xy 339.132616 -49.416033) (xy 341.5886 -49.416033) (xy 341.5886 -49.364059)
			(xy 341.59673 -49.312724) (xy 341.612791 -49.263294) (xy 341.636387 -49.216984) (xy 341.666937 -49.174936)
			(xy 341.703688 -49.138185) (xy 341.745736 -49.107635) (xy 341.792046 -49.084039) (xy 341.841476 -49.067978)
			(xy 341.892811 -49.059848) (xy 341.944785 -49.059848) (xy 341.99612 -49.067978) (xy 342.04555 -49.084039)
			(xy 342.09186 -49.107635) (xy 342.133908 -49.138185) (xy 342.170659 -49.174936) (xy 342.201209 -49.216984)
			(xy 342.224805 -49.263294) (xy 342.240866 -49.312724) (xy 342.248996 -49.364059) (xy 342.249506 -49.390046)
			(xy 342.248996 -49.416033) (xy 342.240866 -49.467368) (xy 342.224805 -49.516798) (xy 342.201209 -49.563108)
			(xy 342.170659 -49.605156) (xy 342.133908 -49.641907) (xy 342.09186 -49.672457) (xy 342.04555 -49.696053)
			(xy 341.99612 -49.712114) (xy 341.944785 -49.720244) (xy 341.892811 -49.720244) (xy 341.841476 -49.712114)
			(xy 341.792046 -49.696053) (xy 341.745736 -49.672457) (xy 341.703688 -49.641907) (xy 341.666937 -49.605156)
			(xy 341.636387 -49.563108) (xy 341.612791 -49.516798) (xy 341.59673 -49.467368) (xy 341.5886 -49.416033)
			(xy 339.132616 -49.416033) (xy 339.151869 -49.435286) (xy 339.182419 -49.477334) (xy 339.206015 -49.523644)
			(xy 339.222076 -49.573074) (xy 339.230206 -49.624409) (xy 339.230716 -49.650396) (xy 339.230206 -49.676383)
			(xy 339.222076 -49.727718) (xy 339.206015 -49.777148) (xy 339.182419 -49.823458) (xy 339.151869 -49.865506)
			(xy 339.115118 -49.902257) (xy 339.07307 -49.932807) (xy 339.02676 -49.956403) (xy 338.97733 -49.972464)
			(xy 338.925995 -49.980594) (xy 338.874021 -49.980594) (xy 338.822686 -49.972464) (xy 338.773256 -49.956403)
			(xy 338.726946 -49.932807) (xy 338.684898 -49.902257) (xy 338.648147 -49.865506) (xy 338.617597 -49.823458)
			(xy 338.594001 -49.777148) (xy 338.57794 -49.727718) (xy 338.56981 -49.676383) (xy 338.429048 -49.676383)
			(xy 338.426768 -49.704234) (xy 338.413662 -49.756638) (xy 338.392206 -49.806212) (xy 338.378038 -49.829212)
			(xy 338.378038 -50.476483) (xy 339.36991 -50.476483) (xy 339.36991 -50.424509) (xy 339.37804 -50.373174)
			(xy 339.394101 -50.323744) (xy 339.417697 -50.277434) (xy 339.448247 -50.235386) (xy 339.484998 -50.198635)
			(xy 339.527046 -50.168085) (xy 339.573356 -50.144489) (xy 339.622786 -50.128428) (xy 339.674121 -50.120298)
			(xy 339.726095 -50.120298) (xy 339.77743 -50.128428) (xy 339.82686 -50.144489) (xy 339.87317 -50.168085)
			(xy 339.915218 -50.198635) (xy 339.951969 -50.235386) (xy 339.982519 -50.277434) (xy 340.006115 -50.323744)
			(xy 340.016541 -50.355833) (xy 341.59114 -50.355833) (xy 341.59114 -50.303859) (xy 341.59927 -50.252524)
			(xy 341.615331 -50.203094) (xy 341.638927 -50.156784) (xy 341.669477 -50.114736) (xy 341.706228 -50.077985)
			(xy 341.748276 -50.047435) (xy 341.794586 -50.023839) (xy 341.844016 -50.007778) (xy 341.895351 -49.999648)
			(xy 341.947325 -49.999648) (xy 341.99866 -50.007778) (xy 342.04809 -50.023839) (xy 342.0944 -50.047435)
			(xy 342.136448 -50.077985) (xy 342.173199 -50.114736) (xy 342.203749 -50.156784) (xy 342.227345 -50.203094)
			(xy 342.243406 -50.252524) (xy 342.251536 -50.303859) (xy 342.252046 -50.329846) (xy 342.251536 -50.355833)
			(xy 342.243406 -50.407168) (xy 342.227345 -50.456598) (xy 342.203749 -50.502908) (xy 342.173199 -50.544956)
			(xy 342.136448 -50.581707) (xy 342.0944 -50.612257) (xy 342.04809 -50.635853) (xy 341.99866 -50.651914)
			(xy 341.947325 -50.660044) (xy 341.895351 -50.660044) (xy 341.844016 -50.651914) (xy 341.794586 -50.635853)
			(xy 341.748276 -50.612257) (xy 341.706228 -50.581707) (xy 341.669477 -50.544956) (xy 341.638927 -50.502908)
			(xy 341.615331 -50.456598) (xy 341.59927 -50.407168) (xy 341.59114 -50.355833) (xy 340.016541 -50.355833)
			(xy 340.022176 -50.373174) (xy 340.030306 -50.424509) (xy 340.030816 -50.450496) (xy 340.030306 -50.476483)
			(xy 340.022176 -50.527818) (xy 340.006115 -50.577248) (xy 339.982519 -50.623558) (xy 339.951969 -50.665606)
			(xy 339.915218 -50.702357) (xy 339.87317 -50.732907) (xy 339.82686 -50.756503) (xy 339.77743 -50.772564)
			(xy 339.726095 -50.780694) (xy 339.674121 -50.780694) (xy 339.622786 -50.772564) (xy 339.573356 -50.756503)
			(xy 339.527046 -50.732907) (xy 339.484998 -50.702357) (xy 339.448247 -50.665606) (xy 339.417697 -50.623558)
			(xy 339.394101 -50.577248) (xy 339.37804 -50.527818) (xy 339.36991 -50.476483) (xy 338.378038 -50.476483)
			(xy 338.378038 -51.26863) (xy 338.351024 -51.295633) (xy 339.96046 -51.295633) (xy 339.96046 -51.243659)
			(xy 339.96859 -51.192324) (xy 339.984651 -51.142894) (xy 340.008247 -51.096584) (xy 340.038797 -51.054536)
			(xy 340.075548 -51.017785) (xy 340.117596 -50.987235) (xy 340.163906 -50.963639) (xy 340.213336 -50.947578)
			(xy 340.264671 -50.939448) (xy 340.316645 -50.939448) (xy 340.36798 -50.947578) (xy 340.41741 -50.963639)
			(xy 340.46372 -50.987235) (xy 340.505768 -51.017785) (xy 340.542519 -51.054536) (xy 340.573069 -51.096584)
			(xy 340.596665 -51.142894) (xy 340.612726 -51.192324) (xy 340.620856 -51.243659) (xy 340.621366 -51.269646)
			(xy 340.620856 -51.295633) (xy 341.59114 -51.295633) (xy 341.59114 -51.243659) (xy 341.59927 -51.192324)
			(xy 341.615331 -51.142894) (xy 341.638927 -51.096584) (xy 341.669477 -51.054536) (xy 341.706228 -51.017785)
			(xy 341.748276 -50.987235) (xy 341.794586 -50.963639) (xy 341.844016 -50.947578) (xy 341.895351 -50.939448)
			(xy 341.947325 -50.939448) (xy 341.99866 -50.947578) (xy 342.04809 -50.963639) (xy 342.0944 -50.987235)
			(xy 342.136448 -51.017785) (xy 342.173199 -51.054536) (xy 342.203749 -51.096584) (xy 342.227345 -51.142894)
			(xy 342.243406 -51.192324) (xy 342.251536 -51.243659) (xy 342.252046 -51.269646) (xy 342.251536 -51.295633)
			(xy 342.243406 -51.346968) (xy 342.227345 -51.396398) (xy 342.203749 -51.442708) (xy 342.173199 -51.484756)
			(xy 342.136448 -51.521507) (xy 342.0944 -51.552057) (xy 342.04809 -51.575653) (xy 341.99866 -51.591714)
			(xy 341.947325 -51.599844) (xy 341.895351 -51.599844) (xy 341.844016 -51.591714) (xy 341.794586 -51.575653)
			(xy 341.748276 -51.552057) (xy 341.706228 -51.521507) (xy 341.669477 -51.484756) (xy 341.638927 -51.442708)
			(xy 341.615331 -51.396398) (xy 341.59927 -51.346968) (xy 341.59114 -51.295633) (xy 340.620856 -51.295633)
			(xy 340.612726 -51.346968) (xy 340.596665 -51.396398) (xy 340.573069 -51.442708) (xy 340.542519 -51.484756)
			(xy 340.505768 -51.521507) (xy 340.46372 -51.552057) (xy 340.41741 -51.575653) (xy 340.36798 -51.591714)
			(xy 340.316645 -51.599844) (xy 340.264671 -51.599844) (xy 340.213336 -51.591714) (xy 340.163906 -51.575653)
			(xy 340.117596 -51.552057) (xy 340.075548 -51.521507) (xy 340.038797 -51.484756) (xy 340.008247 -51.442708)
			(xy 339.984651 -51.396398) (xy 339.96859 -51.346968) (xy 339.96046 -51.295633) (xy 338.351024 -51.295633)
			(xy 337.767676 -51.878738) (xy 337.767676 -52.521437) (xy 339.29371 -52.521437) (xy 339.29371 -52.469463)
			(xy 339.30184 -52.418128) (xy 339.317901 -52.368698) (xy 339.341497 -52.322388) (xy 339.372047 -52.28034)
			(xy 339.408798 -52.243589) (xy 339.450846 -52.213039) (xy 339.497156 -52.189443) (xy 339.546586 -52.173382)
			(xy 339.597921 -52.165252) (xy 339.649895 -52.165252) (xy 339.70123 -52.173382) (xy 339.75066 -52.189443)
			(xy 339.79697 -52.213039) (xy 339.839018 -52.243589) (xy 339.875769 -52.28034) (xy 339.906319 -52.322388)
			(xy 339.929915 -52.368698) (xy 339.945976 -52.418128) (xy 339.954106 -52.469463) (xy 339.954616 -52.49545)
			(xy 339.954106 -52.521437) (xy 339.945976 -52.572772) (xy 339.929915 -52.622202) (xy 339.906319 -52.668512)
			(xy 339.875769 -52.71056) (xy 339.839018 -52.747311) (xy 339.79697 -52.777861) (xy 339.75066 -52.801457)
			(xy 339.70123 -52.817518) (xy 339.649895 -52.825648) (xy 339.597921 -52.825648) (xy 339.546586 -52.817518)
			(xy 339.497156 -52.801457) (xy 339.450846 -52.777861) (xy 339.408798 -52.747311) (xy 339.372047 -52.71056)
			(xy 339.341497 -52.668512) (xy 339.317901 -52.622202) (xy 339.30184 -52.572772) (xy 339.29371 -52.521437)
			(xy 337.767676 -52.521437) (xy 337.767676 -52.875688) (xy 337.787925 -52.889991) (xy 337.824301 -52.923672)
			(xy 337.855243 -52.962405) (xy 337.880057 -53.005322) (xy 337.898189 -53.051461) (xy 337.909231 -53.09979)
			(xy 337.912937 -53.149226) (xy 337.910983 -53.175233) (xy 339.96046 -53.175233) (xy 339.96046 -53.123259)
			(xy 339.96859 -53.071924) (xy 339.984651 -53.022494) (xy 340.008247 -52.976184) (xy 340.038797 -52.934136)
			(xy 340.075548 -52.897385) (xy 340.117596 -52.866835) (xy 340.163906 -52.843239) (xy 340.213336 -52.827178)
			(xy 340.264671 -52.819048) (xy 340.316645 -52.819048) (xy 340.36798 -52.827178) (xy 340.41741 -52.843239)
			(xy 340.46372 -52.866835) (xy 340.505768 -52.897385) (xy 340.542519 -52.934136) (xy 340.573069 -52.976184)
			(xy 340.596665 -53.022494) (xy 340.612726 -53.071924) (xy 340.620856 -53.123259) (xy 340.621366 -53.149246)
			(xy 340.620861 -53.174979) (xy 341.59114 -53.174979) (xy 341.59114 -53.123005) (xy 341.59927 -53.07167)
			(xy 341.615331 -53.02224) (xy 341.638927 -52.97593) (xy 341.669477 -52.933882) (xy 341.706228 -52.897131)
			(xy 341.748276 -52.866581) (xy 341.794586 -52.842985) (xy 341.844016 -52.826924) (xy 341.895351 -52.818794)
			(xy 341.947325 -52.818794) (xy 341.99866 -52.826924) (xy 342.04809 -52.842985) (xy 342.0944 -52.866581)
			(xy 342.136448 -52.897131) (xy 342.173199 -52.933882) (xy 342.203749 -52.97593) (xy 342.227345 -53.02224)
			(xy 342.243406 -53.07167) (xy 342.251536 -53.123005) (xy 342.252046 -53.148992) (xy 342.251536 -53.174979)
			(xy 342.243406 -53.226314) (xy 342.227345 -53.275744) (xy 342.203749 -53.322054) (xy 342.173199 -53.364102)
			(xy 342.136448 -53.400853) (xy 342.0944 -53.431403) (xy 342.04809 -53.454999) (xy 341.99866 -53.47106)
			(xy 341.947325 -53.47919) (xy 341.895351 -53.47919) (xy 341.844016 -53.47106) (xy 341.794586 -53.454999)
			(xy 341.748276 -53.431403) (xy 341.706228 -53.400853) (xy 341.669477 -53.364102) (xy 341.638927 -53.322054)
			(xy 341.615331 -53.275744) (xy 341.59927 -53.226314) (xy 341.59114 -53.174979) (xy 340.620861 -53.174979)
			(xy 340.620856 -53.175233) (xy 340.612726 -53.226568) (xy 340.596665 -53.275998) (xy 340.573069 -53.322308)
			(xy 340.542519 -53.364356) (xy 340.505768 -53.401107) (xy 340.46372 -53.431657) (xy 340.41741 -53.455253)
			(xy 340.36798 -53.471314) (xy 340.316645 -53.479444) (xy 340.264671 -53.479444) (xy 340.213336 -53.471314)
			(xy 340.163906 -53.455253) (xy 340.117596 -53.431657) (xy 340.075548 -53.401107) (xy 340.038797 -53.364356)
			(xy 340.008247 -53.322308) (xy 339.984651 -53.275998) (xy 339.96859 -53.226568) (xy 339.96046 -53.175233)
			(xy 337.910983 -53.175233) (xy 337.909223 -53.198661) (xy 337.898173 -53.246988) (xy 337.880035 -53.293125)
			(xy 337.855213 -53.336038) (xy 337.824266 -53.374766) (xy 337.787884 -53.408441) (xy 337.767676 -53.422804)
			(xy 337.767676 -53.645133) (xy 338.06435 -53.645133) (xy 338.06435 -53.593159) (xy 338.07248 -53.541824)
			(xy 338.088541 -53.492394) (xy 338.112137 -53.446084) (xy 338.142687 -53.404036) (xy 338.179438 -53.367285)
			(xy 338.221486 -53.336735) (xy 338.267796 -53.313139) (xy 338.317226 -53.297078) (xy 338.368561 -53.288948)
			(xy 338.420535 -53.288948) (xy 338.47187 -53.297078) (xy 338.5213 -53.313139) (xy 338.56761 -53.336735)
			(xy 338.609658 -53.367285) (xy 338.646409 -53.404036) (xy 338.676959 -53.446084) (xy 338.700555 -53.492394)
			(xy 338.716616 -53.541824) (xy 338.724746 -53.593159) (xy 338.725256 -53.619146) (xy 338.724746 -53.645133)
			(xy 338.716616 -53.696468) (xy 338.700555 -53.745898) (xy 338.676959 -53.792208) (xy 338.646409 -53.834256)
			(xy 338.609658 -53.871007) (xy 338.56761 -53.901557) (xy 338.5213 -53.925153) (xy 338.47187 -53.941214)
			(xy 338.420535 -53.949344) (xy 338.368561 -53.949344) (xy 338.317226 -53.941214) (xy 338.267796 -53.925153)
			(xy 338.221486 -53.901557) (xy 338.179438 -53.871007) (xy 338.142687 -53.834256) (xy 338.112137 -53.792208)
			(xy 338.088541 -53.745898) (xy 338.07248 -53.696468) (xy 338.06435 -53.645133) (xy 337.767676 -53.645133)
			(xy 337.767676 -53.785516) (xy 337.789594 -53.799478) (xy 337.82951 -53.832753) (xy 337.864164 -53.871479)
			(xy 337.89282 -53.914831) (xy 337.914868 -53.961888) (xy 337.92984 -54.011652) (xy 337.937417 -54.063063)
			(xy 337.937856 -54.089046) (xy 337.937369 -54.115033) (xy 341.59114 -54.115033) (xy 341.59114 -54.063059)
			(xy 341.59927 -54.011724) (xy 341.615331 -53.962294) (xy 341.638927 -53.915984) (xy 341.669477 -53.873936)
			(xy 341.706228 -53.837185) (xy 341.748276 -53.806635) (xy 341.794586 -53.783039) (xy 341.844016 -53.766978)
			(xy 341.895351 -53.758848) (xy 341.947325 -53.758848) (xy 341.99866 -53.766978) (xy 342.04809 -53.783039)
			(xy 342.0944 -53.806635) (xy 342.136448 -53.837185) (xy 342.173199 -53.873936) (xy 342.203749 -53.915984)
			(xy 342.227345 -53.962294) (xy 342.243406 -54.011724) (xy 342.251536 -54.063059) (xy 342.252046 -54.089046)
			(xy 342.251536 -54.115033) (xy 342.243406 -54.166368) (xy 342.227345 -54.215798) (xy 342.203749 -54.262108)
			(xy 342.173199 -54.304156) (xy 342.136448 -54.340907) (xy 342.0944 -54.371457) (xy 342.04809 -54.395053)
			(xy 341.99866 -54.411114) (xy 341.947325 -54.419244) (xy 341.895351 -54.419244) (xy 341.844016 -54.411114)
			(xy 341.794586 -54.395053) (xy 341.748276 -54.371457) (xy 341.706228 -54.340907) (xy 341.669477 -54.304156)
			(xy 341.638927 -54.262108) (xy 341.615331 -54.215798) (xy 341.59927 -54.166368) (xy 341.59114 -54.115033)
			(xy 337.937369 -54.115033) (xy 337.937332 -54.117022) (xy 337.928569 -54.172283) (xy 337.911266 -54.225492)
			(xy 337.885849 -54.275338) (xy 337.852945 -54.320592) (xy 337.813365 -54.360139) (xy 337.768083 -54.393005)
			(xy 337.718216 -54.41838) (xy 337.664993 -54.435638) (xy 337.609724 -54.444355) (xy 337.581748 -54.4449)
			(xy 337.305142 -54.4449) (xy 337.165109 -54.584933) (xy 338.06435 -54.584933) (xy 338.06435 -54.532959)
			(xy 338.07248 -54.481624) (xy 338.088541 -54.432194) (xy 338.112137 -54.385884) (xy 338.142687 -54.343836)
			(xy 338.179438 -54.307085) (xy 338.221486 -54.276535) (xy 338.267796 -54.252939) (xy 338.317226 -54.236878)
			(xy 338.368561 -54.228748) (xy 338.420535 -54.228748) (xy 338.47187 -54.236878) (xy 338.5213 -54.252939)
			(xy 338.56761 -54.276535) (xy 338.609658 -54.307085) (xy 338.646409 -54.343836) (xy 338.676959 -54.385884)
			(xy 338.700555 -54.432194) (xy 338.716616 -54.481624) (xy 338.724746 -54.532959) (xy 338.725256 -54.558946)
			(xy 338.724746 -54.584933) (xy 339.14766 -54.584933) (xy 339.14766 -54.532959) (xy 339.15579 -54.481624)
			(xy 339.171851 -54.432194) (xy 339.195447 -54.385884) (xy 339.225997 -54.343836) (xy 339.262748 -54.307085)
			(xy 339.304796 -54.276535) (xy 339.351106 -54.252939) (xy 339.400536 -54.236878) (xy 339.451871 -54.228748)
			(xy 339.503845 -54.228748) (xy 339.55518 -54.236878) (xy 339.60461 -54.252939) (xy 339.65092 -54.276535)
			(xy 339.692968 -54.307085) (xy 339.729719 -54.343836) (xy 339.760269 -54.385884) (xy 339.783865 -54.432194)
			(xy 339.799926 -54.481624) (xy 339.808056 -54.532959) (xy 339.808566 -54.558946) (xy 339.808056 -54.584933)
			(xy 340.7758 -54.584933) (xy 340.7758 -54.532959) (xy 340.78393 -54.481624) (xy 340.799991 -54.432194)
			(xy 340.823587 -54.385884) (xy 340.854137 -54.343836) (xy 340.890888 -54.307085) (xy 340.932936 -54.276535)
			(xy 340.979246 -54.252939) (xy 341.028676 -54.236878) (xy 341.080011 -54.228748) (xy 341.131985 -54.228748)
			(xy 341.18332 -54.236878) (xy 341.23275 -54.252939) (xy 341.27906 -54.276535) (xy 341.321108 -54.307085)
			(xy 341.357859 -54.343836) (xy 341.388409 -54.385884) (xy 341.412005 -54.432194) (xy 341.428066 -54.481624)
			(xy 341.436196 -54.532959) (xy 341.436706 -54.558946) (xy 341.436196 -54.584933) (xy 341.428066 -54.636268)
			(xy 341.412005 -54.685698) (xy 341.388409 -54.732008) (xy 341.357859 -54.774056) (xy 341.321108 -54.810807)
			(xy 341.27906 -54.841357) (xy 341.23275 -54.864953) (xy 341.18332 -54.881014) (xy 341.131985 -54.889144)
			(xy 341.080011 -54.889144) (xy 341.028676 -54.881014) (xy 340.979246 -54.864953) (xy 340.932936 -54.841357)
			(xy 340.890888 -54.810807) (xy 340.854137 -54.774056) (xy 340.823587 -54.732008) (xy 340.799991 -54.685698)
			(xy 340.78393 -54.636268) (xy 340.7758 -54.584933) (xy 339.808056 -54.584933) (xy 339.799926 -54.636268)
			(xy 339.783865 -54.685698) (xy 339.760269 -54.732008) (xy 339.729719 -54.774056) (xy 339.692968 -54.810807)
			(xy 339.65092 -54.841357) (xy 339.60461 -54.864953) (xy 339.55518 -54.881014) (xy 339.503845 -54.889144)
			(xy 339.451871 -54.889144) (xy 339.400536 -54.881014) (xy 339.351106 -54.864953) (xy 339.304796 -54.841357)
			(xy 339.262748 -54.810807) (xy 339.225997 -54.774056) (xy 339.195447 -54.732008) (xy 339.171851 -54.685698)
			(xy 339.15579 -54.636268) (xy 339.14766 -54.584933) (xy 338.724746 -54.584933) (xy 338.716616 -54.636268)
			(xy 338.700555 -54.685698) (xy 338.676959 -54.732008) (xy 338.646409 -54.774056) (xy 338.609658 -54.810807)
			(xy 338.56761 -54.841357) (xy 338.5213 -54.864953) (xy 338.47187 -54.881014) (xy 338.420535 -54.889144)
			(xy 338.368561 -54.889144) (xy 338.317226 -54.881014) (xy 338.267796 -54.864953) (xy 338.221486 -54.841357)
			(xy 338.179438 -54.810807) (xy 338.142687 -54.774056) (xy 338.112137 -54.732008) (xy 338.088541 -54.685698)
			(xy 338.07248 -54.636268) (xy 338.06435 -54.584933) (xy 337.165109 -54.584933) (xy 337.145376 -54.604666)
			(xy 337.142836 -54.620922) (xy 337.138106 -54.646883) (xy 337.122434 -54.697271) (xy 337.099966 -54.745019)
			(xy 337.071133 -54.789214) (xy 337.036483 -54.829014) (xy 336.996679 -54.863659) (xy 336.952481 -54.892487)
			(xy 336.904731 -54.914949) (xy 336.854341 -54.930616) (xy 336.828384 -54.935374) (xy 336.812128 -54.937914)
			(xy 336.75193 -54.998366) (xy 336.742234 -55.008699) (xy 336.728457 -55.033448) (xy 336.723466 -55.054833)
			(xy 337.25155 -55.054833) (xy 337.25155 -55.002859) (xy 337.25968 -54.951524) (xy 337.275741 -54.902094)
			(xy 337.299337 -54.855784) (xy 337.329887 -54.813736) (xy 337.366638 -54.776985) (xy 337.408686 -54.746435)
			(xy 337.454996 -54.722839) (xy 337.504426 -54.706778) (xy 337.555761 -54.698648) (xy 337.607735 -54.698648)
			(xy 337.65907 -54.706778) (xy 337.7085 -54.722839) (xy 337.75481 -54.746435) (xy 337.796858 -54.776985)
			(xy 337.833609 -54.813736) (xy 337.864159 -54.855784) (xy 337.887755 -54.902094) (xy 337.903816 -54.951524)
			(xy 337.911946 -55.002859) (xy 337.912456 -55.028846) (xy 337.911946 -55.054833) (xy 339.96046 -55.054833)
			(xy 339.96046 -55.002859) (xy 339.96859 -54.951524) (xy 339.984651 -54.902094) (xy 340.008247 -54.855784)
			(xy 340.038797 -54.813736) (xy 340.075548 -54.776985) (xy 340.117596 -54.746435) (xy 340.163906 -54.722839)
			(xy 340.213336 -54.706778) (xy 340.264671 -54.698648) (xy 340.316645 -54.698648) (xy 340.36798 -54.706778)
			(xy 340.41741 -54.722839) (xy 340.46372 -54.746435) (xy 340.505768 -54.776985) (xy 340.542519 -54.813736)
			(xy 340.573069 -54.855784) (xy 340.596665 -54.902094) (xy 340.612726 -54.951524) (xy 340.620856 -55.002859)
			(xy 340.621366 -55.028846) (xy 340.620856 -55.054833) (xy 341.59114 -55.054833) (xy 341.59114 -55.002859)
			(xy 341.59927 -54.951524) (xy 341.615331 -54.902094) (xy 341.638927 -54.855784) (xy 341.669477 -54.813736)
			(xy 341.706228 -54.776985) (xy 341.748276 -54.746435) (xy 341.794586 -54.722839) (xy 341.844016 -54.706778)
			(xy 341.895351 -54.698648) (xy 341.947325 -54.698648) (xy 341.99866 -54.706778) (xy 342.04809 -54.722839)
			(xy 342.0944 -54.746435) (xy 342.136448 -54.776985) (xy 342.173199 -54.813736) (xy 342.203749 -54.855784)
			(xy 342.227345 -54.902094) (xy 342.243406 -54.951524) (xy 342.251536 -55.002859) (xy 342.252046 -55.028846)
			(xy 342.251536 -55.054833) (xy 342.243406 -55.106168) (xy 342.227345 -55.155598) (xy 342.203749 -55.201908)
			(xy 342.173199 -55.243956) (xy 342.136448 -55.280707) (xy 342.0944 -55.311257) (xy 342.04809 -55.334853)
			(xy 341.99866 -55.350914) (xy 341.947325 -55.359044) (xy 341.895351 -55.359044) (xy 341.844016 -55.350914)
			(xy 341.794586 -55.334853) (xy 341.748276 -55.311257) (xy 341.706228 -55.280707) (xy 341.669477 -55.243956)
			(xy 341.638927 -55.201908) (xy 341.615331 -55.155598) (xy 341.59927 -55.106168) (xy 341.59114 -55.054833)
			(xy 340.620856 -55.054833) (xy 340.612726 -55.106168) (xy 340.596665 -55.155598) (xy 340.573069 -55.201908)
			(xy 340.542519 -55.243956) (xy 340.505768 -55.280707) (xy 340.46372 -55.311257) (xy 340.41741 -55.334853)
			(xy 340.36798 -55.350914) (xy 340.316645 -55.359044) (xy 340.264671 -55.359044) (xy 340.213336 -55.350914)
			(xy 340.163906 -55.334853) (xy 340.117596 -55.311257) (xy 340.075548 -55.280707) (xy 340.038797 -55.243956)
			(xy 340.008247 -55.201908) (xy 339.984651 -55.155598) (xy 339.96859 -55.106168) (xy 339.96046 -55.054833)
			(xy 337.911946 -55.054833) (xy 337.903816 -55.106168) (xy 337.887755 -55.155598) (xy 337.864159 -55.201908)
			(xy 337.833609 -55.243956) (xy 337.796858 -55.280707) (xy 337.75481 -55.311257) (xy 337.7085 -55.334853)
			(xy 337.65907 -55.350914) (xy 337.607735 -55.359044) (xy 337.555761 -55.359044) (xy 337.504426 -55.350914)
			(xy 337.454996 -55.334853) (xy 337.408686 -55.311257) (xy 337.366638 -55.280707) (xy 337.329887 -55.243956)
			(xy 337.299337 -55.201908) (xy 337.275741 -55.155598) (xy 337.25968 -55.106168) (xy 337.25155 -55.054833)
			(xy 336.723466 -55.054833) (xy 336.722019 -55.061032) (xy 336.723414 -55.089323) (xy 336.732537 -55.116139)
			(xy 336.748683 -55.139411) (xy 336.770606 -55.157346) (xy 336.796617 -55.16856) (xy 336.810604 -55.170832)
			(xy 336.836795 -55.174786) (xy 336.887546 -55.189943) (xy 336.935232 -55.212995) (xy 336.978633 -55.243354)
			(xy 337.01664 -55.280244) (xy 337.04828 -55.32272) (xy 337.072745 -55.369697) (xy 337.089409 -55.419974)
			(xy 337.097844 -55.472263) (xy 337.098386 -55.498746) (xy 337.097873 -55.52473) (xy 337.097873 -55.524733)
			(xy 338.06435 -55.524733) (xy 338.06435 -55.472759) (xy 338.07248 -55.421424) (xy 338.088541 -55.371994)
			(xy 338.112137 -55.325684) (xy 338.142687 -55.283636) (xy 338.179438 -55.246885) (xy 338.221486 -55.216335)
			(xy 338.267796 -55.192739) (xy 338.317226 -55.176678) (xy 338.368561 -55.168548) (xy 338.420535 -55.168548)
			(xy 338.47187 -55.176678) (xy 338.5213 -55.192739) (xy 338.56761 -55.216335) (xy 338.609658 -55.246885)
			(xy 338.646409 -55.283636) (xy 338.676959 -55.325684) (xy 338.700555 -55.371994) (xy 338.716616 -55.421424)
			(xy 338.724746 -55.472759) (xy 338.725256 -55.498746) (xy 338.724746 -55.524733) (xy 339.14766 -55.524733)
			(xy 339.14766 -55.472759) (xy 339.15579 -55.421424) (xy 339.171851 -55.371994) (xy 339.195447 -55.325684)
			(xy 339.225997 -55.283636) (xy 339.262748 -55.246885) (xy 339.304796 -55.216335) (xy 339.351106 -55.192739)
			(xy 339.400536 -55.176678) (xy 339.451871 -55.168548) (xy 339.503845 -55.168548) (xy 339.55518 -55.176678)
			(xy 339.60461 -55.192739) (xy 339.65092 -55.216335) (xy 339.692968 -55.246885) (xy 339.729719 -55.283636)
			(xy 339.760269 -55.325684) (xy 339.783865 -55.371994) (xy 339.799926 -55.421424) (xy 339.808056 -55.472759)
			(xy 339.808566 -55.498746) (xy 339.808056 -55.524733) (xy 340.7758 -55.524733) (xy 340.7758 -55.472759)
			(xy 340.78393 -55.421424) (xy 340.799991 -55.371994) (xy 340.823587 -55.325684) (xy 340.854137 -55.283636)
			(xy 340.890888 -55.246885) (xy 340.932936 -55.216335) (xy 340.979246 -55.192739) (xy 341.028676 -55.176678)
			(xy 341.080011 -55.168548) (xy 341.131985 -55.168548) (xy 341.18332 -55.176678) (xy 341.23275 -55.192739)
			(xy 341.27906 -55.216335) (xy 341.321108 -55.246885) (xy 341.357859 -55.283636) (xy 341.388409 -55.325684)
			(xy 341.412005 -55.371994) (xy 341.428066 -55.421424) (xy 341.436196 -55.472759) (xy 341.436706 -55.498746)
			(xy 341.436196 -55.524733) (xy 341.428066 -55.576068) (xy 341.412005 -55.625498) (xy 341.388409 -55.671808)
			(xy 341.357859 -55.713856) (xy 341.321108 -55.750607) (xy 341.27906 -55.781157) (xy 341.23275 -55.804753)
			(xy 341.18332 -55.820814) (xy 341.131985 -55.828944) (xy 341.080011 -55.828944) (xy 341.028676 -55.820814)
			(xy 340.979246 -55.804753) (xy 340.932936 -55.781157) (xy 340.890888 -55.750607) (xy 340.854137 -55.713856)
			(xy 340.823587 -55.671808) (xy 340.799991 -55.625498) (xy 340.78393 -55.576068) (xy 340.7758 -55.524733)
			(xy 339.808056 -55.524733) (xy 339.799926 -55.576068) (xy 339.783865 -55.625498) (xy 339.760269 -55.671808)
			(xy 339.729719 -55.713856) (xy 339.692968 -55.750607) (xy 339.65092 -55.781157) (xy 339.60461 -55.804753)
			(xy 339.55518 -55.820814) (xy 339.503845 -55.828944) (xy 339.451871 -55.828944) (xy 339.400536 -55.820814)
			(xy 339.351106 -55.804753) (xy 339.304796 -55.781157) (xy 339.262748 -55.750607) (xy 339.225997 -55.713856)
			(xy 339.195447 -55.671808) (xy 339.171851 -55.625498) (xy 339.15579 -55.576068) (xy 339.14766 -55.524733)
			(xy 338.724746 -55.524733) (xy 338.716616 -55.576068) (xy 338.700555 -55.625498) (xy 338.676959 -55.671808)
			(xy 338.646409 -55.713856) (xy 338.609658 -55.750607) (xy 338.56761 -55.781157) (xy 338.5213 -55.804753)
			(xy 338.47187 -55.820814) (xy 338.420535 -55.828944) (xy 338.368561 -55.828944) (xy 338.317226 -55.820814)
			(xy 338.267796 -55.804753) (xy 338.221486 -55.781157) (xy 338.179438 -55.750607) (xy 338.142687 -55.713856)
			(xy 338.112137 -55.671808) (xy 338.088541 -55.625498) (xy 338.07248 -55.576068) (xy 338.06435 -55.524733)
			(xy 337.097873 -55.524733) (xy 337.089737 -55.576058) (xy 337.073671 -55.625481) (xy 337.050073 -55.671782)
			(xy 337.019522 -55.713822) (xy 336.982771 -55.750566) (xy 336.940724 -55.781108) (xy 336.894418 -55.804697)
			(xy 336.844992 -55.820752) (xy 336.793662 -55.828878) (xy 336.767678 -55.829454) (xy 336.741195 -55.82893)
			(xy 336.688906 -55.820486) (xy 336.638632 -55.803816) (xy 336.591656 -55.779347) (xy 336.54918 -55.747705)
			(xy 336.51229 -55.709698) (xy 336.481929 -55.666298) (xy 336.458871 -55.618614) (xy 336.443708 -55.567865)
			(xy 336.439764 -55.541672) (xy 336.437451 -55.527708) (xy 336.426191 -55.501753) (xy 336.408244 -55.479882)
			(xy 336.384986 -55.463771) (xy 336.358202 -55.454657) (xy 336.329945 -55.453238) (xy 336.302383 -55.459624)
			(xy 336.277628 -55.473324) (xy 336.267298 -55.482998) (xy 336.17281 -55.577232) (xy 336.163411 -55.587258)
			(xy 336.149858 -55.611152) (xy 336.143169 -55.637794) (xy 336.143828 -55.665256) (xy 336.151787 -55.691548)
			(xy 336.16647 -55.714764) (xy 336.176366 -55.724298) (xy 336.196348 -55.743228) (xy 336.230348 -55.78651)
			(xy 336.256705 -55.834829) (xy 336.274689 -55.886847) (xy 336.283803 -55.941126) (xy 336.284316 -55.968646)
			(xy 336.283803 -55.994631) (xy 336.283803 -55.994633) (xy 337.25155 -55.994633) (xy 337.25155 -55.942659)
			(xy 337.25968 -55.891324) (xy 337.275741 -55.841894) (xy 337.299337 -55.795584) (xy 337.329887 -55.753536)
			(xy 337.366638 -55.716785) (xy 337.408686 -55.686235) (xy 337.454996 -55.662639) (xy 337.504426 -55.646578)
			(xy 337.555761 -55.638448) (xy 337.607735 -55.638448) (xy 337.65907 -55.646578) (xy 337.7085 -55.662639)
			(xy 337.75481 -55.686235) (xy 337.796858 -55.716785) (xy 337.833609 -55.753536) (xy 337.864159 -55.795584)
			(xy 337.887755 -55.841894) (xy 337.903816 -55.891324) (xy 337.911946 -55.942659) (xy 337.912456 -55.968646)
			(xy 337.911946 -55.994633) (xy 339.96046 -55.994633) (xy 339.96046 -55.942659) (xy 339.96859 -55.891324)
			(xy 339.984651 -55.841894) (xy 340.008247 -55.795584) (xy 340.038797 -55.753536) (xy 340.075548 -55.716785)
			(xy 340.117596 -55.686235) (xy 340.163906 -55.662639) (xy 340.213336 -55.646578) (xy 340.264671 -55.638448)
			(xy 340.316645 -55.638448) (xy 340.36798 -55.646578) (xy 340.41741 -55.662639) (xy 340.46372 -55.686235)
			(xy 340.505768 -55.716785) (xy 340.542519 -55.753536) (xy 340.573069 -55.795584) (xy 340.596665 -55.841894)
			(xy 340.612726 -55.891324) (xy 340.620856 -55.942659) (xy 340.621366 -55.968646) (xy 340.620856 -55.994633)
			(xy 341.59114 -55.994633) (xy 341.59114 -55.942659) (xy 341.59927 -55.891324) (xy 341.615331 -55.841894)
			(xy 341.638927 -55.795584) (xy 341.669477 -55.753536) (xy 341.706228 -55.716785) (xy 341.748276 -55.686235)
			(xy 341.794586 -55.662639) (xy 341.844016 -55.646578) (xy 341.895351 -55.638448) (xy 341.947325 -55.638448)
			(xy 341.99866 -55.646578) (xy 342.04809 -55.662639) (xy 342.0944 -55.686235) (xy 342.136448 -55.716785)
			(xy 342.173199 -55.753536) (xy 342.203749 -55.795584) (xy 342.227345 -55.841894) (xy 342.243406 -55.891324)
			(xy 342.251536 -55.942659) (xy 342.252046 -55.968646) (xy 342.251536 -55.994633) (xy 342.243406 -56.045968)
			(xy 342.227345 -56.095398) (xy 342.203749 -56.141708) (xy 342.173199 -56.183756) (xy 342.136448 -56.220507)
			(xy 342.0944 -56.251057) (xy 342.04809 -56.274653) (xy 341.99866 -56.290714) (xy 341.947325 -56.298844)
			(xy 341.895351 -56.298844) (xy 341.844016 -56.290714) (xy 341.794586 -56.274653) (xy 341.748276 -56.251057)
			(xy 341.706228 -56.220507) (xy 341.669477 -56.183756) (xy 341.638927 -56.141708) (xy 341.615331 -56.095398)
			(xy 341.59927 -56.045968) (xy 341.59114 -55.994633) (xy 340.620856 -55.994633) (xy 340.612726 -56.045968)
			(xy 340.596665 -56.095398) (xy 340.573069 -56.141708) (xy 340.542519 -56.183756) (xy 340.505768 -56.220507)
			(xy 340.46372 -56.251057) (xy 340.41741 -56.274653) (xy 340.36798 -56.290714) (xy 340.316645 -56.298844)
			(xy 340.264671 -56.298844) (xy 340.213336 -56.290714) (xy 340.163906 -56.274653) (xy 340.117596 -56.251057)
			(xy 340.075548 -56.220507) (xy 340.038797 -56.183756) (xy 340.008247 -56.141708) (xy 339.984651 -56.095398)
			(xy 339.96859 -56.045968) (xy 339.96046 -55.994633) (xy 337.911946 -55.994633) (xy 337.903816 -56.045968)
			(xy 337.887755 -56.095398) (xy 337.864159 -56.141708) (xy 337.833609 -56.183756) (xy 337.796858 -56.220507)
			(xy 337.75481 -56.251057) (xy 337.7085 -56.274653) (xy 337.65907 -56.290714) (xy 337.607735 -56.298844)
			(xy 337.555761 -56.298844) (xy 337.504426 -56.290714) (xy 337.454996 -56.274653) (xy 337.408686 -56.251057)
			(xy 337.366638 -56.220507) (xy 337.329887 -56.183756) (xy 337.299337 -56.141708) (xy 337.275741 -56.095398)
			(xy 337.25968 -56.045968) (xy 337.25155 -55.994633) (xy 336.283803 -55.994633) (xy 336.275667 -56.04596)
			(xy 336.259602 -56.095385) (xy 336.236004 -56.141689) (xy 336.205453 -56.183732) (xy 336.168703 -56.220478)
			(xy 336.126657 -56.251024) (xy 336.08035 -56.274616) (xy 336.030923 -56.290676) (xy 335.979593 -56.298806)
			(xy 335.953608 -56.299354) (xy 335.92609 -56.298807) (xy 335.871814 -56.289693) (xy 335.819797 -56.271716)
			(xy 335.771475 -56.245372) (xy 335.728185 -56.211389) (xy 335.70926 -56.191404) (xy 335.699695 -56.181537)
			(xy 335.676471 -56.166866) (xy 335.65017 -56.158937) (xy 335.622706 -56.158328) (xy 335.59608 -56.165082)
			(xy 335.572227 -56.178708) (xy 335.562194 -56.188102) (xy 335.443322 -56.306974) (xy 335.452974 -56.336438)
			(xy 335.460464 -56.361297) (xy 335.468498 -56.412587) (xy 335.468976 -56.438546) (xy 335.468463 -56.46453)
			(xy 335.468463 -56.464533) (xy 336.437226 -56.464533) (xy 336.437226 -56.412559) (xy 336.445356 -56.361224)
			(xy 336.461417 -56.311794) (xy 336.485013 -56.265484) (xy 336.515563 -56.223436) (xy 336.552314 -56.186685)
			(xy 336.594362 -56.156135) (xy 336.640672 -56.132539) (xy 336.690102 -56.116478) (xy 336.741437 -56.108348)
			(xy 336.793411 -56.108348) (xy 336.844746 -56.116478) (xy 336.894176 -56.132539) (xy 336.940486 -56.156135)
			(xy 336.982534 -56.186685) (xy 337.019285 -56.223436) (xy 337.049835 -56.265484) (xy 337.073431 -56.311794)
			(xy 337.089492 -56.361224) (xy 337.097622 -56.412559) (xy 337.098132 -56.438546) (xy 337.097622 -56.464533)
			(xy 338.06562 -56.464533) (xy 338.06562 -56.412559) (xy 338.07375 -56.361224) (xy 338.089811 -56.311794)
			(xy 338.113407 -56.265484) (xy 338.143957 -56.223436) (xy 338.180708 -56.186685) (xy 338.222756 -56.156135)
			(xy 338.269066 -56.132539) (xy 338.318496 -56.116478) (xy 338.369831 -56.108348) (xy 338.421805 -56.108348)
			(xy 338.47314 -56.116478) (xy 338.52257 -56.132539) (xy 338.56888 -56.156135) (xy 338.610928 -56.186685)
			(xy 338.647679 -56.223436) (xy 338.678229 -56.265484) (xy 338.701825 -56.311794) (xy 338.717886 -56.361224)
			(xy 338.726016 -56.412559) (xy 338.726526 -56.438546) (xy 338.726016 -56.464533) (xy 339.14766 -56.464533)
			(xy 339.14766 -56.412559) (xy 339.15579 -56.361224) (xy 339.171851 -56.311794) (xy 339.195447 -56.265484)
			(xy 339.225997 -56.223436) (xy 339.262748 -56.186685) (xy 339.304796 -56.156135) (xy 339.351106 -56.132539)
			(xy 339.400536 -56.116478) (xy 339.451871 -56.108348) (xy 339.503845 -56.108348) (xy 339.55518 -56.116478)
			(xy 339.60461 -56.132539) (xy 339.65092 -56.156135) (xy 339.692968 -56.186685) (xy 339.729719 -56.223436)
			(xy 339.760269 -56.265484) (xy 339.783865 -56.311794) (xy 339.799926 -56.361224) (xy 339.808056 -56.412559)
			(xy 339.808566 -56.438546) (xy 339.808056 -56.464533) (xy 340.7758 -56.464533) (xy 340.7758 -56.412559)
			(xy 340.78393 -56.361224) (xy 340.799991 -56.311794) (xy 340.823587 -56.265484) (xy 340.854137 -56.223436)
			(xy 340.890888 -56.186685) (xy 340.932936 -56.156135) (xy 340.979246 -56.132539) (xy 341.028676 -56.116478)
			(xy 341.080011 -56.108348) (xy 341.131985 -56.108348) (xy 341.18332 -56.116478) (xy 341.23275 -56.132539)
			(xy 341.27906 -56.156135) (xy 341.321108 -56.186685) (xy 341.357859 -56.223436) (xy 341.388409 -56.265484)
			(xy 341.412005 -56.311794) (xy 341.428066 -56.361224) (xy 341.436196 -56.412559) (xy 341.436706 -56.438546)
			(xy 341.436196 -56.464533) (xy 341.428066 -56.515868) (xy 341.412005 -56.565298) (xy 341.388409 -56.611608)
			(xy 341.357859 -56.653656) (xy 341.321108 -56.690407) (xy 341.27906 -56.720957) (xy 341.23275 -56.744553)
			(xy 341.18332 -56.760614) (xy 341.131985 -56.768744) (xy 341.080011 -56.768744) (xy 341.028676 -56.760614)
			(xy 340.979246 -56.744553) (xy 340.932936 -56.720957) (xy 340.890888 -56.690407) (xy 340.854137 -56.653656)
			(xy 340.823587 -56.611608) (xy 340.799991 -56.565298) (xy 340.78393 -56.515868) (xy 340.7758 -56.464533)
			(xy 339.808056 -56.464533) (xy 339.799926 -56.515868) (xy 339.783865 -56.565298) (xy 339.760269 -56.611608)
			(xy 339.729719 -56.653656) (xy 339.692968 -56.690407) (xy 339.65092 -56.720957) (xy 339.60461 -56.744553)
			(xy 339.55518 -56.760614) (xy 339.503845 -56.768744) (xy 339.451871 -56.768744) (xy 339.400536 -56.760614)
			(xy 339.351106 -56.744553) (xy 339.304796 -56.720957) (xy 339.262748 -56.690407) (xy 339.225997 -56.653656)
			(xy 339.195447 -56.611608) (xy 339.171851 -56.565298) (xy 339.15579 -56.515868) (xy 339.14766 -56.464533)
			(xy 338.726016 -56.464533) (xy 338.717886 -56.515868) (xy 338.701825 -56.565298) (xy 338.678229 -56.611608)
			(xy 338.647679 -56.653656) (xy 338.610928 -56.690407) (xy 338.56888 -56.720957) (xy 338.52257 -56.744553)
			(xy 338.47314 -56.760614) (xy 338.421805 -56.768744) (xy 338.369831 -56.768744) (xy 338.318496 -56.760614)
			(xy 338.269066 -56.744553) (xy 338.222756 -56.720957) (xy 338.180708 -56.690407) (xy 338.143957 -56.653656)
			(xy 338.113407 -56.611608) (xy 338.089811 -56.565298) (xy 338.07375 -56.515868) (xy 338.06562 -56.464533)
			(xy 337.097622 -56.464533) (xy 337.089492 -56.515868) (xy 337.073431 -56.565298) (xy 337.049835 -56.611608)
			(xy 337.019285 -56.653656) (xy 336.982534 -56.690407) (xy 336.940486 -56.720957) (xy 336.894176 -56.744553)
			(xy 336.844746 -56.760614) (xy 336.793411 -56.768744) (xy 336.741437 -56.768744) (xy 336.690102 -56.760614)
			(xy 336.640672 -56.744553) (xy 336.594362 -56.720957) (xy 336.552314 -56.690407) (xy 336.515563 -56.653656)
			(xy 336.485013 -56.611608) (xy 336.461417 -56.565298) (xy 336.445356 -56.515868) (xy 336.437226 -56.464533)
			(xy 335.468463 -56.464533) (xy 335.460326 -56.515857) (xy 335.444261 -56.565279) (xy 335.420662 -56.61158)
			(xy 335.390111 -56.653619) (xy 335.35336 -56.690362) (xy 335.311313 -56.720903) (xy 335.265007 -56.744491)
			(xy 335.215581 -56.760545) (xy 335.164252 -56.768669) (xy 335.138268 -56.769254) (xy 335.112373 -56.768771)
			(xy 335.061211 -56.760731) (xy 335.036414 -56.753252) (xy 335.006696 -56.7436) (xy 334.815863 -56.934433)
			(xy 335.62341 -56.934433) (xy 335.62341 -56.882459) (xy 335.63154 -56.831124) (xy 335.647601 -56.781694)
			(xy 335.671197 -56.735384) (xy 335.701747 -56.693336) (xy 335.738498 -56.656585) (xy 335.780546 -56.626035)
			(xy 335.826856 -56.602439) (xy 335.876286 -56.586378) (xy 335.927621 -56.578248) (xy 335.979595 -56.578248)
			(xy 336.03093 -56.586378) (xy 336.08036 -56.602439) (xy 336.12667 -56.626035) (xy 336.168718 -56.656585)
			(xy 336.205469 -56.693336) (xy 336.236019 -56.735384) (xy 336.259615 -56.781694) (xy 336.275676 -56.831124)
			(xy 336.283806 -56.882459) (xy 336.284316 -56.908446) (xy 336.283806 -56.934433) (xy 337.251296 -56.934433)
			(xy 337.251296 -56.882459) (xy 337.259426 -56.831124) (xy 337.275487 -56.781694) (xy 337.299083 -56.735384)
			(xy 337.329633 -56.693336) (xy 337.366384 -56.656585) (xy 337.408432 -56.626035) (xy 337.454742 -56.602439)
			(xy 337.504172 -56.586378) (xy 337.555507 -56.578248) (xy 337.607481 -56.578248) (xy 337.658816 -56.586378)
			(xy 337.708246 -56.602439) (xy 337.754556 -56.626035) (xy 337.796604 -56.656585) (xy 337.833355 -56.693336)
			(xy 337.863905 -56.735384) (xy 337.887501 -56.781694) (xy 337.903562 -56.831124) (xy 337.911692 -56.882459)
			(xy 337.912202 -56.908446) (xy 337.911692 -56.934433) (xy 337.903562 -56.985768) (xy 337.887501 -57.035198)
			(xy 337.863905 -57.081508) (xy 337.833355 -57.123556) (xy 337.796604 -57.160307) (xy 337.754556 -57.190857)
			(xy 337.708246 -57.214453) (xy 337.658816 -57.230514) (xy 337.607481 -57.238644) (xy 337.555507 -57.238644)
			(xy 337.504172 -57.230514) (xy 337.454742 -57.214453) (xy 337.408432 -57.190857) (xy 337.366384 -57.160307)
			(xy 337.329633 -57.123556) (xy 337.299083 -57.081508) (xy 337.275487 -57.035198) (xy 337.259426 -56.985768)
			(xy 337.251296 -56.934433) (xy 336.283806 -56.934433) (xy 336.275676 -56.985768) (xy 336.259615 -57.035198)
			(xy 336.236019 -57.081508) (xy 336.205469 -57.123556) (xy 336.168718 -57.160307) (xy 336.12667 -57.190857)
			(xy 336.08036 -57.214453) (xy 336.03093 -57.230514) (xy 335.979595 -57.238644) (xy 335.927621 -57.238644)
			(xy 335.876286 -57.230514) (xy 335.826856 -57.214453) (xy 335.780546 -57.190857) (xy 335.738498 -57.160307)
			(xy 335.701747 -57.123556) (xy 335.671197 -57.081508) (xy 335.647601 -57.035198) (xy 335.63154 -56.985768)
			(xy 335.62341 -56.934433) (xy 334.815863 -56.934433) (xy 334.781144 -56.969152) (xy 334.781144 -57.483989)
			(xy 338.04478 -57.483989) (xy 338.04478 -57.430691) (xy 338.052723 -57.377987) (xy 338.068433 -57.327057)
			(xy 338.091559 -57.279036) (xy 338.121583 -57.234999) (xy 338.157835 -57.195928) (xy 338.199506 -57.162697)
			(xy 338.245664 -57.136048) (xy 338.295278 -57.116576) (xy 338.34724 -57.104716) (xy 338.40039 -57.100733)
			(xy 338.45354 -57.104716) (xy 338.505502 -57.116576) (xy 338.555116 -57.136048) (xy 338.601274 -57.162697)
			(xy 338.642945 -57.195928) (xy 338.679197 -57.234999) (xy 338.709221 -57.279036) (xy 338.732347 -57.327057)
			(xy 338.748057 -57.377987) (xy 338.756 -57.430691) (xy 338.756498 -57.45734) (xy 338.756 -57.483989)
			(xy 338.748057 -57.536693) (xy 338.732347 -57.587623) (xy 338.709221 -57.635644) (xy 338.679197 -57.679681)
			(xy 338.642945 -57.718752) (xy 338.601274 -57.751983) (xy 338.555116 -57.778632) (xy 338.505502 -57.798104)
			(xy 338.45354 -57.809964) (xy 338.40039 -57.813948) (xy 338.34724 -57.809964) (xy 338.295278 -57.798104)
			(xy 338.245664 -57.778632) (xy 338.199506 -57.751983) (xy 338.157835 -57.718752) (xy 338.121583 -57.679681)
			(xy 338.091559 -57.635644) (xy 338.068433 -57.587623) (xy 338.052723 -57.536693) (xy 338.04478 -57.483989)
			(xy 334.781144 -57.483989) (xy 334.781144 -58.47588) (xy 333.101971 -60.155053) (xy 335.428834 -60.155053)
			(xy 335.428834 -60.101755) (xy 335.436777 -60.049051) (xy 335.452487 -59.998121) (xy 335.475613 -59.9501)
			(xy 335.505637 -59.906063) (xy 335.541889 -59.866992) (xy 335.58356 -59.833761) (xy 335.629718 -59.807112)
			(xy 335.679332 -59.78764) (xy 335.731294 -59.77578) (xy 335.784444 -59.771797) (xy 335.837594 -59.77578)
			(xy 335.889556 -59.78764) (xy 335.93917 -59.807112) (xy 335.985328 -59.833761) (xy 336.026999 -59.866992)
			(xy 336.063251 -59.906063) (xy 336.069879 -59.915785) (xy 336.544148 -59.915785) (xy 336.544148 -59.862487)
			(xy 336.552091 -59.809783) (xy 336.567801 -59.758853) (xy 336.590927 -59.710832) (xy 336.620951 -59.666795)
			(xy 336.657203 -59.627724) (xy 336.698874 -59.594493) (xy 336.745032 -59.567844) (xy 336.794646 -59.548372)
			(xy 336.846608 -59.536512) (xy 336.899758 -59.532529) (xy 336.952908 -59.536512) (xy 337.00487 -59.548372)
			(xy 337.054484 -59.567844) (xy 337.100642 -59.594493) (xy 337.142313 -59.627724) (xy 337.178565 -59.666795)
			(xy 337.208589 -59.710832) (xy 337.231715 -59.758853) (xy 337.237742 -59.778392) (xy 338.414878 -59.778392)
			(xy 338.418854 -59.724066) (xy 338.430697 -59.670897) (xy 338.450156 -59.62002) (xy 338.476816 -59.572518)
			(xy 338.510107 -59.529404) (xy 338.549321 -59.491597) (xy 338.593623 -59.459902) (xy 338.642066 -59.434996)
			(xy 338.69362 -59.417408) (xy 338.747186 -59.407514) (xy 338.801621 -59.405524) (xy 338.855766 -59.411482)
			(xy 338.908466 -59.42526) (xy 338.958599 -59.446564) (xy 339.005095 -59.47494) (xy 339.046965 -59.509784)
			(xy 339.083314 -59.550353) (xy 339.11337 -59.595782) (xy 339.136491 -59.645103) (xy 339.152184 -59.697265)
			(xy 339.160115 -59.751156) (xy 339.160612 -59.778392) (xy 339.160115 -59.805628) (xy 339.152184 -59.859519)
			(xy 339.136491 -59.911681) (xy 339.11337 -59.961002) (xy 339.083314 -60.006431) (xy 339.046965 -60.047)
			(xy 339.005095 -60.081844) (xy 338.958599 -60.11022) (xy 338.908466 -60.131524) (xy 338.855766 -60.145302)
			(xy 338.801621 -60.15126) (xy 338.747186 -60.14927) (xy 338.69362 -60.139376) (xy 338.642066 -60.121788)
			(xy 338.593623 -60.096882) (xy 338.549321 -60.065187) (xy 338.510107 -60.02738) (xy 338.476816 -59.984266)
			(xy 338.450156 -59.936764) (xy 338.430697 -59.885887) (xy 338.418854 -59.832718) (xy 338.414878 -59.778392)
			(xy 337.237742 -59.778392) (xy 337.247425 -59.809783) (xy 337.255368 -59.862487) (xy 337.255866 -59.889136)
			(xy 337.255368 -59.915785) (xy 337.247425 -59.968489) (xy 337.231715 -60.019419) (xy 337.208589 -60.06744)
			(xy 337.178565 -60.111477) (xy 337.142313 -60.150548) (xy 337.100642 -60.183779) (xy 337.054484 -60.210428)
			(xy 337.00487 -60.2299) (xy 336.952908 -60.24176) (xy 336.899758 -60.245744) (xy 336.846608 -60.24176)
			(xy 336.794646 -60.2299) (xy 336.745032 -60.210428) (xy 336.698874 -60.183779) (xy 336.657203 -60.150548)
			(xy 336.620951 -60.111477) (xy 336.590927 -60.06744) (xy 336.567801 -60.019419) (xy 336.552091 -59.968489)
			(xy 336.544148 -59.915785) (xy 336.069879 -59.915785) (xy 336.093275 -59.9501) (xy 336.116401 -59.998121)
			(xy 336.132111 -60.049051) (xy 336.140054 -60.101755) (xy 336.140552 -60.128404) (xy 336.140054 -60.155053)
			(xy 336.132111 -60.207757) (xy 336.116401 -60.258687) (xy 336.093275 -60.306708) (xy 336.063251 -60.350745)
			(xy 336.026999 -60.389816) (xy 335.985328 -60.423047) (xy 335.93917 -60.449696) (xy 335.889556 -60.469168)
			(xy 335.837594 -60.481028) (xy 335.784444 -60.485012) (xy 335.731294 -60.481028) (xy 335.679332 -60.469168)
			(xy 335.629718 -60.449696) (xy 335.58356 -60.423047) (xy 335.541889 -60.389816) (xy 335.505637 -60.350745)
			(xy 335.475613 -60.306708) (xy 335.452487 -60.258687) (xy 335.436777 -60.207757) (xy 335.428834 -60.155053)
			(xy 333.101971 -60.155053) (xy 331.732636 -61.524388) (xy 331.732636 -61.891672) (xy 331.366114 -62.258194)
			(xy 335.89163 -62.258194) (xy 335.895701 -62.202572) (xy 335.907827 -62.148135) (xy 335.92775 -62.096044)
			(xy 335.955046 -62.047409) (xy 335.989132 -62.003266) (xy 336.029281 -61.964557) (xy 336.074639 -61.932106)
			(xy 336.124239 -61.906605) (xy 336.177023 -61.888598) (xy 336.231866 -61.878468) (xy 336.2876 -61.876431)
			(xy 336.343037 -61.882531) (xy 336.396994 -61.896637) (xy 336.448323 -61.918449) (xy 336.495929 -61.947503)
			(xy 336.538797 -61.983178) (xy 336.576014 -62.024715) (xy 336.606787 -62.071228) (xy 336.630459 -62.121725)
			(xy 336.646527 -62.175132) (xy 336.654647 -62.230308) (xy 336.655156 -62.258194) (xy 336.654647 -62.28608)
			(xy 336.646527 -62.341256) (xy 336.630459 -62.394663) (xy 336.606787 -62.44516) (xy 336.576014 -62.491673)
			(xy 336.538797 -62.53321) (xy 336.495929 -62.568885) (xy 336.448323 -62.597939) (xy 336.396994 -62.619751)
			(xy 336.343037 -62.633857) (xy 336.2876 -62.639957) (xy 336.231866 -62.63792) (xy 336.177023 -62.62779)
			(xy 336.124239 -62.609783) (xy 336.074639 -62.584282) (xy 336.029281 -62.551831) (xy 335.989132 -62.513122)
			(xy 335.955046 -62.468979) (xy 335.92775 -62.420344) (xy 335.907827 -62.368253) (xy 335.895701 -62.313816)
			(xy 335.89163 -62.258194) (xy 331.366114 -62.258194) (xy 331.06868 -62.555628) (xy 331.06868 -65.759584)
			(xy 331.59192 -66.282824) (xy 333.060548 -66.282824)
		)
		(stroke
			(width 0)
			(type solid)
		)
		(fill yes)
		(layer "In13.Cu")
		(net "P1V05_PCH_PLL_AUX")
	)
	(gr_poly
		(pts
			(xy 84.213192 -33.587182) (xy 84.213192 -21.1836) (xy 82.613246 -19.583654) (xy 82.603417 -19.574415)
			(xy 82.580021 -19.561005) (xy 82.553929 -19.554189) (xy 82.526964 -19.554443) (xy 82.501005 -19.561749)
			(xy 82.477866 -19.575598) (xy 82.45916 -19.595022) (xy 82.446194 -19.618667) (xy 82.442558 -19.63166)
			(xy 82.435426 -19.659042) (xy 82.414185 -19.711485) (xy 82.385432 -19.760216) (xy 82.349799 -19.804168)
			(xy 82.308066 -19.842376) (xy 82.261149 -19.874002) (xy 82.210076 -19.898354) (xy 82.155967 -19.914898)
			(xy 82.100009 -19.92327) (xy 82.071718 -19.92376) (xy 82.040821 -19.923142) (xy 81.979838 -19.913152)
			(xy 81.921258 -19.893477) (xy 81.893664 -19.879564) (xy 81.880492 -19.873137) (xy 81.851774 -19.867352)
			(xy 81.822595 -19.869969) (xy 81.795364 -19.880771) (xy 81.772326 -19.898868) (xy 81.755382 -19.922767)
			(xy 81.750154 -19.93646) (xy 81.741182 -19.961181) (xy 81.717405 -20.008089) (xy 81.687416 -20.05129)
			(xy 81.651782 -20.089967) (xy 81.611178 -20.123388) (xy 81.566371 -20.150921) (xy 81.518209 -20.172044)
			(xy 81.467605 -20.186357) (xy 81.415515 -20.193591) (xy 81.38922 -20.194016) (xy 81.361966 -20.193554)
			(xy 81.308011 -20.185799) (xy 81.25571 -20.170445) (xy 81.206126 -20.147803) (xy 81.16027 -20.118335)
			(xy 81.119074 -20.08264) (xy 81.083377 -20.041446) (xy 81.053907 -19.995591) (xy 81.031262 -19.946009)
			(xy 81.015905 -19.893708) (xy 81.008147 -19.839754) (xy 81.008147 -19.785246) (xy 81.015905 -19.731292)
			(xy 81.031262 -19.678991) (xy 81.053907 -19.629409) (xy 81.083377 -19.583554) (xy 81.119074 -19.54236)
			(xy 81.16027 -19.506665) (xy 81.206126 -19.477197) (xy 81.25571 -19.454555) (xy 81.308011 -19.439201)
			(xy 81.361966 -19.431446) (xy 81.38922 -19.431) (xy 81.420117 -19.43162) (xy 81.481098 -19.441615)
			(xy 81.539675 -19.461293) (xy 81.567274 -19.475196) (xy 81.580451 -19.48163) (xy 81.609183 -19.487428)
			(xy 81.638378 -19.484822) (xy 81.665629 -19.474028) (xy 81.688689 -19.455936) (xy 81.705658 -19.432036)
			(xy 81.710784 -19.4183) (xy 81.720124 -19.39258) (xy 81.745124 -19.343907) (xy 81.776822 -19.299306)
			(xy 81.814569 -19.259691) (xy 81.857588 -19.225878) (xy 81.904998 -19.198558) (xy 81.955826 -19.178293)
			(xy 81.98231 -19.171412) (xy 81.995319 -19.167836) (xy 82.018958 -19.154854) (xy 82.038375 -19.136137)
			(xy 82.052217 -19.11299) (xy 82.059518 -19.087028) (xy 82.059769 -19.060059) (xy 82.052953 -19.033965)
			(xy 82.039545 -19.010565) (xy 82.030316 -19.000724) (xy 81.976976 -18.947384) (xy 81.963006 -18.943828)
			(xy 81.9356 -18.936731) (xy 81.883104 -18.915543) (xy 81.834319 -18.886823) (xy 81.79032 -18.851202)
			(xy 81.752074 -18.809465) (xy 81.720422 -18.76253) (xy 81.696061 -18.711429) (xy 81.679528 -18.657286)
			(xy 81.671185 -18.601294) (xy 81.670652 -18.572988) (xy 81.671139 -18.545736) (xy 81.678896 -18.491788)
			(xy 81.694252 -18.439492) (xy 81.716893 -18.389914) (xy 81.746359 -18.344062) (xy 81.78205 -18.30287)
			(xy 81.82324 -18.267176) (xy 81.869089 -18.237707) (xy 81.918666 -18.215062) (xy 81.97096 -18.199702)
			(xy 82.024908 -18.191941) (xy 82.05216 -18.19148) (xy 82.080464 -18.191999) (xy 82.136448 -18.200372)
			(xy 82.190581 -18.216926) (xy 82.241674 -18.241296) (xy 82.288605 -18.272948) (xy 82.330345 -18.311187)
			(xy 82.365975 -18.355174) (xy 82.394716 -18.403942) (xy 82.415935 -18.456422) (xy 82.423 -18.483834)
			(xy 82.426556 -18.497804) (xy 84.388198 -20.459446) (xy 84.399167 -20.469673) (xy 84.425594 -20.483819)
			(xy 84.454989 -20.489691) (xy 84.484822 -20.486785) (xy 84.51253 -20.475349) (xy 84.53573 -20.456367)
			(xy 84.552426 -20.431472) (xy 84.561182 -20.402805) (xy 84.56168 -20.387818) (xy 84.56168 -19.370548)
			(xy 80.251554 -15.060676) (xy 77.981302 -15.060676) (xy 77.967657 -15.061102) (xy 77.941337 -15.068311)
			(xy 77.91787 -15.082241) (xy 77.898936 -15.101894) (xy 77.885891 -15.125863) (xy 77.879668 -15.152434)
			(xy 77.880712 -15.179704) (xy 77.888949 -15.20572) (xy 77.90379 -15.228622) (xy 77.913738 -15.237968)
			(xy 77.933419 -15.256154) (xy 77.968 -15.297089) (xy 77.996519 -15.342455) (xy 78.018417 -15.391363)
			(xy 78.033264 -15.442851) (xy 78.040768 -15.495909) (xy 78.041246 -15.522702) (xy 78.040759 -15.550276)
			(xy 78.032817 -15.60485) (xy 78.017099 -15.657711) (xy 77.993932 -15.707757) (xy 77.9638 -15.753946)
			(xy 77.92733 -15.795313) (xy 77.906626 -15.813532) (xy 77.895727 -15.823429) (xy 77.879652 -15.848079)
			(xy 77.871266 -15.876287) (xy 77.871267 -15.905715) (xy 77.879653 -15.933923) (xy 77.895729 -15.958572)
			(xy 77.906626 -15.968472) (xy 77.927335 -15.986686) (xy 77.963807 -16.028056) (xy 77.993944 -16.074245)
			(xy 78.017117 -16.124291) (xy 78.032844 -16.177152) (xy 78.040798 -16.231727) (xy 78.041246 -16.259302)
			(xy 78.04076 -16.286553) (xy 78.033004 -16.340501) (xy 78.017649 -16.392796) (xy 77.995007 -16.442373)
			(xy 77.965541 -16.488223) (xy 77.92985 -16.529414) (xy 77.888659 -16.565105) (xy 77.842809 -16.594571)
			(xy 77.793232 -16.617213) (xy 77.740937 -16.632568) (xy 77.686989 -16.640324) (xy 77.632487 -16.640324)
			(xy 77.578539 -16.632568) (xy 77.526244 -16.617213) (xy 77.476667 -16.594571) (xy 77.430817 -16.565105)
			(xy 77.389626 -16.529414) (xy 77.353935 -16.488223) (xy 77.324469 -16.442373) (xy 77.301827 -16.392796)
			(xy 77.286472 -16.340501) (xy 77.278716 -16.286553) (xy 77.27823 -16.259302) (xy 77.278716 -16.231727)
			(xy 77.286658 -16.177153) (xy 77.302375 -16.124291) (xy 77.32554 -16.074244) (xy 77.355671 -16.028053)
			(xy 77.392139 -15.986683) (xy 77.41285 -15.968472) (xy 77.423752 -15.958576) (xy 77.439832 -15.933927)
			(xy 77.448221 -15.905717) (xy 77.448221 -15.876286) (xy 77.439833 -15.848076) (xy 77.423753 -15.823426)
			(xy 77.41285 -15.813532) (xy 77.392142 -15.795317) (xy 77.355671 -15.753947) (xy 77.325536 -15.707758)
			(xy 77.302364 -15.657712) (xy 77.286637 -15.604851) (xy 77.278684 -15.550277) (xy 77.27823 -15.522702)
			(xy 77.278683 -15.495908) (xy 77.286181 -15.442847) (xy 77.301029 -15.391356) (xy 77.322935 -15.34245)
			(xy 77.351469 -15.29709) (xy 77.386068 -15.256169) (xy 77.405738 -15.237968) (xy 77.415611 -15.228557)
			(xy 77.430404 -15.205653) (xy 77.438609 -15.179651) (xy 77.43964 -15.152405) (xy 77.433424 -15.125857)
			(xy 77.420405 -15.101901) (xy 77.40151 -15.082244) (xy 77.378087 -15.068287) (xy 77.351806 -15.061027)
			(xy 77.338174 -15.060676) (xy 70.751954 -15.060676) (xy 70.726972 -15.060161) (xy 70.677628 -15.052305)
			(xy 70.630116 -15.036839) (xy 70.585602 -15.014143) (xy 70.545179 -14.984774) (xy 70.527164 -14.967458)
			(xy 70.388734 -14.828774) (xy 70.29196 -14.925548) (xy 70.29196 -18.160746) (xy 74.02525 -18.160746)
			(xy 74.029321 -18.105124) (xy 74.041447 -18.050687) (xy 74.06137 -17.998596) (xy 74.088666 -17.949961)
			(xy 74.122752 -17.905818) (xy 74.162901 -17.867109) (xy 74.208259 -17.834658) (xy 74.257859 -17.809157)
			(xy 74.310643 -17.79115) (xy 74.365486 -17.78102) (xy 74.42122 -17.778983) (xy 74.476657 -17.785083)
			(xy 74.530614 -17.799189) (xy 74.581943 -17.821001) (xy 74.629549 -17.850055) (xy 74.672417 -17.88573)
			(xy 74.709634 -17.927267) (xy 74.740407 -17.97378) (xy 74.764079 -18.024277) (xy 74.780147 -18.077684)
			(xy 74.788267 -18.13286) (xy 74.788776 -18.160746) (xy 74.788461 -18.178018) (xy 77.15072 -18.178018)
			(xy 77.154791 -18.122396) (xy 77.166917 -18.067959) (xy 77.18684 -18.015868) (xy 77.214136 -17.967233)
			(xy 77.248222 -17.92309) (xy 77.288371 -17.884381) (xy 77.333729 -17.85193) (xy 77.383329 -17.826429)
			(xy 77.436113 -17.808422) (xy 77.490956 -17.798292) (xy 77.54669 -17.796255) (xy 77.602127 -17.802355)
			(xy 77.656084 -17.816461) (xy 77.707413 -17.838273) (xy 77.755019 -17.867327) (xy 77.797887 -17.903002)
			(xy 77.835104 -17.944539) (xy 77.865877 -17.991052) (xy 77.889549 -18.041549) (xy 77.905617 -18.094956)
			(xy 77.913737 -18.150132) (xy 77.914246 -18.178018) (xy 77.913737 -18.205904) (xy 77.909019 -18.237962)
			(xy 79.54137 -18.237962) (xy 79.541889 -18.210389) (xy 79.549832 -18.155819) (xy 79.565547 -18.102961)
			(xy 79.588707 -18.052915) (xy 79.61883 -18.006724) (xy 79.655288 -17.96535) (xy 79.67599 -17.947132)
			(xy 79.686926 -17.937272) (xy 79.702998 -17.912611) (xy 79.711378 -17.884393) (xy 79.711371 -17.854958)
			(xy 79.702977 -17.826744) (xy 79.686893 -17.802091) (xy 79.67599 -17.792192) (xy 79.65527 -17.773991)
			(xy 79.618801 -17.73262) (xy 79.58867 -17.686428) (xy 79.565506 -17.636378) (xy 79.549791 -17.583514)
			(xy 79.541854 -17.528937) (xy 79.54137 -17.501362) (xy 79.541856 -17.474111) (xy 79.549612 -17.420163)
			(xy 79.564967 -17.367868) (xy 79.587609 -17.318291) (xy 79.617075 -17.272441) (xy 79.652766 -17.23125)
			(xy 79.693957 -17.195559) (xy 79.739807 -17.166093) (xy 79.789384 -17.143451) (xy 79.841679 -17.128096)
			(xy 79.895627 -17.12034) (xy 79.950129 -17.12034) (xy 80.004077 -17.128096) (xy 80.056372 -17.143451)
			(xy 80.105949 -17.166093) (xy 80.151799 -17.195559) (xy 80.19299 -17.23125) (xy 80.228681 -17.272441)
			(xy 80.258147 -17.318291) (xy 80.280789 -17.367868) (xy 80.296144 -17.420163) (xy 80.3039 -17.474111)
			(xy 80.304386 -17.501362) (xy 80.303899 -17.528936) (xy 80.295952 -17.583508) (xy 80.280231 -17.636368)
			(xy 80.257065 -17.686414) (xy 80.226936 -17.732604) (xy 80.190472 -17.773976) (xy 80.169766 -17.792192)
			(xy 80.15891 -17.802131) (xy 80.142842 -17.826771) (xy 80.134458 -17.854967) (xy 80.13445 -17.884384)
			(xy 80.142822 -17.912584) (xy 80.158878 -17.937232) (xy 80.169766 -17.947132) (xy 80.190489 -17.96533)
			(xy 80.22696 -18.006701) (xy 80.257091 -18.052893) (xy 80.280255 -18.102944) (xy 80.295969 -18.155809)
			(xy 80.303904 -18.210386) (xy 80.304386 -18.237962) (xy 80.3039 -18.265213) (xy 80.296144 -18.319161)
			(xy 80.280789 -18.371456) (xy 80.258147 -18.421033) (xy 80.228681 -18.466883) (xy 80.19299 -18.508074)
			(xy 80.151799 -18.543765) (xy 80.105949 -18.573231) (xy 80.056372 -18.595873) (xy 80.004077 -18.611228)
			(xy 79.950129 -18.618984) (xy 79.895627 -18.618984) (xy 79.841679 -18.611228) (xy 79.789384 -18.595873)
			(xy 79.739807 -18.573231) (xy 79.693957 -18.543765) (xy 79.652766 -18.508074) (xy 79.617075 -18.466883)
			(xy 79.587609 -18.421033) (xy 79.564967 -18.371456) (xy 79.549612 -18.319161) (xy 79.541856 -18.265213)
			(xy 79.54137 -18.237962) (xy 77.909019 -18.237962) (xy 77.905617 -18.26108) (xy 77.889549 -18.314487)
			(xy 77.865877 -18.364984) (xy 77.835104 -18.411497) (xy 77.797887 -18.453034) (xy 77.755019 -18.488709)
			(xy 77.707413 -18.517763) (xy 77.656084 -18.539575) (xy 77.602127 -18.553681) (xy 77.54669 -18.559781)
			(xy 77.490956 -18.557744) (xy 77.436113 -18.547614) (xy 77.383329 -18.529607) (xy 77.333729 -18.504106)
			(xy 77.288371 -18.471655) (xy 77.248222 -18.432946) (xy 77.214136 -18.388803) (xy 77.18684 -18.340168)
			(xy 77.166917 -18.288077) (xy 77.154791 -18.23364) (xy 77.15072 -18.178018) (xy 74.788461 -18.178018)
			(xy 74.788267 -18.188632) (xy 74.780147 -18.243808) (xy 74.764079 -18.297215) (xy 74.740407 -18.347712)
			(xy 74.709634 -18.394225) (xy 74.672417 -18.435762) (xy 74.629549 -18.471437) (xy 74.581943 -18.500491)
			(xy 74.530614 -18.522303) (xy 74.476657 -18.536409) (xy 74.42122 -18.542509) (xy 74.365486 -18.540472)
			(xy 74.310643 -18.530342) (xy 74.257859 -18.512335) (xy 74.208259 -18.486834) (xy 74.162901 -18.454383)
			(xy 74.122752 -18.415674) (xy 74.088666 -18.371531) (xy 74.06137 -18.322896) (xy 74.041447 -18.270805)
			(xy 74.029321 -18.216368) (xy 74.02525 -18.160746) (xy 70.29196 -18.160746) (xy 70.29196 -19.220942)
			(xy 76.404722 -19.220942) (xy 76.408793 -19.16532) (xy 76.420919 -19.110883) (xy 76.440842 -19.058792)
			(xy 76.468138 -19.010157) (xy 76.502224 -18.966014) (xy 76.542373 -18.927305) (xy 76.587731 -18.894854)
			(xy 76.637331 -18.869353) (xy 76.690115 -18.851346) (xy 76.744958 -18.841216) (xy 76.800692 -18.839179)
			(xy 76.856129 -18.845279) (xy 76.910086 -18.859385) (xy 76.961415 -18.881197) (xy 77.009021 -18.910251)
			(xy 77.051889 -18.945926) (xy 77.089106 -18.987463) (xy 77.119879 -19.033976) (xy 77.143551 -19.084473)
			(xy 77.159619 -19.13788) (xy 77.167739 -19.193056) (xy 77.168248 -19.220942) (xy 77.167739 -19.248828)
			(xy 77.163657 -19.276568) (xy 78.474568 -19.276568) (xy 78.478639 -19.220946) (xy 78.490765 -19.166509)
			(xy 78.510688 -19.114418) (xy 78.537984 -19.065783) (xy 78.57207 -19.02164) (xy 78.612219 -18.982931)
			(xy 78.657577 -18.95048) (xy 78.707177 -18.924979) (xy 78.759961 -18.906972) (xy 78.814804 -18.896842)
			(xy 78.870538 -18.894805) (xy 78.925975 -18.900905) (xy 78.979932 -18.915011) (xy 79.031261 -18.936823)
			(xy 79.078867 -18.965877) (xy 79.121735 -19.001552) (xy 79.158952 -19.043089) (xy 79.189725 -19.089602)
			(xy 79.213397 -19.140099) (xy 79.229465 -19.193506) (xy 79.237585 -19.248682) (xy 79.238094 -19.276568)
			(xy 79.237585 -19.304454) (xy 79.229465 -19.35963) (xy 79.213397 -19.413037) (xy 79.189725 -19.463534)
			(xy 79.158952 -19.510047) (xy 79.121735 -19.551584) (xy 79.078867 -19.587259) (xy 79.031261 -19.616313)
			(xy 78.979932 -19.638125) (xy 78.925975 -19.652231) (xy 78.870538 -19.658331) (xy 78.814804 -19.656294)
			(xy 78.759961 -19.646164) (xy 78.707177 -19.628157) (xy 78.657577 -19.602656) (xy 78.612219 -19.570205)
			(xy 78.57207 -19.531496) (xy 78.537984 -19.487353) (xy 78.510688 -19.438718) (xy 78.490765 -19.386627)
			(xy 78.478639 -19.33219) (xy 78.474568 -19.276568) (xy 77.163657 -19.276568) (xy 77.159619 -19.304004)
			(xy 77.143551 -19.357411) (xy 77.119879 -19.407908) (xy 77.089106 -19.454421) (xy 77.051889 -19.495958)
			(xy 77.009021 -19.531633) (xy 76.961415 -19.560687) (xy 76.910086 -19.582499) (xy 76.856129 -19.596605)
			(xy 76.800692 -19.602705) (xy 76.744958 -19.600668) (xy 76.690115 -19.590538) (xy 76.637331 -19.572531)
			(xy 76.587731 -19.54703) (xy 76.542373 -19.514579) (xy 76.502224 -19.47587) (xy 76.468138 -19.431727)
			(xy 76.440842 -19.383092) (xy 76.420919 -19.331001) (xy 76.408793 -19.276564) (xy 76.404722 -19.220942)
			(xy 70.29196 -19.220942) (xy 70.29196 -20.944078) (xy 76.224382 -20.944078) (xy 76.228453 -20.888456)
			(xy 76.240579 -20.834019) (xy 76.260502 -20.781928) (xy 76.287798 -20.733293) (xy 76.321884 -20.68915)
			(xy 76.362033 -20.650441) (xy 76.407391 -20.61799) (xy 76.456991 -20.592489) (xy 76.509775 -20.574482)
			(xy 76.564618 -20.564352) (xy 76.620352 -20.562315) (xy 76.675789 -20.568415) (xy 76.729746 -20.582521)
			(xy 76.781075 -20.604333) (xy 76.828681 -20.633387) (xy 76.871549 -20.669062) (xy 76.908766 -20.710599)
			(xy 76.939539 -20.757112) (xy 76.963211 -20.807609) (xy 76.979279 -20.861016) (xy 76.987399 -20.916192)
			(xy 76.987908 -20.944078) (xy 76.987399 -20.971964) (xy 76.979279 -21.02714) (xy 76.963211 -21.080547)
			(xy 76.939539 -21.131044) (xy 76.908766 -21.177557) (xy 76.871549 -21.219094) (xy 76.828681 -21.254769)
			(xy 76.781075 -21.283823) (xy 76.729746 -21.305635) (xy 76.675789 -21.319741) (xy 76.620352 -21.325841)
			(xy 76.564618 -21.323804) (xy 76.509775 -21.313674) (xy 76.456991 -21.295667) (xy 76.407391 -21.270166)
			(xy 76.362033 -21.237715) (xy 76.321884 -21.199006) (xy 76.287798 -21.154863) (xy 76.260502 -21.106228)
			(xy 76.240579 -21.054137) (xy 76.228453 -20.9997) (xy 76.224382 -20.944078) (xy 70.29196 -20.944078)
			(xy 70.29196 -21.416772) (xy 81.628742 -21.416772) (xy 81.62926 -21.387965) (xy 81.637934 -21.331007)
			(xy 81.655066 -21.275999) (xy 81.680266 -21.224189) (xy 81.712965 -21.176752) (xy 81.752418 -21.134766)
			(xy 81.79773 -21.099183) (xy 81.822544 -21.08454) (xy 81.834696 -21.07709) (xy 81.854691 -21.056799)
			(xy 81.86829 -21.031767) (xy 81.874431 -21.003949) (xy 81.872634 -20.975518) (xy 81.86304 -20.948695)
			(xy 81.846397 -20.925574) (xy 81.835498 -20.916392) (xy 81.813248 -20.898197) (xy 81.773976 -20.856231)
			(xy 81.741439 -20.808852) (xy 81.716371 -20.757131) (xy 81.699339 -20.702237) (xy 81.690727 -20.64541)
			(xy 81.69021 -20.616672) (xy 81.690696 -20.589421) (xy 81.698452 -20.535473) (xy 81.713807 -20.483178)
			(xy 81.736449 -20.433601) (xy 81.765915 -20.387751) (xy 81.801606 -20.34656) (xy 81.842797 -20.310869)
			(xy 81.888647 -20.281403) (xy 81.938224 -20.258761) (xy 81.990519 -20.243406) (xy 82.044467 -20.23565)
			(xy 82.098969 -20.23565) (xy 82.152917 -20.243406) (xy 82.205212 -20.258761) (xy 82.254789 -20.281403)
			(xy 82.300639 -20.310869) (xy 82.34183 -20.34656) (xy 82.377521 -20.387751) (xy 82.406987 -20.433601)
			(xy 82.429629 -20.483178) (xy 82.444984 -20.535473) (xy 82.45274 -20.589421) (xy 82.453226 -20.616672)
			(xy 82.452709 -20.645478) (xy 82.44403 -20.702435) (xy 82.426896 -20.757441) (xy 82.401694 -20.80925)
			(xy 82.368997 -20.856686) (xy 82.329546 -20.898674) (xy 82.284236 -20.934259) (xy 82.259424 -20.948904)
			(xy 82.247234 -20.956295) (xy 82.227242 -20.976601) (xy 82.213648 -21.001645) (xy 82.207513 -21.029473)
			(xy 82.209317 -21.057911) (xy 82.218918 -21.084741) (xy 82.235567 -21.107867) (xy 82.24647 -21.117052)
			(xy 82.268707 -21.135261) (xy 82.307977 -21.177227) (xy 82.340514 -21.224603) (xy 82.365583 -21.276321)
			(xy 82.382619 -21.331212) (xy 82.391237 -21.388035) (xy 82.391758 -21.416772) (xy 82.391272 -21.444023)
			(xy 82.383516 -21.497971) (xy 82.368161 -21.550266) (xy 82.345519 -21.599843) (xy 82.316053 -21.645693)
			(xy 82.280362 -21.686884) (xy 82.239171 -21.722575) (xy 82.193321 -21.752041) (xy 82.143744 -21.774683)
			(xy 82.091449 -21.790038) (xy 82.037501 -21.797794) (xy 81.982999 -21.797794) (xy 81.929051 -21.790038)
			(xy 81.876756 -21.774683) (xy 81.827179 -21.752041) (xy 81.781329 -21.722575) (xy 81.740138 -21.686884)
			(xy 81.704447 -21.645693) (xy 81.674981 -21.599843) (xy 81.652339 -21.550266) (xy 81.636984 -21.497971)
			(xy 81.629228 -21.444023) (xy 81.628742 -21.416772) (xy 70.29196 -21.416772) (xy 70.29196 -22.581362)
			(xy 74.63866 -22.581362) (xy 74.642731 -22.52574) (xy 74.654857 -22.471303) (xy 74.67478 -22.419212)
			(xy 74.702076 -22.370577) (xy 74.736162 -22.326434) (xy 74.776311 -22.287725) (xy 74.821669 -22.255274)
			(xy 74.871269 -22.229773) (xy 74.924053 -22.211766) (xy 74.978896 -22.201636) (xy 75.03463 -22.199599)
			(xy 75.090067 -22.205699) (xy 75.144024 -22.219805) (xy 75.195353 -22.241617) (xy 75.242959 -22.270671)
			(xy 75.285827 -22.306346) (xy 75.323044 -22.347883) (xy 75.353817 -22.394396) (xy 75.377489 -22.444893)
			(xy 75.393557 -22.4983) (xy 75.401677 -22.553476) (xy 75.402186 -22.581362) (xy 75.401677 -22.609248)
			(xy 75.393557 -22.664424) (xy 75.377489 -22.717831) (xy 75.357227 -22.761053) (xy 79.21164 -22.761053)
			(xy 79.21164 -22.706547) (xy 79.219397 -22.652596) (xy 79.234752 -22.600298) (xy 79.257394 -22.550717)
			(xy 79.286861 -22.504863) (xy 79.322554 -22.463669) (xy 79.363745 -22.427974) (xy 79.409598 -22.398504)
			(xy 79.459177 -22.37586) (xy 79.511474 -22.360501) (xy 79.565425 -22.352741) (xy 79.592678 -22.352254)
			(xy 79.618793 -22.352689) (xy 79.670533 -22.35983) (xy 79.720814 -22.373967) (xy 79.768694 -22.394835)
			(xy 79.813277 -22.422045) (xy 79.853729 -22.455085) (xy 79.871824 -22.47392) (xy 79.881243 -22.483397)
			(xy 79.903906 -22.497534) (xy 79.929458 -22.505316) (xy 79.956154 -22.506211) (xy 79.98217 -22.500157)
			(xy 80.005729 -22.487569) (xy 80.025221 -22.469307) (xy 80.032606 -22.458172) (xy 80.047649 -22.43498)
			(xy 80.083338 -22.392766) (xy 80.124745 -22.356144) (xy 80.171003 -22.325881) (xy 80.221144 -22.302609)
			(xy 80.274118 -22.286817) (xy 80.328817 -22.278834) (xy 80.356456 -22.27834) (xy 80.383714 -22.278704)
			(xy 80.437677 -22.286457) (xy 80.489987 -22.301811) (xy 80.539579 -22.324454) (xy 80.585443 -22.353924)
			(xy 80.626646 -22.389623) (xy 80.662349 -22.430822) (xy 80.691825 -22.476683) (xy 80.714474 -22.526272)
			(xy 80.729834 -22.57858) (xy 80.737593 -22.632542) (xy 80.737593 -22.687058) (xy 80.729834 -22.74102)
			(xy 80.714474 -22.793328) (xy 80.691825 -22.842917) (xy 80.662349 -22.888778) (xy 80.626646 -22.929977)
			(xy 80.585443 -22.965676) (xy 80.539579 -22.995146) (xy 80.489987 -23.017789) (xy 80.437677 -23.033143)
			(xy 80.383714 -23.040896) (xy 80.356456 -23.041356) (xy 80.33034 -23.040961) (xy 80.278598 -23.033812)
			(xy 80.228317 -23.019667) (xy 80.180437 -22.998791) (xy 80.135854 -22.971575) (xy 80.095404 -22.938528)
			(xy 80.07731 -22.91969) (xy 80.067857 -22.910248) (xy 80.045203 -22.896108) (xy 80.019659 -22.888321)
			(xy 79.992969 -22.887421) (xy 79.966958 -22.893469) (xy 79.943403 -22.90605) (xy 79.923913 -22.924307)
			(xy 79.916528 -22.935438) (xy 79.901532 -22.958663) (xy 79.865835 -23.000875) (xy 79.82442 -23.037495)
			(xy 79.778154 -23.067754) (xy 79.728005 -23.091021) (xy 79.675024 -23.106806) (xy 79.620319 -23.114781)
			(xy 79.592678 -23.11527) (xy 79.565425 -23.114859) (xy 79.511474 -23.107099) (xy 79.459177 -23.09174)
			(xy 79.409598 -23.069096) (xy 79.363745 -23.039626) (xy 79.322554 -23.003931) (xy 79.286861 -22.962737)
			(xy 79.257394 -22.916883) (xy 79.234752 -22.867302) (xy 79.219397 -22.815004) (xy 79.21164 -22.761053)
			(xy 75.357227 -22.761053) (xy 75.353817 -22.768328) (xy 75.323044 -22.814841) (xy 75.285827 -22.856378)
			(xy 75.242959 -22.892053) (xy 75.195353 -22.921107) (xy 75.144024 -22.942919) (xy 75.090067 -22.957025)
			(xy 75.03463 -22.963125) (xy 74.978896 -22.961088) (xy 74.924053 -22.950958) (xy 74.871269 -22.932951)
			(xy 74.821669 -22.90745) (xy 74.776311 -22.874999) (xy 74.736162 -22.83629) (xy 74.702076 -22.792147)
			(xy 74.67478 -22.743512) (xy 74.654857 -22.691421) (xy 74.642731 -22.636984) (xy 74.63866 -22.581362)
			(xy 70.29196 -22.581362) (xy 70.29196 -24.313896) (xy 77.804262 -24.313896) (xy 77.808333 -24.258274)
			(xy 77.820459 -24.203837) (xy 77.840382 -24.151746) (xy 77.867678 -24.103111) (xy 77.901764 -24.058968)
			(xy 77.941913 -24.020259) (xy 77.987271 -23.987808) (xy 78.036871 -23.962307) (xy 78.089655 -23.9443)
			(xy 78.144498 -23.93417) (xy 78.200232 -23.932133) (xy 78.255669 -23.938233) (xy 78.309626 -23.952339)
			(xy 78.360955 -23.974151) (xy 78.408561 -24.003205) (xy 78.451429 -24.03888) (xy 78.488646 -24.080417)
			(xy 78.519419 -24.12693) (xy 78.543091 -24.177427) (xy 78.559159 -24.230834) (xy 78.567279 -24.28601)
			(xy 78.567788 -24.313896) (xy 78.567279 -24.341782) (xy 78.559159 -24.396958) (xy 78.543091 -24.450365)
			(xy 78.519419 -24.500862) (xy 78.488646 -24.547375) (xy 78.45228 -24.587962) (xy 79.23606 -24.587962)
			(xy 79.240131 -24.53234) (xy 79.252257 -24.477903) (xy 79.27218 -24.425812) (xy 79.299476 -24.377177)
			(xy 79.333562 -24.333034) (xy 79.373711 -24.294325) (xy 79.419069 -24.261874) (xy 79.468669 -24.236373)
			(xy 79.521453 -24.218366) (xy 79.576296 -24.208236) (xy 79.63203 -24.206199) (xy 79.687467 -24.212299)
			(xy 79.741424 -24.226405) (xy 79.792753 -24.248217) (xy 79.840359 -24.277271) (xy 79.883227 -24.312946)
			(xy 79.920444 -24.354483) (xy 79.951217 -24.400996) (xy 79.974889 -24.451493) (xy 79.990957 -24.5049)
			(xy 79.999077 -24.560076) (xy 79.999586 -24.587962) (xy 79.999077 -24.615848) (xy 79.990957 -24.671024)
			(xy 79.974889 -24.724431) (xy 79.951217 -24.774928) (xy 79.920444 -24.821441) (xy 79.883227 -24.862978)
			(xy 79.840359 -24.898653) (xy 79.792753 -24.927707) (xy 79.741424 -24.949519) (xy 79.687467 -24.963625)
			(xy 79.63203 -24.969725) (xy 79.576296 -24.967688) (xy 79.521453 -24.957558) (xy 79.468669 -24.939551)
			(xy 79.419069 -24.91405) (xy 79.373711 -24.881599) (xy 79.333562 -24.84289) (xy 79.299476 -24.798747)
			(xy 79.27218 -24.750112) (xy 79.252257 -24.698021) (xy 79.240131 -24.643584) (xy 79.23606 -24.587962)
			(xy 78.45228 -24.587962) (xy 78.451429 -24.588912) (xy 78.408561 -24.624587) (xy 78.360955 -24.653641)
			(xy 78.309626 -24.675453) (xy 78.255669 -24.689559) (xy 78.200232 -24.695659) (xy 78.144498 -24.693622)
			(xy 78.089655 -24.683492) (xy 78.036871 -24.665485) (xy 77.987271 -24.639984) (xy 77.941913 -24.607533)
			(xy 77.901764 -24.568824) (xy 77.867678 -24.524681) (xy 77.840382 -24.476046) (xy 77.820459 -24.423955)
			(xy 77.808333 -24.369518) (xy 77.804262 -24.313896) (xy 70.29196 -24.313896) (xy 70.29196 -26.566368)
			(xy 70.160275 -26.698053) (xy 72.09964 -26.698053) (xy 72.09964 -26.643547) (xy 72.107397 -26.589596)
			(xy 72.122752 -26.537298) (xy 72.145394 -26.487717) (xy 72.174861 -26.441863) (xy 72.210554 -26.400669)
			(xy 72.251745 -26.364974) (xy 72.297598 -26.335504) (xy 72.347177 -26.31286) (xy 72.399474 -26.297501)
			(xy 72.453425 -26.289741) (xy 72.480678 -26.289254) (xy 72.507935 -26.289747) (xy 72.561894 -26.297511)
			(xy 72.6142 -26.312871) (xy 72.66379 -26.335513) (xy 72.709656 -26.364978) (xy 72.750865 -26.400666)
			(xy 72.786579 -26.441853) (xy 72.801734 -26.464514) (xy 72.810015 -26.476441) (xy 72.831951 -26.495445)
			(xy 72.858351 -26.5075) (xy 72.887078 -26.51163) (xy 72.915805 -26.5075) (xy 72.942205 -26.495445)
			(xy 72.964141 -26.476441) (xy 72.972422 -26.464514) (xy 72.987539 -26.441825) (xy 73.023252 -26.400629)
			(xy 73.064464 -26.364935) (xy 73.110336 -26.335469) (xy 73.159935 -26.312831) (xy 73.21225 -26.297482)
			(xy 73.266218 -26.289735) (xy 73.293478 -26.289254) (xy 73.320729 -26.289792) (xy 73.374677 -26.297545)
			(xy 73.426972 -26.312898) (xy 73.47655 -26.335537) (xy 73.522402 -26.365001) (xy 73.563593 -26.400692)
			(xy 73.599285 -26.441881) (xy 73.628752 -26.48773) (xy 73.651394 -26.537307) (xy 73.66675 -26.589601)
			(xy 73.674507 -26.643549) (xy 73.674507 -26.698051) (xy 73.66675 -26.751999) (xy 73.651394 -26.804293)
			(xy 73.628752 -26.85387) (xy 73.599285 -26.899719) (xy 73.563593 -26.940908) (xy 73.522402 -26.976599)
			(xy 73.47655 -27.006063) (xy 73.426972 -27.028702) (xy 73.374677 -27.044055) (xy 73.320729 -27.051808)
			(xy 73.293478 -27.05227) (xy 73.26622 -27.0518) (xy 73.212261 -27.044031) (xy 73.159954 -27.028666)
			(xy 73.110365 -27.00602) (xy 73.064499 -26.976552) (xy 73.023291 -26.940861) (xy 72.987577 -26.899672)
			(xy 72.972422 -26.87701) (xy 72.964141 -26.865083) (xy 72.942205 -26.846079) (xy 72.915805 -26.834024)
			(xy 72.887078 -26.829894) (xy 72.858351 -26.834024) (xy 72.831951 -26.846079) (xy 72.810015 -26.865083)
			(xy 72.801734 -26.87701) (xy 72.786588 -26.899679) (xy 72.750879 -26.940873) (xy 72.709671 -26.976568)
			(xy 72.663804 -27.006036) (xy 72.614211 -27.028677) (xy 72.5619 -27.044031) (xy 72.507937 -27.051786)
			(xy 72.480678 -27.05227) (xy 72.453425 -27.051859) (xy 72.399474 -27.044099) (xy 72.347177 -27.02874)
			(xy 72.297598 -27.006096) (xy 72.251745 -26.976626) (xy 72.210554 -26.940931) (xy 72.174861 -26.899737)
			(xy 72.145394 -26.853883) (xy 72.122752 -26.804302) (xy 72.107397 -26.752004) (xy 72.09964 -26.698053)
			(xy 70.160275 -26.698053) (xy 69.8754 -26.982928) (xy 59.1185 -26.982928) (xy 58.88228 -27.219148)
			(xy 58.88228 -28.331922) (xy 61.80277 -28.331922) (xy 61.806841 -28.2763) (xy 61.818967 -28.221863)
			(xy 61.83889 -28.169772) (xy 61.866186 -28.121137) (xy 61.900272 -28.076994) (xy 61.940421 -28.038285)
			(xy 61.985779 -28.005834) (xy 62.035379 -27.980333) (xy 62.088163 -27.962326) (xy 62.143006 -27.952196)
			(xy 62.19874 -27.950159) (xy 62.254177 -27.956259) (xy 62.308134 -27.970365) (xy 62.359463 -27.992177)
			(xy 62.407069 -28.021231) (xy 62.449937 -28.056906) (xy 62.487154 -28.098443) (xy 62.517927 -28.144956)
			(xy 62.541599 -28.195453) (xy 62.557667 -28.24886) (xy 62.565787 -28.304036) (xy 62.566296 -28.331922)
			(xy 62.565787 -28.359808) (xy 62.561368 -28.389834) (xy 64.102994 -28.389834) (xy 64.107065 -28.334212)
			(xy 64.119191 -28.279775) (xy 64.139114 -28.227684) (xy 64.16641 -28.179049) (xy 64.200496 -28.134906)
			(xy 64.240645 -28.096197) (xy 64.286003 -28.063746) (xy 64.335603 -28.038245) (xy 64.388387 -28.020238)
			(xy 64.44323 -28.010108) (xy 64.498964 -28.008071) (xy 64.554401 -28.014171) (xy 64.608358 -28.028277)
			(xy 64.659687 -28.050089) (xy 64.707293 -28.079143) (xy 64.750161 -28.114818) (xy 64.787378 -28.156355)
			(xy 64.818151 -28.202868) (xy 64.820305 -28.207462) (xy 66.166238 -28.207462) (xy 66.166725 -28.18014)
			(xy 66.17507 -28.126136) (xy 66.191558 -28.074039) (xy 66.215804 -28.025068) (xy 66.247239 -27.980371)
			(xy 66.265806 -27.96032) (xy 66.276244 -27.94873) (xy 66.290071 -27.920786) (xy 66.294822 -27.889972)
			(xy 66.290054 -27.859161) (xy 66.276212 -27.831225) (xy 66.265806 -27.819604) (xy 66.247204 -27.799581)
			(xy 66.215746 -27.754891) (xy 66.191495 -27.705914) (xy 66.175021 -27.653805) (xy 66.166712 -27.599788)
			(xy 66.166238 -27.572462) (xy 66.166736 -27.545813) (xy 66.174679 -27.493109) (xy 66.190389 -27.442179)
			(xy 66.213515 -27.394158) (xy 66.243539 -27.350121) (xy 66.279791 -27.31105) (xy 66.321462 -27.277819)
			(xy 66.36762 -27.25117) (xy 66.417234 -27.231698) (xy 66.469196 -27.219838) (xy 66.522346 -27.215855)
			(xy 66.575496 -27.219838) (xy 66.627458 -27.231698) (xy 66.677072 -27.25117) (xy 66.72323 -27.277819)
			(xy 66.764901 -27.31105) (xy 66.801153 -27.350121) (xy 66.831177 -27.394158) (xy 66.854303 -27.442179)
			(xy 66.870013 -27.493109) (xy 66.877956 -27.545813) (xy 66.878454 -27.572462) (xy 66.877922 -27.599782)
			(xy 66.869589 -27.653784) (xy 66.853111 -27.705881) (xy 66.828875 -27.754853) (xy 66.797449 -27.799552)
			(xy 66.778886 -27.819604) (xy 66.768524 -27.831256) (xy 66.75469 -27.859178) (xy 66.749926 -27.889972)
			(xy 66.754674 -27.92077) (xy 66.768492 -27.948699) (xy 66.778886 -27.96032) (xy 66.797498 -27.980334)
			(xy 66.828955 -28.025027) (xy 66.853205 -28.074005) (xy 66.869676 -28.126117) (xy 66.877982 -28.180135)
			(xy 66.878454 -28.207462) (xy 67.06616 -28.207462) (xy 67.066669 -28.180141) (xy 67.075011 -28.126139)
			(xy 67.091496 -28.074043) (xy 67.115736 -28.025072) (xy 67.147164 -27.980372) (xy 67.165728 -27.96032)
			(xy 67.176164 -27.948729) (xy 67.189988 -27.920785) (xy 67.194738 -27.889972) (xy 67.189971 -27.859162)
			(xy 67.176132 -27.831226) (xy 67.165728 -27.819604) (xy 67.14713 -27.799577) (xy 67.115671 -27.754889)
			(xy 67.091418 -27.705913) (xy 67.074943 -27.653804) (xy 67.066634 -27.599788) (xy 67.06616 -27.572462)
			(xy 67.066658 -27.545813) (xy 67.074601 -27.493109) (xy 67.090311 -27.442179) (xy 67.113437 -27.394158)
			(xy 67.143461 -27.350121) (xy 67.179713 -27.31105) (xy 67.221384 -27.277819) (xy 67.267542 -27.25117)
			(xy 67.317156 -27.231698) (xy 67.369118 -27.219838) (xy 67.422268 -27.215855) (xy 67.475418 -27.219838)
			(xy 67.52738 -27.231698) (xy 67.576994 -27.25117) (xy 67.623152 -27.277819) (xy 67.664823 -27.31105)
			(xy 67.701075 -27.350121) (xy 67.731099 -27.394158) (xy 67.754225 -27.442179) (xy 67.769935 -27.493109)
			(xy 67.777878 -27.545813) (xy 67.778376 -27.572462) (xy 67.777838 -27.599782) (xy 67.769505 -27.653783)
			(xy 67.753029 -27.70588) (xy 67.728794 -27.754852) (xy 67.69737 -27.799552) (xy 67.678808 -27.819604)
			(xy 67.668452 -27.831259) (xy 67.65463 -27.859181) (xy 67.649869 -27.889972) (xy 67.654613 -27.920766)
			(xy 67.668421 -27.948696) (xy 67.678808 -27.96032) (xy 67.697423 -27.980331) (xy 67.728879 -28.025025)
			(xy 67.753128 -28.074004) (xy 67.769599 -28.126116) (xy 67.777904 -28.180135) (xy 67.778376 -28.207462)
			(xy 67.966082 -28.207462) (xy 67.966585 -28.180141) (xy 67.974928 -28.126139) (xy 67.991414 -28.074042)
			(xy 68.015655 -28.025071) (xy 68.047085 -27.980372) (xy 68.06565 -27.96032) (xy 68.076084 -27.948728)
			(xy 68.089905 -27.920784) (xy 68.094654 -27.889972) (xy 68.089888 -27.859163) (xy 68.076052 -27.831226)
			(xy 68.06565 -27.819604) (xy 68.047056 -27.799574) (xy 68.015595 -27.754887) (xy 67.991341 -27.705912)
			(xy 67.974866 -27.653804) (xy 67.966556 -27.599788) (xy 67.966082 -27.572462) (xy 67.96658 -27.545813)
			(xy 67.974523 -27.493109) (xy 67.990233 -27.442179) (xy 68.013359 -27.394158) (xy 68.043383 -27.350121)
			(xy 68.079635 -27.31105) (xy 68.121306 -27.277819) (xy 68.167464 -27.25117) (xy 68.217078 -27.231698)
			(xy 68.26904 -27.219838) (xy 68.32219 -27.215855) (xy 68.37534 -27.219838) (xy 68.427302 -27.231698)
			(xy 68.476916 -27.25117) (xy 68.523074 -27.277819) (xy 68.564745 -27.31105) (xy 68.600997 -27.350121)
			(xy 68.631021 -27.394158) (xy 68.654147 -27.442179) (xy 68.669857 -27.493109) (xy 68.6778 -27.545813)
			(xy 68.678298 -27.572462) (xy 68.677754 -27.599782) (xy 68.669422 -27.653782) (xy 68.652946 -27.705879)
			(xy 68.628713 -27.754851) (xy 68.597291 -27.799551) (xy 68.57873 -27.819604) (xy 68.568372 -27.831258)
			(xy 68.554547 -27.85918) (xy 68.549785 -27.889972) (xy 68.55453 -27.920767) (xy 68.568341 -27.948697)
			(xy 68.57873 -27.96032) (xy 68.597349 -27.980328) (xy 68.628804 -28.025023) (xy 68.653051 -28.074003)
			(xy 68.669521 -28.126116) (xy 68.677826 -28.180135) (xy 68.678298 -28.207462) (xy 68.866258 -28.207462)
			(xy 68.86674 -28.18014) (xy 68.875085 -28.126136) (xy 68.891574 -28.074038) (xy 68.915821 -28.025067)
			(xy 68.947258 -27.98037) (xy 68.965826 -27.96032) (xy 68.976262 -27.948729) (xy 68.990086 -27.920785)
			(xy 68.994836 -27.889972) (xy 68.99007 -27.859162) (xy 68.976231 -27.831225) (xy 68.965826 -27.819604)
			(xy 68.947228 -27.799578) (xy 68.915768 -27.754889) (xy 68.891516 -27.705913) (xy 68.875041 -27.653804)
			(xy 68.866732 -27.599788) (xy 68.866258 -27.572462) (xy 68.866756 -27.545813) (xy 68.874699 -27.493109)
			(xy 68.890409 -27.442179) (xy 68.913535 -27.394158) (xy 68.943559 -27.350121) (xy 68.979811 -27.31105)
			(xy 69.021482 -27.277819) (xy 69.06764 -27.25117) (xy 69.117254 -27.231698) (xy 69.169216 -27.219838)
			(xy 69.222366 -27.215855) (xy 69.275516 -27.219838) (xy 69.327478 -27.231698) (xy 69.377092 -27.25117)
			(xy 69.42325 -27.277819) (xy 69.464921 -27.31105) (xy 69.501173 -27.350121) (xy 69.531197 -27.394158)
			(xy 69.554323 -27.442179) (xy 69.570033 -27.493109) (xy 69.577976 -27.545813) (xy 69.578474 -27.572462)
			(xy 69.577937 -27.599782) (xy 69.569604 -27.653783) (xy 69.553127 -27.70588) (xy 69.528893 -27.754852)
			(xy 69.497468 -27.799552) (xy 69.478906 -27.819604) (xy 69.468551 -27.831259) (xy 69.454728 -27.859181)
			(xy 69.449967 -27.889972) (xy 69.453879 -27.915362) (xy 70.95617 -27.915362) (xy 70.956679 -27.886623)
			(xy 70.965306 -27.829795) (xy 70.98236 -27.774904) (xy 71.007455 -27.723193) (xy 71.040022 -27.675831)
			(xy 71.059294 -27.654504) (xy 71.069401 -27.642999) (xy 71.082736 -27.615442) (xy 71.087312 -27.585172)
			(xy 71.082719 -27.554905) (xy 71.069369 -27.527355) (xy 71.059294 -27.51582) (xy 71.040015 -27.4945)
			(xy 71.007448 -27.447137) (xy 70.982356 -27.395424) (xy 70.965308 -27.340531) (xy 70.956689 -27.283702)
			(xy 70.95617 -27.254962) (xy 70.956656 -27.227711) (xy 70.964412 -27.173763) (xy 70.979767 -27.121468)
			(xy 71.002409 -27.071891) (xy 71.031875 -27.026041) (xy 71.067566 -26.98485) (xy 71.108757 -26.949159)
			(xy 71.154607 -26.919693) (xy 71.204184 -26.897051) (xy 71.256479 -26.881696) (xy 71.310427 -26.87394)
			(xy 71.364929 -26.87394) (xy 71.418877 -26.881696) (xy 71.471172 -26.897051) (xy 71.520749 -26.919693)
			(xy 71.566599 -26.949159) (xy 71.60779 -26.98485) (xy 71.643481 -27.026041) (xy 71.672947 -27.071891)
			(xy 71.695589 -27.121468) (xy 71.710944 -27.173763) (xy 71.7187 -27.227711) (xy 71.719186 -27.254962)
			(xy 71.718677 -27.283701) (xy 71.710047 -27.340528) (xy 71.692992 -27.395418) (xy 71.667898 -27.44713)
			(xy 71.635332 -27.494492) (xy 71.616062 -27.51582) (xy 71.606025 -27.527383) (xy 71.592674 -27.554918)
			(xy 71.588081 -27.585172) (xy 71.592658 -27.615429) (xy 71.605993 -27.642971) (xy 71.616062 -27.654504)
			(xy 71.635315 -27.675847) (xy 71.667883 -27.723204) (xy 71.692979 -27.774912) (xy 71.710034 -27.829799)
			(xy 71.718662 -27.886624) (xy 71.719186 -27.915362) (xy 71.7187 -27.942613) (xy 71.710944 -27.996561)
			(xy 71.695589 -28.048856) (xy 71.672947 -28.098433) (xy 71.643481 -28.144283) (xy 71.60779 -28.185474)
			(xy 71.566599 -28.221165) (xy 71.520749 -28.250631) (xy 71.471172 -28.273273) (xy 71.418877 -28.288628)
			(xy 71.364929 -28.296384) (xy 71.310427 -28.296384) (xy 71.256479 -28.288628) (xy 71.204184 -28.273273)
			(xy 71.154607 -28.250631) (xy 71.108757 -28.221165) (xy 71.067566 -28.185474) (xy 71.031875 -28.144283)
			(xy 71.002409 -28.098433) (xy 70.979767 -28.048856) (xy 70.964412 -27.996561) (xy 70.956656 -27.942613)
			(xy 70.95617 -27.915362) (xy 69.453879 -27.915362) (xy 69.454712 -27.920766) (xy 69.468519 -27.948696)
			(xy 69.478906 -27.96032) (xy 69.497521 -27.980331) (xy 69.528977 -28.025025) (xy 69.553226 -28.074004)
			(xy 69.569697 -28.126116) (xy 69.578002 -28.180135) (xy 69.578474 -28.207462) (xy 69.577976 -28.234111)
			(xy 69.570033 -28.286815) (xy 69.554323 -28.337745) (xy 69.531197 -28.385766) (xy 69.501173 -28.429803)
			(xy 69.464921 -28.468874) (xy 69.42325 -28.502105) (xy 69.377092 -28.528754) (xy 69.327478 -28.548226)
			(xy 69.275516 -28.560086) (xy 69.222366 -28.56407) (xy 69.169216 -28.560086) (xy 69.117254 -28.548226)
			(xy 69.06764 -28.528754) (xy 69.021482 -28.502105) (xy 68.979811 -28.468874) (xy 68.943559 -28.429803)
			(xy 68.913535 -28.385766) (xy 68.890409 -28.337745) (xy 68.874699 -28.286815) (xy 68.866756 -28.234111)
			(xy 68.866258 -28.207462) (xy 68.678298 -28.207462) (xy 68.6778 -28.234111) (xy 68.669857 -28.286815)
			(xy 68.654147 -28.337745) (xy 68.631021 -28.385766) (xy 68.600997 -28.429803) (xy 68.564745 -28.468874)
			(xy 68.523074 -28.502105) (xy 68.476916 -28.528754) (xy 68.427302 -28.548226) (xy 68.37534 -28.560086)
			(xy 68.32219 -28.56407) (xy 68.26904 -28.560086) (xy 68.217078 -28.548226) (xy 68.167464 -28.528754)
			(xy 68.121306 -28.502105) (xy 68.079635 -28.468874) (xy 68.043383 -28.429803) (xy 68.013359 -28.385766)
			(xy 67.990233 -28.337745) (xy 67.974523 -28.286815) (xy 67.96658 -28.234111) (xy 67.966082 -28.207462)
			(xy 67.778376 -28.207462) (xy 67.777878 -28.234111) (xy 67.769935 -28.286815) (xy 67.754225 -28.337745)
			(xy 67.731099 -28.385766) (xy 67.701075 -28.429803) (xy 67.664823 -28.468874) (xy 67.623152 -28.502105)
			(xy 67.576994 -28.528754) (xy 67.52738 -28.548226) (xy 67.475418 -28.560086) (xy 67.422268 -28.56407)
			(xy 67.369118 -28.560086) (xy 67.317156 -28.548226) (xy 67.267542 -28.528754) (xy 67.221384 -28.502105)
			(xy 67.179713 -28.468874) (xy 67.143461 -28.429803) (xy 67.113437 -28.385766) (xy 67.090311 -28.337745)
			(xy 67.074601 -28.286815) (xy 67.066658 -28.234111) (xy 67.06616 -28.207462) (xy 66.878454 -28.207462)
			(xy 66.877956 -28.234111) (xy 66.870013 -28.286815) (xy 66.854303 -28.337745) (xy 66.831177 -28.385766)
			(xy 66.801153 -28.429803) (xy 66.764901 -28.468874) (xy 66.72323 -28.502105) (xy 66.677072 -28.528754)
			(xy 66.627458 -28.548226) (xy 66.575496 -28.560086) (xy 66.522346 -28.56407) (xy 66.469196 -28.560086)
			(xy 66.417234 -28.548226) (xy 66.36762 -28.528754) (xy 66.321462 -28.502105) (xy 66.279791 -28.468874)
			(xy 66.243539 -28.429803) (xy 66.213515 -28.385766) (xy 66.190389 -28.337745) (xy 66.174679 -28.286815)
			(xy 66.166736 -28.234111) (xy 66.166238 -28.207462) (xy 64.820305 -28.207462) (xy 64.841823 -28.253365)
			(xy 64.857891 -28.306772) (xy 64.866011 -28.361948) (xy 64.86652 -28.389834) (xy 64.866011 -28.41772)
			(xy 64.857891 -28.472896) (xy 64.841823 -28.526303) (xy 64.818151 -28.5768) (xy 64.787378 -28.623313)
			(xy 64.761709 -28.651962) (xy 76.118974 -28.651962) (xy 76.11943 -28.625646) (xy 76.126651 -28.573513)
			(xy 76.140964 -28.522865) (xy 76.162098 -28.474663) (xy 76.189652 -28.429821) (xy 76.223104 -28.389189)
			(xy 76.242164 -28.371038) (xy 76.252225 -28.361264) (xy 76.266926 -28.337381) (xy 76.274562 -28.310397)
			(xy 76.274555 -28.282352) (xy 76.266905 -28.255371) (xy 76.252193 -28.231497) (xy 76.242164 -28.221686)
			(xy 76.22309 -28.203546) (xy 76.189609 -28.162928) (xy 76.162036 -28.118089) (xy 76.140896 -28.069882)
			(xy 76.126591 -28.019225) (xy 76.119394 -27.967081) (xy 76.118974 -27.940762) (xy 76.119492 -27.913189)
			(xy 76.127435 -27.858619) (xy 76.14315 -27.805761) (xy 76.16631 -27.755715) (xy 76.196433 -27.709524)
			(xy 76.232891 -27.66815) (xy 76.253594 -27.649932) (xy 76.264529 -27.640072) (xy 76.280601 -27.615411)
			(xy 76.28898 -27.587193) (xy 76.288973 -27.557758) (xy 76.28058 -27.529544) (xy 76.264497 -27.504891)
			(xy 76.253594 -27.494992) (xy 76.232875 -27.47679) (xy 76.196405 -27.435419) (xy 76.166274 -27.389227)
			(xy 76.14311 -27.339177) (xy 76.127395 -27.286313) (xy 76.119458 -27.231737) (xy 76.118974 -27.204162)
			(xy 76.11946 -27.176911) (xy 76.127216 -27.122963) (xy 76.142571 -27.070668) (xy 76.165213 -27.021091)
			(xy 76.194679 -26.975241) (xy 76.23037 -26.93405) (xy 76.271561 -26.898359) (xy 76.317411 -26.868893)
			(xy 76.366988 -26.846251) (xy 76.419283 -26.830896) (xy 76.473231 -26.82314) (xy 76.527733 -26.82314)
			(xy 76.581681 -26.830896) (xy 76.633976 -26.846251) (xy 76.683553 -26.868893) (xy 76.729403 -26.898359)
			(xy 76.770594 -26.93405) (xy 76.806285 -26.975241) (xy 76.835751 -27.021091) (xy 76.858393 -27.070668)
			(xy 76.873748 -27.122963) (xy 76.881504 -27.176911) (xy 76.88199 -27.204162) (xy 76.881502 -27.231736)
			(xy 76.873554 -27.286308) (xy 76.857834 -27.339167) (xy 76.834668 -27.389213) (xy 76.804539 -27.435404)
			(xy 76.768076 -27.476776) (xy 76.74737 -27.494992) (xy 76.736514 -27.504931) (xy 76.720445 -27.529571)
			(xy 76.71206 -27.557767) (xy 76.712053 -27.587184) (xy 76.720425 -27.615384) (xy 76.736481 -27.640032)
			(xy 76.74737 -27.649932) (xy 76.768094 -27.66813) (xy 76.804564 -27.7095) (xy 76.834696 -27.755693)
			(xy 76.85786 -27.805744) (xy 76.873573 -27.858609) (xy 76.881508 -27.913186) (xy 76.88199 -27.940762)
			(xy 76.881561 -27.967079) (xy 76.874337 -28.019214) (xy 76.860019 -28.069863) (xy 76.83888 -28.118065)
			(xy 76.81132 -28.162906) (xy 76.777862 -28.203537) (xy 76.7588 -28.221686) (xy 76.748818 -28.231534)
			(xy 76.734119 -28.255397) (xy 76.726476 -28.282361) (xy 76.726469 -28.310388) (xy 76.734098 -28.337356)
			(xy 76.748785 -28.361226) (xy 76.7588 -28.371038) (xy 76.777898 -28.389154) (xy 76.811374 -28.429779)
			(xy 76.838942 -28.474623) (xy 76.860078 -28.522834) (xy 76.874378 -28.573495) (xy 76.881572 -28.625641)
			(xy 76.88199 -28.651962) (xy 78.62697 -28.651962) (xy 78.627428 -28.625646) (xy 78.634648 -28.573513)
			(xy 78.648961 -28.522865) (xy 78.670095 -28.474663) (xy 78.697649 -28.429821) (xy 78.731101 -28.389189)
			(xy 78.75016 -28.371038) (xy 78.760222 -28.361264) (xy 78.774923 -28.337381) (xy 78.782559 -28.310397)
			(xy 78.782552 -28.282352) (xy 78.774902 -28.255371) (xy 78.760189 -28.231496) (xy 78.75016 -28.221686)
			(xy 78.731085 -28.203546) (xy 78.697605 -28.162928) (xy 78.670032 -28.118089) (xy 78.648892 -28.069883)
			(xy 78.634587 -28.019225) (xy 78.62739 -27.967081) (xy 78.62697 -27.940762) (xy 78.627489 -27.913189)
			(xy 78.635432 -27.858619) (xy 78.651147 -27.805761) (xy 78.674307 -27.755715) (xy 78.70443 -27.709524)
			(xy 78.740888 -27.66815) (xy 78.76159 -27.649932) (xy 78.772526 -27.640072) (xy 78.788598 -27.615411)
			(xy 78.796978 -27.587193) (xy 78.796971 -27.557758) (xy 78.788577 -27.529544) (xy 78.772493 -27.504891)
			(xy 78.76159 -27.494992) (xy 78.74087 -27.476791) (xy 78.704401 -27.43542) (xy 78.67427 -27.389228)
			(xy 78.651106 -27.339178) (xy 78.635391 -27.286314) (xy 78.627454 -27.231737) (xy 78.62697 -27.204162)
			(xy 78.627456 -27.176911) (xy 78.635212 -27.122963) (xy 78.650567 -27.070668) (xy 78.673209 -27.021091)
			(xy 78.702675 -26.975241) (xy 78.738366 -26.93405) (xy 78.779557 -26.898359) (xy 78.825407 -26.868893)
			(xy 78.874984 -26.846251) (xy 78.927279 -26.830896) (xy 78.981227 -26.82314) (xy 79.035729 -26.82314)
			(xy 79.089677 -26.830896) (xy 79.141972 -26.846251) (xy 79.191549 -26.868893) (xy 79.237399 -26.898359)
			(xy 79.27859 -26.93405) (xy 79.314281 -26.975241) (xy 79.343747 -27.021091) (xy 79.366389 -27.070668)
			(xy 79.381744 -27.122963) (xy 79.3895 -27.176911) (xy 79.389986 -27.204162) (xy 79.389499 -27.231736)
			(xy 79.381552 -27.286308) (xy 79.365831 -27.339168) (xy 79.342665 -27.389214) (xy 79.312536 -27.435404)
			(xy 79.276072 -27.476776) (xy 79.255366 -27.494992) (xy 79.24451 -27.504931) (xy 79.228442 -27.529571)
			(xy 79.220058 -27.557767) (xy 79.22005 -27.587184) (xy 79.228422 -27.615384) (xy 79.244478 -27.640032)
			(xy 79.255366 -27.649932) (xy 79.276089 -27.66813) (xy 79.31256 -27.709501) (xy 79.342691 -27.755693)
			(xy 79.365855 -27.805744) (xy 79.381569 -27.858609) (xy 79.389504 -27.913186) (xy 79.389986 -27.940762)
			(xy 79.389559 -27.967079) (xy 79.382334 -28.019214) (xy 79.368016 -28.069863) (xy 79.346877 -28.118065)
			(xy 79.319317 -28.162906) (xy 79.285858 -28.203537) (xy 79.266796 -28.221686) (xy 79.256814 -28.231534)
			(xy 79.242116 -28.255397) (xy 79.234473 -28.282361) (xy 79.234466 -28.310388) (xy 79.242095 -28.337356)
			(xy 79.256782 -28.361226) (xy 79.266796 -28.371038) (xy 79.285893 -28.389155) (xy 79.31937 -28.429779)
			(xy 79.346938 -28.474623) (xy 79.368073 -28.522834) (xy 79.382374 -28.573495) (xy 79.389568 -28.625641)
			(xy 79.389986 -28.651962) (xy 79.3895 -28.679213) (xy 79.381744 -28.733161) (xy 79.366389 -28.785456)
			(xy 79.343747 -28.835033) (xy 79.314281 -28.880883) (xy 79.27859 -28.922074) (xy 79.237399 -28.957765)
			(xy 79.191549 -28.987231) (xy 79.141972 -29.009873) (xy 79.089677 -29.025228) (xy 79.035729 -29.032984)
			(xy 78.981227 -29.032984) (xy 78.927279 -29.025228) (xy 78.874984 -29.009873) (xy 78.825407 -28.987231)
			(xy 78.779557 -28.957765) (xy 78.738366 -28.922074) (xy 78.702675 -28.880883) (xy 78.673209 -28.835033)
			(xy 78.650567 -28.785456) (xy 78.635212 -28.733161) (xy 78.627456 -28.679213) (xy 78.62697 -28.651962)
			(xy 76.88199 -28.651962) (xy 76.881504 -28.679213) (xy 76.873748 -28.733161) (xy 76.858393 -28.785456)
			(xy 76.835751 -28.835033) (xy 76.806285 -28.880883) (xy 76.770594 -28.922074) (xy 76.729403 -28.957765)
			(xy 76.683553 -28.987231) (xy 76.633976 -29.009873) (xy 76.581681 -29.025228) (xy 76.527733 -29.032984)
			(xy 76.473231 -29.032984) (xy 76.419283 -29.025228) (xy 76.366988 -29.009873) (xy 76.317411 -28.987231)
			(xy 76.271561 -28.957765) (xy 76.23037 -28.922074) (xy 76.194679 -28.880883) (xy 76.165213 -28.835033)
			(xy 76.142571 -28.785456) (xy 76.127216 -28.733161) (xy 76.11946 -28.679213) (xy 76.118974 -28.651962)
			(xy 64.761709 -28.651962) (xy 64.750161 -28.66485) (xy 64.707293 -28.700525) (xy 64.659687 -28.729579)
			(xy 64.608358 -28.751391) (xy 64.554401 -28.765497) (xy 64.498964 -28.771597) (xy 64.44323 -28.76956)
			(xy 64.388387 -28.75943) (xy 64.335603 -28.741423) (xy 64.286003 -28.715922) (xy 64.240645 -28.683471)
			(xy 64.200496 -28.644762) (xy 64.16641 -28.600619) (xy 64.139114 -28.551984) (xy 64.119191 -28.499893)
			(xy 64.107065 -28.445456) (xy 64.102994 -28.389834) (xy 62.561368 -28.389834) (xy 62.557667 -28.414984)
			(xy 62.541599 -28.468391) (xy 62.517927 -28.518888) (xy 62.487154 -28.565401) (xy 62.449937 -28.606938)
			(xy 62.407069 -28.642613) (xy 62.359463 -28.671667) (xy 62.308134 -28.693479) (xy 62.254177 -28.707585)
			(xy 62.19874 -28.713685) (xy 62.143006 -28.711648) (xy 62.088163 -28.701518) (xy 62.035379 -28.683511)
			(xy 61.985779 -28.65801) (xy 61.940421 -28.625559) (xy 61.900272 -28.58685) (xy 61.866186 -28.542707)
			(xy 61.83889 -28.494072) (xy 61.818967 -28.441981) (xy 61.806841 -28.387544) (xy 61.80277 -28.331922)
			(xy 58.88228 -28.331922) (xy 58.88228 -29.347922) (xy 61.80277 -29.347922) (xy 61.806841 -29.2923)
			(xy 61.818967 -29.237863) (xy 61.83889 -29.185772) (xy 61.866186 -29.137137) (xy 61.900272 -29.092994)
			(xy 61.940421 -29.054285) (xy 61.985779 -29.021834) (xy 62.035379 -28.996333) (xy 62.088163 -28.978326)
			(xy 62.143006 -28.968196) (xy 62.19874 -28.966159) (xy 62.254177 -28.972259) (xy 62.308134 -28.986365)
			(xy 62.359463 -29.008177) (xy 62.407069 -29.037231) (xy 62.449937 -29.072906) (xy 62.487154 -29.114443)
			(xy 62.517927 -29.160956) (xy 62.541599 -29.211453) (xy 62.557667 -29.26486) (xy 62.565787 -29.320036)
			(xy 62.566296 -29.347922) (xy 62.565787 -29.375808) (xy 62.5632 -29.393388) (xy 64.111122 -29.393388)
			(xy 64.115193 -29.337766) (xy 64.127319 -29.283329) (xy 64.147242 -29.231238) (xy 64.174538 -29.182603)
			(xy 64.208624 -29.13846) (xy 64.248773 -29.099751) (xy 64.294131 -29.0673) (xy 64.343731 -29.041799)
			(xy 64.396515 -29.023792) (xy 64.451358 -29.013662) (xy 64.507092 -29.011625) (xy 64.562529 -29.017725)
			(xy 64.616486 -29.031831) (xy 64.667815 -29.053643) (xy 64.715421 -29.082697) (xy 64.758289 -29.118372)
			(xy 64.795506 -29.159909) (xy 64.826279 -29.206422) (xy 64.849951 -29.256919) (xy 64.866019 -29.310326)
			(xy 64.874139 -29.365502) (xy 64.874594 -29.390453) (xy 71.46464 -29.390453) (xy 71.46464 -29.335947)
			(xy 71.472397 -29.281996) (xy 71.487752 -29.229698) (xy 71.510394 -29.180117) (xy 71.539861 -29.134263)
			(xy 71.575554 -29.093069) (xy 71.616745 -29.057374) (xy 71.662598 -29.027904) (xy 71.712177 -29.00526)
			(xy 71.764474 -28.989901) (xy 71.818425 -28.982141) (xy 71.845678 -28.981654) (xy 71.874595 -28.982168)
			(xy 71.931768 -28.990895) (xy 71.986967 -29.008152) (xy 72.03893 -29.033545) (xy 72.086463 -29.06649)
			(xy 72.128479 -29.106233) (xy 72.146668 -29.12872) (xy 72.156565 -29.140525) (xy 72.181889 -29.158044)
			(xy 72.211282 -29.16722) (xy 72.242074 -29.16722) (xy 72.271467 -29.158044) (xy 72.296791 -29.140525)
			(xy 72.306688 -29.12872) (xy 72.324891 -29.106246) (xy 72.366908 -29.06651) (xy 72.41444 -29.033569)
			(xy 72.466399 -29.008179) (xy 72.521595 -28.990921) (xy 72.578763 -28.98219) (xy 72.607678 -28.981654)
			(xy 72.634929 -28.982192) (xy 72.688877 -28.989945) (xy 72.741172 -29.005298) (xy 72.79075 -29.027937)
			(xy 72.836602 -29.057401) (xy 72.877793 -29.093092) (xy 72.913485 -29.134281) (xy 72.942952 -29.18013)
			(xy 72.965594 -29.229707) (xy 72.98095 -29.282001) (xy 72.988707 -29.335949) (xy 72.988707 -29.390451)
			(xy 72.98095 -29.444399) (xy 72.965594 -29.496693) (xy 72.942952 -29.54627) (xy 72.913485 -29.592119)
			(xy 72.877793 -29.633308) (xy 72.836602 -29.668999) (xy 72.79075 -29.698463) (xy 72.741172 -29.721102)
			(xy 72.688877 -29.736455) (xy 72.634929 -29.744208) (xy 72.607678 -29.74467) (xy 72.578763 -29.744107)
			(xy 72.521593 -29.735389) (xy 72.466395 -29.71814) (xy 72.414433 -29.692757) (xy 72.366898 -29.659821)
			(xy 72.324879 -29.620086) (xy 72.306688 -29.597604) (xy 72.296791 -29.585799) (xy 72.271467 -29.56828)
			(xy 72.242074 -29.559104) (xy 72.211282 -29.559104) (xy 72.181889 -29.56828) (xy 72.156565 -29.585799)
			(xy 72.146668 -29.597604) (xy 72.128496 -29.620104) (xy 72.086472 -29.659838) (xy 72.038933 -29.692775)
			(xy 71.986968 -29.71816) (xy 71.931767 -29.735413) (xy 71.874595 -29.744137) (xy 71.845678 -29.74467)
			(xy 71.818425 -29.744259) (xy 71.764474 -29.736499) (xy 71.712177 -29.72114) (xy 71.662598 -29.698496)
			(xy 71.616745 -29.669026) (xy 71.575554 -29.633331) (xy 71.539861 -29.592137) (xy 71.510394 -29.546283)
			(xy 71.487752 -29.496702) (xy 71.472397 -29.444404) (xy 71.46464 -29.390453) (xy 64.874594 -29.390453)
			(xy 64.874648 -29.393388) (xy 64.874139 -29.421274) (xy 64.866019 -29.47645) (xy 64.849951 -29.529857)
			(xy 64.826279 -29.580354) (xy 64.795506 -29.626867) (xy 64.758289 -29.668404) (xy 64.715421 -29.704079)
			(xy 64.667815 -29.733133) (xy 64.616486 -29.754945) (xy 64.562529 -29.769051) (xy 64.507092 -29.775151)
			(xy 64.451358 -29.773114) (xy 64.396515 -29.762984) (xy 64.343731 -29.744977) (xy 64.294131 -29.719476)
			(xy 64.248773 -29.687025) (xy 64.208624 -29.648316) (xy 64.174538 -29.604173) (xy 64.147242 -29.555538)
			(xy 64.127319 -29.503447) (xy 64.115193 -29.44901) (xy 64.111122 -29.393388) (xy 62.5632 -29.393388)
			(xy 62.557667 -29.430984) (xy 62.541599 -29.484391) (xy 62.517927 -29.534888) (xy 62.487154 -29.581401)
			(xy 62.449937 -29.622938) (xy 62.407069 -29.658613) (xy 62.359463 -29.687667) (xy 62.308134 -29.709479)
			(xy 62.254177 -29.723585) (xy 62.19874 -29.729685) (xy 62.143006 -29.727648) (xy 62.088163 -29.717518)
			(xy 62.035379 -29.699511) (xy 61.985779 -29.67401) (xy 61.940421 -29.641559) (xy 61.900272 -29.60285)
			(xy 61.866186 -29.558707) (xy 61.83889 -29.510072) (xy 61.818967 -29.457981) (xy 61.806841 -29.403544)
			(xy 61.80277 -29.347922) (xy 58.88228 -29.347922) (xy 58.88228 -30.714188) (xy 66.559682 -30.714188)
			(xy 66.563753 -30.658566) (xy 66.575879 -30.604129) (xy 66.595802 -30.552038) (xy 66.623098 -30.503403)
			(xy 66.657184 -30.45926) (xy 66.697333 -30.420551) (xy 66.742691 -30.3881) (xy 66.792291 -30.362599)
			(xy 66.845075 -30.344592) (xy 66.899918 -30.334462) (xy 66.955652 -30.332425) (xy 67.011089 -30.338525)
			(xy 67.065046 -30.352631) (xy 67.116375 -30.374443) (xy 67.163981 -30.403497) (xy 67.206849 -30.439172)
			(xy 67.244066 -30.480709) (xy 67.274839 -30.527222) (xy 67.298511 -30.577719) (xy 67.314579 -30.631126)
			(xy 67.322699 -30.686302) (xy 67.323208 -30.714188) (xy 67.322699 -30.742074) (xy 67.320448 -30.757368)
			(xy 67.992496 -30.757368) (xy 67.996567 -30.701746) (xy 68.008693 -30.647309) (xy 68.028616 -30.595218)
			(xy 68.055912 -30.546583) (xy 68.089998 -30.50244) (xy 68.130147 -30.463731) (xy 68.175505 -30.43128)
			(xy 68.225105 -30.405779) (xy 68.277889 -30.387772) (xy 68.332732 -30.377642) (xy 68.388466 -30.375605)
			(xy 68.443903 -30.381705) (xy 68.49786 -30.395811) (xy 68.549189 -30.417623) (xy 68.596795 -30.446677)
			(xy 68.639663 -30.482352) (xy 68.67688 -30.523889) (xy 68.689014 -30.54223) (xy 69.67042 -30.54223)
			(xy 69.674491 -30.486608) (xy 69.686617 -30.432171) (xy 69.70654 -30.38008) (xy 69.733836 -30.331445)
			(xy 69.767922 -30.287302) (xy 69.808071 -30.248593) (xy 69.853429 -30.216142) (xy 69.903029 -30.190641)
			(xy 69.955813 -30.172634) (xy 70.010656 -30.162504) (xy 70.06639 -30.160467) (xy 70.121827 -30.166567)
			(xy 70.175784 -30.180673) (xy 70.227113 -30.202485) (xy 70.274719 -30.231539) (xy 70.317587 -30.267214)
			(xy 70.354804 -30.308751) (xy 70.385577 -30.355264) (xy 70.409249 -30.405761) (xy 70.425317 -30.459168)
			(xy 70.433437 -30.514344) (xy 70.433946 -30.54223) (xy 70.433437 -30.570116) (xy 70.425317 -30.625292)
			(xy 70.409249 -30.678699) (xy 70.385577 -30.729196) (xy 70.354804 -30.775709) (xy 70.317587 -30.817246)
			(xy 70.274719 -30.852921) (xy 70.227113 -30.881975) (xy 70.175784 -30.903787) (xy 70.121827 -30.917893)
			(xy 70.06639 -30.923993) (xy 70.010656 -30.921956) (xy 69.955813 -30.911826) (xy 69.903029 -30.893819)
			(xy 69.853429 -30.868318) (xy 69.808071 -30.835867) (xy 69.767922 -30.797158) (xy 69.733836 -30.753015)
			(xy 69.70654 -30.70438) (xy 69.686617 -30.652289) (xy 69.674491 -30.597852) (xy 69.67042 -30.54223)
			(xy 68.689014 -30.54223) (xy 68.707653 -30.570402) (xy 68.731325 -30.620899) (xy 68.747393 -30.674306)
			(xy 68.755513 -30.729482) (xy 68.756022 -30.757368) (xy 68.755513 -30.785254) (xy 68.747393 -30.84043)
			(xy 68.731325 -30.893837) (xy 68.707653 -30.944334) (xy 68.67688 -30.990847) (xy 68.639663 -31.032384)
			(xy 68.596795 -31.068059) (xy 68.549189 -31.097113) (xy 68.49786 -31.118925) (xy 68.443903 -31.133031)
			(xy 68.388466 -31.139131) (xy 68.332732 -31.137094) (xy 68.277889 -31.126964) (xy 68.225105 -31.108957)
			(xy 68.175505 -31.083456) (xy 68.130147 -31.051005) (xy 68.089998 -31.012296) (xy 68.055912 -30.968153)
			(xy 68.028616 -30.919518) (xy 68.008693 -30.867427) (xy 67.996567 -30.81299) (xy 67.992496 -30.757368)
			(xy 67.320448 -30.757368) (xy 67.314579 -30.79725) (xy 67.298511 -30.850657) (xy 67.274839 -30.901154)
			(xy 67.244066 -30.947667) (xy 67.206849 -30.989204) (xy 67.163981 -31.024879) (xy 67.116375 -31.053933)
			(xy 67.065046 -31.075745) (xy 67.011089 -31.089851) (xy 66.955652 -31.095951) (xy 66.899918 -31.093914)
			(xy 66.845075 -31.083784) (xy 66.792291 -31.065777) (xy 66.742691 -31.040276) (xy 66.697333 -31.007825)
			(xy 66.657184 -30.969116) (xy 66.623098 -30.924973) (xy 66.595802 -30.876338) (xy 66.575879 -30.824247)
			(xy 66.563753 -30.76981) (xy 66.559682 -30.714188) (xy 58.88228 -30.714188) (xy 58.88228 -31.874968)
			(xy 67.159122 -31.874968) (xy 67.163193 -31.819346) (xy 67.175319 -31.764909) (xy 67.195242 -31.712818)
			(xy 67.222538 -31.664183) (xy 67.256624 -31.62004) (xy 67.296773 -31.581331) (xy 67.342131 -31.54888)
			(xy 67.391731 -31.523379) (xy 67.444515 -31.505372) (xy 67.499358 -31.495242) (xy 67.555092 -31.493205)
			(xy 67.610529 -31.499305) (xy 67.664486 -31.513411) (xy 67.715815 -31.535223) (xy 67.763421 -31.564277)
			(xy 67.806289 -31.599952) (xy 67.843506 -31.641489) (xy 67.874279 -31.688002) (xy 67.897951 -31.738499)
			(xy 67.914019 -31.791906) (xy 67.922139 -31.847082) (xy 67.922648 -31.874968) (xy 67.922139 -31.902854)
			(xy 67.914019 -31.95803) (xy 67.897951 -32.011437) (xy 67.874279 -32.061934) (xy 67.843506 -32.108447)
			(xy 67.806289 -32.149984) (xy 67.763421 -32.185659) (xy 67.715815 -32.214713) (xy 67.664486 -32.236525)
			(xy 67.610529 -32.250631) (xy 67.555092 -32.256731) (xy 67.499358 -32.254694) (xy 67.444515 -32.244564)
			(xy 67.391731 -32.226557) (xy 67.342131 -32.201056) (xy 67.296773 -32.168605) (xy 67.256624 -32.129896)
			(xy 67.222538 -32.085753) (xy 67.195242 -32.037118) (xy 67.175319 -31.985027) (xy 67.163193 -31.93059)
			(xy 67.159122 -31.874968) (xy 58.88228 -31.874968) (xy 58.88228 -32.944562) (xy 60.14542 -32.944562)
			(xy 60.149491 -32.88894) (xy 60.161617 -32.834503) (xy 60.18154 -32.782412) (xy 60.208836 -32.733777)
			(xy 60.242922 -32.689634) (xy 60.283071 -32.650925) (xy 60.328429 -32.618474) (xy 60.378029 -32.592973)
			(xy 60.430813 -32.574966) (xy 60.485656 -32.564836) (xy 60.54139 -32.562799) (xy 60.596827 -32.568899)
			(xy 60.650784 -32.583005) (xy 60.702113 -32.604817) (xy 60.749719 -32.633871) (xy 60.792587 -32.669546)
			(xy 60.829804 -32.711083) (xy 60.860577 -32.757596) (xy 60.884249 -32.808093) (xy 60.900317 -32.8615)
			(xy 60.908392 -32.916368) (xy 69.67042 -32.916368) (xy 69.674491 -32.860746) (xy 69.686617 -32.806309)
			(xy 69.70654 -32.754218) (xy 69.733836 -32.705583) (xy 69.767922 -32.66144) (xy 69.808071 -32.622731)
			(xy 69.853429 -32.59028) (xy 69.903029 -32.564779) (xy 69.955813 -32.546772) (xy 70.010656 -32.536642)
			(xy 70.06639 -32.534605) (xy 70.121827 -32.540705) (xy 70.175784 -32.554811) (xy 70.227113 -32.576623)
			(xy 70.274719 -32.605677) (xy 70.317587 -32.641352) (xy 70.354804 -32.682889) (xy 70.385577 -32.729402)
			(xy 70.409249 -32.779899) (xy 70.425317 -32.833306) (xy 70.433437 -32.888482) (xy 70.433946 -32.916368)
			(xy 70.433437 -32.944254) (xy 70.425317 -32.99943) (xy 70.409249 -33.052837) (xy 70.385577 -33.103334)
			(xy 70.354804 -33.149847) (xy 70.317587 -33.191384) (xy 70.274719 -33.227059) (xy 70.227113 -33.256113)
			(xy 70.175784 -33.277925) (xy 70.121827 -33.292031) (xy 70.06639 -33.298131) (xy 70.010656 -33.296094)
			(xy 69.955813 -33.285964) (xy 69.903029 -33.267957) (xy 69.853429 -33.242456) (xy 69.808071 -33.210005)
			(xy 69.767922 -33.171296) (xy 69.733836 -33.127153) (xy 69.70654 -33.078518) (xy 69.686617 -33.026427)
			(xy 69.674491 -32.97199) (xy 69.67042 -32.916368) (xy 60.908392 -32.916368) (xy 60.908437 -32.916676)
			(xy 60.908946 -32.944562) (xy 60.908437 -32.972448) (xy 60.900317 -33.027624) (xy 60.884249 -33.081031)
			(xy 60.860577 -33.131528) (xy 60.829804 -33.178041) (xy 60.792587 -33.219578) (xy 60.749719 -33.255253)
			(xy 60.702113 -33.284307) (xy 60.650784 -33.306119) (xy 60.596827 -33.320225) (xy 60.54139 -33.326325)
			(xy 60.485656 -33.324288) (xy 60.430813 -33.314158) (xy 60.378029 -33.296151) (xy 60.328429 -33.27065)
			(xy 60.283071 -33.238199) (xy 60.242922 -33.19949) (xy 60.208836 -33.155347) (xy 60.18154 -33.106712)
			(xy 60.161617 -33.054621) (xy 60.149491 -33.000184) (xy 60.14542 -32.944562) (xy 58.88228 -32.944562)
			(xy 58.88228 -33.772348) (xy 59.33948 -34.229548) (xy 83.57108 -34.229548)
		)
		(stroke
			(width 0)
			(type solid)
		)
		(fill yes)
		(layer "In13.Cu")
		(net "GND")
	)
	(gr_poly
		(pts
			(xy 214.8586 -399.07464) (xy 218.61272 -399.07464) (xy 219.68206 -400.14398) (xy 224.4852 -400.14398)
			(xy 225.66884 -398.96034) (xy 229.16134 -398.96034) (xy 230.43642 -400.23542) (xy 238.7981 -400.23542)
			(xy 239.05464 -399.97888) (xy 239.05464 -396.7861) (xy 239.54232 -396.29842) (xy 284.25648 -396.29842)
			(xy 286.236918 -394.317982) (xy 286.246313 -394.307959) (xy 286.259863 -394.284075) (xy 286.266557 -394.257444)
			(xy 286.26591 -394.229991) (xy 286.257969 -394.203705) (xy 286.24331 -394.180485) (xy 286.222992 -394.162013)
			(xy 286.198485 -394.149624) (xy 286.185102 -394.146532) (xy 286.156656 -394.140275) (xy 286.10195 -394.120291)
			(xy 286.050918 -394.092223) (xy 286.004745 -394.056724) (xy 285.964505 -394.014618) (xy 285.931134 -393.966885)
			(xy 285.905407 -393.914634) (xy 285.887921 -393.859079) (xy 285.879084 -393.801511) (xy 285.878524 -393.77239)
			(xy 285.878988 -393.745138) (xy 285.886746 -393.69119) (xy 285.902104 -393.638896) (xy 285.924747 -393.589319)
			(xy 285.954216 -393.543469) (xy 285.98991 -393.50228) (xy 286.031103 -393.466591) (xy 286.076956 -393.437127)
			(xy 286.126535 -393.414489) (xy 286.178831 -393.399137) (xy 286.23278 -393.391385) (xy 286.260032 -393.390882)
			(xy 286.289151 -393.391434) (xy 286.346712 -393.400287) (xy 286.40226 -393.417784) (xy 286.454504 -393.443518)
			(xy 286.502232 -393.476891) (xy 286.544335 -393.517128) (xy 286.579835 -393.563295) (xy 286.607909 -393.61432)
			(xy 286.627903 -393.669019) (xy 286.634174 -393.69746) (xy 286.637333 -393.710815) (xy 286.649734 -393.735284)
			(xy 286.668202 -393.755569) (xy 286.691403 -393.770207) (xy 286.717663 -393.77814) (xy 286.745088 -393.778798)
			(xy 286.771698 -393.772131) (xy 286.795573 -393.758622) (xy 286.805624 -393.749276) (xy 290.02355 -390.53135)
			(xy 290.043694 -390.503533) (xy 290.092255 -390.454976) (xy 290.12007 -390.43483) (xy 290.70808 -389.84682)
			(xy 290.70808 -375.442226) (xy 290.680902 -375.428002) (xy 290.65655 -375.414742) (xy 290.611616 -375.382255)
			(xy 290.571862 -375.343603) (xy 290.538125 -375.2996) (xy 290.511117 -375.251175) (xy 290.491407 -375.199349)
			(xy 290.479412 -375.145214) (xy 290.475384 -375.089913) (xy 290.479409 -375.034612) (xy 290.4914 -374.980476)
			(xy 290.511106 -374.928649) (xy 290.538111 -374.880222) (xy 290.571844 -374.836216) (xy 290.611596 -374.797561)
			(xy 290.656528 -374.765071) (xy 290.680902 -374.751854) (xy 290.70808 -374.73763) (xy 290.70808 -371.515894)
			(xy 290.683486 -371.464095) (xy 290.640226 -371.357888) (xy 290.603898 -371.249115) (xy 290.574653 -371.138227)
			(xy 290.552613 -371.025686) (xy 290.537868 -370.911959) (xy 290.530482 -370.797518) (xy 290.530026 -370.740178)
			(xy 290.530487 -370.68408) (xy 290.537605 -370.572109) (xy 290.54425 -370.516404) (xy 290.547298 -370.491766)
			(xy 287.88868 -367.833148) (xy 287.252156 -367.833148) (xy 287.219784 -367.855653) (xy 287.151232 -367.894604)
			(xy 287.079028 -367.926276) (xy 287.003941 -367.950331) (xy 286.926774 -367.966511) (xy 286.848349 -367.974645)
			(xy 286.769503 -367.974645) (xy 286.691078 -367.966511) (xy 286.613911 -367.950331) (xy 286.538824 -367.926276)
			(xy 286.46662 -367.894604) (xy 286.398068 -367.855653) (xy 286.365696 -367.833148) (xy 284.34665 -367.833148)
			(xy 284.333156 -367.833599) (xy 284.307125 -367.840733) (xy 284.283872 -367.854438) (xy 284.265021 -367.873755)
			(xy 284.251889 -367.897336) (xy 284.245393 -367.923533) (xy 284.245304 -367.937034) (xy 284.245304 -367.945416)
			(xy 284.244818 -367.972667) (xy 284.237062 -368.026615) (xy 284.221707 -368.07891) (xy 284.199065 -368.128487)
			(xy 284.169599 -368.174337) (xy 284.133908 -368.215528) (xy 284.092717 -368.251219) (xy 284.046867 -368.280685)
			(xy 283.99729 -368.303327) (xy 283.944995 -368.318682) (xy 283.891047 -368.326438) (xy 283.836545 -368.326438)
			(xy 283.782597 -368.318682) (xy 283.730302 -368.303327) (xy 283.680725 -368.280685) (xy 283.634875 -368.251219)
			(xy 283.593684 -368.215528) (xy 283.557993 -368.174337) (xy 283.528527 -368.128487) (xy 283.505885 -368.07891)
			(xy 283.49053 -368.026615) (xy 283.482774 -367.972667) (xy 283.482288 -367.945416) (xy 283.482288 -367.937034)
			(xy 283.482179 -367.923529) (xy 283.475702 -367.897318) (xy 283.462581 -367.873722) (xy 283.443734 -367.854391)
			(xy 283.420478 -367.840676) (xy 283.39444 -367.833537) (xy 283.380942 -367.833148) (xy 175.31588 -367.833148)
			(xy 173.84268 -366.359948) (xy 173.84268 -365.724186) (xy 173.815502 -365.709962) (xy 173.791326 -365.696633)
			(xy 173.746746 -365.664074) (xy 173.707322 -365.625431) (xy 173.673879 -365.58151) (xy 173.647113 -365.533228)
			(xy 173.627585 -365.481593) (xy 173.615701 -365.427683) (xy 173.61171 -365.372623) (xy 173.615694 -365.317563)
			(xy 173.627571 -365.263652) (xy 173.647094 -365.212014) (xy 173.673853 -365.163729) (xy 173.707291 -365.119804)
			(xy 173.74671 -365.081156) (xy 173.791287 -365.048592) (xy 173.815502 -365.035338) (xy 173.84268 -365.021114)
			(xy 173.84268 -362.027978) (xy 173.83055 -361.986527) (xy 173.80984 -361.90267) (xy 173.801278 -361.860338)
			(xy 173.798484 -361.845352) (xy 173.15688 -361.203748) (xy 168.89984 -361.203748) (xy 167.586406 -362.517182)
			(xy 167.586406 -368.133376) (xy 167.586986 -368.148416) (xy 167.595825 -368.17717) (xy 167.612655 -368.202103)
			(xy 167.636016 -368.221055) (xy 167.663885 -368.232382) (xy 167.693844 -368.235101) (xy 167.723296 -368.228978)
			(xy 167.736774 -368.222276) (xy 167.764958 -368.207606) (xy 167.824989 -368.186803) (xy 167.887634 -368.176214)
			(xy 167.9194 -368.17554) (xy 167.946648 -368.176026) (xy 168.000589 -368.183782) (xy 168.052877 -368.199135)
			(xy 168.102448 -368.221773) (xy 168.148292 -368.251236) (xy 168.189477 -368.286923) (xy 168.225164 -368.328108)
			(xy 168.254627 -368.373952) (xy 168.277265 -368.423523) (xy 168.278584 -368.428016) (xy 285.6517 -368.428016)
			(xy 285.655771 -368.372394) (xy 285.667897 -368.317957) (xy 285.68782 -368.265866) (xy 285.715116 -368.217231)
			(xy 285.749202 -368.173088) (xy 285.789351 -368.134379) (xy 285.834709 -368.101928) (xy 285.884309 -368.076427)
			(xy 285.937093 -368.05842) (xy 285.991936 -368.04829) (xy 286.04767 -368.046253) (xy 286.103107 -368.052353)
			(xy 286.157064 -368.066459) (xy 286.208393 -368.088271) (xy 286.255999 -368.117325) (xy 286.298867 -368.153)
			(xy 286.336084 -368.194537) (xy 286.366857 -368.24105) (xy 286.390529 -368.291547) (xy 286.406597 -368.344954)
			(xy 286.414717 -368.40013) (xy 286.415226 -368.428016) (xy 286.414717 -368.455902) (xy 286.406597 -368.511078)
			(xy 286.390529 -368.564485) (xy 286.366857 -368.614982) (xy 286.336084 -368.661495) (xy 286.298867 -368.703032)
			(xy 286.255999 -368.738707) (xy 286.208393 -368.767761) (xy 286.157064 -368.789573) (xy 286.103107 -368.803679)
			(xy 286.04767 -368.809779) (xy 285.991936 -368.807742) (xy 285.937093 -368.797612) (xy 285.884309 -368.779605)
			(xy 285.834709 -368.754104) (xy 285.789351 -368.721653) (xy 285.749202 -368.682944) (xy 285.715116 -368.638801)
			(xy 285.68782 -368.590166) (xy 285.667897 -368.538075) (xy 285.655771 -368.483638) (xy 285.6517 -368.428016)
			(xy 168.278584 -368.428016) (xy 168.292618 -368.475811) (xy 168.300374 -368.529752) (xy 168.300374 -368.584248)
			(xy 168.292618 -368.638189) (xy 168.277265 -368.690477) (xy 168.254627 -368.740048) (xy 168.225164 -368.785892)
			(xy 168.189477 -368.827077) (xy 168.148292 -368.862764) (xy 168.102448 -368.892227) (xy 168.052877 -368.914865)
			(xy 168.000589 -368.930218) (xy 167.946648 -368.937974) (xy 167.9194 -368.938556) (xy 167.887632 -368.937903)
			(xy 167.824982 -368.927326) (xy 167.764955 -368.9065) (xy 167.736774 -368.89182) (xy 167.723312 -368.885073)
			(xy 167.693846 -368.878947) (xy 167.663873 -368.881668) (xy 167.635991 -368.893) (xy 167.612618 -368.91196)
			(xy 167.595779 -368.936905) (xy 167.586935 -368.965673) (xy 167.586406 -368.98072) (xy 167.586406 -383.747461)
			(xy 271.909282 -383.747461) (xy 271.909282 -383.662739) (xy 271.917335 -383.578402) (xy 271.933369 -383.495212)
			(xy 271.957237 -383.413922) (xy 271.988725 -383.33527) (xy 272.027547 -383.259967) (xy 272.07335 -383.188695)
			(xy 272.125721 -383.122099) (xy 272.184186 -383.060784) (xy 272.248214 -383.005303) (xy 272.317226 -382.95616)
			(xy 272.390596 -382.9138) (xy 272.467661 -382.878605) (xy 272.547723 -382.850896) (xy 272.630056 -382.830922)
			(xy 272.713915 -382.818865) (xy 272.79854 -382.814834) (xy 272.883165 -382.818865) (xy 272.967024 -382.830922)
			(xy 273.049357 -382.850896) (xy 273.129419 -382.878605) (xy 273.206484 -382.9138) (xy 273.279854 -382.95616)
			(xy 273.348866 -383.005303) (xy 273.412894 -383.060784) (xy 273.471359 -383.122099) (xy 273.52373 -383.188695)
			(xy 273.569533 -383.259967) (xy 273.608355 -383.33527) (xy 273.639843 -383.413922) (xy 273.663711 -383.495212)
			(xy 273.679745 -383.578402) (xy 273.687798 -383.662739) (xy 273.688302 -383.7051) (xy 273.687798 -383.747461)
			(xy 273.679745 -383.831798) (xy 273.663711 -383.914988) (xy 273.639843 -383.996278) (xy 273.608355 -384.07493)
			(xy 273.569533 -384.150233) (xy 273.52373 -384.221505) (xy 273.471359 -384.288101) (xy 273.412894 -384.349416)
			(xy 273.348866 -384.404897) (xy 273.279854 -384.45404) (xy 273.206484 -384.4964) (xy 273.129419 -384.531595)
			(xy 273.049357 -384.559304) (xy 272.967024 -384.579278) (xy 272.883165 -384.591335) (xy 272.79854 -384.595367)
			(xy 272.713915 -384.591335) (xy 272.630056 -384.579278) (xy 272.547723 -384.559304) (xy 272.467661 -384.531595)
			(xy 272.390596 -384.4964) (xy 272.317226 -384.45404) (xy 272.248214 -384.404897) (xy 272.184186 -384.349416)
			(xy 272.125721 -384.288101) (xy 272.07335 -384.221505) (xy 272.027547 -384.150233) (xy 271.988725 -384.07493)
			(xy 271.957237 -383.996278) (xy 271.933369 -383.914988) (xy 271.917335 -383.831798) (xy 271.909282 -383.747461)
			(xy 167.586406 -383.747461) (xy 167.586406 -386.144713) (xy 269.99209 -386.144713) (xy 269.99209 -386.059991)
			(xy 270.000143 -385.975654) (xy 270.016177 -385.892464) (xy 270.040045 -385.811174) (xy 270.071533 -385.732522)
			(xy 270.110355 -385.657219) (xy 270.156158 -385.585947) (xy 270.208529 -385.519351) (xy 270.266994 -385.458036)
			(xy 270.331022 -385.402555) (xy 270.400034 -385.353412) (xy 270.473404 -385.311052) (xy 270.550469 -385.275857)
			(xy 270.630531 -385.248148) (xy 270.712864 -385.228174) (xy 270.796723 -385.216117) (xy 270.881348 -385.212086)
			(xy 270.965973 -385.216117) (xy 271.049832 -385.228174) (xy 271.132165 -385.248148) (xy 271.212227 -385.275857)
			(xy 271.289292 -385.311052) (xy 271.362662 -385.353412) (xy 271.431674 -385.402555) (xy 271.495702 -385.458036)
			(xy 271.554167 -385.519351) (xy 271.591975 -385.567428) (xy 280.409902 -385.567428) (xy 280.413973 -385.511806)
			(xy 280.426099 -385.457369) (xy 280.446022 -385.405278) (xy 280.473318 -385.356643) (xy 280.507404 -385.3125)
			(xy 280.547553 -385.273791) (xy 280.592911 -385.24134) (xy 280.642511 -385.215839) (xy 280.695295 -385.197832)
			(xy 280.750138 -385.187702) (xy 280.805872 -385.185665) (xy 280.861309 -385.191765) (xy 280.915266 -385.205871)
			(xy 280.966595 -385.227683) (xy 281.014201 -385.256737) (xy 281.057069 -385.292412) (xy 281.094286 -385.333949)
			(xy 281.125059 -385.380462) (xy 281.148731 -385.430959) (xy 281.164799 -385.484366) (xy 281.172919 -385.539542)
			(xy 281.173428 -385.567428) (xy 281.173131 -385.583684) (xy 281.742132 -385.583684) (xy 281.746203 -385.528062)
			(xy 281.758329 -385.473625) (xy 281.778252 -385.421534) (xy 281.805548 -385.372899) (xy 281.839634 -385.328756)
			(xy 281.879783 -385.290047) (xy 281.925141 -385.257596) (xy 281.974741 -385.232095) (xy 282.027525 -385.214088)
			(xy 282.082368 -385.203958) (xy 282.138102 -385.201921) (xy 282.193539 -385.208021) (xy 282.247496 -385.222127)
			(xy 282.298825 -385.243939) (xy 282.346431 -385.272993) (xy 282.389299 -385.308668) (xy 282.426516 -385.350205)
			(xy 282.457289 -385.396718) (xy 282.480961 -385.447215) (xy 282.497029 -385.500622) (xy 282.505149 -385.555798)
			(xy 282.505658 -385.583684) (xy 282.505149 -385.61157) (xy 282.502113 -385.632198) (xy 282.675582 -385.632198)
			(xy 282.679653 -385.576576) (xy 282.691779 -385.522139) (xy 282.711702 -385.470048) (xy 282.738998 -385.421413)
			(xy 282.773084 -385.37727) (xy 282.813233 -385.338561) (xy 282.858591 -385.30611) (xy 282.908191 -385.280609)
			(xy 282.960975 -385.262602) (xy 283.015818 -385.252472) (xy 283.071552 -385.250435) (xy 283.126989 -385.256535)
			(xy 283.180946 -385.270641) (xy 283.232275 -385.292453) (xy 283.279881 -385.321507) (xy 283.322749 -385.357182)
			(xy 283.359966 -385.398719) (xy 283.390739 -385.445232) (xy 283.414411 -385.495729) (xy 283.430479 -385.549136)
			(xy 283.438599 -385.604312) (xy 283.439108 -385.632198) (xy 283.438599 -385.660084) (xy 283.430479 -385.71526)
			(xy 283.414411 -385.768667) (xy 283.390739 -385.819164) (xy 283.359966 -385.865677) (xy 283.322749 -385.907214)
			(xy 283.279881 -385.942889) (xy 283.232275 -385.971943) (xy 283.180946 -385.993755) (xy 283.126989 -386.007861)
			(xy 283.071552 -386.013961) (xy 283.015818 -386.011924) (xy 282.960975 -386.001794) (xy 282.908191 -385.983787)
			(xy 282.858591 -385.958286) (xy 282.813233 -385.925835) (xy 282.773084 -385.887126) (xy 282.738998 -385.842983)
			(xy 282.711702 -385.794348) (xy 282.691779 -385.742257) (xy 282.679653 -385.68782) (xy 282.675582 -385.632198)
			(xy 282.502113 -385.632198) (xy 282.497029 -385.666746) (xy 282.480961 -385.720153) (xy 282.457289 -385.77065)
			(xy 282.426516 -385.817163) (xy 282.389299 -385.8587) (xy 282.346431 -385.894375) (xy 282.298825 -385.923429)
			(xy 282.247496 -385.945241) (xy 282.193539 -385.959347) (xy 282.138102 -385.965447) (xy 282.082368 -385.96341)
			(xy 282.027525 -385.95328) (xy 281.974741 -385.935273) (xy 281.925141 -385.909772) (xy 281.879783 -385.877321)
			(xy 281.839634 -385.838612) (xy 281.805548 -385.794469) (xy 281.778252 -385.745834) (xy 281.758329 -385.693743)
			(xy 281.746203 -385.639306) (xy 281.742132 -385.583684) (xy 281.173131 -385.583684) (xy 281.172919 -385.595314)
			(xy 281.164799 -385.65049) (xy 281.148731 -385.703897) (xy 281.125059 -385.754394) (xy 281.094286 -385.800907)
			(xy 281.057069 -385.842444) (xy 281.014201 -385.878119) (xy 280.966595 -385.907173) (xy 280.915266 -385.928985)
			(xy 280.861309 -385.943091) (xy 280.805872 -385.949191) (xy 280.750138 -385.947154) (xy 280.695295 -385.937024)
			(xy 280.642511 -385.919017) (xy 280.592911 -385.893516) (xy 280.547553 -385.861065) (xy 280.507404 -385.822356)
			(xy 280.473318 -385.778213) (xy 280.446022 -385.729578) (xy 280.426099 -385.677487) (xy 280.413973 -385.62305)
			(xy 280.409902 -385.567428) (xy 271.591975 -385.567428) (xy 271.606538 -385.585947) (xy 271.652341 -385.657219)
			(xy 271.691163 -385.732522) (xy 271.722651 -385.811174) (xy 271.746519 -385.892464) (xy 271.762553 -385.975654)
			(xy 271.770606 -386.059991) (xy 271.77111 -386.102352) (xy 271.770606 -386.144713) (xy 271.762553 -386.22905)
			(xy 271.746519 -386.31224) (xy 271.722651 -386.39353) (xy 271.691163 -386.472182) (xy 271.652341 -386.547485)
			(xy 271.606538 -386.618757) (xy 271.554167 -386.685353) (xy 271.495702 -386.746668) (xy 271.431674 -386.802149)
			(xy 271.362662 -386.851292) (xy 271.289292 -386.893652) (xy 271.212227 -386.928847) (xy 271.132165 -386.956556)
			(xy 271.049832 -386.97653) (xy 270.965973 -386.988587) (xy 270.881348 -386.992619) (xy 270.796723 -386.988587)
			(xy 270.712864 -386.97653) (xy 270.630531 -386.956556) (xy 270.550469 -386.928847) (xy 270.473404 -386.893652)
			(xy 270.400034 -386.851292) (xy 270.331022 -386.802149) (xy 270.266994 -386.746668) (xy 270.208529 -386.685353)
			(xy 270.156158 -386.618757) (xy 270.110355 -386.547485) (xy 270.071533 -386.472182) (xy 270.040045 -386.39353)
			(xy 270.016177 -386.31224) (xy 270.000143 -386.22905) (xy 269.99209 -386.144713) (xy 167.586406 -386.144713)
			(xy 167.586406 -388.01294) (xy 233.776012 -388.01294) (xy 233.776499 -387.98557) (xy 233.784311 -387.931392)
			(xy 233.799795 -387.878889) (xy 233.822632 -387.829142) (xy 233.852353 -387.783174) (xy 233.869992 -387.762242)
			(xy 233.879191 -387.750886) (xy 233.891374 -387.724339) (xy 233.895555 -387.69543) (xy 233.891391 -387.666519)
			(xy 233.879224 -387.639965) (xy 233.869992 -387.628638) (xy 233.852356 -387.607703) (xy 233.822644 -387.561731)
			(xy 233.799808 -387.511984) (xy 233.784316 -387.459484) (xy 233.776487 -387.405309) (xy 233.776012 -387.37794)
			(xy 233.776493 -387.350687) (xy 233.784245 -387.296736) (xy 233.799597 -387.244437) (xy 233.822236 -387.194856)
			(xy 233.851702 -387.149002) (xy 233.887394 -387.107808) (xy 233.928585 -387.072114) (xy 233.974438 -387.042645)
			(xy 234.024018 -387.020004) (xy 234.076316 -387.004649) (xy 234.130267 -386.996894) (xy 234.15752 -386.996432)
			(xy 234.184891 -386.996879) (xy 234.239071 -387.0047) (xy 234.291575 -387.020193) (xy 234.341321 -387.043039)
			(xy 234.387287 -387.072769) (xy 234.408218 -387.090412) (xy 234.419546 -387.099648) (xy 234.446103 -387.111824)
			(xy 234.47502 -387.115997) (xy 234.503937 -387.111824) (xy 234.530494 -387.099648) (xy 234.541822 -387.090412)
			(xy 234.562755 -387.072771) (xy 234.608723 -387.043047) (xy 234.658469 -387.020201) (xy 234.710971 -387.004705)
			(xy 234.765149 -386.996876) (xy 234.819891 -386.996876) (xy 234.874069 -387.004705) (xy 234.926571 -387.020201)
			(xy 234.976317 -387.043047) (xy 235.022285 -387.072771) (xy 235.043218 -387.090412) (xy 235.054546 -387.099648)
			(xy 235.081103 -387.111824) (xy 235.11002 -387.115997) (xy 235.138937 -387.111824) (xy 235.165494 -387.099648)
			(xy 235.176822 -387.090412) (xy 235.197755 -387.072771) (xy 235.243723 -387.043047) (xy 235.293469 -387.020201)
			(xy 235.345971 -387.004705) (xy 235.400149 -386.996876) (xy 235.454891 -386.996876) (xy 235.509069 -387.004705)
			(xy 235.561571 -387.020201) (xy 235.611317 -387.043047) (xy 235.657285 -387.072771) (xy 235.678218 -387.090412)
			(xy 235.689546 -387.099648) (xy 235.716103 -387.111824) (xy 235.74502 -387.115997) (xy 235.773937 -387.111824)
			(xy 235.800494 -387.099648) (xy 235.811822 -387.090412) (xy 235.832755 -387.072771) (xy 235.878723 -387.043047)
			(xy 235.928469 -387.020201) (xy 235.980971 -387.004705) (xy 236.035149 -386.996876) (xy 236.089891 -386.996876)
			(xy 236.144069 -387.004705) (xy 236.196571 -387.020201) (xy 236.246317 -387.043047) (xy 236.292285 -387.072771)
			(xy 236.313218 -387.090412) (xy 236.324546 -387.099648) (xy 236.351103 -387.111824) (xy 236.38002 -387.115997)
			(xy 236.408937 -387.111824) (xy 236.435494 -387.099648) (xy 236.446822 -387.090412) (xy 236.467755 -387.072771)
			(xy 236.513723 -387.043047) (xy 236.563469 -387.020201) (xy 236.615971 -387.004705) (xy 236.670149 -386.996876)
			(xy 236.724891 -386.996876) (xy 236.779069 -387.004705) (xy 236.831571 -387.020201) (xy 236.881317 -387.043047)
			(xy 236.927285 -387.072771) (xy 236.948218 -387.090412) (xy 236.959546 -387.099648) (xy 236.986103 -387.111824)
			(xy 237.01502 -387.115997) (xy 237.043937 -387.111824) (xy 237.070494 -387.099648) (xy 237.081822 -387.090412)
			(xy 237.102755 -387.072771) (xy 237.148723 -387.043047) (xy 237.198469 -387.020201) (xy 237.250971 -387.004705)
			(xy 237.305149 -386.996876) (xy 237.359891 -386.996876) (xy 237.414069 -387.004705) (xy 237.466571 -387.020201)
			(xy 237.516317 -387.043047) (xy 237.562285 -387.072771) (xy 237.583218 -387.090412) (xy 237.594546 -387.099648)
			(xy 237.621103 -387.111824) (xy 237.65002 -387.115997) (xy 237.678937 -387.111824) (xy 237.705494 -387.099648)
			(xy 237.716822 -387.090412) (xy 237.737755 -387.072771) (xy 237.783723 -387.043047) (xy 237.833469 -387.020201)
			(xy 237.885971 -387.004705) (xy 237.940149 -386.996876) (xy 237.994891 -386.996876) (xy 238.049069 -387.004705)
			(xy 238.101571 -387.020201) (xy 238.151317 -387.043047) (xy 238.197285 -387.072771) (xy 238.218218 -387.090412)
			(xy 238.229546 -387.099648) (xy 238.256103 -387.111824) (xy 238.28502 -387.115997) (xy 238.313937 -387.111824)
			(xy 238.340494 -387.099648) (xy 238.351822 -387.090412) (xy 238.372774 -387.072798) (xy 238.418741 -387.043082)
			(xy 238.468484 -387.020241) (xy 238.52098 -387.004744) (xy 238.575152 -386.996909) (xy 238.60252 -386.996432)
			(xy 238.629775 -386.996836) (xy 238.68373 -387.004597) (xy 238.736032 -387.019958) (xy 238.785615 -387.042605)
			(xy 238.83147 -387.072079) (xy 238.872663 -387.107779) (xy 238.90713 -387.147562) (xy 285.878014 -387.147562)
			(xy 285.882085 -387.09194) (xy 285.894211 -387.037503) (xy 285.914134 -386.985412) (xy 285.94143 -386.936777)
			(xy 285.975516 -386.892634) (xy 286.015665 -386.853925) (xy 286.061023 -386.821474) (xy 286.110623 -386.795973)
			(xy 286.163407 -386.777966) (xy 286.21825 -386.767836) (xy 286.273984 -386.765799) (xy 286.329421 -386.771899)
			(xy 286.383378 -386.786005) (xy 286.434707 -386.807817) (xy 286.482313 -386.836871) (xy 286.525181 -386.872546)
			(xy 286.562398 -386.914083) (xy 286.593171 -386.960596) (xy 286.616843 -387.011093) (xy 286.632911 -387.0645)
			(xy 286.641031 -387.119676) (xy 286.64154 -387.147562) (xy 286.641117 -387.170751) (xy 288.098976 -387.170751)
			(xy 288.098976 -387.116249) (xy 288.106732 -387.062302) (xy 288.122087 -387.010007) (xy 288.144728 -386.96043)
			(xy 288.174193 -386.91458) (xy 288.209884 -386.87339) (xy 288.251074 -386.837698) (xy 288.296923 -386.808231)
			(xy 288.3465 -386.78559) (xy 288.398794 -386.770234) (xy 288.452741 -386.762476) (xy 288.479992 -386.76199)
			(xy 288.509328 -386.762512) (xy 288.567309 -386.771482) (xy 288.623233 -386.789228) (xy 288.675778 -386.81533)
			(xy 288.723705 -386.849173) (xy 288.745168 -386.869178) (xy 288.754974 -386.878143) (xy 288.778141 -386.891128)
			(xy 288.803879 -386.897678) (xy 288.830435 -386.897347) (xy 288.856002 -386.890158) (xy 288.878838 -386.8766)
			(xy 288.888424 -386.8674) (xy 288.906423 -386.84956) (xy 288.946338 -386.818333) (xy 288.990035 -386.792666)
			(xy 289.036746 -386.773011) (xy 289.085648 -386.759712) (xy 289.135881 -386.753005) (xy 289.16122 -386.752592)
			(xy 289.18847 -386.753079) (xy 289.242416 -386.760838) (xy 289.294708 -386.776195) (xy 289.344283 -386.798837)
			(xy 289.390131 -386.828304) (xy 289.431319 -386.863995) (xy 289.467008 -386.905185) (xy 289.496472 -386.951035)
			(xy 289.519112 -387.000611) (xy 289.534466 -387.052904) (xy 289.542222 -387.10685) (xy 289.542222 -387.16135)
			(xy 289.534466 -387.215296) (xy 289.519112 -387.267589) (xy 289.496472 -387.317165) (xy 289.467008 -387.363015)
			(xy 289.431319 -387.404205) (xy 289.390131 -387.439896) (xy 289.344283 -387.469363) (xy 289.294708 -387.492005)
			(xy 289.242416 -387.507362) (xy 289.18847 -387.515121) (xy 289.16122 -387.515608) (xy 289.131884 -387.515079)
			(xy 289.073903 -387.506111) (xy 289.01798 -387.488366) (xy 288.965435 -387.462266) (xy 288.917508 -387.428424)
			(xy 288.896044 -387.40842) (xy 288.886228 -387.399468) (xy 288.863064 -387.386482) (xy 288.837329 -387.37993)
			(xy 288.810775 -387.380259) (xy 288.78521 -387.387445) (xy 288.762374 -387.401) (xy 288.752788 -387.410198)
			(xy 288.734783 -387.428032) (xy 288.69487 -387.459259) (xy 288.651174 -387.484927) (xy 288.604464 -387.504584)
			(xy 288.555562 -387.517884) (xy 288.505331 -387.524592) (xy 288.479992 -387.525006) (xy 288.452741 -387.524524)
			(xy 288.398794 -387.516766) (xy 288.3465 -387.50141) (xy 288.296923 -387.478769) (xy 288.251074 -387.449302)
			(xy 288.209884 -387.41361) (xy 288.174193 -387.37242) (xy 288.144728 -387.32657) (xy 288.122087 -387.276993)
			(xy 288.106732 -387.224698) (xy 288.098976 -387.170751) (xy 286.641117 -387.170751) (xy 286.641031 -387.175448)
			(xy 286.632911 -387.230624) (xy 286.616843 -387.284031) (xy 286.593171 -387.334528) (xy 286.562398 -387.381041)
			(xy 286.525181 -387.422578) (xy 286.482313 -387.458253) (xy 286.434707 -387.487307) (xy 286.383378 -387.509119)
			(xy 286.329421 -387.523225) (xy 286.273984 -387.529325) (xy 286.21825 -387.527288) (xy 286.163407 -387.517158)
			(xy 286.110623 -387.499151) (xy 286.061023 -387.47365) (xy 286.015665 -387.441199) (xy 285.975516 -387.40249)
			(xy 285.94143 -387.358347) (xy 285.914134 -387.309712) (xy 285.894211 -387.257621) (xy 285.882085 -387.203184)
			(xy 285.878014 -387.147562) (xy 238.90713 -387.147562) (xy 238.908357 -387.148978) (xy 238.937823 -387.194838)
			(xy 238.960463 -387.244424) (xy 238.975816 -387.296728) (xy 238.983568 -387.350685) (xy 238.984028 -387.37794)
			(xy 238.983544 -387.40531) (xy 238.975733 -387.459489) (xy 238.960249 -387.511992) (xy 238.937411 -387.56174)
			(xy 238.907689 -387.607707) (xy 238.900966 -387.615684) (xy 281.333954 -387.615684) (xy 281.338025 -387.560062)
			(xy 281.350151 -387.505625) (xy 281.370074 -387.453534) (xy 281.39737 -387.404899) (xy 281.431456 -387.360756)
			(xy 281.471605 -387.322047) (xy 281.516963 -387.289596) (xy 281.566563 -387.264095) (xy 281.619347 -387.246088)
			(xy 281.67419 -387.235958) (xy 281.729924 -387.233921) (xy 281.785361 -387.240021) (xy 281.839318 -387.254127)
			(xy 281.890647 -387.275939) (xy 281.938253 -387.304993) (xy 281.981121 -387.340668) (xy 282.018338 -387.382205)
			(xy 282.049111 -387.428718) (xy 282.072783 -387.479215) (xy 282.088851 -387.532622) (xy 282.096971 -387.587798)
			(xy 282.09748 -387.615684) (xy 282.096971 -387.64357) (xy 282.088851 -387.698746) (xy 282.072783 -387.752153)
			(xy 282.049111 -387.80265) (xy 282.018338 -387.849163) (xy 281.981121 -387.8907) (xy 281.938253 -387.926375)
			(xy 281.890647 -387.955429) (xy 281.839318 -387.977241) (xy 281.785361 -387.991347) (xy 281.729924 -387.997447)
			(xy 281.67419 -387.99541) (xy 281.619347 -387.98528) (xy 281.566563 -387.967273) (xy 281.516963 -387.941772)
			(xy 281.471605 -387.909321) (xy 281.431456 -387.870612) (xy 281.39737 -387.826469) (xy 281.370074 -387.777834)
			(xy 281.350151 -387.725743) (xy 281.338025 -387.671306) (xy 281.333954 -387.615684) (xy 238.900966 -387.615684)
			(xy 238.890048 -387.628638) (xy 238.880776 -387.639938) (xy 238.86861 -387.666507) (xy 238.864447 -387.69543)
			(xy 238.868627 -387.724352) (xy 238.880809 -387.750913) (xy 238.890048 -387.762242) (xy 238.907665 -387.783192)
			(xy 238.937382 -387.829159) (xy 238.960223 -387.878902) (xy 238.975719 -387.931399) (xy 238.983552 -387.985572)
			(xy 238.984028 -388.01294) (xy 238.983559 -388.040191) (xy 238.975798 -388.094139) (xy 238.960439 -388.146432)
			(xy 238.937794 -388.196009) (xy 238.908326 -388.241858) (xy 238.872633 -388.283047) (xy 238.831442 -388.318738)
			(xy 238.785591 -388.348204) (xy 238.736014 -388.370846) (xy 238.683719 -388.386202) (xy 238.629771 -388.393961)
			(xy 238.60252 -388.394448) (xy 238.57515 -388.393983) (xy 238.52097 -388.386167) (xy 238.468466 -388.370678)
			(xy 238.418719 -388.347836) (xy 238.372753 -388.31811) (xy 238.351822 -388.300468) (xy 238.340494 -388.291232)
			(xy 238.313937 -388.279056) (xy 238.28502 -388.274883) (xy 238.256103 -388.279056) (xy 238.229546 -388.291232)
			(xy 238.218218 -388.300468) (xy 238.197285 -388.318109) (xy 238.151317 -388.347833) (xy 238.101571 -388.370679)
			(xy 238.049069 -388.386175) (xy 237.994891 -388.394004) (xy 237.940149 -388.394004) (xy 237.885971 -388.386175)
			(xy 237.833469 -388.370679) (xy 237.783723 -388.347833) (xy 237.737755 -388.318109) (xy 237.716822 -388.300468)
			(xy 237.705494 -388.291232) (xy 237.678937 -388.279056) (xy 237.65002 -388.274883) (xy 237.621103 -388.279056)
			(xy 237.594546 -388.291232) (xy 237.583218 -388.300468) (xy 237.562285 -388.318109) (xy 237.516317 -388.347833)
			(xy 237.466571 -388.370679) (xy 237.414069 -388.386175) (xy 237.359891 -388.394004) (xy 237.305149 -388.394004)
			(xy 237.250971 -388.386175) (xy 237.198469 -388.370679) (xy 237.148723 -388.347833) (xy 237.102755 -388.318109)
			(xy 237.081822 -388.300468) (xy 237.070494 -388.291232) (xy 237.043937 -388.279056) (xy 237.01502 -388.274883)
			(xy 236.986103 -388.279056) (xy 236.959546 -388.291232) (xy 236.948218 -388.300468) (xy 236.927285 -388.318109)
			(xy 236.881317 -388.347833) (xy 236.831571 -388.370679) (xy 236.779069 -388.386175) (xy 236.724891 -388.394004)
			(xy 236.670149 -388.394004) (xy 236.615971 -388.386175) (xy 236.563469 -388.370679) (xy 236.513723 -388.347833)
			(xy 236.467755 -388.318109) (xy 236.446822 -388.300468) (xy 236.435494 -388.291232) (xy 236.408937 -388.279056)
			(xy 236.38002 -388.274883) (xy 236.351103 -388.279056) (xy 236.324546 -388.291232) (xy 236.313218 -388.300468)
			(xy 236.292285 -388.318109) (xy 236.246317 -388.347833) (xy 236.196571 -388.370679) (xy 236.144069 -388.386175)
			(xy 236.089891 -388.394004) (xy 236.035149 -388.394004) (xy 235.980971 -388.386175) (xy 235.928469 -388.370679)
			(xy 235.878723 -388.347833) (xy 235.832755 -388.318109) (xy 235.811822 -388.300468) (xy 235.800494 -388.291232)
			(xy 235.773937 -388.279056) (xy 235.74502 -388.274883) (xy 235.716103 -388.279056) (xy 235.689546 -388.291232)
			(xy 235.678218 -388.300468) (xy 235.657285 -388.318109) (xy 235.611317 -388.347833) (xy 235.561571 -388.370679)
			(xy 235.509069 -388.386175) (xy 235.454891 -388.394004) (xy 235.400149 -388.394004) (xy 235.345971 -388.386175)
			(xy 235.293469 -388.370679) (xy 235.243723 -388.347833) (xy 235.197755 -388.318109) (xy 235.176822 -388.300468)
			(xy 235.165494 -388.291232) (xy 235.138937 -388.279056) (xy 235.11002 -388.274883) (xy 235.081103 -388.279056)
			(xy 235.054546 -388.291232) (xy 235.043218 -388.300468) (xy 235.022285 -388.318109) (xy 234.976317 -388.347833)
			(xy 234.926571 -388.370679) (xy 234.874069 -388.386175) (xy 234.819891 -388.394004) (xy 234.765149 -388.394004)
			(xy 234.710971 -388.386175) (xy 234.658469 -388.370679) (xy 234.608723 -388.347833) (xy 234.562755 -388.318109)
			(xy 234.541822 -388.300468) (xy 234.530494 -388.291232) (xy 234.503937 -388.279056) (xy 234.47502 -388.274883)
			(xy 234.446103 -388.279056) (xy 234.419546 -388.291232) (xy 234.408218 -388.300468) (xy 234.387286 -388.318107)
			(xy 234.341314 -388.34782) (xy 234.291566 -388.370657) (xy 234.239065 -388.386147) (xy 234.184889 -388.393975)
			(xy 234.15752 -388.394448) (xy 234.130271 -388.393903) (xy 234.076328 -388.386151) (xy 234.024036 -388.3708)
			(xy 233.974462 -388.348164) (xy 233.928614 -388.318704) (xy 233.887424 -388.283018) (xy 233.851732 -388.241835)
			(xy 233.822265 -388.195991) (xy 233.799621 -388.14642) (xy 233.784262 -388.094131) (xy 233.776501 -388.040189)
			(xy 233.776012 -388.01294) (xy 167.586406 -388.01294) (xy 167.586406 -388.345934) (xy 168.097962 -388.85749)
			(xy 282.504132 -388.85749) (xy 282.508203 -388.801868) (xy 282.520329 -388.747431) (xy 282.540252 -388.69534)
			(xy 282.567548 -388.646705) (xy 282.601634 -388.602562) (xy 282.641783 -388.563853) (xy 282.687141 -388.531402)
			(xy 282.736741 -388.505901) (xy 282.789525 -388.487894) (xy 282.844368 -388.477764) (xy 282.900102 -388.475727)
			(xy 282.955539 -388.481827) (xy 283.009496 -388.495933) (xy 283.060825 -388.517745) (xy 283.108431 -388.546799)
			(xy 283.151299 -388.582474) (xy 283.188516 -388.624011) (xy 283.219289 -388.670524) (xy 283.242961 -388.721021)
			(xy 283.259029 -388.774428) (xy 283.267149 -388.829604) (xy 283.267658 -388.85749) (xy 283.267149 -388.885376)
			(xy 283.259029 -388.940552) (xy 283.242961 -388.993959) (xy 283.219289 -389.044456) (xy 283.188516 -389.090969)
			(xy 283.151299 -389.132506) (xy 283.108431 -389.168181) (xy 283.060825 -389.197235) (xy 283.009496 -389.219047)
			(xy 282.955539 -389.233153) (xy 282.900102 -389.239253) (xy 282.844368 -389.237216) (xy 282.789525 -389.227086)
			(xy 282.736741 -389.209079) (xy 282.687141 -389.183578) (xy 282.641783 -389.151127) (xy 282.601634 -389.112418)
			(xy 282.567548 -389.068275) (xy 282.540252 -389.01964) (xy 282.520329 -388.967549) (xy 282.508203 -388.913112)
			(xy 282.504132 -388.85749) (xy 168.097962 -388.85749) (xy 168.642747 -389.402275) (xy 286.566098 -389.402275)
			(xy 286.566098 -389.317529) (xy 286.574154 -389.233168) (xy 286.590192 -389.149954) (xy 286.614067 -389.068641)
			(xy 286.645564 -388.989966) (xy 286.684397 -388.914642) (xy 286.730213 -388.843349) (xy 286.7826 -388.776735)
			(xy 286.84108 -388.715402) (xy 286.905127 -388.659906) (xy 286.974158 -388.610748) (xy 287.04755 -388.568376)
			(xy 287.124637 -388.533171) (xy 287.204721 -388.505454) (xy 287.287078 -388.485474) (xy 287.370961 -388.473414)
			(xy 287.45561 -388.469382) (xy 287.540259 -388.473414) (xy 287.624142 -388.485474) (xy 287.706499 -388.505454)
			(xy 287.786583 -388.533171) (xy 287.86367 -388.568376) (xy 287.937062 -388.610748) (xy 288.006093 -388.659906)
			(xy 288.07014 -388.715402) (xy 288.12862 -388.776735) (xy 288.181007 -388.843349) (xy 288.226823 -388.914642)
			(xy 288.265656 -388.989966) (xy 288.297153 -389.068641) (xy 288.321028 -389.149954) (xy 288.337066 -389.233168)
			(xy 288.345122 -389.317529) (xy 288.345626 -389.359902) (xy 288.345122 -389.402275) (xy 288.337066 -389.486636)
			(xy 288.321028 -389.56985) (xy 288.297153 -389.651163) (xy 288.265656 -389.729838) (xy 288.226823 -389.805162)
			(xy 288.181007 -389.876455) (xy 288.12862 -389.943069) (xy 288.07014 -390.004402) (xy 288.006093 -390.059898)
			(xy 287.937062 -390.109056) (xy 287.86367 -390.151428) (xy 287.786583 -390.186633) (xy 287.706499 -390.21435)
			(xy 287.624142 -390.23433) (xy 287.540259 -390.24639) (xy 287.45561 -390.250423) (xy 287.370961 -390.24639)
			(xy 287.287078 -390.23433) (xy 287.204721 -390.21435) (xy 287.124637 -390.186633) (xy 287.04755 -390.151428)
			(xy 286.974158 -390.109056) (xy 286.905127 -390.059898) (xy 286.84108 -390.004402) (xy 286.7826 -389.943069)
			(xy 286.730213 -389.876455) (xy 286.684397 -389.805162) (xy 286.645564 -389.729838) (xy 286.614067 -389.651163)
			(xy 286.590192 -389.56985) (xy 286.574154 -389.486636) (xy 286.566098 -389.402275) (xy 168.642747 -389.402275)
			(xy 172.442632 -393.20216) (xy 172.886622 -393.20216) (xy 172.890693 -393.146538) (xy 172.902819 -393.092101)
			(xy 172.922742 -393.04001) (xy 172.950038 -392.991375) (xy 172.984124 -392.947232) (xy 173.024273 -392.908523)
			(xy 173.069631 -392.876072) (xy 173.119231 -392.850571) (xy 173.172015 -392.832564) (xy 173.226858 -392.822434)
			(xy 173.282592 -392.820397) (xy 173.338029 -392.826497) (xy 173.391986 -392.840603) (xy 173.443315 -392.862415)
			(xy 173.490921 -392.891469) (xy 173.533789 -392.927144) (xy 173.571006 -392.968681) (xy 173.601779 -393.015194)
			(xy 173.609648 -393.03198) (xy 181.812182 -393.03198) (xy 181.816253 -392.976358) (xy 181.828379 -392.921921)
			(xy 181.848302 -392.86983) (xy 181.875598 -392.821195) (xy 181.909684 -392.777052) (xy 181.949833 -392.738343)
			(xy 181.995191 -392.705892) (xy 182.044791 -392.680391) (xy 182.097575 -392.662384) (xy 182.152418 -392.652254)
			(xy 182.208152 -392.650217) (xy 182.263589 -392.656317) (xy 182.317546 -392.670423) (xy 182.368875 -392.692235)
			(xy 182.416481 -392.721289) (xy 182.459349 -392.756964) (xy 182.496566 -392.798501) (xy 182.527339 -392.845014)
			(xy 182.551011 -392.895511) (xy 182.567079 -392.948918) (xy 182.575199 -393.004094) (xy 182.575708 -393.03198)
			(xy 182.575199 -393.059866) (xy 182.567079 -393.115042) (xy 182.551011 -393.168449) (xy 182.527339 -393.218946)
			(xy 182.496566 -393.265459) (xy 182.459349 -393.306996) (xy 182.416481 -393.342671) (xy 182.368875 -393.371725)
			(xy 182.317546 -393.393537) (xy 182.263589 -393.407643) (xy 182.208152 -393.413743) (xy 182.152418 -393.411706)
			(xy 182.097575 -393.401576) (xy 182.044791 -393.383569) (xy 181.995191 -393.358068) (xy 181.949833 -393.325617)
			(xy 181.909684 -393.286908) (xy 181.875598 -393.242765) (xy 181.848302 -393.19413) (xy 181.828379 -393.142039)
			(xy 181.816253 -393.087602) (xy 181.812182 -393.03198) (xy 173.609648 -393.03198) (xy 173.625451 -393.065691)
			(xy 173.641519 -393.119098) (xy 173.649639 -393.174274) (xy 173.650148 -393.20216) (xy 173.649639 -393.230046)
			(xy 173.641519 -393.285222) (xy 173.625451 -393.338629) (xy 173.601779 -393.389126) (xy 173.571006 -393.435639)
			(xy 173.533789 -393.477176) (xy 173.490921 -393.512851) (xy 173.443315 -393.541905) (xy 173.391986 -393.563717)
			(xy 173.338029 -393.577823) (xy 173.282592 -393.583923) (xy 173.226858 -393.581886) (xy 173.172015 -393.571756)
			(xy 173.119231 -393.553749) (xy 173.069631 -393.528248) (xy 173.024273 -393.495797) (xy 172.984124 -393.457088)
			(xy 172.950038 -393.412945) (xy 172.922742 -393.36431) (xy 172.902819 -393.312219) (xy 172.890693 -393.257782)
			(xy 172.886622 -393.20216) (xy 172.442632 -393.20216) (xy 173.313344 -394.072872) (xy 173.324899 -394.083552)
			(xy 173.352876 -394.097913) (xy 173.383896 -394.103088) (xy 173.415019 -394.098585) (xy 173.443301 -394.084832)
			(xy 173.455076 -394.074396) (xy 173.476494 -394.054765) (xy 173.524164 -394.021556) (xy 173.576316 -393.995954)
			(xy 173.631745 -393.978552) (xy 173.689171 -393.96975) (xy 173.71822 -393.96924) (xy 173.745471 -393.969705)
			(xy 173.799417 -393.977464) (xy 173.85171 -393.992823) (xy 173.901284 -394.015467) (xy 173.947131 -394.044936)
			(xy 173.988318 -394.08063) (xy 174.024005 -394.121823) (xy 174.053466 -394.167676) (xy 174.076101 -394.217254)
			(xy 174.09145 -394.26955) (xy 174.0992 -394.323497) (xy 174.099728 -394.350748) (xy 174.099253 -394.378116)
			(xy 174.091422 -394.43229) (xy 174.075927 -394.484788) (xy 174.053087 -394.534532) (xy 174.023371 -394.580501)
			(xy 174.005748 -394.601446) (xy 173.996522 -394.612775) (xy 173.984364 -394.639329) (xy 173.980205 -394.668236)
			(xy 173.984385 -394.697141) (xy 173.996562 -394.723686) (xy 174.005748 -394.73505) (xy 174.021412 -394.75355)
			(xy 174.048422 -394.793802) (xy 174.056057 -394.8085) (xy 243.179528 -394.8085) (xy 243.183558 -394.723892)
			(xy 243.195613 -394.640051) (xy 243.215583 -394.557735) (xy 243.243287 -394.47769) (xy 243.278475 -394.400641)
			(xy 243.320827 -394.327286) (xy 243.36996 -394.258289) (xy 243.42543 -394.194274) (xy 243.486733 -394.135823)
			(xy 243.553315 -394.083463) (xy 243.624573 -394.03767) (xy 243.699861 -393.998857) (xy 243.778498 -393.967377)
			(xy 243.859771 -393.943515) (xy 243.942944 -393.927486) (xy 244.027264 -393.919435) (xy 244.069616 -393.918948)
			(xy 244.11084 -393.919417) (xy 244.192933 -393.927053) (xy 244.273968 -393.94225) (xy 244.35325 -393.964876)
			(xy 244.430099 -393.994739) (xy 244.503857 -394.031582) (xy 244.573891 -394.075088) (xy 244.639601 -394.124886)
			(xy 244.670326 -394.152374) (xy 244.677558 -394.158461) (xy 244.695171 -394.165287) (xy 244.714061 -394.165287)
			(xy 244.731674 -394.158461) (xy 244.738906 -394.152374) (xy 244.769639 -394.124894) (xy 244.835341 -394.075085)
			(xy 244.905371 -394.03157) (xy 244.979128 -393.994723) (xy 245.055977 -393.964858) (xy 245.13526 -393.942233)
			(xy 245.216297 -393.927041) (xy 245.298392 -393.919413) (xy 245.339616 -393.918948) (xy 245.381408 -393.919476)
			(xy 245.464624 -393.927312) (xy 245.546738 -393.942923) (xy 245.627024 -393.96617) (xy 245.704775 -393.996849)
			(xy 245.779303 -394.034689) (xy 245.849951 -394.079356) (xy 245.916096 -394.130456) (xy 245.977154 -394.187537)
			(xy 246.032585 -394.250097) (xy 246.081902 -394.317582) (xy 246.124667 -394.389397) (xy 246.143018 -394.426948)
			(xy 246.170089 -394.428781) (xy 246.223268 -394.43954) (xy 246.274197 -394.458246) (xy 246.321697 -394.484466)
			(xy 246.364667 -394.51759) (xy 246.402111 -394.556853) (xy 246.433163 -394.601345) (xy 246.457102 -394.650034)
			(xy 246.473374 -394.701792) (xy 246.481601 -394.75542) (xy 246.482108 -394.782548) (xy 246.481601 -394.8085)
			(xy 249.114543 -394.8085) (xy 249.118574 -394.723896) (xy 249.130628 -394.640058) (xy 249.150596 -394.557746)
			(xy 249.178298 -394.477704) (xy 249.213483 -394.400658) (xy 249.255833 -394.327305) (xy 249.304963 -394.25831)
			(xy 249.360429 -394.194298) (xy 249.421729 -394.135847) (xy 249.488307 -394.083488) (xy 249.55956 -394.037695)
			(xy 249.634844 -393.998882) (xy 249.713476 -393.967401) (xy 249.794745 -393.943537) (xy 249.877914 -393.927506)
			(xy 249.96223 -393.919453) (xy 250.00458 -393.918948) (xy 250.045803 -393.919439) (xy 250.127896 -393.927072)
			(xy 250.20893 -393.942266) (xy 250.288212 -393.964889) (xy 250.365061 -393.994749) (xy 250.438819 -394.031588)
			(xy 250.508854 -394.075092) (xy 250.574564 -394.124887) (xy 250.60529 -394.152374) (xy 250.612522 -394.158461)
			(xy 250.630135 -394.165287) (xy 250.649025 -394.165287) (xy 250.666638 -394.158461) (xy 250.67387 -394.152374)
			(xy 250.704576 -394.124863) (xy 250.770283 -394.075057) (xy 250.840317 -394.031545) (xy 250.914078 -393.994701)
			(xy 250.990931 -393.96484) (xy 251.070218 -393.942219) (xy 251.151257 -393.927032) (xy 251.233355 -393.91941)
			(xy 251.27458 -393.918948) (xy 251.316356 -393.919458) (xy 251.399539 -393.927298) (xy 251.481621 -393.942901)
			(xy 251.561879 -393.966129) (xy 251.639606 -393.996779) (xy 251.714118 -394.03458) (xy 251.784758 -394.079199)
			(xy 251.850904 -394.130243) (xy 251.911974 -394.187264) (xy 251.96743 -394.249758) (xy 252.016784 -394.317175)
			(xy 252.059601 -394.388922) (xy 252.077982 -394.42644) (xy 252.086364 -394.42644) (xy 252.114351 -394.426946)
			(xy 252.169636 -394.435698) (xy 252.222871 -394.452992) (xy 252.272744 -394.478402) (xy 252.318028 -394.511302)
			(xy 252.357606 -394.550881) (xy 252.390505 -394.596166) (xy 252.415913 -394.646041) (xy 252.433205 -394.699276)
			(xy 252.441955 -394.754561) (xy 252.442472 -394.782548) (xy 252.441992 -394.8085) (xy 255.049428 -394.8085)
			(xy 255.053459 -394.723891) (xy 255.065514 -394.640048) (xy 255.085484 -394.55773) (xy 255.11319 -394.477684)
			(xy 255.148379 -394.400634) (xy 255.190732 -394.327277) (xy 255.239868 -394.258279) (xy 255.295339 -394.194265)
			(xy 255.356645 -394.135813) (xy 255.423229 -394.083453) (xy 255.494489 -394.03766) (xy 255.56978 -393.998849)
			(xy 255.648419 -393.96737) (xy 255.729694 -393.943509) (xy 255.812869 -393.927482) (xy 255.897191 -393.919434)
			(xy 255.939544 -393.918948) (xy 255.980768 -393.919399) (xy 256.062862 -393.927038) (xy 256.143897 -393.942237)
			(xy 256.223179 -393.964866) (xy 256.300029 -393.994731) (xy 256.373786 -394.031576) (xy 256.44382 -394.075085)
			(xy 256.509529 -394.124885) (xy 256.540254 -394.152374) (xy 256.547486 -394.158461) (xy 256.565099 -394.165287)
			(xy 256.583989 -394.165287) (xy 256.601602 -394.158461) (xy 256.608834 -394.152374) (xy 256.639555 -394.12488)
			(xy 256.70526 -394.075073) (xy 256.775292 -394.031559) (xy 256.849049 -393.994713) (xy 256.925901 -393.96485)
			(xy 257.005185 -393.942227) (xy 257.086223 -393.927037) (xy 257.168319 -393.919412) (xy 257.209544 -393.918948)
			(xy 257.251493 -393.919491) (xy 257.335018 -393.927401) (xy 257.417428 -393.943137) (xy 257.497991 -393.96656)
			(xy 257.575991 -393.997462) (xy 257.650737 -394.035568) (xy 257.721565 -394.08054) (xy 257.787845 -394.131979)
			(xy 257.848989 -394.189427) (xy 257.904455 -394.252376) (xy 257.95375 -394.320266) (xy 257.996436 -394.392494)
			(xy 258.014724 -394.43025) (xy 258.027542 -394.428485) (xy 258.053348 -394.426578) (xy 258.066286 -394.42644)
			(xy 258.067048 -394.42644) (xy 258.093699 -394.426845) (xy 258.146403 -394.434796) (xy 258.197335 -394.450512)
			(xy 258.245356 -394.473643) (xy 258.289393 -394.503673) (xy 258.328463 -394.539929) (xy 258.361693 -394.581604)
			(xy 258.388341 -394.627765) (xy 258.407813 -394.677383) (xy 258.419673 -394.729348) (xy 258.423656 -394.7825)
			(xy 258.421708 -394.8085) (xy 260.984428 -394.8085) (xy 260.988458 -394.723893) (xy 261.000513 -394.640052)
			(xy 261.020483 -394.557736) (xy 261.048186 -394.477692) (xy 261.083374 -394.400643) (xy 261.125725 -394.327288)
			(xy 261.174858 -394.258291) (xy 261.230327 -394.194277) (xy 261.29163 -394.135826) (xy 261.358212 -394.083466)
			(xy 261.429469 -394.037672) (xy 261.504756 -393.99886) (xy 261.583392 -393.967379) (xy 261.664664 -393.943516)
			(xy 261.747837 -393.927487) (xy 261.832156 -393.919436) (xy 261.874508 -393.918948) (xy 261.915732 -393.919422)
			(xy 261.997825 -393.927057) (xy 262.078859 -393.942253) (xy 262.158141 -393.964879) (xy 262.234991 -393.994741)
			(xy 262.308749 -394.031583) (xy 262.378783 -394.075089) (xy 262.444493 -394.124886) (xy 262.475218 -394.152374)
			(xy 262.48245 -394.158461) (xy 262.500063 -394.165287) (xy 262.518953 -394.165287) (xy 262.536566 -394.158461)
			(xy 262.543798 -394.152374) (xy 262.574534 -394.124897) (xy 262.640236 -394.075089) (xy 262.710266 -394.031574)
			(xy 262.784021 -393.994725) (xy 262.86087 -393.96486) (xy 262.940153 -393.942234) (xy 263.021189 -393.927042)
			(xy 263.103284 -393.919413) (xy 263.144508 -393.918948) (xy 263.18635 -393.919404) (xy 263.269665 -393.927258)
			(xy 263.351874 -393.942906) (xy 263.432248 -393.966208) (xy 263.510078 -393.996959) (xy 263.584674 -394.034887)
			(xy 263.655376 -394.079656) (xy 263.721559 -394.130869) (xy 263.782638 -394.188075) (xy 263.838071 -394.250766)
			(xy 263.887369 -394.318389) (xy 263.930095 -394.390344) (xy 263.948418 -394.427964) (xy 263.981692 -394.42644)
			(xy 264.008347 -394.426817) (xy 264.061062 -394.434761) (xy 264.112004 -394.450474) (xy 264.160035 -394.473603)
			(xy 264.204083 -394.503633) (xy 264.243162 -394.539893) (xy 264.276401 -394.581572) (xy 264.303057 -394.62774)
			(xy 264.322533 -394.677365) (xy 264.334396 -394.729339) (xy 264.33838 -394.7825) (xy 264.336432 -394.8085)
			(xy 266.919443 -394.8085) (xy 266.923474 -394.723896) (xy 266.935527 -394.640059) (xy 266.955496 -394.557747)
			(xy 266.983198 -394.477706) (xy 267.018382 -394.40066) (xy 267.060731 -394.327308) (xy 267.109861 -394.258313)
			(xy 267.165326 -394.194301) (xy 267.226625 -394.13585) (xy 267.293203 -394.083491) (xy 267.364456 -394.037698)
			(xy 267.439739 -393.998885) (xy 267.51837 -393.967403) (xy 267.599638 -393.943538) (xy 267.682807 -393.927507)
			(xy 267.767122 -393.919453) (xy 267.809472 -393.918948) (xy 267.850695 -393.919444) (xy 267.932787 -393.927077)
			(xy 268.013822 -393.942269) (xy 268.093103 -393.964892) (xy 268.169953 -393.994751) (xy 268.243711 -394.03159)
			(xy 268.313746 -394.075093) (xy 268.379456 -394.124888) (xy 268.410182 -394.152374) (xy 268.417414 -394.158461)
			(xy 268.435027 -394.165287) (xy 268.453917 -394.165287) (xy 268.47153 -394.158461) (xy 268.478762 -394.152374)
			(xy 268.509471 -394.124866) (xy 268.575178 -394.07506) (xy 268.645212 -394.031548) (xy 268.718971 -393.994703)
			(xy 268.795824 -393.964842) (xy 268.87511 -393.942221) (xy 268.95615 -393.927033) (xy 269.038247 -393.91941)
			(xy 269.079472 -393.918948) (xy 269.121265 -393.919428) (xy 269.204483 -393.927269) (xy 269.286598 -393.942885)
			(xy 269.366885 -393.966137) (xy 269.444636 -393.996821) (xy 269.519164 -394.034666) (xy 269.589812 -394.079337)
			(xy 269.655956 -394.130441) (xy 269.717013 -394.187526) (xy 269.772444 -394.250089) (xy 269.821759 -394.317577)
			(xy 269.864524 -394.389396) (xy 269.882874 -394.426948) (xy 269.909949 -394.428731) (xy 269.963129 -394.439499)
			(xy 270.014058 -394.458212) (xy 270.061558 -394.484438) (xy 270.104527 -394.517569) (xy 270.141971 -394.556837)
			(xy 270.173021 -394.601333) (xy 270.19696 -394.650026) (xy 270.213231 -394.701787) (xy 270.221458 -394.755419)
			(xy 270.221964 -394.782548) (xy 270.221496 -394.8085) (xy 272.854328 -394.8085) (xy 272.858359 -394.723891)
			(xy 272.870414 -394.640048) (xy 272.890384 -394.557731) (xy 272.918089 -394.477686) (xy 272.953277 -394.400636)
			(xy 272.995631 -394.32728) (xy 273.044766 -394.258282) (xy 273.100237 -394.194267) (xy 273.161542 -394.135816)
			(xy 273.228125 -394.083456) (xy 273.299385 -394.037663) (xy 273.374675 -393.998851) (xy 273.453313 -393.967372)
			(xy 273.534587 -393.943511) (xy 273.617762 -393.927483) (xy 273.702084 -393.919434) (xy 273.744436 -393.918948)
			(xy 273.78566 -393.919404) (xy 273.867754 -393.927042) (xy 273.948789 -393.942241) (xy 274.028071 -393.964869)
			(xy 274.10492 -393.994734) (xy 274.178678 -394.031578) (xy 274.248712 -394.075086) (xy 274.314421 -394.124886)
			(xy 274.345146 -394.152374) (xy 274.352378 -394.158461) (xy 274.369991 -394.165287) (xy 274.388881 -394.165287)
			(xy 274.406494 -394.158461) (xy 274.413726 -394.152374) (xy 274.44445 -394.124884) (xy 274.510154 -394.075076)
			(xy 274.580186 -394.031562) (xy 274.653943 -393.994716) (xy 274.730794 -393.964852) (xy 274.810078 -393.942228)
			(xy 274.891116 -393.927038) (xy 274.973211 -393.919412) (xy 275.014436 -393.918948) (xy 275.056229 -393.919459)
			(xy 275.139445 -393.927297) (xy 275.221559 -393.942909) (xy 275.301846 -393.966158) (xy 275.379596 -393.996839)
			(xy 275.454125 -394.034681) (xy 275.524773 -394.079349) (xy 275.590918 -394.130451) (xy 275.651975 -394.187533)
			(xy 275.707406 -394.250094) (xy 275.756722 -394.31758) (xy 275.799488 -394.389397) (xy 275.817838 -394.426948)
			(xy 275.844911 -394.428763) (xy 275.898089 -394.439526) (xy 275.949019 -394.458234) (xy 275.996518 -394.484456)
			(xy 276.039488 -394.517583) (xy 276.076932 -394.556848) (xy 276.107984 -394.601341) (xy 276.131922 -394.650031)
			(xy 276.148194 -394.70179) (xy 276.156421 -394.75542) (xy 276.156928 -394.782548) (xy 276.156405 -394.808456)
			(xy 278.916892 -394.808456) (xy 278.917356 -394.766262) (xy 278.925335 -394.682252) (xy 278.941234 -394.599376)
			(xy 278.964912 -394.518378) (xy 278.996156 -394.439987) (xy 279.034684 -394.364908) (xy 279.08015 -394.293815)
			(xy 279.132146 -394.227349) (xy 279.190203 -394.166106) (xy 279.2538 -394.110638) (xy 279.322365 -394.061443)
			(xy 279.395282 -394.018964) (xy 279.471894 -393.983582) (xy 279.551513 -393.955615) (xy 279.633423 -393.935316)
			(xy 279.675082 -393.9286) (xy 279.689459 -393.925944) (xy 279.715949 -393.913606) (xy 279.737852 -393.894262)
			(xy 279.753368 -393.869499) (xy 279.761223 -393.841352) (xy 279.760772 -393.812133) (xy 279.75687 -393.798044)
			(xy 279.744165 -393.755179) (xy 279.726399 -393.667554) (xy 279.717507 -393.578589) (xy 279.716992 -393.533884)
			(xy 279.717496 -393.491536) (xy 279.725547 -393.407222) (xy 279.741576 -393.324056) (xy 279.765437 -393.242789)
			(xy 279.796916 -393.164159) (xy 279.835727 -393.088878) (xy 279.881517 -393.017626) (xy 279.933873 -392.95105)
			(xy 279.992321 -392.889752) (xy 280.056331 -392.834287) (xy 280.125323 -392.785158) (xy 280.198673 -392.742809)
			(xy 280.275716 -392.707625) (xy 280.355755 -392.679923) (xy 280.438064 -392.659955) (xy 280.521899 -392.647902)
			(xy 280.6065 -392.643872) (xy 280.691101 -392.647902) (xy 280.774936 -392.659955) (xy 280.857245 -392.679923)
			(xy 280.937284 -392.707625) (xy 281.014327 -392.742809) (xy 281.087677 -392.785158) (xy 281.156669 -392.834287)
			(xy 281.220679 -392.889752) (xy 281.279127 -392.95105) (xy 281.331483 -393.017626) (xy 281.377273 -393.088878)
			(xy 281.416084 -393.164159) (xy 281.447563 -393.242789) (xy 281.471424 -393.324056) (xy 281.487453 -393.407222)
			(xy 281.495504 -393.491536) (xy 281.496008 -393.533884) (xy 281.495487 -393.576077) (xy 281.487514 -393.660085)
			(xy 281.47162 -393.74296) (xy 281.447947 -393.823957) (xy 281.416708 -393.902348) (xy 281.378185 -393.977427)
			(xy 281.332723 -394.04852) (xy 281.280732 -394.114986) (xy 281.222678 -394.176229) (xy 281.159084 -394.231698)
			(xy 281.090523 -394.280894) (xy 281.017609 -394.323374) (xy 280.941 -394.358757) (xy 280.861383 -394.386724)
			(xy 280.779476 -394.407024) (xy 280.737818 -394.41374) (xy 280.72343 -394.416347) (xy 280.696933 -394.428691)
			(xy 280.675026 -394.448046) (xy 280.659511 -394.472819) (xy 280.651661 -394.500977) (xy 280.652122 -394.530204)
			(xy 280.65603 -394.544296) (xy 280.668744 -394.587158) (xy 280.686507 -394.674785) (xy 280.695395 -394.763751)
			(xy 280.695908 -394.808456) (xy 280.695404 -394.850804) (xy 280.687353 -394.935118) (xy 280.671324 -395.018284)
			(xy 280.647463 -395.099551) (xy 280.615984 -395.178181) (xy 280.577173 -395.253462) (xy 280.531383 -395.324714)
			(xy 280.479027 -395.39129) (xy 280.420579 -395.452588) (xy 280.356569 -395.508053) (xy 280.287577 -395.557182)
			(xy 280.214227 -395.599531) (xy 280.137184 -395.634715) (xy 280.057145 -395.662417) (xy 279.974836 -395.682385)
			(xy 279.891001 -395.694438) (xy 279.8064 -395.698469) (xy 279.721799 -395.694438) (xy 279.637964 -395.682385)
			(xy 279.555655 -395.662417) (xy 279.475616 -395.634715) (xy 279.398573 -395.599531) (xy 279.325223 -395.557182)
			(xy 279.256231 -395.508053) (xy 279.192221 -395.452588) (xy 279.133773 -395.39129) (xy 279.081417 -395.324714)
			(xy 279.035627 -395.253462) (xy 278.996816 -395.178181) (xy 278.965337 -395.099551) (xy 278.941476 -395.018284)
			(xy 278.925447 -394.935118) (xy 278.917396 -394.850804) (xy 278.916892 -394.808456) (xy 276.156405 -394.808456)
			(xy 276.156404 -394.808503) (xy 276.148874 -394.859865) (xy 276.133965 -394.909589) (xy 276.111994 -394.956621)
			(xy 276.083427 -394.999964) (xy 276.048869 -395.038699) (xy 276.009052 -395.072006) (xy 275.964821 -395.099179)
			(xy 275.917114 -395.11964) (xy 275.86694 -395.132958) (xy 275.841206 -395.13637) (xy 275.825747 -395.174161)
			(xy 275.788816 -395.246988) (xy 275.745365 -395.316123) (xy 275.695761 -395.380985) (xy 275.64042 -395.441027)
			(xy 275.579808 -395.495744) (xy 275.514437 -395.544676) (xy 275.444856 -395.587409) (xy 275.371651 -395.623585)
			(xy 275.295438 -395.652899) (xy 275.216859 -395.675104) (xy 275.136576 -395.690013) (xy 275.055264 -395.6975)
			(xy 275.014436 -395.697964) (xy 274.973213 -395.69746) (xy 274.891121 -395.689828) (xy 274.810087 -395.674636)
			(xy 274.730806 -395.652015) (xy 274.653956 -395.622157) (xy 274.580198 -395.585319) (xy 274.510163 -395.541817)
			(xy 274.444452 -395.492024) (xy 274.413726 -395.464538) (xy 274.406494 -395.458451) (xy 274.388881 -395.451625)
			(xy 274.369991 -395.451625) (xy 274.352378 -395.458451) (xy 274.345146 -395.464538) (xy 274.314435 -395.492044)
			(xy 274.248729 -395.54185) (xy 274.178695 -395.585362) (xy 274.104936 -395.622207) (xy 274.028083 -395.652068)
			(xy 273.948797 -395.67469) (xy 273.867758 -395.689878) (xy 273.785661 -395.697501) (xy 273.744436 -395.697964)
			(xy 273.702084 -395.697566) (xy 273.617762 -395.689517) (xy 273.534587 -395.673489) (xy 273.453313 -395.649628)
			(xy 273.374675 -395.618149) (xy 273.299385 -395.579337) (xy 273.228125 -395.533544) (xy 273.161542 -395.481184)
			(xy 273.100237 -395.422733) (xy 273.044766 -395.358718) (xy 272.995631 -395.28972) (xy 272.953277 -395.216364)
			(xy 272.918089 -395.139314) (xy 272.890384 -395.059269) (xy 272.870414 -394.976952) (xy 272.858359 -394.893109)
			(xy 272.854328 -394.8085) (xy 270.221496 -394.8085) (xy 270.221496 -394.808506) (xy 270.213964 -394.859873)
			(xy 270.199053 -394.909601) (xy 270.177077 -394.956636) (xy 270.148504 -394.999982) (xy 270.113939 -395.038718)
			(xy 270.074115 -395.072025) (xy 270.029876 -395.099194) (xy 269.98216 -395.119651) (xy 269.93198 -395.132962)
			(xy 269.906242 -395.13637) (xy 269.890753 -395.174148) (xy 269.853824 -395.246974) (xy 269.810375 -395.316109)
			(xy 269.760773 -395.38097) (xy 269.705435 -395.441012) (xy 269.644826 -395.49573) (xy 269.579457 -395.544662)
			(xy 269.509879 -395.587396) (xy 269.436676 -395.623574) (xy 269.360466 -395.652889) (xy 269.28189 -395.675096)
			(xy 269.201609 -395.690008) (xy 269.120299 -395.697499) (xy 269.079472 -395.697964) (xy 269.038248 -395.6975)
			(xy 268.956155 -395.689862) (xy 268.87512 -395.674665) (xy 268.795838 -395.652037) (xy 268.718989 -395.622174)
			(xy 268.645231 -395.585331) (xy 268.575197 -395.541824) (xy 268.509487 -395.492026) (xy 268.478762 -395.464538)
			(xy 268.47153 -395.458451) (xy 268.453917 -395.451625) (xy 268.435027 -395.451625) (xy 268.417414 -395.458451)
			(xy 268.410182 -395.464538) (xy 268.379456 -395.492026) (xy 268.313752 -395.541834) (xy 268.243721 -395.585348)
			(xy 268.169964 -395.622194) (xy 268.093113 -395.652058) (xy 268.013829 -395.674682) (xy 267.932792 -395.689873)
			(xy 267.850696 -395.6975) (xy 267.809472 -395.697964) (xy 267.767122 -395.697547) (xy 267.682807 -395.689493)
			(xy 267.599638 -395.673462) (xy 267.51837 -395.649597) (xy 267.439739 -395.618115) (xy 267.364456 -395.579302)
			(xy 267.293203 -395.533509) (xy 267.226625 -395.48115) (xy 267.165326 -395.422699) (xy 267.109861 -395.358687)
			(xy 267.060731 -395.289692) (xy 267.018382 -395.21634) (xy 266.983198 -395.139294) (xy 266.955496 -395.059253)
			(xy 266.935527 -394.976941) (xy 266.923474 -394.893104) (xy 266.919443 -394.8085) (xy 264.336432 -394.8085)
			(xy 264.334396 -394.835661) (xy 264.322533 -394.887635) (xy 264.303057 -394.93726) (xy 264.276401 -394.983428)
			(xy 264.243162 -395.025107) (xy 264.204083 -395.061367) (xy 264.160035 -395.091397) (xy 264.112004 -395.114526)
			(xy 264.061062 -395.130239) (xy 264.008347 -395.138183) (xy 263.981692 -395.138656) (xy 263.970516 -395.138402)
			(xy 263.954928 -395.17605) (xy 263.917915 -395.248648) (xy 263.874417 -395.317555) (xy 263.824797 -395.382194)
			(xy 263.769471 -395.442023) (xy 263.708905 -395.496539) (xy 263.643605 -395.545287) (xy 263.57412 -395.587856)
			(xy 263.501032 -395.623891) (xy 263.424953 -395.653088) (xy 263.346523 -395.675203) (xy 263.266399 -395.69005)
			(xy 263.185252 -395.697505) (xy 263.144508 -395.697964) (xy 263.103285 -395.697477) (xy 263.021192 -395.689843)
			(xy 262.940158 -395.674649) (xy 262.860876 -395.652025) (xy 262.784027 -395.622164) (xy 262.710269 -395.585324)
			(xy 262.640234 -395.54182) (xy 262.574524 -395.492025) (xy 262.543798 -395.464538) (xy 262.536566 -395.458451)
			(xy 262.518953 -395.451625) (xy 262.500063 -395.451625) (xy 262.48245 -395.458451) (xy 262.475218 -395.464538)
			(xy 262.444477 -395.492009) (xy 262.378775 -395.541818) (xy 262.308747 -395.585333) (xy 262.234992 -395.622182)
			(xy 262.158144 -395.652048) (xy 262.078861 -395.674675) (xy 261.997826 -395.689868) (xy 261.915732 -395.697498)
			(xy 261.874508 -395.697964) (xy 261.832156 -395.697564) (xy 261.747837 -395.689513) (xy 261.664664 -395.673484)
			(xy 261.583392 -395.649621) (xy 261.504756 -395.61814) (xy 261.429469 -395.579328) (xy 261.358212 -395.533534)
			(xy 261.29163 -395.481174) (xy 261.230327 -395.422723) (xy 261.174858 -395.358709) (xy 261.125725 -395.289712)
			(xy 261.083374 -395.216357) (xy 261.048186 -395.139308) (xy 261.020483 -395.059264) (xy 261.000513 -394.976948)
			(xy 260.988458 -394.893107) (xy 260.984428 -394.8085) (xy 258.421708 -394.8085) (xy 258.419673 -394.835652)
			(xy 258.407813 -394.887617) (xy 258.388341 -394.937235) (xy 258.361693 -394.983396) (xy 258.328463 -395.025071)
			(xy 258.289393 -395.061327) (xy 258.245356 -395.091357) (xy 258.197335 -395.114488) (xy 258.146403 -395.130204)
			(xy 258.093699 -395.138155) (xy 258.067048 -395.138656) (xy 258.03606 -395.137386) (xy 258.020546 -395.175113)
			(xy 257.983557 -395.247826) (xy 257.940067 -395.316846) (xy 257.89044 -395.381595) (xy 257.835094 -395.441529)
			(xy 257.774494 -395.496144) (xy 257.709147 -395.544982) (xy 257.639604 -395.587632) (xy 257.566448 -395.623736)
			(xy 257.490294 -395.65299) (xy 257.411782 -395.67515) (xy 257.331571 -395.690029) (xy 257.250334 -395.697502)
			(xy 257.209544 -395.697964) (xy 257.168321 -395.697455) (xy 257.08623 -395.689824) (xy 257.005196 -395.674633)
			(xy 256.925914 -395.652012) (xy 256.849065 -395.622155) (xy 256.775306 -395.585317) (xy 256.705271 -395.541816)
			(xy 256.63956 -395.492023) (xy 256.608834 -395.464538) (xy 256.601602 -395.458451) (xy 256.583989 -395.451625)
			(xy 256.565099 -395.451625) (xy 256.547486 -395.458451) (xy 256.540254 -395.464538) (xy 256.50954 -395.49204)
			(xy 256.443834 -395.541846) (xy 256.373801 -395.585359) (xy 256.300042 -395.622204) (xy 256.22319 -395.652066)
			(xy 256.143904 -395.674688) (xy 256.062865 -395.689877) (xy 255.980769 -395.697501) (xy 255.939544 -395.697964)
			(xy 255.897191 -395.697566) (xy 255.812869 -395.689518) (xy 255.729694 -395.673491) (xy 255.648419 -395.64963)
			(xy 255.56978 -395.618151) (xy 255.494489 -395.57934) (xy 255.423229 -395.533547) (xy 255.356645 -395.481187)
			(xy 255.295339 -395.422735) (xy 255.239868 -395.358721) (xy 255.190732 -395.289723) (xy 255.148379 -395.216366)
			(xy 255.11319 -395.139316) (xy 255.085484 -395.05927) (xy 255.065514 -394.976952) (xy 255.053459 -394.893109)
			(xy 255.049428 -394.8085) (xy 252.441992 -394.8085) (xy 252.441968 -394.809821) (xy 252.433657 -394.863731)
			(xy 252.417221 -394.915743) (xy 252.393046 -394.964639) (xy 252.361695 -395.009276) (xy 252.323904 -395.04861)
			(xy 252.280556 -395.081721) (xy 252.232666 -395.107832) (xy 252.181353 -395.126335) (xy 252.127819 -395.136795)
			(xy 252.100588 -395.138402) (xy 252.085024 -395.17606) (xy 252.048009 -395.248659) (xy 252.004509 -395.317566)
			(xy 251.954887 -395.382206) (xy 251.89956 -395.442034) (xy 251.838991 -395.496551) (xy 251.773689 -395.545298)
			(xy 251.704202 -395.587866) (xy 251.631111 -395.623899) (xy 251.555031 -395.653095) (xy 251.476599 -395.675208)
			(xy 251.396473 -395.690054) (xy 251.315325 -395.697507) (xy 251.27458 -395.697964) (xy 251.233356 -395.697495)
			(xy 251.151263 -395.689858) (xy 251.070228 -395.674661) (xy 250.990947 -395.652035) (xy 250.914097 -395.622172)
			(xy 250.840339 -395.58533) (xy 250.770305 -395.541823) (xy 250.704595 -395.492026) (xy 250.67387 -395.464538)
			(xy 250.666638 -395.458451) (xy 250.649025 -395.451625) (xy 250.630135 -395.451625) (xy 250.612522 -395.458451)
			(xy 250.60529 -395.464538) (xy 250.574561 -395.492023) (xy 250.508857 -395.54183) (xy 250.438827 -395.585344)
			(xy 250.36507 -395.622192) (xy 250.28822 -395.652056) (xy 250.208936 -395.67468) (xy 250.127899 -395.689872)
			(xy 250.045804 -395.697499) (xy 250.00458 -395.697964) (xy 249.96223 -395.697547) (xy 249.877914 -395.689494)
			(xy 249.794745 -395.673463) (xy 249.713476 -395.649599) (xy 249.634844 -395.618118) (xy 249.55956 -395.579305)
			(xy 249.488307 -395.533512) (xy 249.421729 -395.481153) (xy 249.360429 -395.422702) (xy 249.304963 -395.35869)
			(xy 249.255833 -395.289695) (xy 249.213483 -395.216342) (xy 249.178298 -395.139296) (xy 249.150596 -395.059254)
			(xy 249.130628 -394.976942) (xy 249.118574 -394.893104) (xy 249.114543 -394.8085) (xy 246.481601 -394.8085)
			(xy 246.481601 -394.808504) (xy 246.474071 -394.859867) (xy 246.459161 -394.909593) (xy 246.437189 -394.956626)
			(xy 246.40862 -394.999969) (xy 246.374059 -395.038705) (xy 246.334241 -395.072012) (xy 246.290007 -395.099183)
			(xy 246.242297 -395.119644) (xy 246.192121 -395.132959) (xy 246.166386 -395.13637) (xy 246.15086 -395.174132)
			(xy 246.113933 -395.246957) (xy 246.070488 -395.316091) (xy 246.020888 -395.380952) (xy 245.965553 -395.440994)
			(xy 245.904948 -395.495712) (xy 245.839582 -395.544645) (xy 245.770007 -395.587381) (xy 245.696808 -395.62356)
			(xy 245.620601 -395.652878) (xy 245.542028 -395.675088) (xy 245.461749 -395.690002) (xy 245.380442 -395.697497)
			(xy 245.339616 -395.697964) (xy 245.298393 -395.697472) (xy 245.216301 -395.689839) (xy 245.135266 -395.674645)
			(xy 245.055985 -395.652022) (xy 244.979135 -395.622162) (xy 244.905377 -395.585323) (xy 244.835342 -395.541819)
			(xy 244.769632 -395.492024) (xy 244.738906 -395.464538) (xy 244.731674 -395.458451) (xy 244.714061 -395.451625)
			(xy 244.695171 -395.451625) (xy 244.677558 -395.458451) (xy 244.670326 -395.464538) (xy 244.639624 -395.492053)
			(xy 244.573916 -395.541859) (xy 244.503881 -395.58537) (xy 244.43012 -395.622214) (xy 244.353266 -395.652074)
			(xy 244.273979 -395.674694) (xy 244.192939 -395.68988) (xy 244.110841 -395.697502) (xy 244.069616 -395.697964)
			(xy 244.027264 -395.697565) (xy 243.942944 -395.689514) (xy 243.859771 -395.673485) (xy 243.778498 -395.649623)
			(xy 243.699861 -395.618143) (xy 243.624573 -395.57933) (xy 243.553315 -395.533537) (xy 243.486733 -395.481177)
			(xy 243.42543 -395.422726) (xy 243.36996 -395.358711) (xy 243.320827 -395.289714) (xy 243.278475 -395.216359)
			(xy 243.243287 -395.13931) (xy 243.215583 -395.059265) (xy 243.195613 -394.976949) (xy 243.183558 -394.893108)
			(xy 243.179528 -394.8085) (xy 174.056057 -394.8085) (xy 174.059596 -394.815314) (xy 174.063406 -394.822934)
			(xy 175.419512 -396.17904) (xy 184.41416 -396.17904) (xy 185.88482 -397.6497) (xy 185.88482 -399.90014)
			(xy 186.1693 -400.18462) (xy 192.59296 -400.18462) (xy 194.12458 -398.653) (xy 196.83476 -398.653)
			(xy 198.29018 -400.10842) (xy 203.1619 -400.10842) (xy 204.30998 -398.96034) (xy 207.8609 -398.96034)
			(xy 209.14614 -400.24558) (xy 213.68766 -400.24558)
		)
		(stroke
			(width 0)
			(type solid)
		)
		(fill yes)
		(layer "In13.Cu")
		(net "P12V_AUX")
	)
	(gr_poly
		(pts
			(xy 280.8986 -76.987146) (xy 280.8986 -63.17234) (xy 280.323798 -62.597538) (xy 279.342088 -62.597538)
			(xy 279.317342 -62.611016) (xy 279.264787 -62.631343) (xy 279.209815 -62.643719) (xy 279.15362 -62.647874)
			(xy 279.097425 -62.643719) (xy 279.042453 -62.631343) (xy 278.989898 -62.611016) (xy 278.965152 -62.597538)
			(xy 278.84247 -62.597538) (xy 278.841328 -62.581973) (xy 278.830821 -62.552602) (xy 278.811941 -62.52777)
			(xy 278.786449 -62.509792) (xy 278.75672 -62.500344) (xy 278.741124 -62.499748) (xy 275.811488 -62.499748)
			(xy 275.796031 -62.500281) (xy 275.766529 -62.509518) (xy 275.741151 -62.52717) (xy 275.722227 -62.551614)
			(xy 275.711497 -62.580606) (xy 275.710142 -62.596014) (xy 275.708083 -62.624923) (xy 275.696324 -62.681671)
			(xy 275.676115 -62.735987) (xy 275.647923 -62.786622) (xy 275.612397 -62.832409) (xy 275.570353 -62.872296)
			(xy 275.522759 -62.905364) (xy 275.470712 -62.930853) (xy 275.415407 -62.948175) (xy 275.358119 -62.956933)
			(xy 275.329142 -62.957456) (xy 275.300228 -62.956918) (xy 275.243062 -62.948182) (xy 275.18787 -62.930921)
			(xy 275.135915 -62.905528) (xy 275.088386 -62.872586) (xy 275.046373 -62.832848) (xy 275.028152 -62.81039)
			(xy 275.018255 -62.798585) (xy 274.992931 -62.781066) (xy 274.963538 -62.77189) (xy 274.932746 -62.77189)
			(xy 274.903353 -62.781066) (xy 274.878029 -62.798585) (xy 274.868132 -62.81039) (xy 274.851379 -62.831173)
			(xy 274.813025 -62.868303) (xy 274.769871 -62.899725) (xy 274.722757 -62.924824) (xy 274.672605 -62.94311)
			(xy 274.620394 -62.954227) (xy 274.567142 -62.957957) (xy 274.51389 -62.954227) (xy 274.461679 -62.94311)
			(xy 274.411527 -62.924824) (xy 274.364413 -62.899725) (xy 274.321259 -62.868303) (xy 274.282905 -62.831173)
			(xy 274.266152 -62.81039) (xy 274.256255 -62.798585) (xy 274.230931 -62.781066) (xy 274.201538 -62.77189)
			(xy 274.170746 -62.77189) (xy 274.141353 -62.781066) (xy 274.116029 -62.798585) (xy 274.106132 -62.81039)
			(xy 274.087942 -62.832874) (xy 274.045925 -62.872613) (xy 273.99839 -62.905553) (xy 273.946428 -62.930939)
			(xy 273.891229 -62.948191) (xy 273.834058 -62.956913) (xy 273.805142 -62.957456) (xy 273.776169 -62.956913)
			(xy 273.71889 -62.948142) (xy 273.663596 -62.930812) (xy 273.611559 -62.905319) (xy 273.563974 -62.872251)
			(xy 273.521937 -62.832368) (xy 273.486414 -62.786588) (xy 273.458222 -62.735962) (xy 273.438008 -62.681655)
			(xy 273.426239 -62.624917) (xy 273.424142 -62.596014) (xy 273.422785 -62.580613) (xy 273.41201 -62.551651)
			(xy 273.39308 -62.527226) (xy 273.367721 -62.509567) (xy 273.338246 -62.500285) (xy 273.322796 -62.499748)
			(xy 271.381982 -62.499748) (xy 269.185644 -63.409322) (xy 269.171141 -63.415119) (xy 269.14124 -63.424151)
			(xy 269.125954 -63.427356) (xy 268.455648 -63.560706) (xy 268.44032 -63.563629) (xy 268.409275 -63.566808)
			(xy 268.393672 -63.567056) (xy 265.963908 -63.567056) (xy 264.187775 -63.920313) (xy 278.713942 -63.920313)
			(xy 278.713942 -63.835591) (xy 278.721995 -63.751254) (xy 278.738029 -63.668064) (xy 278.761897 -63.586774)
			(xy 278.793385 -63.508122) (xy 278.832207 -63.432819) (xy 278.87801 -63.361547) (xy 278.930381 -63.294951)
			(xy 278.988846 -63.233636) (xy 279.052874 -63.178155) (xy 279.121886 -63.129012) (xy 279.195256 -63.086652)
			(xy 279.272321 -63.051457) (xy 279.352383 -63.023748) (xy 279.434716 -63.003774) (xy 279.518575 -62.991717)
			(xy 279.6032 -62.987686) (xy 279.687825 -62.991717) (xy 279.771684 -63.003774) (xy 279.854017 -63.023748)
			(xy 279.934079 -63.051457) (xy 280.011144 -63.086652) (xy 280.084514 -63.129012) (xy 280.153526 -63.178155)
			(xy 280.217554 -63.233636) (xy 280.276019 -63.294951) (xy 280.32839 -63.361547) (xy 280.374193 -63.432819)
			(xy 280.413015 -63.508122) (xy 280.444503 -63.586774) (xy 280.468371 -63.668064) (xy 280.484405 -63.751254)
			(xy 280.492458 -63.835591) (xy 280.492962 -63.877952) (xy 280.492458 -63.920313) (xy 280.484405 -64.00465)
			(xy 280.468371 -64.08784) (xy 280.444503 -64.16913) (xy 280.413015 -64.247782) (xy 280.374193 -64.323085)
			(xy 280.32839 -64.394357) (xy 280.276019 -64.460953) (xy 280.217554 -64.522268) (xy 280.153526 -64.577749)
			(xy 280.084514 -64.626892) (xy 280.011144 -64.669252) (xy 279.934079 -64.704447) (xy 279.854017 -64.732156)
			(xy 279.771684 -64.75213) (xy 279.687825 -64.764187) (xy 279.6032 -64.768219) (xy 279.518575 -64.764187)
			(xy 279.434716 -64.75213) (xy 279.352383 -64.732156) (xy 279.272321 -64.704447) (xy 279.195256 -64.669252)
			(xy 279.121886 -64.626892) (xy 279.052874 -64.577749) (xy 278.988846 -64.522268) (xy 278.930381 -64.460953)
			(xy 278.87801 -64.394357) (xy 278.832207 -64.323085) (xy 278.793385 -64.247782) (xy 278.761897 -64.16913)
			(xy 278.738029 -64.08784) (xy 278.721995 -64.00465) (xy 278.713942 -63.920313) (xy 264.187775 -63.920313)
			(xy 251.997752 -66.3448) (xy 263.172954 -66.3448) (xy 263.177025 -66.289178) (xy 263.189151 -66.234741)
			(xy 263.209074 -66.18265) (xy 263.23637 -66.134015) (xy 263.270456 -66.089872) (xy 263.310605 -66.051163)
			(xy 263.355963 -66.018712) (xy 263.405563 -65.993211) (xy 263.458347 -65.975204) (xy 263.51319 -65.965074)
			(xy 263.568924 -65.963037) (xy 263.624361 -65.969137) (xy 263.678318 -65.983243) (xy 263.729647 -66.005055)
			(xy 263.777253 -66.034109) (xy 263.820121 -66.069784) (xy 263.857338 -66.111321) (xy 263.888111 -66.157834)
			(xy 263.911783 -66.208331) (xy 263.927851 -66.261738) (xy 263.930708 -66.281153) (xy 273.401246 -66.281153)
			(xy 273.401246 -66.226647) (xy 273.409003 -66.172697) (xy 273.424358 -66.120399) (xy 273.447 -66.070819)
			(xy 273.476467 -66.024965) (xy 273.512159 -65.983772) (xy 273.553351 -65.948078) (xy 273.599203 -65.918608)
			(xy 273.648782 -65.895964) (xy 273.701079 -65.880606) (xy 273.755029 -65.872847) (xy 273.782282 -65.87236)
			(xy 273.8112 -65.872868) (xy 273.868372 -65.881596) (xy 273.923572 -65.898855) (xy 273.975534 -65.924248)
			(xy 274.023068 -65.957194) (xy 274.065083 -65.996939) (xy 274.083272 -66.019426) (xy 274.093169 -66.031231)
			(xy 274.118493 -66.04875) (xy 274.147886 -66.057926) (xy 274.178678 -66.057926) (xy 274.208071 -66.04875)
			(xy 274.233395 -66.031231) (xy 274.243292 -66.019426) (xy 274.260045 -65.998643) (xy 274.298399 -65.961513)
			(xy 274.341553 -65.930091) (xy 274.388667 -65.904992) (xy 274.438819 -65.886706) (xy 274.49103 -65.875589)
			(xy 274.544282 -65.871859) (xy 274.597534 -65.875589) (xy 274.649745 -65.886706) (xy 274.699897 -65.904992)
			(xy 274.747011 -65.930091) (xy 274.790165 -65.961513) (xy 274.828519 -65.998643) (xy 274.845272 -66.019426)
			(xy 274.855169 -66.031231) (xy 274.880493 -66.04875) (xy 274.909886 -66.057926) (xy 274.940678 -66.057926)
			(xy 274.970071 -66.04875) (xy 274.995395 -66.031231) (xy 275.005292 -66.019426) (xy 275.023494 -65.996952)
			(xy 275.065511 -65.957215) (xy 275.113043 -65.924274) (xy 275.165002 -65.898884) (xy 275.220198 -65.881626)
			(xy 275.277367 -65.872896) (xy 275.306282 -65.87236) (xy 275.333533 -65.872886) (xy 275.368752 -65.877948)
			(xy 278.687535 -65.877948) (xy 278.691558 -65.792204) (xy 278.703593 -65.707213) (xy 278.723534 -65.623723)
			(xy 278.751205 -65.542466) (xy 278.786364 -65.464158) (xy 278.828701 -65.389487) (xy 278.877844 -65.319108)
			(xy 278.933362 -65.25364) (xy 278.994766 -65.193659) (xy 279.061518 -65.139691) (xy 279.133029 -65.092211)
			(xy 279.208673 -65.051636) (xy 279.287784 -65.018323) (xy 279.369666 -64.992564) (xy 279.453601 -64.974586)
			(xy 279.538851 -64.964546) (xy 279.624666 -64.962534) (xy 279.710292 -64.968567) (xy 279.794977 -64.982591)
			(xy 279.877977 -65.004483) (xy 279.958562 -65.034052) (xy 280.036025 -65.071036) (xy 280.109683 -65.115112)
			(xy 280.178891 -65.165892) (xy 280.243039 -65.222929) (xy 280.301565 -65.285723) (xy 280.353953 -65.353721)
			(xy 280.399743 -65.426326) (xy 280.438534 -65.5029) (xy 280.469983 -65.58277) (xy 280.493816 -65.665234)
			(xy 280.509821 -65.749567) (xy 280.517859 -65.835029) (xy 280.518362 -65.877948) (xy 280.517859 -65.920867)
			(xy 280.509821 -66.006329) (xy 280.493816 -66.090662) (xy 280.469983 -66.173126) (xy 280.438534 -66.252996)
			(xy 280.399743 -66.32957) (xy 280.353953 -66.402175) (xy 280.301565 -66.470173) (xy 280.243039 -66.532967)
			(xy 280.178891 -66.590004) (xy 280.109683 -66.640784) (xy 280.036025 -66.68486) (xy 279.958562 -66.721844)
			(xy 279.877977 -66.751413) (xy 279.794977 -66.773305) (xy 279.710292 -66.787329) (xy 279.624666 -66.793362)
			(xy 279.538851 -66.79135) (xy 279.453601 -66.78131) (xy 279.369666 -66.763332) (xy 279.287784 -66.737573)
			(xy 279.208673 -66.70426) (xy 279.133029 -66.663685) (xy 279.061518 -66.616205) (xy 278.994766 -66.562237)
			(xy 278.933362 -66.502256) (xy 278.877844 -66.436788) (xy 278.828701 -66.366409) (xy 278.786364 -66.291738)
			(xy 278.751205 -66.21343) (xy 278.723534 -66.132173) (xy 278.703593 -66.048683) (xy 278.691558 -65.963692)
			(xy 278.687535 -65.877948) (xy 275.368752 -65.877948) (xy 275.387482 -65.88064) (xy 275.439777 -65.895993)
			(xy 275.489356 -65.918633) (xy 275.535207 -65.948098) (xy 275.576399 -65.983789) (xy 275.612091 -66.024978)
			(xy 275.641558 -66.070829) (xy 275.6642 -66.120406) (xy 275.679556 -66.172701) (xy 275.687313 -66.226649)
			(xy 275.687313 -66.281151) (xy 275.679556 -66.335099) (xy 275.6642 -66.387394) (xy 275.641558 -66.436971)
			(xy 275.612091 -66.482822) (xy 275.576399 -66.524011) (xy 275.535207 -66.559702) (xy 275.489356 -66.589167)
			(xy 275.439777 -66.611807) (xy 275.387482 -66.62716) (xy 275.333533 -66.634914) (xy 275.306282 -66.635376)
			(xy 275.277367 -66.634808) (xy 275.220197 -66.626091) (xy 275.164999 -66.608843) (xy 275.113037 -66.583461)
			(xy 275.065502 -66.550526) (xy 275.023483 -66.510792) (xy 275.005292 -66.48831) (xy 274.995395 -66.476505)
			(xy 274.970071 -66.458986) (xy 274.940678 -66.44981) (xy 274.909886 -66.44981) (xy 274.880493 -66.458986)
			(xy 274.855169 -66.476505) (xy 274.845272 -66.48831) (xy 274.828519 -66.509093) (xy 274.790165 -66.546223)
			(xy 274.747011 -66.577645) (xy 274.699897 -66.602744) (xy 274.649745 -66.62103) (xy 274.597534 -66.632147)
			(xy 274.544282 -66.635877) (xy 274.49103 -66.632147) (xy 274.438819 -66.62103) (xy 274.388667 -66.602744)
			(xy 274.341553 -66.577645) (xy 274.298399 -66.546223) (xy 274.260045 -66.509093) (xy 274.243292 -66.48831)
			(xy 274.233395 -66.476505) (xy 274.208071 -66.458986) (xy 274.178678 -66.44981) (xy 274.147886 -66.44981)
			(xy 274.118493 -66.458986) (xy 274.093169 -66.476505) (xy 274.083272 -66.48831) (xy 274.065099 -66.510809)
			(xy 274.023075 -66.550543) (xy 273.975537 -66.58348) (xy 273.923572 -66.608865) (xy 273.868371 -66.626118)
			(xy 273.811199 -66.634843) (xy 273.782282 -66.635376) (xy 273.755029 -66.634953) (xy 273.701079 -66.627194)
			(xy 273.648782 -66.611836) (xy 273.599203 -66.589192) (xy 273.553351 -66.559722) (xy 273.512159 -66.524028)
			(xy 273.476467 -66.482835) (xy 273.447 -66.436981) (xy 273.424358 -66.387401) (xy 273.409003 -66.335103)
			(xy 273.401246 -66.281153) (xy 263.930708 -66.281153) (xy 263.935971 -66.316914) (xy 263.93648 -66.3448)
			(xy 263.935971 -66.372686) (xy 263.927851 -66.427862) (xy 263.911783 -66.481269) (xy 263.888111 -66.531766)
			(xy 263.857338 -66.578279) (xy 263.820121 -66.619816) (xy 263.777253 -66.655491) (xy 263.729647 -66.684545)
			(xy 263.678318 -66.706357) (xy 263.624361 -66.720463) (xy 263.568924 -66.726563) (xy 263.51319 -66.724526)
			(xy 263.458347 -66.714396) (xy 263.405563 -66.696389) (xy 263.355963 -66.670888) (xy 263.310605 -66.638437)
			(xy 263.270456 -66.599728) (xy 263.23637 -66.555585) (xy 263.209074 -66.50695) (xy 263.189151 -66.454859)
			(xy 263.177025 -66.400422) (xy 263.172954 -66.3448) (xy 251.997752 -66.3448) (xy 249.197114 -66.901822)
			(xy 249.009952 -67.08902) (xy 261.67029 -67.08902) (xy 261.674361 -67.033398) (xy 261.686487 -66.978961)
			(xy 261.70641 -66.92687) (xy 261.733706 -66.878235) (xy 261.767792 -66.834092) (xy 261.807941 -66.795383)
			(xy 261.853299 -66.762932) (xy 261.902899 -66.737431) (xy 261.955683 -66.719424) (xy 262.010526 -66.709294)
			(xy 262.06626 -66.707257) (xy 262.121697 -66.713357) (xy 262.175654 -66.727463) (xy 262.226983 -66.749275)
			(xy 262.274589 -66.778329) (xy 262.317457 -66.814004) (xy 262.354674 -66.855541) (xy 262.385447 -66.902054)
			(xy 262.409119 -66.952551) (xy 262.425187 -67.005958) (xy 262.433307 -67.061134) (xy 262.433816 -67.08902)
			(xy 262.433307 -67.116906) (xy 262.425187 -67.172082) (xy 262.409119 -67.225489) (xy 262.385447 -67.275986)
			(xy 262.354674 -67.322499) (xy 262.317457 -67.364036) (xy 262.274589 -67.399711) (xy 262.239293 -67.421252)
			(xy 273.131024 -67.421252) (xy 273.135095 -67.36563) (xy 273.147221 -67.311193) (xy 273.167144 -67.259102)
			(xy 273.19444 -67.210467) (xy 273.228526 -67.166324) (xy 273.268675 -67.127615) (xy 273.314033 -67.095164)
			(xy 273.363633 -67.069663) (xy 273.416417 -67.051656) (xy 273.47126 -67.041526) (xy 273.526994 -67.039489)
			(xy 273.582431 -67.045589) (xy 273.636388 -67.059695) (xy 273.687717 -67.081507) (xy 273.735323 -67.110561)
			(xy 273.778191 -67.146236) (xy 273.815408 -67.187773) (xy 273.846181 -67.234286) (xy 273.869853 -67.284783)
			(xy 273.885921 -67.33819) (xy 273.894041 -67.393366) (xy 273.89455 -67.421252) (xy 274.020024 -67.421252)
			(xy 274.024095 -67.36563) (xy 274.036221 -67.311193) (xy 274.056144 -67.259102) (xy 274.08344 -67.210467)
			(xy 274.117526 -67.166324) (xy 274.157675 -67.127615) (xy 274.203033 -67.095164) (xy 274.252633 -67.069663)
			(xy 274.305417 -67.051656) (xy 274.36026 -67.041526) (xy 274.415994 -67.039489) (xy 274.471431 -67.045589)
			(xy 274.525388 -67.059695) (xy 274.576717 -67.081507) (xy 274.624323 -67.110561) (xy 274.667191 -67.146236)
			(xy 274.704408 -67.187773) (xy 274.735181 -67.234286) (xy 274.758853 -67.284783) (xy 274.774921 -67.33819)
			(xy 274.783041 -67.393366) (xy 274.78355 -67.421252) (xy 274.909024 -67.421252) (xy 274.913095 -67.36563)
			(xy 274.925221 -67.311193) (xy 274.945144 -67.259102) (xy 274.97244 -67.210467) (xy 275.006526 -67.166324)
			(xy 275.046675 -67.127615) (xy 275.092033 -67.095164) (xy 275.141633 -67.069663) (xy 275.194417 -67.051656)
			(xy 275.24926 -67.041526) (xy 275.304994 -67.039489) (xy 275.360431 -67.045589) (xy 275.414388 -67.059695)
			(xy 275.465717 -67.081507) (xy 275.513323 -67.110561) (xy 275.556191 -67.146236) (xy 275.593408 -67.187773)
			(xy 275.624181 -67.234286) (xy 275.647853 -67.284783) (xy 275.663921 -67.33819) (xy 275.672041 -67.393366)
			(xy 275.67255 -67.421252) (xy 275.672041 -67.449138) (xy 275.663921 -67.504314) (xy 275.647853 -67.557721)
			(xy 275.624181 -67.608218) (xy 275.593408 -67.654731) (xy 275.556191 -67.696268) (xy 275.513323 -67.731943)
			(xy 275.465717 -67.760997) (xy 275.414388 -67.782809) (xy 275.360431 -67.796915) (xy 275.304994 -67.803015)
			(xy 275.24926 -67.800978) (xy 275.194417 -67.790848) (xy 275.141633 -67.772841) (xy 275.092033 -67.74734)
			(xy 275.046675 -67.714889) (xy 275.006526 -67.67618) (xy 274.97244 -67.632037) (xy 274.945144 -67.583402)
			(xy 274.925221 -67.531311) (xy 274.913095 -67.476874) (xy 274.909024 -67.421252) (xy 274.78355 -67.421252)
			(xy 274.783041 -67.449138) (xy 274.774921 -67.504314) (xy 274.758853 -67.557721) (xy 274.735181 -67.608218)
			(xy 274.704408 -67.654731) (xy 274.667191 -67.696268) (xy 274.624323 -67.731943) (xy 274.576717 -67.760997)
			(xy 274.525388 -67.782809) (xy 274.471431 -67.796915) (xy 274.415994 -67.803015) (xy 274.36026 -67.800978)
			(xy 274.305417 -67.790848) (xy 274.252633 -67.772841) (xy 274.203033 -67.74734) (xy 274.157675 -67.714889)
			(xy 274.117526 -67.67618) (xy 274.08344 -67.632037) (xy 274.056144 -67.583402) (xy 274.036221 -67.531311)
			(xy 274.024095 -67.476874) (xy 274.020024 -67.421252) (xy 273.89455 -67.421252) (xy 273.894041 -67.449138)
			(xy 273.885921 -67.504314) (xy 273.869853 -67.557721) (xy 273.846181 -67.608218) (xy 273.815408 -67.654731)
			(xy 273.778191 -67.696268) (xy 273.735323 -67.731943) (xy 273.687717 -67.760997) (xy 273.636388 -67.782809)
			(xy 273.582431 -67.796915) (xy 273.526994 -67.803015) (xy 273.47126 -67.800978) (xy 273.416417 -67.790848)
			(xy 273.363633 -67.772841) (xy 273.314033 -67.74734) (xy 273.268675 -67.714889) (xy 273.228526 -67.67618)
			(xy 273.19444 -67.632037) (xy 273.167144 -67.583402) (xy 273.147221 -67.531311) (xy 273.135095 -67.476874)
			(xy 273.131024 -67.421252) (xy 262.239293 -67.421252) (xy 262.226983 -67.428765) (xy 262.175654 -67.450577)
			(xy 262.121697 -67.464683) (xy 262.06626 -67.470783) (xy 262.010526 -67.468746) (xy 261.955683 -67.458616)
			(xy 261.902899 -67.440609) (xy 261.853299 -67.415108) (xy 261.807941 -67.382657) (xy 261.767792 -67.343948)
			(xy 261.733706 -67.299805) (xy 261.70641 -67.25117) (xy 261.686487 -67.199079) (xy 261.674361 -67.144642)
			(xy 261.67029 -67.08902) (xy 249.009952 -67.08902) (xy 247.892057 -68.207128) (xy 248.911362 -68.207128)
			(xy 248.915433 -68.151506) (xy 248.927559 -68.097069) (xy 248.947482 -68.044978) (xy 248.974778 -67.996343)
			(xy 249.008864 -67.9522) (xy 249.049013 -67.913491) (xy 249.094371 -67.88104) (xy 249.143971 -67.855539)
			(xy 249.196755 -67.837532) (xy 249.251598 -67.827402) (xy 249.307332 -67.825365) (xy 249.362769 -67.831465)
			(xy 249.416726 -67.845571) (xy 249.468055 -67.867383) (xy 249.515661 -67.896437) (xy 249.558529 -67.932112)
			(xy 249.595746 -67.973649) (xy 249.626519 -68.020162) (xy 249.650191 -68.070659) (xy 249.666259 -68.124066)
			(xy 249.674379 -68.179242) (xy 249.674888 -68.207128) (xy 249.674379 -68.235014) (xy 249.666259 -68.29019)
			(xy 249.650191 -68.343597) (xy 249.626519 -68.394094) (xy 249.595746 -68.440607) (xy 249.562016 -68.478252)
			(xy 273.901646 -68.478252) (xy 273.901646 -68.423748) (xy 273.909402 -68.369799) (xy 273.924756 -68.317503)
			(xy 273.947397 -68.267924) (xy 273.976862 -68.222072) (xy 274.012552 -68.180879) (xy 274.053741 -68.145185)
			(xy 274.099591 -68.115715) (xy 274.149168 -68.09307) (xy 274.201462 -68.07771) (xy 274.25541 -68.069948)
			(xy 274.282662 -68.06946) (xy 274.311579 -68.069983) (xy 274.368751 -68.078708) (xy 274.423951 -68.095963)
			(xy 274.475913 -68.121354) (xy 274.523447 -68.154298) (xy 274.565463 -68.19404) (xy 274.583652 -68.216526)
			(xy 274.593549 -68.228331) (xy 274.618873 -68.24585) (xy 274.648266 -68.255026) (xy 274.679058 -68.255026)
			(xy 274.708451 -68.24585) (xy 274.733775 -68.228331) (xy 274.743672 -68.216526) (xy 274.761885 -68.194061)
			(xy 274.8039 -68.154324) (xy 274.85143 -68.121382) (xy 274.903387 -68.09599) (xy 274.958581 -68.07873)
			(xy 275.015747 -68.069997) (xy 275.044662 -68.06946) (xy 275.071914 -68.069985) (xy 275.125865 -68.077737)
			(xy 275.178163 -68.093088) (xy 275.227744 -68.115726) (xy 275.273598 -68.145191) (xy 275.314791 -68.180882)
			(xy 275.350486 -68.222072) (xy 275.379955 -68.267923) (xy 275.402599 -68.317501) (xy 275.417955 -68.369798)
			(xy 275.425713 -68.423748) (xy 275.425713 -68.478252) (xy 275.417955 -68.532202) (xy 275.402599 -68.584499)
			(xy 275.379955 -68.634077) (xy 275.350486 -68.679928) (xy 275.314791 -68.721118) (xy 275.273598 -68.756809)
			(xy 275.227744 -68.786274) (xy 275.178163 -68.808912) (xy 275.125865 -68.824263) (xy 275.071914 -68.832015)
			(xy 275.044662 -68.832476) (xy 275.015746 -68.831922) (xy 274.958576 -68.823202) (xy 274.903378 -68.805952)
			(xy 274.851416 -68.780567) (xy 274.803881 -68.747629) (xy 274.761863 -68.707893) (xy 274.743672 -68.68541)
			(xy 274.733775 -68.673605) (xy 274.708451 -68.656086) (xy 274.679058 -68.64691) (xy 274.648266 -68.64691)
			(xy 274.618873 -68.656086) (xy 274.593549 -68.673605) (xy 274.583652 -68.68541) (xy 274.565434 -68.707871)
			(xy 274.52342 -68.747607) (xy 274.47589 -68.780548) (xy 274.423934 -68.80594) (xy 274.368742 -68.823202)
			(xy 274.311576 -68.831937) (xy 274.282662 -68.832476) (xy 274.25541 -68.832052) (xy 274.201462 -68.82429)
			(xy 274.149168 -68.80893) (xy 274.099591 -68.786285) (xy 274.053741 -68.756815) (xy 274.012552 -68.721121)
			(xy 273.976862 -68.679928) (xy 273.947397 -68.634076) (xy 273.924756 -68.584497) (xy 273.909402 -68.532201)
			(xy 273.901646 -68.478252) (xy 249.562016 -68.478252) (xy 249.558529 -68.482144) (xy 249.515661 -68.517819)
			(xy 249.468055 -68.546873) (xy 249.416726 -68.568685) (xy 249.362769 -68.582791) (xy 249.307332 -68.588891)
			(xy 249.251598 -68.586854) (xy 249.196755 -68.576724) (xy 249.143971 -68.558717) (xy 249.094371 -68.533216)
			(xy 249.049013 -68.500765) (xy 249.008864 -68.462056) (xy 248.974778 -68.417913) (xy 248.947482 -68.369278)
			(xy 248.927559 -68.317187) (xy 248.915433 -68.26275) (xy 248.911362 -68.207128) (xy 247.892057 -68.207128)
			(xy 247.866916 -68.232274) (xy 247.848933 -68.249632) (xy 247.808522 -68.279042) (xy 247.764004 -68.30176)
			(xy 247.716478 -68.317225) (xy 247.667116 -68.325057) (xy 247.642126 -68.325492) (xy 247.31599 -68.325492)
			(xy 246.61368 -69.027548) (xy 246.61368 -69.562748) (xy 272.770626 -69.562748) (xy 272.770626 -69.508252)
			(xy 272.778382 -69.454311) (xy 272.793735 -69.402023) (xy 272.816373 -69.352452) (xy 272.845836 -69.306608)
			(xy 272.881523 -69.265423) (xy 272.922708 -69.229736) (xy 272.968552 -69.200273) (xy 273.018123 -69.177635)
			(xy 273.070411 -69.162282) (xy 273.124352 -69.154526) (xy 273.1516 -69.15404) (xy 273.180518 -69.154543)
			(xy 273.23769 -69.163273) (xy 273.29289 -69.180533) (xy 273.344852 -69.205928) (xy 273.392385 -69.238875)
			(xy 273.434401 -69.278619) (xy 273.45259 -69.301106) (xy 273.462487 -69.312911) (xy 273.487811 -69.33043)
			(xy 273.517204 -69.339606) (xy 273.547996 -69.339606) (xy 273.577389 -69.33043) (xy 273.602713 -69.312911)
			(xy 273.61261 -69.301106) (xy 273.629363 -69.280323) (xy 273.667717 -69.243193) (xy 273.710871 -69.211771)
			(xy 273.757985 -69.186672) (xy 273.808137 -69.168386) (xy 273.860348 -69.157269) (xy 273.9136 -69.153539)
			(xy 273.966852 -69.157269) (xy 274.019063 -69.168386) (xy 274.069215 -69.186672) (xy 274.116329 -69.211771)
			(xy 274.159483 -69.243193) (xy 274.197837 -69.280323) (xy 274.21459 -69.301106) (xy 274.224487 -69.312911)
			(xy 274.249811 -69.33043) (xy 274.279204 -69.339606) (xy 274.309996 -69.339606) (xy 274.339389 -69.33043)
			(xy 274.364713 -69.312911) (xy 274.37461 -69.301106) (xy 274.391363 -69.280323) (xy 274.429717 -69.243193)
			(xy 274.472871 -69.211771) (xy 274.519985 -69.186672) (xy 274.570137 -69.168386) (xy 274.622348 -69.157269)
			(xy 274.6756 -69.153539) (xy 274.728852 -69.157269) (xy 274.781063 -69.168386) (xy 274.831215 -69.186672)
			(xy 274.878329 -69.211771) (xy 274.921483 -69.243193) (xy 274.959837 -69.280323) (xy 274.97659 -69.301106)
			(xy 274.986487 -69.312911) (xy 275.011811 -69.33043) (xy 275.041204 -69.339606) (xy 275.071996 -69.339606)
			(xy 275.101389 -69.33043) (xy 275.126713 -69.312911) (xy 275.13661 -69.301106) (xy 275.153363 -69.280323)
			(xy 275.191717 -69.243193) (xy 275.234871 -69.211771) (xy 275.281985 -69.186672) (xy 275.332137 -69.168386)
			(xy 275.384348 -69.157269) (xy 275.4376 -69.153539) (xy 275.490852 -69.157269) (xy 275.543063 -69.168386)
			(xy 275.593215 -69.186672) (xy 275.640329 -69.211771) (xy 275.683483 -69.243193) (xy 275.721837 -69.280323)
			(xy 275.73859 -69.301106) (xy 275.748487 -69.312911) (xy 275.773811 -69.33043) (xy 275.803204 -69.339606)
			(xy 275.833996 -69.339606) (xy 275.863389 -69.33043) (xy 275.888713 -69.312911) (xy 275.89861 -69.301106)
			(xy 275.916797 -69.278619) (xy 275.958817 -69.238884) (xy 276.006353 -69.205945) (xy 276.058315 -69.180557)
			(xy 276.113514 -69.163302) (xy 276.170684 -69.154574) (xy 276.1996 -69.15404) (xy 276.226855 -69.15443)
			(xy 276.280809 -69.162187) (xy 276.333111 -69.177544) (xy 276.382694 -69.200188) (xy 276.42855 -69.229658)
			(xy 276.469746 -69.265354) (xy 276.505442 -69.30655) (xy 276.534912 -69.352406) (xy 276.557556 -69.401989)
			(xy 276.572913 -69.454291) (xy 276.58067 -69.508245) (xy 276.58067 -69.562755) (xy 276.572913 -69.616709)
			(xy 276.557556 -69.669011) (xy 276.534912 -69.718594) (xy 276.505442 -69.76445) (xy 276.469746 -69.805646)
			(xy 276.42855 -69.841342) (xy 276.382694 -69.870812) (xy 276.333111 -69.893456) (xy 276.280809 -69.908813)
			(xy 276.226855 -69.91657) (xy 276.1996 -69.917056) (xy 276.170682 -69.916554) (xy 276.11351 -69.907824)
			(xy 276.05831 -69.890564) (xy 276.006348 -69.865169) (xy 275.958814 -69.832222) (xy 275.916799 -69.792477)
			(xy 275.89861 -69.76999) (xy 275.888713 -69.758185) (xy 275.863389 -69.740666) (xy 275.833996 -69.73149)
			(xy 275.803204 -69.73149) (xy 275.773811 -69.740666) (xy 275.748487 -69.758185) (xy 275.73859 -69.76999)
			(xy 275.721837 -69.790773) (xy 275.683483 -69.827903) (xy 275.640329 -69.859325) (xy 275.593215 -69.884424)
			(xy 275.543063 -69.90271) (xy 275.490852 -69.913827) (xy 275.4376 -69.917557) (xy 275.384348 -69.913827)
			(xy 275.332137 -69.90271) (xy 275.281985 -69.884424) (xy 275.234871 -69.859325) (xy 275.191717 -69.827903)
			(xy 275.153363 -69.790773) (xy 275.13661 -69.76999) (xy 275.126713 -69.758185) (xy 275.101389 -69.740666)
			(xy 275.071996 -69.73149) (xy 275.041204 -69.73149) (xy 275.011811 -69.740666) (xy 274.986487 -69.758185)
			(xy 274.97659 -69.76999) (xy 274.959837 -69.790773) (xy 274.921483 -69.827903) (xy 274.878329 -69.859325)
			(xy 274.831215 -69.884424) (xy 274.781063 -69.90271) (xy 274.728852 -69.913827) (xy 274.6756 -69.917557)
			(xy 274.622348 -69.913827) (xy 274.570137 -69.90271) (xy 274.519985 -69.884424) (xy 274.472871 -69.859325)
			(xy 274.429717 -69.827903) (xy 274.391363 -69.790773) (xy 274.37461 -69.76999) (xy 274.364713 -69.758185)
			(xy 274.339389 -69.740666) (xy 274.309996 -69.73149) (xy 274.279204 -69.73149) (xy 274.249811 -69.740666)
			(xy 274.224487 -69.758185) (xy 274.21459 -69.76999) (xy 274.197837 -69.790773) (xy 274.159483 -69.827903)
			(xy 274.116329 -69.859325) (xy 274.069215 -69.884424) (xy 274.019063 -69.90271) (xy 273.966852 -69.913827)
			(xy 273.9136 -69.917557) (xy 273.860348 -69.913827) (xy 273.808137 -69.90271) (xy 273.757985 -69.884424)
			(xy 273.710871 -69.859325) (xy 273.667717 -69.827903) (xy 273.629363 -69.790773) (xy 273.61261 -69.76999)
			(xy 273.602713 -69.758185) (xy 273.577389 -69.740666) (xy 273.547996 -69.73149) (xy 273.517204 -69.73149)
			(xy 273.487811 -69.740666) (xy 273.462487 -69.758185) (xy 273.45259 -69.76999) (xy 273.434402 -69.792476)
			(xy 273.392382 -69.832212) (xy 273.344847 -69.865151) (xy 273.292885 -69.890539) (xy 273.237686 -69.907794)
			(xy 273.180516 -69.916522) (xy 273.1516 -69.917056) (xy 273.124352 -69.916474) (xy 273.070411 -69.908718)
			(xy 273.018123 -69.893365) (xy 272.968552 -69.870727) (xy 272.922708 -69.841264) (xy 272.881523 -69.805577)
			(xy 272.845836 -69.764392) (xy 272.816373 -69.718548) (xy 272.793735 -69.668977) (xy 272.778382 -69.616689)
			(xy 272.770626 -69.562748) (xy 246.61368 -69.562748) (xy 246.61368 -71.652384) (xy 247.39854 -71.652384)
			(xy 247.398982 -71.625711) (xy 247.406426 -71.572887) (xy 247.421154 -71.521615) (xy 247.442878 -71.472893)
			(xy 247.471175 -71.42767) (xy 247.505494 -71.386829) (xy 247.525032 -71.368666) (xy 247.535357 -71.35882)
			(xy 247.550505 -71.334654) (xy 247.558383 -71.307243) (xy 247.558378 -71.278722) (xy 247.550491 -71.251314)
			(xy 247.535335 -71.227153) (xy 247.525032 -71.217282) (xy 247.505486 -71.199126) (xy 247.471158 -71.15829)
			(xy 247.442856 -71.113068) (xy 247.421133 -71.064343) (xy 247.406413 -71.013066) (xy 247.398983 -70.960238)
			(xy 247.39854 -70.933564) (xy 247.398922 -70.906308) (xy 247.406685 -70.852352) (xy 247.422048 -70.800049)
			(xy 247.444698 -70.750466) (xy 247.474174 -70.70461) (xy 247.509876 -70.663417) (xy 247.551078 -70.627724)
			(xy 247.59694 -70.598258) (xy 247.646528 -70.575618) (xy 247.698834 -70.560267) (xy 247.752792 -70.552516)
			(xy 247.780048 -70.552056) (xy 247.806286 -70.552464) (xy 247.858265 -70.559667) (xy 247.908765 -70.57393)
			(xy 247.956831 -70.594984) (xy 248.001557 -70.622431) (xy 248.042096 -70.655752) (xy 248.06021 -70.674738)
			(xy 248.067739 -70.68211) (xy 248.087024 -70.690541) (xy 248.108072 -70.690541) (xy 248.127357 -70.68211)
			(xy 248.134886 -70.674738) (xy 248.160032 -70.649846) (xy 248.170378 -70.64002) (xy 248.185524 -70.615848)
			(xy 248.1934 -70.588432) (xy 248.193392 -70.559907) (xy 248.185499 -70.532495) (xy 248.170338 -70.508333)
			(xy 248.160032 -70.498462) (xy 248.140476 -70.480316) (xy 248.106149 -70.439478) (xy 248.077849 -70.394254)
			(xy 248.056128 -70.345527) (xy 248.04141 -70.294248) (xy 248.033982 -70.241419) (xy 248.03354 -70.214744)
			(xy 248.034026 -70.187493) (xy 248.041782 -70.133545) (xy 248.057137 -70.08125) (xy 248.079779 -70.031673)
			(xy 248.109245 -69.985823) (xy 248.144936 -69.944632) (xy 248.186127 -69.908941) (xy 248.231977 -69.879475)
			(xy 248.281554 -69.856833) (xy 248.333849 -69.841478) (xy 248.387797 -69.833722) (xy 248.442299 -69.833722)
			(xy 248.496247 -69.841478) (xy 248.548542 -69.856833) (xy 248.598119 -69.879475) (xy 248.643969 -69.908941)
			(xy 248.68516 -69.944632) (xy 248.720851 -69.985823) (xy 248.750317 -70.031673) (xy 248.772959 -70.08125)
			(xy 248.776266 -70.092513) (xy 278.688542 -70.092513) (xy 278.688542 -70.007791) (xy 278.696595 -69.923454)
			(xy 278.712629 -69.840264) (xy 278.736497 -69.758974) (xy 278.767985 -69.680322) (xy 278.806807 -69.605019)
			(xy 278.85261 -69.533747) (xy 278.904981 -69.467151) (xy 278.963446 -69.405836) (xy 279.027474 -69.350355)
			(xy 279.096486 -69.301212) (xy 279.169856 -69.258852) (xy 279.246921 -69.223657) (xy 279.326983 -69.195948)
			(xy 279.409316 -69.175974) (xy 279.493175 -69.163917) (xy 279.5778 -69.159886) (xy 279.662425 -69.163917)
			(xy 279.746284 -69.175974) (xy 279.828617 -69.195948) (xy 279.908679 -69.223657) (xy 279.985744 -69.258852)
			(xy 280.059114 -69.301212) (xy 280.128126 -69.350355) (xy 280.192154 -69.405836) (xy 280.250619 -69.467151)
			(xy 280.30299 -69.533747) (xy 280.348793 -69.605019) (xy 280.387615 -69.680322) (xy 280.419103 -69.758974)
			(xy 280.442971 -69.840264) (xy 280.459005 -69.923454) (xy 280.467058 -70.007791) (xy 280.467562 -70.050152)
			(xy 280.467058 -70.092513) (xy 280.459005 -70.17685) (xy 280.442971 -70.26004) (xy 280.419103 -70.34133)
			(xy 280.387615 -70.419982) (xy 280.348793 -70.495285) (xy 280.30299 -70.566557) (xy 280.250619 -70.633153)
			(xy 280.192154 -70.694468) (xy 280.128126 -70.749949) (xy 280.059114 -70.799092) (xy 279.985744 -70.841452)
			(xy 279.908679 -70.876647) (xy 279.828617 -70.904356) (xy 279.746284 -70.92433) (xy 279.662425 -70.936387)
			(xy 279.5778 -70.940419) (xy 279.493175 -70.936387) (xy 279.409316 -70.92433) (xy 279.326983 -70.904356)
			(xy 279.246921 -70.876647) (xy 279.169856 -70.841452) (xy 279.096486 -70.799092) (xy 279.027474 -70.749949)
			(xy 278.963446 -70.694468) (xy 278.904981 -70.633153) (xy 278.85261 -70.566557) (xy 278.806807 -70.495285)
			(xy 278.767985 -70.419982) (xy 278.736497 -70.34133) (xy 278.712629 -70.26004) (xy 278.696595 -70.17685)
			(xy 278.688542 -70.092513) (xy 248.776266 -70.092513) (xy 248.788314 -70.133545) (xy 248.79607 -70.187493)
			(xy 248.796556 -70.214744) (xy 248.796067 -70.241415) (xy 248.788632 -70.294237) (xy 248.773914 -70.345509)
			(xy 248.752199 -70.394231) (xy 248.72391 -70.439455) (xy 248.689599 -70.480298) (xy 248.670064 -70.498462)
			(xy 248.659811 -70.508377) (xy 248.644661 -70.532524) (xy 248.636774 -70.559917) (xy 248.636765 -70.588422)
			(xy 248.644635 -70.61582) (xy 248.659771 -70.639975) (xy 248.670064 -70.649846) (xy 248.689565 -70.668046)
			(xy 248.72388 -70.708882) (xy 248.752172 -70.7541) (xy 248.773889 -70.802819) (xy 248.788608 -70.854087)
			(xy 248.796041 -70.906906) (xy 248.796045 -70.960246) (xy 248.788618 -71.013066) (xy 248.773905 -71.064336)
			(xy 248.752194 -71.113057) (xy 248.723908 -71.158279) (xy 248.689599 -71.199119) (xy 248.670064 -71.217282)
			(xy 248.659791 -71.227178) (xy 248.644642 -71.25133) (xy 248.636757 -71.278728) (xy 248.636752 -71.307238)
			(xy 248.644627 -71.334638) (xy 248.659769 -71.358795) (xy 248.670064 -71.368666) (xy 248.689584 -71.386849)
			(xy 248.723915 -71.427679) (xy 248.75222 -71.472895) (xy 248.773947 -71.521615) (xy 248.788673 -71.572887)
			(xy 248.796109 -71.625712) (xy 248.796556 -71.652384) (xy 248.796094 -71.679035) (xy 248.788674 -71.731818)
			(xy 248.773975 -71.783053) (xy 248.763536 -71.807578) (xy 248.757906 -71.821707) (xy 248.754301 -71.85189)
			(xy 248.759721 -71.8818) (xy 248.773687 -71.9088) (xy 248.794967 -71.930506) (xy 248.821683 -71.945005)
			(xy 248.85148 -71.951017) (xy 248.86666 -71.950072) (xy 248.90476 -71.94804) (xy 248.932014 -71.948493)
			(xy 248.985968 -71.956245) (xy 249.038269 -71.971599) (xy 249.087852 -71.99424) (xy 249.133708 -72.023708)
			(xy 249.16422 -72.050148) (xy 278.662135 -72.050148) (xy 278.666158 -71.964404) (xy 278.678193 -71.879413)
			(xy 278.698134 -71.795923) (xy 278.725805 -71.714666) (xy 278.760964 -71.636358) (xy 278.803301 -71.561687)
			(xy 278.852444 -71.491308) (xy 278.907962 -71.42584) (xy 278.969366 -71.365859) (xy 279.036118 -71.311891)
			(xy 279.107629 -71.264411) (xy 279.183273 -71.223836) (xy 279.262384 -71.190523) (xy 279.344266 -71.164764)
			(xy 279.428201 -71.146786) (xy 279.513451 -71.136746) (xy 279.599266 -71.134734) (xy 279.684892 -71.140767)
			(xy 279.769577 -71.154791) (xy 279.852577 -71.176683) (xy 279.933162 -71.206252) (xy 280.010625 -71.243236)
			(xy 280.084283 -71.287312) (xy 280.153491 -71.338092) (xy 280.217639 -71.395129) (xy 280.276165 -71.457923)
			(xy 280.328553 -71.525921) (xy 280.374343 -71.598526) (xy 280.413134 -71.6751) (xy 280.444583 -71.75497)
			(xy 280.468416 -71.837434) (xy 280.484421 -71.921767) (xy 280.492459 -72.007229) (xy 280.492962 -72.050148)
			(xy 280.492459 -72.093067) (xy 280.484421 -72.178529) (xy 280.468416 -72.262862) (xy 280.444583 -72.345326)
			(xy 280.413134 -72.425196) (xy 280.374343 -72.50177) (xy 280.328553 -72.574375) (xy 280.276165 -72.642373)
			(xy 280.217639 -72.705167) (xy 280.153491 -72.762204) (xy 280.084283 -72.812984) (xy 280.010625 -72.85706)
			(xy 279.933162 -72.894044) (xy 279.852577 -72.923613) (xy 279.769577 -72.945505) (xy 279.684892 -72.959529)
			(xy 279.599266 -72.965562) (xy 279.513451 -72.96355) (xy 279.428201 -72.95351) (xy 279.344266 -72.935532)
			(xy 279.262384 -72.909773) (xy 279.183273 -72.87646) (xy 279.107629 -72.835885) (xy 279.036118 -72.788405)
			(xy 278.969366 -72.734437) (xy 278.907962 -72.674456) (xy 278.852444 -72.608988) (xy 278.803301 -72.538609)
			(xy 278.760964 -72.463938) (xy 278.725805 -72.38563) (xy 278.698134 -72.304373) (xy 278.678193 -72.220883)
			(xy 278.666158 -72.135892) (xy 278.662135 -72.050148) (xy 249.16422 -72.050148) (xy 249.174902 -72.059404)
			(xy 249.210596 -72.100599) (xy 249.240064 -72.146455) (xy 249.262704 -72.196039) (xy 249.278056 -72.24834)
			(xy 249.285808 -72.302294) (xy 249.286268 -72.329548) (xy 249.285779 -72.356918) (xy 249.277968 -72.411096)
			(xy 249.262485 -72.463599) (xy 249.239648 -72.513346) (xy 249.209927 -72.559314) (xy 249.192288 -72.580246)
			(xy 249.183006 -72.591539) (xy 249.170836 -72.61811) (xy 249.166673 -72.647036) (xy 249.170856 -72.67596)
			(xy 249.183045 -72.702522) (xy 249.192288 -72.71385) (xy 249.209975 -72.734745) (xy 249.239697 -72.78072)
			(xy 249.262538 -72.830472) (xy 249.27803 -72.88298) (xy 249.285854 -72.937163) (xy 249.285849 -72.991909)
			(xy 249.278015 -73.046091) (xy 249.262513 -73.098596) (xy 249.239662 -73.148344) (xy 249.209931 -73.194313)
			(xy 249.192288 -73.215246) (xy 249.183006 -73.226539) (xy 249.170836 -73.25311) (xy 249.166673 -73.282036)
			(xy 249.170856 -73.31096) (xy 249.183045 -73.337522) (xy 249.192288 -73.34885) (xy 249.209975 -73.369745)
			(xy 249.239697 -73.41572) (xy 249.262538 -73.465472) (xy 249.27803 -73.51798) (xy 249.285854 -73.572163)
			(xy 249.28585 -73.620122) (xy 252.28245 -73.620122) (xy 252.286523 -73.564463) (xy 252.298658 -73.50999)
			(xy 252.318594 -73.457864) (xy 252.345908 -73.409196) (xy 252.380016 -73.365024) (xy 252.420193 -73.326289)
			(xy 252.465581 -73.293817) (xy 252.515213 -73.268299) (xy 252.568033 -73.25028) (xy 252.622912 -73.240143)
			(xy 252.678683 -73.238105) (xy 252.734157 -73.244208) (xy 252.78815 -73.258324) (xy 252.839513 -73.280151)
			(xy 252.887151 -73.309224) (xy 252.930047 -73.344923) (xy 252.967289 -73.386487) (xy 252.998083 -73.433031)
			(xy 253.021771 -73.483562) (xy 253.037201 -73.53485) (xy 272.927578 -73.53485) (xy 272.927578 -73.48035)
			(xy 272.935333 -73.426405) (xy 272.950687 -73.374112) (xy 272.973326 -73.324537) (xy 273.00279 -73.278688)
			(xy 273.038478 -73.237498) (xy 273.079665 -73.201807) (xy 273.125512 -73.17234) (xy 273.175086 -73.149697)
			(xy 273.227377 -73.134339) (xy 273.281322 -73.12658) (xy 273.308572 -73.126092) (xy 273.33749 -73.126595)
			(xy 273.394663 -73.135323) (xy 273.449864 -73.152581) (xy 273.501827 -73.177975) (xy 273.54936 -73.210923)
			(xy 273.591374 -73.25067) (xy 273.609562 -73.273158) (xy 273.619459 -73.284963) (xy 273.644783 -73.302482)
			(xy 273.674176 -73.311658) (xy 273.704968 -73.311658) (xy 273.734361 -73.302482) (xy 273.759685 -73.284963)
			(xy 273.769582 -73.273158) (xy 273.786335 -73.252375) (xy 273.824689 -73.215245) (xy 273.867843 -73.183823)
			(xy 273.914957 -73.158724) (xy 273.965109 -73.140438) (xy 274.01732 -73.129321) (xy 274.070572 -73.125591)
			(xy 274.123824 -73.129321) (xy 274.176035 -73.140438) (xy 274.226187 -73.158724) (xy 274.273301 -73.183823)
			(xy 274.316455 -73.215245) (xy 274.354809 -73.252375) (xy 274.371562 -73.273158) (xy 274.381459 -73.284963)
			(xy 274.406783 -73.302482) (xy 274.436176 -73.311658) (xy 274.466968 -73.311658) (xy 274.496361 -73.302482)
			(xy 274.521685 -73.284963) (xy 274.531582 -73.273158) (xy 274.548335 -73.252375) (xy 274.586689 -73.215245)
			(xy 274.629843 -73.183823) (xy 274.676957 -73.158724) (xy 274.727109 -73.140438) (xy 274.77932 -73.129321)
			(xy 274.832572 -73.125591) (xy 274.885824 -73.129321) (xy 274.938035 -73.140438) (xy 274.988187 -73.158724)
			(xy 275.035301 -73.183823) (xy 275.078455 -73.215245) (xy 275.116809 -73.252375) (xy 275.133562 -73.273158)
			(xy 275.143459 -73.284963) (xy 275.168783 -73.302482) (xy 275.198176 -73.311658) (xy 275.228968 -73.311658)
			(xy 275.258361 -73.302482) (xy 275.283685 -73.284963) (xy 275.293582 -73.273158) (xy 275.310335 -73.252375)
			(xy 275.348689 -73.215245) (xy 275.391843 -73.183823) (xy 275.438957 -73.158724) (xy 275.489109 -73.140438)
			(xy 275.54132 -73.129321) (xy 275.594572 -73.125591) (xy 275.647824 -73.129321) (xy 275.700035 -73.140438)
			(xy 275.750187 -73.158724) (xy 275.797301 -73.183823) (xy 275.840455 -73.215245) (xy 275.878809 -73.252375)
			(xy 275.895562 -73.273158) (xy 275.905459 -73.284963) (xy 275.930783 -73.302482) (xy 275.960176 -73.311658)
			(xy 275.990968 -73.311658) (xy 276.020361 -73.302482) (xy 276.045685 -73.284963) (xy 276.055582 -73.273158)
			(xy 276.073773 -73.250674) (xy 276.115794 -73.210941) (xy 276.163329 -73.178003) (xy 276.21529 -73.152615)
			(xy 276.270487 -73.135359) (xy 276.327656 -73.126628) (xy 276.356572 -73.126092) (xy 276.383826 -73.126553)
			(xy 276.43778 -73.134307) (xy 276.490081 -73.149661) (xy 276.539665 -73.172302) (xy 276.585522 -73.201769)
			(xy 276.626718 -73.237463) (xy 276.662414 -73.278656) (xy 276.691885 -73.32451) (xy 276.714529 -73.374092)
			(xy 276.729887 -73.426392) (xy 276.737645 -73.480346) (xy 276.737645 -73.534854) (xy 276.729887 -73.588808)
			(xy 276.714529 -73.641108) (xy 276.691885 -73.69069) (xy 276.662414 -73.736544) (xy 276.626718 -73.777737)
			(xy 276.585522 -73.813431) (xy 276.539665 -73.842898) (xy 276.490081 -73.865539) (xy 276.43778 -73.880893)
			(xy 276.383826 -73.888647) (xy 276.356572 -73.889108) (xy 276.327655 -73.888573) (xy 276.270483 -73.879852)
			(xy 276.215283 -73.8626) (xy 276.163321 -73.837212) (xy 276.115787 -73.804269) (xy 276.073771 -73.764528)
			(xy 276.055582 -73.742042) (xy 276.045685 -73.730237) (xy 276.020361 -73.712718) (xy 275.990968 -73.703542)
			(xy 275.960176 -73.703542) (xy 275.930783 -73.712718) (xy 275.905459 -73.730237) (xy 275.895562 -73.742042)
			(xy 275.878809 -73.762825) (xy 275.840455 -73.799955) (xy 275.797301 -73.831377) (xy 275.750187 -73.856476)
			(xy 275.700035 -73.874762) (xy 275.647824 -73.885879) (xy 275.594572 -73.889609) (xy 275.54132 -73.885879)
			(xy 275.489109 -73.874762) (xy 275.438957 -73.856476) (xy 275.391843 -73.831377) (xy 275.348689 -73.799955)
			(xy 275.310335 -73.762825) (xy 275.293582 -73.742042) (xy 275.283685 -73.730237) (xy 275.258361 -73.712718)
			(xy 275.228968 -73.703542) (xy 275.198176 -73.703542) (xy 275.168783 -73.712718) (xy 275.143459 -73.730237)
			(xy 275.133562 -73.742042) (xy 275.116809 -73.762825) (xy 275.078455 -73.799955) (xy 275.035301 -73.831377)
			(xy 274.988187 -73.856476) (xy 274.938035 -73.874762) (xy 274.885824 -73.885879) (xy 274.832572 -73.889609)
			(xy 274.77932 -73.885879) (xy 274.727109 -73.874762) (xy 274.676957 -73.856476) (xy 274.629843 -73.831377)
			(xy 274.586689 -73.799955) (xy 274.548335 -73.762825) (xy 274.531582 -73.742042) (xy 274.521685 -73.730237)
			(xy 274.496361 -73.712718) (xy 274.466968 -73.703542) (xy 274.436176 -73.703542) (xy 274.406783 -73.712718)
			(xy 274.381459 -73.730237) (xy 274.371562 -73.742042) (xy 274.354809 -73.762825) (xy 274.316455 -73.799955)
			(xy 274.273301 -73.831377) (xy 274.226187 -73.856476) (xy 274.176035 -73.874762) (xy 274.123824 -73.885879)
			(xy 274.070572 -73.889609) (xy 274.01732 -73.885879) (xy 273.965109 -73.874762) (xy 273.914957 -73.856476)
			(xy 273.867843 -73.831377) (xy 273.824689 -73.799955) (xy 273.786335 -73.762825) (xy 273.769582 -73.742042)
			(xy 273.759685 -73.730237) (xy 273.734361 -73.712718) (xy 273.704968 -73.703542) (xy 273.674176 -73.703542)
			(xy 273.644783 -73.712718) (xy 273.619459 -73.730237) (xy 273.609562 -73.742042) (xy 273.591403 -73.764552)
			(xy 273.549375 -73.804284) (xy 273.501833 -73.837219) (xy 273.449866 -73.862602) (xy 273.394663 -73.879853)
			(xy 273.33749 -73.888576) (xy 273.308572 -73.889108) (xy 273.281322 -73.88862) (xy 273.227377 -73.880861)
			(xy 273.175086 -73.865503) (xy 273.125512 -73.84286) (xy 273.079665 -73.813393) (xy 273.038478 -73.777702)
			(xy 273.00279 -73.736512) (xy 272.973326 -73.690663) (xy 272.950687 -73.641088) (xy 272.935333 -73.588795)
			(xy 272.927578 -73.53485) (xy 253.037201 -73.53485) (xy 253.037849 -73.537004) (xy 253.045975 -73.592218)
			(xy 253.046484 -73.620122) (xy 253.045975 -73.648026) (xy 253.037849 -73.70324) (xy 253.021771 -73.756682)
			(xy 252.998083 -73.807213) (xy 252.967289 -73.853757) (xy 252.930047 -73.895321) (xy 252.887151 -73.93102)
			(xy 252.839513 -73.960093) (xy 252.78815 -73.98192) (xy 252.734157 -73.996036) (xy 252.678683 -74.002139)
			(xy 252.622912 -74.000101) (xy 252.568033 -73.989964) (xy 252.515213 -73.971945) (xy 252.465581 -73.946427)
			(xy 252.420193 -73.913955) (xy 252.380016 -73.87522) (xy 252.345908 -73.831048) (xy 252.318594 -73.78238)
			(xy 252.298658 -73.730254) (xy 252.286523 -73.675781) (xy 252.28245 -73.620122) (xy 249.28585 -73.620122)
			(xy 249.285849 -73.626909) (xy 249.278015 -73.681091) (xy 249.262513 -73.733596) (xy 249.239662 -73.783344)
			(xy 249.209931 -73.829313) (xy 249.192288 -73.850246) (xy 249.183006 -73.861539) (xy 249.170836 -73.88811)
			(xy 249.166673 -73.917036) (xy 249.170856 -73.94596) (xy 249.183045 -73.972522) (xy 249.192288 -73.98385)
			(xy 249.209915 -74.004792) (xy 249.239629 -74.050762) (xy 249.261619 -74.098658) (xy 260.18693 -74.098658)
			(xy 260.191001 -74.043036) (xy 260.203127 -73.988599) (xy 260.22305 -73.936508) (xy 260.250346 -73.887873)
			(xy 260.284432 -73.84373) (xy 260.324581 -73.805021) (xy 260.369939 -73.77257) (xy 260.419539 -73.747069)
			(xy 260.472323 -73.729062) (xy 260.527166 -73.718932) (xy 260.5829 -73.716895) (xy 260.638337 -73.722995)
			(xy 260.692294 -73.737101) (xy 260.743623 -73.758913) (xy 260.791229 -73.787967) (xy 260.834097 -73.823642)
			(xy 260.871314 -73.865179) (xy 260.902087 -73.911692) (xy 260.925759 -73.962189) (xy 260.932964 -73.986136)
			(xy 261.8265 -73.986136) (xy 261.830571 -73.930514) (xy 261.842697 -73.876077) (xy 261.86262 -73.823986)
			(xy 261.889916 -73.775351) (xy 261.924002 -73.731208) (xy 261.964151 -73.692499) (xy 262.009509 -73.660048)
			(xy 262.059109 -73.634547) (xy 262.111893 -73.61654) (xy 262.166736 -73.60641) (xy 262.22247 -73.604373)
			(xy 262.277907 -73.610473) (xy 262.331864 -73.624579) (xy 262.383193 -73.646391) (xy 262.430799 -73.675445)
			(xy 262.473667 -73.71112) (xy 262.510884 -73.752657) (xy 262.541657 -73.79917) (xy 262.565329 -73.849667)
			(xy 262.581397 -73.903074) (xy 262.589517 -73.95825) (xy 262.590026 -73.986136) (xy 262.589517 -74.014022)
			(xy 262.581397 -74.069198) (xy 262.565329 -74.122605) (xy 262.541657 -74.173102) (xy 262.510884 -74.219615)
			(xy 262.473667 -74.261152) (xy 262.430799 -74.296827) (xy 262.383193 -74.325881) (xy 262.331864 -74.347693)
			(xy 262.277907 -74.361799) (xy 262.22247 -74.367899) (xy 262.166736 -74.365862) (xy 262.111893 -74.355732)
			(xy 262.059109 -74.337725) (xy 262.009509 -74.312224) (xy 261.964151 -74.279773) (xy 261.924002 -74.241064)
			(xy 261.889916 -74.196921) (xy 261.86262 -74.148286) (xy 261.842697 -74.096195) (xy 261.830571 -74.041758)
			(xy 261.8265 -73.986136) (xy 260.932964 -73.986136) (xy 260.941827 -74.015596) (xy 260.949947 -74.070772)
			(xy 260.950456 -74.098658) (xy 260.949947 -74.126544) (xy 260.941827 -74.18172) (xy 260.925759 -74.235127)
			(xy 260.902087 -74.285624) (xy 260.871314 -74.332137) (xy 260.834097 -74.373674) (xy 260.791229 -74.409349)
			(xy 260.743623 -74.438403) (xy 260.692294 -74.460215) (xy 260.638337 -74.474321) (xy 260.5829 -74.480421)
			(xy 260.527166 -74.478384) (xy 260.472323 -74.468254) (xy 260.419539 -74.450247) (xy 260.369939 -74.424746)
			(xy 260.324581 -74.392295) (xy 260.284432 -74.353586) (xy 260.250346 -74.309443) (xy 260.22305 -74.260808)
			(xy 260.203127 -74.208717) (xy 260.191001 -74.15428) (xy 260.18693 -74.098658) (xy 249.261619 -74.098658)
			(xy 249.262468 -74.100507) (xy 249.277961 -74.153005) (xy 249.285793 -74.207179) (xy 249.286268 -74.234548)
			(xy 249.285867 -74.261802) (xy 249.278103 -74.315755) (xy 249.262739 -74.368054) (xy 249.24009 -74.417634)
			(xy 249.210615 -74.463486) (xy 249.174914 -74.504677) (xy 249.133715 -74.540368) (xy 249.087857 -74.569832)
			(xy 249.038271 -74.59247) (xy 248.985969 -74.607821) (xy 248.932014 -74.615573) (xy 248.90476 -74.616056)
			(xy 248.893495 -74.616003) (xy 248.871001 -74.614732) (xy 248.859802 -74.613516) (xy 248.846201 -74.612398)
			(xy 248.819238 -74.616521) (xy 248.79433 -74.627641) (xy 248.773259 -74.644963) (xy 248.757532 -74.667249)
			(xy 248.748272 -74.692906) (xy 248.746141 -74.7201) (xy 248.751293 -74.746886) (xy 248.752552 -74.74966)
			(xy 258.981954 -74.74966) (xy 258.986025 -74.694038) (xy 258.998151 -74.639601) (xy 259.018074 -74.58751)
			(xy 259.04537 -74.538875) (xy 259.079456 -74.494732) (xy 259.119605 -74.456023) (xy 259.164963 -74.423572)
			(xy 259.214563 -74.398071) (xy 259.267347 -74.380064) (xy 259.32219 -74.369934) (xy 259.377924 -74.367897)
			(xy 259.433361 -74.373997) (xy 259.487318 -74.388103) (xy 259.538647 -74.409915) (xy 259.586253 -74.438969)
			(xy 259.629121 -74.474644) (xy 259.666338 -74.516181) (xy 259.697111 -74.562694) (xy 259.720783 -74.613191)
			(xy 259.736851 -74.666598) (xy 259.744971 -74.721774) (xy 259.74548 -74.74966) (xy 259.744971 -74.777546)
			(xy 259.736851 -74.832722) (xy 259.720783 -74.886129) (xy 259.697111 -74.936626) (xy 259.666338 -74.983139)
			(xy 259.629121 -75.024676) (xy 259.586253 -75.060351) (xy 259.538647 -75.089405) (xy 259.487318 -75.111217)
			(xy 259.433361 -75.125323) (xy 259.377924 -75.131423) (xy 259.32219 -75.129386) (xy 259.267347 -75.119256)
			(xy 259.214563 -75.101249) (xy 259.164963 -75.075748) (xy 259.119605 -75.043297) (xy 259.079456 -75.004588)
			(xy 259.04537 -74.960445) (xy 259.018074 -74.91181) (xy 258.998151 -74.859719) (xy 258.986025 -74.805282)
			(xy 258.981954 -74.74966) (xy 248.752552 -74.74966) (xy 248.756932 -74.759312) (xy 248.769388 -74.785711)
			(xy 248.787005 -74.841359) (xy 248.795961 -74.899038) (xy 248.796556 -74.928222) (xy 248.796556 -74.928984)
			(xy 248.796007 -74.956233) (xy 248.788254 -75.010176) (xy 248.772903 -75.062466) (xy 248.750268 -75.11204)
			(xy 248.720807 -75.157888) (xy 248.685123 -75.199077) (xy 248.643939 -75.234769) (xy 248.598096 -75.264237)
			(xy 248.548526 -75.286881) (xy 248.496238 -75.30224) (xy 248.442297 -75.310002) (xy 248.415048 -75.310492)
			(xy 248.387679 -75.31) (xy 248.333501 -75.302189) (xy 248.280998 -75.286706) (xy 248.23125 -75.26387)
			(xy 248.185283 -75.234151) (xy 248.16435 -75.216512) (xy 248.153022 -75.207276) (xy 248.126465 -75.1951)
			(xy 248.097548 -75.190927) (xy 248.068631 -75.1951) (xy 248.042074 -75.207276) (xy 248.030746 -75.216512)
			(xy 248.009809 -75.234145) (xy 247.963837 -75.263857) (xy 247.914091 -75.286694) (xy 247.861592 -75.302187)
			(xy 247.807417 -75.310017) (xy 247.780048 -75.310492) (xy 247.752792 -75.310064) (xy 247.698833 -75.302313)
			(xy 247.646527 -75.28696) (xy 247.596939 -75.264319) (xy 247.551078 -75.234851) (xy 247.509878 -75.199156)
			(xy 247.474177 -75.15796) (xy 247.444704 -75.112103) (xy 247.422057 -75.062518) (xy 247.406698 -75.010214)
			(xy 247.398939 -74.956256) (xy 247.398939 -74.901744) (xy 247.406698 -74.847786) (xy 247.422057 -74.795482)
			(xy 247.444704 -74.745897) (xy 247.474177 -74.70004) (xy 247.509878 -74.658844) (xy 247.551078 -74.623149)
			(xy 247.596939 -74.593681) (xy 247.646527 -74.57104) (xy 247.698833 -74.555687) (xy 247.752792 -74.547936)
			(xy 247.780048 -74.547476) (xy 247.807418 -74.547954) (xy 247.861597 -74.555766) (xy 247.914101 -74.571251)
			(xy 247.963848 -74.594091) (xy 248.009815 -74.623815) (xy 248.030746 -74.641456) (xy 248.042074 -74.650692)
			(xy 248.068631 -74.662868) (xy 248.097548 -74.667041) (xy 248.126465 -74.662868) (xy 248.153022 -74.650692)
			(xy 248.16435 -74.641456) (xy 248.185284 -74.62382) (xy 248.231257 -74.594109) (xy 248.281004 -74.571273)
			(xy 248.333504 -74.555781) (xy 248.387679 -74.547951) (xy 248.415048 -74.547476) (xy 248.426313 -74.547528)
			(xy 248.448807 -74.5488) (xy 248.460006 -74.550016) (xy 248.473603 -74.551239) (xy 248.500583 -74.547112)
			(xy 248.525505 -74.535982) (xy 248.546585 -74.518644) (xy 248.562316 -74.496339) (xy 248.571573 -74.470663)
			(xy 248.573693 -74.443451) (xy 248.568525 -74.416651) (xy 248.562876 -74.40422) (xy 248.550432 -74.377816)
			(xy 248.532811 -74.32217) (xy 248.52385 -74.264494) (xy 248.523252 -74.23531) (xy 248.523252 -74.234548)
			(xy 248.523734 -74.207178) (xy 248.531546 -74.152999) (xy 248.54703 -74.100496) (xy 248.569869 -74.050749)
			(xy 248.599591 -74.004782) (xy 248.617232 -73.98385) (xy 248.62642 -73.972487) (xy 248.638599 -73.945942)
			(xy 248.642779 -73.917036) (xy 248.63862 -73.888128) (xy 248.62646 -73.861574) (xy 248.617232 -73.850246)
			(xy 248.599638 -73.829275) (xy 248.569911 -73.783314) (xy 248.547063 -73.733574) (xy 248.531562 -73.681078)
			(xy 248.523729 -73.626905) (xy 248.523724 -73.572168) (xy 248.531547 -73.517993) (xy 248.547037 -73.465494)
			(xy 248.569876 -73.415749) (xy 248.599595 -73.369783) (xy 248.617232 -73.34885) (xy 248.62642 -73.337487)
			(xy 248.638599 -73.310942) (xy 248.642779 -73.282036) (xy 248.63862 -73.253128) (xy 248.62646 -73.226574)
			(xy 248.617232 -73.215246) (xy 248.599638 -73.194275) (xy 248.569911 -73.148314) (xy 248.547063 -73.098574)
			(xy 248.531562 -73.046078) (xy 248.523729 -72.991905) (xy 248.523724 -72.937168) (xy 248.531547 -72.882993)
			(xy 248.547037 -72.830494) (xy 248.569876 -72.780749) (xy 248.599595 -72.734783) (xy 248.617232 -72.71385)
			(xy 248.62642 -72.702487) (xy 248.638599 -72.675942) (xy 248.642779 -72.647036) (xy 248.63862 -72.618128)
			(xy 248.62646 -72.591574) (xy 248.617232 -72.580246) (xy 248.599606 -72.559303) (xy 248.569891 -72.513334)
			(xy 248.547052 -72.463589) (xy 248.531558 -72.411091) (xy 248.523727 -72.356917) (xy 248.523252 -72.329548)
			(xy 248.52369 -72.302896) (xy 248.53112 -72.250113) (xy 248.545828 -72.198878) (xy 248.556272 -72.174354)
			(xy 248.561856 -72.160208) (xy 248.565466 -72.130032) (xy 248.560054 -72.100128) (xy 248.546096 -72.073132)
			(xy 248.524823 -72.051428) (xy 248.498114 -72.036929) (xy 248.468324 -72.030916) (xy 248.453148 -72.03186)
			(xy 248.415048 -72.033892) (xy 248.387679 -72.0334) (xy 248.333501 -72.025589) (xy 248.280998 -72.010106)
			(xy 248.23125 -71.98727) (xy 248.185283 -71.957551) (xy 248.16435 -71.939912) (xy 248.153022 -71.930676)
			(xy 248.126465 -71.9185) (xy 248.097548 -71.914327) (xy 248.068631 -71.9185) (xy 248.042074 -71.930676)
			(xy 248.030746 -71.939912) (xy 248.009809 -71.957545) (xy 247.963837 -71.987257) (xy 247.914091 -72.010094)
			(xy 247.861592 -72.025587) (xy 247.807417 -72.033417) (xy 247.780048 -72.033892) (xy 247.752796 -72.0334)
			(xy 247.698845 -72.025649) (xy 247.646547 -72.010298) (xy 247.596966 -71.98766) (xy 247.551111 -71.958196)
			(xy 247.509918 -71.922505) (xy 247.474223 -71.881314) (xy 247.444755 -71.835463) (xy 247.422113 -71.785883)
			(xy 247.406758 -71.733586) (xy 247.399002 -71.679636) (xy 247.39854 -71.652384) (xy 246.61368 -71.652384)
			(xy 246.61368 -75.377548) (xy 248.16308 -76.926948) (xy 257.560062 -76.926948) (xy 257.564133 -76.871326)
			(xy 257.576259 -76.816889) (xy 257.596182 -76.764798) (xy 257.623478 -76.716163) (xy 257.657564 -76.67202)
			(xy 257.697713 -76.633311) (xy 257.743071 -76.60086) (xy 257.792671 -76.575359) (xy 257.845455 -76.557352)
			(xy 257.900298 -76.547222) (xy 257.956032 -76.545185) (xy 258.011469 -76.551285) (xy 258.065426 -76.565391)
			(xy 258.116755 -76.587203) (xy 258.164361 -76.616257) (xy 258.207229 -76.651932) (xy 258.244446 -76.693469)
			(xy 258.275219 -76.739982) (xy 258.298891 -76.790479) (xy 258.314959 -76.843886) (xy 258.323079 -76.899062)
			(xy 258.323588 -76.926948) (xy 258.323079 -76.954834) (xy 258.314959 -77.01001) (xy 258.298891 -77.063417)
			(xy 258.275219 -77.113914) (xy 258.244446 -77.160427) (xy 258.207229 -77.201964) (xy 258.164361 -77.237639)
			(xy 258.116755 -77.266693) (xy 258.065426 -77.288505) (xy 258.011469 -77.302611) (xy 257.956032 -77.308711)
			(xy 257.900298 -77.306674) (xy 257.845455 -77.296544) (xy 257.792671 -77.278537) (xy 257.743071 -77.253036)
			(xy 257.697713 -77.220585) (xy 257.657564 -77.181876) (xy 257.623478 -77.137733) (xy 257.596182 -77.089098)
			(xy 257.576259 -77.037007) (xy 257.564133 -76.98257) (xy 257.560062 -76.926948) (xy 248.16308 -76.926948)
			(xy 249.313954 -78.077822) (xy 262.833104 -78.077822) (xy 262.833509 -78.051441) (xy 262.840772 -77.999182)
			(xy 262.855163 -77.948421) (xy 262.876408 -77.900125) (xy 262.904101 -77.855216) (xy 262.937715 -77.814548)
			(xy 262.97661 -77.778897) (xy 263.020043 -77.748942) (xy 263.043416 -77.7367) (xy 263.05576 -77.72997)
			(xy 263.076497 -77.711003) (xy 263.091265 -77.687094) (xy 263.098943 -77.660061) (xy 263.098945 -77.631959)
			(xy 263.091273 -77.604924) (xy 263.076509 -77.581012) (xy 263.055777 -77.562042) (xy 263.043416 -77.555344)
			(xy 263.020059 -77.543078) (xy 262.976634 -77.513121) (xy 262.937747 -77.477469) (xy 262.90414 -77.436803)
			(xy 262.876451 -77.391898) (xy 262.855209 -77.343608) (xy 262.840817 -77.292853) (xy 262.833551 -77.2406)
			(xy 262.833104 -77.214222) (xy 262.83359 -77.186971) (xy 262.841346 -77.133023) (xy 262.856701 -77.080728)
			(xy 262.879343 -77.031151) (xy 262.908809 -76.985301) (xy 262.9445 -76.94411) (xy 262.985691 -76.908419)
			(xy 263.031541 -76.878953) (xy 263.081118 -76.856311) (xy 263.133413 -76.840956) (xy 263.187361 -76.8332)
			(xy 263.241863 -76.8332) (xy 263.295811 -76.840956) (xy 263.348106 -76.856311) (xy 263.397683 -76.878953)
			(xy 263.443533 -76.908419) (xy 263.484724 -76.94411) (xy 263.520415 -76.985301) (xy 263.549881 -77.031151)
			(xy 263.572523 -77.080728) (xy 263.587878 -77.133023) (xy 263.595634 -77.186971) (xy 263.59612 -77.214222)
			(xy 263.595656 -77.240601) (xy 263.588401 -77.292857) (xy 263.574018 -77.343616) (xy 263.552782 -77.39191)
			(xy 263.525097 -77.43682) (xy 263.491491 -77.477489) (xy 263.452604 -77.513142) (xy 263.409177 -77.5431)
			(xy 263.385808 -77.555344) (xy 263.373433 -77.562015) (xy 263.352707 -77.580998) (xy 263.337949 -77.604918)
			(xy 263.330281 -77.631957) (xy 263.330283 -77.660063) (xy 263.337957 -77.6871) (xy 263.352719 -77.711017)
			(xy 263.373449 -77.729996) (xy 263.385808 -77.7367) (xy 263.409189 -77.748922) (xy 263.452614 -77.778887)
			(xy 263.491499 -77.814545) (xy 263.525104 -77.855217) (xy 263.55279 -77.900129) (xy 263.574029 -77.948425)
			(xy 263.588415 -77.999185) (xy 263.595676 -78.051442) (xy 263.59612 -78.077822) (xy 263.595634 -78.105073)
			(xy 263.587878 -78.159021) (xy 263.572523 -78.211316) (xy 263.549881 -78.260893) (xy 263.520415 -78.306743)
			(xy 263.484724 -78.347934) (xy 263.443533 -78.383625) (xy 263.397683 -78.413091) (xy 263.348106 -78.435733)
			(xy 263.295811 -78.451088) (xy 263.241863 -78.458844) (xy 263.187361 -78.458844) (xy 263.133413 -78.451088)
			(xy 263.081118 -78.435733) (xy 263.031541 -78.413091) (xy 262.985691 -78.383625) (xy 262.9445 -78.347934)
			(xy 262.908809 -78.306743) (xy 262.879343 -78.260893) (xy 262.856701 -78.211316) (xy 262.841346 -78.159021)
			(xy 262.83359 -78.105073) (xy 262.833104 -78.077822) (xy 249.313954 -78.077822) (xy 250.579128 -79.342996)
			(xy 258.858004 -79.342996) (xy 258.871642 -79.342519) (xy 258.897927 -79.335222) (xy 258.921345 -79.321231)
			(xy 258.940226 -79.301542) (xy 258.953225 -79.277558) (xy 258.959414 -79.250991) (xy 258.958353 -79.223732)
			(xy 258.950117 -79.197726) (xy 258.943094 -79.186024) (xy 258.928492 -79.162696) (xy 258.905418 -79.112734)
			(xy 258.889759 -79.059975) (xy 258.88184 -79.005515) (xy 258.881372 -78.977998) (xy 258.881858 -78.950747)
			(xy 258.889614 -78.896799) (xy 258.904969 -78.844504) (xy 258.927611 -78.794927) (xy 258.957077 -78.749077)
			(xy 258.992768 -78.707886) (xy 259.033959 -78.672195) (xy 259.079809 -78.642729) (xy 259.129386 -78.620087)
			(xy 259.181681 -78.604732) (xy 259.235629 -78.596976) (xy 259.290131 -78.596976) (xy 259.344079 -78.604732)
			(xy 259.396374 -78.620087) (xy 259.445951 -78.642729) (xy 259.491801 -78.672195) (xy 259.532992 -78.707886)
			(xy 259.568683 -78.749077) (xy 259.598149 -78.794927) (xy 259.620791 -78.844504) (xy 259.636146 -78.896799)
			(xy 259.643902 -78.950747) (xy 259.644388 -78.977998) (xy 259.643906 -79.005514) (xy 259.635996 -79.059975)
			(xy 259.620341 -79.112734) (xy 259.597266 -79.162695) (xy 259.582666 -79.186024) (xy 259.575596 -79.197712)
			(xy 259.567319 -79.223733) (xy 259.566233 -79.251018) (xy 259.572416 -79.277615) (xy 259.585426 -79.301622)
			(xy 259.604332 -79.321324) (xy 259.627784 -79.335312) (xy 259.654104 -79.342585) (xy 259.667756 -79.342996)
			(xy 272.803366 -79.342996) (xy 275.051012 -77.095096) (xy 275.051012 -75.989942) (xy 275.035995 -75.96642)
			(xy 275.012262 -75.915913) (xy 274.996149 -75.862485) (xy 274.987999 -75.807278) (xy 274.987512 -75.779376)
			(xy 274.987512 -75.778868) (xy 274.988 -75.751619) (xy 274.995761 -75.697676) (xy 275.011119 -75.645386)
			(xy 275.033762 -75.595814) (xy 275.06323 -75.549969) (xy 275.098921 -75.508784) (xy 275.140111 -75.473098)
			(xy 275.18596 -75.443637) (xy 275.235535 -75.421001) (xy 275.287827 -75.40565) (xy 275.341771 -75.397897)
			(xy 275.36902 -75.39736) (xy 275.396389 -75.397833) (xy 275.450565 -75.405661) (xy 275.503066 -75.421152)
			(xy 275.552813 -75.443989) (xy 275.598785 -75.473702) (xy 275.619718 -75.49134) (xy 275.631046 -75.500576)
			(xy 275.657603 -75.512752) (xy 275.68652 -75.516925) (xy 275.715437 -75.512752) (xy 275.741994 -75.500576)
			(xy 275.753322 -75.49134) (xy 275.774255 -75.473699) (xy 275.820223 -75.443975) (xy 275.869969 -75.421129)
			(xy 275.922471 -75.405633) (xy 275.976649 -75.397804) (xy 276.031391 -75.397804) (xy 276.085569 -75.405633)
			(xy 276.138071 -75.421129) (xy 276.187817 -75.443975) (xy 276.233785 -75.473699) (xy 276.254718 -75.49134)
			(xy 276.266046 -75.500576) (xy 276.292603 -75.512752) (xy 276.32152 -75.516925) (xy 276.350437 -75.512752)
			(xy 276.376994 -75.500576) (xy 276.388322 -75.49134) (xy 276.409255 -75.473699) (xy 276.455223 -75.443975)
			(xy 276.504969 -75.421129) (xy 276.557471 -75.405633) (xy 276.611649 -75.397804) (xy 276.666391 -75.397804)
			(xy 276.720569 -75.405633) (xy 276.773071 -75.421129) (xy 276.822817 -75.443975) (xy 276.868785 -75.473699)
			(xy 276.889718 -75.49134) (xy 276.901046 -75.500576) (xy 276.927603 -75.512752) (xy 276.95652 -75.516925)
			(xy 276.985437 -75.512752) (xy 277.011994 -75.500576) (xy 277.023322 -75.49134) (xy 277.044255 -75.473699)
			(xy 277.090223 -75.443975) (xy 277.139969 -75.421129) (xy 277.192471 -75.405633) (xy 277.246649 -75.397804)
			(xy 277.301391 -75.397804) (xy 277.355569 -75.405633) (xy 277.408071 -75.421129) (xy 277.457817 -75.443975)
			(xy 277.503785 -75.473699) (xy 277.524718 -75.49134) (xy 277.536046 -75.500576) (xy 277.562603 -75.512752)
			(xy 277.59152 -75.516925) (xy 277.620437 -75.512752) (xy 277.646994 -75.500576) (xy 277.658322 -75.49134)
			(xy 277.679253 -75.473698) (xy 277.725219 -75.443971) (xy 277.774966 -75.421128) (xy 277.82747 -75.405639)
			(xy 277.881649 -75.397823) (xy 277.90902 -75.39736) (xy 277.936271 -75.397847) (xy 277.990218 -75.405606)
			(xy 278.042513 -75.420962) (xy 278.092089 -75.443604) (xy 278.13794 -75.47307) (xy 278.17913 -75.508762)
			(xy 278.214822 -75.549951) (xy 278.24429 -75.5958) (xy 278.266933 -75.645376) (xy 278.282292 -75.69767)
			(xy 278.290052 -75.751617) (xy 278.290528 -75.778868) (xy 278.290528 -75.779376) (xy 278.29 -75.807275)
			(xy 278.28184 -75.862475) (xy 278.265735 -75.9159) (xy 278.242027 -75.966412) (xy 278.227028 -75.989942)
			(xy 278.227028 -77.130402) (xy 278.226517 -77.155386) (xy 278.218667 -77.204735) (xy 278.203208 -77.252252)
			(xy 278.180519 -77.296773) (xy 278.151156 -77.337205) (xy 278.13381 -77.355192) (xy 277.675848 -77.813154)
			(xy 277.791418 -77.929232) (xy 277.808727 -77.94722) (xy 277.838087 -77.98759) (xy 277.860776 -78.032052)
			(xy 277.876238 -78.079514) (xy 277.884091 -78.12881) (xy 277.884636 -78.153768) (xy 277.884636 -78.333092)
			(xy 277.884118 -78.358073) (xy 277.876256 -78.407415) (xy 277.860787 -78.454924) (xy 277.83809 -78.499435)
			(xy 277.808722 -78.539857) (xy 277.791418 -78.557882) (xy 277.663402 -78.685898) (xy 277.645418 -78.703254)
			(xy 277.605006 -78.73266) (xy 277.560488 -78.755374) (xy 277.512962 -78.770836) (xy 277.463601 -78.778665)
			(xy 277.438612 -78.779116) (xy 277.259288 -78.779116) (xy 277.234289 -78.778632) (xy 277.184914 -78.770763)
			(xy 277.137383 -78.755253) (xy 277.092869 -78.732486) (xy 277.052474 -78.703023) (xy 277.034498 -78.685644)
			(xy 276.918928 -78.570074) (xy 276.119336 -79.369666) (xy 276.109122 -79.380633) (xy 276.094999 -79.40705)
			(xy 276.089142 -79.436427) (xy 276.092056 -79.46624) (xy 276.10349 -79.493926) (xy 276.122462 -79.517108)
			(xy 276.14734 -79.533792) (xy 276.175988 -79.542545) (xy 276.190964 -79.543148) (xy 278.342598 -79.543148)
		)
		(stroke
			(width 0)
			(type solid)
		)
		(fill yes)
		(layer "In13.Cu")
		(net "GND")
	)
	(gr_poly
		(pts
			(xy 459.66888 -31.714948) (xy 459.66888 -23.506938) (xy 459.646099 -23.408037) (xy 459.60723 -23.208815)
			(xy 459.576061 -23.008244) (xy 459.552639 -22.806621) (xy 459.536998 -22.604246) (xy 459.529161 -22.401419)
			(xy 459.528672 -22.29993) (xy 459.529176 -22.198441) (xy 459.537021 -21.995615) (xy 459.552666 -21.793241)
			(xy 459.576088 -21.591619) (xy 459.607252 -21.391048) (xy 459.646112 -21.191825) (xy 459.66888 -21.092922)
			(xy 459.66888 -15.331948) (xy 459.004162 -14.66723) (xy 458.993748 -14.66342) (xy 458.96991 -14.654124)
			(xy 458.924963 -14.629678) (xy 458.883977 -14.599053) (xy 458.847795 -14.562877) (xy 458.817161 -14.521897)
			(xy 458.792706 -14.476955) (xy 458.783436 -14.453108) (xy 458.779626 -14.442694) (xy 457.76388 -13.426948)
			(xy 457.557124 -13.426948) (xy 457.546456 -13.463778) (xy 457.538466 -13.489991) (xy 457.516013 -13.53998)
			(xy 457.486638 -13.586241) (xy 457.450947 -13.627824) (xy 457.409672 -13.663871) (xy 457.363665 -13.693642)
			(xy 457.313871 -13.716523) (xy 457.261315 -13.732044) (xy 457.20708 -13.739885) (xy 457.15228 -13.739885)
			(xy 457.098045 -13.732044) (xy 457.045489 -13.716523) (xy 456.995695 -13.693642) (xy 456.949688 -13.663871)
			(xy 456.908413 -13.627824) (xy 456.872722 -13.586241) (xy 456.843347 -13.53998) (xy 456.820894 -13.489991)
			(xy 456.812904 -13.463778) (xy 456.802236 -13.426948) (xy 452.9455 -13.426948) (xy 452.93117 -13.427435)
			(xy 452.903638 -13.435395) (xy 452.8794 -13.450687) (xy 452.860362 -13.47211) (xy 452.848023 -13.497977)
			(xy 452.843352 -13.526253) (xy 452.846719 -13.554714) (xy 452.857857 -13.581121) (xy 452.866506 -13.592556)
			(xy 452.882614 -13.613058) (xy 452.909707 -13.657604) (xy 452.930483 -13.705424) (xy 452.944555 -13.755627)
			(xy 452.951661 -13.807279) (xy 452.952104 -13.833348) (xy 452.951618 -13.860599) (xy 452.943862 -13.914547)
			(xy 452.928507 -13.966842) (xy 452.905865 -14.016419) (xy 452.876399 -14.062269) (xy 452.840708 -14.10346)
			(xy 452.799517 -14.139151) (xy 452.753667 -14.168617) (xy 452.70409 -14.191259) (xy 452.651795 -14.206614)
			(xy 452.597847 -14.21437) (xy 452.543345 -14.21437) (xy 452.489397 -14.206614) (xy 452.437102 -14.191259)
			(xy 452.387525 -14.168617) (xy 452.341675 -14.139151) (xy 452.300484 -14.10346) (xy 452.264793 -14.062269)
			(xy 452.235327 -14.016419) (xy 452.212685 -13.966842) (xy 452.19733 -13.914547) (xy 452.189574 -13.860599)
			(xy 452.189088 -13.833348) (xy 452.18951 -13.807277) (xy 452.196607 -13.755619) (xy 452.210674 -13.70541)
			(xy 452.23145 -13.657585) (xy 452.258548 -13.613036) (xy 452.274686 -13.592556) (xy 452.283329 -13.581119)
			(xy 452.294477 -13.554723) (xy 452.29785 -13.526268) (xy 452.293181 -13.497997) (xy 452.280839 -13.472138)
			(xy 452.261796 -13.450727) (xy 452.237553 -13.435453) (xy 452.21002 -13.427518) (xy 452.195692 -13.426948)
			(xy 451.761352 -13.426948) (xy 451.74669 -13.42744) (xy 451.718577 -13.435786) (xy 451.693996 -13.451778)
			(xy 451.674972 -13.474096) (xy 451.663075 -13.500899) (xy 451.659285 -13.529979) (xy 451.661022 -13.54455)
			(xy 451.66327 -13.559498) (xy 451.665684 -13.589633) (xy 451.665848 -13.604748) (xy 451.665362 -13.631999)
			(xy 451.657606 -13.685947) (xy 451.642251 -13.738242) (xy 451.619609 -13.787819) (xy 451.590143 -13.833669)
			(xy 451.554452 -13.87486) (xy 451.513261 -13.910551) (xy 451.467411 -13.940017) (xy 451.417834 -13.962659)
			(xy 451.365539 -13.978014) (xy 451.311591 -13.98577) (xy 451.257089 -13.98577) (xy 451.203141 -13.978014)
			(xy 451.150846 -13.962659) (xy 451.101269 -13.940017) (xy 451.055419 -13.910551) (xy 451.014228 -13.87486)
			(xy 450.978537 -13.833669) (xy 450.949071 -13.787819) (xy 450.926429 -13.738242) (xy 450.911074 -13.685947)
			(xy 450.903318 -13.631999) (xy 450.902832 -13.604748) (xy 450.902992 -13.589633) (xy 450.90541 -13.559498)
			(xy 450.907658 -13.54455) (xy 450.909497 -13.529981) (xy 450.905703 -13.500875) (xy 450.893794 -13.474047)
			(xy 450.87475 -13.45171) (xy 450.850144 -13.435706) (xy 450.822004 -13.427356) (xy 450.807328 -13.426948)
			(xy 450.501766 -13.426948) (xy 450.486555 -13.427504) (xy 450.457477 -13.436446) (xy 450.432324 -13.453556)
			(xy 450.413326 -13.477317) (xy 450.402171 -13.505619) (xy 450.399847 -13.535952) (xy 450.402706 -13.5509)
			(xy 450.407104 -13.571704) (xy 450.41181 -13.613966) (xy 450.412104 -13.635228) (xy 450.411618 -13.662479)
			(xy 450.403862 -13.716427) (xy 450.388507 -13.768722) (xy 450.365865 -13.818299) (xy 450.336399 -13.864149)
			(xy 450.300708 -13.90534) (xy 450.259517 -13.941031) (xy 450.213667 -13.970497) (xy 450.16409 -13.993139)
			(xy 450.111795 -14.008494) (xy 450.057847 -14.01625) (xy 450.003345 -14.01625) (xy 449.949397 -14.008494)
			(xy 449.897102 -13.993139) (xy 449.847525 -13.970497) (xy 449.801675 -13.941031) (xy 449.760484 -13.90534)
			(xy 449.724793 -13.864149) (xy 449.695327 -13.818299) (xy 449.672685 -13.768722) (xy 449.65733 -13.716427)
			(xy 449.649574 -13.662479) (xy 449.649088 -13.635228) (xy 449.649365 -13.613965) (xy 449.654076 -13.571702)
			(xy 449.658486 -13.5509) (xy 449.661273 -13.535952) (xy 449.658927 -13.505652) (xy 449.647769 -13.477384)
			(xy 449.628788 -13.45365) (xy 449.603664 -13.436552) (xy 449.574621 -13.427603) (xy 449.559426 -13.426948)
			(xy 449.35648 -13.426948) (xy 449.342803 -13.427383) (xy 449.31643 -13.434644) (xy 449.292942 -13.448663)
			(xy 449.274032 -13.468428) (xy 449.261067 -13.492514) (xy 449.254981 -13.519182) (xy 449.255134 -13.532866)
			(xy 449.255388 -13.548868) (xy 449.254902 -13.576119) (xy 449.247146 -13.630067) (xy 449.231791 -13.682362)
			(xy 449.209149 -13.731939) (xy 449.179683 -13.777789) (xy 449.143992 -13.81898) (xy 449.102801 -13.854671)
			(xy 449.056951 -13.884137) (xy 449.007374 -13.906779) (xy 448.955079 -13.922134) (xy 448.901131 -13.92989)
			(xy 448.846629 -13.92989) (xy 448.792681 -13.922134) (xy 448.740386 -13.906779) (xy 448.690809 -13.884137)
			(xy 448.644959 -13.854671) (xy 448.603768 -13.81898) (xy 448.568077 -13.777789) (xy 448.538611 -13.731939)
			(xy 448.515969 -13.682362) (xy 448.500614 -13.630067) (xy 448.492858 -13.576119) (xy 448.492372 -13.548868)
			(xy 448.492626 -13.532866) (xy 448.492759 -13.51919) (xy 448.486623 -13.492548) (xy 448.473643 -13.468486)
			(xy 448.454748 -13.448727) (xy 448.43129 -13.434684) (xy 448.404949 -13.427363) (xy 448.39128 -13.426948)
			(xy 448.21856 -13.426948) (xy 448.205242 -13.427349) (xy 448.179516 -13.434253) (xy 448.156454 -13.447581)
			(xy 448.137627 -13.466424) (xy 448.124319 -13.489498) (xy 448.117437 -13.51523) (xy 448.11696 -13.528548)
			(xy 448.116474 -13.555799) (xy 448.108718 -13.609747) (xy 448.093363 -13.662042) (xy 448.070721 -13.711619)
			(xy 448.041255 -13.757469) (xy 448.005564 -13.79866) (xy 447.964373 -13.834351) (xy 447.918523 -13.863817)
			(xy 447.868946 -13.886459) (xy 447.816651 -13.901814) (xy 447.762703 -13.90957) (xy 447.708201 -13.90957)
			(xy 447.654253 -13.901814) (xy 447.601958 -13.886459) (xy 447.552381 -13.863817) (xy 447.506531 -13.834351)
			(xy 447.46534 -13.79866) (xy 447.429649 -13.757469) (xy 447.400183 -13.711619) (xy 447.377541 -13.662042)
			(xy 447.362186 -13.609747) (xy 447.35443 -13.555799) (xy 447.353944 -13.528548) (xy 447.353555 -13.515218)
			(xy 447.346667 -13.489463) (xy 447.333347 -13.466369) (xy 447.314504 -13.447509) (xy 447.291422 -13.434169)
			(xy 447.265674 -13.427257) (xy 447.252344 -13.426948) (xy 442.67628 -13.426948) (xy 440.10453 -15.998698)
			(xy 450.297804 -15.998698) (xy 450.298267 -15.971123) (xy 450.30622 -15.91655) (xy 450.321945 -15.86369)
			(xy 450.345116 -15.813644) (xy 450.375249 -15.767455) (xy 450.411717 -15.726084) (xy 450.432424 -15.707868)
			(xy 450.443321 -15.69797) (xy 450.459389 -15.673319) (xy 450.46777 -15.645112) (xy 450.467769 -15.615686)
			(xy 450.459388 -15.587479) (xy 450.443319 -15.562828) (xy 450.432424 -15.552928) (xy 450.411728 -15.5347)
			(xy 450.375256 -15.493336) (xy 450.345121 -15.447149) (xy 450.321952 -15.397105) (xy 450.306233 -15.344245)
			(xy 450.298291 -15.289672) (xy 450.297804 -15.262098) (xy 450.29829 -15.234847) (xy 450.306046 -15.180899)
			(xy 450.321401 -15.128604) (xy 450.344043 -15.079027) (xy 450.373509 -15.033177) (xy 450.4092 -14.991986)
			(xy 450.450391 -14.956295) (xy 450.496241 -14.926829) (xy 450.545818 -14.904187) (xy 450.598113 -14.888832)
			(xy 450.652061 -14.881076) (xy 450.706563 -14.881076) (xy 450.760511 -14.888832) (xy 450.812806 -14.904187)
			(xy 450.862383 -14.926829) (xy 450.908233 -14.956295) (xy 450.949424 -14.991986) (xy 450.985115 -15.033177)
			(xy 451.014581 -15.079027) (xy 451.037223 -15.128604) (xy 451.052578 -15.180899) (xy 451.060334 -15.234847)
			(xy 451.06082 -15.262098) (xy 451.060346 -15.289672) (xy 451.052394 -15.344244) (xy 451.03667 -15.397104)
			(xy 451.013502 -15.44715) (xy 450.983371 -15.493339) (xy 450.946906 -15.534711) (xy 450.9262 -15.552928)
			(xy 450.915305 -15.562829) (xy 450.899233 -15.587479) (xy 450.890849 -15.615685) (xy 450.890849 -15.645112)
			(xy 450.899232 -15.673319) (xy 450.915304 -15.697969) (xy 450.9262 -15.707868) (xy 450.946899 -15.726092)
			(xy 450.98337 -15.767458) (xy 451.013504 -15.813646) (xy 451.036672 -15.863691) (xy 451.052391 -15.916551)
			(xy 451.060333 -15.971124) (xy 451.06082 -15.998698) (xy 451.060334 -16.025949) (xy 451.052578 -16.079897)
			(xy 451.037223 -16.132192) (xy 451.014581 -16.181769) (xy 450.985115 -16.227619) (xy 450.949424 -16.26881)
			(xy 450.908233 -16.304501) (xy 450.862383 -16.333967) (xy 450.812806 -16.356609) (xy 450.760511 -16.371964)
			(xy 450.706563 -16.37972) (xy 450.652061 -16.37972) (xy 450.598113 -16.371964) (xy 450.545818 -16.356609)
			(xy 450.496241 -16.333967) (xy 450.450391 -16.304501) (xy 450.4092 -16.26881) (xy 450.373509 -16.227619)
			(xy 450.344043 -16.181769) (xy 450.321401 -16.132192) (xy 450.306046 -16.079897) (xy 450.29829 -16.025949)
			(xy 450.297804 -15.998698) (xy 440.10453 -15.998698) (xy 439.97372 -16.129508) (xy 439.97372 -19.00682)
			(xy 441.796424 -19.00682) (xy 441.796896 -18.97945) (xy 441.804711 -18.925271) (xy 441.820199 -18.872768)
			(xy 441.843039 -18.823021) (xy 441.872763 -18.777054) (xy 441.890404 -18.756122) (xy 441.899621 -18.74478)
			(xy 441.911801 -18.718228) (xy 441.915977 -18.689315) (xy 441.911809 -18.660401) (xy 441.899638 -18.633845)
			(xy 441.890404 -18.622518) (xy 441.872761 -18.601589) (xy 441.843049 -18.555616) (xy 441.820214 -18.505867)
			(xy 441.804724 -18.453366) (xy 441.796897 -18.399189) (xy 441.796424 -18.37182) (xy 441.79691 -18.344569)
			(xy 441.804666 -18.290621) (xy 441.820021 -18.238326) (xy 441.842663 -18.188749) (xy 441.872129 -18.142899)
			(xy 441.90782 -18.101708) (xy 441.949011 -18.066017) (xy 441.994861 -18.036551) (xy 442.044438 -18.013909)
			(xy 442.096733 -17.998554) (xy 442.150681 -17.990798) (xy 442.205183 -17.990798) (xy 442.259131 -17.998554)
			(xy 442.311426 -18.013909) (xy 442.361003 -18.036551) (xy 442.406853 -18.066017) (xy 442.448044 -18.101708)
			(xy 442.483735 -18.142899) (xy 442.513201 -18.188749) (xy 442.535843 -18.238326) (xy 442.551198 -18.290621)
			(xy 442.558954 -18.344569) (xy 442.55944 -18.37182) (xy 442.559 -18.399191) (xy 442.552207 -18.446242)
			(xy 446.165984 -18.446242) (xy 446.170055 -18.39062) (xy 446.182181 -18.336183) (xy 446.202104 -18.284092)
			(xy 446.2294 -18.235457) (xy 446.263486 -18.191314) (xy 446.303635 -18.152605) (xy 446.348993 -18.120154)
			(xy 446.398593 -18.094653) (xy 446.451377 -18.076646) (xy 446.50622 -18.066516) (xy 446.561954 -18.064479)
			(xy 446.617391 -18.070579) (xy 446.671348 -18.084685) (xy 446.722677 -18.106497) (xy 446.770283 -18.135551)
			(xy 446.813151 -18.171226) (xy 446.850368 -18.212763) (xy 446.881141 -18.259276) (xy 446.904813 -18.309773)
			(xy 446.920881 -18.36318) (xy 446.929001 -18.418356) (xy 446.92951 -18.446242) (xy 446.929195 -18.463514)
			(xy 449.291454 -18.463514) (xy 449.295525 -18.407892) (xy 449.307651 -18.353455) (xy 449.327574 -18.301364)
			(xy 449.35487 -18.252729) (xy 449.388956 -18.208586) (xy 449.429105 -18.169877) (xy 449.474463 -18.137426)
			(xy 449.524063 -18.111925) (xy 449.576847 -18.093918) (xy 449.63169 -18.083788) (xy 449.687424 -18.081751)
			(xy 449.742861 -18.087851) (xy 449.796818 -18.101957) (xy 449.848147 -18.123769) (xy 449.895753 -18.152823)
			(xy 449.938621 -18.188498) (xy 449.975838 -18.230035) (xy 450.006611 -18.276548) (xy 450.030283 -18.327045)
			(xy 450.046351 -18.380452) (xy 450.054471 -18.435628) (xy 450.05498 -18.463514) (xy 450.054471 -18.4914)
			(xy 450.046351 -18.546576) (xy 450.030283 -18.599983) (xy 450.018171 -18.62582) (xy 450.615302 -18.62582)
			(xy 450.619373 -18.570198) (xy 450.631499 -18.515761) (xy 450.651422 -18.46367) (xy 450.678718 -18.415035)
			(xy 450.712804 -18.370892) (xy 450.752953 -18.332183) (xy 450.798311 -18.299732) (xy 450.847911 -18.274231)
			(xy 450.900695 -18.256224) (xy 450.955538 -18.246094) (xy 451.011272 -18.244057) (xy 451.066709 -18.250157)
			(xy 451.120666 -18.264263) (xy 451.171995 -18.286075) (xy 451.219601 -18.315129) (xy 451.262469 -18.350804)
			(xy 451.299686 -18.392341) (xy 451.330459 -18.438854) (xy 451.354131 -18.489351) (xy 451.364392 -18.523458)
			(xy 451.682104 -18.523458) (xy 451.682608 -18.495885) (xy 451.690553 -18.441314) (xy 451.70627 -18.388454)
			(xy 451.729433 -18.338408) (xy 451.759559 -18.292218) (xy 451.79602 -18.250845) (xy 451.816724 -18.232628)
			(xy 451.827661 -18.222771) (xy 451.843728 -18.198108) (xy 451.852104 -18.16989) (xy 451.852096 -18.140456)
			(xy 451.843705 -18.112242) (xy 451.827625 -18.087588) (xy 451.816724 -18.077688) (xy 451.796009 -18.059481)
			(xy 451.759538 -18.018112) (xy 451.729405 -17.971922) (xy 451.70624 -17.921873) (xy 451.690525 -17.869009)
			(xy 451.682588 -17.814433) (xy 451.682104 -17.786858) (xy 451.68259 -17.759607) (xy 451.690346 -17.705659)
			(xy 451.705701 -17.653364) (xy 451.728343 -17.603787) (xy 451.757809 -17.557937) (xy 451.7935 -17.516746)
			(xy 451.834691 -17.481055) (xy 451.880541 -17.451589) (xy 451.930118 -17.428947) (xy 451.982413 -17.413592)
			(xy 452.036361 -17.405836) (xy 452.090863 -17.405836) (xy 452.144811 -17.413592) (xy 452.197106 -17.428947)
			(xy 452.246683 -17.451589) (xy 452.292533 -17.481055) (xy 452.333724 -17.516746) (xy 452.369415 -17.557937)
			(xy 452.398881 -17.603787) (xy 452.421523 -17.653364) (xy 452.436878 -17.705659) (xy 452.444634 -17.759607)
			(xy 452.44512 -17.786858) (xy 452.444618 -17.814431) (xy 452.436672 -17.869002) (xy 452.420954 -17.921861)
			(xy 452.39779 -17.971907) (xy 452.367665 -18.018098) (xy 452.331204 -18.059471) (xy 452.3105 -18.077688)
			(xy 452.299645 -18.087629) (xy 452.283572 -18.112268) (xy 452.275183 -18.140464) (xy 452.275176 -18.169882)
			(xy 452.283549 -18.198083) (xy 452.299609 -18.222729) (xy 452.3105 -18.232628) (xy 452.331228 -18.250821)
			(xy 452.367697 -18.292194) (xy 452.397827 -18.338387) (xy 452.42099 -18.388439) (xy 452.436703 -18.441305)
			(xy 452.444637 -18.495882) (xy 452.44512 -18.523458) (xy 452.444634 -18.550709) (xy 452.436878 -18.604657)
			(xy 452.421523 -18.656952) (xy 452.398881 -18.706529) (xy 452.369415 -18.752379) (xy 452.333724 -18.79357)
			(xy 452.292533 -18.829261) (xy 452.246683 -18.858727) (xy 452.197106 -18.881369) (xy 452.144811 -18.896724)
			(xy 452.090863 -18.90448) (xy 452.036361 -18.90448) (xy 451.982413 -18.896724) (xy 451.930118 -18.881369)
			(xy 451.880541 -18.858727) (xy 451.834691 -18.829261) (xy 451.7935 -18.79357) (xy 451.757809 -18.752379)
			(xy 451.728343 -18.706529) (xy 451.705701 -18.656952) (xy 451.690346 -18.604657) (xy 451.68259 -18.550709)
			(xy 451.682104 -18.523458) (xy 451.364392 -18.523458) (xy 451.370199 -18.542758) (xy 451.378319 -18.597934)
			(xy 451.378828 -18.62582) (xy 451.378319 -18.653706) (xy 451.370199 -18.708882) (xy 451.354131 -18.762289)
			(xy 451.330459 -18.812786) (xy 451.299686 -18.859299) (xy 451.262469 -18.900836) (xy 451.219601 -18.936511)
			(xy 451.171995 -18.965565) (xy 451.120666 -18.987377) (xy 451.066709 -19.001483) (xy 451.011272 -19.007583)
			(xy 450.955538 -19.005546) (xy 450.900695 -18.995416) (xy 450.847911 -18.977409) (xy 450.798311 -18.951908)
			(xy 450.752953 -18.919457) (xy 450.712804 -18.880748) (xy 450.678718 -18.836605) (xy 450.651422 -18.78797)
			(xy 450.631499 -18.735879) (xy 450.619373 -18.681442) (xy 450.615302 -18.62582) (xy 450.018171 -18.62582)
			(xy 450.006611 -18.65048) (xy 449.975838 -18.696993) (xy 449.938621 -18.73853) (xy 449.895753 -18.774205)
			(xy 449.848147 -18.803259) (xy 449.796818 -18.825071) (xy 449.742861 -18.839177) (xy 449.687424 -18.845277)
			(xy 449.63169 -18.84324) (xy 449.576847 -18.83311) (xy 449.524063 -18.815103) (xy 449.474463 -18.789602)
			(xy 449.429105 -18.757151) (xy 449.388956 -18.718442) (xy 449.35487 -18.674299) (xy 449.327574 -18.625664)
			(xy 449.307651 -18.573573) (xy 449.295525 -18.519136) (xy 449.291454 -18.463514) (xy 446.929195 -18.463514)
			(xy 446.929001 -18.474128) (xy 446.920881 -18.529304) (xy 446.904813 -18.582711) (xy 446.881141 -18.633208)
			(xy 446.850368 -18.679721) (xy 446.813151 -18.721258) (xy 446.770283 -18.756933) (xy 446.722677 -18.785987)
			(xy 446.671348 -18.807799) (xy 446.617391 -18.821905) (xy 446.561954 -18.828005) (xy 446.50622 -18.825968)
			(xy 446.451377 -18.815838) (xy 446.398593 -18.797831) (xy 446.348993 -18.77233) (xy 446.303635 -18.739879)
			(xy 446.263486 -18.70117) (xy 446.2294 -18.657027) (xy 446.202104 -18.608392) (xy 446.182181 -18.556301)
			(xy 446.170055 -18.501864) (xy 446.165984 -18.446242) (xy 442.552207 -18.446242) (xy 442.551178 -18.453372)
			(xy 442.535684 -18.505876) (xy 442.512836 -18.555623) (xy 442.483105 -18.601588) (xy 442.46546 -18.622518)
			(xy 442.456207 -18.633832) (xy 442.444037 -18.660395) (xy 442.43987 -18.689315) (xy 442.444046 -18.718234)
			(xy 442.456224 -18.744793) (xy 442.46546 -18.756122) (xy 442.48307 -18.777078) (xy 442.512787 -18.823043)
			(xy 442.53563 -18.872785) (xy 442.551127 -18.925281) (xy 442.558963 -18.979452) (xy 442.55944 -19.00682)
			(xy 442.558954 -19.034071) (xy 442.551198 -19.088019) (xy 442.535843 -19.140314) (xy 442.513201 -19.189891)
			(xy 442.483735 -19.235741) (xy 442.448044 -19.276932) (xy 442.406853 -19.312623) (xy 442.361003 -19.342089)
			(xy 442.311426 -19.364731) (xy 442.259131 -19.380086) (xy 442.205183 -19.387842) (xy 442.150681 -19.387842)
			(xy 442.096733 -19.380086) (xy 442.044438 -19.364731) (xy 441.994861 -19.342089) (xy 441.949011 -19.312623)
			(xy 441.90782 -19.276932) (xy 441.872129 -19.235741) (xy 441.842663 -19.189891) (xy 441.820021 -19.140314)
			(xy 441.804666 -19.088019) (xy 441.79691 -19.034071) (xy 441.796424 -19.00682) (xy 439.97372 -19.00682)
			(xy 439.97372 -19.309334) (xy 439.97499 -19.314922) (xy 439.979381 -19.33489) (xy 439.984095 -19.375505)
			(xy 439.984388 -19.395948) (xy 439.984089 -19.416391) (xy 439.979379 -19.457005) (xy 439.97499 -19.476974)
			(xy 439.97372 -19.482562) (xy 439.97372 -19.506438) (xy 448.687442 -19.506438) (xy 448.691513 -19.450816)
			(xy 448.703639 -19.396379) (xy 448.723562 -19.344288) (xy 448.750858 -19.295653) (xy 448.784944 -19.25151)
			(xy 448.825093 -19.212801) (xy 448.870451 -19.18035) (xy 448.920051 -19.154849) (xy 448.972835 -19.136842)
			(xy 449.027678 -19.126712) (xy 449.083412 -19.124675) (xy 449.138849 -19.130775) (xy 449.192806 -19.144881)
			(xy 449.244135 -19.166693) (xy 449.291741 -19.195747) (xy 449.334609 -19.231422) (xy 449.371826 -19.272959)
			(xy 449.402599 -19.319472) (xy 449.411916 -19.339348) (xy 453.045106 -19.339348) (xy 453.045106 -19.284852)
			(xy 453.052861 -19.230911) (xy 453.068214 -19.178623) (xy 453.090851 -19.129052) (xy 453.120312 -19.083206)
			(xy 453.155997 -19.04202) (xy 453.197181 -19.006331) (xy 453.243024 -18.976866) (xy 453.292593 -18.954225)
			(xy 453.34488 -18.938868) (xy 453.39882 -18.931108) (xy 453.426068 -18.93062) (xy 453.452759 -18.931048)
			(xy 453.505623 -18.938468) (xy 453.556937 -18.953181) (xy 453.6057 -18.9749) (xy 453.650961 -19.003203)
			(xy 453.671686 -19.020028) (xy 453.683668 -19.029415) (xy 453.711676 -19.041295) (xy 453.741941 -19.044396)
			(xy 453.771777 -19.038442) (xy 453.798534 -19.023963) (xy 453.819837 -19.002243) (xy 453.833796 -18.97521)
			(xy 453.83704 -18.960338) (xy 453.84216 -18.934245) (xy 453.858715 -18.883713) (xy 453.882129 -18.83597)
			(xy 453.911946 -18.791942) (xy 453.94759 -18.752482) (xy 453.988368 -18.718356) (xy 454.033492 -18.690223)
			(xy 454.082085 -18.668631) (xy 454.133206 -18.653996) (xy 454.185865 -18.646604) (xy 454.212452 -18.64614)
			(xy 454.239706 -18.6466) (xy 454.293659 -18.654352) (xy 454.34596 -18.669704) (xy 454.395543 -18.692345)
			(xy 454.441399 -18.721812) (xy 454.482594 -18.757506) (xy 454.518288 -18.798701) (xy 454.547755 -18.844557)
			(xy 454.570396 -18.89414) (xy 454.585748 -18.946441) (xy 454.5935 -19.000394) (xy 454.59396 -19.027648)
			(xy 454.593489 -19.054251) (xy 454.586114 -19.106944) (xy 454.571485 -19.1581) (xy 454.549886 -19.206726)
			(xy 454.521737 -19.251877) (xy 454.487586 -19.292676) (xy 454.448093 -19.328331) (xy 454.42632 -19.343624)
			(xy 454.41484 -19.35196) (xy 454.396633 -19.373702) (xy 454.385114 -19.399615) (xy 454.381172 -19.427699)
			(xy 454.385113 -19.455782) (xy 454.396632 -19.481696) (xy 454.414838 -19.503439) (xy 454.42632 -19.511772)
			(xy 454.448077 -19.527085) (xy 454.487558 -19.562747) (xy 454.521704 -19.603547) (xy 454.549852 -19.648694)
			(xy 454.571456 -19.697312) (xy 454.586099 -19.748461) (xy 454.593495 -19.801147) (xy 454.59396 -19.827748)
			(xy 454.593474 -19.854999) (xy 454.585718 -19.908947) (xy 454.570363 -19.961242) (xy 454.547721 -20.010819)
			(xy 454.518255 -20.056669) (xy 454.482564 -20.09786) (xy 454.441373 -20.133551) (xy 454.395523 -20.163017)
			(xy 454.345946 -20.185659) (xy 454.293651 -20.201014) (xy 454.239703 -20.20877) (xy 454.185201 -20.20877)
			(xy 454.131253 -20.201014) (xy 454.078958 -20.185659) (xy 454.029381 -20.163017) (xy 453.983531 -20.133551)
			(xy 453.94234 -20.09786) (xy 453.906649 -20.056669) (xy 453.877183 -20.010819) (xy 453.854541 -19.961242)
			(xy 453.839186 -19.908947) (xy 453.83143 -19.854999) (xy 453.830944 -19.827748) (xy 453.83141 -19.801144)
			(xy 453.838786 -19.748451) (xy 453.853416 -19.697295) (xy 453.875015 -19.64867) (xy 453.903165 -19.603519)
			(xy 453.937317 -19.56272) (xy 453.97681 -19.527064) (xy 453.998584 -19.511772) (xy 454.010068 -19.503441)
			(xy 454.028274 -19.481698) (xy 454.039793 -19.455783) (xy 454.043733 -19.427699) (xy 454.039792 -19.399615)
			(xy 454.028273 -19.3737) (xy 454.010066 -19.351958) (xy 453.998584 -19.343624) (xy 453.99038 -19.338018)
			(xy 453.974496 -19.326074) (xy 453.966834 -19.319748) (xy 453.954892 -19.310292) (xy 453.926864 -19.298389)
			(xy 453.896573 -19.295278) (xy 453.866711 -19.301235) (xy 453.839932 -19.31573) (xy 453.818617 -19.337476)
			(xy 453.80466 -19.36454) (xy 453.80148 -19.379438) (xy 453.796323 -19.405524) (xy 453.779772 -19.456054)
			(xy 453.756363 -19.503796) (xy 453.72655 -19.547823) (xy 453.690911 -19.587284) (xy 453.650136 -19.621411)
			(xy 453.605017 -19.649545) (xy 453.556427 -19.671139) (xy 453.505309 -19.685776) (xy 453.452654 -19.69317)
			(xy 453.426068 -19.693636) (xy 453.39882 -19.693092) (xy 453.34488 -19.685332) (xy 453.292593 -19.669975)
			(xy 453.243024 -19.647334) (xy 453.197181 -19.617869) (xy 453.155997 -19.58218) (xy 453.120312 -19.540994)
			(xy 453.090851 -19.495148) (xy 453.068214 -19.445577) (xy 453.052861 -19.393289) (xy 453.045106 -19.339348)
			(xy 449.411916 -19.339348) (xy 449.426271 -19.369969) (xy 449.442339 -19.423376) (xy 449.450459 -19.478552)
			(xy 449.450968 -19.506438) (xy 449.450459 -19.534324) (xy 449.442339 -19.5895) (xy 449.426271 -19.642907)
			(xy 449.402599 -19.693404) (xy 449.371826 -19.739917) (xy 449.334609 -19.781454) (xy 449.291741 -19.817129)
			(xy 449.244135 -19.846183) (xy 449.192806 -19.867995) (xy 449.138849 -19.882101) (xy 449.083412 -19.888201)
			(xy 449.027678 -19.886164) (xy 448.972835 -19.876034) (xy 448.920051 -19.858027) (xy 448.870451 -19.832526)
			(xy 448.825093 -19.800075) (xy 448.784944 -19.761366) (xy 448.750858 -19.717223) (xy 448.723562 -19.668588)
			(xy 448.703639 -19.616497) (xy 448.691513 -19.56206) (xy 448.687442 -19.506438) (xy 439.97372 -19.506438)
			(xy 439.97372 -20.91182) (xy 441.796424 -20.91182) (xy 441.796896 -20.88445) (xy 441.804711 -20.830271)
			(xy 441.820199 -20.777768) (xy 441.843039 -20.728021) (xy 441.872763 -20.682054) (xy 441.890404 -20.661122)
			(xy 441.899621 -20.64978) (xy 441.911801 -20.623228) (xy 441.915977 -20.594315) (xy 441.911809 -20.565401)
			(xy 441.899638 -20.538845) (xy 441.890404 -20.527518) (xy 441.872761 -20.506589) (xy 441.843049 -20.460616)
			(xy 441.820214 -20.410867) (xy 441.804724 -20.358366) (xy 441.796897 -20.304189) (xy 441.796424 -20.27682)
			(xy 441.79691 -20.249569) (xy 441.804666 -20.195621) (xy 441.820021 -20.143326) (xy 441.842663 -20.093749)
			(xy 441.872129 -20.047899) (xy 441.90782 -20.006708) (xy 441.949011 -19.971017) (xy 441.994861 -19.941551)
			(xy 442.044438 -19.918909) (xy 442.096733 -19.903554) (xy 442.150681 -19.895798) (xy 442.205183 -19.895798)
			(xy 442.259131 -19.903554) (xy 442.311426 -19.918909) (xy 442.361003 -19.941551) (xy 442.406853 -19.971017)
			(xy 442.448044 -20.006708) (xy 442.483735 -20.047899) (xy 442.513201 -20.093749) (xy 442.535843 -20.143326)
			(xy 442.551198 -20.195621) (xy 442.558954 -20.249569) (xy 442.55944 -20.27682) (xy 442.559 -20.304191)
			(xy 442.551178 -20.358372) (xy 442.535684 -20.410876) (xy 442.512836 -20.460623) (xy 442.483105 -20.506588)
			(xy 442.46546 -20.527518) (xy 442.456207 -20.538832) (xy 442.444037 -20.565395) (xy 442.43987 -20.594315)
			(xy 442.444046 -20.623234) (xy 442.456224 -20.649793) (xy 442.46546 -20.661122) (xy 442.48307 -20.682078)
			(xy 442.512787 -20.728043) (xy 442.53563 -20.777785) (xy 442.551127 -20.830281) (xy 442.558963 -20.884452)
			(xy 442.55944 -20.91182) (xy 442.558954 -20.939071) (xy 442.551198 -20.993019) (xy 442.535843 -21.045314)
			(xy 442.513201 -21.094891) (xy 442.483735 -21.140741) (xy 442.448044 -21.181932) (xy 442.406853 -21.217623)
			(xy 442.377981 -21.236178) (xy 448.479162 -21.236178) (xy 448.483233 -21.180556) (xy 448.495359 -21.126119)
			(xy 448.515282 -21.074028) (xy 448.542578 -21.025393) (xy 448.576664 -20.98125) (xy 448.616813 -20.942541)
			(xy 448.662171 -20.91009) (xy 448.711771 -20.884589) (xy 448.764555 -20.866582) (xy 448.819398 -20.856452)
			(xy 448.875132 -20.854415) (xy 448.930569 -20.860515) (xy 448.984526 -20.874621) (xy 449.035855 -20.896433)
			(xy 449.083461 -20.925487) (xy 449.126329 -20.961162) (xy 449.163546 -21.002699) (xy 449.194319 -21.049212)
			(xy 449.217991 -21.099709) (xy 449.234059 -21.153116) (xy 449.242179 -21.208292) (xy 449.242688 -21.236178)
			(xy 449.242179 -21.264064) (xy 449.234059 -21.31924) (xy 449.217991 -21.372647) (xy 449.194319 -21.423144)
			(xy 449.163546 -21.469657) (xy 449.126329 -21.511194) (xy 449.083461 -21.546869) (xy 449.035855 -21.575923)
			(xy 448.984526 -21.597735) (xy 448.930569 -21.611841) (xy 448.875132 -21.617941) (xy 448.819398 -21.615904)
			(xy 448.764555 -21.605774) (xy 448.711771 -21.587767) (xy 448.662171 -21.562266) (xy 448.616813 -21.529815)
			(xy 448.576664 -21.491106) (xy 448.542578 -21.446963) (xy 448.515282 -21.398328) (xy 448.495359 -21.346237)
			(xy 448.483233 -21.2918) (xy 448.479162 -21.236178) (xy 442.377981 -21.236178) (xy 442.361003 -21.247089)
			(xy 442.311426 -21.269731) (xy 442.259131 -21.285086) (xy 442.205183 -21.292842) (xy 442.150681 -21.292842)
			(xy 442.096733 -21.285086) (xy 442.044438 -21.269731) (xy 441.994861 -21.247089) (xy 441.949011 -21.217623)
			(xy 441.90782 -21.181932) (xy 441.872129 -21.140741) (xy 441.842663 -21.094891) (xy 441.820021 -21.045314)
			(xy 441.804666 -20.993019) (xy 441.79691 -20.939071) (xy 441.796424 -20.91182) (xy 439.97372 -20.91182)
			(xy 439.97372 -21.623528) (xy 453.717152 -21.623528) (xy 453.717637 -21.595899) (xy 453.725599 -21.541219)
			(xy 453.741363 -21.488258) (xy 453.764597 -21.438123) (xy 453.794816 -21.391861) (xy 453.83139 -21.35044)
			(xy 453.873553 -21.314725) (xy 453.89673 -21.299678) (xy 453.908805 -21.291585) (xy 453.928135 -21.269892)
			(xy 453.940583 -21.243638) (xy 453.945145 -21.214942) (xy 453.941451 -21.186121) (xy 453.9298 -21.159504)
			(xy 453.92086 -21.14804) (xy 453.90395 -21.127324) (xy 453.875493 -21.082051) (xy 453.85365 -21.033242)
			(xy 453.838851 -20.981856) (xy 453.831387 -20.928905) (xy 453.830944 -20.902168) (xy 453.83143 -20.874917)
			(xy 453.839186 -20.820969) (xy 453.854541 -20.768674) (xy 453.877183 -20.719097) (xy 453.906649 -20.673247)
			(xy 453.94234 -20.632056) (xy 453.983531 -20.596365) (xy 454.029381 -20.566899) (xy 454.078958 -20.544257)
			(xy 454.131253 -20.528902) (xy 454.185201 -20.521146) (xy 454.239703 -20.521146) (xy 454.293651 -20.528902)
			(xy 454.345946 -20.544257) (xy 454.395523 -20.566899) (xy 454.441373 -20.596365) (xy 454.482564 -20.632056)
			(xy 454.518255 -20.673247) (xy 454.547721 -20.719097) (xy 454.570363 -20.768674) (xy 454.585718 -20.820969)
			(xy 454.593474 -20.874917) (xy 454.59396 -20.902168) (xy 454.593513 -20.929798) (xy 454.585549 -20.984482)
			(xy 454.569782 -21.037446) (xy 454.546543 -21.087583) (xy 454.516317 -21.133844) (xy 454.479735 -21.175263)
			(xy 454.437563 -21.210974) (xy 454.414382 -21.226018) (xy 454.402311 -21.234117) (xy 454.382979 -21.255808)
			(xy 454.370529 -21.282061) (xy 454.365967 -21.310756) (xy 454.369661 -21.339576) (xy 454.381312 -21.366193)
			(xy 454.390252 -21.377656) (xy 454.407162 -21.398372) (xy 454.435619 -21.443645) (xy 454.457462 -21.492455)
			(xy 454.472261 -21.54384) (xy 454.479725 -21.596791) (xy 454.480168 -21.623528) (xy 454.479682 -21.650779)
			(xy 454.471926 -21.704727) (xy 454.456571 -21.757022) (xy 454.433929 -21.806599) (xy 454.404463 -21.852449)
			(xy 454.368772 -21.89364) (xy 454.327581 -21.929331) (xy 454.281731 -21.958797) (xy 454.232154 -21.981439)
			(xy 454.179859 -21.996794) (xy 454.125911 -22.00455) (xy 454.071409 -22.00455) (xy 454.017461 -21.996794)
			(xy 453.965166 -21.981439) (xy 453.915589 -21.958797) (xy 453.869739 -21.929331) (xy 453.828548 -21.89364)
			(xy 453.792857 -21.852449) (xy 453.763391 -21.806599) (xy 453.740749 -21.757022) (xy 453.725394 -21.704727)
			(xy 453.717638 -21.650779) (xy 453.717152 -21.623528) (xy 439.97372 -21.623528) (xy 439.97372 -22.426422)
			(xy 450.115176 -22.426422) (xy 450.119247 -22.3708) (xy 450.131373 -22.316363) (xy 450.151296 -22.264272)
			(xy 450.178592 -22.215637) (xy 450.212678 -22.171494) (xy 450.252827 -22.132785) (xy 450.298185 -22.100334)
			(xy 450.347785 -22.074833) (xy 450.400569 -22.056826) (xy 450.455412 -22.046696) (xy 450.511146 -22.044659)
			(xy 450.566583 -22.050759) (xy 450.62054 -22.064865) (xy 450.671869 -22.086677) (xy 450.719475 -22.115731)
			(xy 450.762343 -22.151406) (xy 450.79956 -22.192943) (xy 450.830333 -22.239456) (xy 450.854005 -22.289953)
			(xy 450.870073 -22.34336) (xy 450.878193 -22.398536) (xy 450.878234 -22.400768) (xy 452.115172 -22.400768)
			(xy 452.119243 -22.345146) (xy 452.131369 -22.290709) (xy 452.151292 -22.238618) (xy 452.178588 -22.189983)
			(xy 452.212674 -22.14584) (xy 452.252823 -22.107131) (xy 452.298181 -22.07468) (xy 452.347781 -22.049179)
			(xy 452.400565 -22.031172) (xy 452.455408 -22.021042) (xy 452.511142 -22.019005) (xy 452.566579 -22.025105)
			(xy 452.620536 -22.039211) (xy 452.671865 -22.061023) (xy 452.719471 -22.090077) (xy 452.762339 -22.125752)
			(xy 452.799556 -22.167289) (xy 452.830329 -22.213802) (xy 452.854001 -22.264299) (xy 452.870069 -22.317706)
			(xy 452.878189 -22.372882) (xy 452.878698 -22.400768) (xy 452.878189 -22.428654) (xy 452.870069 -22.48383)
			(xy 452.854001 -22.537237) (xy 452.830329 -22.587734) (xy 452.799556 -22.634247) (xy 452.762339 -22.675784)
			(xy 452.719471 -22.711459) (xy 452.671865 -22.740513) (xy 452.620536 -22.762325) (xy 452.566579 -22.776431)
			(xy 452.511142 -22.782531) (xy 452.455408 -22.780494) (xy 452.400565 -22.770364) (xy 452.347781 -22.752357)
			(xy 452.298181 -22.726856) (xy 452.252823 -22.694405) (xy 452.212674 -22.655696) (xy 452.178588 -22.611553)
			(xy 452.151292 -22.562918) (xy 452.131369 -22.510827) (xy 452.119243 -22.45639) (xy 452.115172 -22.400768)
			(xy 450.878234 -22.400768) (xy 450.878702 -22.426422) (xy 450.878193 -22.454308) (xy 450.870073 -22.509484)
			(xy 450.854005 -22.562891) (xy 450.830333 -22.613388) (xy 450.79956 -22.659901) (xy 450.762343 -22.701438)
			(xy 450.719475 -22.737113) (xy 450.671869 -22.766167) (xy 450.62054 -22.787979) (xy 450.566583 -22.802085)
			(xy 450.511146 -22.808185) (xy 450.455412 -22.806148) (xy 450.400569 -22.796018) (xy 450.347785 -22.778011)
			(xy 450.298185 -22.75251) (xy 450.252827 -22.720059) (xy 450.212678 -22.68135) (xy 450.178592 -22.637207)
			(xy 450.151296 -22.588572) (xy 450.131373 -22.536481) (xy 450.119247 -22.482044) (xy 450.115176 -22.426422)
			(xy 439.97372 -22.426422) (xy 439.97372 -22.866858) (xy 446.779394 -22.866858) (xy 446.783465 -22.811236)
			(xy 446.795591 -22.756799) (xy 446.815514 -22.704708) (xy 446.84281 -22.656073) (xy 446.876896 -22.61193)
			(xy 446.917045 -22.573221) (xy 446.962403 -22.54077) (xy 447.012003 -22.515269) (xy 447.064787 -22.497262)
			(xy 447.11963 -22.487132) (xy 447.175364 -22.485095) (xy 447.230801 -22.491195) (xy 447.284758 -22.505301)
			(xy 447.336087 -22.527113) (xy 447.383693 -22.556167) (xy 447.426561 -22.591842) (xy 447.463778 -22.633379)
			(xy 447.494551 -22.679892) (xy 447.518223 -22.730389) (xy 447.534291 -22.783796) (xy 447.542411 -22.838972)
			(xy 447.54292 -22.866858) (xy 447.542411 -22.894744) (xy 447.534291 -22.94992) (xy 447.518223 -23.003327)
			(xy 447.510755 -23.019258) (xy 451.351394 -23.019258) (xy 451.355465 -22.963636) (xy 451.367591 -22.909199)
			(xy 451.387514 -22.857108) (xy 451.41481 -22.808473) (xy 451.448896 -22.76433) (xy 451.489045 -22.725621)
			(xy 451.534403 -22.69317) (xy 451.584003 -22.667669) (xy 451.636787 -22.649662) (xy 451.69163 -22.639532)
			(xy 451.747364 -22.637495) (xy 451.802801 -22.643595) (xy 451.856758 -22.657701) (xy 451.908087 -22.679513)
			(xy 451.955693 -22.708567) (xy 451.998561 -22.744242) (xy 452.035778 -22.785779) (xy 452.066551 -22.832292)
			(xy 452.090223 -22.882789) (xy 452.106291 -22.936196) (xy 452.114411 -22.991372) (xy 452.11492 -23.019258)
			(xy 452.114411 -23.047144) (xy 452.106291 -23.10232) (xy 452.090223 -23.155727) (xy 452.066551 -23.206224)
			(xy 452.035778 -23.252737) (xy 451.998561 -23.294274) (xy 451.955693 -23.329949) (xy 451.908087 -23.359003)
			(xy 451.856758 -23.380815) (xy 451.802801 -23.394921) (xy 451.747364 -23.401021) (xy 451.69163 -23.398984)
			(xy 451.636787 -23.388854) (xy 451.584003 -23.370847) (xy 451.534403 -23.345346) (xy 451.489045 -23.312895)
			(xy 451.448896 -23.274186) (xy 451.41481 -23.230043) (xy 451.387514 -23.181408) (xy 451.367591 -23.129317)
			(xy 451.355465 -23.07488) (xy 451.351394 -23.019258) (xy 447.510755 -23.019258) (xy 447.494551 -23.053824)
			(xy 447.463778 -23.100337) (xy 447.426561 -23.141874) (xy 447.383693 -23.177549) (xy 447.336087 -23.206603)
			(xy 447.284758 -23.228415) (xy 447.230801 -23.242521) (xy 447.175364 -23.248621) (xy 447.11963 -23.246584)
			(xy 447.064787 -23.236454) (xy 447.012003 -23.218447) (xy 446.962403 -23.192946) (xy 446.917045 -23.160495)
			(xy 446.876896 -23.121786) (xy 446.84281 -23.077643) (xy 446.815514 -23.029008) (xy 446.795591 -22.976917)
			(xy 446.783465 -22.92248) (xy 446.779394 -22.866858) (xy 439.97372 -22.866858) (xy 439.97372 -25.872948)
			(xy 440.745372 -25.872948) (xy 440.745911 -25.846179) (xy 440.753416 -25.793169) (xy 440.768258 -25.74173)
			(xy 440.790146 -25.69287) (xy 440.818649 -25.647549) (xy 440.853207 -25.606658) (xy 440.893142 -25.571)
			(xy 440.937671 -25.541275) (xy 440.985917 -25.518066) (xy 441.036934 -25.501829) (xy 441.08972 -25.492884)
			(xy 441.116466 -25.491694) (xy 441.130171 -25.490836) (xy 441.156404 -25.482755) (xy 441.179535 -25.467978)
			(xy 441.197895 -25.447573) (xy 441.210156 -25.423014) (xy 441.215431 -25.396077) (xy 441.21334 -25.368708)
			(xy 441.204034 -25.342885) (xy 441.196476 -25.33142) (xy 441.179919 -25.307123) (xy 441.153727 -25.254482)
			(xy 441.135917 -25.198448) (xy 441.12691 -25.140346) (xy 441.126372 -25.110948) (xy 441.126858 -25.083697)
			(xy 441.134614 -25.029749) (xy 441.149969 -24.977454) (xy 441.172611 -24.927877) (xy 441.202077 -24.882027)
			(xy 441.237768 -24.840836) (xy 441.278959 -24.805145) (xy 441.324809 -24.775679) (xy 441.374386 -24.753037)
			(xy 441.426681 -24.737682) (xy 441.480629 -24.729926) (xy 441.535131 -24.729926) (xy 441.589079 -24.737682)
			(xy 441.641374 -24.753037) (xy 441.690951 -24.775679) (xy 441.736801 -24.805145) (xy 441.777992 -24.840836)
			(xy 441.813683 -24.882027) (xy 441.843149 -24.927877) (xy 441.865791 -24.977454) (xy 441.881146 -25.029749)
			(xy 441.888902 -25.083697) (xy 441.889388 -25.110948) (xy 441.888884 -25.137719) (xy 441.881378 -25.190731)
			(xy 441.866535 -25.242174) (xy 441.844645 -25.291037) (xy 441.816139 -25.336359) (xy 441.781577 -25.377251)
			(xy 441.741637 -25.412909) (xy 441.697104 -25.442634) (xy 441.648854 -25.465841) (xy 441.597832 -25.482074)
			(xy 441.545042 -25.491014) (xy 441.518294 -25.492202) (xy 441.504588 -25.49304) (xy 441.478358 -25.501129)
			(xy 441.45523 -25.515911) (xy 441.436873 -25.536319) (xy 441.424614 -25.560878) (xy 441.419339 -25.587815)
			(xy 441.421427 -25.615185) (xy 441.430729 -25.64101) (xy 441.438284 -25.652476) (xy 441.454835 -25.676778)
			(xy 441.481029 -25.729416) (xy 441.498841 -25.785449) (xy 441.50785 -25.84355) (xy 441.508388 -25.872948)
			(xy 441.634372 -25.872948) (xy 441.634911 -25.846179) (xy 441.642416 -25.793169) (xy 441.657258 -25.74173)
			(xy 441.679146 -25.69287) (xy 441.707649 -25.647549) (xy 441.742207 -25.606658) (xy 441.782142 -25.571)
			(xy 441.826671 -25.541275) (xy 441.874917 -25.518066) (xy 441.925934 -25.501829) (xy 441.97872 -25.492884)
			(xy 442.005466 -25.491694) (xy 442.019171 -25.490836) (xy 442.045404 -25.482755) (xy 442.068535 -25.467978)
			(xy 442.086895 -25.447573) (xy 442.099156 -25.423014) (xy 442.104431 -25.396077) (xy 442.10234 -25.368708)
			(xy 442.093034 -25.342885) (xy 442.085476 -25.33142) (xy 442.068919 -25.307123) (xy 442.042727 -25.254482)
			(xy 442.024917 -25.198448) (xy 442.01591 -25.140346) (xy 442.015372 -25.110948) (xy 442.015858 -25.083697)
			(xy 442.023614 -25.029749) (xy 442.038969 -24.977454) (xy 442.061611 -24.927877) (xy 442.091077 -24.882027)
			(xy 442.126768 -24.840836) (xy 442.167959 -24.805145) (xy 442.213809 -24.775679) (xy 442.263386 -24.753037)
			(xy 442.315681 -24.737682) (xy 442.369629 -24.729926) (xy 442.424131 -24.729926) (xy 442.478079 -24.737682)
			(xy 442.530374 -24.753037) (xy 442.579951 -24.775679) (xy 442.625801 -24.805145) (xy 442.666992 -24.840836)
			(xy 442.702683 -24.882027) (xy 442.732149 -24.927877) (xy 442.754791 -24.977454) (xy 442.770146 -25.029749)
			(xy 442.777902 -25.083697) (xy 442.778388 -25.110948) (xy 442.777884 -25.137719) (xy 442.770378 -25.190731)
			(xy 442.755535 -25.242174) (xy 442.733645 -25.291037) (xy 442.705139 -25.336359) (xy 442.670577 -25.377251)
			(xy 442.630637 -25.412909) (xy 442.586104 -25.442634) (xy 442.537854 -25.465841) (xy 442.486832 -25.482074)
			(xy 442.434042 -25.491014) (xy 442.407294 -25.492202) (xy 442.393588 -25.49304) (xy 442.367358 -25.501129)
			(xy 442.34423 -25.515911) (xy 442.325873 -25.536319) (xy 442.313614 -25.560878) (xy 442.308339 -25.587815)
			(xy 442.310427 -25.615185) (xy 442.319729 -25.64101) (xy 442.327284 -25.652476) (xy 442.343835 -25.676778)
			(xy 442.370029 -25.729416) (xy 442.387841 -25.785449) (xy 442.39685 -25.84355) (xy 442.397388 -25.872948)
			(xy 442.523372 -25.872948) (xy 442.523911 -25.846179) (xy 442.531416 -25.793169) (xy 442.546258 -25.74173)
			(xy 442.568146 -25.69287) (xy 442.596649 -25.647549) (xy 442.631207 -25.606658) (xy 442.671142 -25.571)
			(xy 442.715671 -25.541275) (xy 442.763917 -25.518066) (xy 442.814934 -25.501829) (xy 442.86772 -25.492884)
			(xy 442.894466 -25.491694) (xy 442.908171 -25.490836) (xy 442.934404 -25.482755) (xy 442.957535 -25.467978)
			(xy 442.975895 -25.447573) (xy 442.988156 -25.423014) (xy 442.993431 -25.396077) (xy 442.99134 -25.368708)
			(xy 442.982034 -25.342885) (xy 442.974476 -25.33142) (xy 442.957919 -25.307123) (xy 442.931727 -25.254482)
			(xy 442.913917 -25.198448) (xy 442.90491 -25.140346) (xy 442.904372 -25.110948) (xy 442.904858 -25.083697)
			(xy 442.912614 -25.029749) (xy 442.927969 -24.977454) (xy 442.950611 -24.927877) (xy 442.980077 -24.882027)
			(xy 443.015768 -24.840836) (xy 443.056959 -24.805145) (xy 443.102809 -24.775679) (xy 443.152386 -24.753037)
			(xy 443.204681 -24.737682) (xy 443.258629 -24.729926) (xy 443.313131 -24.729926) (xy 443.313284 -24.729948)
			(xy 443.792862 -24.729948) (xy 443.796933 -24.674326) (xy 443.809059 -24.619889) (xy 443.828982 -24.567798)
			(xy 443.856278 -24.519163) (xy 443.890364 -24.47502) (xy 443.930513 -24.436311) (xy 443.975871 -24.40386)
			(xy 444.025471 -24.378359) (xy 444.078255 -24.360352) (xy 444.133098 -24.350222) (xy 444.188832 -24.348185)
			(xy 444.244269 -24.354285) (xy 444.298226 -24.368391) (xy 444.349555 -24.390203) (xy 444.397161 -24.419257)
			(xy 444.440029 -24.454932) (xy 444.477246 -24.496469) (xy 444.508019 -24.542982) (xy 444.531691 -24.593479)
			(xy 444.547759 -24.646886) (xy 444.555879 -24.702062) (xy 444.556388 -24.729948) (xy 444.555879 -24.757834)
			(xy 444.547759 -24.81301) (xy 444.531691 -24.866417) (xy 444.52839 -24.873458) (xy 451.376794 -24.873458)
			(xy 451.380865 -24.817836) (xy 451.392991 -24.763399) (xy 451.412914 -24.711308) (xy 451.44021 -24.662673)
			(xy 451.474296 -24.61853) (xy 451.514445 -24.579821) (xy 451.559803 -24.54737) (xy 451.609403 -24.521869)
			(xy 451.662187 -24.503862) (xy 451.71703 -24.493732) (xy 451.772764 -24.491695) (xy 451.828201 -24.497795)
			(xy 451.882158 -24.511901) (xy 451.933487 -24.533713) (xy 451.981093 -24.562767) (xy 452.023961 -24.598442)
			(xy 452.061178 -24.639979) (xy 452.091951 -24.686492) (xy 452.115623 -24.736989) (xy 452.131691 -24.790396)
			(xy 452.139811 -24.845572) (xy 452.14032 -24.873458) (xy 452.139811 -24.901344) (xy 452.131691 -24.95652)
			(xy 452.115623 -25.009927) (xy 452.091951 -25.060424) (xy 452.061178 -25.106937) (xy 452.023961 -25.148474)
			(xy 451.981093 -25.184149) (xy 451.933487 -25.213203) (xy 451.882158 -25.235015) (xy 451.828201 -25.249121)
			(xy 451.772764 -25.255221) (xy 451.71703 -25.253184) (xy 451.662187 -25.243054) (xy 451.609403 -25.225047)
			(xy 451.559803 -25.199546) (xy 451.514445 -25.167095) (xy 451.474296 -25.128386) (xy 451.44021 -25.084243)
			(xy 451.412914 -25.035608) (xy 451.392991 -24.983517) (xy 451.380865 -24.92908) (xy 451.376794 -24.873458)
			(xy 444.52839 -24.873458) (xy 444.508019 -24.916914) (xy 444.477246 -24.963427) (xy 444.440029 -25.004964)
			(xy 444.397161 -25.040639) (xy 444.349555 -25.069693) (xy 444.298226 -25.091505) (xy 444.244269 -25.105611)
			(xy 444.188832 -25.111711) (xy 444.133098 -25.109674) (xy 444.078255 -25.099544) (xy 444.025471 -25.081537)
			(xy 443.975871 -25.056036) (xy 443.930513 -25.023585) (xy 443.890364 -24.984876) (xy 443.856278 -24.940733)
			(xy 443.828982 -24.892098) (xy 443.809059 -24.840007) (xy 443.796933 -24.78557) (xy 443.792862 -24.729948)
			(xy 443.313284 -24.729948) (xy 443.367079 -24.737682) (xy 443.419374 -24.753037) (xy 443.468951 -24.775679)
			(xy 443.514801 -24.805145) (xy 443.555992 -24.840836) (xy 443.591683 -24.882027) (xy 443.621149 -24.927877)
			(xy 443.643791 -24.977454) (xy 443.659146 -25.029749) (xy 443.666902 -25.083697) (xy 443.667388 -25.110948)
			(xy 443.666884 -25.137719) (xy 443.659378 -25.190731) (xy 443.644535 -25.242174) (xy 443.622645 -25.291037)
			(xy 443.594139 -25.336359) (xy 443.559577 -25.377251) (xy 443.519637 -25.412909) (xy 443.475104 -25.442634)
			(xy 443.426854 -25.465841) (xy 443.375832 -25.482074) (xy 443.323042 -25.491014) (xy 443.296294 -25.492202)
			(xy 443.282588 -25.49304) (xy 443.256358 -25.501129) (xy 443.23323 -25.515911) (xy 443.214873 -25.536319)
			(xy 443.202614 -25.560878) (xy 443.197339 -25.587815) (xy 443.199427 -25.615185) (xy 443.208729 -25.64101)
			(xy 443.216284 -25.652476) (xy 443.232835 -25.676778) (xy 443.259029 -25.729416) (xy 443.276841 -25.785449)
			(xy 443.28585 -25.84355) (xy 443.286388 -25.872948) (xy 443.285902 -25.900199) (xy 443.278146 -25.954147)
			(xy 443.262791 -26.006442) (xy 443.240149 -26.056019) (xy 443.210683 -26.101869) (xy 443.174992 -26.14306)
			(xy 443.133801 -26.178751) (xy 443.087951 -26.208217) (xy 443.038374 -26.230859) (xy 442.986079 -26.246214)
			(xy 442.932131 -26.25397) (xy 442.877629 -26.25397) (xy 442.823681 -26.246214) (xy 442.771386 -26.230859)
			(xy 442.721809 -26.208217) (xy 442.675959 -26.178751) (xy 442.634768 -26.14306) (xy 442.599077 -26.101869)
			(xy 442.569611 -26.056019) (xy 442.546969 -26.006442) (xy 442.531614 -25.954147) (xy 442.523858 -25.900199)
			(xy 442.523372 -25.872948) (xy 442.397388 -25.872948) (xy 442.396902 -25.900199) (xy 442.389146 -25.954147)
			(xy 442.373791 -26.006442) (xy 442.351149 -26.056019) (xy 442.321683 -26.101869) (xy 442.285992 -26.14306)
			(xy 442.244801 -26.178751) (xy 442.198951 -26.208217) (xy 442.149374 -26.230859) (xy 442.097079 -26.246214)
			(xy 442.043131 -26.25397) (xy 441.988629 -26.25397) (xy 441.934681 -26.246214) (xy 441.882386 -26.230859)
			(xy 441.832809 -26.208217) (xy 441.786959 -26.178751) (xy 441.745768 -26.14306) (xy 441.710077 -26.101869)
			(xy 441.680611 -26.056019) (xy 441.657969 -26.006442) (xy 441.642614 -25.954147) (xy 441.634858 -25.900199)
			(xy 441.634372 -25.872948) (xy 441.508388 -25.872948) (xy 441.507902 -25.900199) (xy 441.500146 -25.954147)
			(xy 441.484791 -26.006442) (xy 441.462149 -26.056019) (xy 441.432683 -26.101869) (xy 441.396992 -26.14306)
			(xy 441.355801 -26.178751) (xy 441.309951 -26.208217) (xy 441.260374 -26.230859) (xy 441.208079 -26.246214)
			(xy 441.154131 -26.25397) (xy 441.099629 -26.25397) (xy 441.045681 -26.246214) (xy 440.993386 -26.230859)
			(xy 440.943809 -26.208217) (xy 440.897959 -26.178751) (xy 440.856768 -26.14306) (xy 440.821077 -26.101869)
			(xy 440.791611 -26.056019) (xy 440.768969 -26.006442) (xy 440.753614 -25.954147) (xy 440.745858 -25.900199)
			(xy 440.745372 -25.872948) (xy 439.97372 -25.872948) (xy 439.97372 -26.983556) (xy 446.780313 -26.983556)
			(xy 446.780313 -26.929044) (xy 446.788071 -26.875086) (xy 446.803429 -26.822781) (xy 446.826075 -26.773195)
			(xy 446.855548 -26.727336) (xy 446.891247 -26.686138) (xy 446.932445 -26.650441) (xy 446.978305 -26.62097)
			(xy 447.027892 -26.598325) (xy 447.080197 -26.582969) (xy 447.134156 -26.575212) (xy 447.161412 -26.57475)
			(xy 447.18867 -26.575219) (xy 447.24263 -26.582987) (xy 447.294937 -26.598351) (xy 447.344526 -26.620998)
			(xy 447.390392 -26.650466) (xy 447.4316 -26.686158) (xy 447.467313 -26.727348) (xy 447.482468 -26.75001)
			(xy 447.490749 -26.761937) (xy 447.512685 -26.780941) (xy 447.539085 -26.792996) (xy 447.567812 -26.797126)
			(xy 447.596539 -26.792996) (xy 447.622939 -26.780941) (xy 447.644875 -26.761937) (xy 447.653156 -26.75001)
			(xy 447.668315 -26.727351) (xy 447.704021 -26.686155) (xy 447.745226 -26.650459) (xy 447.791091 -26.620989)
			(xy 447.840683 -26.598347) (xy 447.892992 -26.582991) (xy 447.946954 -26.575235) (xy 447.974212 -26.57475)
			(xy 448.00146 -26.575321) (xy 448.0554 -26.583078) (xy 448.107688 -26.598432) (xy 448.157258 -26.621072)
			(xy 448.203102 -26.650535) (xy 448.244286 -26.686223) (xy 448.279972 -26.727408) (xy 448.309434 -26.773253)
			(xy 448.332072 -26.822824) (xy 448.347425 -26.875112) (xy 448.35518 -26.929052) (xy 448.35518 -26.983548)
			(xy 448.347425 -27.037488) (xy 448.332072 -27.089776) (xy 448.309434 -27.139347) (xy 448.279972 -27.185192)
			(xy 448.244286 -27.226377) (xy 448.203102 -27.262065) (xy 448.157258 -27.291528) (xy 448.107688 -27.314168)
			(xy 448.0554 -27.329522) (xy 448.00146 -27.337279) (xy 447.974212 -27.337766) (xy 447.946955 -27.337272)
			(xy 447.892997 -27.329506) (xy 447.840691 -27.314147) (xy 447.791101 -27.291504) (xy 447.745236 -27.26204)
			(xy 447.704027 -27.226352) (xy 447.668312 -27.185166) (xy 447.653156 -27.162506) (xy 447.644875 -27.150579)
			(xy 447.622939 -27.131575) (xy 447.596539 -27.11952) (xy 447.567812 -27.11539) (xy 447.539085 -27.11952)
			(xy 447.512685 -27.131575) (xy 447.490749 -27.150579) (xy 447.482468 -27.162506) (xy 447.467298 -27.185158)
			(xy 447.431593 -27.226353) (xy 447.39039 -27.262049) (xy 447.344527 -27.291519) (xy 447.294937 -27.314163)
			(xy 447.24263 -27.329521) (xy 447.18867 -27.337279) (xy 447.161412 -27.337766) (xy 447.134156 -27.337388)
			(xy 447.080197 -27.329631) (xy 447.027892 -27.314275) (xy 446.978305 -27.29163) (xy 446.932445 -27.262159)
			(xy 446.891247 -27.226462) (xy 446.855548 -27.185264) (xy 446.826075 -27.139405) (xy 446.803429 -27.089819)
			(xy 446.788071 -27.037514) (xy 446.780313 -26.983556) (xy 439.97372 -26.983556) (xy 439.97372 -28.492958)
			(xy 440.846972 -28.492958) (xy 440.847475 -28.465637) (xy 440.855819 -28.411635) (xy 440.872304 -28.359538)
			(xy 440.896546 -28.310567) (xy 440.927975 -28.265868) (xy 440.94654 -28.245816) (xy 440.956979 -28.234228)
			(xy 440.970801 -28.206283) (xy 440.975549 -28.17547) (xy 440.970782 -28.144659) (xy 440.956944 -28.116722)
			(xy 440.94654 -28.1051) (xy 440.927942 -28.085073) (xy 440.896482 -28.040385) (xy 440.872229 -27.991409)
			(xy 440.855754 -27.9393) (xy 440.847445 -27.885284) (xy 440.846972 -27.857958) (xy 440.84747 -27.831309)
			(xy 440.855413 -27.778605) (xy 440.871123 -27.727675) (xy 440.894249 -27.679654) (xy 440.924273 -27.635617)
			(xy 440.960525 -27.596546) (xy 441.002196 -27.563315) (xy 441.048354 -27.536666) (xy 441.097968 -27.517194)
			(xy 441.14993 -27.505334) (xy 441.20308 -27.501351) (xy 441.25623 -27.505334) (xy 441.308192 -27.517194)
			(xy 441.357806 -27.536666) (xy 441.403964 -27.563315) (xy 441.445635 -27.596546) (xy 441.481887 -27.635617)
			(xy 441.511911 -27.679654) (xy 441.535037 -27.727675) (xy 441.550747 -27.778605) (xy 441.55869 -27.831309)
			(xy 441.559188 -27.857958) (xy 441.558644 -27.885278) (xy 441.550312 -27.939278) (xy 441.533837 -27.991375)
			(xy 441.509604 -28.040347) (xy 441.478182 -28.085047) (xy 441.45962 -28.1051) (xy 441.449267 -28.116757)
			(xy 441.435442 -28.144679) (xy 441.43068 -28.17547) (xy 441.435424 -28.206263) (xy 441.449232 -28.234193)
			(xy 441.45962 -28.245816) (xy 441.478236 -28.265827) (xy 441.509691 -28.310521) (xy 441.533939 -28.3595)
			(xy 441.55041 -28.411612) (xy 441.558716 -28.465631) (xy 441.559188 -28.492958) (xy 441.746894 -28.492958)
			(xy 441.747391 -28.465636) (xy 441.755735 -28.411634) (xy 441.772222 -28.359537) (xy 441.796465 -28.310566)
			(xy 441.827896 -28.265868) (xy 441.846462 -28.245816) (xy 441.856899 -28.234227) (xy 441.870718 -28.206282)
			(xy 441.875465 -28.17547) (xy 441.8707 -28.14466) (xy 441.856864 -28.116723) (xy 441.846462 -28.1051)
			(xy 441.827868 -28.08507) (xy 441.796407 -28.040383) (xy 441.772153 -27.991408) (xy 441.755677 -27.9393)
			(xy 441.747368 -27.885284) (xy 441.746894 -27.857958) (xy 441.747392 -27.831309) (xy 441.755335 -27.778605)
			(xy 441.771045 -27.727675) (xy 441.794171 -27.679654) (xy 441.824195 -27.635617) (xy 441.860447 -27.596546)
			(xy 441.902118 -27.563315) (xy 441.948276 -27.536666) (xy 441.99789 -27.517194) (xy 442.049852 -27.505334)
			(xy 442.103002 -27.501351) (xy 442.156152 -27.505334) (xy 442.208114 -27.517194) (xy 442.257728 -27.536666)
			(xy 442.303886 -27.563315) (xy 442.345557 -27.596546) (xy 442.381809 -27.635617) (xy 442.411833 -27.679654)
			(xy 442.434959 -27.727675) (xy 442.450669 -27.778605) (xy 442.458612 -27.831309) (xy 442.45911 -27.857958)
			(xy 442.45856 -27.885278) (xy 442.450229 -27.939278) (xy 442.433754 -27.991374) (xy 442.409523 -28.040346)
			(xy 442.378102 -28.085047) (xy 442.359542 -28.1051) (xy 442.349187 -28.116756) (xy 442.335359 -28.144678)
			(xy 442.330596 -28.17547) (xy 442.335341 -28.206264) (xy 442.349152 -28.234194) (xy 442.359542 -28.245816)
			(xy 442.378144 -28.265839) (xy 442.409604 -28.310528) (xy 442.433857 -28.359504) (xy 442.450331 -28.411614)
			(xy 442.458638 -28.465631) (xy 442.45911 -28.492958) (xy 442.646816 -28.492958) (xy 442.647307 -28.465636)
			(xy 442.655652 -28.411633) (xy 442.672139 -28.359536) (xy 442.696384 -28.310565) (xy 442.727817 -28.265867)
			(xy 442.746384 -28.245816) (xy 442.756819 -28.234226) (xy 442.770635 -28.206281) (xy 442.775381 -28.17547)
			(xy 442.770617 -28.144661) (xy 442.756784 -28.116724) (xy 442.746384 -28.1051) (xy 442.727777 -28.085082)
			(xy 442.69632 -28.04039) (xy 442.67207 -27.991412) (xy 442.655597 -27.939302) (xy 442.647289 -27.885285)
			(xy 442.646816 -27.857958) (xy 442.647314 -27.831309) (xy 442.655257 -27.778605) (xy 442.670967 -27.727675)
			(xy 442.694093 -27.679654) (xy 442.724117 -27.635617) (xy 442.760369 -27.596546) (xy 442.80204 -27.563315)
			(xy 442.848198 -27.536666) (xy 442.897812 -27.517194) (xy 442.949774 -27.505334) (xy 443.002924 -27.501351)
			(xy 443.056074 -27.505334) (xy 443.108036 -27.517194) (xy 443.15765 -27.536666) (xy 443.203808 -27.563315)
			(xy 443.245479 -27.596546) (xy 443.281731 -27.635617) (xy 443.311755 -27.679654) (xy 443.334881 -27.727675)
			(xy 443.350591 -27.778605) (xy 443.358534 -27.831309) (xy 443.359032 -27.857958) (xy 443.358476 -27.885277)
			(xy 443.350145 -27.939277) (xy 443.333672 -27.991373) (xy 443.309442 -28.040345) (xy 443.278023 -28.085046)
			(xy 443.259464 -28.1051) (xy 443.249107 -28.116755) (xy 443.235276 -28.144677) (xy 443.230512 -28.17547)
			(xy 443.235258 -28.206265) (xy 443.249072 -28.234195) (xy 443.259464 -28.245816) (xy 443.27807 -28.265836)
			(xy 443.309529 -28.310526) (xy 443.33378 -28.359503) (xy 443.350253 -28.411614) (xy 443.35856 -28.465631)
			(xy 443.359032 -28.492958) (xy 443.546992 -28.492958) (xy 443.547489 -28.465636) (xy 443.555834 -28.411634)
			(xy 443.57232 -28.359537) (xy 443.596563 -28.310566) (xy 443.627995 -28.265868) (xy 443.64656 -28.245816)
			(xy 443.656998 -28.234228) (xy 443.670816 -28.206282) (xy 443.675564 -28.17547) (xy 443.670798 -28.14466)
			(xy 443.656963 -28.116723) (xy 443.64656 -28.1051) (xy 443.627966 -28.08507) (xy 443.596504 -28.040383)
			(xy 443.57225 -27.991408) (xy 443.555775 -27.9393) (xy 443.547466 -27.885284) (xy 443.546992 -27.857958)
			(xy 443.54749 -27.831309) (xy 443.555433 -27.778605) (xy 443.571143 -27.727675) (xy 443.594269 -27.679654)
			(xy 443.624293 -27.635617) (xy 443.660545 -27.596546) (xy 443.702216 -27.563315) (xy 443.748374 -27.536666)
			(xy 443.797988 -27.517194) (xy 443.84995 -27.505334) (xy 443.9031 -27.501351) (xy 443.95625 -27.505334)
			(xy 444.008212 -27.517194) (xy 444.057826 -27.536666) (xy 444.103984 -27.563315) (xy 444.145655 -27.596546)
			(xy 444.181907 -27.635617) (xy 444.211931 -27.679654) (xy 444.235057 -27.727675) (xy 444.250767 -27.778605)
			(xy 444.25871 -27.831309) (xy 444.259208 -27.857958) (xy 444.258659 -27.885278) (xy 444.250327 -27.939278)
			(xy 444.233853 -27.991374) (xy 444.209621 -28.040346) (xy 444.178201 -28.085047) (xy 444.15964 -28.1051)
			(xy 444.149285 -28.116756) (xy 444.135458 -28.144678) (xy 444.130695 -28.17547) (xy 444.134607 -28.200858)
			(xy 445.636904 -28.200858) (xy 445.637401 -28.172118) (xy 445.64603 -28.11529) (xy 445.663086 -28.060398)
			(xy 445.688184 -28.008687) (xy 445.720755 -27.961326) (xy 445.740028 -27.94) (xy 445.750145 -27.928501)
			(xy 445.763488 -27.900943) (xy 445.768067 -27.870669) (xy 445.76347 -27.840398) (xy 445.75011 -27.812849)
			(xy 445.740028 -27.801316) (xy 445.720736 -27.780008) (xy 445.688173 -27.73264) (xy 445.663085 -27.680924)
			(xy 445.646039 -27.626029) (xy 445.637422 -27.569198) (xy 445.636904 -27.540458) (xy 445.63739 -27.513207)
			(xy 445.645146 -27.459259) (xy 445.660501 -27.406964) (xy 445.683143 -27.357387) (xy 445.712609 -27.311537)
			(xy 445.7483 -27.270346) (xy 445.789491 -27.234655) (xy 445.835341 -27.205189) (xy 445.884918 -27.182547)
			(xy 445.937213 -27.167192) (xy 445.991161 -27.159436) (xy 446.045663 -27.159436) (xy 446.099611 -27.167192)
			(xy 446.151906 -27.182547) (xy 446.201483 -27.205189) (xy 446.247333 -27.234655) (xy 446.288524 -27.270346)
			(xy 446.324215 -27.311537) (xy 446.353681 -27.357387) (xy 446.376323 -27.406964) (xy 446.391678 -27.459259)
			(xy 446.399434 -27.513207) (xy 446.39992 -27.540458) (xy 446.399426 -27.569198) (xy 446.390795 -27.626026)
			(xy 446.373738 -27.680917) (xy 446.34864 -27.732628) (xy 446.316069 -27.77999) (xy 446.296796 -27.801316)
			(xy 446.286768 -27.812884) (xy 446.273426 -27.840419) (xy 446.268835 -27.870669) (xy 446.273408 -27.900922)
			(xy 446.286733 -27.928465) (xy 446.296796 -27.94) (xy 446.316083 -27.961313) (xy 446.348649 -28.008678)
			(xy 446.37374 -28.060393) (xy 446.390786 -28.115287) (xy 446.399403 -28.172118) (xy 446.39992 -28.200858)
			(xy 446.399434 -28.228109) (xy 446.391678 -28.282057) (xy 446.376323 -28.334352) (xy 446.353681 -28.383929)
			(xy 446.324215 -28.429779) (xy 446.288524 -28.47097) (xy 446.247333 -28.506661) (xy 446.201483 -28.536127)
			(xy 446.151906 -28.558769) (xy 446.099611 -28.574124) (xy 446.045663 -28.58188) (xy 445.991161 -28.58188)
			(xy 445.937213 -28.574124) (xy 445.884918 -28.558769) (xy 445.835341 -28.536127) (xy 445.789491 -28.506661)
			(xy 445.7483 -28.47097) (xy 445.712609 -28.429779) (xy 445.683143 -28.383929) (xy 445.660501 -28.334352)
			(xy 445.645146 -28.282057) (xy 445.63739 -28.228109) (xy 445.636904 -28.200858) (xy 444.134607 -28.200858)
			(xy 444.13544 -28.206264) (xy 444.14925 -28.234194) (xy 444.15964 -28.245816) (xy 444.178242 -28.265839)
			(xy 444.209702 -28.310528) (xy 444.233955 -28.359504) (xy 444.250428 -28.411614) (xy 444.258736 -28.465631)
			(xy 444.259208 -28.492958) (xy 444.25871 -28.519607) (xy 444.250767 -28.572311) (xy 444.235057 -28.623241)
			(xy 444.211931 -28.671262) (xy 444.181907 -28.715299) (xy 444.145655 -28.75437) (xy 444.103984 -28.787601)
			(xy 444.057826 -28.81425) (xy 444.008212 -28.833722) (xy 443.95625 -28.845582) (xy 443.9031 -28.849566)
			(xy 443.84995 -28.845582) (xy 443.797988 -28.833722) (xy 443.748374 -28.81425) (xy 443.702216 -28.787601)
			(xy 443.660545 -28.75437) (xy 443.624293 -28.715299) (xy 443.594269 -28.671262) (xy 443.571143 -28.623241)
			(xy 443.555433 -28.572311) (xy 443.54749 -28.519607) (xy 443.546992 -28.492958) (xy 443.359032 -28.492958)
			(xy 443.358534 -28.519607) (xy 443.350591 -28.572311) (xy 443.334881 -28.623241) (xy 443.311755 -28.671262)
			(xy 443.281731 -28.715299) (xy 443.245479 -28.75437) (xy 443.203808 -28.787601) (xy 443.15765 -28.81425)
			(xy 443.108036 -28.833722) (xy 443.056074 -28.845582) (xy 443.002924 -28.849566) (xy 442.949774 -28.845582)
			(xy 442.897812 -28.833722) (xy 442.848198 -28.81425) (xy 442.80204 -28.787601) (xy 442.760369 -28.75437)
			(xy 442.724117 -28.715299) (xy 442.694093 -28.671262) (xy 442.670967 -28.623241) (xy 442.655257 -28.572311)
			(xy 442.647314 -28.519607) (xy 442.646816 -28.492958) (xy 442.45911 -28.492958) (xy 442.458612 -28.519607)
			(xy 442.450669 -28.572311) (xy 442.434959 -28.623241) (xy 442.411833 -28.671262) (xy 442.381809 -28.715299)
			(xy 442.345557 -28.75437) (xy 442.303886 -28.787601) (xy 442.257728 -28.81425) (xy 442.208114 -28.833722)
			(xy 442.156152 -28.845582) (xy 442.103002 -28.849566) (xy 442.049852 -28.845582) (xy 441.99789 -28.833722)
			(xy 441.948276 -28.81425) (xy 441.902118 -28.787601) (xy 441.860447 -28.75437) (xy 441.824195 -28.715299)
			(xy 441.794171 -28.671262) (xy 441.771045 -28.623241) (xy 441.755335 -28.572311) (xy 441.747392 -28.519607)
			(xy 441.746894 -28.492958) (xy 441.559188 -28.492958) (xy 441.55869 -28.519607) (xy 441.550747 -28.572311)
			(xy 441.535037 -28.623241) (xy 441.511911 -28.671262) (xy 441.481887 -28.715299) (xy 441.445635 -28.75437)
			(xy 441.403964 -28.787601) (xy 441.357806 -28.81425) (xy 441.308192 -28.833722) (xy 441.25623 -28.845582)
			(xy 441.20308 -28.849566) (xy 441.14993 -28.845582) (xy 441.097968 -28.833722) (xy 441.048354 -28.81425)
			(xy 441.002196 -28.787601) (xy 440.960525 -28.75437) (xy 440.924273 -28.715299) (xy 440.894249 -28.671262)
			(xy 440.871123 -28.623241) (xy 440.855413 -28.572311) (xy 440.84747 -28.519607) (xy 440.846972 -28.492958)
			(xy 439.97372 -28.492958) (xy 439.97372 -28.886658) (xy 449.015104 -28.886658) (xy 449.015548 -28.860342)
			(xy 449.02277 -28.808207) (xy 449.037085 -28.757559) (xy 449.058221 -28.709357) (xy 449.085778 -28.664515)
			(xy 449.119233 -28.623884) (xy 449.138294 -28.605734) (xy 449.148357 -28.595962) (xy 449.163053 -28.572078)
			(xy 449.170686 -28.545093) (xy 449.170678 -28.51705) (xy 449.16303 -28.49007) (xy 449.148321 -28.466194)
			(xy 449.138294 -28.456382) (xy 449.119205 -28.438257) (xy 449.085728 -28.397635) (xy 449.058159 -28.352792)
			(xy 449.037022 -28.304583) (xy 449.02272 -28.253923) (xy 449.015523 -28.201778) (xy 449.015104 -28.175458)
			(xy 449.015608 -28.147885) (xy 449.023553 -28.093314) (xy 449.03927 -28.040454) (xy 449.062433 -27.990408)
			(xy 449.092559 -27.944218) (xy 449.12902 -27.902845) (xy 449.149724 -27.884628) (xy 449.160661 -27.874771)
			(xy 449.176728 -27.850108) (xy 449.185104 -27.82189) (xy 449.185096 -27.792456) (xy 449.176705 -27.764242)
			(xy 449.160625 -27.739588) (xy 449.149724 -27.729688) (xy 449.129009 -27.711481) (xy 449.092538 -27.670112)
			(xy 449.062405 -27.623922) (xy 449.03924 -27.573873) (xy 449.023525 -27.521009) (xy 449.015588 -27.466433)
			(xy 449.015104 -27.438858) (xy 449.01559 -27.411607) (xy 449.023346 -27.357659) (xy 449.038701 -27.305364)
			(xy 449.061343 -27.255787) (xy 449.090809 -27.209937) (xy 449.1265 -27.168746) (xy 449.167691 -27.133055)
			(xy 449.213541 -27.103589) (xy 449.263118 -27.080947) (xy 449.315413 -27.065592) (xy 449.369361 -27.057836)
			(xy 449.423863 -27.057836) (xy 449.477811 -27.065592) (xy 449.530106 -27.080947) (xy 449.579683 -27.103589)
			(xy 449.625533 -27.133055) (xy 449.666724 -27.168746) (xy 449.702415 -27.209937) (xy 449.731881 -27.255787)
			(xy 449.754523 -27.305364) (xy 449.769878 -27.357659) (xy 449.777634 -27.411607) (xy 449.77812 -27.438858)
			(xy 449.777618 -27.466431) (xy 449.769672 -27.521002) (xy 449.753954 -27.573861) (xy 449.73079 -27.623907)
			(xy 449.700665 -27.670098) (xy 449.664204 -27.711471) (xy 449.6435 -27.729688) (xy 449.632645 -27.739629)
			(xy 449.616572 -27.764268) (xy 449.608183 -27.792464) (xy 449.608176 -27.821882) (xy 449.616549 -27.850083)
			(xy 449.632609 -27.874729) (xy 449.6435 -27.884628) (xy 449.664228 -27.902821) (xy 449.700697 -27.944194)
			(xy 449.730827 -27.990387) (xy 449.75399 -28.040439) (xy 449.769703 -28.093305) (xy 449.777637 -28.147882)
			(xy 449.77812 -28.175458) (xy 449.777679 -28.201774) (xy 449.770455 -28.253909) (xy 449.75614 -28.304557)
			(xy 449.735003 -28.352759) (xy 449.707446 -28.3976) (xy 449.673991 -28.438232) (xy 449.65493 -28.456382)
			(xy 449.64495 -28.466233) (xy 449.630245 -28.490093) (xy 449.6226 -28.517058) (xy 449.622592 -28.545085)
			(xy 449.630222 -28.572054) (xy 449.644913 -28.595923) (xy 449.65493 -28.605734) (xy 449.674013 -28.623866)
			(xy 449.707493 -28.664485) (xy 449.735065 -28.709326) (xy 449.756203 -28.757534) (xy 449.770506 -28.808193)
			(xy 449.777701 -28.860338) (xy 449.77812 -28.886658) (xy 449.777634 -28.913909) (xy 449.774248 -28.937458)
			(xy 452.799704 -28.937458) (xy 452.800148 -28.911142) (xy 452.80737 -28.859007) (xy 452.821685 -28.808359)
			(xy 452.842821 -28.760157) (xy 452.870378 -28.715315) (xy 452.903833 -28.674684) (xy 452.922894 -28.656534)
			(xy 452.932957 -28.646762) (xy 452.947653 -28.622878) (xy 452.955286 -28.595893) (xy 452.955278 -28.56785)
			(xy 452.94763 -28.54087) (xy 452.932921 -28.516994) (xy 452.922894 -28.507182) (xy 452.903805 -28.489057)
			(xy 452.870328 -28.448435) (xy 452.842759 -28.403592) (xy 452.821622 -28.355383) (xy 452.80732 -28.304723)
			(xy 452.800123 -28.252578) (xy 452.799704 -28.226258) (xy 452.800208 -28.198685) (xy 452.808153 -28.144114)
			(xy 452.82387 -28.091254) (xy 452.847033 -28.041208) (xy 452.877159 -27.995018) (xy 452.91362 -27.953645)
			(xy 452.934324 -27.935428) (xy 452.945261 -27.925571) (xy 452.961328 -27.900908) (xy 452.969704 -27.87269)
			(xy 452.969696 -27.843256) (xy 452.961305 -27.815042) (xy 452.945225 -27.790388) (xy 452.934324 -27.780488)
			(xy 452.913609 -27.762281) (xy 452.877138 -27.720912) (xy 452.847005 -27.674722) (xy 452.82384 -27.624673)
			(xy 452.808125 -27.571809) (xy 452.800188 -27.517233) (xy 452.799704 -27.489658) (xy 452.80019 -27.462407)
			(xy 452.807946 -27.408459) (xy 452.823301 -27.356164) (xy 452.845943 -27.306587) (xy 452.875409 -27.260737)
			(xy 452.9111 -27.219546) (xy 452.952291 -27.183855) (xy 452.998141 -27.154389) (xy 453.047718 -27.131747)
			(xy 453.100013 -27.116392) (xy 453.153961 -27.108636) (xy 453.208463 -27.108636) (xy 453.262411 -27.116392)
			(xy 453.314706 -27.131747) (xy 453.364283 -27.154389) (xy 453.410133 -27.183855) (xy 453.451324 -27.219546)
			(xy 453.487015 -27.260737) (xy 453.516481 -27.306587) (xy 453.539123 -27.356164) (xy 453.554478 -27.408459)
			(xy 453.562234 -27.462407) (xy 453.56272 -27.489658) (xy 453.562218 -27.517231) (xy 453.554272 -27.571802)
			(xy 453.538554 -27.624661) (xy 453.51539 -27.674707) (xy 453.485265 -27.720898) (xy 453.448804 -27.762271)
			(xy 453.4281 -27.780488) (xy 453.417245 -27.790429) (xy 453.401172 -27.815068) (xy 453.392783 -27.843264)
			(xy 453.392776 -27.872682) (xy 453.401149 -27.900883) (xy 453.417209 -27.925529) (xy 453.4281 -27.935428)
			(xy 453.448828 -27.953621) (xy 453.485297 -27.994994) (xy 453.515427 -28.041187) (xy 453.53859 -28.091239)
			(xy 453.554303 -28.144105) (xy 453.562237 -28.198682) (xy 453.56272 -28.226258) (xy 453.562279 -28.252574)
			(xy 453.555055 -28.304709) (xy 453.54074 -28.355357) (xy 453.519603 -28.403559) (xy 453.492046 -28.4484)
			(xy 453.458591 -28.489032) (xy 453.43953 -28.507182) (xy 453.42955 -28.517033) (xy 453.414845 -28.540893)
			(xy 453.4072 -28.567858) (xy 453.407192 -28.595885) (xy 453.414822 -28.622854) (xy 453.429513 -28.646723)
			(xy 453.43953 -28.656534) (xy 453.458613 -28.674666) (xy 453.492093 -28.715285) (xy 453.519665 -28.760126)
			(xy 453.540803 -28.808334) (xy 453.555106 -28.858993) (xy 453.562301 -28.911138) (xy 453.56272 -28.937458)
			(xy 453.562234 -28.964709) (xy 453.554478 -29.018657) (xy 453.539123 -29.070952) (xy 453.516481 -29.120529)
			(xy 453.487015 -29.166379) (xy 453.451324 -29.20757) (xy 453.410133 -29.243261) (xy 453.364283 -29.272727)
			(xy 453.314706 -29.295369) (xy 453.262411 -29.310724) (xy 453.208463 -29.31848) (xy 453.153961 -29.31848)
			(xy 453.100013 -29.310724) (xy 453.047718 -29.295369) (xy 452.998141 -29.272727) (xy 452.952291 -29.243261)
			(xy 452.9111 -29.20757) (xy 452.875409 -29.166379) (xy 452.845943 -29.120529) (xy 452.823301 -29.070952)
			(xy 452.807946 -29.018657) (xy 452.80019 -28.964709) (xy 452.799704 -28.937458) (xy 449.774248 -28.937458)
			(xy 449.769878 -28.967857) (xy 449.754523 -29.020152) (xy 449.731881 -29.069729) (xy 449.702415 -29.115579)
			(xy 449.666724 -29.15677) (xy 449.625533 -29.192461) (xy 449.579683 -29.221927) (xy 449.530106 -29.244569)
			(xy 449.477811 -29.259924) (xy 449.423863 -29.26768) (xy 449.369361 -29.26768) (xy 449.315413 -29.259924)
			(xy 449.263118 -29.244569) (xy 449.213541 -29.221927) (xy 449.167691 -29.192461) (xy 449.1265 -29.15677)
			(xy 449.090809 -29.115579) (xy 449.061343 -29.069729) (xy 449.038701 -29.020152) (xy 449.023346 -28.967857)
			(xy 449.01559 -28.913909) (xy 449.015104 -28.886658) (xy 439.97372 -28.886658) (xy 439.97372 -29.675956)
			(xy 446.145313 -29.675956) (xy 446.145313 -29.621444) (xy 446.153071 -29.567486) (xy 446.168429 -29.515181)
			(xy 446.191075 -29.465595) (xy 446.220548 -29.419736) (xy 446.256247 -29.378538) (xy 446.297445 -29.342841)
			(xy 446.343305 -29.31337) (xy 446.392892 -29.290725) (xy 446.445197 -29.275369) (xy 446.499156 -29.267612)
			(xy 446.526412 -29.26715) (xy 446.555327 -29.267713) (xy 446.612497 -29.27643) (xy 446.667696 -29.293678)
			(xy 446.719659 -29.319061) (xy 446.767193 -29.351998) (xy 446.809211 -29.391733) (xy 446.827402 -29.414216)
			(xy 446.837299 -29.426021) (xy 446.862623 -29.44354) (xy 446.892016 -29.452716) (xy 446.922808 -29.452716)
			(xy 446.952201 -29.44354) (xy 446.977525 -29.426021) (xy 446.987422 -29.414216) (xy 447.005605 -29.391725)
			(xy 447.047626 -29.35199) (xy 447.095162 -29.319051) (xy 447.147125 -29.293664) (xy 447.202324 -29.27641)
			(xy 447.259495 -29.267683) (xy 447.288412 -29.26715) (xy 447.31566 -29.267721) (xy 447.3696 -29.275478)
			(xy 447.421888 -29.290832) (xy 447.471458 -29.313472) (xy 447.517302 -29.342935) (xy 447.558486 -29.378623)
			(xy 447.594172 -29.419808) (xy 447.623634 -29.465653) (xy 447.646272 -29.515224) (xy 447.661625 -29.567512)
			(xy 447.66938 -29.621452) (xy 447.66938 -29.675948) (xy 447.661625 -29.729888) (xy 447.646272 -29.782176)
			(xy 447.623634 -29.831747) (xy 447.594172 -29.877592) (xy 447.558486 -29.918777) (xy 447.517302 -29.954465)
			(xy 447.471458 -29.983928) (xy 447.421888 -30.006568) (xy 447.3696 -30.021922) (xy 447.31566 -30.029679)
			(xy 447.288412 -30.030166) (xy 447.259495 -30.029652) (xy 447.202323 -30.020924) (xy 447.147123 -30.003666)
			(xy 447.095161 -29.978273) (xy 447.047628 -29.945329) (xy 447.005612 -29.905586) (xy 446.987422 -29.8831)
			(xy 446.977525 -29.871295) (xy 446.952201 -29.853776) (xy 446.922808 -29.8446) (xy 446.892016 -29.8446)
			(xy 446.862623 -29.853776) (xy 446.837299 -29.871295) (xy 446.827402 -29.8831) (xy 446.80921 -29.905583)
			(xy 446.76719 -29.945318) (xy 446.719656 -29.978257) (xy 446.667695 -30.003645) (xy 446.612497 -30.020902)
			(xy 446.555328 -30.029631) (xy 446.526412 -30.030166) (xy 446.499156 -30.029788) (xy 446.445197 -30.022031)
			(xy 446.392892 -30.006675) (xy 446.343305 -29.98403) (xy 446.297445 -29.954559) (xy 446.256247 -29.918862)
			(xy 446.220548 -29.877664) (xy 446.191075 -29.831805) (xy 446.168429 -29.782219) (xy 446.153071 -29.729914)
			(xy 446.145313 -29.675956) (xy 439.97372 -29.675956) (xy 439.97372 -30.706568) (xy 441.506862 -30.706568)
			(xy 441.510933 -30.650946) (xy 441.523059 -30.596509) (xy 441.542982 -30.544418) (xy 441.570278 -30.495783)
			(xy 441.604364 -30.45164) (xy 441.644513 -30.412931) (xy 441.689871 -30.38048) (xy 441.739471 -30.354979)
			(xy 441.792255 -30.336972) (xy 441.847098 -30.326842) (xy 441.902832 -30.324805) (xy 441.958269 -30.330905)
			(xy 442.012226 -30.345011) (xy 442.063555 -30.366823) (xy 442.111161 -30.395877) (xy 442.154029 -30.431552)
			(xy 442.191066 -30.472888) (xy 444.326262 -30.472888) (xy 444.330333 -30.417266) (xy 444.342459 -30.362829)
			(xy 444.362382 -30.310738) (xy 444.389678 -30.262103) (xy 444.423764 -30.21796) (xy 444.463913 -30.179251)
			(xy 444.509271 -30.1468) (xy 444.558871 -30.121299) (xy 444.611655 -30.103292) (xy 444.666498 -30.093162)
			(xy 444.722232 -30.091125) (xy 444.777669 -30.097225) (xy 444.831626 -30.111331) (xy 444.882955 -30.133143)
			(xy 444.930561 -30.162197) (xy 444.973429 -30.197872) (xy 445.010646 -30.239409) (xy 445.041419 -30.285922)
			(xy 445.065091 -30.336419) (xy 445.081159 -30.389826) (xy 445.089279 -30.445002) (xy 445.089788 -30.472888)
			(xy 445.089279 -30.500774) (xy 445.081159 -30.55595) (xy 445.065091 -30.609357) (xy 445.041419 -30.659854)
			(xy 445.010646 -30.706367) (xy 444.973429 -30.747904) (xy 444.930561 -30.783579) (xy 444.882955 -30.812633)
			(xy 444.831626 -30.834445) (xy 444.777669 -30.848551) (xy 444.722232 -30.854651) (xy 444.666498 -30.852614)
			(xy 444.611655 -30.842484) (xy 444.558871 -30.824477) (xy 444.509271 -30.798976) (xy 444.463913 -30.766525)
			(xy 444.423764 -30.727816) (xy 444.389678 -30.683673) (xy 444.362382 -30.635038) (xy 444.342459 -30.582947)
			(xy 444.330333 -30.52851) (xy 444.326262 -30.472888) (xy 442.191066 -30.472888) (xy 442.191246 -30.473089)
			(xy 442.222019 -30.519602) (xy 442.245691 -30.570099) (xy 442.261759 -30.623506) (xy 442.269879 -30.678682)
			(xy 442.270388 -30.706568) (xy 442.269879 -30.734454) (xy 442.261759 -30.78963) (xy 442.245691 -30.843037)
			(xy 442.222019 -30.893534) (xy 442.191246 -30.940047) (xy 442.154029 -30.981584) (xy 442.111161 -31.017259)
			(xy 442.063555 -31.046313) (xy 442.012226 -31.068125) (xy 441.958269 -31.082231) (xy 441.902832 -31.088331)
			(xy 441.847098 -31.086294) (xy 441.792255 -31.076164) (xy 441.739471 -31.058157) (xy 441.689871 -31.032656)
			(xy 441.644513 -31.000205) (xy 441.604364 -30.961496) (xy 441.570278 -30.917353) (xy 441.542982 -30.868718)
			(xy 441.523059 -30.816627) (xy 441.510933 -30.76219) (xy 441.506862 -30.706568) (xy 439.97372 -30.706568)
			(xy 439.97372 -31.229808) (xy 442.850522 -31.229808) (xy 442.854593 -31.174186) (xy 442.866719 -31.119749)
			(xy 442.886642 -31.067658) (xy 442.913938 -31.019023) (xy 442.948024 -30.97488) (xy 442.988173 -30.936171)
			(xy 443.033531 -30.90372) (xy 443.083131 -30.878219) (xy 443.135915 -30.860212) (xy 443.190758 -30.850082)
			(xy 443.246492 -30.848045) (xy 443.301929 -30.854145) (xy 443.355886 -30.868251) (xy 443.407215 -30.890063)
			(xy 443.454821 -30.919117) (xy 443.497689 -30.954792) (xy 443.534906 -30.996329) (xy 443.565679 -31.042842)
			(xy 443.589351 -31.093339) (xy 443.605419 -31.146746) (xy 443.613539 -31.201922) (xy 443.614048 -31.229808)
			(xy 443.613539 -31.257694) (xy 443.605419 -31.31287) (xy 443.589351 -31.366277) (xy 443.565679 -31.416774)
			(xy 443.534906 -31.463287) (xy 443.497689 -31.504824) (xy 443.454821 -31.540499) (xy 443.407215 -31.569553)
			(xy 443.355886 -31.591365) (xy 443.301929 -31.605471) (xy 443.246492 -31.611571) (xy 443.190758 -31.609534)
			(xy 443.135915 -31.599404) (xy 443.083131 -31.581397) (xy 443.033531 -31.555896) (xy 442.988173 -31.523445)
			(xy 442.948024 -31.484736) (xy 442.913938 -31.440593) (xy 442.886642 -31.391958) (xy 442.866719 -31.339867)
			(xy 442.854593 -31.28543) (xy 442.850522 -31.229808) (xy 439.97372 -31.229808) (xy 439.97372 -32.573468)
			(xy 446.226182 -32.573468) (xy 446.230253 -32.517846) (xy 446.242379 -32.463409) (xy 446.262302 -32.411318)
			(xy 446.289598 -32.362683) (xy 446.323684 -32.31854) (xy 446.363833 -32.279831) (xy 446.409191 -32.24738)
			(xy 446.458791 -32.221879) (xy 446.511575 -32.203872) (xy 446.566418 -32.193742) (xy 446.622152 -32.191705)
			(xy 446.677589 -32.197805) (xy 446.731546 -32.211911) (xy 446.782875 -32.233723) (xy 446.830481 -32.262777)
			(xy 446.873349 -32.298452) (xy 446.910566 -32.339989) (xy 446.941339 -32.386502) (xy 446.965011 -32.436999)
			(xy 446.981079 -32.490406) (xy 446.989199 -32.545582) (xy 446.989708 -32.573468) (xy 446.989199 -32.601354)
			(xy 446.981079 -32.65653) (xy 446.965011 -32.709937) (xy 446.941339 -32.760434) (xy 446.910566 -32.806947)
			(xy 446.873349 -32.848484) (xy 446.830481 -32.884159) (xy 446.782875 -32.913213) (xy 446.731546 -32.935025)
			(xy 446.677589 -32.949131) (xy 446.622152 -32.955231) (xy 446.566418 -32.953194) (xy 446.511575 -32.943064)
			(xy 446.458791 -32.925057) (xy 446.409191 -32.899556) (xy 446.363833 -32.867105) (xy 446.323684 -32.828396)
			(xy 446.289598 -32.784253) (xy 446.262302 -32.735618) (xy 446.242379 -32.683527) (xy 446.230253 -32.62909)
			(xy 446.226182 -32.573468) (xy 439.97372 -32.573468) (xy 439.97372 -33.837372) (xy 440.095132 -33.958784)
			(xy 440.12739 -33.943798) (xy 440.151081 -33.933234) (xy 440.200759 -33.918308) (xy 440.252077 -33.910752)
			(xy 440.278012 -33.91027) (xy 440.305995 -33.91082) (xy 440.361272 -33.919576) (xy 440.414499 -33.936872)
			(xy 440.464365 -33.96228) (xy 440.509643 -33.995176) (xy 440.549218 -34.034749) (xy 440.582115 -34.080026)
			(xy 440.607525 -34.129892) (xy 440.624821 -34.183118) (xy 440.633579 -34.238395) (xy 440.63412 -34.266378)
			(xy 440.633632 -34.292313) (xy 440.626072 -34.343629) (xy 440.61115 -34.393307) (xy 440.600592 -34.417)
			(xy 440.585606 -34.449258) (xy 440.772296 -34.635948) (xy 456.74788 -34.635948)
		)
		(stroke
			(width 0)
			(type solid)
		)
		(fill yes)
		(layer "In13.Cu")
		(net "GND")
	)
	(gr_poly
		(pts
			(xy 185.469276 -34.959544) (xy 185.490124 -34.939414) (xy 185.536971 -34.905303) (xy 185.588579 -34.878942)
			(xy 185.643676 -34.860981) (xy 185.700905 -34.851864) (xy 185.72988 -34.85134) (xy 187.12434 -34.85134)
			(xy 187.138591 -34.850868) (xy 187.165982 -34.842987) (xy 187.190117 -34.827827) (xy 187.209107 -34.806573)
			(xy 187.221464 -34.780889) (xy 187.226223 -34.752788) (xy 187.225178 -34.738564) (xy 187.224099 -34.728057)
			(xy 187.222958 -34.706963) (xy 187.222892 -34.6964) (xy 187.223378 -34.669149) (xy 187.231134 -34.615201)
			(xy 187.246489 -34.562906) (xy 187.269131 -34.513329) (xy 187.298597 -34.467479) (xy 187.334288 -34.426288)
			(xy 187.375479 -34.390597) (xy 187.421329 -34.361131) (xy 187.470906 -34.338489) (xy 187.523201 -34.323134)
			(xy 187.577149 -34.315378) (xy 187.631651 -34.315378) (xy 187.685599 -34.323134) (xy 187.737894 -34.338489)
			(xy 187.787471 -34.361131) (xy 187.833321 -34.390597) (xy 187.874512 -34.426288) (xy 187.910203 -34.467479)
			(xy 187.939669 -34.513329) (xy 187.962311 -34.562906) (xy 187.977666 -34.615201) (xy 187.985422 -34.669149)
			(xy 187.985908 -34.6964) (xy 187.985849 -34.706963) (xy 187.984703 -34.728057) (xy 187.983622 -34.738564)
			(xy 187.982534 -34.752778) (xy 187.987354 -34.780862) (xy 187.999739 -34.806525) (xy 188.018728 -34.827771)
			(xy 188.042844 -34.84295) (xy 188.070213 -34.850881) (xy 188.08446 -34.85134) (xy 189.38748 -34.85134)
			(xy 189.416453 -34.851901) (xy 189.473679 -34.861012) (xy 189.528774 -34.878966) (xy 189.58038 -34.905321)
			(xy 189.627227 -34.939426) (xy 189.648084 -34.959544) (xy 190.098934 -35.41014) (xy 190.424308 -35.41014)
			(xy 190.438434 -35.409721) (xy 190.465623 -35.402055) (xy 190.489669 -35.387231) (xy 190.508731 -35.366382)
			(xy 190.521347 -35.341107) (xy 190.526552 -35.313342) (xy 190.523947 -35.285214) (xy 190.513731 -35.258877)
			(xy 190.505588 -35.247326) (xy 190.487445 -35.222349) (xy 190.458623 -35.167759) (xy 190.438966 -35.109241)
			(xy 190.428987 -35.048321) (xy 190.428372 -35.017456) (xy 190.428858 -34.990205) (xy 190.436614 -34.936257)
			(xy 190.451969 -34.883962) (xy 190.474611 -34.834385) (xy 190.504077 -34.788535) (xy 190.539768 -34.747344)
			(xy 190.580959 -34.711653) (xy 190.626809 -34.682187) (xy 190.676386 -34.659545) (xy 190.728681 -34.64419)
			(xy 190.782629 -34.636434) (xy 190.837131 -34.636434) (xy 190.891079 -34.64419) (xy 190.943374 -34.659545)
			(xy 190.992951 -34.682187) (xy 191.038801 -34.711653) (xy 191.079992 -34.747344) (xy 191.115683 -34.788535)
			(xy 191.145149 -34.834385) (xy 191.167791 -34.883962) (xy 191.183146 -34.936257) (xy 191.190902 -34.990205)
			(xy 191.191388 -35.017456) (xy 191.190773 -35.048322) (xy 191.180795 -35.109242) (xy 191.161141 -35.167761)
			(xy 191.132323 -35.222354) (xy 191.114172 -35.247326) (xy 191.106039 -35.258871) (xy 191.095863 -35.285203)
			(xy 191.093284 -35.313315) (xy 191.098499 -35.341058) (xy 191.11111 -35.366314) (xy 191.130153 -35.387153)
			(xy 191.154174 -35.401983) (xy 191.181336 -35.409671) (xy 191.195452 -35.41014) (xy 191.723772 -35.41014)
			(xy 193.989198 -33.144714) (xy 193.989198 -28.541726) (xy 190.90005 -25.452578) (xy 190.882693 -25.434595)
			(xy 190.853286 -25.394184) (xy 190.830571 -25.349665) (xy 190.81511 -25.302139) (xy 190.807284 -25.252777)
			(xy 190.806832 -25.227788) (xy 190.806832 -24.03475) (xy 190.806356 -24.020263) (xy 190.798284 -23.99244)
			(xy 190.782719 -23.968006) (xy 190.760915 -23.948931) (xy 190.734629 -23.936751) (xy 190.705979 -23.932448)
			(xy 190.677275 -23.936369) (xy 190.66383 -23.941786) (xy 190.639262 -23.952252) (xy 190.587951 -23.967039)
			(xy 190.535081 -23.974546) (xy 190.508382 -23.97506) (xy 190.481131 -23.974595) (xy 190.427185 -23.966836)
			(xy 190.374892 -23.951478) (xy 190.325317 -23.928834) (xy 190.27947 -23.899365) (xy 190.238283 -23.86367)
			(xy 190.202596 -23.822477) (xy 190.173135 -23.776625) (xy 190.150499 -23.727046) (xy 190.13515 -23.674751)
			(xy 190.1274 -23.620803) (xy 190.126874 -23.593552) (xy 190.127357 -23.565976) (xy 190.135293 -23.511399)
			(xy 190.151006 -23.458534) (xy 190.174169 -23.408483) (xy 190.204299 -23.362289) (xy 190.240768 -23.320917)
			(xy 190.261494 -23.302722) (xy 190.272385 -23.292824) (xy 190.288444 -23.268178) (xy 190.296817 -23.239977)
			(xy 190.296808 -23.210561) (xy 190.288418 -23.182366) (xy 190.272343 -23.157729) (xy 190.261494 -23.147782)
			(xy 190.240791 -23.129564) (xy 190.204331 -23.088191) (xy 190.174207 -23.042) (xy 190.151044 -22.991954)
			(xy 190.135327 -22.939096) (xy 190.127382 -22.884525) (xy 190.126874 -22.856952) (xy 190.127021 -22.843122)
			(xy 190.129059 -22.815537) (xy 190.130938 -22.801834) (xy 190.132557 -22.787368) (xy 190.128432 -22.758565)
			(xy 190.116354 -22.732092) (xy 190.097303 -22.710099) (xy 190.072824 -22.694369) (xy 190.044903 -22.686178)
			(xy 190.030354 -22.685756) (xy 188.258196 -22.685756) (xy 188.243233 -22.686271) (xy 188.214584 -22.694919)
			(xy 188.189672 -22.7115) (xy 188.170637 -22.734592) (xy 188.159113 -22.76221) (xy 188.15609 -22.791982)
			(xy 188.161828 -22.821353) (xy 188.175833 -22.847799) (xy 188.18606 -22.85873) (xy 188.206622 -22.880305)
			(xy 188.241469 -22.928652) (xy 188.268377 -22.981828) (xy 188.286693 -23.03854) (xy 188.295971 -23.09741)
			(xy 188.29655 -23.127208) (xy 188.296064 -23.154459) (xy 188.288308 -23.208407) (xy 188.272953 -23.260702)
			(xy 188.250311 -23.310279) (xy 188.220845 -23.356129) (xy 188.185154 -23.39732) (xy 188.143963 -23.433011)
			(xy 188.098113 -23.462477) (xy 188.048536 -23.485119) (xy 187.996241 -23.500474) (xy 187.942293 -23.50823)
			(xy 187.887791 -23.50823) (xy 187.833843 -23.500474) (xy 187.781548 -23.485119) (xy 187.731971 -23.462477)
			(xy 187.686121 -23.433011) (xy 187.64493 -23.39732) (xy 187.609239 -23.356129) (xy 187.579773 -23.310279)
			(xy 187.557131 -23.260702) (xy 187.541776 -23.208407) (xy 187.53402 -23.154459) (xy 187.533534 -23.127208)
			(xy 187.534108 -23.097409) (xy 187.543378 -23.038537) (xy 187.561692 -22.981823) (xy 187.588607 -22.928649)
			(xy 187.623465 -22.880308) (xy 187.644024 -22.85873) (xy 187.654162 -22.847731) (xy 187.66813 -22.821298)
			(xy 187.673848 -22.791952) (xy 187.670824 -22.762208) (xy 187.659319 -22.734613) (xy 187.640317 -22.711531)
			(xy 187.615446 -22.69494) (xy 187.586836 -22.686259) (xy 187.571888 -22.685756) (xy 185.148982 -22.685756)
			(xy 185.134332 -22.686228) (xy 185.106235 -22.694533) (xy 185.081657 -22.710481) (xy 185.062625 -22.732757)
			(xy 185.050709 -22.759524) (xy 185.046892 -22.788573) (xy 185.051489 -22.817509) (xy 185.064121 -22.843945)
			(xy 185.073544 -22.855174) (xy 185.091821 -22.876274) (xy 185.122648 -22.922814) (xy 185.146364 -22.973348)
			(xy 185.162466 -23.026799) (xy 185.170608 -23.082025) (xy 185.17108 -23.109936) (xy 185.170594 -23.137187)
			(xy 185.162838 -23.191135) (xy 185.147483 -23.24343) (xy 185.124841 -23.293007) (xy 185.095375 -23.338857)
			(xy 185.059684 -23.380048) (xy 185.018493 -23.415739) (xy 184.972643 -23.445205) (xy 184.923066 -23.467847)
			(xy 184.870771 -23.483202) (xy 184.816823 -23.490958) (xy 184.762321 -23.490958) (xy 184.708373 -23.483202)
			(xy 184.656078 -23.467847) (xy 184.606501 -23.445205) (xy 184.560651 -23.415739) (xy 184.51946 -23.380048)
			(xy 184.483769 -23.338857) (xy 184.454303 -23.293007) (xy 184.431661 -23.24343) (xy 184.416306 -23.191135)
			(xy 184.40855 -23.137187) (xy 184.408064 -23.109936) (xy 184.408548 -23.082024) (xy 184.416679 -23.026796)
			(xy 184.432773 -22.973343) (xy 184.456487 -22.922806) (xy 184.487313 -22.876266) (xy 184.5056 -22.855174)
			(xy 184.515024 -22.843958) (xy 184.527603 -22.817514) (xy 184.532164 -22.788587) (xy 184.528333 -22.759555)
			(xy 184.516425 -22.732803) (xy 184.497417 -22.710526) (xy 184.472871 -22.694557) (xy 184.444803 -22.686206)
			(xy 184.430162 -22.685756) (xy 179.74564 -22.685756) (xy 179.720658 -22.68524) (xy 179.671316 -22.677381)
			(xy 179.623806 -22.661913) (xy 179.579295 -22.639215) (xy 179.538875 -22.609844) (xy 179.52085 -22.592538)
			(xy 179.093876 -22.165564) (xy 179.079906 -22.162008) (xy 179.052967 -22.155031) (xy 179.001314 -22.13433)
			(xy 178.953219 -22.106342) (xy 178.909702 -22.071661) (xy 178.871689 -22.031022) (xy 178.839986 -21.98529)
			(xy 178.827176 -21.960586) (xy 178.820023 -21.94729) (xy 178.799368 -21.925293) (xy 178.773183 -21.910296)
			(xy 178.743758 -21.90361) (xy 178.713664 -21.905818) (xy 178.699414 -21.910802) (xy 178.677421 -21.91891)
			(xy 178.631956 -21.930321) (xy 178.585437 -21.936093) (xy 178.562 -21.936456) (xy 178.534748 -21.93597)
			(xy 178.480797 -21.928214) (xy 178.4285 -21.912859) (xy 178.378919 -21.890219) (xy 178.333066 -21.860753)
			(xy 178.291871 -21.825063) (xy 178.256175 -21.783873) (xy 178.226704 -21.738023) (xy 178.204057 -21.688445)
			(xy 178.188696 -21.63615) (xy 178.180933 -21.5822) (xy 178.180492 -21.554948) (xy 178.181011 -21.526644)
			(xy 178.189383 -21.470659) (xy 178.205936 -21.416526) (xy 178.230306 -21.365433) (xy 178.261958 -21.318501)
			(xy 178.300197 -21.276762) (xy 178.344185 -21.241132) (xy 178.392954 -21.212392) (xy 178.445435 -21.191174)
			(xy 178.472846 -21.184108) (xy 178.486816 -21.180552) (xy 178.590702 -21.076666) (xy 178.608687 -21.059312)
			(xy 178.6491 -21.02991) (xy 178.693618 -21.007199) (xy 178.741144 -20.991739) (xy 178.790504 -20.983912)
			(xy 178.815492 -20.983448) (xy 179.201572 -20.983448) (xy 179.216551 -20.982921) (xy 179.245221 -20.974236)
			(xy 179.270138 -20.957606) (xy 179.289157 -20.934461) (xy 179.300641 -20.906793) (xy 179.303603 -20.876983)
			(xy 179.297788 -20.847596) (xy 179.283695 -20.821161) (xy 179.273454 -20.81022) (xy 177.852578 -19.389344)
			(xy 177.838608 -19.386042) (xy 177.813164 -19.379533) (xy 177.764225 -19.36047) (xy 177.718367 -19.334869)
			(xy 177.676458 -19.303216) (xy 177.63929 -19.266108) (xy 177.607569 -19.22425) (xy 177.581894 -19.178433)
			(xy 177.562752 -19.129526) (xy 177.55616 -19.104102) (xy 177.552604 -19.090132) (xy 177.326036 -18.863564)
			(xy 174.935896 -18.863564) (xy 174.916298 -18.882409) (xy 174.872724 -18.914923) (xy 174.824975 -18.940922)
			(xy 174.774018 -18.959878) (xy 174.720886 -18.971408) (xy 174.666656 -18.975277) (xy 174.612426 -18.971408)
			(xy 174.559294 -18.959878) (xy 174.508337 -18.940922) (xy 174.460588 -18.914923) (xy 174.417014 -18.882409)
			(xy 174.397416 -18.863564) (xy 174.202598 -18.863564) (xy 173.124114 -19.942048) (xy 176.496472 -19.942048)
			(xy 176.496958 -19.914797) (xy 176.504714 -19.860849) (xy 176.520069 -19.808554) (xy 176.542711 -19.758977)
			(xy 176.572177 -19.713127) (xy 176.607868 -19.671936) (xy 176.649059 -19.636245) (xy 176.694909 -19.606779)
			(xy 176.744486 -19.584137) (xy 176.796781 -19.568782) (xy 176.850729 -19.561026) (xy 176.905231 -19.561026)
			(xy 176.959179 -19.568782) (xy 177.011474 -19.584137) (xy 177.061051 -19.606779) (xy 177.106901 -19.636245)
			(xy 177.148092 -19.671936) (xy 177.183783 -19.713127) (xy 177.213249 -19.758977) (xy 177.235891 -19.808554)
			(xy 177.251246 -19.860849) (xy 177.259002 -19.914797) (xy 177.259488 -19.942048) (xy 177.25908 -19.968062)
			(xy 177.252003 -20.019606) (xy 177.237988 -20.06971) (xy 177.217293 -20.117445) (xy 177.190304 -20.161925)
			(xy 177.157521 -20.202325) (xy 177.138838 -20.220432) (xy 177.12914 -20.230009) (xy 177.114828 -20.253195)
			(xy 177.107164 -20.279342) (xy 177.106696 -20.306585) (xy 177.113457 -20.332981) (xy 177.126965 -20.356644)
			(xy 177.146255 -20.375887) (xy 177.157888 -20.382992) (xy 177.182525 -20.397672) (xy 177.227509 -20.433241)
			(xy 177.266661 -20.475145) (xy 177.299097 -20.522439) (xy 177.324086 -20.574056) (xy 177.341064 -20.628833)
			(xy 177.34965 -20.685534) (xy 177.350166 -20.714208) (xy 177.349713 -20.741579) (xy 177.341893 -20.795759)
			(xy 177.326402 -20.848262) (xy 177.303557 -20.898009) (xy 177.273829 -20.943975) (xy 177.256186 -20.964906)
			(xy 177.246943 -20.976228) (xy 177.234768 -21.002788) (xy 177.230597 -21.031706) (xy 177.234771 -21.060624)
			(xy 177.246949 -21.087182) (xy 177.256186 -21.09851) (xy 177.273841 -21.119429) (xy 177.303551 -21.165405)
			(xy 177.326384 -21.215156) (xy 177.341871 -21.26766) (xy 177.349695 -21.321838) (xy 177.350166 -21.349208)
			(xy 177.349912 -21.365718) (xy 177.349784 -21.379791) (xy 177.356241 -21.407169) (xy 177.369933 -21.431741)
			(xy 177.389819 -21.451637) (xy 177.414384 -21.465341) (xy 177.441759 -21.471811) (xy 177.45583 -21.471636)
			(xy 177.47234 -21.471382) (xy 177.499588 -21.471921) (xy 177.553528 -21.479682) (xy 177.605815 -21.495041)
			(xy 177.655384 -21.517684) (xy 177.701226 -21.547151) (xy 177.742408 -21.582842) (xy 177.778091 -21.62403)
			(xy 177.80755 -21.669878) (xy 177.830184 -21.719451) (xy 177.845533 -21.77174) (xy 177.853284 -21.825682)
			(xy 177.85328 -21.880178) (xy 177.84552 -21.934118) (xy 177.830163 -21.986406) (xy 177.807521 -22.035975)
			(xy 177.778055 -22.081818) (xy 177.742365 -22.123001) (xy 177.701178 -22.158685) (xy 177.655331 -22.188145)
			(xy 177.605759 -22.21078) (xy 177.553469 -22.226131) (xy 177.499528 -22.233883) (xy 177.445032 -22.23388)
			(xy 177.391091 -22.226122) (xy 177.338804 -22.210766) (xy 177.289234 -22.188126) (xy 177.24339 -22.158661)
			(xy 177.202206 -22.122972) (xy 177.166521 -22.081786) (xy 177.13706 -22.03594) (xy 177.114423 -21.986368)
			(xy 177.099071 -21.934079) (xy 177.091317 -21.880138) (xy 177.090832 -21.85289) (xy 177.091086 -21.83638)
			(xy 177.091218 -21.822307) (xy 177.08476 -21.794928) (xy 177.071067 -21.770356) (xy 177.051181 -21.750461)
			(xy 177.026615 -21.736756) (xy 176.999239 -21.730286) (xy 176.985168 -21.730462) (xy 176.968658 -21.730716)
			(xy 176.941406 -21.730261) (xy 176.887458 -21.722499) (xy 176.835163 -21.707139) (xy 176.785586 -21.684494)
			(xy 176.739736 -21.655024) (xy 176.698547 -21.619329) (xy 176.662856 -21.578137) (xy 176.63339 -21.532284)
			(xy 176.610749 -21.482705) (xy 176.595394 -21.430409) (xy 176.587636 -21.37646) (xy 176.58715 -21.349208)
			(xy 176.587609 -21.321837) (xy 176.595426 -21.267657) (xy 176.610916 -21.215154) (xy 176.63376 -21.165407)
			(xy 176.663487 -21.119441) (xy 176.68113 -21.09851) (xy 176.690357 -21.087176) (xy 176.702531 -21.06062)
			(xy 176.706704 -21.031706) (xy 176.702535 -21.002792) (xy 176.690363 -20.976234) (xy 176.68113 -20.964906)
			(xy 176.663485 -20.943979) (xy 176.633773 -20.898005) (xy 176.610938 -20.848256) (xy 176.595448 -20.795754)
			(xy 176.587622 -20.741578) (xy 176.58715 -20.714208) (xy 176.587614 -20.688196) (xy 176.594682 -20.636655)
			(xy 176.608688 -20.586553) (xy 176.629372 -20.538818) (xy 176.65635 -20.494336) (xy 176.689122 -20.453933)
			(xy 176.7078 -20.435824) (xy 176.717428 -20.426183) (xy 176.731736 -20.403013) (xy 176.739402 -20.376882)
			(xy 176.739878 -20.349654) (xy 176.733131 -20.32327) (xy 176.719642 -20.299614) (xy 176.700372 -20.280371)
			(xy 176.68875 -20.273264) (xy 176.664102 -20.258601) (xy 176.619116 -20.22303) (xy 176.579964 -20.181124)
			(xy 176.547528 -20.133828) (xy 176.522541 -20.082208) (xy 176.505566 -20.027428) (xy 176.496985 -19.970723)
			(xy 176.496472 -19.942048) (xy 173.124114 -19.942048) (xy 171.510198 -21.555964) (xy 171.510198 -22.054566)
			(xy 171.525325 -22.078186) (xy 171.549238 -22.128921) (xy 171.565469 -22.18261) (xy 171.57367 -22.238096)
			(xy 171.573664 -22.294184) (xy 171.565451 -22.349668) (xy 171.549209 -22.403353) (xy 171.525286 -22.454084)
			(xy 171.510198 -22.47773) (xy 171.510198 -22.723348) (xy 171.784262 -22.723348) (xy 171.788333 -22.667726)
			(xy 171.800459 -22.613289) (xy 171.820382 -22.561198) (xy 171.847678 -22.512563) (xy 171.881764 -22.46842)
			(xy 171.921913 -22.429711) (xy 171.967271 -22.39726) (xy 172.016871 -22.371759) (xy 172.069655 -22.353752)
			(xy 172.124498 -22.343622) (xy 172.180232 -22.341585) (xy 172.235669 -22.347685) (xy 172.289626 -22.361791)
			(xy 172.340955 -22.383603) (xy 172.388561 -22.412657) (xy 172.431429 -22.448332) (xy 172.468646 -22.489869)
			(xy 172.499419 -22.536382) (xy 172.523091 -22.586879) (xy 172.539159 -22.640286) (xy 172.547279 -22.695462)
			(xy 172.547788 -22.723348) (xy 172.547279 -22.751234) (xy 172.539159 -22.80641) (xy 172.523091 -22.859817)
			(xy 172.499419 -22.910314) (xy 172.468646 -22.956827) (xy 172.431429 -22.998364) (xy 172.388561 -23.034039)
			(xy 172.340955 -23.063093) (xy 172.289626 -23.084905) (xy 172.235669 -23.099011) (xy 172.180232 -23.105111)
			(xy 172.124498 -23.103074) (xy 172.069655 -23.092944) (xy 172.016871 -23.074937) (xy 171.967271 -23.049436)
			(xy 171.921913 -23.016985) (xy 171.881764 -22.978276) (xy 171.847678 -22.934133) (xy 171.820382 -22.885498)
			(xy 171.800459 -22.833407) (xy 171.788333 -22.77897) (xy 171.784262 -22.723348) (xy 171.510198 -22.723348)
			(xy 171.510198 -24.126952) (xy 186.503562 -24.126952) (xy 186.507633 -24.07133) (xy 186.519759 -24.016893)
			(xy 186.539682 -23.964802) (xy 186.566978 -23.916167) (xy 186.601064 -23.872024) (xy 186.641213 -23.833315)
			(xy 186.686571 -23.800864) (xy 186.736171 -23.775363) (xy 186.788955 -23.757356) (xy 186.843798 -23.747226)
			(xy 186.899532 -23.745189) (xy 186.954969 -23.751289) (xy 187.008926 -23.765395) (xy 187.060255 -23.787207)
			(xy 187.107861 -23.816261) (xy 187.150729 -23.851936) (xy 187.187946 -23.893473) (xy 187.218719 -23.939986)
			(xy 187.242391 -23.990483) (xy 187.256244 -24.036528) (xy 188.856872 -24.036528) (xy 188.860943 -23.980906)
			(xy 188.873069 -23.926469) (xy 188.892992 -23.874378) (xy 188.920288 -23.825743) (xy 188.954374 -23.7816)
			(xy 188.994523 -23.742891) (xy 189.039881 -23.71044) (xy 189.089481 -23.684939) (xy 189.142265 -23.666932)
			(xy 189.197108 -23.656802) (xy 189.252842 -23.654765) (xy 189.308279 -23.660865) (xy 189.362236 -23.674971)
			(xy 189.413565 -23.696783) (xy 189.461171 -23.725837) (xy 189.504039 -23.761512) (xy 189.541256 -23.803049)
			(xy 189.572029 -23.849562) (xy 189.595701 -23.900059) (xy 189.611769 -23.953466) (xy 189.619889 -24.008642)
			(xy 189.620398 -24.036528) (xy 189.619889 -24.064414) (xy 189.611769 -24.11959) (xy 189.595701 -24.172997)
			(xy 189.572029 -24.223494) (xy 189.541256 -24.270007) (xy 189.504039 -24.311544) (xy 189.461171 -24.347219)
			(xy 189.413565 -24.376273) (xy 189.362236 -24.398085) (xy 189.308279 -24.412191) (xy 189.252842 -24.418291)
			(xy 189.197108 -24.416254) (xy 189.142265 -24.406124) (xy 189.089481 -24.388117) (xy 189.039881 -24.362616)
			(xy 188.994523 -24.330165) (xy 188.954374 -24.291456) (xy 188.920288 -24.247313) (xy 188.892992 -24.198678)
			(xy 188.873069 -24.146587) (xy 188.860943 -24.09215) (xy 188.856872 -24.036528) (xy 187.256244 -24.036528)
			(xy 187.258459 -24.04389) (xy 187.266579 -24.099066) (xy 187.267088 -24.126952) (xy 187.266579 -24.154838)
			(xy 187.258459 -24.210014) (xy 187.242391 -24.263421) (xy 187.218719 -24.313918) (xy 187.187946 -24.360431)
			(xy 187.150729 -24.401968) (xy 187.107861 -24.437643) (xy 187.060255 -24.466697) (xy 187.008926 -24.488509)
			(xy 186.954969 -24.502615) (xy 186.899532 -24.508715) (xy 186.843798 -24.506678) (xy 186.788955 -24.496548)
			(xy 186.736171 -24.478541) (xy 186.686571 -24.45304) (xy 186.641213 -24.420589) (xy 186.601064 -24.38188)
			(xy 186.566978 -24.337737) (xy 186.539682 -24.289102) (xy 186.519759 -24.237011) (xy 186.507633 -24.182574)
			(xy 186.503562 -24.126952) (xy 171.510198 -24.126952) (xy 171.510198 -25.517348) (xy 179.124862 -25.517348)
			(xy 179.128933 -25.461726) (xy 179.141059 -25.407289) (xy 179.160982 -25.355198) (xy 179.188278 -25.306563)
			(xy 179.222364 -25.26242) (xy 179.262513 -25.223711) (xy 179.307871 -25.19126) (xy 179.357471 -25.165759)
			(xy 179.410255 -25.147752) (xy 179.465098 -25.137622) (xy 179.520832 -25.135585) (xy 179.576269 -25.141685)
			(xy 179.630226 -25.155791) (xy 179.681555 -25.177603) (xy 179.729161 -25.206657) (xy 179.772029 -25.242332)
			(xy 179.809246 -25.283869) (xy 179.840019 -25.330382) (xy 179.863691 -25.380879) (xy 179.879759 -25.434286)
			(xy 179.887879 -25.489462) (xy 179.888388 -25.517348) (xy 179.887879 -25.545234) (xy 179.879759 -25.60041)
			(xy 179.863691 -25.653817) (xy 179.840019 -25.704314) (xy 179.809246 -25.750827) (xy 179.772029 -25.792364)
			(xy 179.73624 -25.822148) (xy 186.744862 -25.822148) (xy 186.748933 -25.766526) (xy 186.761059 -25.712089)
			(xy 186.780982 -25.659998) (xy 186.808278 -25.611363) (xy 186.842364 -25.56722) (xy 186.882513 -25.528511)
			(xy 186.927871 -25.49606) (xy 186.977471 -25.470559) (xy 187.030255 -25.452552) (xy 187.085098 -25.442422)
			(xy 187.140832 -25.440385) (xy 187.196269 -25.446485) (xy 187.250226 -25.460591) (xy 187.301555 -25.482403)
			(xy 187.349161 -25.511457) (xy 187.392029 -25.547132) (xy 187.429246 -25.588669) (xy 187.460019 -25.635182)
			(xy 187.483691 -25.685679) (xy 187.499759 -25.739086) (xy 187.507879 -25.794262) (xy 187.508388 -25.822148)
			(xy 187.507879 -25.850034) (xy 187.499759 -25.90521) (xy 187.483691 -25.958617) (xy 187.460019 -26.009114)
			(xy 187.429246 -26.055627) (xy 187.392029 -26.097164) (xy 187.349161 -26.132839) (xy 187.301555 -26.161893)
			(xy 187.250226 -26.183705) (xy 187.196269 -26.197811) (xy 187.140832 -26.203911) (xy 187.085098 -26.201874)
			(xy 187.030255 -26.191744) (xy 186.977471 -26.173737) (xy 186.927871 -26.148236) (xy 186.882513 -26.115785)
			(xy 186.842364 -26.077076) (xy 186.808278 -26.032933) (xy 186.780982 -25.984298) (xy 186.761059 -25.932207)
			(xy 186.748933 -25.87777) (xy 186.744862 -25.822148) (xy 179.73624 -25.822148) (xy 179.729161 -25.828039)
			(xy 179.681555 -25.857093) (xy 179.630226 -25.878905) (xy 179.576269 -25.893011) (xy 179.520832 -25.899111)
			(xy 179.465098 -25.897074) (xy 179.410255 -25.886944) (xy 179.357471 -25.868937) (xy 179.307871 -25.843436)
			(xy 179.262513 -25.810985) (xy 179.222364 -25.772276) (xy 179.188278 -25.728133) (xy 179.160982 -25.679498)
			(xy 179.141059 -25.627407) (xy 179.128933 -25.57297) (xy 179.124862 -25.517348) (xy 171.510198 -25.517348)
			(xy 171.510198 -26.666748) (xy 171.777698 -26.666748) (xy 171.777698 -26.612252) (xy 171.785453 -26.558311)
			(xy 171.800805 -26.506022) (xy 171.823442 -26.45645) (xy 171.852903 -26.410604) (xy 171.888589 -26.369417)
			(xy 171.929772 -26.333727) (xy 171.975615 -26.304262) (xy 172.025184 -26.281619) (xy 172.077472 -26.266262)
			(xy 172.131412 -26.258501) (xy 172.15866 -26.258012) (xy 172.185096 -26.258433) (xy 172.237461 -26.265724)
			(xy 172.28832 -26.280173) (xy 172.336698 -26.301502) (xy 172.381669 -26.329303) (xy 172.422373 -26.363046)
			(xy 172.458031 -26.402082) (xy 172.473366 -26.42362) (xy 172.482357 -26.435682) (xy 172.505832 -26.454465)
			(xy 172.533759 -26.465597) (xy 172.563718 -26.468116) (xy 172.593112 -26.461801) (xy 172.619393 -26.447202)
			(xy 172.640285 -26.425582) (xy 172.64761 -26.412444) (xy 172.659887 -26.389266) (xy 172.689873 -26.34623)
			(xy 172.725473 -26.307711) (xy 172.766017 -26.274434) (xy 172.810739 -26.247028) (xy 172.858795 -26.22601)
			(xy 172.909279 -26.211776) (xy 172.961236 -26.204596) (xy 172.987462 -26.204164) (xy 173.014715 -26.204681)
			(xy 173.068666 -26.212433) (xy 173.120964 -26.227784) (xy 173.170546 -26.250423) (xy 173.2164 -26.279888)
			(xy 173.257594 -26.315579) (xy 173.293289 -26.356769) (xy 173.322759 -26.402621) (xy 173.345402 -26.4522)
			(xy 173.360759 -26.504497) (xy 173.368517 -26.558447) (xy 173.368517 -26.612953) (xy 173.365354 -26.634948)
			(xy 175.950372 -26.634948) (xy 175.950906 -26.607186) (xy 175.958947 -26.552249) (xy 175.974868 -26.499058)
			(xy 175.998332 -26.448736) (xy 176.028842 -26.402347) (xy 176.065755 -26.360872) (xy 176.10829 -26.325185)
			(xy 176.155549 -26.296041) (xy 176.206534 -26.274056) (xy 176.260168 -26.259694) (xy 176.287684 -26.25598)
			(xy 176.301308 -26.253896) (xy 176.326816 -26.243495) (xy 176.348612 -26.226649) (xy 176.365105 -26.204584)
			(xy 176.375093 -26.178912) (xy 176.377847 -26.151502) (xy 176.373168 -26.124356) (xy 176.367694 -26.111708)
			(xy 176.356212 -26.086166) (xy 176.340041 -26.03255) (xy 176.331865 -25.977149) (xy 176.331372 -25.949148)
			(xy 176.331858 -25.921897) (xy 176.339614 -25.867949) (xy 176.354969 -25.815654) (xy 176.377611 -25.766077)
			(xy 176.407077 -25.720227) (xy 176.442768 -25.679036) (xy 176.483959 -25.643345) (xy 176.529809 -25.613879)
			(xy 176.579386 -25.591237) (xy 176.631681 -25.575882) (xy 176.685629 -25.568126) (xy 176.740131 -25.568126)
			(xy 176.794079 -25.575882) (xy 176.846374 -25.591237) (xy 176.895951 -25.613879) (xy 176.941801 -25.643345)
			(xy 176.982992 -25.679036) (xy 177.018683 -25.720227) (xy 177.048149 -25.766077) (xy 177.070791 -25.815654)
			(xy 177.086146 -25.867949) (xy 177.093902 -25.921897) (xy 177.094388 -25.949148) (xy 177.093906 -25.977474)
			(xy 177.085563 -26.033509) (xy 177.069023 -26.087693) (xy 177.057304 -26.113486) (xy 177.051815 -26.126112)
			(xy 177.047046 -26.153215) (xy 177.049687 -26.180608) (xy 177.059546 -26.206301) (xy 177.075906 -26.228429)
			(xy 177.097581 -26.245385) (xy 177.122996 -26.255939) (xy 177.150306 -26.259324) (xy 177.163984 -26.257758)
			(xy 177.176684 -26.25598) (xy 177.190308 -26.253896) (xy 177.215816 -26.243495) (xy 177.237612 -26.226649)
			(xy 177.254105 -26.204584) (xy 177.264093 -26.178912) (xy 177.266847 -26.151502) (xy 177.262168 -26.124356)
			(xy 177.256694 -26.111708) (xy 177.245212 -26.086166) (xy 177.229041 -26.03255) (xy 177.220865 -25.977149)
			(xy 177.220372 -25.949148) (xy 177.220858 -25.921897) (xy 177.228614 -25.867949) (xy 177.243969 -25.815654)
			(xy 177.266611 -25.766077) (xy 177.296077 -25.720227) (xy 177.331768 -25.679036) (xy 177.372959 -25.643345)
			(xy 177.418809 -25.613879) (xy 177.468386 -25.591237) (xy 177.520681 -25.575882) (xy 177.574629 -25.568126)
			(xy 177.629131 -25.568126) (xy 177.683079 -25.575882) (xy 177.735374 -25.591237) (xy 177.784951 -25.613879)
			(xy 177.830801 -25.643345) (xy 177.871992 -25.679036) (xy 177.907683 -25.720227) (xy 177.937149 -25.766077)
			(xy 177.959791 -25.815654) (xy 177.975146 -25.867949) (xy 177.982902 -25.921897) (xy 177.983388 -25.949148)
			(xy 177.982906 -25.977474) (xy 177.974563 -26.033509) (xy 177.958023 -26.087693) (xy 177.946304 -26.113486)
			(xy 177.940815 -26.126112) (xy 177.936046 -26.153215) (xy 177.938687 -26.180608) (xy 177.948546 -26.206301)
			(xy 177.964906 -26.228429) (xy 177.986581 -26.245385) (xy 178.011996 -26.255939) (xy 178.039306 -26.259324)
			(xy 178.052984 -26.257758) (xy 178.065684 -26.25598) (xy 178.079308 -26.253896) (xy 178.104816 -26.243495)
			(xy 178.126612 -26.226649) (xy 178.143105 -26.204584) (xy 178.153093 -26.178912) (xy 178.155847 -26.151502)
			(xy 178.151168 -26.124356) (xy 178.145694 -26.111708) (xy 178.134212 -26.086166) (xy 178.118041 -26.03255)
			(xy 178.109865 -25.977149) (xy 178.109372 -25.949148) (xy 178.109858 -25.921897) (xy 178.117614 -25.867949)
			(xy 178.132969 -25.815654) (xy 178.155611 -25.766077) (xy 178.185077 -25.720227) (xy 178.220768 -25.679036)
			(xy 178.261959 -25.643345) (xy 178.307809 -25.613879) (xy 178.357386 -25.591237) (xy 178.409681 -25.575882)
			(xy 178.463629 -25.568126) (xy 178.518131 -25.568126) (xy 178.572079 -25.575882) (xy 178.624374 -25.591237)
			(xy 178.673951 -25.613879) (xy 178.719801 -25.643345) (xy 178.760992 -25.679036) (xy 178.796683 -25.720227)
			(xy 178.826149 -25.766077) (xy 178.848791 -25.815654) (xy 178.864146 -25.867949) (xy 178.871902 -25.921897)
			(xy 178.872388 -25.949148) (xy 178.871886 -25.976911) (xy 178.863844 -26.031852) (xy 178.847921 -26.085046)
			(xy 178.824455 -26.135369) (xy 178.793942 -26.18176) (xy 178.757025 -26.223236) (xy 178.714485 -26.258922)
			(xy 178.667221 -26.288064) (xy 178.616232 -26.310046) (xy 178.562594 -26.324404) (xy 178.535076 -26.328116)
			(xy 178.521432 -26.330108) (xy 178.495903 -26.340509) (xy 178.474092 -26.357367) (xy 178.457592 -26.37945)
			(xy 178.447608 -26.405145) (xy 178.444869 -26.432575) (xy 178.449576 -26.459737) (xy 178.455066 -26.472388)
			(xy 178.466551 -26.497929) (xy 178.482719 -26.551546) (xy 178.490895 -26.606947) (xy 178.491388 -26.634948)
			(xy 178.490902 -26.662199) (xy 178.483146 -26.716147) (xy 178.467791 -26.768442) (xy 178.445149 -26.818019)
			(xy 178.415683 -26.863869) (xy 178.379992 -26.90506) (xy 178.338801 -26.940751) (xy 178.292951 -26.970217)
			(xy 178.243374 -26.992859) (xy 178.191079 -27.008214) (xy 178.137131 -27.01597) (xy 178.082629 -27.01597)
			(xy 178.028681 -27.008214) (xy 177.976386 -26.992859) (xy 177.926809 -26.970217) (xy 177.880959 -26.940751)
			(xy 177.839768 -26.90506) (xy 177.804077 -26.863869) (xy 177.774611 -26.818019) (xy 177.751969 -26.768442)
			(xy 177.736614 -26.716147) (xy 177.728858 -26.662199) (xy 177.728372 -26.634948) (xy 177.728856 -26.606622)
			(xy 177.737199 -26.550587) (xy 177.753737 -26.496403) (xy 177.765456 -26.47061) (xy 177.770991 -26.458001)
			(xy 177.775763 -26.430889) (xy 177.773122 -26.403487) (xy 177.763258 -26.377786) (xy 177.74689 -26.355653)
			(xy 177.725205 -26.338695) (xy 177.699778 -26.328144) (xy 177.672458 -26.324766) (xy 177.658776 -26.326338)
			(xy 177.646076 -26.328116) (xy 177.632432 -26.330108) (xy 177.606903 -26.340509) (xy 177.585092 -26.357367)
			(xy 177.568592 -26.37945) (xy 177.558608 -26.405145) (xy 177.555869 -26.432575) (xy 177.560576 -26.459737)
			(xy 177.566066 -26.472388) (xy 177.577551 -26.497929) (xy 177.593719 -26.551546) (xy 177.601895 -26.606947)
			(xy 177.602388 -26.634948) (xy 177.601902 -26.662199) (xy 177.594146 -26.716147) (xy 177.578791 -26.768442)
			(xy 177.556149 -26.818019) (xy 177.526683 -26.863869) (xy 177.490992 -26.90506) (xy 177.449801 -26.940751)
			(xy 177.403951 -26.970217) (xy 177.354374 -26.992859) (xy 177.302079 -27.008214) (xy 177.248131 -27.01597)
			(xy 177.193629 -27.01597) (xy 177.139681 -27.008214) (xy 177.087386 -26.992859) (xy 177.037809 -26.970217)
			(xy 176.991959 -26.940751) (xy 176.950768 -26.90506) (xy 176.915077 -26.863869) (xy 176.885611 -26.818019)
			(xy 176.862969 -26.768442) (xy 176.847614 -26.716147) (xy 176.839858 -26.662199) (xy 176.839372 -26.634948)
			(xy 176.839856 -26.606622) (xy 176.848199 -26.550587) (xy 176.864737 -26.496403) (xy 176.876456 -26.47061)
			(xy 176.881991 -26.458001) (xy 176.886763 -26.430889) (xy 176.884122 -26.403487) (xy 176.874258 -26.377786)
			(xy 176.85789 -26.355653) (xy 176.836205 -26.338695) (xy 176.810778 -26.328144) (xy 176.783458 -26.324766)
			(xy 176.769776 -26.326338) (xy 176.757076 -26.328116) (xy 176.743432 -26.330108) (xy 176.717903 -26.340509)
			(xy 176.696092 -26.357367) (xy 176.679592 -26.37945) (xy 176.669608 -26.405145) (xy 176.666869 -26.432575)
			(xy 176.671576 -26.459737) (xy 176.677066 -26.472388) (xy 176.688551 -26.497929) (xy 176.704719 -26.551546)
			(xy 176.712895 -26.606947) (xy 176.713388 -26.634948) (xy 176.712902 -26.662199) (xy 176.705146 -26.716147)
			(xy 176.689791 -26.768442) (xy 176.667149 -26.818019) (xy 176.637683 -26.863869) (xy 176.601992 -26.90506)
			(xy 176.560801 -26.940751) (xy 176.514951 -26.970217) (xy 176.465374 -26.992859) (xy 176.413079 -27.008214)
			(xy 176.359131 -27.01597) (xy 176.304629 -27.01597) (xy 176.250681 -27.008214) (xy 176.198386 -26.992859)
			(xy 176.148809 -26.970217) (xy 176.102959 -26.940751) (xy 176.061768 -26.90506) (xy 176.026077 -26.863869)
			(xy 175.996611 -26.818019) (xy 175.973969 -26.768442) (xy 175.958614 -26.716147) (xy 175.950858 -26.662199)
			(xy 175.950372 -26.634948) (xy 173.365354 -26.634948) (xy 173.360759 -26.666903) (xy 173.345402 -26.7192)
			(xy 173.322759 -26.768779) (xy 173.293289 -26.814631) (xy 173.257594 -26.855821) (xy 173.2164 -26.891512)
			(xy 173.170546 -26.920977) (xy 173.120964 -26.943616) (xy 173.068666 -26.958967) (xy 173.014715 -26.966719)
			(xy 172.987462 -26.96718) (xy 172.961027 -26.966746) (xy 172.908661 -26.959457) (xy 172.857803 -26.945012)
			(xy 172.809425 -26.923685) (xy 172.764454 -26.895885) (xy 172.723749 -26.862145) (xy 172.688091 -26.823109)
			(xy 172.672756 -26.801572) (xy 172.663864 -26.789432) (xy 172.640365 -26.770649) (xy 172.612416 -26.759521)
			(xy 172.582438 -26.757013) (xy 172.553028 -26.763343) (xy 172.526735 -26.77796) (xy 172.505838 -26.7996)
			(xy 172.498512 -26.812748) (xy 172.486215 -26.835915) (xy 172.456232 -26.87895) (xy 172.420635 -26.91747)
			(xy 172.380094 -26.950748) (xy 172.335375 -26.978156) (xy 172.287321 -26.999176) (xy 172.23684 -27.013412)
			(xy 172.184885 -27.020595) (xy 172.15866 -27.021028) (xy 172.131412 -27.020499) (xy 172.077472 -27.012738)
			(xy 172.025184 -26.997381) (xy 171.975615 -26.974738) (xy 171.929772 -26.945273) (xy 171.888589 -26.909583)
			(xy 171.852903 -26.868396) (xy 171.823442 -26.82255) (xy 171.800805 -26.772978) (xy 171.785453 -26.720689)
			(xy 171.777698 -26.666748) (xy 171.510198 -26.666748) (xy 171.510198 -27.107388) (xy 180.539642 -27.107388)
			(xy 180.543713 -27.051766) (xy 180.555839 -26.997329) (xy 180.575762 -26.945238) (xy 180.603058 -26.896603)
			(xy 180.637144 -26.85246) (xy 180.677293 -26.813751) (xy 180.722651 -26.7813) (xy 180.772251 -26.755799)
			(xy 180.825035 -26.737792) (xy 180.879878 -26.727662) (xy 180.935612 -26.725625) (xy 180.991049 -26.731725)
			(xy 181.045006 -26.745831) (xy 181.096335 -26.767643) (xy 181.143941 -26.796697) (xy 181.186809 -26.832372)
			(xy 181.224026 -26.873909) (xy 181.254799 -26.920422) (xy 181.278471 -26.970919) (xy 181.294539 -27.024326)
			(xy 181.302659 -27.079502) (xy 181.302797 -27.087068) (xy 190.295782 -27.087068) (xy 190.299853 -27.031446)
			(xy 190.311979 -26.977009) (xy 190.331902 -26.924918) (xy 190.359198 -26.876283) (xy 190.393284 -26.83214)
			(xy 190.433433 -26.793431) (xy 190.478791 -26.76098) (xy 190.528391 -26.735479) (xy 190.581175 -26.717472)
			(xy 190.636018 -26.707342) (xy 190.691752 -26.705305) (xy 190.747189 -26.711405) (xy 190.801146 -26.725511)
			(xy 190.852475 -26.747323) (xy 190.900081 -26.776377) (xy 190.942949 -26.812052) (xy 190.980166 -26.853589)
			(xy 191.010939 -26.900102) (xy 191.034611 -26.950599) (xy 191.050679 -27.004006) (xy 191.058799 -27.059182)
			(xy 191.059308 -27.087068) (xy 191.058799 -27.114954) (xy 191.050679 -27.17013) (xy 191.034611 -27.223537)
			(xy 191.010939 -27.274034) (xy 190.980166 -27.320547) (xy 190.942949 -27.362084) (xy 190.900081 -27.397759)
			(xy 190.852475 -27.426813) (xy 190.801146 -27.448625) (xy 190.747189 -27.462731) (xy 190.691752 -27.468831)
			(xy 190.636018 -27.466794) (xy 190.581175 -27.456664) (xy 190.528391 -27.438657) (xy 190.478791 -27.413156)
			(xy 190.433433 -27.380705) (xy 190.393284 -27.341996) (xy 190.359198 -27.297853) (xy 190.331902 -27.249218)
			(xy 190.311979 -27.197127) (xy 190.299853 -27.14269) (xy 190.295782 -27.087068) (xy 181.302797 -27.087068)
			(xy 181.303168 -27.107388) (xy 181.302659 -27.135274) (xy 181.294539 -27.19045) (xy 181.278471 -27.243857)
			(xy 181.254799 -27.294354) (xy 181.224026 -27.340867) (xy 181.186809 -27.382404) (xy 181.143941 -27.418079)
			(xy 181.096335 -27.447133) (xy 181.045006 -27.468945) (xy 180.991049 -27.483051) (xy 180.935612 -27.489151)
			(xy 180.879878 -27.487114) (xy 180.825035 -27.476984) (xy 180.772251 -27.458977) (xy 180.722651 -27.433476)
			(xy 180.677293 -27.401025) (xy 180.637144 -27.362316) (xy 180.603058 -27.318173) (xy 180.575762 -27.269538)
			(xy 180.555839 -27.217447) (xy 180.543713 -27.16301) (xy 180.539642 -27.107388) (xy 171.510198 -27.107388)
			(xy 171.510198 -28.563824) (xy 171.529649 -28.585182) (xy 171.562538 -28.63267) (xy 171.587888 -28.684576)
			(xy 171.600476 -28.72486) (xy 174.124112 -28.72486) (xy 174.124575 -28.698208) (xy 174.132012 -28.645427)
			(xy 174.146724 -28.594193) (xy 174.168422 -28.545506) (xy 174.196685 -28.500313) (xy 174.230963 -28.459493)
			(xy 174.270589 -28.423841) (xy 174.31479 -28.39405) (xy 174.362708 -28.370701) (xy 174.413408 -28.354249)
			(xy 174.43958 -28.349194) (xy 174.453331 -28.346366) (xy 174.47862 -28.334198) (xy 174.499643 -28.315607)
			(xy 174.514814 -28.291997) (xy 174.522988 -28.265149) (xy 174.523549 -28.237091) (xy 174.516453 -28.209938)
			(xy 174.502236 -28.185742) (xy 174.492412 -28.175712) (xy 174.474221 -28.157679) (xy 174.442384 -28.117553)
			(xy 174.416201 -28.073528) (xy 174.396143 -28.026396) (xy 174.38257 -27.977005) (xy 174.375727 -27.926241)
			(xy 174.375318 -27.90063) (xy 174.375804 -27.873379) (xy 174.38356 -27.819431) (xy 174.398915 -27.767136)
			(xy 174.421557 -27.717559) (xy 174.451023 -27.671709) (xy 174.486714 -27.630518) (xy 174.527905 -27.594827)
			(xy 174.573755 -27.565361) (xy 174.623332 -27.542719) (xy 174.675627 -27.527364) (xy 174.729575 -27.519608)
			(xy 174.784077 -27.519608) (xy 174.838025 -27.527364) (xy 174.848882 -27.530552) (xy 185.020964 -27.530552)
			(xy 185.025035 -27.47493) (xy 185.037161 -27.420493) (xy 185.057084 -27.368402) (xy 185.08438 -27.319767)
			(xy 185.118466 -27.275624) (xy 185.158615 -27.236915) (xy 185.203973 -27.204464) (xy 185.253573 -27.178963)
			(xy 185.306357 -27.160956) (xy 185.3612 -27.150826) (xy 185.416934 -27.148789) (xy 185.472371 -27.154889)
			(xy 185.526328 -27.168995) (xy 185.577657 -27.190807) (xy 185.625263 -27.219861) (xy 185.668131 -27.255536)
			(xy 185.705348 -27.297073) (xy 185.736121 -27.343586) (xy 185.759793 -27.394083) (xy 185.775861 -27.44749)
			(xy 185.783981 -27.502666) (xy 185.78449 -27.530552) (xy 185.783981 -27.558438) (xy 185.775861 -27.613614)
			(xy 185.773799 -27.620468) (xy 187.910214 -27.620468) (xy 187.914285 -27.564846) (xy 187.926411 -27.510409)
			(xy 187.946334 -27.458318) (xy 187.97363 -27.409683) (xy 188.007716 -27.36554) (xy 188.047865 -27.326831)
			(xy 188.093223 -27.29438) (xy 188.142823 -27.268879) (xy 188.195607 -27.250872) (xy 188.25045 -27.240742)
			(xy 188.306184 -27.238705) (xy 188.361621 -27.244805) (xy 188.415578 -27.258911) (xy 188.466907 -27.280723)
			(xy 188.514513 -27.309777) (xy 188.557381 -27.345452) (xy 188.594598 -27.386989) (xy 188.625371 -27.433502)
			(xy 188.649043 -27.483999) (xy 188.665111 -27.537406) (xy 188.67098 -27.577288) (xy 189.414402 -27.577288)
			(xy 189.418473 -27.521666) (xy 189.430599 -27.467229) (xy 189.450522 -27.415138) (xy 189.477818 -27.366503)
			(xy 189.511904 -27.32236) (xy 189.552053 -27.283651) (xy 189.597411 -27.2512) (xy 189.647011 -27.225699)
			(xy 189.699795 -27.207692) (xy 189.754638 -27.197562) (xy 189.810372 -27.195525) (xy 189.865809 -27.201625)
			(xy 189.919766 -27.215731) (xy 189.971095 -27.237543) (xy 190.018701 -27.266597) (xy 190.061569 -27.302272)
			(xy 190.098786 -27.343809) (xy 190.129559 -27.390322) (xy 190.153231 -27.440819) (xy 190.169299 -27.494226)
			(xy 190.177419 -27.549402) (xy 190.177928 -27.577288) (xy 190.177419 -27.605174) (xy 190.169299 -27.66035)
			(xy 190.153231 -27.713757) (xy 190.129559 -27.764254) (xy 190.098786 -27.810767) (xy 190.061569 -27.852304)
			(xy 190.018701 -27.887979) (xy 189.971095 -27.917033) (xy 189.919766 -27.938845) (xy 189.865809 -27.952951)
			(xy 189.810372 -27.959051) (xy 189.754638 -27.957014) (xy 189.699795 -27.946884) (xy 189.647011 -27.928877)
			(xy 189.597411 -27.903376) (xy 189.552053 -27.870925) (xy 189.511904 -27.832216) (xy 189.477818 -27.788073)
			(xy 189.450522 -27.739438) (xy 189.430599 -27.687347) (xy 189.418473 -27.63291) (xy 189.414402 -27.577288)
			(xy 188.67098 -27.577288) (xy 188.673231 -27.592582) (xy 188.67374 -27.620468) (xy 188.673231 -27.648354)
			(xy 188.665111 -27.70353) (xy 188.649043 -27.756937) (xy 188.625371 -27.807434) (xy 188.594598 -27.853947)
			(xy 188.557381 -27.895484) (xy 188.514513 -27.931159) (xy 188.466907 -27.960213) (xy 188.415578 -27.982025)
			(xy 188.361621 -27.996131) (xy 188.306184 -28.002231) (xy 188.25045 -28.000194) (xy 188.195607 -27.990064)
			(xy 188.142823 -27.972057) (xy 188.093223 -27.946556) (xy 188.047865 -27.914105) (xy 188.007716 -27.875396)
			(xy 187.97363 -27.831253) (xy 187.946334 -27.782618) (xy 187.926411 -27.730527) (xy 187.914285 -27.67609)
			(xy 187.910214 -27.620468) (xy 185.773799 -27.620468) (xy 185.759793 -27.667021) (xy 185.736121 -27.717518)
			(xy 185.705348 -27.764031) (xy 185.668131 -27.805568) (xy 185.625263 -27.841243) (xy 185.577657 -27.870297)
			(xy 185.526328 -27.892109) (xy 185.472371 -27.906215) (xy 185.416934 -27.912315) (xy 185.3612 -27.910278)
			(xy 185.306357 -27.900148) (xy 185.253573 -27.882141) (xy 185.203973 -27.85664) (xy 185.158615 -27.824189)
			(xy 185.118466 -27.78548) (xy 185.08438 -27.741337) (xy 185.057084 -27.692702) (xy 185.037161 -27.640611)
			(xy 185.025035 -27.586174) (xy 185.020964 -27.530552) (xy 174.848882 -27.530552) (xy 174.89032 -27.542719)
			(xy 174.939897 -27.565361) (xy 174.985747 -27.594827) (xy 175.026938 -27.630518) (xy 175.062629 -27.671709)
			(xy 175.092095 -27.717559) (xy 175.114737 -27.767136) (xy 175.130092 -27.819431) (xy 175.137848 -27.873379)
			(xy 175.138334 -27.90063) (xy 175.137803 -27.927278) (xy 175.130368 -27.980053) (xy 175.115661 -28.03128)
			(xy 175.093968 -28.079962) (xy 175.065711 -28.125152) (xy 175.031441 -28.165969) (xy 174.991824 -28.20162)
			(xy 174.947631 -28.231411) (xy 174.899722 -28.254761) (xy 174.84903 -28.271218) (xy 174.822866 -28.276296)
			(xy 174.809122 -28.279158) (xy 174.78383 -28.291316) (xy 174.762802 -28.3099) (xy 174.747628 -28.333506)
			(xy 174.739451 -28.360351) (xy 174.738891 -28.388408) (xy 174.745988 -28.415558) (xy 174.760208 -28.439751)
			(xy 174.770034 -28.449778) (xy 174.78821 -28.467826) (xy 174.820051 -28.507948) (xy 174.846237 -28.551969)
			(xy 174.866298 -28.599098) (xy 174.879873 -28.648488) (xy 174.886718 -28.699249) (xy 174.887128 -28.72486)
			(xy 174.886664 -28.751206) (xy 174.879435 -28.8034) (xy 174.865096 -28.854104) (xy 174.843918 -28.902353)
			(xy 174.816306 -28.947231) (xy 174.782782 -28.987884) (xy 174.763684 -29.006038) (xy 174.753683 -29.01594)
			(xy 174.738953 -29.039903) (xy 174.731317 -29.066975) (xy 174.731356 -29.095103) (xy 174.739065 -29.122154)
			(xy 174.753862 -29.146076) (xy 174.763938 -29.155898) (xy 174.783138 -29.17405) (xy 174.816857 -29.214727)
			(xy 174.841886 -29.255212) (xy 176.187862 -29.255212) (xy 176.188401 -29.227892) (xy 176.196736 -29.173892)
			(xy 176.213214 -29.121796) (xy 176.237447 -29.072824) (xy 176.268869 -29.028123) (xy 176.28743 -29.00807)
			(xy 176.297817 -28.996439) (xy 176.311645 -28.968509) (xy 176.316404 -28.937709) (xy 176.311651 -28.906908)
			(xy 176.297827 -28.878975) (xy 176.28743 -28.867354) (xy 176.268809 -28.847348) (xy 176.237352 -28.802654)
			(xy 176.213104 -28.753673) (xy 176.196635 -28.701559) (xy 176.188332 -28.64754) (xy 176.187862 -28.620212)
			(xy 176.18836 -28.593563) (xy 176.196303 -28.540859) (xy 176.212013 -28.489929) (xy 176.235139 -28.441908)
			(xy 176.265163 -28.397871) (xy 176.301415 -28.3588) (xy 176.343086 -28.325569) (xy 176.389244 -28.29892)
			(xy 176.438858 -28.279448) (xy 176.49082 -28.267588) (xy 176.54397 -28.263605) (xy 176.59712 -28.267588)
			(xy 176.649082 -28.279448) (xy 176.698696 -28.29892) (xy 176.744854 -28.325569) (xy 176.786525 -28.3588)
			(xy 176.822777 -28.397871) (xy 176.852801 -28.441908) (xy 176.875927 -28.489929) (xy 176.891637 -28.540859)
			(xy 176.89958 -28.593563) (xy 176.900078 -28.620212) (xy 176.89957 -28.647533) (xy 176.89123 -28.701536)
			(xy 176.874746 -28.753633) (xy 176.850505 -28.802604) (xy 176.819075 -28.847302) (xy 176.80051 -28.867354)
			(xy 176.790105 -28.878968) (xy 176.776287 -28.906905) (xy 176.771535 -28.937709) (xy 176.776292 -28.968511)
			(xy 176.790115 -28.996446) (xy 176.80051 -29.00807) (xy 176.819102 -29.028102) (xy 176.850561 -29.07279)
			(xy 176.874814 -29.121764) (xy 176.89129 -29.173872) (xy 176.899602 -29.227886) (xy 176.900078 -29.255212)
			(xy 177.087784 -29.255212) (xy 177.088317 -29.227892) (xy 177.096653 -29.173891) (xy 177.113131 -29.121795)
			(xy 177.137366 -29.072823) (xy 177.16879 -29.028123) (xy 177.187352 -29.00807) (xy 177.197737 -28.996438)
			(xy 177.211562 -28.968508) (xy 177.21632 -28.937709) (xy 177.211568 -28.906909) (xy 177.197747 -28.878976)
			(xy 177.187352 -28.867354) (xy 177.168734 -28.847345) (xy 177.137277 -28.802652) (xy 177.113027 -28.753672)
			(xy 177.096557 -28.701559) (xy 177.088254 -28.647539) (xy 177.087784 -28.620212) (xy 177.088282 -28.593563)
			(xy 177.096225 -28.540859) (xy 177.111935 -28.489929) (xy 177.135061 -28.441908) (xy 177.165085 -28.397871)
			(xy 177.201337 -28.3588) (xy 177.243008 -28.325569) (xy 177.289166 -28.29892) (xy 177.33878 -28.279448)
			(xy 177.390742 -28.267588) (xy 177.443892 -28.263605) (xy 177.497042 -28.267588) (xy 177.549004 -28.279448)
			(xy 177.598618 -28.29892) (xy 177.644776 -28.325569) (xy 177.686447 -28.3588) (xy 177.722699 -28.397871)
			(xy 177.752723 -28.441908) (xy 177.775849 -28.489929) (xy 177.791559 -28.540859) (xy 177.799502 -28.593563)
			(xy 177.8 -28.620212) (xy 177.799486 -28.647533) (xy 177.791146 -28.701535) (xy 177.774664 -28.753631)
			(xy 177.750424 -28.802603) (xy 177.718996 -28.847302) (xy 177.700432 -28.867354) (xy 177.690025 -28.878967)
			(xy 177.676204 -28.906904) (xy 177.671452 -28.937709) (xy 177.676209 -28.968512) (xy 177.690035 -28.996447)
			(xy 177.700432 -29.00807) (xy 177.719028 -29.028099) (xy 177.750485 -29.072788) (xy 177.774737 -29.121763)
			(xy 177.791213 -29.173871) (xy 177.799524 -29.227886) (xy 177.8 -29.255212) (xy 177.987706 -29.255212)
			(xy 177.988233 -29.227892) (xy 177.996569 -29.17389) (xy 178.013049 -29.121794) (xy 178.037285 -29.072822)
			(xy 178.068711 -29.028122) (xy 178.087274 -29.00807) (xy 178.097657 -28.996437) (xy 178.111479 -28.968507)
			(xy 178.116236 -28.937709) (xy 178.111485 -28.90691) (xy 178.097667 -28.878977) (xy 178.087274 -28.867354)
			(xy 178.068643 -28.847357) (xy 178.03719 -28.802659) (xy 178.012945 -28.753676) (xy 177.996477 -28.701561)
			(xy 177.988176 -28.64754) (xy 177.987706 -28.620212) (xy 177.988204 -28.593563) (xy 177.996147 -28.540859)
			(xy 178.011857 -28.489929) (xy 178.034983 -28.441908) (xy 178.065007 -28.397871) (xy 178.101259 -28.3588)
			(xy 178.14293 -28.325569) (xy 178.189088 -28.29892) (xy 178.238702 -28.279448) (xy 178.290664 -28.267588)
			(xy 178.343814 -28.263605) (xy 178.396964 -28.267588) (xy 178.448926 -28.279448) (xy 178.49854 -28.29892)
			(xy 178.544698 -28.325569) (xy 178.586369 -28.3588) (xy 178.622621 -28.397871) (xy 178.652645 -28.441908)
			(xy 178.675771 -28.489929) (xy 178.691481 -28.540859) (xy 178.699424 -28.593563) (xy 178.699922 -28.620212)
			(xy 178.699402 -28.647533) (xy 178.691063 -28.701534) (xy 178.674581 -28.75363) (xy 178.650344 -28.802602)
			(xy 178.618917 -28.847301) (xy 178.600354 -28.867354) (xy 178.589945 -28.878966) (xy 178.576121 -28.906903)
			(xy 178.571367 -28.937709) (xy 178.576126 -28.968513) (xy 178.589955 -28.996448) (xy 178.600354 -29.00807)
			(xy 178.618936 -29.028111) (xy 178.650399 -29.072795) (xy 178.674655 -29.121767) (xy 178.691133 -29.173873)
			(xy 178.699446 -29.227887) (xy 178.699922 -29.255212) (xy 178.887882 -29.255212) (xy 178.888415 -29.227892)
			(xy 178.896751 -29.173891) (xy 178.91323 -29.121795) (xy 178.937464 -29.072823) (xy 178.968888 -29.028123)
			(xy 178.98745 -29.00807) (xy 178.997835 -28.996438) (xy 179.011661 -28.968508) (xy 179.016419 -28.937709)
			(xy 179.011666 -28.906908) (xy 178.997845 -28.878976) (xy 178.98745 -28.867354) (xy 178.968832 -28.847345)
			(xy 178.937374 -28.802652) (xy 178.913125 -28.753672) (xy 178.896655 -28.701559) (xy 178.888352 -28.647539)
			(xy 178.887882 -28.620212) (xy 178.88838 -28.593563) (xy 178.896323 -28.540859) (xy 178.912033 -28.489929)
			(xy 178.935159 -28.441908) (xy 178.965183 -28.397871) (xy 179.001435 -28.3588) (xy 179.043106 -28.325569)
			(xy 179.089264 -28.29892) (xy 179.138878 -28.279448) (xy 179.19084 -28.267588) (xy 179.24399 -28.263605)
			(xy 179.29714 -28.267588) (xy 179.349102 -28.279448) (xy 179.398716 -28.29892) (xy 179.444874 -28.325569)
			(xy 179.486545 -28.3588) (xy 179.522797 -28.397871) (xy 179.524071 -28.39974) (xy 192.757042 -28.39974)
			(xy 192.761113 -28.344118) (xy 192.773239 -28.289681) (xy 192.793162 -28.23759) (xy 192.820458 -28.188955)
			(xy 192.854544 -28.144812) (xy 192.894693 -28.106103) (xy 192.940051 -28.073652) (xy 192.989651 -28.048151)
			(xy 193.042435 -28.030144) (xy 193.097278 -28.020014) (xy 193.153012 -28.017977) (xy 193.208449 -28.024077)
			(xy 193.262406 -28.038183) (xy 193.313735 -28.059995) (xy 193.361341 -28.089049) (xy 193.404209 -28.124724)
			(xy 193.441426 -28.166261) (xy 193.472199 -28.212774) (xy 193.495871 -28.263271) (xy 193.511939 -28.316678)
			(xy 193.520059 -28.371854) (xy 193.520568 -28.39974) (xy 193.520059 -28.427626) (xy 193.511939 -28.482802)
			(xy 193.495871 -28.536209) (xy 193.472199 -28.586706) (xy 193.441426 -28.633219) (xy 193.404209 -28.674756)
			(xy 193.361341 -28.710431) (xy 193.313735 -28.739485) (xy 193.262406 -28.761297) (xy 193.208449 -28.775403)
			(xy 193.153012 -28.781503) (xy 193.097278 -28.779466) (xy 193.042435 -28.769336) (xy 192.989651 -28.751329)
			(xy 192.940051 -28.725828) (xy 192.894693 -28.693377) (xy 192.854544 -28.654668) (xy 192.820458 -28.610525)
			(xy 192.793162 -28.56189) (xy 192.773239 -28.509799) (xy 192.761113 -28.455362) (xy 192.757042 -28.39974)
			(xy 179.524071 -28.39974) (xy 179.552821 -28.441908) (xy 179.575947 -28.489929) (xy 179.591657 -28.540859)
			(xy 179.5996 -28.593563) (xy 179.600098 -28.620212) (xy 179.599585 -28.647533) (xy 179.591245 -28.701535)
			(xy 179.574762 -28.753632) (xy 179.550523 -28.802603) (xy 179.519094 -28.847302) (xy 179.50053 -28.867354)
			(xy 179.490123 -28.878967) (xy 179.476303 -28.906904) (xy 179.47155 -28.937709) (xy 179.476308 -28.968512)
			(xy 179.490133 -28.996447) (xy 179.50053 -29.00807) (xy 179.519125 -29.028099) (xy 179.550583 -29.072788)
			(xy 179.574835 -29.121763) (xy 179.591311 -29.173871) (xy 179.599622 -29.227886) (xy 179.600098 -29.255212)
			(xy 179.5996 -29.281861) (xy 179.591657 -29.334565) (xy 179.575947 -29.385495) (xy 179.552821 -29.433516)
			(xy 179.522797 -29.477553) (xy 179.486545 -29.516624) (xy 179.444874 -29.549855) (xy 179.398716 -29.576504)
			(xy 179.349102 -29.595976) (xy 179.29714 -29.607836) (xy 179.24399 -29.61182) (xy 179.19084 -29.607836)
			(xy 179.138878 -29.595976) (xy 179.089264 -29.576504) (xy 179.043106 -29.549855) (xy 179.001435 -29.516624)
			(xy 178.965183 -29.477553) (xy 178.935159 -29.433516) (xy 178.912033 -29.385495) (xy 178.896323 -29.334565)
			(xy 178.88838 -29.281861) (xy 178.887882 -29.255212) (xy 178.699922 -29.255212) (xy 178.699424 -29.281861)
			(xy 178.691481 -29.334565) (xy 178.675771 -29.385495) (xy 178.652645 -29.433516) (xy 178.622621 -29.477553)
			(xy 178.586369 -29.516624) (xy 178.544698 -29.549855) (xy 178.49854 -29.576504) (xy 178.448926 -29.595976)
			(xy 178.396964 -29.607836) (xy 178.343814 -29.61182) (xy 178.290664 -29.607836) (xy 178.238702 -29.595976)
			(xy 178.189088 -29.576504) (xy 178.14293 -29.549855) (xy 178.101259 -29.516624) (xy 178.065007 -29.477553)
			(xy 178.034983 -29.433516) (xy 178.011857 -29.385495) (xy 177.996147 -29.334565) (xy 177.988204 -29.281861)
			(xy 177.987706 -29.255212) (xy 177.8 -29.255212) (xy 177.799502 -29.281861) (xy 177.791559 -29.334565)
			(xy 177.775849 -29.385495) (xy 177.752723 -29.433516) (xy 177.722699 -29.477553) (xy 177.686447 -29.516624)
			(xy 177.644776 -29.549855) (xy 177.598618 -29.576504) (xy 177.549004 -29.595976) (xy 177.497042 -29.607836)
			(xy 177.443892 -29.61182) (xy 177.390742 -29.607836) (xy 177.33878 -29.595976) (xy 177.289166 -29.576504)
			(xy 177.243008 -29.549855) (xy 177.201337 -29.516624) (xy 177.165085 -29.477553) (xy 177.135061 -29.433516)
			(xy 177.111935 -29.385495) (xy 177.096225 -29.334565) (xy 177.088282 -29.281861) (xy 177.087784 -29.255212)
			(xy 176.900078 -29.255212) (xy 176.89958 -29.281861) (xy 176.891637 -29.334565) (xy 176.875927 -29.385495)
			(xy 176.852801 -29.433516) (xy 176.822777 -29.477553) (xy 176.786525 -29.516624) (xy 176.744854 -29.549855)
			(xy 176.698696 -29.576504) (xy 176.649082 -29.595976) (xy 176.59712 -29.607836) (xy 176.54397 -29.61182)
			(xy 176.49082 -29.607836) (xy 176.438858 -29.595976) (xy 176.389244 -29.576504) (xy 176.343086 -29.549855)
			(xy 176.301415 -29.516624) (xy 176.265163 -29.477553) (xy 176.235139 -29.433516) (xy 176.212013 -29.385495)
			(xy 176.196303 -29.334565) (xy 176.18836 -29.281861) (xy 176.187862 -29.255212) (xy 174.841886 -29.255212)
			(xy 174.844641 -29.259668) (xy 174.865959 -29.308012) (xy 174.880402 -29.358836) (xy 174.887694 -29.411166)
			(xy 174.888144 -29.437584) (xy 174.887658 -29.464835) (xy 174.879902 -29.518783) (xy 174.864547 -29.571078)
			(xy 174.841905 -29.620655) (xy 174.812439 -29.666505) (xy 174.776748 -29.707696) (xy 174.735557 -29.743387)
			(xy 174.689707 -29.772853) (xy 174.64013 -29.795495) (xy 174.587835 -29.81085) (xy 174.533887 -29.818606)
			(xy 174.479385 -29.818606) (xy 174.425437 -29.81085) (xy 174.373142 -29.795495) (xy 174.323565 -29.772853)
			(xy 174.277715 -29.743387) (xy 174.236524 -29.707696) (xy 174.200833 -29.666505) (xy 174.171367 -29.620655)
			(xy 174.148725 -29.571078) (xy 174.13337 -29.518783) (xy 174.125614 -29.464835) (xy 174.125128 -29.437584)
			(xy 174.125537 -29.411236) (xy 174.132774 -29.359038) (xy 174.147123 -29.308333) (xy 174.168311 -29.260084)
			(xy 174.195934 -29.215207) (xy 174.229468 -29.174558) (xy 174.248572 -29.156406) (xy 174.258625 -29.146554)
			(xy 174.273344 -29.122575) (xy 174.280968 -29.095492) (xy 174.280919 -29.067355) (xy 174.2732 -29.040298)
			(xy 174.258397 -29.016371) (xy 174.248318 -29.006546) (xy 174.229102 -28.98841) (xy 174.195382 -28.947731)
			(xy 174.167599 -28.902787) (xy 174.146283 -28.854439) (xy 174.131844 -28.803612) (xy 174.124558 -28.751279)
			(xy 174.124112 -28.72486) (xy 171.600476 -28.72486) (xy 171.605117 -28.739712) (xy 171.613831 -28.796816)
			(xy 171.613831 -28.854581) (xy 171.605117 -28.911685) (xy 171.587889 -28.966822) (xy 171.56254 -29.018728)
			(xy 171.529651 -29.066216) (xy 171.510198 -29.087572) (xy 171.510198 -29.26588) (xy 171.510798 -29.281445)
			(xy 171.520241 -29.311112) (xy 171.538168 -29.336567) (xy 171.562919 -29.355453) (xy 171.592203 -29.366023)
			(xy 171.607734 -29.367226) (xy 171.631927 -29.368619) (xy 171.679697 -29.376775) (xy 171.702984 -29.383482)
			(xy 171.716684 -29.38716) (xy 171.745035 -29.387621) (xy 171.772415 -29.380252) (xy 171.796705 -29.365622)
			(xy 171.816023 -29.344866) (xy 171.828872 -29.31959) (xy 171.832016 -29.305758) (xy 171.838231 -29.277245)
			(xy 171.858153 -29.222395) (xy 171.886188 -29.171216) (xy 171.921684 -29.124897) (xy 171.963813 -29.084519)
			(xy 172.011596 -29.05102) (xy 172.063918 -29.025181) (xy 172.119563 -29.007603) (xy 172.177235 -28.998697)
			(xy 172.206412 -28.998164) (xy 172.233665 -28.998651) (xy 172.287615 -29.006409) (xy 172.339912 -29.021766)
			(xy 172.389492 -29.04441) (xy 172.435344 -29.073879) (xy 172.476536 -29.109573) (xy 172.512229 -29.150766)
			(xy 172.541696 -29.196619) (xy 172.564338 -29.246199) (xy 172.579693 -29.298497) (xy 172.58745 -29.352447)
			(xy 172.58745 -29.406953) (xy 172.579693 -29.460903) (xy 172.564338 -29.513201) (xy 172.541696 -29.562781)
			(xy 172.512229 -29.608634) (xy 172.476536 -29.649827) (xy 172.435344 -29.685521) (xy 172.389492 -29.71499)
			(xy 172.339912 -29.737634) (xy 172.287615 -29.752991) (xy 172.233665 -29.760749) (xy 172.206412 -29.76118)
			(xy 172.178304 -29.760664) (xy 172.122702 -29.75238) (xy 172.095668 -29.74467) (xy 172.08197 -29.741)
			(xy 172.053626 -29.740551) (xy 172.026254 -29.747926) (xy 172.001972 -29.762554) (xy 171.982659 -29.783304)
			(xy 171.969807 -29.808571) (xy 171.966636 -29.822394) (xy 171.962403 -29.841952) (xy 180.652674 -29.841952)
			(xy 180.653185 -29.814379) (xy 180.661129 -29.759809) (xy 180.676846 -29.70695) (xy 180.700008 -29.656904)
			(xy 180.730132 -29.610713) (xy 180.766591 -29.56934) (xy 180.787294 -29.551122) (xy 180.798239 -29.541272)
			(xy 180.814311 -29.516608) (xy 180.822689 -29.488388) (xy 180.82268 -29.45895) (xy 180.814284 -29.430735)
			(xy 180.798198 -29.406081) (xy 180.787294 -29.396182) (xy 180.76657 -29.377985) (xy 180.730101 -29.336613)
			(xy 180.69997 -29.29042) (xy 180.676807 -29.24037) (xy 180.661093 -29.187504) (xy 180.653157 -29.132928)
			(xy 180.652674 -29.105352) (xy 180.653133 -29.0781) (xy 180.660896 -29.024153) (xy 180.676256 -28.971859)
			(xy 180.698901 -28.922282) (xy 180.728371 -28.876433) (xy 180.764065 -28.835244) (xy 180.805257 -28.799553)
			(xy 180.851109 -28.770087) (xy 180.900687 -28.747445) (xy 180.952982 -28.732089) (xy 181.00693 -28.724331)
			(xy 181.034182 -28.723844) (xy 181.061439 -28.724338) (xy 181.115398 -28.732103) (xy 181.167704 -28.747462)
			(xy 181.217293 -28.770105) (xy 181.263159 -28.799569) (xy 181.304368 -28.835257) (xy 181.340083 -28.876443)
			(xy 181.355238 -28.899104) (xy 181.363519 -28.911031) (xy 181.385455 -28.930035) (xy 181.411855 -28.94209)
			(xy 181.440582 -28.94622) (xy 181.469309 -28.94209) (xy 181.495709 -28.930035) (xy 181.517645 -28.911031)
			(xy 181.525926 -28.899104) (xy 181.541103 -28.876457) (xy 181.576806 -28.835261) (xy 181.618008 -28.799565)
			(xy 181.66387 -28.770094) (xy 181.713459 -28.747449) (xy 181.765765 -28.732091) (xy 181.819725 -28.724331)
			(xy 181.846982 -28.723844) (xy 181.874231 -28.724395) (xy 181.928173 -28.732148) (xy 181.980464 -28.747498)
			(xy 182.030038 -28.770134) (xy 182.075886 -28.799593) (xy 182.117075 -28.835278) (xy 182.152767 -28.876461)
			(xy 182.182235 -28.922304) (xy 182.204879 -28.971874) (xy 182.220238 -29.024162) (xy 182.228 -29.078103)
			(xy 182.22849 -29.105352) (xy 182.227995 -29.132926) (xy 182.220049 -29.187497) (xy 182.20433 -29.240357)
			(xy 182.181165 -29.290403) (xy 182.151038 -29.336593) (xy 182.114575 -29.377965) (xy 182.09387 -29.396182)
			(xy 182.083024 -29.406131) (xy 182.066955 -29.430768) (xy 182.058569 -29.458962) (xy 182.05856 -29.488376)
			(xy 182.066929 -29.516575) (xy 182.080332 -29.537152) (xy 189.618364 -29.537152) (xy 189.622435 -29.48153)
			(xy 189.634561 -29.427093) (xy 189.654484 -29.375002) (xy 189.68178 -29.326367) (xy 189.715866 -29.282224)
			(xy 189.756015 -29.243515) (xy 189.801373 -29.211064) (xy 189.850973 -29.185563) (xy 189.903757 -29.167556)
			(xy 189.9586 -29.157426) (xy 190.014334 -29.155389) (xy 190.069771 -29.161489) (xy 190.123728 -29.175595)
			(xy 190.175057 -29.197407) (xy 190.222663 -29.226461) (xy 190.265531 -29.262136) (xy 190.302748 -29.303673)
			(xy 190.333521 -29.350186) (xy 190.357193 -29.400683) (xy 190.373261 -29.45409) (xy 190.381381 -29.509266)
			(xy 190.38189 -29.537152) (xy 190.381381 -29.565038) (xy 190.373261 -29.620214) (xy 190.357193 -29.673621)
			(xy 190.333521 -29.724118) (xy 190.302748 -29.770631) (xy 190.265531 -29.812168) (xy 190.222663 -29.847843)
			(xy 190.175057 -29.876897) (xy 190.123728 -29.898709) (xy 190.069771 -29.912815) (xy 190.014334 -29.918915)
			(xy 189.9586 -29.916878) (xy 189.903757 -29.906748) (xy 189.850973 -29.888741) (xy 189.801373 -29.86324)
			(xy 189.756015 -29.830789) (xy 189.715866 -29.79208) (xy 189.68178 -29.747937) (xy 189.654484 -29.699302)
			(xy 189.634561 -29.647211) (xy 189.622435 -29.592774) (xy 189.618364 -29.537152) (xy 182.080332 -29.537152)
			(xy 182.082983 -29.541222) (xy 182.09387 -29.551122) (xy 182.114589 -29.569325) (xy 182.15106 -29.610695)
			(xy 182.181192 -29.656886) (xy 182.204357 -29.706936) (xy 182.220071 -29.7598) (xy 182.228007 -29.814377)
			(xy 182.22849 -29.841952) (xy 182.228 -29.869204) (xy 182.220249 -29.923155) (xy 182.204898 -29.975454)
			(xy 182.18226 -30.025035) (xy 182.152795 -30.070889) (xy 182.117104 -30.112083) (xy 182.075913 -30.147777)
			(xy 182.030061 -30.177246) (xy 181.980482 -30.199888) (xy 181.928185 -30.215243) (xy 181.874234 -30.222998)
			(xy 181.846982 -30.22346) (xy 181.819724 -30.222991) (xy 181.765764 -30.215222) (xy 181.713458 -30.199858)
			(xy 181.663868 -30.177211) (xy 181.618003 -30.147743) (xy 181.576795 -30.112051) (xy 181.541081 -30.070862)
			(xy 181.525926 -30.0482) (xy 181.517645 -30.036273) (xy 181.495709 -30.017269) (xy 181.469309 -30.005214)
			(xy 181.440582 -30.001084) (xy 181.411855 -30.005214) (xy 181.385455 -30.017269) (xy 181.363519 -30.036273)
			(xy 181.355238 -30.0482) (xy 181.340086 -30.070864) (xy 181.304378 -30.11206) (xy 181.263172 -30.147755)
			(xy 181.217306 -30.177224) (xy 181.167713 -30.199866) (xy 181.115403 -30.21522) (xy 181.061441 -30.222975)
			(xy 181.034182 -30.22346) (xy 181.006926 -30.223062) (xy 180.952971 -30.215301) (xy 180.900669 -30.19994)
			(xy 180.851085 -30.177292) (xy 180.80523 -30.147818) (xy 180.764036 -30.112117) (xy 180.728343 -30.070917)
			(xy 180.698876 -30.025057) (xy 180.676237 -29.975469) (xy 180.660885 -29.923165) (xy 180.653134 -29.869208)
			(xy 180.652674 -29.841952) (xy 171.962403 -29.841952) (xy 171.960644 -29.850077) (xy 171.941577 -29.903409)
			(xy 171.914834 -29.953336) (xy 171.881002 -29.99876) (xy 171.840826 -30.038683) (xy 171.795188 -30.072226)
			(xy 171.745093 -30.098652) (xy 171.69164 -30.11738) (xy 171.636006 -30.127999) (xy 171.607734 -30.129734)
			(xy 171.59219 -30.130903) (xy 171.562873 -30.141445) (xy 171.538095 -30.160332) (xy 171.52016 -30.185807)
			(xy 171.510736 -30.215503) (xy 171.510198 -30.23108) (xy 171.510198 -30.395672) (xy 171.824394 -30.395672)
			(xy 171.828465 -30.34005) (xy 171.840591 -30.285613) (xy 171.860514 -30.233522) (xy 171.88781 -30.184887)
			(xy 171.921896 -30.140744) (xy 171.962045 -30.102035) (xy 172.007403 -30.069584) (xy 172.057003 -30.044083)
			(xy 172.109787 -30.026076) (xy 172.16463 -30.015946) (xy 172.220364 -30.013909) (xy 172.275801 -30.020009)
			(xy 172.329758 -30.034115) (xy 172.381087 -30.055927) (xy 172.428693 -30.084981) (xy 172.471561 -30.120656)
			(xy 172.508778 -30.162193) (xy 172.539551 -30.208706) (xy 172.563223 -30.259203) (xy 172.579291 -30.31261)
			(xy 172.587411 -30.367786) (xy 172.58792 -30.395672) (xy 172.587411 -30.423558) (xy 172.579291 -30.478734)
			(xy 172.563223 -30.532141) (xy 172.539551 -30.582638) (xy 172.508778 -30.629151) (xy 172.471561 -30.670688)
			(xy 172.428693 -30.706363) (xy 172.381087 -30.735417) (xy 172.329758 -30.757229) (xy 172.275801 -30.771335)
			(xy 172.220364 -30.777435) (xy 172.16463 -30.775398) (xy 172.109787 -30.765268) (xy 172.057003 -30.747261)
			(xy 172.007403 -30.72176) (xy 171.962045 -30.689309) (xy 171.921896 -30.6506) (xy 171.88781 -30.606457)
			(xy 171.860514 -30.557822) (xy 171.840591 -30.505731) (xy 171.828465 -30.451294) (xy 171.824394 -30.395672)
			(xy 171.510198 -30.395672) (xy 171.510198 -30.445964) (xy 172.510482 -31.446248) (xy 176.813144 -31.446248)
			(xy 176.813145 -31.39174) (xy 176.820904 -31.337786) (xy 176.836262 -31.285486) (xy 176.858907 -31.235903)
			(xy 176.888378 -31.190049) (xy 176.924075 -31.148855) (xy 176.965271 -31.113161) (xy 177.011128 -31.083693)
			(xy 177.060712 -31.061052) (xy 177.113013 -31.045698) (xy 177.166968 -31.037943) (xy 177.221476 -31.037946)
			(xy 177.27543 -31.045707) (xy 177.327729 -31.061067) (xy 177.377311 -31.083715) (xy 177.423164 -31.113188)
			(xy 177.464356 -31.148886) (xy 177.500048 -31.190084) (xy 177.529514 -31.235942) (xy 177.552154 -31.285527)
			(xy 177.567506 -31.337829) (xy 177.575258 -31.391784) (xy 177.575718 -31.419038) (xy 177.575718 -31.428944)
			(xy 177.575825 -31.44294) (xy 177.582765 -31.470045) (xy 177.5968 -31.49425) (xy 177.616878 -31.513737)
			(xy 177.64149 -31.527045) (xy 177.66879 -31.533174) (xy 177.696728 -31.531664) (xy 177.723209 -31.522629)
			(xy 177.734976 -31.51505) (xy 177.759047 -31.498984) (xy 177.811029 -31.473548) (xy 177.866258 -31.45626)
			(xy 177.923464 -31.447515) (xy 177.9524 -31.446978) (xy 177.979653 -31.447455) (xy 178.033604 -31.455212)
			(xy 178.085903 -31.470569) (xy 178.135483 -31.493212) (xy 178.181336 -31.52268) (xy 178.222529 -31.558374)
			(xy 178.258223 -31.599567) (xy 178.287691 -31.645421) (xy 178.310333 -31.695002) (xy 178.325689 -31.7473)
			(xy 178.333445 -31.801252) (xy 178.333444 -31.855758) (xy 178.325687 -31.909709) (xy 178.312618 -31.954216)
			(xy 179.198014 -31.954216) (xy 179.202085 -31.898594) (xy 179.214211 -31.844157) (xy 179.234134 -31.792066)
			(xy 179.26143 -31.743431) (xy 179.295516 -31.699288) (xy 179.335665 -31.660579) (xy 179.381023 -31.628128)
			(xy 179.430623 -31.602627) (xy 179.483407 -31.58462) (xy 179.53825 -31.57449) (xy 179.593984 -31.572453)
			(xy 179.649421 -31.578553) (xy 179.703378 -31.592659) (xy 179.754707 -31.614471) (xy 179.802313 -31.643525)
			(xy 179.806794 -31.647254) (xy 182.48193 -31.647254) (xy 182.48193 -31.592746) (xy 182.489687 -31.538793)
			(xy 182.505043 -31.486493) (xy 182.527686 -31.436911) (xy 182.557154 -31.391056) (xy 182.592848 -31.349861)
			(xy 182.634041 -31.314165) (xy 182.679895 -31.284694) (xy 182.729476 -31.262049) (xy 182.781776 -31.246691)
			(xy 182.835728 -31.238931) (xy 182.862982 -31.238444) (xy 182.890239 -31.238938) (xy 182.944198 -31.246703)
			(xy 182.996504 -31.262062) (xy 183.046093 -31.284705) (xy 183.091959 -31.314169) (xy 183.133168 -31.349857)
			(xy 183.168883 -31.391043) (xy 183.184038 -31.413704) (xy 183.192319 -31.425631) (xy 183.214255 -31.444635)
			(xy 183.240655 -31.45669) (xy 183.269382 -31.46082) (xy 183.298109 -31.45669) (xy 183.324509 -31.444635)
			(xy 183.346445 -31.425631) (xy 183.354726 -31.413704) (xy 183.369903 -31.391057) (xy 183.405606 -31.349861)
			(xy 183.446808 -31.314165) (xy 183.49267 -31.284694) (xy 183.542259 -31.262049) (xy 183.594565 -31.246691)
			(xy 183.648525 -31.238931) (xy 183.675782 -31.238444) (xy 183.703032 -31.239002) (xy 183.756978 -31.246756)
			(xy 183.809272 -31.262108) (xy 183.858848 -31.284747) (xy 183.904698 -31.314211) (xy 183.945887 -31.3499)
			(xy 183.981578 -31.391088) (xy 184.011044 -31.436936) (xy 184.033685 -31.486511) (xy 184.04904 -31.538804)
			(xy 184.056797 -31.59275) (xy 184.056797 -31.64725) (xy 184.04904 -31.701196) (xy 184.033685 -31.753489)
			(xy 184.011044 -31.803064) (xy 183.981578 -31.848912) (xy 183.945887 -31.8901) (xy 183.904698 -31.925789)
			(xy 183.858848 -31.955253) (xy 183.809272 -31.977892) (xy 183.756978 -31.993244) (xy 183.703032 -32.000998)
			(xy 183.675782 -32.00146) (xy 183.648524 -32.000991) (xy 183.594564 -31.993222) (xy 183.542258 -31.977858)
			(xy 183.492668 -31.955211) (xy 183.446803 -31.925743) (xy 183.405595 -31.890051) (xy 183.369881 -31.848862)
			(xy 183.354726 -31.8262) (xy 183.346445 -31.814273) (xy 183.324509 -31.795269) (xy 183.298109 -31.783214)
			(xy 183.269382 -31.779084) (xy 183.240655 -31.783214) (xy 183.214255 -31.795269) (xy 183.192319 -31.814273)
			(xy 183.184038 -31.8262) (xy 183.168886 -31.848864) (xy 183.133178 -31.89006) (xy 183.091972 -31.925755)
			(xy 183.046106 -31.955224) (xy 182.996513 -31.977866) (xy 182.944203 -31.99322) (xy 182.890241 -32.000975)
			(xy 182.862982 -32.00146) (xy 182.835728 -32.001069) (xy 182.781776 -31.993309) (xy 182.729476 -31.977951)
			(xy 182.679895 -31.955306) (xy 182.634041 -31.925835) (xy 182.592848 -31.890139) (xy 182.557154 -31.848944)
			(xy 182.527686 -31.803089) (xy 182.505043 -31.753507) (xy 182.489687 -31.701207) (xy 182.48193 -31.647254)
			(xy 179.806794 -31.647254) (xy 179.845181 -31.6792) (xy 179.882398 -31.720737) (xy 179.913171 -31.76725)
			(xy 179.936843 -31.817747) (xy 179.952911 -31.871154) (xy 179.961031 -31.92633) (xy 179.96154 -31.954216)
			(xy 179.961031 -31.982102) (xy 179.952911 -32.037278) (xy 179.936843 -32.090685) (xy 179.913171 -32.141182)
			(xy 179.882398 -32.187695) (xy 179.845181 -32.229232) (xy 179.802313 -32.264907) (xy 179.754707 -32.293961)
			(xy 179.703378 -32.315773) (xy 179.649421 -32.329879) (xy 179.593984 -32.335979) (xy 179.53825 -32.333942)
			(xy 179.483407 -32.323812) (xy 179.430623 -32.305805) (xy 179.381023 -32.280304) (xy 179.335665 -32.247853)
			(xy 179.295516 -32.209144) (xy 179.26143 -32.165001) (xy 179.234134 -32.116366) (xy 179.214211 -32.064275)
			(xy 179.202085 -32.009838) (xy 179.198014 -31.954216) (xy 178.312618 -31.954216) (xy 178.31033 -31.962007)
			(xy 178.287686 -32.011587) (xy 178.258217 -32.05744) (xy 178.222523 -32.098632) (xy 178.181329 -32.134326)
			(xy 178.135475 -32.163793) (xy 178.085894 -32.186435) (xy 178.033595 -32.20179) (xy 177.979644 -32.209545)
			(xy 177.925138 -32.209544) (xy 177.871186 -32.201786) (xy 177.818889 -32.186428) (xy 177.769309 -32.163784)
			(xy 177.723456 -32.134314) (xy 177.682264 -32.098619) (xy 177.646572 -32.057425) (xy 177.617105 -32.011571)
			(xy 177.594464 -31.961989) (xy 177.579109 -31.909691) (xy 177.571354 -31.855739) (xy 177.570892 -31.828486)
			(xy 177.570892 -31.81858) (xy 177.570823 -31.804585) (xy 177.563868 -31.777484) (xy 177.549822 -31.753286)
			(xy 177.52974 -31.733805) (xy 177.505126 -31.7205) (xy 177.477827 -31.714371) (xy 177.449888 -31.715875)
			(xy 177.423405 -31.724901) (xy 177.411634 -31.732474) (xy 177.387554 -31.748527) (xy 177.335576 -31.773968)
			(xy 177.28035 -31.791261) (xy 177.223145 -31.800008) (xy 177.19421 -31.800546) (xy 177.166956 -31.800056)
			(xy 177.113002 -31.7923) (xy 177.060701 -31.776944) (xy 177.011118 -31.754301) (xy 176.965262 -31.724832)
			(xy 176.924066 -31.689136) (xy 176.888371 -31.647942) (xy 176.858901 -31.602086) (xy 176.836258 -31.552503)
			(xy 176.820901 -31.500202) (xy 176.813144 -31.446248) (xy 172.510482 -31.446248) (xy 173.599856 -32.535622)
			(xy 180.552342 -32.535622) (xy 180.556413 -32.48) (xy 180.568539 -32.425563) (xy 180.588462 -32.373472)
			(xy 180.615758 -32.324837) (xy 180.649844 -32.280694) (xy 180.689993 -32.241985) (xy 180.735351 -32.209534)
			(xy 180.784951 -32.184033) (xy 180.837735 -32.166026) (xy 180.892578 -32.155896) (xy 180.948312 -32.153859)
			(xy 181.003749 -32.159959) (xy 181.057706 -32.174065) (xy 181.109035 -32.195877) (xy 181.156641 -32.224931)
			(xy 181.199509 -32.260606) (xy 181.236726 -32.302143) (xy 181.267499 -32.348656) (xy 181.291171 -32.399153)
			(xy 181.307239 -32.45256) (xy 181.315359 -32.507736) (xy 181.315868 -32.535622) (xy 181.315359 -32.563508)
			(xy 181.307239 -32.618684) (xy 181.291171 -32.672091) (xy 181.267499 -32.722588) (xy 181.236726 -32.769101)
			(xy 181.199509 -32.810638) (xy 181.156641 -32.846313) (xy 181.109035 -32.875367) (xy 181.057706 -32.897179)
			(xy 181.003749 -32.911285) (xy 180.948312 -32.917385) (xy 180.892578 -32.915348) (xy 180.837735 -32.905218)
			(xy 180.784951 -32.887211) (xy 180.735351 -32.86171) (xy 180.689993 -32.829259) (xy 180.649844 -32.79055)
			(xy 180.615758 -32.746407) (xy 180.588462 -32.697772) (xy 180.568539 -32.645681) (xy 180.556413 -32.591244)
			(xy 180.552342 -32.535622) (xy 173.599856 -32.535622) (xy 174.614586 -33.550352) (xy 184.716674 -33.550352)
			(xy 184.717124 -33.524036) (xy 184.724346 -33.471902) (xy 184.73866 -33.421254) (xy 184.759795 -33.373052)
			(xy 184.787351 -33.328211) (xy 184.820804 -33.287578) (xy 184.839864 -33.269428) (xy 184.849935 -33.259663)
			(xy 184.864636 -33.235778) (xy 184.87227 -33.208791) (xy 184.872261 -33.180745) (xy 184.864609 -33.153762)
			(xy 184.849894 -33.129887) (xy 184.839864 -33.120076) (xy 184.820785 -33.10194) (xy 184.787305 -33.061322)
			(xy 184.759732 -33.016482) (xy 184.738593 -32.968274) (xy 184.72429 -32.917616) (xy 184.717093 -32.865472)
			(xy 184.716674 -32.839152) (xy 184.717185 -32.811579) (xy 184.725129 -32.757009) (xy 184.740846 -32.70415)
			(xy 184.764008 -32.654104) (xy 184.794132 -32.607913) (xy 184.830591 -32.56654) (xy 184.851294 -32.548322)
			(xy 184.862239 -32.538472) (xy 184.878311 -32.513808) (xy 184.886689 -32.485588) (xy 184.88668 -32.45615)
			(xy 184.878284 -32.427935) (xy 184.862198 -32.403281) (xy 184.851294 -32.393382) (xy 184.83057 -32.375185)
			(xy 184.794101 -32.333813) (xy 184.76397 -32.28762) (xy 184.740807 -32.23757) (xy 184.725093 -32.184704)
			(xy 184.717157 -32.130128) (xy 184.716674 -32.102552) (xy 184.71716 -32.075301) (xy 184.724916 -32.021353)
			(xy 184.740271 -31.969058) (xy 184.762913 -31.919481) (xy 184.792379 -31.873631) (xy 184.82807 -31.83244)
			(xy 184.869261 -31.796749) (xy 184.915111 -31.767283) (xy 184.964688 -31.744641) (xy 185.016983 -31.729286)
			(xy 185.070931 -31.72153) (xy 185.125433 -31.72153) (xy 185.179381 -31.729286) (xy 185.231676 -31.744641)
			(xy 185.281253 -31.767283) (xy 185.327103 -31.796749) (xy 185.368294 -31.83244) (xy 185.403985 -31.873631)
			(xy 185.433451 -31.919481) (xy 185.456093 -31.969058) (xy 185.471448 -32.021353) (xy 185.479204 -32.075301)
			(xy 185.47969 -32.102552) (xy 185.479195 -32.130126) (xy 185.471249 -32.184697) (xy 185.45553 -32.237557)
			(xy 185.432365 -32.287603) (xy 185.402238 -32.333793) (xy 185.365775 -32.375165) (xy 185.34507 -32.393382)
			(xy 185.334224 -32.403331) (xy 185.318155 -32.427968) (xy 185.309769 -32.456162) (xy 185.30976 -32.485576)
			(xy 185.318129 -32.513775) (xy 185.334183 -32.538422) (xy 185.34507 -32.548322) (xy 185.365789 -32.566525)
			(xy 185.40226 -32.607895) (xy 185.432392 -32.654086) (xy 185.455557 -32.704136) (xy 185.471271 -32.757)
			(xy 185.479207 -32.811577) (xy 185.47969 -32.839152) (xy 185.479255 -32.865469) (xy 185.472031 -32.917604)
			(xy 185.457715 -32.968252) (xy 185.436577 -33.016454) (xy 185.409019 -33.061296) (xy 185.375562 -33.101927)
			(xy 185.3565 -33.120076) (xy 185.346528 -33.129934) (xy 185.331828 -33.153793) (xy 185.324184 -33.180755)
			(xy 185.324175 -33.20878) (xy 185.331802 -33.235747) (xy 185.346487 -33.259616) (xy 185.3565 -33.269428)
			(xy 185.375593 -33.287549) (xy 185.40907 -33.328172) (xy 185.436638 -33.373016) (xy 185.457775 -33.421226)
			(xy 185.472076 -33.471886) (xy 185.479271 -33.524032) (xy 185.47969 -33.550352) (xy 185.479204 -33.577603)
			(xy 185.471448 -33.631551) (xy 185.456093 -33.683846) (xy 185.433451 -33.733423) (xy 185.403985 -33.779273)
			(xy 185.368294 -33.820464) (xy 185.327103 -33.856155) (xy 185.281253 -33.885621) (xy 185.231676 -33.908263)
			(xy 185.179381 -33.923618) (xy 185.125433 -33.931374) (xy 185.070931 -33.931374) (xy 185.016983 -33.923618)
			(xy 184.964688 -33.908263) (xy 184.915111 -33.885621) (xy 184.869261 -33.856155) (xy 184.82807 -33.820464)
			(xy 184.792379 -33.779273) (xy 184.762913 -33.733423) (xy 184.740271 -33.683846) (xy 184.724916 -33.631551)
			(xy 184.71716 -33.577603) (xy 184.716674 -33.550352) (xy 174.614586 -33.550352) (xy 175.403888 -34.339654)
			(xy 181.84693 -34.339654) (xy 181.84693 -34.285146) (xy 181.854687 -34.231193) (xy 181.870043 -34.178893)
			(xy 181.892686 -34.129311) (xy 181.922154 -34.083456) (xy 181.957848 -34.042261) (xy 181.999041 -34.006565)
			(xy 182.044895 -33.977094) (xy 182.094476 -33.954449) (xy 182.146776 -33.939091) (xy 182.200728 -33.931331)
			(xy 182.227982 -33.930844) (xy 182.256899 -33.931359) (xy 182.314071 -33.940086) (xy 182.369271 -33.957344)
			(xy 182.421233 -33.982736) (xy 182.468767 -34.015681) (xy 182.510783 -34.055424) (xy 182.528972 -34.07791)
			(xy 182.538869 -34.089715) (xy 182.564193 -34.107234) (xy 182.593586 -34.11641) (xy 182.624378 -34.11641)
			(xy 182.653771 -34.107234) (xy 182.679095 -34.089715) (xy 182.688992 -34.07791) (xy 182.70719 -34.055432)
			(xy 182.749208 -34.015696) (xy 182.796741 -33.982756) (xy 182.848701 -33.957367) (xy 182.903898 -33.94011)
			(xy 182.961066 -33.931379) (xy 182.989982 -33.930844) (xy 183.017232 -33.931402) (xy 183.071178 -33.939156)
			(xy 183.123472 -33.954508) (xy 183.173048 -33.977147) (xy 183.218898 -34.006611) (xy 183.260087 -34.0423)
			(xy 183.295778 -34.083488) (xy 183.325244 -34.129336) (xy 183.347885 -34.178911) (xy 183.36324 -34.231204)
			(xy 183.370997 -34.28515) (xy 183.370997 -34.33965) (xy 183.36324 -34.393596) (xy 183.347885 -34.445889)
			(xy 183.325244 -34.495464) (xy 183.295778 -34.541312) (xy 183.260087 -34.5825) (xy 183.218898 -34.618189)
			(xy 183.173048 -34.647653) (xy 183.123472 -34.670292) (xy 183.071178 -34.685644) (xy 183.017232 -34.693398)
			(xy 182.989982 -34.69386) (xy 182.961067 -34.693298) (xy 182.903897 -34.68458) (xy 182.848698 -34.667332)
			(xy 182.796736 -34.641948) (xy 182.749201 -34.609012) (xy 182.707183 -34.569277) (xy 182.688992 -34.546794)
			(xy 182.679095 -34.534989) (xy 182.653771 -34.51747) (xy 182.624378 -34.508294) (xy 182.593586 -34.508294)
			(xy 182.564193 -34.51747) (xy 182.538869 -34.534989) (xy 182.528972 -34.546794) (xy 182.510795 -34.56929)
			(xy 182.468773 -34.609024) (xy 182.421235 -34.641962) (xy 182.369271 -34.667348) (xy 182.314071 -34.684602)
			(xy 182.256899 -34.693327) (xy 182.227982 -34.69386) (xy 182.200728 -34.693469) (xy 182.146776 -34.685709)
			(xy 182.094476 -34.670351) (xy 182.044895 -34.647706) (xy 181.999041 -34.618235) (xy 181.957848 -34.582539)
			(xy 181.922154 -34.541344) (xy 181.892686 -34.495489) (xy 181.870043 -34.445907) (xy 181.854687 -34.393607)
			(xy 181.84693 -34.339654) (xy 175.403888 -34.339654) (xy 176.590198 -35.525964) (xy 184.902602 -35.525964)
		)
		(stroke
			(width 0)
			(type solid)
		)
		(fill yes)
		(layer "In13.Cu")
		(net "GND")
	)
	(gr_poly
		(pts
			(xy 334.744314 -52.958746) (xy 334.758781 -52.958194) (xy 334.786533 -52.949995) (xy 334.810873 -52.934343)
			(xy 334.829848 -52.912495) (xy 334.841936 -52.886203) (xy 334.846168 -52.857576) (xy 334.842203 -52.828911)
			(xy 334.83677 -52.81549) (xy 334.827528 -52.793997) (xy 334.814508 -52.749061) (xy 334.807951 -52.702738)
			(xy 334.80756 -52.679346) (xy 334.80807 -52.653359) (xy 334.8162 -52.602024) (xy 334.832261 -52.552594)
			(xy 334.855857 -52.506284) (xy 334.886407 -52.464236) (xy 334.923158 -52.427485) (xy 334.965206 -52.396935)
			(xy 335.011516 -52.373339) (xy 335.060946 -52.357278) (xy 335.112281 -52.349148) (xy 335.164255 -52.349148)
			(xy 335.21559 -52.357278) (xy 335.26502 -52.373339) (xy 335.31133 -52.396935) (xy 335.353378 -52.427485)
			(xy 335.390129 -52.464236) (xy 335.420679 -52.506284) (xy 335.444275 -52.552594) (xy 335.460336 -52.602024)
			(xy 335.468466 -52.653359) (xy 335.468976 -52.679346) (xy 335.468589 -52.702739) (xy 335.46203 -52.749061)
			(xy 335.449008 -52.793997) (xy 335.439766 -52.81549) (xy 335.434301 -52.828897) (xy 335.430329 -52.857561)
			(xy 335.43456 -52.886187) (xy 335.446655 -52.912476) (xy 335.465641 -52.934314) (xy 335.489994 -52.949946)
			(xy 335.517754 -52.958116) (xy 335.532222 -52.958746) (xy 335.683352 -52.958746) (xy 335.698961 -52.937468)
			(xy 335.735806 -52.899694) (xy 335.778186 -52.868253) (xy 335.825022 -52.843946) (xy 335.875126 -52.82739)
			(xy 335.927224 -52.819006) (xy 335.979992 -52.819006) (xy 336.03209 -52.82739) (xy 336.082194 -52.843946)
			(xy 336.12903 -52.868253) (xy 336.17141 -52.899694) (xy 336.208255 -52.937468) (xy 336.223864 -52.958746)
			(xy 337.230212 -52.958746) (xy 337.513168 -52.675536) (xy 337.513168 -51.773328) (xy 337.552792 -51.733958)
			(xy 337.552792 -51.65344) (xy 337.93684 -51.269392) (xy 337.93684 -49.938178) (xy 337.91536 -49.925485)
			(xy 337.87614 -49.89465) (xy 337.841995 -49.858274) (xy 337.8137 -49.817183) (xy 337.791898 -49.772308)
			(xy 337.777083 -49.724668) (xy 337.76959 -49.675343) (xy 337.76959 -49.625453) (xy 337.777084 -49.576128)
			(xy 337.7919 -49.528488) (xy 337.813702 -49.483614) (xy 337.841997 -49.442523) (xy 337.876143 -49.406147)
			(xy 337.915364 -49.375312) (xy 337.93684 -49.362614) (xy 337.93684 -48.337978) (xy 337.91536 -48.325285)
			(xy 337.87614 -48.29445) (xy 337.841995 -48.258074) (xy 337.8137 -48.216983) (xy 337.791898 -48.172108)
			(xy 337.777083 -48.124468) (xy 337.76959 -48.075143) (xy 337.76959 -48.025253) (xy 337.777084 -47.975928)
			(xy 337.7919 -47.928288) (xy 337.813702 -47.883414) (xy 337.841997 -47.842323) (xy 337.876143 -47.805947)
			(xy 337.915364 -47.775112) (xy 337.93684 -47.762414) (xy 337.93684 -47.537878) (xy 337.91536 -47.525185)
			(xy 337.87614 -47.49435) (xy 337.841995 -47.457974) (xy 337.8137 -47.416883) (xy 337.791898 -47.372008)
			(xy 337.777083 -47.324368) (xy 337.76959 -47.275043) (xy 337.76959 -47.225153) (xy 337.777084 -47.175828)
			(xy 337.7919 -47.128188) (xy 337.813702 -47.083314) (xy 337.841997 -47.042223) (xy 337.876143 -47.005847)
			(xy 337.915364 -46.975012) (xy 337.93684 -46.962314) (xy 337.93684 -46.737778) (xy 337.91536 -46.725085)
			(xy 337.87614 -46.69425) (xy 337.841995 -46.657874) (xy 337.8137 -46.616783) (xy 337.791898 -46.571908)
			(xy 337.777083 -46.524268) (xy 337.76959 -46.474943) (xy 337.76959 -46.425053) (xy 337.777084 -46.375728)
			(xy 337.7919 -46.328088) (xy 337.813702 -46.283214) (xy 337.841997 -46.242123) (xy 337.876143 -46.205747)
			(xy 337.915364 -46.174912) (xy 337.93684 -46.162214) (xy 337.93684 -45.937678) (xy 337.91536 -45.924985)
			(xy 337.87614 -45.89415) (xy 337.841995 -45.857774) (xy 337.8137 -45.816683) (xy 337.791898 -45.771808)
			(xy 337.777083 -45.724168) (xy 337.76959 -45.674843) (xy 337.76959 -45.624953) (xy 337.777084 -45.575628)
			(xy 337.7919 -45.527988) (xy 337.813702 -45.483114) (xy 337.841997 -45.442023) (xy 337.876143 -45.405647)
			(xy 337.915364 -45.374812) (xy 337.93684 -45.362114) (xy 337.93684 -45.137578) (xy 337.91536 -45.124885)
			(xy 337.87614 -45.09405) (xy 337.841995 -45.057674) (xy 337.8137 -45.016583) (xy 337.791898 -44.971708)
			(xy 337.777083 -44.924068) (xy 337.76959 -44.874743) (xy 337.76959 -44.824853) (xy 337.777084 -44.775528)
			(xy 337.7919 -44.727888) (xy 337.813702 -44.683014) (xy 337.841997 -44.641923) (xy 337.876143 -44.605547)
			(xy 337.915364 -44.574712) (xy 337.93684 -44.562014) (xy 337.93684 -44.101512) (xy 337.936402 -44.08752)
			(xy 337.928812 -44.060586) (xy 337.914199 -44.036721) (xy 337.89366 -44.017717) (xy 337.868734 -44.004998)
			(xy 337.841292 -43.999519) (xy 337.813394 -44.001692) (xy 337.787131 -44.011353) (xy 337.77555 -44.019216)
			(xy 337.754271 -44.033987) (xy 337.708084 -44.057429) (xy 337.658807 -44.073385) (xy 337.607646 -44.081466)
			(xy 337.581748 -44.081954) (xy 337.555753 -44.081474) (xy 337.504401 -44.073348) (xy 337.454953 -44.057288)
			(xy 337.408627 -44.033689) (xy 337.366563 -44.003134) (xy 337.329798 -43.966373) (xy 337.299236 -43.924314)
			(xy 337.275631 -43.877991) (xy 337.259563 -43.828546) (xy 337.251429 -43.777195) (xy 337.251429 -43.725205)
			(xy 337.259563 -43.673854) (xy 337.275631 -43.624409) (xy 337.299236 -43.578086) (xy 337.329798 -43.536027)
			(xy 337.366563 -43.499266) (xy 337.408627 -43.468711) (xy 337.454953 -43.445112) (xy 337.504401 -43.429052)
			(xy 337.555753 -43.420926) (xy 337.581748 -43.420538) (xy 337.607644 -43.421045) (xy 337.658801 -43.429127)
			(xy 337.708073 -43.445087) (xy 337.754254 -43.468533) (xy 337.77555 -43.483276) (xy 337.787135 -43.491131)
			(xy 337.813395 -43.500792) (xy 337.841291 -43.502965) (xy 337.86873 -43.497487) (xy 337.893653 -43.484769)
			(xy 337.91419 -43.465765) (xy 337.9288 -43.441902) (xy 337.936387 -43.41497) (xy 337.93684 -43.40098)
			(xy 337.93684 -43.161712) (xy 337.936402 -43.14772) (xy 337.928812 -43.120786) (xy 337.914199 -43.096921)
			(xy 337.89366 -43.077917) (xy 337.868734 -43.065198) (xy 337.841292 -43.059719) (xy 337.813394 -43.061892)
			(xy 337.787131 -43.071553) (xy 337.77555 -43.079416) (xy 337.754271 -43.094187) (xy 337.708084 -43.117629)
			(xy 337.658807 -43.133585) (xy 337.607646 -43.141666) (xy 337.581748 -43.142154) (xy 337.555753 -43.141674)
			(xy 337.504401 -43.133548) (xy 337.454953 -43.117488) (xy 337.408627 -43.093889) (xy 337.366563 -43.063334)
			(xy 337.329798 -43.026573) (xy 337.299236 -42.984514) (xy 337.275631 -42.938191) (xy 337.259563 -42.888746)
			(xy 337.251429 -42.837395) (xy 337.251429 -42.785405) (xy 337.259563 -42.734054) (xy 337.275631 -42.684609)
			(xy 337.299236 -42.638286) (xy 337.329798 -42.596227) (xy 337.366563 -42.559466) (xy 337.408627 -42.528911)
			(xy 337.454953 -42.505312) (xy 337.504401 -42.489252) (xy 337.555753 -42.481126) (xy 337.581748 -42.480738)
			(xy 337.607644 -42.481245) (xy 337.658801 -42.489327) (xy 337.708073 -42.505287) (xy 337.754254 -42.528733)
			(xy 337.77555 -42.543476) (xy 337.787135 -42.551331) (xy 337.813395 -42.560992) (xy 337.841291 -42.563165)
			(xy 337.86873 -42.557687) (xy 337.893653 -42.544969) (xy 337.91419 -42.525965) (xy 337.9288 -42.502102)
			(xy 337.936387 -42.47517) (xy 337.93684 -42.46118) (xy 337.93684 -42.221912) (xy 337.936402 -42.20792)
			(xy 337.928812 -42.180986) (xy 337.914199 -42.157121) (xy 337.89366 -42.138117) (xy 337.868734 -42.125398)
			(xy 337.841292 -42.119919) (xy 337.813394 -42.122092) (xy 337.787131 -42.131753) (xy 337.77555 -42.139616)
			(xy 337.754271 -42.154387) (xy 337.708084 -42.177829) (xy 337.658807 -42.193785) (xy 337.607646 -42.201866)
			(xy 337.581748 -42.202354) (xy 337.555753 -42.201874) (xy 337.504401 -42.193748) (xy 337.454953 -42.177688)
			(xy 337.408627 -42.154089) (xy 337.366563 -42.123534) (xy 337.329798 -42.086773) (xy 337.299236 -42.044714)
			(xy 337.275631 -41.998391) (xy 337.259563 -41.948946) (xy 337.251429 -41.897595) (xy 337.251429 -41.845605)
			(xy 337.259563 -41.794254) (xy 337.275631 -41.744809) (xy 337.299236 -41.698486) (xy 337.329798 -41.656427)
			(xy 337.366563 -41.619666) (xy 337.408627 -41.589111) (xy 337.454953 -41.565512) (xy 337.504401 -41.549452)
			(xy 337.555753 -41.541326) (xy 337.581748 -41.540938) (xy 337.607644 -41.541445) (xy 337.658801 -41.549527)
			(xy 337.708073 -41.565487) (xy 337.754254 -41.588933) (xy 337.77555 -41.603676) (xy 337.787135 -41.611531)
			(xy 337.813395 -41.621192) (xy 337.841291 -41.623365) (xy 337.86873 -41.617887) (xy 337.893653 -41.605169)
			(xy 337.91419 -41.586165) (xy 337.9288 -41.562302) (xy 337.936387 -41.53537) (xy 337.93684 -41.52138)
			(xy 337.93684 -40.342312) (xy 337.936402 -40.32832) (xy 337.928812 -40.301386) (xy 337.914199 -40.277521)
			(xy 337.89366 -40.258517) (xy 337.868734 -40.245798) (xy 337.841292 -40.240319) (xy 337.813394 -40.242492)
			(xy 337.787131 -40.252153) (xy 337.77555 -40.260016) (xy 337.754271 -40.274787) (xy 337.708084 -40.298229)
			(xy 337.658807 -40.314185) (xy 337.607646 -40.322266) (xy 337.581748 -40.322754) (xy 337.555753 -40.322274)
			(xy 337.504401 -40.314148) (xy 337.454953 -40.298088) (xy 337.408627 -40.274489) (xy 337.366563 -40.243934)
			(xy 337.329798 -40.207173) (xy 337.299236 -40.165114) (xy 337.275631 -40.118791) (xy 337.259563 -40.069346)
			(xy 337.251429 -40.017995) (xy 337.251429 -39.966005) (xy 337.259563 -39.914654) (xy 337.275631 -39.865209)
			(xy 337.299236 -39.818886) (xy 337.329798 -39.776827) (xy 337.366563 -39.740066) (xy 337.408627 -39.709511)
			(xy 337.454953 -39.685912) (xy 337.504401 -39.669852) (xy 337.555753 -39.661726) (xy 337.581748 -39.661338)
			(xy 337.607644 -39.661845) (xy 337.658801 -39.669927) (xy 337.708073 -39.685887) (xy 337.754254 -39.709333)
			(xy 337.77555 -39.724076) (xy 337.787135 -39.731931) (xy 337.813395 -39.741592) (xy 337.841291 -39.743765)
			(xy 337.86873 -39.738287) (xy 337.893653 -39.725569) (xy 337.91419 -39.706565) (xy 337.9288 -39.682702)
			(xy 337.936387 -39.65577) (xy 337.93684 -39.64178) (xy 337.93684 -36.383976) (xy 337.917536 -36.364926)
			(xy 337.887156 -36.33387) (xy 337.831363 -36.267266) (xy 337.781634 -36.196021) (xy 337.738352 -36.120685)
			(xy 337.71967 -36.081462) (xy 337.680446 -36.062782) (xy 337.605112 -36.019496) (xy 337.533867 -35.969767)
			(xy 337.46726 -35.913978) (xy 337.436206 -35.883596) (xy 337.127088 -35.574478) (xy 337.0933 -35.539837)
			(xy 337.03191 -35.465029) (xy 336.978125 -35.384579) (xy 336.93246 -35.299257) (xy 336.895353 -35.209881)
			(xy 336.880708 -35.16376) (xy 336.876898 -35.151822) (xy 336.084672 -34.359596) (xy 336.0545 -34.328758)
			(xy 335.99904 -34.262662) (xy 335.949551 -34.191985) (xy 335.90641 -34.117264) (xy 335.869944 -34.039067)
			(xy 335.84043 -33.95799) (xy 335.818095 -33.87465) (xy 335.803107 -33.789681) (xy 335.79558 -33.703729)
			(xy 335.795112 -33.660588) (xy 335.795112 -33.42259) (xy 335.78927 -33.411414) (xy 335.767042 -33.368443)
			(xy 335.73011 -33.279018) (xy 335.702093 -33.186412) (xy 335.68326 -33.091511) (xy 335.673791 -32.995224)
			(xy 335.673192 -32.946848) (xy 335.673192 -32.509968) (xy 335.673621 -32.468623) (xy 335.680528 -32.386223)
			(xy 335.6943 -32.304688) (xy 335.714839 -32.224591) (xy 335.742003 -32.14649) (xy 335.775602 -32.070934)
			(xy 335.795112 -32.03448) (xy 335.795112 -30.422596) (xy 332.196948 -26.824178) (xy 332.185264 -26.820368)
			(xy 332.160718 -26.812048) (xy 332.113958 -26.789699) (xy 332.070655 -26.761222) (xy 332.031607 -26.727143)
			(xy 331.997536 -26.688089) (xy 331.969067 -26.644781) (xy 331.946726 -26.598016) (xy 331.938376 -26.57348)
			(xy 331.934566 -26.561796) (xy 330.039472 -24.666956) (xy 330.007159 -24.633888) (xy 329.948166 -24.562692)
			(xy 329.896083 -24.486295) (xy 329.851364 -24.405367) (xy 329.814401 -24.320615) (xy 329.785518 -24.23278)
			(xy 329.764966 -24.142631) (xy 329.752927 -24.050957) (xy 329.750674 -24.004778) (xy 329.723418 -23.996513)
			(xy 329.671535 -23.973024) (xy 329.623719 -23.942084) (xy 329.581035 -23.904379) (xy 329.54443 -23.860747)
			(xy 329.514718 -23.812159) (xy 329.49256 -23.759693) (xy 329.48499 -23.732236) (xy 329.475084 -23.694136)
			(xy 328.774044 -23.694136) (xy 328.76617 -23.735284) (xy 328.760754 -23.761073) (xy 328.743768 -23.810955)
			(xy 328.720077 -23.858025) (xy 328.690133 -23.901385) (xy 328.654505 -23.940211) (xy 328.613872 -23.973763)
			(xy 328.569007 -24.001403) (xy 328.520764 -24.022603) (xy 328.470063 -24.036962) (xy 328.417868 -24.044204)
			(xy 328.39152 -24.044656) (xy 328.363046 -24.044129) (xy 328.306732 -24.035664) (xy 328.252302 -24.018918)
			(xy 328.200968 -23.994265) (xy 328.15387 -23.962252) (xy 328.112057 -23.923592) (xy 328.076457 -23.879143)
			(xy 328.047863 -23.829895) (xy 328.02691 -23.776943) (xy 328.014065 -23.721463) (xy 328.011282 -23.69312)
			(xy 327.965304 -23.690747) (xy 327.874046 -23.678518) (xy 327.784321 -23.657856) (xy 327.696907 -23.628939)
			(xy 327.61256 -23.59202) (xy 327.532012 -23.547416) (xy 327.455961 -23.495516) (xy 327.385065 -23.436768)
			(xy 327.352152 -23.404576) (xy 324.900036 -20.95246) (xy 324.867016 -20.969986) (xy 324.839316 -20.983997)
			(xy 324.780495 -21.003822) (xy 324.719237 -21.013843) (xy 324.6882 -21.014436) (xy 324.661389 -21.01398)
			(xy 324.608296 -21.006466) (xy 324.55678 -20.991587) (xy 324.507857 -20.969635) (xy 324.462492 -20.941045)
			(xy 324.421582 -20.90638) (xy 324.385933 -20.866324) (xy 324.3707 -20.844256) (xy 320.74612 -20.844256)
			(xy 320.616326 -20.97405) (xy 320.616326 -22.233128) (xy 320.616761 -22.246815) (xy 320.624018 -22.273208)
			(xy 320.63803 -22.296723) (xy 320.657788 -22.315668) (xy 320.681871 -22.32868) (xy 320.708546 -22.334822)
			(xy 320.735894 -22.333653) (xy 320.761947 -22.325256) (xy 320.784832 -22.310237) (xy 320.794126 -22.300184)
			(xy 320.812335 -22.280177) (xy 320.853423 -22.244987) (xy 320.899066 -22.215949) (xy 320.94835 -22.193641)
			(xy 321.000289 -22.178511) (xy 321.053843 -22.170862) (xy 321.080892 -22.17039) (xy 321.108145 -22.170853)
			(xy 321.162097 -22.178609) (xy 321.214397 -22.193964) (xy 321.263978 -22.216606) (xy 321.309832 -22.246074)
			(xy 321.351026 -22.281768) (xy 321.386721 -22.322961) (xy 321.39918 -22.342348) (xy 323.676262 -22.342348)
			(xy 323.680333 -22.286726) (xy 323.692459 -22.232289) (xy 323.712382 -22.180198) (xy 323.739678 -22.131563)
			(xy 323.773764 -22.08742) (xy 323.813913 -22.048711) (xy 323.859271 -22.01626) (xy 323.908871 -21.990759)
			(xy 323.961655 -21.972752) (xy 324.016498 -21.962622) (xy 324.072232 -21.960585) (xy 324.127669 -21.966685)
			(xy 324.181626 -21.980791) (xy 324.232955 -22.002603) (xy 324.280561 -22.031657) (xy 324.323429 -22.067332)
			(xy 324.360646 -22.108869) (xy 324.391419 -22.155382) (xy 324.415091 -22.205879) (xy 324.431159 -22.259286)
			(xy 324.433477 -22.275038) (xy 324.583552 -22.275038) (xy 324.584038 -22.247787) (xy 324.591794 -22.193839)
			(xy 324.607149 -22.141544) (xy 324.629791 -22.091967) (xy 324.659257 -22.046117) (xy 324.694948 -22.004926)
			(xy 324.736139 -21.969235) (xy 324.781989 -21.939769) (xy 324.831566 -21.917127) (xy 324.883861 -21.901772)
			(xy 324.937809 -21.894016) (xy 324.992311 -21.894016) (xy 325.046259 -21.901772) (xy 325.098554 -21.917127)
			(xy 325.148131 -21.939769) (xy 325.193981 -21.969235) (xy 325.235172 -22.004926) (xy 325.270863 -22.046117)
			(xy 325.300329 -22.091967) (xy 325.322971 -22.141544) (xy 325.338326 -22.193839) (xy 325.346082 -22.247787)
			(xy 325.346568 -22.275038) (xy 325.346098 -22.301418) (xy 325.338835 -22.353675) (xy 325.32444 -22.404433)
			(xy 325.303186 -22.452722) (xy 325.27548 -22.497622) (xy 325.241851 -22.538274) (xy 325.20294 -22.573904)
			(xy 325.181468 -22.589236) (xy 325.170038 -22.597669) (xy 325.15199 -22.619589) (xy 325.140666 -22.645627)
			(xy 325.136937 -22.673775) (xy 325.141092 -22.701863) (xy 325.15281 -22.727726) (xy 325.171187 -22.749371)
			(xy 325.182738 -22.757638) (xy 325.204842 -22.77282) (xy 325.244893 -22.808481) (xy 325.279553 -22.849401)
			(xy 325.308138 -22.894774) (xy 325.330083 -22.943704) (xy 325.344957 -22.995227) (xy 325.352465 -23.048325)
			(xy 325.352918 -23.075138) (xy 325.352432 -23.102389) (xy 325.344676 -23.156337) (xy 325.329321 -23.208632)
			(xy 325.306679 -23.258209) (xy 325.277213 -23.304059) (xy 325.241522 -23.34525) (xy 325.200331 -23.380941)
			(xy 325.154481 -23.410407) (xy 325.104904 -23.433049) (xy 325.052609 -23.448404) (xy 324.998661 -23.45616)
			(xy 324.944159 -23.45616) (xy 324.890211 -23.448404) (xy 324.837916 -23.433049) (xy 324.788339 -23.410407)
			(xy 324.742489 -23.380941) (xy 324.701298 -23.34525) (xy 324.665607 -23.304059) (xy 324.636141 -23.258209)
			(xy 324.613499 -23.208632) (xy 324.598144 -23.156337) (xy 324.590388 -23.102389) (xy 324.589902 -23.075138)
			(xy 324.590367 -23.048758) (xy 324.597632 -22.996501) (xy 324.612029 -22.945744) (xy 324.633284 -22.897455)
			(xy 324.66099 -22.852555) (xy 324.69462 -22.811902) (xy 324.73353 -22.776272) (xy 324.755002 -22.76094)
			(xy 324.766459 -22.752539) (xy 324.784512 -22.730613) (xy 324.795839 -22.704568) (xy 324.799566 -22.676411)
			(xy 324.795405 -22.648316) (xy 324.783678 -22.622448) (xy 324.765289 -22.600804) (xy 324.753732 -22.592538)
			(xy 324.731679 -22.577285) (xy 324.691623 -22.541638) (xy 324.656958 -22.500731) (xy 324.628366 -22.455371)
			(xy 324.606412 -22.406451) (xy 324.591529 -22.354938) (xy 324.58401 -22.301848) (xy 324.583552 -22.275038)
			(xy 324.433477 -22.275038) (xy 324.439279 -22.314462) (xy 324.439788 -22.342348) (xy 324.439279 -22.370234)
			(xy 324.431159 -22.42541) (xy 324.415091 -22.478817) (xy 324.391419 -22.529314) (xy 324.360646 -22.575827)
			(xy 324.323429 -22.617364) (xy 324.280561 -22.653039) (xy 324.232955 -22.682093) (xy 324.181626 -22.703905)
			(xy 324.127669 -22.718011) (xy 324.072232 -22.724111) (xy 324.016498 -22.722074) (xy 323.961655 -22.711944)
			(xy 323.908871 -22.693937) (xy 323.859271 -22.668436) (xy 323.813913 -22.635985) (xy 323.773764 -22.597276)
			(xy 323.739678 -22.553133) (xy 323.712382 -22.504498) (xy 323.692459 -22.452407) (xy 323.680333 -22.39797)
			(xy 323.676262 -22.342348) (xy 321.39918 -22.342348) (xy 321.41619 -22.368815) (xy 321.438833 -22.418396)
			(xy 321.454189 -22.470695) (xy 321.461947 -22.524647) (xy 321.461947 -22.579153) (xy 321.454189 -22.633105)
			(xy 321.438833 -22.685404) (xy 321.41619 -22.734985) (xy 321.386721 -22.780839) (xy 321.351026 -22.822032)
			(xy 321.309832 -22.857726) (xy 321.263978 -22.887194) (xy 321.214397 -22.909836) (xy 321.162097 -22.925191)
			(xy 321.108145 -22.932947) (xy 321.080892 -22.933406) (xy 321.053843 -22.932934) (xy 321.000288 -22.925293)
			(xy 320.948349 -22.910165) (xy 320.899067 -22.887854) (xy 320.85343 -22.858806) (xy 320.812352 -22.823604)
			(xy 320.794126 -22.803612) (xy 320.784754 -22.793648) (xy 320.761878 -22.778671) (xy 320.735847 -22.770302)
			(xy 320.708528 -22.769143) (xy 320.681882 -22.775277) (xy 320.657819 -22.788264) (xy 320.638067 -22.807172)
			(xy 320.624042 -22.830644) (xy 320.61675 -22.856997) (xy 320.616326 -22.870668) (xy 320.616326 -23.615142)
			(xy 320.65976 -23.658576) (xy 320.669792 -23.667966) (xy 320.693692 -23.681502) (xy 320.720335 -23.688177)
			(xy 320.747794 -23.687508) (xy 320.77408 -23.679543) (xy 320.797293 -23.664859) (xy 320.815751 -23.644519)
			(xy 320.828119 -23.619994) (xy 320.833502 -23.59306) (xy 320.832988 -23.579328) (xy 320.831972 -23.551896)
			(xy 320.832458 -23.524645) (xy 320.840214 -23.470697) (xy 320.855569 -23.418402) (xy 320.878211 -23.368825)
			(xy 320.907677 -23.322975) (xy 320.943368 -23.281784) (xy 320.984559 -23.246093) (xy 321.030409 -23.216627)
			(xy 321.079986 -23.193985) (xy 321.132281 -23.17863) (xy 321.186229 -23.170874) (xy 321.240731 -23.170874)
			(xy 321.294679 -23.17863) (xy 321.346974 -23.193985) (xy 321.396551 -23.216627) (xy 321.442401 -23.246093)
			(xy 321.483592 -23.281784) (xy 321.519283 -23.322975) (xy 321.548749 -23.368825) (xy 321.571391 -23.418402)
			(xy 321.586746 -23.470697) (xy 321.594502 -23.524645) (xy 321.594988 -23.551896) (xy 321.594337 -23.584354)
			(xy 321.583358 -23.648334) (xy 321.573144 -23.67915) (xy 321.568979 -23.692393) (xy 321.567151 -23.720082)
			(xy 321.572847 -23.74724) (xy 321.585644 -23.771862) (xy 321.604599 -23.792129) (xy 321.628311 -23.806543)
			(xy 321.655028 -23.814041) (xy 321.668902 -23.814532) (xy 324.654418 -23.814532) (xy 324.699884 -23.859998)
			(xy 324.72122 -23.859744) (xy 324.727824 -23.859744) (xy 324.759914 -23.860158) (xy 324.823694 -23.867309)
			(xy 324.88627 -23.881563) (xy 324.946855 -23.902742) (xy 325.004684 -23.930577) (xy 325.059029 -23.964718)
			(xy 325.109205 -24.004735) (xy 325.132192 -24.02713) (xy 325.183754 -24.078692) (xy 325.22414 -24.03856)
			(xy 325.227188 -24.033226) (xy 325.242132 -24.009683) (xy 325.277813 -23.966832) (xy 325.319353 -23.929632)
			(xy 325.365867 -23.898878) (xy 325.416363 -23.875224) (xy 325.469765 -23.859174) (xy 325.524935 -23.851072)
			(xy 325.552816 -23.8506) (xy 325.580066 -23.851087) (xy 325.634012 -23.858845) (xy 325.686304 -23.874202)
			(xy 325.735879 -23.896844) (xy 325.781727 -23.926311) (xy 325.822914 -23.962003) (xy 325.858604 -24.003192)
			(xy 325.888067 -24.049042) (xy 325.910707 -24.098618) (xy 325.92606 -24.150912) (xy 325.933815 -24.204858)
			(xy 325.934324 -24.232108) (xy 325.933836 -24.259703) (xy 325.925885 -24.314317) (xy 325.91015 -24.367217)
			(xy 325.886958 -24.417298) (xy 325.856794 -24.463516) (xy 325.820288 -24.504907) (xy 325.778199 -24.540607)
			(xy 325.731407 -24.569873) (xy 325.680888 -24.592093) (xy 325.654416 -24.5999) (xy 325.639926 -24.604447)
			(xy 325.614298 -24.620712) (xy 325.594587 -24.643794) (xy 325.582535 -24.671651) (xy 325.579209 -24.701822)
			(xy 325.584901 -24.731636) (xy 325.599109 -24.758458) (xy 325.609458 -24.769572) (xy 325.863712 -25.023826)
			(xy 328.014328 -25.023826) (xy 328.018399 -24.968204) (xy 328.030525 -24.913767) (xy 328.050448 -24.861676)
			(xy 328.077744 -24.813041) (xy 328.11183 -24.768898) (xy 328.151979 -24.730189) (xy 328.197337 -24.697738)
			(xy 328.246937 -24.672237) (xy 328.299721 -24.65423) (xy 328.354564 -24.6441) (xy 328.410298 -24.642063)
			(xy 328.465735 -24.648163) (xy 328.519692 -24.662269) (xy 328.571021 -24.684081) (xy 328.618627 -24.713135)
			(xy 328.661495 -24.74881) (xy 328.698712 -24.790347) (xy 328.729485 -24.83686) (xy 328.753157 -24.887357)
			(xy 328.769225 -24.940764) (xy 328.777345 -24.99594) (xy 328.777854 -25.023826) (xy 328.777345 -25.051712)
			(xy 328.769225 -25.106888) (xy 328.753157 -25.160295) (xy 328.729485 -25.210792) (xy 328.698712 -25.257305)
			(xy 328.661495 -25.298842) (xy 328.618627 -25.334517) (xy 328.571021 -25.363571) (xy 328.519692 -25.385383)
			(xy 328.465735 -25.399489) (xy 328.410298 -25.405589) (xy 328.354564 -25.403552) (xy 328.299721 -25.393422)
			(xy 328.246937 -25.375415) (xy 328.197337 -25.349914) (xy 328.151979 -25.317463) (xy 328.11183 -25.278754)
			(xy 328.077744 -25.234611) (xy 328.050448 -25.185976) (xy 328.030525 -25.133885) (xy 328.018399 -25.079448)
			(xy 328.014328 -25.023826) (xy 325.863712 -25.023826) (xy 327.572116 -26.73223) (xy 327.572116 -26.901648)
			(xy 328.384408 -26.901648) (xy 328.384815 -26.875997) (xy 328.391702 -26.825158) (xy 328.405346 -26.775703)
			(xy 328.4255 -26.728524) (xy 328.451799 -26.684475) (xy 328.483768 -26.644351) (xy 328.50201 -26.626312)
			(xy 328.511586 -26.616514) (xy 328.525618 -26.592997) (xy 328.532897 -26.566597) (xy 328.532898 -26.539211)
			(xy 328.525622 -26.51281) (xy 328.511591 -26.489293) (xy 328.50201 -26.4795) (xy 328.483799 -26.461435)
			(xy 328.451855 -26.421301) (xy 328.42557 -26.377252) (xy 328.405418 -26.330082) (xy 328.391762 -26.280638)
			(xy 328.384848 -26.229811) (xy 328.384408 -26.204164) (xy 328.384894 -26.176913) (xy 328.39265 -26.122965)
			(xy 328.408005 -26.07067) (xy 328.430647 -26.021093) (xy 328.460113 -25.975243) (xy 328.495804 -25.934052)
			(xy 328.536995 -25.898361) (xy 328.582845 -25.868895) (xy 328.632422 -25.846253) (xy 328.684717 -25.830898)
			(xy 328.738665 -25.823142) (xy 328.793167 -25.823142) (xy 328.847115 -25.830898) (xy 328.89941 -25.846253)
			(xy 328.948987 -25.868895) (xy 328.994837 -25.898361) (xy 329.036028 -25.934052) (xy 329.071719 -25.975243)
			(xy 329.101185 -26.021093) (xy 329.123827 -26.07067) (xy 329.139182 -26.122965) (xy 329.146938 -26.176913)
			(xy 329.147424 -26.204164) (xy 329.147015 -26.229815) (xy 329.140127 -26.280653) (xy 329.126483 -26.330108)
			(xy 329.106329 -26.377286) (xy 329.080031 -26.421336) (xy 329.048063 -26.461461) (xy 329.029822 -26.4795)
			(xy 329.02024 -26.48929) (xy 329.006217 -26.512811) (xy 328.998945 -26.539212) (xy 328.998947 -26.566596)
			(xy 329.006221 -26.592996) (xy 329.020245 -26.616517) (xy 329.029822 -26.626312) (xy 329.048045 -26.644366)
			(xy 329.079987 -26.684503) (xy 329.106269 -26.728554) (xy 329.126418 -26.775727) (xy 329.140072 -26.825172)
			(xy 329.146985 -26.876) (xy 329.147424 -26.901648) (xy 329.146938 -26.928899) (xy 329.139182 -26.982847)
			(xy 329.123827 -27.035142) (xy 329.101185 -27.084719) (xy 329.071719 -27.130569) (xy 329.036028 -27.17176)
			(xy 328.994837 -27.207451) (xy 328.948987 -27.236917) (xy 328.89941 -27.259559) (xy 328.847115 -27.274914)
			(xy 328.793167 -27.28267) (xy 328.738665 -27.28267) (xy 328.684717 -27.274914) (xy 328.632422 -27.259559)
			(xy 328.582845 -27.236917) (xy 328.536995 -27.207451) (xy 328.495804 -27.17176) (xy 328.460113 -27.130569)
			(xy 328.430647 -27.084719) (xy 328.408005 -27.035142) (xy 328.39265 -26.982847) (xy 328.384894 -26.928899)
			(xy 328.384408 -26.901648) (xy 327.572116 -26.901648) (xy 327.572116 -27.284934) (xy 327.815448 -27.528266)
			(xy 327.851262 -27.49931) (xy 327.87178 -27.483051) (xy 327.916428 -27.455717) (xy 327.964397 -27.43475)
			(xy 328.014784 -27.420545) (xy 328.066641 -27.41337) (xy 328.092816 -27.41295) (xy 328.120068 -27.413437)
			(xy 328.174016 -27.421195) (xy 328.226311 -27.436551) (xy 328.275889 -27.459193) (xy 328.32174 -27.488659)
			(xy 328.32729 -27.493468) (xy 331.554326 -27.493468) (xy 331.558397 -27.437846) (xy 331.570523 -27.383409)
			(xy 331.590446 -27.331318) (xy 331.617742 -27.282683) (xy 331.651828 -27.23854) (xy 331.691977 -27.199831)
			(xy 331.737335 -27.16738) (xy 331.786935 -27.141879) (xy 331.839719 -27.123872) (xy 331.894562 -27.113742)
			(xy 331.950296 -27.111705) (xy 332.005733 -27.117805) (xy 332.05969 -27.131911) (xy 332.111019 -27.153723)
			(xy 332.158625 -27.182777) (xy 332.201493 -27.218452) (xy 332.23871 -27.259989) (xy 332.269483 -27.306502)
			(xy 332.293155 -27.356999) (xy 332.309223 -27.410406) (xy 332.317343 -27.465582) (xy 332.317852 -27.493468)
			(xy 332.317343 -27.521354) (xy 332.309223 -27.57653) (xy 332.293155 -27.629937) (xy 332.269483 -27.680434)
			(xy 332.23871 -27.726947) (xy 332.201493 -27.768484) (xy 332.158625 -27.804159) (xy 332.111019 -27.833213)
			(xy 332.05969 -27.855025) (xy 332.005733 -27.869131) (xy 331.950296 -27.875231) (xy 331.894562 -27.873194)
			(xy 331.839719 -27.863064) (xy 331.786935 -27.845057) (xy 331.737335 -27.819556) (xy 331.691977 -27.787105)
			(xy 331.651828 -27.748396) (xy 331.617742 -27.704253) (xy 331.590446 -27.655618) (xy 331.570523 -27.603527)
			(xy 331.558397 -27.54909) (xy 331.554326 -27.493468) (xy 328.32729 -27.493468) (xy 328.362932 -27.524349)
			(xy 328.398626 -27.565539) (xy 328.428095 -27.611388) (xy 328.45074 -27.660965) (xy 328.466099 -27.713259)
			(xy 328.473861 -27.767206) (xy 328.474324 -27.794458) (xy 328.473869 -27.82063) (xy 328.466672 -27.872477)
			(xy 328.452462 -27.922855) (xy 328.431505 -27.970821) (xy 328.404194 -28.015475) (xy 328.387964 -28.036012)
			(xy 328.359008 -28.071826) (xy 329.20559 -28.918408) (xy 330.341732 -28.918408) (xy 330.342218 -28.891157)
			(xy 330.349974 -28.837209) (xy 330.365329 -28.784914) (xy 330.387971 -28.735337) (xy 330.417437 -28.689487)
			(xy 330.453128 -28.648296) (xy 330.494319 -28.612605) (xy 330.540169 -28.583139) (xy 330.589746 -28.560497)
			(xy 330.642041 -28.545142) (xy 330.695989 -28.537386) (xy 330.750491 -28.537386) (xy 330.804439 -28.545142)
			(xy 330.856734 -28.560497) (xy 330.906311 -28.583139) (xy 330.952161 -28.612605) (xy 330.993352 -28.648296)
			(xy 331.029043 -28.689487) (xy 331.058509 -28.735337) (xy 331.081151 -28.784914) (xy 331.096506 -28.837209)
			(xy 331.104262 -28.891157) (xy 331.104748 -28.918408) (xy 331.104306 -28.94522) (xy 331.096791 -28.998315)
			(xy 331.081911 -29.049832) (xy 331.059958 -29.098757) (xy 331.031367 -29.144123) (xy 330.996701 -29.185034)
			(xy 330.956644 -29.220685) (xy 330.934568 -29.235908) (xy 330.922822 -29.244252) (xy 330.904255 -29.266269)
			(xy 330.892566 -29.292593) (xy 330.888685 -29.321132) (xy 330.892918 -29.349621) (xy 330.904931 -29.375798)
			(xy 330.92377 -29.397584) (xy 330.935584 -29.405834) (xy 330.958149 -29.420969) (xy 330.999113 -29.456663)
			(xy 331.034599 -29.497809) (xy 331.063888 -29.543572) (xy 331.086389 -29.593028) (xy 331.101646 -29.645176)
			(xy 331.10935 -29.698961) (xy 331.109828 -29.726128) (xy 331.109342 -29.753379) (xy 331.101586 -29.807327)
			(xy 331.086231 -29.859622) (xy 331.063589 -29.909199) (xy 331.034123 -29.955049) (xy 330.998432 -29.99624)
			(xy 330.957241 -30.031931) (xy 330.911391 -30.061397) (xy 330.861814 -30.084039) (xy 330.852384 -30.086808)
			(xy 331.657958 -30.086808) (xy 331.662029 -30.031186) (xy 331.674155 -29.976749) (xy 331.694078 -29.924658)
			(xy 331.721374 -29.876023) (xy 331.75546 -29.83188) (xy 331.795609 -29.793171) (xy 331.840967 -29.76072)
			(xy 331.890567 -29.735219) (xy 331.943351 -29.717212) (xy 331.998194 -29.707082) (xy 332.053928 -29.705045)
			(xy 332.109365 -29.711145) (xy 332.163322 -29.725251) (xy 332.214651 -29.747063) (xy 332.262257 -29.776117)
			(xy 332.305125 -29.811792) (xy 332.342342 -29.853329) (xy 332.373115 -29.899842) (xy 332.396787 -29.950339)
			(xy 332.412855 -30.003746) (xy 332.420975 -30.058922) (xy 332.421484 -30.086808) (xy 332.420975 -30.114694)
			(xy 332.412855 -30.16987) (xy 332.396787 -30.223277) (xy 332.373115 -30.273774) (xy 332.342342 -30.320287)
			(xy 332.305125 -30.361824) (xy 332.262257 -30.397499) (xy 332.214651 -30.426553) (xy 332.163322 -30.448365)
			(xy 332.109365 -30.462471) (xy 332.053928 -30.468571) (xy 331.998194 -30.466534) (xy 331.943351 -30.456404)
			(xy 331.890567 -30.438397) (xy 331.840967 -30.412896) (xy 331.795609 -30.380445) (xy 331.75546 -30.341736)
			(xy 331.721374 -30.297593) (xy 331.694078 -30.248958) (xy 331.674155 -30.196867) (xy 331.662029 -30.14243)
			(xy 331.657958 -30.086808) (xy 330.852384 -30.086808) (xy 330.809519 -30.099394) (xy 330.755571 -30.10715)
			(xy 330.701069 -30.10715) (xy 330.647121 -30.099394) (xy 330.594826 -30.084039) (xy 330.545249 -30.061397)
			(xy 330.499399 -30.031931) (xy 330.458208 -29.99624) (xy 330.422517 -29.955049) (xy 330.393051 -29.909199)
			(xy 330.370409 -29.859622) (xy 330.355054 -29.807327) (xy 330.347298 -29.753379) (xy 330.346812 -29.726128)
			(xy 330.347299 -29.699318) (xy 330.354808 -29.646226) (xy 330.369682 -29.59471) (xy 330.391628 -29.545786)
			(xy 330.420212 -29.50042) (xy 330.45487 -29.459506) (xy 330.494919 -29.423853) (xy 330.516992 -29.408628)
			(xy 330.528706 -29.400242) (xy 330.54728 -29.378236) (xy 330.558976 -29.351921) (xy 330.562863 -29.323388)
			(xy 330.558634 -29.294904) (xy 330.546625 -29.268731) (xy 330.527789 -29.246949) (xy 330.515976 -29.238702)
			(xy 330.493441 -29.223524) (xy 330.452474 -29.187838) (xy 330.416984 -29.146701) (xy 330.38769 -29.100945)
			(xy 330.365184 -29.051496) (xy 330.349922 -28.999353) (xy 330.342213 -28.945573) (xy 330.341732 -28.918408)
			(xy 329.20559 -28.918408) (xy 331.303122 -31.01594) (xy 331.303122 -31.505144) (xy 331.306678 -31.514288)
			(xy 331.315431 -31.537013) (xy 331.327749 -31.58413) (xy 331.333959 -31.632432) (xy 331.334364 -31.656782)
			(xy 331.333964 -31.681132) (xy 331.327741 -31.729432) (xy 331.315433 -31.776551) (xy 331.306678 -31.799276)
			(xy 331.303122 -31.80842) (xy 331.303122 -33.186624) (xy 333.667606 -33.186624) (xy 333.671677 -33.131002)
			(xy 333.683803 -33.076565) (xy 333.703726 -33.024474) (xy 333.731022 -32.975839) (xy 333.765108 -32.931696)
			(xy 333.805257 -32.892987) (xy 333.850615 -32.860536) (xy 333.900215 -32.835035) (xy 333.952999 -32.817028)
			(xy 334.007842 -32.806898) (xy 334.063576 -32.804861) (xy 334.119013 -32.810961) (xy 334.17297 -32.825067)
			(xy 334.224299 -32.846879) (xy 334.271905 -32.875933) (xy 334.314773 -32.911608) (xy 334.35199 -32.953145)
			(xy 334.382763 -32.999658) (xy 334.406435 -33.050155) (xy 334.422503 -33.103562) (xy 334.430623 -33.158738)
			(xy 334.431132 -33.186624) (xy 334.430623 -33.21451) (xy 334.422503 -33.269686) (xy 334.406435 -33.323093)
			(xy 334.382763 -33.37359) (xy 334.35199 -33.420103) (xy 334.314773 -33.46164) (xy 334.271905 -33.497315)
			(xy 334.224299 -33.526369) (xy 334.17297 -33.548181) (xy 334.119013 -33.562287) (xy 334.063576 -33.568387)
			(xy 334.007842 -33.56635) (xy 333.952999 -33.55622) (xy 333.900215 -33.538213) (xy 333.850615 -33.512712)
			(xy 333.805257 -33.480261) (xy 333.765108 -33.441552) (xy 333.731022 -33.397409) (xy 333.703726 -33.348774)
			(xy 333.683803 -33.296683) (xy 333.671677 -33.242246) (xy 333.667606 -33.186624) (xy 331.303122 -33.186624)
			(xy 331.303122 -33.680146) (xy 332.00467 -34.381694) (xy 333.607662 -34.381694) (xy 333.611733 -34.326072)
			(xy 333.623859 -34.271635) (xy 333.643782 -34.219544) (xy 333.671078 -34.170909) (xy 333.705164 -34.126766)
			(xy 333.745313 -34.088057) (xy 333.790671 -34.055606) (xy 333.840271 -34.030105) (xy 333.893055 -34.012098)
			(xy 333.947898 -34.001968) (xy 334.003632 -33.999931) (xy 334.059069 -34.006031) (xy 334.113026 -34.020137)
			(xy 334.164355 -34.041949) (xy 334.211961 -34.071003) (xy 334.254829 -34.106678) (xy 334.292046 -34.148215)
			(xy 334.322819 -34.194728) (xy 334.346491 -34.245225) (xy 334.362559 -34.298632) (xy 334.370679 -34.353808)
			(xy 334.371188 -34.381694) (xy 334.370679 -34.40958) (xy 334.362559 -34.464756) (xy 334.346491 -34.518163)
			(xy 334.322819 -34.56866) (xy 334.292046 -34.615173) (xy 334.254829 -34.65671) (xy 334.211961 -34.692385)
			(xy 334.164355 -34.721439) (xy 334.113026 -34.743251) (xy 334.059069 -34.757357) (xy 334.003632 -34.763457)
			(xy 333.947898 -34.76142) (xy 333.893055 -34.75129) (xy 333.840271 -34.733283) (xy 333.790671 -34.707782)
			(xy 333.745313 -34.675331) (xy 333.705164 -34.636622) (xy 333.671078 -34.592479) (xy 333.643782 -34.543844)
			(xy 333.623859 -34.491753) (xy 333.611733 -34.437316) (xy 333.607662 -34.381694) (xy 332.00467 -34.381694)
			(xy 333.614268 -35.991292) (xy 333.614268 -36.089844) (xy 333.619348 -36.100258) (xy 333.632959 -36.129442)
			(xy 333.654278 -36.190208) (xy 333.668633 -36.252986) (xy 333.67584 -36.316979) (xy 333.676244 -36.349178)
			(xy 333.676244 -37.141658) (xy 335.912216 -37.141658) (xy 335.916192 -37.087332) (xy 335.928035 -37.034163)
			(xy 335.947494 -36.983286) (xy 335.974154 -36.935784) (xy 336.007445 -36.89267) (xy 336.046659 -36.854863)
			(xy 336.090961 -36.823168) (xy 336.139404 -36.798262) (xy 336.190958 -36.780674) (xy 336.244524 -36.77078)
			(xy 336.298959 -36.76879) (xy 336.353104 -36.774748) (xy 336.405804 -36.788526) (xy 336.455937 -36.80983)
			(xy 336.502433 -36.838206) (xy 336.544303 -36.87305) (xy 336.580652 -36.913619) (xy 336.610708 -36.959048)
			(xy 336.633829 -37.008369) (xy 336.649522 -37.060531) (xy 336.657453 -37.114422) (xy 336.65795 -37.141658)
			(xy 336.657453 -37.168894) (xy 336.649522 -37.222785) (xy 336.633829 -37.274947) (xy 336.610708 -37.324268)
			(xy 336.580652 -37.369697) (xy 336.544303 -37.410266) (xy 336.502433 -37.44511) (xy 336.455937 -37.473486)
			(xy 336.405804 -37.49479) (xy 336.353104 -37.508568) (xy 336.298959 -37.514526) (xy 336.244524 -37.512536)
			(xy 336.190958 -37.502642) (xy 336.139404 -37.485054) (xy 336.090961 -37.460148) (xy 336.046659 -37.428453)
			(xy 336.007445 -37.390646) (xy 335.974154 -37.347532) (xy 335.947494 -37.30003) (xy 335.928035 -37.249153)
			(xy 335.916192 -37.195984) (xy 335.912216 -37.141658) (xy 333.676244 -37.141658) (xy 333.676244 -39.256208)
			(xy 333.675774 -39.289826) (xy 333.667914 -39.356601) (xy 333.652268 -39.421991) (xy 333.634921 -39.469139)
			(xy 335.068928 -39.469139) (xy 335.068928 -39.417165) (xy 335.077058 -39.36583) (xy 335.093119 -39.3164)
			(xy 335.116715 -39.27009) (xy 335.147265 -39.228042) (xy 335.184016 -39.191291) (xy 335.226064 -39.160741)
			(xy 335.272374 -39.137145) (xy 335.321804 -39.121084) (xy 335.373139 -39.112954) (xy 335.425113 -39.112954)
			(xy 335.476448 -39.121084) (xy 335.525878 -39.137145) (xy 335.572188 -39.160741) (xy 335.614236 -39.191291)
			(xy 335.650987 -39.228042) (xy 335.681537 -39.27009) (xy 335.705133 -39.3164) (xy 335.721194 -39.36583)
			(xy 335.729324 -39.417165) (xy 335.729834 -39.443152) (xy 335.729324 -39.469139) (xy 335.721194 -39.520474)
			(xy 335.705133 -39.569904) (xy 335.681537 -39.616214) (xy 335.650987 -39.658262) (xy 335.614236 -39.695013)
			(xy 335.572188 -39.725563) (xy 335.525878 -39.749159) (xy 335.476448 -39.76522) (xy 335.425113 -39.77335)
			(xy 335.373139 -39.77335) (xy 335.321804 -39.76522) (xy 335.272374 -39.749159) (xy 335.226064 -39.725563)
			(xy 335.184016 -39.695013) (xy 335.147265 -39.658262) (xy 335.116715 -39.616214) (xy 335.093119 -39.569904)
			(xy 335.077058 -39.520474) (xy 335.068928 -39.469139) (xy 333.634921 -39.469139) (xy 333.629052 -39.485091)
			(xy 333.614268 -39.515288) (xy 333.614268 -40.018033) (xy 333.995016 -40.018033) (xy 333.995016 -39.966059)
			(xy 334.003146 -39.914724) (xy 334.019207 -39.865294) (xy 334.042803 -39.818984) (xy 334.073353 -39.776936)
			(xy 334.110104 -39.740185) (xy 334.152152 -39.709635) (xy 334.198462 -39.686039) (xy 334.247892 -39.669978)
			(xy 334.299227 -39.661848) (xy 334.351201 -39.661848) (xy 334.402536 -39.669978) (xy 334.451966 -39.686039)
			(xy 334.498276 -39.709635) (xy 334.540324 -39.740185) (xy 334.577075 -39.776936) (xy 334.607625 -39.818984)
			(xy 334.631221 -39.865294) (xy 334.647282 -39.914724) (xy 334.655412 -39.966059) (xy 334.655922 -39.992046)
			(xy 334.655412 -40.018033) (xy 335.62341 -40.018033) (xy 335.62341 -39.966059) (xy 335.63154 -39.914724)
			(xy 335.647601 -39.865294) (xy 335.671197 -39.818984) (xy 335.701747 -39.776936) (xy 335.738498 -39.740185)
			(xy 335.780546 -39.709635) (xy 335.826856 -39.686039) (xy 335.876286 -39.669978) (xy 335.927621 -39.661848)
			(xy 335.979595 -39.661848) (xy 336.03093 -39.669978) (xy 336.08036 -39.686039) (xy 336.12667 -39.709635)
			(xy 336.168718 -39.740185) (xy 336.205469 -39.776936) (xy 336.236019 -39.818984) (xy 336.259615 -39.865294)
			(xy 336.275676 -39.914724) (xy 336.283806 -39.966059) (xy 336.284316 -39.992046) (xy 336.283806 -40.018033)
			(xy 336.275676 -40.069368) (xy 336.259615 -40.118798) (xy 336.236019 -40.165108) (xy 336.205469 -40.207156)
			(xy 336.168718 -40.243907) (xy 336.12667 -40.274457) (xy 336.08036 -40.298053) (xy 336.03093 -40.314114)
			(xy 335.979595 -40.322244) (xy 335.927621 -40.322244) (xy 335.876286 -40.314114) (xy 335.826856 -40.298053)
			(xy 335.780546 -40.274457) (xy 335.738498 -40.243907) (xy 335.701747 -40.207156) (xy 335.671197 -40.165108)
			(xy 335.647601 -40.118798) (xy 335.63154 -40.069368) (xy 335.62341 -40.018033) (xy 334.655412 -40.018033)
			(xy 334.647282 -40.069368) (xy 334.631221 -40.118798) (xy 334.607625 -40.165108) (xy 334.577075 -40.207156)
			(xy 334.540324 -40.243907) (xy 334.498276 -40.274457) (xy 334.451966 -40.298053) (xy 334.402536 -40.314114)
			(xy 334.351201 -40.322244) (xy 334.299227 -40.322244) (xy 334.247892 -40.314114) (xy 334.198462 -40.298053)
			(xy 334.152152 -40.274457) (xy 334.110104 -40.243907) (xy 334.073353 -40.207156) (xy 334.042803 -40.165108)
			(xy 334.019207 -40.118798) (xy 334.003146 -40.069368) (xy 333.995016 -40.018033) (xy 333.614268 -40.018033)
			(xy 333.614268 -40.14597) (xy 333.644494 -40.159178) (xy 333.667659 -40.169879) (xy 333.710661 -40.197347)
			(xy 333.748934 -40.231095) (xy 333.781568 -40.270321) (xy 333.807789 -40.314094) (xy 333.826976 -40.361376)
			(xy 333.838672 -40.411044) (xy 333.8426 -40.461919) (xy 333.840588 -40.487933) (xy 334.80807 -40.487933)
			(xy 334.80807 -40.435959) (xy 334.8162 -40.384624) (xy 334.832261 -40.335194) (xy 334.855857 -40.288884)
			(xy 334.886407 -40.246836) (xy 334.923158 -40.210085) (xy 334.965206 -40.179535) (xy 335.011516 -40.155939)
			(xy 335.060946 -40.139878) (xy 335.112281 -40.131748) (xy 335.164255 -40.131748) (xy 335.21559 -40.139878)
			(xy 335.26502 -40.155939) (xy 335.31133 -40.179535) (xy 335.353378 -40.210085) (xy 335.390129 -40.246836)
			(xy 335.420679 -40.288884) (xy 335.444275 -40.335194) (xy 335.460336 -40.384624) (xy 335.468466 -40.435959)
			(xy 335.468976 -40.461946) (xy 335.468466 -40.487933) (xy 335.460336 -40.539268) (xy 335.444275 -40.588698)
			(xy 335.420679 -40.635008) (xy 335.390129 -40.677056) (xy 335.353378 -40.713807) (xy 335.31133 -40.744357)
			(xy 335.26502 -40.767953) (xy 335.21559 -40.784014) (xy 335.164255 -40.792144) (xy 335.112281 -40.792144)
			(xy 335.060946 -40.784014) (xy 335.011516 -40.767953) (xy 334.965206 -40.744357) (xy 334.923158 -40.713807)
			(xy 334.886407 -40.677056) (xy 334.855857 -40.635008) (xy 334.832261 -40.588698) (xy 334.8162 -40.539268)
			(xy 334.80807 -40.487933) (xy 333.840588 -40.487933) (xy 333.838666 -40.512793) (xy 333.826965 -40.562459)
			(xy 333.807773 -40.609739) (xy 333.781546 -40.653509) (xy 333.748908 -40.692732) (xy 333.710632 -40.726475)
			(xy 333.667627 -40.753938) (xy 333.644494 -40.764714) (xy 333.614268 -40.777922) (xy 333.614268 -40.957833)
			(xy 333.99527 -40.957833) (xy 333.99527 -40.905859) (xy 334.0034 -40.854524) (xy 334.019461 -40.805094)
			(xy 334.043057 -40.758784) (xy 334.073607 -40.716736) (xy 334.110358 -40.679985) (xy 334.152406 -40.649435)
			(xy 334.198716 -40.625839) (xy 334.248146 -40.609778) (xy 334.299481 -40.601648) (xy 334.351455 -40.601648)
			(xy 334.40279 -40.609778) (xy 334.45222 -40.625839) (xy 334.49853 -40.649435) (xy 334.540578 -40.679985)
			(xy 334.577329 -40.716736) (xy 334.607879 -40.758784) (xy 334.631475 -40.805094) (xy 334.647536 -40.854524)
			(xy 334.655666 -40.905859) (xy 334.656176 -40.931846) (xy 334.655666 -40.957833) (xy 335.62341 -40.957833)
			(xy 335.62341 -40.905859) (xy 335.63154 -40.854524) (xy 335.647601 -40.805094) (xy 335.671197 -40.758784)
			(xy 335.701747 -40.716736) (xy 335.738498 -40.679985) (xy 335.780546 -40.649435) (xy 335.826856 -40.625839)
			(xy 335.876286 -40.609778) (xy 335.927621 -40.601648) (xy 335.979595 -40.601648) (xy 336.03093 -40.609778)
			(xy 336.08036 -40.625839) (xy 336.12667 -40.649435) (xy 336.168718 -40.679985) (xy 336.205469 -40.716736)
			(xy 336.236019 -40.758784) (xy 336.259615 -40.805094) (xy 336.275676 -40.854524) (xy 336.283806 -40.905859)
			(xy 336.284316 -40.931846) (xy 336.283806 -40.957833) (xy 336.283323 -40.960881) (xy 336.706974 -40.960881)
			(xy 336.706974 -40.908907) (xy 336.715104 -40.857572) (xy 336.731165 -40.808142) (xy 336.754761 -40.761832)
			(xy 336.785311 -40.719784) (xy 336.822062 -40.683033) (xy 336.86411 -40.652483) (xy 336.91042 -40.628887)
			(xy 336.95985 -40.612826) (xy 337.011185 -40.604696) (xy 337.063159 -40.604696) (xy 337.114494 -40.612826)
			(xy 337.163924 -40.628887) (xy 337.210234 -40.652483) (xy 337.252282 -40.683033) (xy 337.289033 -40.719784)
			(xy 337.319583 -40.761832) (xy 337.343179 -40.808142) (xy 337.35924 -40.857572) (xy 337.36737 -40.908907)
			(xy 337.36788 -40.934894) (xy 337.36737 -40.960881) (xy 337.35924 -41.012216) (xy 337.343179 -41.061646)
			(xy 337.319583 -41.107956) (xy 337.289033 -41.150004) (xy 337.252282 -41.186755) (xy 337.210234 -41.217305)
			(xy 337.163924 -41.240901) (xy 337.114494 -41.256962) (xy 337.063159 -41.265092) (xy 337.011185 -41.265092)
			(xy 336.95985 -41.256962) (xy 336.91042 -41.240901) (xy 336.86411 -41.217305) (xy 336.822062 -41.186755)
			(xy 336.785311 -41.150004) (xy 336.754761 -41.107956) (xy 336.731165 -41.061646) (xy 336.715104 -41.012216)
			(xy 336.706974 -40.960881) (xy 336.283323 -40.960881) (xy 336.275676 -41.009168) (xy 336.259615 -41.058598)
			(xy 336.236019 -41.104908) (xy 336.205469 -41.146956) (xy 336.168718 -41.183707) (xy 336.12667 -41.214257)
			(xy 336.08036 -41.237853) (xy 336.03093 -41.253914) (xy 335.979595 -41.262044) (xy 335.927621 -41.262044)
			(xy 335.876286 -41.253914) (xy 335.826856 -41.237853) (xy 335.780546 -41.214257) (xy 335.738498 -41.183707)
			(xy 335.701747 -41.146956) (xy 335.671197 -41.104908) (xy 335.647601 -41.058598) (xy 335.63154 -41.009168)
			(xy 335.62341 -40.957833) (xy 334.655666 -40.957833) (xy 334.647536 -41.009168) (xy 334.631475 -41.058598)
			(xy 334.607879 -41.104908) (xy 334.577329 -41.146956) (xy 334.540578 -41.183707) (xy 334.49853 -41.214257)
			(xy 334.45222 -41.237853) (xy 334.40279 -41.253914) (xy 334.351455 -41.262044) (xy 334.299481 -41.262044)
			(xy 334.248146 -41.253914) (xy 334.198716 -41.237853) (xy 334.152406 -41.214257) (xy 334.110358 -41.183707)
			(xy 334.073607 -41.146956) (xy 334.043057 -41.104908) (xy 334.019461 -41.058598) (xy 334.0034 -41.009168)
			(xy 333.99527 -40.957833) (xy 333.614268 -40.957833) (xy 333.614268 -41.08577) (xy 333.644494 -41.098978)
			(xy 333.667659 -41.109679) (xy 333.710661 -41.137147) (xy 333.748934 -41.170895) (xy 333.781568 -41.210121)
			(xy 333.807789 -41.253894) (xy 333.826976 -41.301176) (xy 333.838672 -41.350844) (xy 333.8426 -41.401719)
			(xy 333.840588 -41.427733) (xy 334.81061 -41.427733) (xy 334.81061 -41.375759) (xy 334.81874 -41.324424)
			(xy 334.834801 -41.274994) (xy 334.858397 -41.228684) (xy 334.888947 -41.186636) (xy 334.925698 -41.149885)
			(xy 334.967746 -41.119335) (xy 335.014056 -41.095739) (xy 335.063486 -41.079678) (xy 335.114821 -41.071548)
			(xy 335.166795 -41.071548) (xy 335.21813 -41.079678) (xy 335.26756 -41.095739) (xy 335.31387 -41.119335)
			(xy 335.355918 -41.149885) (xy 335.392669 -41.186636) (xy 335.423219 -41.228684) (xy 335.446815 -41.274994)
			(xy 335.462876 -41.324424) (xy 335.471006 -41.375759) (xy 335.471516 -41.401746) (xy 335.471006 -41.427733)
			(xy 335.462876 -41.479068) (xy 335.446815 -41.528498) (xy 335.423219 -41.574808) (xy 335.392669 -41.616856)
			(xy 335.355918 -41.653607) (xy 335.31387 -41.684157) (xy 335.26756 -41.707753) (xy 335.21813 -41.723814)
			(xy 335.166795 -41.731944) (xy 335.114821 -41.731944) (xy 335.063486 -41.723814) (xy 335.014056 -41.707753)
			(xy 334.967746 -41.684157) (xy 334.925698 -41.653607) (xy 334.888947 -41.616856) (xy 334.858397 -41.574808)
			(xy 334.834801 -41.528498) (xy 334.81874 -41.479068) (xy 334.81061 -41.427733) (xy 333.840588 -41.427733)
			(xy 333.838666 -41.452593) (xy 333.826965 -41.502259) (xy 333.807773 -41.549539) (xy 333.781546 -41.593309)
			(xy 333.748908 -41.632532) (xy 333.710632 -41.666275) (xy 333.667627 -41.693738) (xy 333.644494 -41.704514)
			(xy 333.614268 -41.717722) (xy 333.614268 -41.897633) (xy 333.99527 -41.897633) (xy 333.99527 -41.845659)
			(xy 334.0034 -41.794324) (xy 334.019461 -41.744894) (xy 334.043057 -41.698584) (xy 334.073607 -41.656536)
			(xy 334.110358 -41.619785) (xy 334.152406 -41.589235) (xy 334.198716 -41.565639) (xy 334.248146 -41.549578)
			(xy 334.299481 -41.541448) (xy 334.351455 -41.541448) (xy 334.40279 -41.549578) (xy 334.45222 -41.565639)
			(xy 334.49853 -41.589235) (xy 334.540578 -41.619785) (xy 334.577329 -41.656536) (xy 334.607879 -41.698584)
			(xy 334.631475 -41.744894) (xy 334.647536 -41.794324) (xy 334.655666 -41.845659) (xy 334.656176 -41.871646)
			(xy 334.655666 -41.897633) (xy 335.62341 -41.897633) (xy 335.62341 -41.845659) (xy 335.63154 -41.794324)
			(xy 335.647601 -41.744894) (xy 335.671197 -41.698584) (xy 335.701747 -41.656536) (xy 335.738498 -41.619785)
			(xy 335.780546 -41.589235) (xy 335.826856 -41.565639) (xy 335.876286 -41.549578) (xy 335.927621 -41.541448)
			(xy 335.979595 -41.541448) (xy 336.03093 -41.549578) (xy 336.08036 -41.565639) (xy 336.12667 -41.589235)
			(xy 336.168718 -41.619785) (xy 336.205469 -41.656536) (xy 336.236019 -41.698584) (xy 336.259615 -41.744894)
			(xy 336.275676 -41.794324) (xy 336.283806 -41.845659) (xy 336.284316 -41.871646) (xy 336.283806 -41.897633)
			(xy 336.275676 -41.948968) (xy 336.259615 -41.998398) (xy 336.236019 -42.044708) (xy 336.205469 -42.086756)
			(xy 336.168718 -42.123507) (xy 336.12667 -42.154057) (xy 336.08036 -42.177653) (xy 336.03093 -42.193714)
			(xy 335.979595 -42.201844) (xy 335.927621 -42.201844) (xy 335.876286 -42.193714) (xy 335.826856 -42.177653)
			(xy 335.780546 -42.154057) (xy 335.738498 -42.123507) (xy 335.701747 -42.086756) (xy 335.671197 -42.044708)
			(xy 335.647601 -41.998398) (xy 335.63154 -41.948968) (xy 335.62341 -41.897633) (xy 334.655666 -41.897633)
			(xy 334.647536 -41.948968) (xy 334.631475 -41.998398) (xy 334.607879 -42.044708) (xy 334.577329 -42.086756)
			(xy 334.540578 -42.123507) (xy 334.49853 -42.154057) (xy 334.45222 -42.177653) (xy 334.40279 -42.193714)
			(xy 334.351455 -42.201844) (xy 334.299481 -42.201844) (xy 334.248146 -42.193714) (xy 334.198716 -42.177653)
			(xy 334.152406 -42.154057) (xy 334.110358 -42.123507) (xy 334.073607 -42.086756) (xy 334.043057 -42.044708)
			(xy 334.019461 -41.998398) (xy 334.0034 -41.948968) (xy 333.99527 -41.897633) (xy 333.614268 -41.897633)
			(xy 333.614268 -42.025824) (xy 333.644494 -42.039286) (xy 333.667553 -42.050028) (xy 333.71034 -42.077537)
			(xy 333.74841 -42.111274) (xy 333.780864 -42.150445) (xy 333.806935 -42.194123) (xy 333.826008 -42.24128)
			(xy 333.837634 -42.290801) (xy 333.841538 -42.341519) (xy 333.839533 -42.367533) (xy 334.81061 -42.367533)
			(xy 334.81061 -42.315559) (xy 334.81874 -42.264224) (xy 334.834801 -42.214794) (xy 334.858397 -42.168484)
			(xy 334.888947 -42.126436) (xy 334.925698 -42.089685) (xy 334.967746 -42.059135) (xy 335.014056 -42.035539)
			(xy 335.063486 -42.019478) (xy 335.114821 -42.011348) (xy 335.166795 -42.011348) (xy 335.21813 -42.019478)
			(xy 335.26756 -42.035539) (xy 335.31387 -42.059135) (xy 335.355918 -42.089685) (xy 335.392669 -42.126436)
			(xy 335.423219 -42.168484) (xy 335.446815 -42.214794) (xy 335.462876 -42.264224) (xy 335.471006 -42.315559)
			(xy 335.471516 -42.341546) (xy 335.471006 -42.367533) (xy 335.462876 -42.418868) (xy 335.446815 -42.468298)
			(xy 335.423219 -42.514608) (xy 335.392669 -42.556656) (xy 335.355918 -42.593407) (xy 335.31387 -42.623957)
			(xy 335.26756 -42.647553) (xy 335.21813 -42.663614) (xy 335.166795 -42.671744) (xy 335.114821 -42.671744)
			(xy 335.063486 -42.663614) (xy 335.014056 -42.647553) (xy 334.967746 -42.623957) (xy 334.925698 -42.593407)
			(xy 334.888947 -42.556656) (xy 334.858397 -42.514608) (xy 334.834801 -42.468298) (xy 334.81874 -42.418868)
			(xy 334.81061 -42.367533) (xy 333.839533 -42.367533) (xy 333.837629 -42.392236) (xy 333.825997 -42.441756)
			(xy 333.806918 -42.48891) (xy 333.780842 -42.532586) (xy 333.748384 -42.571752) (xy 333.710311 -42.605486)
			(xy 333.66752 -42.632989) (xy 333.644494 -42.643806) (xy 333.614268 -42.657268) (xy 333.614268 -42.837433)
			(xy 333.99527 -42.837433) (xy 333.99527 -42.785459) (xy 334.0034 -42.734124) (xy 334.019461 -42.684694)
			(xy 334.043057 -42.638384) (xy 334.073607 -42.596336) (xy 334.110358 -42.559585) (xy 334.152406 -42.529035)
			(xy 334.198716 -42.505439) (xy 334.248146 -42.489378) (xy 334.299481 -42.481248) (xy 334.351455 -42.481248)
			(xy 334.40279 -42.489378) (xy 334.45222 -42.505439) (xy 334.49853 -42.529035) (xy 334.540578 -42.559585)
			(xy 334.577329 -42.596336) (xy 334.607879 -42.638384) (xy 334.631475 -42.684694) (xy 334.647536 -42.734124)
			(xy 334.655666 -42.785459) (xy 334.656176 -42.811446) (xy 334.655666 -42.837433) (xy 334.647536 -42.888768)
			(xy 334.631475 -42.938198) (xy 334.607879 -42.984508) (xy 334.577329 -43.026556) (xy 334.540578 -43.063307)
			(xy 334.49853 -43.093857) (xy 334.45222 -43.117453) (xy 334.40279 -43.133514) (xy 334.351455 -43.141644)
			(xy 334.299481 -43.141644) (xy 334.248146 -43.133514) (xy 334.198716 -43.117453) (xy 334.152406 -43.093857)
			(xy 334.110358 -43.063307) (xy 334.073607 -43.026556) (xy 334.043057 -42.984508) (xy 334.019461 -42.938198)
			(xy 334.0034 -42.888768) (xy 333.99527 -42.837433) (xy 333.614268 -42.837433) (xy 333.614268 -42.96537)
			(xy 333.644494 -42.978578) (xy 333.667659 -42.989279) (xy 333.710661 -43.016747) (xy 333.748934 -43.050495)
			(xy 333.781568 -43.089721) (xy 333.807789 -43.133494) (xy 333.826976 -43.180776) (xy 333.838672 -43.230444)
			(xy 333.8426 -43.281319) (xy 333.840588 -43.307333) (xy 334.80807 -43.307333) (xy 334.80807 -43.255359)
			(xy 334.8162 -43.204024) (xy 334.832261 -43.154594) (xy 334.855857 -43.108284) (xy 334.886407 -43.066236)
			(xy 334.923158 -43.029485) (xy 334.965206 -42.998935) (xy 335.011516 -42.975339) (xy 335.060946 -42.959278)
			(xy 335.112281 -42.951148) (xy 335.164255 -42.951148) (xy 335.21559 -42.959278) (xy 335.26502 -42.975339)
			(xy 335.31133 -42.998935) (xy 335.353378 -43.029485) (xy 335.390129 -43.066236) (xy 335.420679 -43.108284)
			(xy 335.444275 -43.154594) (xy 335.460336 -43.204024) (xy 335.468466 -43.255359) (xy 335.468976 -43.281346)
			(xy 335.468466 -43.307333) (xy 335.460336 -43.358668) (xy 335.444275 -43.408098) (xy 335.420679 -43.454408)
			(xy 335.390129 -43.496456) (xy 335.353378 -43.533207) (xy 335.31133 -43.563757) (xy 335.26502 -43.587353)
			(xy 335.21559 -43.603414) (xy 335.164255 -43.611544) (xy 335.112281 -43.611544) (xy 335.060946 -43.603414)
			(xy 335.011516 -43.587353) (xy 334.965206 -43.563757) (xy 334.923158 -43.533207) (xy 334.886407 -43.496456)
			(xy 334.855857 -43.454408) (xy 334.832261 -43.408098) (xy 334.8162 -43.358668) (xy 334.80807 -43.307333)
			(xy 333.840588 -43.307333) (xy 333.838666 -43.332193) (xy 333.826965 -43.381859) (xy 333.807773 -43.429139)
			(xy 333.781546 -43.472909) (xy 333.748908 -43.512132) (xy 333.710632 -43.545875) (xy 333.667627 -43.573338)
			(xy 333.644494 -43.584114) (xy 333.614268 -43.597322) (xy 333.614268 -43.777233) (xy 333.994 -43.777233)
			(xy 333.994 -43.725259) (xy 334.00213 -43.673924) (xy 334.018191 -43.624494) (xy 334.041787 -43.578184)
			(xy 334.072337 -43.536136) (xy 334.109088 -43.499385) (xy 334.151136 -43.468835) (xy 334.197446 -43.445239)
			(xy 334.246876 -43.429178) (xy 334.298211 -43.421048) (xy 334.350185 -43.421048) (xy 334.40152 -43.429178)
			(xy 334.45095 -43.445239) (xy 334.49726 -43.468835) (xy 334.539308 -43.499385) (xy 334.576059 -43.536136)
			(xy 334.606609 -43.578184) (xy 334.630205 -43.624494) (xy 334.646266 -43.673924) (xy 334.654396 -43.725259)
			(xy 334.654906 -43.751246) (xy 334.654396 -43.777233) (xy 334.646266 -43.828568) (xy 334.630205 -43.877998)
			(xy 334.606609 -43.924308) (xy 334.576059 -43.966356) (xy 334.539308 -44.003107) (xy 334.49726 -44.033657)
			(xy 334.45095 -44.057253) (xy 334.40152 -44.073314) (xy 334.350185 -44.081444) (xy 334.298211 -44.081444)
			(xy 334.246876 -44.073314) (xy 334.197446 -44.057253) (xy 334.151136 -44.033657) (xy 334.109088 -44.003107)
			(xy 334.072337 -43.966356) (xy 334.041787 -43.924308) (xy 334.018191 -43.877998) (xy 334.00213 -43.828568)
			(xy 333.994 -43.777233) (xy 333.614268 -43.777233) (xy 333.614268 -43.905424) (xy 333.644494 -43.918886)
			(xy 333.66913 -43.930425) (xy 333.714568 -43.960333) (xy 333.7545 -43.997273) (xy 333.78785 -44.040249)
			(xy 333.813718 -44.088103) (xy 333.831407 -44.139544) (xy 333.84044 -44.193187) (xy 333.84109 -44.220384)
			(xy 333.84109 -44.241212) (xy 334.41005 -44.810172) (xy 334.421184 -44.820608) (xy 334.448143 -44.834877)
			(xy 334.478114 -44.840548) (xy 334.508423 -44.837114) (xy 334.536365 -44.824881) (xy 334.559448 -44.804941)
			(xy 334.575612 -44.779073) (xy 334.579976 -44.764452) (xy 334.587554 -44.73812) (xy 334.610214 -44.688234)
			(xy 334.640798 -44.642773) (xy 334.678468 -44.602985) (xy 334.722188 -44.569962) (xy 334.770761 -44.544609)
			(xy 334.796638 -44.535598) (xy 334.810843 -44.530358) (xy 334.835573 -44.512918) (xy 334.854106 -44.488997)
			(xy 334.864816 -44.460695) (xy 334.866763 -44.430497) (xy 334.859774 -44.401055) (xy 334.852518 -44.38777)
			(xy 334.838401 -44.362293) (xy 334.818358 -44.30761) (xy 334.808176 -44.250266) (xy 334.80756 -44.221146)
			(xy 334.80807 -44.195159) (xy 334.8162 -44.143824) (xy 334.832261 -44.094394) (xy 334.855857 -44.048084)
			(xy 334.886407 -44.006036) (xy 334.923158 -43.969285) (xy 334.965206 -43.938735) (xy 335.011516 -43.915139)
			(xy 335.060946 -43.899078) (xy 335.112281 -43.890948) (xy 335.164255 -43.890948) (xy 335.21559 -43.899078)
			(xy 335.26502 -43.915139) (xy 335.31133 -43.938735) (xy 335.353378 -43.969285) (xy 335.390129 -44.006036)
			(xy 335.420679 -44.048084) (xy 335.444275 -44.094394) (xy 335.460336 -44.143824) (xy 335.468466 -44.195159)
			(xy 335.468976 -44.221146) (xy 335.468467 -44.247084) (xy 335.460359 -44.298323) (xy 335.444349 -44.347667)
			(xy 335.42083 -44.393906) (xy 335.390379 -44.435905) (xy 335.353743 -44.472634) (xy 335.311822 -44.503191)
			(xy 335.265643 -44.526827) (xy 335.241138 -44.535344) (xy 335.22694 -44.540586) (xy 335.202226 -44.558028)
			(xy 335.183707 -44.581946) (xy 335.173009 -44.61024) (xy 335.171072 -44.640427) (xy 335.178065 -44.669857)
			(xy 335.185258 -44.683172) (xy 335.199372 -44.70865) (xy 335.21941 -44.763333) (xy 335.227001 -44.806108)
			(xy 336.240882 -44.806108) (xy 336.241381 -44.779728) (xy 336.249777 -44.727641) (xy 336.266326 -44.677544)
			(xy 336.290609 -44.630704) (xy 336.322011 -44.588308) (xy 336.359739 -44.551427) (xy 336.402838 -44.520995)
			(xy 336.426302 -44.508928) (xy 336.438178 -44.502585) (xy 336.458406 -44.484837) (xy 336.473289 -44.462416)
			(xy 336.481792 -44.436884) (xy 336.483322 -44.410017) (xy 336.477774 -44.383685) (xy 336.472022 -44.371514)
			(xy 336.460615 -44.348112) (xy 336.44453 -44.298599) (xy 336.436415 -44.247176) (xy 336.435954 -44.221146)
			(xy 336.436464 -44.195159) (xy 336.444594 -44.143824) (xy 336.460655 -44.094394) (xy 336.484251 -44.048084)
			(xy 336.514801 -44.006036) (xy 336.551552 -43.969285) (xy 336.5936 -43.938735) (xy 336.63991 -43.915139)
			(xy 336.68934 -43.899078) (xy 336.740675 -43.890948) (xy 336.792649 -43.890948) (xy 336.843984 -43.899078)
			(xy 336.893414 -43.915139) (xy 336.939724 -43.938735) (xy 336.981772 -43.969285) (xy 337.018523 -44.006036)
			(xy 337.049073 -44.048084) (xy 337.072669 -44.094394) (xy 337.08873 -44.143824) (xy 337.09686 -44.195159)
			(xy 337.09737 -44.221146) (xy 337.09686 -44.247526) (xy 337.08847 -44.299614) (xy 337.071925 -44.349712)
			(xy 337.047644 -44.396553) (xy 337.016243 -44.43895) (xy 336.978514 -44.475831) (xy 336.935415 -44.506261)
			(xy 336.91195 -44.518326) (xy 336.900032 -44.524594) (xy 336.879806 -44.542362) (xy 336.864928 -44.564799)
			(xy 336.856434 -44.590346) (xy 336.854913 -44.617224) (xy 336.860472 -44.643566) (xy 336.86623 -44.65574)
			(xy 336.877617 -44.679151) (xy 336.89371 -44.728659) (xy 336.901833 -44.780079) (xy 336.902298 -44.806108)
			(xy 336.901788 -44.832095) (xy 336.893658 -44.88343) (xy 336.877597 -44.93286) (xy 336.854001 -44.97917)
			(xy 336.823451 -45.021218) (xy 336.7867 -45.057969) (xy 336.744652 -45.088519) (xy 336.698342 -45.112115)
			(xy 336.648912 -45.128176) (xy 336.597577 -45.136306) (xy 336.545603 -45.136306) (xy 336.494268 -45.128176)
			(xy 336.444838 -45.112115) (xy 336.398528 -45.088519) (xy 336.35648 -45.057969) (xy 336.319729 -45.021218)
			(xy 336.289179 -44.97917) (xy 336.265583 -44.93286) (xy 336.249522 -44.88343) (xy 336.241392 -44.832095)
			(xy 336.240882 -44.806108) (xy 335.227001 -44.806108) (xy 335.229586 -44.820676) (xy 335.230216 -44.849796)
			(xy 335.229726 -44.875545) (xy 335.221746 -44.926422) (xy 335.205979 -44.975448) (xy 335.182805 -45.021438)
			(xy 335.152784 -45.063282) (xy 335.116641 -45.099968) (xy 335.075251 -45.13061) (xy 335.029611 -45.154468)
			(xy 334.980827 -45.170966) (xy 334.930074 -45.179705) (xy 334.904334 -45.180504) (xy 334.891143 -45.181113)
			(xy 334.86573 -45.188251) (xy 334.842998 -45.201669) (xy 334.824469 -45.220469) (xy 334.811381 -45.243392)
			(xy 334.804612 -45.268906) (xy 334.804258 -45.282104) (xy 334.804258 -45.675883) (xy 336.16951 -45.675883)
			(xy 336.16951 -45.623909) (xy 336.17764 -45.572574) (xy 336.193701 -45.523144) (xy 336.217297 -45.476834)
			(xy 336.247847 -45.434786) (xy 336.284598 -45.398035) (xy 336.326646 -45.367485) (xy 336.372956 -45.343889)
			(xy 336.422386 -45.327828) (xy 336.473721 -45.319698) (xy 336.525695 -45.319698) (xy 336.57703 -45.327828)
			(xy 336.62646 -45.343889) (xy 336.67277 -45.367485) (xy 336.714818 -45.398035) (xy 336.751569 -45.434786)
			(xy 336.782119 -45.476834) (xy 336.805715 -45.523144) (xy 336.821776 -45.572574) (xy 336.829906 -45.623909)
			(xy 336.830416 -45.649896) (xy 336.829906 -45.675883) (xy 336.821776 -45.727218) (xy 336.805715 -45.776648)
			(xy 336.782119 -45.822958) (xy 336.751569 -45.865006) (xy 336.714818 -45.901757) (xy 336.67277 -45.932307)
			(xy 336.62646 -45.955903) (xy 336.57703 -45.971964) (xy 336.525695 -45.980094) (xy 336.473721 -45.980094)
			(xy 336.422386 -45.971964) (xy 336.372956 -45.955903) (xy 336.326646 -45.932307) (xy 336.284598 -45.901757)
			(xy 336.247847 -45.865006) (xy 336.217297 -45.822958) (xy 336.193701 -45.776648) (xy 336.17764 -45.727218)
			(xy 336.16951 -45.675883) (xy 334.804258 -45.675883) (xy 334.804258 -46.017688) (xy 334.804674 -46.030883)
			(xy 334.811437 -46.056392) (xy 334.824512 -46.079316) (xy 334.843028 -46.098121) (xy 334.865745 -46.111551)
			(xy 334.891146 -46.118709) (xy 334.904334 -46.119288) (xy 334.93007 -46.120156) (xy 334.980817 -46.128881)
			(xy 335.029598 -46.145367) (xy 335.075234 -46.169216) (xy 335.116621 -46.199851) (xy 335.152758 -46.236532)
			(xy 335.182773 -46.278371) (xy 335.205939 -46.324357) (xy 335.221696 -46.373378) (xy 335.229663 -46.42425)
			(xy 335.230216 -46.449996) (xy 335.229707 -46.475983) (xy 336.16951 -46.475983) (xy 336.16951 -46.424009)
			(xy 336.17764 -46.372674) (xy 336.193701 -46.323244) (xy 336.217297 -46.276934) (xy 336.247847 -46.234886)
			(xy 336.284598 -46.198135) (xy 336.326646 -46.167585) (xy 336.372956 -46.143989) (xy 336.422386 -46.127928)
			(xy 336.473721 -46.119798) (xy 336.525695 -46.119798) (xy 336.57703 -46.127928) (xy 336.62646 -46.143989)
			(xy 336.67277 -46.167585) (xy 336.714818 -46.198135) (xy 336.751569 -46.234886) (xy 336.782119 -46.276934)
			(xy 336.805715 -46.323244) (xy 336.821776 -46.372674) (xy 336.829906 -46.424009) (xy 336.830416 -46.449996)
			(xy 336.829906 -46.475983) (xy 336.96961 -46.475983) (xy 336.96961 -46.424009) (xy 336.97774 -46.372674)
			(xy 336.993801 -46.323244) (xy 337.017397 -46.276934) (xy 337.047947 -46.234886) (xy 337.084698 -46.198135)
			(xy 337.126746 -46.167585) (xy 337.173056 -46.143989) (xy 337.222486 -46.127928) (xy 337.273821 -46.119798)
			(xy 337.325795 -46.119798) (xy 337.37713 -46.127928) (xy 337.42656 -46.143989) (xy 337.47287 -46.167585)
			(xy 337.514918 -46.198135) (xy 337.551669 -46.234886) (xy 337.582219 -46.276934) (xy 337.605815 -46.323244)
			(xy 337.621876 -46.372674) (xy 337.630006 -46.424009) (xy 337.630516 -46.449996) (xy 337.630006 -46.475983)
			(xy 337.621876 -46.527318) (xy 337.605815 -46.576748) (xy 337.582219 -46.623058) (xy 337.551669 -46.665106)
			(xy 337.514918 -46.701857) (xy 337.47287 -46.732407) (xy 337.42656 -46.756003) (xy 337.37713 -46.772064)
			(xy 337.325795 -46.780194) (xy 337.273821 -46.780194) (xy 337.222486 -46.772064) (xy 337.173056 -46.756003)
			(xy 337.126746 -46.732407) (xy 337.084698 -46.701857) (xy 337.047947 -46.665106) (xy 337.017397 -46.623058)
			(xy 336.993801 -46.576748) (xy 336.97774 -46.527318) (xy 336.96961 -46.475983) (xy 336.829906 -46.475983)
			(xy 336.821776 -46.527318) (xy 336.805715 -46.576748) (xy 336.782119 -46.623058) (xy 336.751569 -46.665106)
			(xy 336.714818 -46.701857) (xy 336.67277 -46.732407) (xy 336.62646 -46.756003) (xy 336.57703 -46.772064)
			(xy 336.525695 -46.780194) (xy 336.473721 -46.780194) (xy 336.422386 -46.772064) (xy 336.372956 -46.756003)
			(xy 336.326646 -46.732407) (xy 336.284598 -46.701857) (xy 336.247847 -46.665106) (xy 336.217297 -46.623058)
			(xy 336.193701 -46.576748) (xy 336.17764 -46.527318) (xy 336.16951 -46.475983) (xy 335.229707 -46.475983)
			(xy 335.229707 -46.475984) (xy 335.221577 -46.527319) (xy 335.205516 -46.576751) (xy 335.181921 -46.623061)
			(xy 335.151371 -46.665111) (xy 335.11462 -46.701863) (xy 335.072572 -46.732414) (xy 335.026262 -46.756012)
			(xy 334.976831 -46.772074) (xy 334.925496 -46.780206) (xy 334.899508 -46.780704) (xy 334.889833 -46.780626)
			(xy 334.870516 -46.779484) (xy 334.8609 -46.778418) (xy 334.858106 -46.778164) (xy 334.804258 -46.778164)
			(xy 334.804258 -46.921928) (xy 334.858106 -46.921928) (xy 334.8609 -46.921674) (xy 334.870516 -46.920606)
			(xy 334.889833 -46.919465) (xy 334.899508 -46.919388) (xy 334.925495 -46.919898) (xy 334.976829 -46.92803)
			(xy 335.026259 -46.944092) (xy 335.072568 -46.967688) (xy 335.114616 -46.998239) (xy 335.151367 -47.03499)
			(xy 335.181916 -47.077039) (xy 335.205511 -47.123348) (xy 335.221572 -47.172779) (xy 335.229702 -47.224113)
			(xy 335.229702 -47.276083) (xy 336.16951 -47.276083) (xy 336.16951 -47.224109) (xy 336.17764 -47.172774)
			(xy 336.193701 -47.123344) (xy 336.217297 -47.077034) (xy 336.247847 -47.034986) (xy 336.284598 -46.998235)
			(xy 336.326646 -46.967685) (xy 336.372956 -46.944089) (xy 336.422386 -46.928028) (xy 336.473721 -46.919898)
			(xy 336.525695 -46.919898) (xy 336.57703 -46.928028) (xy 336.62646 -46.944089) (xy 336.67277 -46.967685)
			(xy 336.714818 -46.998235) (xy 336.751569 -47.034986) (xy 336.782119 -47.077034) (xy 336.805715 -47.123344)
			(xy 336.821776 -47.172774) (xy 336.829906 -47.224109) (xy 336.830416 -47.250096) (xy 336.829906 -47.276083)
			(xy 336.96961 -47.276083) (xy 336.96961 -47.224109) (xy 336.97774 -47.172774) (xy 336.993801 -47.123344)
			(xy 337.017397 -47.077034) (xy 337.047947 -47.034986) (xy 337.084698 -46.998235) (xy 337.126746 -46.967685)
			(xy 337.173056 -46.944089) (xy 337.222486 -46.928028) (xy 337.273821 -46.919898) (xy 337.325795 -46.919898)
			(xy 337.37713 -46.928028) (xy 337.42656 -46.944089) (xy 337.47287 -46.967685) (xy 337.514918 -46.998235)
			(xy 337.551669 -47.034986) (xy 337.582219 -47.077034) (xy 337.605815 -47.123344) (xy 337.621876 -47.172774)
			(xy 337.630006 -47.224109) (xy 337.630516 -47.250096) (xy 337.630006 -47.276083) (xy 337.621876 -47.327418)
			(xy 337.605815 -47.376848) (xy 337.582219 -47.423158) (xy 337.551669 -47.465206) (xy 337.514918 -47.501957)
			(xy 337.47287 -47.532507) (xy 337.42656 -47.556103) (xy 337.37713 -47.572164) (xy 337.325795 -47.580294)
			(xy 337.273821 -47.580294) (xy 337.222486 -47.572164) (xy 337.173056 -47.556103) (xy 337.126746 -47.532507)
			(xy 337.084698 -47.501957) (xy 337.047947 -47.465206) (xy 337.017397 -47.423158) (xy 336.993801 -47.376848)
			(xy 336.97774 -47.327418) (xy 336.96961 -47.276083) (xy 336.829906 -47.276083) (xy 336.821776 -47.327418)
			(xy 336.805715 -47.376848) (xy 336.782119 -47.423158) (xy 336.751569 -47.465206) (xy 336.714818 -47.501957)
			(xy 336.67277 -47.532507) (xy 336.62646 -47.556103) (xy 336.57703 -47.572164) (xy 336.525695 -47.580294)
			(xy 336.473721 -47.580294) (xy 336.422386 -47.572164) (xy 336.372956 -47.556103) (xy 336.326646 -47.532507)
			(xy 336.284598 -47.501957) (xy 336.247847 -47.465206) (xy 336.217297 -47.423158) (xy 336.193701 -47.376848)
			(xy 336.17764 -47.327418) (xy 336.16951 -47.276083) (xy 335.229702 -47.276083) (xy 335.229702 -47.276087)
			(xy 335.221572 -47.327421) (xy 335.205511 -47.376852) (xy 335.181916 -47.423161) (xy 335.151367 -47.46521)
			(xy 335.114616 -47.501961) (xy 335.072568 -47.532512) (xy 335.026259 -47.556108) (xy 334.976829 -47.57217)
			(xy 334.925495 -47.580302) (xy 334.899508 -47.580804) (xy 334.889833 -47.580726) (xy 334.870516 -47.579584)
			(xy 334.8609 -47.578518) (xy 334.858106 -47.578264) (xy 334.804258 -47.578264) (xy 334.804258 -47.722028)
			(xy 334.858106 -47.722028) (xy 334.8609 -47.721774) (xy 334.870516 -47.720706) (xy 334.889833 -47.719565)
			(xy 334.899508 -47.719488) (xy 334.925495 -47.719998) (xy 334.976829 -47.72813) (xy 335.026258 -47.744191)
			(xy 335.072567 -47.767788) (xy 335.114614 -47.798337) (xy 335.151365 -47.835089) (xy 335.181915 -47.877136)
			(xy 335.20551 -47.923445) (xy 335.221571 -47.972875) (xy 335.229702 -48.024209) (xy 335.230216 -48.050196)
			(xy 335.229726 -48.075945) (xy 335.229689 -48.076183) (xy 336.96961 -48.076183) (xy 336.96961 -48.024209)
			(xy 336.97774 -47.972874) (xy 336.993801 -47.923444) (xy 337.017397 -47.877134) (xy 337.047947 -47.835086)
			(xy 337.084698 -47.798335) (xy 337.126746 -47.767785) (xy 337.173056 -47.744189) (xy 337.222486 -47.728128)
			(xy 337.273821 -47.719998) (xy 337.325795 -47.719998) (xy 337.37713 -47.728128) (xy 337.42656 -47.744189)
			(xy 337.47287 -47.767785) (xy 337.514918 -47.798335) (xy 337.551669 -47.835086) (xy 337.582219 -47.877134)
			(xy 337.605815 -47.923444) (xy 337.621876 -47.972874) (xy 337.630006 -48.024209) (xy 337.630516 -48.050196)
			(xy 337.630006 -48.076183) (xy 337.621876 -48.127518) (xy 337.605815 -48.176948) (xy 337.582219 -48.223258)
			(xy 337.551669 -48.265306) (xy 337.514918 -48.302057) (xy 337.47287 -48.332607) (xy 337.42656 -48.356203)
			(xy 337.37713 -48.372264) (xy 337.325795 -48.380394) (xy 337.273821 -48.380394) (xy 337.222486 -48.372264)
			(xy 337.173056 -48.356203) (xy 337.126746 -48.332607) (xy 337.084698 -48.302057) (xy 337.047947 -48.265306)
			(xy 337.017397 -48.223258) (xy 336.993801 -48.176948) (xy 336.97774 -48.127518) (xy 336.96961 -48.076183)
			(xy 335.229689 -48.076183) (xy 335.221746 -48.126822) (xy 335.205979 -48.175848) (xy 335.182805 -48.221838)
			(xy 335.152784 -48.263682) (xy 335.116641 -48.300368) (xy 335.075251 -48.33101) (xy 335.029611 -48.354868)
			(xy 334.980827 -48.371366) (xy 334.930074 -48.380105) (xy 334.904334 -48.380904) (xy 334.891143 -48.381513)
			(xy 334.86573 -48.388651) (xy 334.842998 -48.402069) (xy 334.824469 -48.420869) (xy 334.811381 -48.443792)
			(xy 334.804612 -48.469306) (xy 334.804258 -48.482504) (xy 334.804258 -49.218088) (xy 334.804674 -49.231283)
			(xy 334.811437 -49.256792) (xy 334.824512 -49.279716) (xy 334.843028 -49.298521) (xy 334.865745 -49.311951)
			(xy 334.891146 -49.319109) (xy 334.904334 -49.319688) (xy 334.930073 -49.320555) (xy 334.980826 -49.329279)
			(xy 335.029614 -49.345765) (xy 335.075258 -49.369612) (xy 335.116653 -49.400246) (xy 335.152801 -49.436926)
			(xy 335.182826 -49.478765) (xy 335.206004 -49.524752) (xy 335.221775 -49.573775) (xy 335.229757 -49.624651)
			(xy 335.229757 -49.676149) (xy 335.22972 -49.676383) (xy 335.36941 -49.676383) (xy 335.36941 -49.624409)
			(xy 335.37754 -49.573074) (xy 335.393601 -49.523644) (xy 335.417197 -49.477334) (xy 335.447747 -49.435286)
			(xy 335.484498 -49.398535) (xy 335.526546 -49.367985) (xy 335.572856 -49.344389) (xy 335.622286 -49.328328)
			(xy 335.673621 -49.320198) (xy 335.725595 -49.320198) (xy 335.77693 -49.328328) (xy 335.82636 -49.344389)
			(xy 335.87267 -49.367985) (xy 335.914718 -49.398535) (xy 335.951469 -49.435286) (xy 335.982019 -49.477334)
			(xy 336.005615 -49.523644) (xy 336.021676 -49.573074) (xy 336.029806 -49.624409) (xy 336.030316 -49.650396)
			(xy 336.029806 -49.676383) (xy 336.16951 -49.676383) (xy 336.16951 -49.624409) (xy 336.17764 -49.573074)
			(xy 336.193701 -49.523644) (xy 336.217297 -49.477334) (xy 336.247847 -49.435286) (xy 336.284598 -49.398535)
			(xy 336.326646 -49.367985) (xy 336.372956 -49.344389) (xy 336.422386 -49.328328) (xy 336.473721 -49.320198)
			(xy 336.525695 -49.320198) (xy 336.57703 -49.328328) (xy 336.62646 -49.344389) (xy 336.67277 -49.367985)
			(xy 336.714818 -49.398535) (xy 336.751569 -49.435286) (xy 336.782119 -49.477334) (xy 336.805715 -49.523644)
			(xy 336.821776 -49.573074) (xy 336.829906 -49.624409) (xy 336.830416 -49.650396) (xy 336.829906 -49.676383)
			(xy 336.96961 -49.676383) (xy 336.96961 -49.624409) (xy 336.97774 -49.573074) (xy 336.993801 -49.523644)
			(xy 337.017397 -49.477334) (xy 337.047947 -49.435286) (xy 337.084698 -49.398535) (xy 337.126746 -49.367985)
			(xy 337.173056 -49.344389) (xy 337.222486 -49.328328) (xy 337.273821 -49.320198) (xy 337.325795 -49.320198)
			(xy 337.37713 -49.328328) (xy 337.42656 -49.344389) (xy 337.47287 -49.367985) (xy 337.514918 -49.398535)
			(xy 337.551669 -49.435286) (xy 337.582219 -49.477334) (xy 337.605815 -49.523644) (xy 337.621876 -49.573074)
			(xy 337.630006 -49.624409) (xy 337.630516 -49.650396) (xy 337.630006 -49.676383) (xy 337.621876 -49.727718)
			(xy 337.605815 -49.777148) (xy 337.582219 -49.823458) (xy 337.551669 -49.865506) (xy 337.514918 -49.902257)
			(xy 337.47287 -49.932807) (xy 337.42656 -49.956403) (xy 337.37713 -49.972464) (xy 337.325795 -49.980594)
			(xy 337.273821 -49.980594) (xy 337.222486 -49.972464) (xy 337.173056 -49.956403) (xy 337.126746 -49.932807)
			(xy 337.084698 -49.902257) (xy 337.047947 -49.865506) (xy 337.017397 -49.823458) (xy 336.993801 -49.777148)
			(xy 336.97774 -49.727718) (xy 336.96961 -49.676383) (xy 336.829906 -49.676383) (xy 336.821776 -49.727718)
			(xy 336.805715 -49.777148) (xy 336.782119 -49.823458) (xy 336.751569 -49.865506) (xy 336.714818 -49.902257)
			(xy 336.67277 -49.932807) (xy 336.62646 -49.956403) (xy 336.57703 -49.972464) (xy 336.525695 -49.980594)
			(xy 336.473721 -49.980594) (xy 336.422386 -49.972464) (xy 336.372956 -49.956403) (xy 336.326646 -49.932807)
			(xy 336.284598 -49.902257) (xy 336.247847 -49.865506) (xy 336.217297 -49.823458) (xy 336.193701 -49.777148)
			(xy 336.17764 -49.727718) (xy 336.16951 -49.676383) (xy 336.029806 -49.676383) (xy 336.021676 -49.727718)
			(xy 336.005615 -49.777148) (xy 335.982019 -49.823458) (xy 335.951469 -49.865506) (xy 335.914718 -49.902257)
			(xy 335.87267 -49.932807) (xy 335.82636 -49.956403) (xy 335.77693 -49.972464) (xy 335.725595 -49.980594)
			(xy 335.673621 -49.980594) (xy 335.622286 -49.972464) (xy 335.572856 -49.956403) (xy 335.526546 -49.932807)
			(xy 335.484498 -49.902257) (xy 335.447747 -49.865506) (xy 335.417197 -49.823458) (xy 335.393601 -49.777148)
			(xy 335.37754 -49.727718) (xy 335.36941 -49.676383) (xy 335.22972 -49.676383) (xy 335.221775 -49.727024)
			(xy 335.206004 -49.776048) (xy 335.182826 -49.822035) (xy 335.152801 -49.863874) (xy 335.116653 -49.900554)
			(xy 335.075258 -49.931187) (xy 335.029615 -49.955035) (xy 334.980827 -49.971521) (xy 334.930073 -49.980245)
			(xy 334.904334 -49.981104) (xy 334.891143 -49.981713) (xy 334.86573 -49.988851) (xy 334.842998 -50.002269)
			(xy 334.824469 -50.021069) (xy 334.811381 -50.043992) (xy 334.804612 -50.069506) (xy 334.804258 -50.082704)
			(xy 334.804258 -50.476483) (xy 335.36941 -50.476483) (xy 335.36941 -50.424509) (xy 335.37754 -50.373174)
			(xy 335.393601 -50.323744) (xy 335.417197 -50.277434) (xy 335.447747 -50.235386) (xy 335.484498 -50.198635)
			(xy 335.526546 -50.168085) (xy 335.572856 -50.144489) (xy 335.622286 -50.128428) (xy 335.673621 -50.120298)
			(xy 335.725595 -50.120298) (xy 335.77693 -50.128428) (xy 335.82636 -50.144489) (xy 335.87267 -50.168085)
			(xy 335.914718 -50.198635) (xy 335.951469 -50.235386) (xy 335.982019 -50.277434) (xy 336.005615 -50.323744)
			(xy 336.021676 -50.373174) (xy 336.029806 -50.424509) (xy 336.030316 -50.450496) (xy 336.029806 -50.476483)
			(xy 336.96961 -50.476483) (xy 336.96961 -50.424509) (xy 336.97774 -50.373174) (xy 336.993801 -50.323744)
			(xy 337.017397 -50.277434) (xy 337.047947 -50.235386) (xy 337.084698 -50.198635) (xy 337.126746 -50.168085)
			(xy 337.173056 -50.144489) (xy 337.222486 -50.128428) (xy 337.273821 -50.120298) (xy 337.325795 -50.120298)
			(xy 337.37713 -50.128428) (xy 337.42656 -50.144489) (xy 337.47287 -50.168085) (xy 337.514918 -50.198635)
			(xy 337.551669 -50.235386) (xy 337.582219 -50.277434) (xy 337.605815 -50.323744) (xy 337.621876 -50.373174)
			(xy 337.630006 -50.424509) (xy 337.630516 -50.450496) (xy 337.630006 -50.476483) (xy 337.621876 -50.527818)
			(xy 337.605815 -50.577248) (xy 337.582219 -50.623558) (xy 337.551669 -50.665606) (xy 337.514918 -50.702357)
			(xy 337.47287 -50.732907) (xy 337.42656 -50.756503) (xy 337.37713 -50.772564) (xy 337.325795 -50.780694)
			(xy 337.273821 -50.780694) (xy 337.222486 -50.772564) (xy 337.173056 -50.756503) (xy 337.126746 -50.732907)
			(xy 337.084698 -50.702357) (xy 337.047947 -50.665606) (xy 337.017397 -50.623558) (xy 336.993801 -50.577248)
			(xy 336.97774 -50.527818) (xy 336.96961 -50.476483) (xy 336.029806 -50.476483) (xy 336.021676 -50.527818)
			(xy 336.005615 -50.577248) (xy 335.982019 -50.623558) (xy 335.951469 -50.665606) (xy 335.914718 -50.702357)
			(xy 335.87267 -50.732907) (xy 335.82636 -50.756503) (xy 335.77693 -50.772564) (xy 335.725595 -50.780694)
			(xy 335.673621 -50.780694) (xy 335.622286 -50.772564) (xy 335.572856 -50.756503) (xy 335.526546 -50.732907)
			(xy 335.484498 -50.702357) (xy 335.447747 -50.665606) (xy 335.417197 -50.623558) (xy 335.393601 -50.577248)
			(xy 335.37754 -50.527818) (xy 335.36941 -50.476483) (xy 334.804258 -50.476483) (xy 334.804258 -51.100736)
			(xy 334.628411 -51.276583) (xy 335.36941 -51.276583) (xy 335.36941 -51.224609) (xy 335.37754 -51.173274)
			(xy 335.393601 -51.123844) (xy 335.417197 -51.077534) (xy 335.447747 -51.035486) (xy 335.484498 -50.998735)
			(xy 335.526546 -50.968185) (xy 335.572856 -50.944589) (xy 335.622286 -50.928528) (xy 335.673621 -50.920398)
			(xy 335.725595 -50.920398) (xy 335.77693 -50.928528) (xy 335.82636 -50.944589) (xy 335.87267 -50.968185)
			(xy 335.914718 -50.998735) (xy 335.951469 -51.035486) (xy 335.982019 -51.077534) (xy 336.005615 -51.123844)
			(xy 336.021676 -51.173274) (xy 336.029806 -51.224609) (xy 336.030316 -51.250596) (xy 336.029806 -51.276583)
			(xy 336.96961 -51.276583) (xy 336.96961 -51.224609) (xy 336.97774 -51.173274) (xy 336.993801 -51.123844)
			(xy 337.017397 -51.077534) (xy 337.047947 -51.035486) (xy 337.084698 -50.998735) (xy 337.126746 -50.968185)
			(xy 337.173056 -50.944589) (xy 337.222486 -50.928528) (xy 337.273821 -50.920398) (xy 337.325795 -50.920398)
			(xy 337.37713 -50.928528) (xy 337.42656 -50.944589) (xy 337.47287 -50.968185) (xy 337.514918 -50.998735)
			(xy 337.551669 -51.035486) (xy 337.582219 -51.077534) (xy 337.605815 -51.123844) (xy 337.621876 -51.173274)
			(xy 337.630006 -51.224609) (xy 337.630516 -51.250596) (xy 337.630006 -51.276583) (xy 337.621876 -51.327918)
			(xy 337.605815 -51.377348) (xy 337.582219 -51.423658) (xy 337.551669 -51.465706) (xy 337.514918 -51.502457)
			(xy 337.47287 -51.533007) (xy 337.42656 -51.556603) (xy 337.37713 -51.572664) (xy 337.325795 -51.580794)
			(xy 337.273821 -51.580794) (xy 337.222486 -51.572664) (xy 337.173056 -51.556603) (xy 337.126746 -51.533007)
			(xy 337.084698 -51.502457) (xy 337.047947 -51.465706) (xy 337.017397 -51.423658) (xy 336.993801 -51.377348)
			(xy 336.97774 -51.327918) (xy 336.96961 -51.276583) (xy 336.029806 -51.276583) (xy 336.021676 -51.327918)
			(xy 336.005615 -51.377348) (xy 335.982019 -51.423658) (xy 335.951469 -51.465706) (xy 335.914718 -51.502457)
			(xy 335.87267 -51.533007) (xy 335.82636 -51.556603) (xy 335.77693 -51.572664) (xy 335.725595 -51.580794)
			(xy 335.673621 -51.580794) (xy 335.622286 -51.572664) (xy 335.572856 -51.556603) (xy 335.526546 -51.533007)
			(xy 335.484498 -51.502457) (xy 335.447747 -51.465706) (xy 335.417197 -51.423658) (xy 335.393601 -51.377348)
			(xy 335.37754 -51.327918) (xy 335.36941 -51.276583) (xy 334.628411 -51.276583) (xy 333.913734 -51.99126)
			(xy 333.913734 -52.421282) (xy 334.310736 -52.818284) (xy 334.33131 -52.818538) (xy 334.357195 -52.819491)
			(xy 334.408207 -52.828461) (xy 334.457192 -52.845285) (xy 334.502951 -52.869552) (xy 334.544359 -52.900665)
			(xy 334.580402 -52.937861) (xy 334.595724 -52.958746)
		)
		(stroke
			(width 0)
			(type solid)
		)
		(fill yes)
		(layer "In13.Cu")
		(net "P1V8_PCH_AUX")
	)
	(gr_poly
		(pts
			(xy 469.65108 -76.647548) (xy 469.65108 -55.926228) (xy 463.35315 -49.628298) (xy 460.00289 -49.628298)
			(xy 458.797914 -48.423576) (xy 446.740026 -48.423576) (xy 446.175638 -48.987964) (xy 446.010538 -48.987964)
			(xy 445.95288 -49.045368) (xy 442.95314 -49.045368) (xy 442.56325 -49.435258) (xy 442.549397 -49.455753)
			(xy 442.531426 -49.476406) (xy 448.662047 -49.476406) (xy 448.666083 -49.392959) (xy 448.678155 -49.310291)
			(xy 448.698148 -49.229174) (xy 448.725877 -49.150365) (xy 448.761083 -49.0746) (xy 448.803437 -49.002587)
			(xy 448.852543 -48.934998) (xy 448.907944 -48.872464) (xy 448.969121 -48.815569) (xy 449.035504 -48.764843)
			(xy 449.106472 -48.720762) (xy 449.181364 -48.683736) (xy 449.25948 -48.65411) (xy 449.34009 -48.632162)
			(xy 449.422442 -48.618097) (xy 449.505768 -48.612045) (xy 449.589288 -48.614064) (xy 449.672224 -48.624134)
			(xy 449.7538 -48.642162) (xy 449.833256 -48.667979) (xy 449.909849 -48.701344) (xy 449.982865 -48.741945)
			(xy 450.051621 -48.789404) (xy 450.115475 -48.843277) (xy 450.173832 -48.903062) (xy 450.226147 -48.968199)
			(xy 450.27193 -49.038082) (xy 450.310755 -49.112057) (xy 450.34226 -49.189434) (xy 450.366149 -49.269491)
			(xy 450.3822 -49.351479) (xy 450.390263 -49.434634) (xy 450.390768 -49.476406) (xy 456.170287 -49.476406)
			(xy 456.174323 -49.392959) (xy 456.186395 -49.310291) (xy 456.206388 -49.229174) (xy 456.234117 -49.150365)
			(xy 456.269323 -49.0746) (xy 456.311677 -49.002587) (xy 456.360783 -48.934998) (xy 456.416184 -48.872464)
			(xy 456.477361 -48.815569) (xy 456.543744 -48.764843) (xy 456.614712 -48.720762) (xy 456.689604 -48.683736)
			(xy 456.76772 -48.65411) (xy 456.84833 -48.632162) (xy 456.930682 -48.618097) (xy 457.014008 -48.612045)
			(xy 457.097528 -48.614064) (xy 457.180464 -48.624134) (xy 457.26204 -48.642162) (xy 457.341496 -48.667979)
			(xy 457.418089 -48.701344) (xy 457.491105 -48.741945) (xy 457.559861 -48.789404) (xy 457.623715 -48.843277)
			(xy 457.682072 -48.903062) (xy 457.734387 -48.968199) (xy 457.78017 -49.038082) (xy 457.818995 -49.112057)
			(xy 457.8505 -49.189434) (xy 457.874389 -49.269491) (xy 457.89044 -49.351479) (xy 457.898503 -49.434634)
			(xy 457.899008 -49.476406) (xy 457.898503 -49.518178) (xy 457.89044 -49.601333) (xy 457.874389 -49.683321)
			(xy 457.8505 -49.763378) (xy 457.818995 -49.840755) (xy 457.78017 -49.91473) (xy 457.734387 -49.984613)
			(xy 457.682072 -50.04975) (xy 457.623715 -50.109535) (xy 457.559861 -50.163408) (xy 457.491105 -50.210867)
			(xy 457.418089 -50.251468) (xy 457.341496 -50.284833) (xy 457.26204 -50.31065) (xy 457.180464 -50.328678)
			(xy 457.097528 -50.338748) (xy 457.014008 -50.340767) (xy 456.930682 -50.334715) (xy 456.84833 -50.32065)
			(xy 456.76772 -50.298702) (xy 456.689604 -50.269076) (xy 456.614712 -50.23205) (xy 456.543744 -50.187969)
			(xy 456.477361 -50.137243) (xy 456.416184 -50.080348) (xy 456.360783 -50.017814) (xy 456.311677 -49.950225)
			(xy 456.269323 -49.878212) (xy 456.234117 -49.802447) (xy 456.206388 -49.723638) (xy 456.186395 -49.642521)
			(xy 456.174323 -49.559853) (xy 456.170287 -49.476406) (xy 450.390768 -49.476406) (xy 450.390263 -49.518178)
			(xy 450.3822 -49.601333) (xy 450.366149 -49.683321) (xy 450.34226 -49.763378) (xy 450.310755 -49.840755)
			(xy 450.27193 -49.91473) (xy 450.226147 -49.984613) (xy 450.173832 -50.04975) (xy 450.115475 -50.109535)
			(xy 450.051621 -50.163408) (xy 449.982865 -50.210867) (xy 449.909849 -50.251468) (xy 449.833256 -50.284833)
			(xy 449.7538 -50.31065) (xy 449.672224 -50.328678) (xy 449.589288 -50.338748) (xy 449.505768 -50.340767)
			(xy 449.422442 -50.334715) (xy 449.34009 -50.32065) (xy 449.25948 -50.298702) (xy 449.181364 -50.269076)
			(xy 449.106472 -50.23205) (xy 449.035504 -50.187969) (xy 448.969121 -50.137243) (xy 448.907944 -50.080348)
			(xy 448.852543 -50.017814) (xy 448.803437 -49.950225) (xy 448.761083 -49.878212) (xy 448.725877 -49.802447)
			(xy 448.698148 -49.723638) (xy 448.678155 -49.642521) (xy 448.666083 -49.559853) (xy 448.662047 -49.476406)
			(xy 442.531426 -49.476406) (xy 442.516925 -49.493072) (xy 442.4796 -49.525537) (xy 442.45911 -49.539398)
			(xy 440.02706 -51.971448) (xy 440.02706 -52.517548) (xy 444.575182 -52.517548) (xy 444.579253 -52.461926)
			(xy 444.591379 -52.407489) (xy 444.611302 -52.355398) (xy 444.638598 -52.306763) (xy 444.672684 -52.26262)
			(xy 444.712833 -52.223911) (xy 444.758191 -52.19146) (xy 444.807791 -52.165959) (xy 444.860575 -52.147952)
			(xy 444.915418 -52.137822) (xy 444.971152 -52.135785) (xy 445.026589 -52.141885) (xy 445.080546 -52.155991)
			(xy 445.131875 -52.177803) (xy 445.179481 -52.206857) (xy 445.222349 -52.242532) (xy 445.259566 -52.284069)
			(xy 445.290339 -52.330582) (xy 445.314011 -52.381079) (xy 445.330079 -52.434486) (xy 445.338199 -52.489662)
			(xy 445.338708 -52.517548) (xy 445.338199 -52.545434) (xy 445.330079 -52.60061) (xy 445.314011 -52.654017)
			(xy 445.290339 -52.704514) (xy 445.259566 -52.751027) (xy 445.222349 -52.792564) (xy 445.179481 -52.828239)
			(xy 445.131875 -52.857293) (xy 445.080546 -52.879105) (xy 445.026589 -52.893211) (xy 444.971152 -52.899311)
			(xy 444.915418 -52.897274) (xy 444.860575 -52.887144) (xy 444.807791 -52.869137) (xy 444.758191 -52.843636)
			(xy 444.712833 -52.811185) (xy 444.672684 -52.772476) (xy 444.638598 -52.728333) (xy 444.611302 -52.679698)
			(xy 444.591379 -52.627607) (xy 444.579253 -52.57317) (xy 444.575182 -52.517548) (xy 440.02706 -52.517548)
			(xy 440.02706 -56.88633) (xy 440.94303 -56.88633) (xy 440.946755 -56.833083) (xy 440.957867 -56.780876)
			(xy 440.976147 -56.730727) (xy 441.00124 -56.683617) (xy 441.032655 -56.640464) (xy 441.069779 -56.602112)
			(xy 441.090558 -56.585358) (xy 441.102318 -56.57541) (xy 441.119841 -56.550102) (xy 441.129025 -56.520721)
			(xy 441.129034 -56.489938) (xy 441.119868 -56.460552) (xy 441.102359 -56.435234) (xy 441.090558 -56.425338)
			(xy 441.069823 -56.408528) (xy 441.032693 -56.370181) (xy 441.001272 -56.327033) (xy 440.976172 -56.279927)
			(xy 440.957883 -56.229781) (xy 440.946764 -56.177575) (xy 440.94303 -56.12433) (xy 440.946755 -56.071083)
			(xy 440.957867 -56.018876) (xy 440.976147 -55.968727) (xy 441.00124 -55.921617) (xy 441.032655 -55.878464)
			(xy 441.069779 -55.840112) (xy 441.090558 -55.823358) (xy 441.102318 -55.81341) (xy 441.119841 -55.788102)
			(xy 441.129025 -55.758721) (xy 441.129034 -55.727938) (xy 441.119868 -55.698552) (xy 441.102359 -55.673234)
			(xy 441.090558 -55.663338) (xy 441.069823 -55.646528) (xy 441.032693 -55.608181) (xy 441.001272 -55.565033)
			(xy 440.976172 -55.517927) (xy 440.957883 -55.467781) (xy 440.946764 -55.415575) (xy 440.94303 -55.36233)
			(xy 440.946755 -55.309083) (xy 440.957867 -55.256876) (xy 440.976147 -55.206727) (xy 441.00124 -55.159617)
			(xy 441.032655 -55.116464) (xy 441.069779 -55.078112) (xy 441.090558 -55.061358) (xy 441.102318 -55.05141)
			(xy 441.119841 -55.026102) (xy 441.129025 -54.996721) (xy 441.129034 -54.965938) (xy 441.119868 -54.936552)
			(xy 441.102359 -54.911234) (xy 441.090558 -54.901338) (xy 441.069823 -54.884528) (xy 441.032693 -54.846181)
			(xy 441.001272 -54.803033) (xy 440.976172 -54.755927) (xy 440.957883 -54.705781) (xy 440.946764 -54.653575)
			(xy 440.94303 -54.60033) (xy 440.946755 -54.547083) (xy 440.957867 -54.494876) (xy 440.976147 -54.444727)
			(xy 441.00124 -54.397617) (xy 441.032655 -54.354464) (xy 441.069779 -54.316112) (xy 441.090558 -54.299358)
			(xy 441.102318 -54.28941) (xy 441.119841 -54.264102) (xy 441.129025 -54.234721) (xy 441.129034 -54.203938)
			(xy 441.119868 -54.174552) (xy 441.102359 -54.149234) (xy 441.090558 -54.139338) (xy 441.069823 -54.122528)
			(xy 441.032693 -54.084181) (xy 441.001272 -54.041033) (xy 440.976172 -53.993927) (xy 440.957883 -53.943781)
			(xy 440.946764 -53.891575) (xy 440.94303 -53.83833) (xy 440.946755 -53.785083) (xy 440.957867 -53.732876)
			(xy 440.976147 -53.682727) (xy 441.00124 -53.635617) (xy 441.032655 -53.592464) (xy 441.069779 -53.554112)
			(xy 441.090558 -53.537358) (xy 441.102318 -53.52741) (xy 441.119841 -53.502102) (xy 441.129025 -53.472721)
			(xy 441.129034 -53.441938) (xy 441.119868 -53.412552) (xy 441.102359 -53.387234) (xy 441.090558 -53.377338)
			(xy 441.068084 -53.359136) (xy 441.02835 -53.317117) (xy 440.995411 -53.269584) (xy 440.970022 -53.217625)
			(xy 440.952763 -53.16243) (xy 440.94403 -53.105263) (xy 440.943492 -53.076348) (xy 440.944 -53.049096)
			(xy 440.95175 -52.995147) (xy 440.9671 -52.94285) (xy 440.989737 -52.89327) (xy 441.0192 -52.847417)
			(xy 441.054889 -52.806223) (xy 441.096078 -52.770529) (xy 441.141928 -52.74106) (xy 441.191505 -52.718417)
			(xy 441.2438 -52.703061) (xy 441.297748 -52.695303) (xy 441.325 -52.69484) (xy 441.353918 -52.695343)
			(xy 441.41109 -52.704073) (xy 441.46629 -52.721333) (xy 441.518252 -52.746728) (xy 441.565785 -52.779675)
			(xy 441.607801 -52.819419) (xy 441.62599 -52.841906) (xy 441.635887 -52.853711) (xy 441.661211 -52.87123)
			(xy 441.690604 -52.880406) (xy 441.721396 -52.880406) (xy 441.750789 -52.87123) (xy 441.776113 -52.853711)
			(xy 441.78601 -52.841906) (xy 441.804197 -52.819419) (xy 441.846217 -52.779684) (xy 441.893753 -52.746745)
			(xy 441.945715 -52.721357) (xy 442.000914 -52.704102) (xy 442.058084 -52.695374) (xy 442.087 -52.69484)
			(xy 442.114255 -52.695255) (xy 442.16821 -52.703014) (xy 442.220512 -52.718372) (xy 442.270095 -52.741018)
			(xy 442.315951 -52.770491) (xy 442.357145 -52.806189) (xy 442.392838 -52.847388) (xy 442.422305 -52.893247)
			(xy 442.444945 -52.942833) (xy 442.460297 -52.995137) (xy 442.468048 -53.049093) (xy 442.468508 -53.076348)
			(xy 442.467987 -53.105265) (xy 442.464373 -53.128948) (xy 442.747426 -53.128948) (xy 442.747426 -53.074452)
			(xy 442.755182 -53.020511) (xy 442.770535 -52.968223) (xy 442.793173 -52.918652) (xy 442.822636 -52.872808)
			(xy 442.858323 -52.831623) (xy 442.899508 -52.795936) (xy 442.945352 -52.766473) (xy 442.994923 -52.743835)
			(xy 443.047211 -52.728482) (xy 443.101152 -52.720726) (xy 443.1284 -52.72024) (xy 443.157318 -52.720743)
			(xy 443.21449 -52.729473) (xy 443.26969 -52.746733) (xy 443.321652 -52.772128) (xy 443.369185 -52.805075)
			(xy 443.411201 -52.844819) (xy 443.42939 -52.867306) (xy 443.439287 -52.879111) (xy 443.464611 -52.89663)
			(xy 443.494004 -52.905806) (xy 443.524796 -52.905806) (xy 443.554189 -52.89663) (xy 443.579513 -52.879111)
			(xy 443.58941 -52.867306) (xy 443.607597 -52.844819) (xy 443.649617 -52.805084) (xy 443.697153 -52.772145)
			(xy 443.749115 -52.746757) (xy 443.804314 -52.729502) (xy 443.861484 -52.720774) (xy 443.8904 -52.72024)
			(xy 443.917655 -52.72063) (xy 443.971609 -52.728387) (xy 444.023911 -52.743744) (xy 444.073494 -52.766388)
			(xy 444.11935 -52.795858) (xy 444.160546 -52.831554) (xy 444.196242 -52.87275) (xy 444.225712 -52.918606)
			(xy 444.248356 -52.968189) (xy 444.263713 -53.020491) (xy 444.27147 -53.074445) (xy 444.27147 -53.128955)
			(xy 444.263713 -53.182909) (xy 444.248356 -53.235211) (xy 444.225712 -53.284794) (xy 444.196242 -53.33065)
			(xy 444.160546 -53.371846) (xy 444.11935 -53.407542) (xy 444.073494 -53.437012) (xy 444.023911 -53.459656)
			(xy 443.971609 -53.475013) (xy 443.917655 -53.48277) (xy 443.8904 -53.483256) (xy 443.861482 -53.482754)
			(xy 443.80431 -53.474024) (xy 443.74911 -53.456764) (xy 443.697148 -53.431369) (xy 443.649614 -53.398422)
			(xy 443.607599 -53.358677) (xy 443.58941 -53.33619) (xy 443.579513 -53.324385) (xy 443.554189 -53.306866)
			(xy 443.524796 -53.29769) (xy 443.494004 -53.29769) (xy 443.464611 -53.306866) (xy 443.439287 -53.324385)
			(xy 443.42939 -53.33619) (xy 443.411202 -53.358676) (xy 443.369182 -53.398412) (xy 443.321647 -53.431351)
			(xy 443.269685 -53.456739) (xy 443.214486 -53.473994) (xy 443.157316 -53.482722) (xy 443.1284 -53.483256)
			(xy 443.101152 -53.482674) (xy 443.047211 -53.474918) (xy 442.994923 -53.459565) (xy 442.945352 -53.436927)
			(xy 442.899508 -53.407464) (xy 442.858323 -53.371777) (xy 442.822636 -53.330592) (xy 442.793173 -53.284748)
			(xy 442.770535 -53.235177) (xy 442.755182 -53.182889) (xy 442.747426 -53.128948) (xy 442.464373 -53.128948)
			(xy 442.459263 -53.162438) (xy 442.442008 -53.217638) (xy 442.416617 -53.269601) (xy 442.383672 -53.317134)
			(xy 442.343929 -53.359149) (xy 442.321442 -53.377338) (xy 442.309586 -53.387181) (xy 442.292064 -53.412518)
			(xy 442.282891 -53.441927) (xy 442.2829 -53.472732) (xy 442.29209 -53.502135) (xy 442.309627 -53.527462)
			(xy 442.321442 -53.537358) (xy 442.342272 -53.554055) (xy 442.379403 -53.592415) (xy 442.410824 -53.635576)
			(xy 442.435922 -53.682696) (xy 442.454206 -53.732855) (xy 442.46532 -53.785073) (xy 442.469046 -53.83833)
			(xy 442.465312 -53.891586) (xy 442.45419 -53.943802) (xy 442.435898 -53.993958) (xy 442.410793 -54.041074)
			(xy 442.379365 -54.08423) (xy 442.342228 -54.122585) (xy 442.321442 -54.139338) (xy 442.309586 -54.149181)
			(xy 442.292064 -54.174518) (xy 442.282891 -54.203927) (xy 442.2829 -54.234732) (xy 442.29209 -54.264135)
			(xy 442.309627 -54.289462) (xy 442.321442 -54.299358) (xy 442.342272 -54.316055) (xy 442.379403 -54.354415)
			(xy 442.410824 -54.397576) (xy 442.435922 -54.444696) (xy 442.454206 -54.494855) (xy 442.46532 -54.547073)
			(xy 442.469046 -54.60033) (xy 442.465312 -54.653586) (xy 442.45419 -54.705802) (xy 442.435898 -54.755958)
			(xy 442.410793 -54.803074) (xy 442.379365 -54.84623) (xy 442.342228 -54.884585) (xy 442.321442 -54.901338)
			(xy 442.309586 -54.911181) (xy 442.292064 -54.936518) (xy 442.282891 -54.965927) (xy 442.2829 -54.996732)
			(xy 442.29209 -55.026135) (xy 442.309627 -55.051462) (xy 442.321442 -55.061358) (xy 442.342272 -55.078055)
			(xy 442.379403 -55.116415) (xy 442.410824 -55.159576) (xy 442.435922 -55.206696) (xy 442.454206 -55.256855)
			(xy 442.46532 -55.309073) (xy 442.469046 -55.36233) (xy 442.465312 -55.415586) (xy 442.45419 -55.467802)
			(xy 442.435898 -55.517958) (xy 442.410793 -55.565074) (xy 442.379365 -55.60823) (xy 442.342228 -55.646585)
			(xy 442.321442 -55.663338) (xy 442.309586 -55.673181) (xy 442.292064 -55.698518) (xy 442.282891 -55.727927)
			(xy 442.2829 -55.758732) (xy 442.29209 -55.788135) (xy 442.309627 -55.813462) (xy 442.321442 -55.823358)
			(xy 442.342272 -55.840055) (xy 442.379403 -55.878415) (xy 442.410824 -55.921576) (xy 442.435922 -55.968696)
			(xy 442.454206 -56.018855) (xy 442.46532 -56.071073) (xy 442.469046 -56.12433) (xy 442.465312 -56.177586)
			(xy 442.45419 -56.229802) (xy 442.435898 -56.279958) (xy 442.410793 -56.327074) (xy 442.379365 -56.37023)
			(xy 442.342228 -56.408585) (xy 442.321442 -56.425338) (xy 442.309586 -56.435181) (xy 442.292064 -56.460518)
			(xy 442.282891 -56.489927) (xy 442.2829 -56.520732) (xy 442.29209 -56.550135) (xy 442.309627 -56.575462)
			(xy 442.321442 -56.585358) (xy 442.342272 -56.602055) (xy 442.379403 -56.640415) (xy 442.410824 -56.683576)
			(xy 442.435922 -56.730696) (xy 442.454206 -56.780855) (xy 442.46532 -56.833073) (xy 442.469046 -56.88633)
			(xy 442.465312 -56.939586) (xy 442.45419 -56.991802) (xy 442.435898 -57.041958) (xy 442.410793 -57.089074)
			(xy 442.379365 -57.13223) (xy 442.342228 -57.170585) (xy 442.321442 -57.187338) (xy 442.309586 -57.197181)
			(xy 442.292064 -57.222518) (xy 442.282891 -57.251927) (xy 442.2829 -57.282732) (xy 442.29209 -57.312135)
			(xy 442.309627 -57.337462) (xy 442.321442 -57.347358) (xy 442.343914 -57.365562) (xy 442.383648 -57.40758)
			(xy 442.416587 -57.455113) (xy 442.441977 -57.507071) (xy 442.459237 -57.562266) (xy 442.46797 -57.619433)
			(xy 442.468508 -57.648348) (xy 442.468067 -57.6756) (xy 442.460304 -57.72955) (xy 442.444943 -57.781845)
			(xy 442.422296 -57.831423) (xy 442.392825 -57.877273) (xy 442.357129 -57.918463) (xy 442.315934 -57.954153)
			(xy 442.270081 -57.983619) (xy 442.2205 -58.006259) (xy 442.168203 -58.021614) (xy 442.114252 -58.02937)
			(xy 442.087 -58.029856) (xy 442.058082 -58.029354) (xy 442.00091 -58.020624) (xy 441.94571 -58.003364)
			(xy 441.893748 -57.977969) (xy 441.846214 -57.945022) (xy 441.804199 -57.905277) (xy 441.78601 -57.88279)
			(xy 441.776113 -57.870985) (xy 441.750789 -57.853466) (xy 441.721396 -57.84429) (xy 441.690604 -57.84429)
			(xy 441.661211 -57.853466) (xy 441.635887 -57.870985) (xy 441.62599 -57.88279) (xy 441.607802 -57.905276)
			(xy 441.565782 -57.945012) (xy 441.518247 -57.977951) (xy 441.466285 -58.003339) (xy 441.411086 -58.020594)
			(xy 441.353916 -58.029322) (xy 441.325 -58.029856) (xy 441.297751 -58.029322) (xy 441.243807 -58.021567)
			(xy 441.191516 -58.006214) (xy 441.141942 -57.983577) (xy 441.096094 -57.954115) (xy 441.054905 -57.918429)
			(xy 441.019214 -57.877244) (xy 440.989746 -57.8314) (xy 440.967102 -57.781829) (xy 440.951743 -57.72954)
			(xy 440.943981 -57.675597) (xy 440.943492 -57.648348) (xy 440.94401 -57.619431) (xy 440.952734 -57.562258)
			(xy 440.96999 -57.507058) (xy 440.995382 -57.455095) (xy 441.028327 -57.407562) (xy 441.068071 -57.365547)
			(xy 441.090558 -57.347358) (xy 441.102318 -57.33741) (xy 441.119841 -57.312102) (xy 441.129025 -57.282721)
			(xy 441.129034 -57.251938) (xy 441.119868 -57.222552) (xy 441.102359 -57.197234) (xy 441.090558 -57.187338)
			(xy 441.069823 -57.170528) (xy 441.032693 -57.132181) (xy 441.001272 -57.089033) (xy 440.976172 -57.041927)
			(xy 440.957883 -56.991781) (xy 440.946764 -56.939575) (xy 440.94303 -56.88633) (xy 440.02706 -56.88633)
			(xy 440.02706 -60.588398) (xy 440.027633 -60.603372) (xy 440.036399 -60.632012) (xy 440.05309 -60.656882)
			(xy 440.076274 -60.675845) (xy 440.103959 -60.687275) (xy 440.133768 -60.690189) (xy 440.163142 -60.684337)
			(xy 440.189559 -60.670222) (xy 440.200542 -60.660026) (xy 443.097412 -57.763156) (xy 443.097412 -55.342028)
			(xy 443.097928 -55.317046) (xy 443.105788 -55.267704) (xy 443.121257 -55.220195) (xy 443.143955 -55.175683)
			(xy 443.173325 -55.135263) (xy 443.19063 -55.117238) (xy 446.55613 -51.751738) (xy 446.574114 -51.734382)
			(xy 446.614525 -51.704977) (xy 446.659044 -51.682265) (xy 446.70657 -51.666805) (xy 446.755931 -51.658981)
			(xy 446.78092 -51.65852) (xy 448.695826 -51.65852) (xy 448.711017 -51.620175) (xy 448.747529 -51.546213)
			(xy 448.790729 -51.475947) (xy 448.840246 -51.40998) (xy 448.895655 -51.348878) (xy 448.956481 -51.293167)
			(xy 449.022201 -51.243323) (xy 449.092252 -51.199775) (xy 449.166032 -51.162897) (xy 449.242908 -51.133004)
			(xy 449.322221 -51.110354) (xy 449.40329 -51.09514) (xy 449.485418 -51.087494) (xy 449.52666 -51.08702)
			(xy 449.569009 -51.087506) (xy 449.653324 -51.095554) (xy 449.736492 -51.11158) (xy 449.817761 -51.135439)
			(xy 449.896393 -51.166915) (xy 449.971677 -51.205724) (xy 450.042931 -51.251513) (xy 450.10951 -51.303869)
			(xy 450.17081 -51.362316) (xy 450.226277 -51.426325) (xy 450.275408 -51.495317) (xy 450.317758 -51.568668)
			(xy 450.352944 -51.645711) (xy 450.380647 -51.725751) (xy 450.400616 -51.808062) (xy 450.41267 -51.891898)
			(xy 450.4167 -51.9765) (xy 450.414681 -52.018876) (xy 456.145896 -52.018876) (xy 456.145896 -51.93418)
			(xy 456.153947 -51.849866) (xy 456.169976 -51.7667) (xy 456.193837 -51.685433) (xy 456.225316 -51.606803)
			(xy 456.264127 -51.531522) (xy 456.309917 -51.46027) (xy 456.362273 -51.393694) (xy 456.420721 -51.332396)
			(xy 456.484731 -51.276931) (xy 456.553723 -51.227802) (xy 456.627073 -51.185453) (xy 456.704116 -51.150269)
			(xy 456.784155 -51.122567) (xy 456.866464 -51.102599) (xy 456.950299 -51.090546) (xy 457.0349 -51.086516)
			(xy 457.119501 -51.090546) (xy 457.203336 -51.102599) (xy 457.285645 -51.122567) (xy 457.365684 -51.150269)
			(xy 457.442727 -51.185453) (xy 457.516077 -51.227802) (xy 457.585069 -51.276931) (xy 457.649079 -51.332396)
			(xy 457.707527 -51.393694) (xy 457.759883 -51.46027) (xy 457.805673 -51.531522) (xy 457.844484 -51.606803)
			(xy 457.875963 -51.685433) (xy 457.899824 -51.7667) (xy 457.915853 -51.849866) (xy 457.923904 -51.93418)
			(xy 457.924408 -51.976528) (xy 457.923904 -52.018876) (xy 457.915853 -52.10319) (xy 457.899824 -52.186356)
			(xy 457.875963 -52.267623) (xy 457.844484 -52.346253) (xy 457.805673 -52.421534) (xy 457.759883 -52.492786)
			(xy 457.707527 -52.559362) (xy 457.649079 -52.62066) (xy 457.585069 -52.676125) (xy 457.516077 -52.725254)
			(xy 457.442727 -52.767603) (xy 457.365684 -52.802787) (xy 457.285645 -52.830489) (xy 457.203336 -52.850457)
			(xy 457.119501 -52.86251) (xy 457.0349 -52.866541) (xy 456.950299 -52.86251) (xy 456.866464 -52.850457)
			(xy 456.784155 -52.830489) (xy 456.704116 -52.802787) (xy 456.627073 -52.767603) (xy 456.553723 -52.725254)
			(xy 456.484731 -52.676125) (xy 456.420721 -52.62066) (xy 456.362273 -52.559362) (xy 456.309917 -52.492786)
			(xy 456.264127 -52.421534) (xy 456.225316 -52.346253) (xy 456.193837 -52.267623) (xy 456.169976 -52.186356)
			(xy 456.153947 -52.10319) (xy 456.145896 -52.018876) (xy 450.414681 -52.018876) (xy 450.41267 -52.061102)
			(xy 450.400616 -52.144938) (xy 450.380647 -52.227249) (xy 450.352944 -52.307289) (xy 450.317758 -52.384332)
			(xy 450.275408 -52.457683) (xy 450.226277 -52.526675) (xy 450.17081 -52.590684) (xy 450.10951 -52.649131)
			(xy 450.042931 -52.701487) (xy 449.971677 -52.747276) (xy 449.896393 -52.786085) (xy 449.817761 -52.817561)
			(xy 449.736492 -52.84142) (xy 449.653324 -52.857446) (xy 449.569009 -52.865494) (xy 449.52666 -52.866036)
			(xy 449.485416 -52.865572) (xy 449.403281 -52.857942) (xy 449.322205 -52.842741) (xy 449.242884 -52.8201)
			(xy 449.166 -52.790213) (xy 449.092213 -52.753337) (xy 449.022156 -52.709789) (xy 448.956432 -52.659943)
			(xy 448.895604 -52.604227) (xy 448.840194 -52.543119) (xy 448.79068 -52.477144) (xy 448.747485 -52.406869)
			(xy 448.710982 -52.332897) (xy 448.695826 -52.294536) (xy 446.912492 -52.294536) (xy 444.83528 -54.371748)
			(xy 447.038982 -54.371748) (xy 447.043053 -54.316126) (xy 447.055179 -54.261689) (xy 447.075102 -54.209598)
			(xy 447.102398 -54.160963) (xy 447.136484 -54.11682) (xy 447.176633 -54.078111) (xy 447.221991 -54.04566)
			(xy 447.271591 -54.020159) (xy 447.324375 -54.002152) (xy 447.379218 -53.992022) (xy 447.434952 -53.989985)
			(xy 447.490389 -53.996085) (xy 447.544346 -54.010191) (xy 447.595675 -54.032003) (xy 447.643281 -54.061057)
			(xy 447.686149 -54.096732) (xy 447.723366 -54.138269) (xy 447.754139 -54.184782) (xy 447.777811 -54.235279)
			(xy 447.793879 -54.288686) (xy 447.801999 -54.343862) (xy 447.802508 -54.371748) (xy 447.927982 -54.371748)
			(xy 447.932053 -54.316126) (xy 447.944179 -54.261689) (xy 447.964102 -54.209598) (xy 447.991398 -54.160963)
			(xy 448.025484 -54.11682) (xy 448.065633 -54.078111) (xy 448.110991 -54.04566) (xy 448.160591 -54.020159)
			(xy 448.213375 -54.002152) (xy 448.268218 -53.992022) (xy 448.323952 -53.989985) (xy 448.379389 -53.996085)
			(xy 448.433346 -54.010191) (xy 448.484675 -54.032003) (xy 448.532281 -54.061057) (xy 448.575149 -54.096732)
			(xy 448.612366 -54.138269) (xy 448.643139 -54.184782) (xy 448.666811 -54.235279) (xy 448.682879 -54.288686)
			(xy 448.690999 -54.343862) (xy 448.691508 -54.371748) (xy 448.816982 -54.371748) (xy 448.821053 -54.316126)
			(xy 448.833179 -54.261689) (xy 448.853102 -54.209598) (xy 448.880398 -54.160963) (xy 448.914484 -54.11682)
			(xy 448.954633 -54.078111) (xy 448.999991 -54.04566) (xy 449.049591 -54.020159) (xy 449.102375 -54.002152)
			(xy 449.157218 -53.992022) (xy 449.212952 -53.989985) (xy 449.268389 -53.996085) (xy 449.322346 -54.010191)
			(xy 449.373675 -54.032003) (xy 449.421281 -54.061057) (xy 449.464149 -54.096732) (xy 449.501366 -54.138269)
			(xy 449.532139 -54.184782) (xy 449.555811 -54.235279) (xy 449.571879 -54.288686) (xy 449.579999 -54.343862)
			(xy 449.580508 -54.371748) (xy 449.705982 -54.371748) (xy 449.710053 -54.316126) (xy 449.722179 -54.261689)
			(xy 449.742102 -54.209598) (xy 449.769398 -54.160963) (xy 449.803484 -54.11682) (xy 449.843633 -54.078111)
			(xy 449.888991 -54.04566) (xy 449.938591 -54.020159) (xy 449.991375 -54.002152) (xy 450.046218 -53.992022)
			(xy 450.101952 -53.989985) (xy 450.157389 -53.996085) (xy 450.211346 -54.010191) (xy 450.262675 -54.032003)
			(xy 450.310281 -54.061057) (xy 450.353149 -54.096732) (xy 450.390366 -54.138269) (xy 450.421139 -54.184782)
			(xy 450.444811 -54.235279) (xy 450.460879 -54.288686) (xy 450.468999 -54.343862) (xy 450.469508 -54.371748)
			(xy 450.468999 -54.399634) (xy 450.460879 -54.45481) (xy 450.444811 -54.508217) (xy 450.421139 -54.558714)
			(xy 450.390366 -54.605227) (xy 450.353149 -54.646764) (xy 450.310281 -54.682439) (xy 450.262675 -54.711493)
			(xy 450.211346 -54.733305) (xy 450.157389 -54.747411) (xy 450.101952 -54.753511) (xy 450.046218 -54.751474)
			(xy 449.991375 -54.741344) (xy 449.938591 -54.723337) (xy 449.888991 -54.697836) (xy 449.843633 -54.665385)
			(xy 449.803484 -54.626676) (xy 449.769398 -54.582533) (xy 449.742102 -54.533898) (xy 449.722179 -54.481807)
			(xy 449.710053 -54.42737) (xy 449.705982 -54.371748) (xy 449.580508 -54.371748) (xy 449.579999 -54.399634)
			(xy 449.571879 -54.45481) (xy 449.555811 -54.508217) (xy 449.532139 -54.558714) (xy 449.501366 -54.605227)
			(xy 449.464149 -54.646764) (xy 449.421281 -54.682439) (xy 449.373675 -54.711493) (xy 449.322346 -54.733305)
			(xy 449.268389 -54.747411) (xy 449.212952 -54.753511) (xy 449.157218 -54.751474) (xy 449.102375 -54.741344)
			(xy 449.049591 -54.723337) (xy 448.999991 -54.697836) (xy 448.954633 -54.665385) (xy 448.914484 -54.626676)
			(xy 448.880398 -54.582533) (xy 448.853102 -54.533898) (xy 448.833179 -54.481807) (xy 448.821053 -54.42737)
			(xy 448.816982 -54.371748) (xy 448.691508 -54.371748) (xy 448.690999 -54.399634) (xy 448.682879 -54.45481)
			(xy 448.666811 -54.508217) (xy 448.643139 -54.558714) (xy 448.612366 -54.605227) (xy 448.575149 -54.646764)
			(xy 448.532281 -54.682439) (xy 448.484675 -54.711493) (xy 448.433346 -54.733305) (xy 448.379389 -54.747411)
			(xy 448.323952 -54.753511) (xy 448.268218 -54.751474) (xy 448.213375 -54.741344) (xy 448.160591 -54.723337)
			(xy 448.110991 -54.697836) (xy 448.065633 -54.665385) (xy 448.025484 -54.626676) (xy 447.991398 -54.582533)
			(xy 447.964102 -54.533898) (xy 447.944179 -54.481807) (xy 447.932053 -54.42737) (xy 447.927982 -54.371748)
			(xy 447.802508 -54.371748) (xy 447.801999 -54.399634) (xy 447.793879 -54.45481) (xy 447.777811 -54.508217)
			(xy 447.754139 -54.558714) (xy 447.723366 -54.605227) (xy 447.686149 -54.646764) (xy 447.643281 -54.682439)
			(xy 447.595675 -54.711493) (xy 447.544346 -54.733305) (xy 447.490389 -54.747411) (xy 447.434952 -54.753511)
			(xy 447.379218 -54.751474) (xy 447.324375 -54.741344) (xy 447.271591 -54.723337) (xy 447.221991 -54.697836)
			(xy 447.176633 -54.665385) (xy 447.136484 -54.626676) (xy 447.102398 -54.582533) (xy 447.075102 -54.533898)
			(xy 447.055179 -54.481807) (xy 447.043053 -54.42737) (xy 447.038982 -54.371748) (xy 444.83528 -54.371748)
			(xy 443.733428 -55.4736) (xy 443.733428 -57.588912) (xy 444.646304 -57.588912) (xy 444.646776 -57.561542)
			(xy 444.654592 -57.507363) (xy 444.67008 -57.45486) (xy 444.69292 -57.405113) (xy 444.722643 -57.359146)
			(xy 444.740284 -57.338214) (xy 444.749511 -57.326879) (xy 444.761691 -57.300324) (xy 444.765867 -57.271409)
			(xy 444.761696 -57.242493) (xy 444.74952 -57.215937) (xy 444.740284 -57.20461) (xy 444.722657 -57.183667)
			(xy 444.692935 -57.1377) (xy 444.670091 -57.087955) (xy 444.654596 -57.035455) (xy 444.646767 -56.981279)
			(xy 444.646766 -56.926539) (xy 444.654592 -56.872363) (xy 444.670085 -56.819862) (xy 444.692926 -56.770116)
			(xy 444.722646 -56.724148) (xy 444.740284 -56.703214) (xy 444.749511 -56.691879) (xy 444.761691 -56.665324)
			(xy 444.765867 -56.636409) (xy 444.761696 -56.607493) (xy 444.74952 -56.580937) (xy 444.740284 -56.56961)
			(xy 444.722657 -56.548667) (xy 444.692935 -56.5027) (xy 444.670091 -56.452955) (xy 444.654596 -56.400455)
			(xy 444.646767 -56.346279) (xy 444.646766 -56.291539) (xy 444.654592 -56.237363) (xy 444.670085 -56.184862)
			(xy 444.692926 -56.135116) (xy 444.722646 -56.089148) (xy 444.740284 -56.068214) (xy 444.749511 -56.056879)
			(xy 444.761691 -56.030324) (xy 444.765867 -56.001409) (xy 444.761696 -55.972493) (xy 444.74952 -55.945937)
			(xy 444.740284 -55.93461) (xy 444.722657 -55.913667) (xy 444.692935 -55.8677) (xy 444.670091 -55.817955)
			(xy 444.654596 -55.765455) (xy 444.646767 -55.711279) (xy 444.646766 -55.656539) (xy 444.654592 -55.602363)
			(xy 444.670085 -55.549862) (xy 444.692926 -55.500116) (xy 444.722646 -55.454148) (xy 444.740284 -55.433214)
			(xy 444.749511 -55.421879) (xy 444.761691 -55.395324) (xy 444.765867 -55.366409) (xy 444.761696 -55.337493)
			(xy 444.74952 -55.310937) (xy 444.740284 -55.29961) (xy 444.722634 -55.278687) (xy 444.692924 -55.232711)
			(xy 444.670091 -55.182962) (xy 444.654602 -55.130459) (xy 444.646777 -55.076282) (xy 444.646304 -55.048912)
			(xy 444.646767 -55.021659) (xy 444.654522 -54.967707) (xy 444.669877 -54.915409) (xy 444.692519 -54.865828)
			(xy 444.721987 -54.819974) (xy 444.757681 -54.778781) (xy 444.798874 -54.743087) (xy 444.844728 -54.713619)
			(xy 444.894309 -54.690977) (xy 444.946607 -54.675622) (xy 445.000559 -54.667867) (xy 445.027812 -54.667404)
			(xy 445.054483 -54.66783) (xy 445.107306 -54.67525) (xy 445.158579 -54.689958) (xy 445.207304 -54.711667)
			(xy 445.252528 -54.739952) (xy 445.29337 -54.774263) (xy 445.329032 -54.81393) (xy 445.344296 -54.835806)
			(xy 445.35343 -54.848302) (xy 445.377599 -54.867612) (xy 445.406436 -54.87881) (xy 445.437302 -54.88087)
			(xy 445.467372 -54.873605) (xy 445.493892 -54.857678) (xy 445.50457 -54.846474) (xy 445.522735 -54.826673)
			(xy 445.563685 -54.791879) (xy 445.609115 -54.76318) (xy 445.658124 -54.741143) (xy 445.709741 -54.726205)
			(xy 445.762944 -54.718663) (xy 445.789812 -54.718204) (xy 445.817064 -54.718667) (xy 445.871013 -54.726425)
			(xy 445.923309 -54.741782) (xy 445.972887 -54.764426) (xy 446.018738 -54.793894) (xy 446.059929 -54.829588)
			(xy 446.09562 -54.870781) (xy 446.125086 -54.916634) (xy 446.147726 -54.966213) (xy 446.16308 -55.01851)
			(xy 446.170835 -55.07246) (xy 446.17132 -55.099712) (xy 446.17088 -55.127083) (xy 446.163059 -55.181264)
			(xy 446.147565 -55.233769) (xy 446.124717 -55.283515) (xy 446.094985 -55.32948) (xy 446.07734 -55.35041)
			(xy 446.068088 -55.361727) (xy 446.055908 -55.388288) (xy 446.051735 -55.417209) (xy 446.055913 -55.44613)
			(xy 446.068098 -55.472688) (xy 446.07734 -55.484014) (xy 446.094994 -55.504937) (xy 446.124721 -55.550905)
			(xy 446.147567 -55.600653) (xy 446.163064 -55.653157) (xy 446.170892 -55.707337) (xy 446.170891 -55.762081)
			(xy 446.16306 -55.816261) (xy 446.147561 -55.868764) (xy 446.124712 -55.918511) (xy 446.094983 -55.964478)
			(xy 446.07734 -55.98541) (xy 446.068088 -55.996727) (xy 446.055908 -56.023288) (xy 446.051735 -56.052209)
			(xy 446.055913 -56.08113) (xy 446.068098 -56.107688) (xy 446.07734 -56.119014) (xy 446.094994 -56.139937)
			(xy 446.124721 -56.185905) (xy 446.147567 -56.235653) (xy 446.163064 -56.288157) (xy 446.170892 -56.342337)
			(xy 446.170891 -56.369712) (xy 451.428104 -56.369712) (xy 451.428576 -56.342342) (xy 451.436392 -56.288163)
			(xy 451.45188 -56.23566) (xy 451.47472 -56.185913) (xy 451.504443 -56.139946) (xy 451.522084 -56.119014)
			(xy 451.531311 -56.107679) (xy 451.543491 -56.081124) (xy 451.547667 -56.052209) (xy 451.543496 -56.023293)
			(xy 451.53132 -55.996737) (xy 451.522084 -55.98541) (xy 451.504457 -55.964467) (xy 451.474735 -55.9185)
			(xy 451.451891 -55.868755) (xy 451.436396 -55.816255) (xy 451.428567 -55.762079) (xy 451.428566 -55.707339)
			(xy 451.436392 -55.653163) (xy 451.451885 -55.600662) (xy 451.474726 -55.550916) (xy 451.504446 -55.504948)
			(xy 451.522084 -55.484014) (xy 451.531311 -55.472679) (xy 451.543491 -55.446124) (xy 451.547667 -55.417209)
			(xy 451.543496 -55.388293) (xy 451.53132 -55.361737) (xy 451.522084 -55.35041) (xy 451.504434 -55.329487)
			(xy 451.474724 -55.283511) (xy 451.451891 -55.233762) (xy 451.436402 -55.181259) (xy 451.428577 -55.127082)
			(xy 451.428104 -55.099712) (xy 451.42859 -55.072461) (xy 451.436346 -55.018513) (xy 451.451701 -54.966218)
			(xy 451.474343 -54.916641) (xy 451.503809 -54.870791) (xy 451.5395 -54.8296) (xy 451.580691 -54.793909)
			(xy 451.626541 -54.764443) (xy 451.676118 -54.741801) (xy 451.728413 -54.726446) (xy 451.782361 -54.71869)
			(xy 451.836863 -54.71869) (xy 451.890811 -54.726446) (xy 451.943106 -54.741801) (xy 451.992683 -54.764443)
			(xy 452.038533 -54.793909) (xy 452.079724 -54.8296) (xy 452.115415 -54.870791) (xy 452.144881 -54.916641)
			(xy 452.167523 -54.966218) (xy 452.182878 -55.018513) (xy 452.190634 -55.072461) (xy 452.19112 -55.099712)
			(xy 452.19068 -55.127083) (xy 452.182859 -55.181264) (xy 452.167365 -55.233769) (xy 452.144517 -55.283515)
			(xy 452.114785 -55.32948) (xy 452.09714 -55.35041) (xy 452.087888 -55.361727) (xy 452.075708 -55.388288)
			(xy 452.071535 -55.417209) (xy 452.075713 -55.44613) (xy 452.087898 -55.472688) (xy 452.09714 -55.484014)
			(xy 452.114794 -55.504937) (xy 452.144521 -55.550905) (xy 452.167367 -55.600653) (xy 452.182864 -55.653157)
			(xy 452.190692 -55.707337) (xy 452.190691 -55.762081) (xy 452.18286 -55.816261) (xy 452.167361 -55.868764)
			(xy 452.144512 -55.918511) (xy 452.114783 -55.964478) (xy 452.09714 -55.98541) (xy 452.087888 -55.996727)
			(xy 452.075708 -56.023288) (xy 452.071535 -56.052209) (xy 452.075713 -56.08113) (xy 452.087898 -56.107688)
			(xy 452.09714 -56.119014) (xy 452.114759 -56.139962) (xy 452.144472 -56.185931) (xy 452.167312 -56.235675)
			(xy 452.182808 -56.288172) (xy 452.190643 -56.342344) (xy 452.19112 -56.369712) (xy 452.190634 -56.396963)
			(xy 452.182878 -56.450911) (xy 452.167523 -56.503206) (xy 452.144881 -56.552783) (xy 452.115415 -56.598633)
			(xy 452.079724 -56.639824) (xy 452.038533 -56.675515) (xy 451.992683 -56.704981) (xy 451.943106 -56.727623)
			(xy 451.890811 -56.742978) (xy 451.836863 -56.750734) (xy 451.782361 -56.750734) (xy 451.728413 -56.742978)
			(xy 451.676118 -56.727623) (xy 451.626541 -56.704981) (xy 451.580691 -56.675515) (xy 451.5395 -56.639824)
			(xy 451.503809 -56.598633) (xy 451.474343 -56.552783) (xy 451.451701 -56.503206) (xy 451.436346 -56.450911)
			(xy 451.42859 -56.396963) (xy 451.428104 -56.369712) (xy 446.170891 -56.369712) (xy 446.170891 -56.397081)
			(xy 446.16306 -56.451261) (xy 446.147561 -56.503764) (xy 446.124712 -56.553511) (xy 446.094983 -56.599478)
			(xy 446.07734 -56.62041) (xy 446.068088 -56.631727) (xy 446.055908 -56.658288) (xy 446.051735 -56.687209)
			(xy 446.055913 -56.71613) (xy 446.068098 -56.742688) (xy 446.07734 -56.754014) (xy 446.094959 -56.774962)
			(xy 446.124672 -56.820931) (xy 446.147512 -56.870675) (xy 446.163008 -56.923172) (xy 446.170843 -56.977344)
			(xy 446.17132 -57.004712) (xy 446.170833 -57.031963) (xy 446.163076 -57.08591) (xy 446.14772 -57.138204)
			(xy 446.125078 -57.187781) (xy 446.095611 -57.23363) (xy 446.05992 -57.27482) (xy 446.01873 -57.310511)
			(xy 445.972881 -57.339978) (xy 445.923304 -57.36262) (xy 445.87101 -57.377976) (xy 445.817063 -57.385733)
			(xy 445.789812 -57.38622) (xy 445.762381 -57.385755) (xy 445.708084 -57.377911) (xy 445.65547 -57.362369)
			(xy 445.605626 -57.339449) (xy 445.55958 -57.309624) (xy 445.518282 -57.27351) (xy 445.482584 -57.231852)
			(xy 445.453222 -57.185509) (xy 445.441578 -57.160668) (xy 445.436517 -57.15084) (xy 445.419862 -57.13635)
			(xy 445.398659 -57.130199) (xy 445.376835 -57.133527) (xy 445.358428 -57.145717) (xy 445.35217 -57.154826)
			(xy 445.343856 -57.167909) (xy 445.325419 -57.192833) (xy 445.31534 -57.20461) (xy 445.306088 -57.215927)
			(xy 445.293908 -57.242488) (xy 445.289735 -57.271409) (xy 445.293913 -57.30033) (xy 445.306098 -57.326888)
			(xy 445.31534 -57.338214) (xy 445.332959 -57.359162) (xy 445.362672 -57.405131) (xy 445.385512 -57.454875)
			(xy 445.401008 -57.507372) (xy 445.408843 -57.561544) (xy 445.40932 -57.588912) (xy 445.408834 -57.616163)
			(xy 445.405448 -57.639712) (xy 452.723504 -57.639712) (xy 452.723976 -57.612342) (xy 452.731792 -57.558163)
			(xy 452.74728 -57.50566) (xy 452.77012 -57.455913) (xy 452.799843 -57.409946) (xy 452.817484 -57.389014)
			(xy 452.826711 -57.377679) (xy 452.838891 -57.351124) (xy 452.843067 -57.322209) (xy 452.838896 -57.293293)
			(xy 452.82672 -57.266737) (xy 452.817484 -57.25541) (xy 452.799857 -57.234467) (xy 452.770135 -57.1885)
			(xy 452.747291 -57.138755) (xy 452.731796 -57.086255) (xy 452.723967 -57.032079) (xy 452.723966 -56.977339)
			(xy 452.731792 -56.923163) (xy 452.747285 -56.870662) (xy 452.770126 -56.820916) (xy 452.799846 -56.774948)
			(xy 452.817484 -56.754014) (xy 452.826711 -56.742679) (xy 452.838891 -56.716124) (xy 452.843067 -56.687209)
			(xy 452.838896 -56.658293) (xy 452.82672 -56.631737) (xy 452.817484 -56.62041) (xy 452.799857 -56.599467)
			(xy 452.770135 -56.5535) (xy 452.747291 -56.503755) (xy 452.731796 -56.451255) (xy 452.723967 -56.397079)
			(xy 452.723966 -56.342339) (xy 452.731792 -56.288163) (xy 452.747285 -56.235662) (xy 452.770126 -56.185916)
			(xy 452.799846 -56.139948) (xy 452.817484 -56.119014) (xy 452.826711 -56.107679) (xy 452.838891 -56.081124)
			(xy 452.843067 -56.052209) (xy 452.838896 -56.023293) (xy 452.82672 -55.996737) (xy 452.817484 -55.98541)
			(xy 452.799857 -55.964467) (xy 452.770135 -55.9185) (xy 452.747291 -55.868755) (xy 452.731796 -55.816255)
			(xy 452.723967 -55.762079) (xy 452.723966 -55.707339) (xy 452.731792 -55.653163) (xy 452.747285 -55.600662)
			(xy 452.770126 -55.550916) (xy 452.799846 -55.504948) (xy 452.817484 -55.484014) (xy 452.826711 -55.472679)
			(xy 452.838891 -55.446124) (xy 452.843067 -55.417209) (xy 452.838896 -55.388293) (xy 452.82672 -55.361737)
			(xy 452.817484 -55.35041) (xy 452.799834 -55.329487) (xy 452.770124 -55.283511) (xy 452.747291 -55.233762)
			(xy 452.731802 -55.181259) (xy 452.723977 -55.127082) (xy 452.723504 -55.099712) (xy 452.72399 -55.072461)
			(xy 452.731746 -55.018513) (xy 452.747101 -54.966218) (xy 452.769743 -54.916641) (xy 452.799209 -54.870791)
			(xy 452.8349 -54.8296) (xy 452.876091 -54.793909) (xy 452.921941 -54.764443) (xy 452.971518 -54.741801)
			(xy 453.023813 -54.726446) (xy 453.077761 -54.71869) (xy 453.132263 -54.71869) (xy 453.186211 -54.726446)
			(xy 453.238506 -54.741801) (xy 453.288083 -54.764443) (xy 453.333933 -54.793909) (xy 453.375124 -54.8296)
			(xy 453.410815 -54.870791) (xy 453.440281 -54.916641) (xy 453.462923 -54.966218) (xy 453.478278 -55.018513)
			(xy 453.486034 -55.072461) (xy 453.48652 -55.099712) (xy 453.48608 -55.127083) (xy 453.478259 -55.181264)
			(xy 453.462765 -55.233769) (xy 453.439917 -55.283515) (xy 453.410185 -55.32948) (xy 453.39254 -55.35041)
			(xy 453.383288 -55.361727) (xy 453.371108 -55.388288) (xy 453.366935 -55.417209) (xy 453.371113 -55.44613)
			(xy 453.383298 -55.472688) (xy 453.39254 -55.484014) (xy 453.410194 -55.504937) (xy 453.439921 -55.550905)
			(xy 453.462767 -55.600653) (xy 453.478264 -55.653157) (xy 453.486092 -55.707337) (xy 453.486091 -55.762081)
			(xy 453.47826 -55.816261) (xy 453.462761 -55.868764) (xy 453.439912 -55.918511) (xy 453.410183 -55.964478)
			(xy 453.39254 -55.98541) (xy 453.383288 -55.996727) (xy 453.371108 -56.023288) (xy 453.366935 -56.052209)
			(xy 453.371113 -56.08113) (xy 453.383298 -56.107688) (xy 453.39254 -56.119014) (xy 453.410194 -56.139937)
			(xy 453.439921 -56.185905) (xy 453.462767 -56.235653) (xy 453.478264 -56.288157) (xy 453.486092 -56.342337)
			(xy 453.486091 -56.397081) (xy 453.47826 -56.451261) (xy 453.462761 -56.503764) (xy 453.439912 -56.553511)
			(xy 453.410183 -56.599478) (xy 453.39254 -56.62041) (xy 453.383288 -56.631727) (xy 453.371108 -56.658288)
			(xy 453.366935 -56.687209) (xy 453.371113 -56.71613) (xy 453.383298 -56.742688) (xy 453.39254 -56.754014)
			(xy 453.410194 -56.774937) (xy 453.439921 -56.820905) (xy 453.462767 -56.870653) (xy 453.478264 -56.923157)
			(xy 453.486092 -56.977337) (xy 453.486091 -57.032081) (xy 453.47826 -57.086261) (xy 453.462761 -57.138764)
			(xy 453.439912 -57.188511) (xy 453.410183 -57.234478) (xy 453.39254 -57.25541) (xy 453.383288 -57.266727)
			(xy 453.371108 -57.293288) (xy 453.366935 -57.322209) (xy 453.371113 -57.35113) (xy 453.383298 -57.377688)
			(xy 453.39254 -57.389014) (xy 453.410159 -57.409962) (xy 453.439872 -57.455931) (xy 453.462712 -57.505675)
			(xy 453.478208 -57.558172) (xy 453.486043 -57.612344) (xy 453.48652 -57.639712) (xy 453.486034 -57.666963)
			(xy 453.478278 -57.720911) (xy 453.462923 -57.773206) (xy 453.440281 -57.822783) (xy 453.410815 -57.868633)
			(xy 453.375124 -57.909824) (xy 453.333933 -57.945515) (xy 453.288083 -57.974981) (xy 453.238506 -57.997623)
			(xy 453.186211 -58.012978) (xy 453.132263 -58.020734) (xy 453.077761 -58.020734) (xy 453.023813 -58.012978)
			(xy 452.971518 -57.997623) (xy 452.921941 -57.974981) (xy 452.876091 -57.945515) (xy 452.8349 -57.909824)
			(xy 452.799209 -57.868633) (xy 452.769743 -57.822783) (xy 452.747101 -57.773206) (xy 452.731746 -57.720911)
			(xy 452.72399 -57.666963) (xy 452.723504 -57.639712) (xy 445.405448 -57.639712) (xy 445.401078 -57.670111)
			(xy 445.385723 -57.722406) (xy 445.363081 -57.771983) (xy 445.333615 -57.817833) (xy 445.297924 -57.859024)
			(xy 445.256733 -57.894715) (xy 445.210883 -57.924181) (xy 445.161306 -57.946823) (xy 445.109011 -57.962178)
			(xy 445.055063 -57.969934) (xy 445.000561 -57.969934) (xy 444.946613 -57.962178) (xy 444.894318 -57.946823)
			(xy 444.844741 -57.924181) (xy 444.798891 -57.894715) (xy 444.7577 -57.859024) (xy 444.722009 -57.817833)
			(xy 444.692543 -57.771983) (xy 444.669901 -57.722406) (xy 444.654546 -57.670111) (xy 444.64679 -57.616163)
			(xy 444.646304 -57.588912) (xy 443.733428 -57.588912) (xy 443.733428 -57.894728) (xy 443.732915 -57.919711)
			(xy 443.725062 -57.969058) (xy 443.7096 -58.016573) (xy 443.686908 -58.061091) (xy 443.657543 -58.101519)
			(xy 443.64021 -58.119518) (xy 442.340746 -59.418982) (xy 462.938622 -59.418982) (xy 462.939072 -59.391611)
			(xy 462.946893 -59.337431) (xy 462.962386 -59.284928) (xy 462.985231 -59.235181) (xy 463.014959 -59.189215)
			(xy 463.032602 -59.168284) (xy 463.041856 -59.15697) (xy 463.054031 -59.130407) (xy 463.0582 -59.101486)
			(xy 463.054023 -59.072567) (xy 463.041841 -59.046007) (xy 463.032602 -59.03468) (xy 463.014945 -59.013761)
			(xy 462.985223 -58.96779) (xy 462.96238 -58.918042) (xy 462.946886 -58.865538) (xy 462.93906 -58.811358)
			(xy 462.939062 -58.756615) (xy 462.946892 -58.702436) (xy 462.962389 -58.649933) (xy 462.985236 -58.600186)
			(xy 463.014961 -58.554217) (xy 463.032602 -58.533284) (xy 463.041856 -58.52197) (xy 463.054031 -58.495407)
			(xy 463.0582 -58.466486) (xy 463.054023 -58.437567) (xy 463.041841 -58.411007) (xy 463.032602 -58.39968)
			(xy 463.014987 -58.378728) (xy 462.985272 -58.332761) (xy 462.962431 -58.283018) (xy 462.946934 -58.230522)
			(xy 462.9391 -58.17635) (xy 462.938622 -58.148982) (xy 462.939156 -58.120244) (xy 462.947779 -58.063418)
			(xy 462.964828 -58.008528) (xy 462.989917 -57.956816) (xy 463.022478 -57.909452) (xy 463.041746 -57.888124)
			(xy 463.051837 -57.876605) (xy 463.065181 -57.849054) (xy 463.069763 -57.818787) (xy 463.065173 -57.788521)
			(xy 463.051822 -57.760973) (xy 463.041746 -57.74944) (xy 463.022456 -57.728129) (xy 462.98989 -57.680765)
			(xy 462.964798 -57.62905) (xy 462.947748 -57.574157) (xy 462.939127 -57.517327) (xy 462.939129 -57.459847)
			(xy 462.947754 -57.403017) (xy 462.964807 -57.348125) (xy 462.989903 -57.296413) (xy 463.022473 -57.24905)
			(xy 463.041746 -57.227724) (xy 463.051837 -57.216205) (xy 463.065181 -57.188654) (xy 463.069763 -57.158387)
			(xy 463.065173 -57.128121) (xy 463.051822 -57.100573) (xy 463.041746 -57.08904) (xy 463.022468 -57.067719)
			(xy 462.989902 -57.020356) (xy 462.964811 -56.968642) (xy 462.947762 -56.91375) (xy 462.939142 -56.856921)
			(xy 462.938622 -56.828182) (xy 462.939038 -56.800927) (xy 462.946798 -56.746973) (xy 462.962158 -56.694672)
			(xy 462.984805 -56.64509) (xy 463.014278 -56.599236) (xy 463.049976 -56.558042) (xy 463.091174 -56.522349)
			(xy 463.137032 -56.492882) (xy 463.186618 -56.470241) (xy 463.23892 -56.454888) (xy 463.292875 -56.447135)
			(xy 463.32013 -56.446674) (xy 463.349046 -56.447215) (xy 463.406218 -56.455935) (xy 463.461417 -56.473187)
			(xy 463.51338 -56.498574) (xy 463.560914 -56.531515) (xy 463.60293 -56.571255) (xy 463.62112 -56.59374)
			(xy 463.631017 -56.605545) (xy 463.656341 -56.623064) (xy 463.685734 -56.63224) (xy 463.716526 -56.63224)
			(xy 463.745919 -56.623064) (xy 463.771243 -56.605545) (xy 463.78114 -56.59374) (xy 463.799319 -56.571246)
			(xy 463.84134 -56.531509) (xy 463.888877 -56.49857) (xy 463.940841 -56.473184) (xy 463.996041 -56.45593)
			(xy 464.053213 -56.447206) (xy 464.08213 -56.446674) (xy 464.110869 -56.447186) (xy 464.167697 -56.455813)
			(xy 464.222587 -56.472866) (xy 464.274299 -56.49796) (xy 464.321661 -56.530527) (xy 464.342988 -56.549798)
			(xy 464.354522 -56.55987) (xy 464.382068 -56.573212) (xy 464.41233 -56.577797) (xy 464.442592 -56.573212)
			(xy 464.470138 -56.55987) (xy 464.481672 -56.549798) (xy 464.502999 -56.530528) (xy 464.550362 -56.497963)
			(xy 464.602073 -56.472872) (xy 464.656964 -56.455822) (xy 464.713791 -56.4472) (xy 464.771269 -56.4472)
			(xy 464.828096 -56.455822) (xy 464.882987 -56.472872) (xy 464.934698 -56.497963) (xy 464.982061 -56.530528)
			(xy 465.003388 -56.549798) (xy 465.014922 -56.55987) (xy 465.042468 -56.573212) (xy 465.07273 -56.577797)
			(xy 465.102992 -56.573212) (xy 465.130538 -56.55987) (xy 465.142072 -56.549798) (xy 465.163399 -56.530528)
			(xy 465.210762 -56.497963) (xy 465.262473 -56.472872) (xy 465.317364 -56.455822) (xy 465.374191 -56.4472)
			(xy 465.431669 -56.4472) (xy 465.488496 -56.455822) (xy 465.543387 -56.472872) (xy 465.595098 -56.497963)
			(xy 465.642461 -56.530528) (xy 465.663788 -56.549798) (xy 465.675322 -56.55987) (xy 465.702868 -56.573212)
			(xy 465.73313 -56.577797) (xy 465.763392 -56.573212) (xy 465.790938 -56.55987) (xy 465.802472 -56.549798)
			(xy 465.823796 -56.530523) (xy 465.871158 -56.497955) (xy 465.92287 -56.472863) (xy 465.977762 -56.455813)
			(xy 466.034591 -56.447193) (xy 466.06333 -56.446674) (xy 466.092246 -56.447215) (xy 466.149418 -56.455935)
			(xy 466.204617 -56.473187) (xy 466.25658 -56.498574) (xy 466.304114 -56.531515) (xy 466.34613 -56.571255)
			(xy 466.36432 -56.59374) (xy 466.374217 -56.605545) (xy 466.399541 -56.623064) (xy 466.428934 -56.63224)
			(xy 466.459726 -56.63224) (xy 466.489119 -56.623064) (xy 466.514443 -56.605545) (xy 466.52434 -56.59374)
			(xy 466.542519 -56.571246) (xy 466.58454 -56.531509) (xy 466.632077 -56.49857) (xy 466.684041 -56.473184)
			(xy 466.739241 -56.45593) (xy 466.796413 -56.447206) (xy 466.82533 -56.446674) (xy 466.852581 -56.44715)
			(xy 466.906528 -56.45491) (xy 466.958822 -56.470268) (xy 467.008398 -56.492911) (xy 467.054248 -56.522379)
			(xy 467.095437 -56.558071) (xy 467.131128 -56.599262) (xy 467.160594 -56.645112) (xy 467.183236 -56.694689)
			(xy 467.198593 -56.746983) (xy 467.206351 -56.800931) (xy 467.206838 -56.828182) (xy 467.206293 -56.85692)
			(xy 467.197674 -56.913746) (xy 467.180628 -56.968636) (xy 467.155542 -57.020348) (xy 467.122982 -57.067712)
			(xy 467.103714 -57.08904) (xy 467.093661 -57.100589) (xy 467.080319 -57.12813) (xy 467.075732 -57.158387)
			(xy 467.080311 -57.188645) (xy 467.093646 -57.21619) (xy 467.103714 -57.227724) (xy 467.122965 -57.249067)
			(xy 467.155528 -57.296428) (xy 467.180618 -57.348137) (xy 467.197667 -57.403025) (xy 467.206291 -57.459849)
			(xy 467.206293 -57.517324) (xy 467.197673 -57.574149) (xy 467.180628 -57.629038) (xy 467.155541 -57.680749)
			(xy 467.122982 -57.728112) (xy 467.103714 -57.74944) (xy 467.093661 -57.760989) (xy 467.080319 -57.78853)
			(xy 467.075732 -57.818787) (xy 467.080311 -57.849045) (xy 467.093646 -57.87659) (xy 467.103714 -57.888124)
			(xy 467.122968 -57.909465) (xy 467.155539 -57.956823) (xy 467.180635 -58.008531) (xy 467.197689 -58.063418)
			(xy 467.206316 -58.120244) (xy 467.206838 -58.148982) (xy 467.206376 -58.176353) (xy 467.19856 -58.230532)
			(xy 467.183071 -58.283036) (xy 467.160227 -58.332783) (xy 467.130501 -58.378749) (xy 467.112858 -58.39968)
			(xy 467.103642 -58.411022) (xy 467.091467 -58.437575) (xy 467.087293 -58.466486) (xy 467.09146 -58.495399)
			(xy 467.103627 -58.521955) (xy 467.112858 -58.533284) (xy 467.130482 -58.554231) (xy 467.160208 -58.600196)
			(xy 467.183056 -58.64994) (xy 467.198554 -58.70244) (xy 467.206385 -58.756617) (xy 467.206387 -58.811356)
			(xy 467.19856 -58.865534) (xy 467.183065 -58.918035) (xy 467.160221 -58.96778) (xy 467.130498 -59.013748)
			(xy 467.112858 -59.03468) (xy 467.103642 -59.046022) (xy 467.091467 -59.072575) (xy 467.087293 -59.101486)
			(xy 467.09146 -59.130399) (xy 467.103627 -59.156955) (xy 467.112858 -59.168284) (xy 467.130497 -59.189217)
			(xy 467.16021 -59.235189) (xy 467.183047 -59.284936) (xy 467.198538 -59.337437) (xy 467.206365 -59.391613)
			(xy 467.206838 -59.418982) (xy 467.206305 -59.446231) (xy 467.198552 -59.500176) (xy 467.1832 -59.552468)
			(xy 467.160564 -59.602043) (xy 467.131102 -59.647892) (xy 467.095416 -59.689082) (xy 467.05423 -59.724773)
			(xy 467.008385 -59.754241) (xy 466.958813 -59.776884) (xy 466.906523 -59.792242) (xy 466.852579 -59.800002)
			(xy 466.82533 -59.80049) (xy 466.796414 -59.799954) (xy 466.739243 -59.791229) (xy 466.684045 -59.773975)
			(xy 466.632083 -59.748587) (xy 466.584548 -59.715646) (xy 466.542531 -59.675908) (xy 466.52434 -59.653424)
			(xy 466.514443 -59.641619) (xy 466.489119 -59.6241) (xy 466.459726 -59.614924) (xy 466.428934 -59.614924)
			(xy 466.399541 -59.6241) (xy 466.374217 -59.641619) (xy 466.36432 -59.653424) (xy 466.346124 -59.675903)
			(xy 466.304104 -59.715637) (xy 466.25657 -59.748576) (xy 466.20461 -59.773965) (xy 466.149414 -59.791223)
			(xy 466.092246 -59.799954) (xy 466.06333 -59.80049) (xy 466.034592 -59.799951) (xy 465.977765 -59.791332)
			(xy 465.922874 -59.774286) (xy 465.871162 -59.749198) (xy 465.823799 -59.716636) (xy 465.802472 -59.697366)
			(xy 465.790938 -59.687294) (xy 465.763392 -59.673952) (xy 465.73313 -59.669367) (xy 465.702868 -59.673952)
			(xy 465.675322 -59.687294) (xy 465.663788 -59.697366) (xy 465.642461 -59.716636) (xy 465.595098 -59.749201)
			(xy 465.543387 -59.774292) (xy 465.488496 -59.791342) (xy 465.431669 -59.799964) (xy 465.374191 -59.799964)
			(xy 465.317364 -59.791342) (xy 465.262473 -59.774292) (xy 465.210762 -59.749201) (xy 465.163399 -59.716636)
			(xy 465.142072 -59.697366) (xy 465.130538 -59.687294) (xy 465.102992 -59.673952) (xy 465.07273 -59.669367)
			(xy 465.042468 -59.673952) (xy 465.014922 -59.687294) (xy 465.003388 -59.697366) (xy 464.982061 -59.716636)
			(xy 464.934698 -59.749201) (xy 464.882987 -59.774292) (xy 464.828096 -59.791342) (xy 464.771269 -59.799964)
			(xy 464.713791 -59.799964) (xy 464.656964 -59.791342) (xy 464.602073 -59.774292) (xy 464.550362 -59.749201)
			(xy 464.502999 -59.716636) (xy 464.481672 -59.697366) (xy 464.470138 -59.687294) (xy 464.442592 -59.673952)
			(xy 464.41233 -59.669367) (xy 464.382068 -59.673952) (xy 464.354522 -59.687294) (xy 464.342988 -59.697366)
			(xy 464.321649 -59.716623) (xy 464.27429 -59.749191) (xy 464.222582 -59.774286) (xy 464.167694 -59.79134)
			(xy 464.110868 -59.799967) (xy 464.08213 -59.80049) (xy 464.053214 -59.799954) (xy 463.996043 -59.791229)
			(xy 463.940845 -59.773975) (xy 463.888883 -59.748587) (xy 463.841348 -59.715646) (xy 463.799331 -59.675908)
			(xy 463.78114 -59.653424) (xy 463.771243 -59.641619) (xy 463.745919 -59.6241) (xy 463.716526 -59.614924)
			(xy 463.685734 -59.614924) (xy 463.656341 -59.6241) (xy 463.631017 -59.641619) (xy 463.62112 -59.653424)
			(xy 463.602924 -59.675903) (xy 463.560904 -59.715637) (xy 463.51337 -59.748576) (xy 463.46141 -59.773965)
			(xy 463.406214 -59.791223) (xy 463.349046 -59.799954) (xy 463.32013 -59.80049) (xy 463.292877 -59.800017)
			(xy 463.238926 -59.792263) (xy 463.186627 -59.77691) (xy 463.137046 -59.75427) (xy 463.091191 -59.724803)
			(xy 463.049998 -59.689111) (xy 463.014304 -59.647918) (xy 462.984836 -59.602065) (xy 462.962194 -59.552484)
			(xy 462.946839 -59.500186) (xy 462.939084 -59.446235) (xy 462.938622 -59.418982) (xy 442.340746 -59.418982)
			(xy 440.246008 -61.51372) (xy 440.246008 -68.56215) (xy 463.017866 -68.56215) (xy 463.017866 -68.477454)
			(xy 463.025917 -68.39314) (xy 463.041946 -68.309974) (xy 463.065807 -68.228707) (xy 463.097286 -68.150077)
			(xy 463.136097 -68.074796) (xy 463.181887 -68.003544) (xy 463.234243 -67.936968) (xy 463.292691 -67.87567)
			(xy 463.356701 -67.820205) (xy 463.425693 -67.771076) (xy 463.499043 -67.728727) (xy 463.576086 -67.693543)
			(xy 463.656125 -67.665841) (xy 463.738434 -67.645873) (xy 463.822269 -67.63382) (xy 463.90687 -67.62979)
			(xy 463.991471 -67.63382) (xy 464.075306 -67.645873) (xy 464.157615 -67.665841) (xy 464.237654 -67.693543)
			(xy 464.314697 -67.728727) (xy 464.388047 -67.771076) (xy 464.457039 -67.820205) (xy 464.521049 -67.87567)
			(xy 464.579497 -67.936968) (xy 464.631853 -68.003544) (xy 464.677643 -68.074796) (xy 464.716454 -68.150077)
			(xy 464.747933 -68.228707) (xy 464.771794 -68.309974) (xy 464.787823 -68.39314) (xy 464.795874 -68.477454)
			(xy 464.796378 -68.519802) (xy 465.542379 -68.519802) (xy 465.546415 -68.436355) (xy 465.558487 -68.353687)
			(xy 465.57848 -68.27257) (xy 465.606209 -68.193761) (xy 465.641415 -68.117996) (xy 465.683769 -68.045983)
			(xy 465.732875 -67.978394) (xy 465.788276 -67.91586) (xy 465.849453 -67.858965) (xy 465.915836 -67.808239)
			(xy 465.986804 -67.764158) (xy 466.061696 -67.727132) (xy 466.139812 -67.697506) (xy 466.220422 -67.675558)
			(xy 466.302774 -67.661493) (xy 466.3861 -67.655441) (xy 466.46962 -67.65746) (xy 466.552556 -67.66753)
			(xy 466.634132 -67.685558) (xy 466.713588 -67.711375) (xy 466.790181 -67.74474) (xy 466.863197 -67.785341)
			(xy 466.931953 -67.8328) (xy 466.995807 -67.886673) (xy 467.054164 -67.946458) (xy 467.106479 -68.011595)
			(xy 467.152262 -68.081478) (xy 467.191087 -68.155453) (xy 467.222592 -68.23283) (xy 467.246481 -68.312887)
			(xy 467.262532 -68.394875) (xy 467.270595 -68.47803) (xy 467.2711 -68.519802) (xy 467.270595 -68.561574)
			(xy 467.262532 -68.644729) (xy 467.246481 -68.726717) (xy 467.222592 -68.806774) (xy 467.191087 -68.884151)
			(xy 467.152262 -68.958126) (xy 467.106479 -69.028009) (xy 467.054164 -69.093146) (xy 466.995807 -69.152931)
			(xy 466.931953 -69.206804) (xy 466.863197 -69.254263) (xy 466.790181 -69.294864) (xy 466.713588 -69.328229)
			(xy 466.634132 -69.354046) (xy 466.552556 -69.372074) (xy 466.46962 -69.382144) (xy 466.3861 -69.384163)
			(xy 466.302774 -69.378111) (xy 466.220422 -69.364046) (xy 466.139812 -69.342098) (xy 466.061696 -69.312472)
			(xy 465.986804 -69.275446) (xy 465.915836 -69.231365) (xy 465.849453 -69.180639) (xy 465.788276 -69.123744)
			(xy 465.732875 -69.06121) (xy 465.683769 -68.993621) (xy 465.641415 -68.921608) (xy 465.606209 -68.845843)
			(xy 465.57848 -68.767034) (xy 465.558487 -68.685917) (xy 465.546415 -68.603249) (xy 465.542379 -68.519802)
			(xy 464.796378 -68.519802) (xy 464.795874 -68.56215) (xy 464.787823 -68.646464) (xy 464.771794 -68.72963)
			(xy 464.747933 -68.810897) (xy 464.716454 -68.889527) (xy 464.677643 -68.964808) (xy 464.631853 -69.03606)
			(xy 464.579497 -69.102636) (xy 464.521049 -69.163934) (xy 464.457039 -69.219399) (xy 464.388047 -69.268528)
			(xy 464.314697 -69.310877) (xy 464.237654 -69.346061) (xy 464.157615 -69.373763) (xy 464.075306 -69.393731)
			(xy 463.991471 -69.405784) (xy 463.90687 -69.409815) (xy 463.822269 -69.405784) (xy 463.738434 -69.393731)
			(xy 463.656125 -69.373763) (xy 463.576086 -69.346061) (xy 463.499043 -69.310877) (xy 463.425693 -69.268528)
			(xy 463.356701 -69.219399) (xy 463.292691 -69.163934) (xy 463.234243 -69.102636) (xy 463.181887 -69.03606)
			(xy 463.136097 -68.964808) (xy 463.097286 -68.889527) (xy 463.065807 -68.810897) (xy 463.041946 -68.72963)
			(xy 463.025917 -68.646464) (xy 463.017866 -68.56215) (xy 440.246008 -68.56215) (xy 440.246008 -71.039228)
			(xy 443.224918 -71.039228) (xy 443.228989 -70.983606) (xy 443.241115 -70.929169) (xy 443.261038 -70.877078)
			(xy 443.288334 -70.828443) (xy 443.32242 -70.7843) (xy 443.362569 -70.745591) (xy 443.407927 -70.71314)
			(xy 443.457527 -70.687639) (xy 443.510311 -70.669632) (xy 443.565154 -70.659502) (xy 443.620888 -70.657465)
			(xy 443.676325 -70.663565) (xy 443.730282 -70.677671) (xy 443.781611 -70.699483) (xy 443.829217 -70.728537)
			(xy 443.872085 -70.764212) (xy 443.909302 -70.805749) (xy 443.940075 -70.852262) (xy 443.963747 -70.902759)
			(xy 443.979815 -70.956166) (xy 443.987935 -71.011342) (xy 443.988444 -71.039228) (xy 443.987935 -71.067114)
			(xy 443.979815 -71.12229) (xy 443.963747 -71.175697) (xy 443.940075 -71.226194) (xy 443.909302 -71.272707)
			(xy 443.872085 -71.314244) (xy 443.829217 -71.349919) (xy 443.781611 -71.378973) (xy 443.730282 -71.400785)
			(xy 443.676325 -71.414891) (xy 443.620888 -71.420991) (xy 443.565154 -71.418954) (xy 443.510311 -71.408824)
			(xy 443.457527 -71.390817) (xy 443.407927 -71.365316) (xy 443.362569 -71.332865) (xy 443.32242 -71.294156)
			(xy 443.288334 -71.250013) (xy 443.261038 -71.201378) (xy 443.241115 -71.149287) (xy 443.228989 -71.09485)
			(xy 443.224918 -71.039228) (xy 440.246008 -71.039228) (xy 440.246008 -73.088052) (xy 452.643969 -73.088052)
			(xy 452.643969 -73.033548) (xy 452.651726 -72.979599) (xy 452.667082 -72.927303) (xy 452.689723 -72.877724)
			(xy 452.719191 -72.831873) (xy 452.754883 -72.790682) (xy 452.796074 -72.754989) (xy 452.841926 -72.725522)
			(xy 452.891505 -72.702881) (xy 452.943801 -72.687526) (xy 452.99775 -72.679769) (xy 453.025002 -72.679306)
			(xy 453.052711 -72.679821) (xy 453.107544 -72.687844) (xy 453.160639 -72.703721) (xy 453.210876 -72.727117)
			(xy 453.257196 -72.75754) (xy 453.27824 -72.775572) (xy 453.289642 -72.78504) (xy 453.316492 -72.797557)
			(xy 453.345804 -72.80185) (xy 453.375116 -72.797557) (xy 453.401966 -72.78504) (xy 453.413368 -72.775572)
			(xy 453.434411 -72.757537) (xy 453.480729 -72.727108) (xy 453.530966 -72.703707) (xy 453.584061 -72.687827)
			(xy 453.638896 -72.679803) (xy 453.666606 -72.679306) (xy 453.693858 -72.679764) (xy 453.747807 -72.687522)
			(xy 453.800103 -72.702878) (xy 453.849681 -72.72552) (xy 453.895533 -72.754988) (xy 453.936724 -72.790681)
			(xy 453.972416 -72.831872) (xy 454.001883 -72.877724) (xy 454.024524 -72.927303) (xy 454.03988 -72.979599)
			(xy 454.047636 -73.033548) (xy 454.047636 -73.088052) (xy 454.047636 -73.088053) (xy 454.467669 -73.088053)
			(xy 454.467669 -73.033547) (xy 454.475427 -72.979596) (xy 454.490783 -72.927299) (xy 454.513426 -72.877719)
			(xy 454.542895 -72.831866) (xy 454.57859 -72.790675) (xy 454.619784 -72.754982) (xy 454.665638 -72.725516)
			(xy 454.715219 -72.702876) (xy 454.767518 -72.687522) (xy 454.821469 -72.679768) (xy 454.848722 -72.679306)
			(xy 454.876431 -72.679809) (xy 454.931265 -72.687835) (xy 454.98436 -72.703715) (xy 455.034596 -72.727113)
			(xy 455.080916 -72.757538) (xy 455.10196 -72.775572) (xy 455.113362 -72.78504) (xy 455.140212 -72.797557)
			(xy 455.169524 -72.80185) (xy 455.198836 -72.797557) (xy 455.225686 -72.78504) (xy 455.237088 -72.775572)
			(xy 455.258124 -72.757528) (xy 455.304444 -72.7271) (xy 455.354682 -72.703701) (xy 455.407779 -72.687823)
			(xy 455.462616 -72.679801) (xy 455.490326 -72.679306) (xy 455.517577 -72.679766) (xy 455.571524 -72.687525)
			(xy 455.623817 -72.702883) (xy 455.673393 -72.725527) (xy 455.719242 -72.754995) (xy 455.760431 -72.790688)
			(xy 455.796121 -72.831879) (xy 455.825586 -72.87773) (xy 455.848226 -72.927307) (xy 455.86358 -72.979602)
			(xy 455.871336 -73.033549) (xy 455.871336 -73.088051) (xy 455.86358 -73.141998) (xy 455.848226 -73.194293)
			(xy 455.825586 -73.24387) (xy 455.796121 -73.289721) (xy 455.760431 -73.330912) (xy 455.719242 -73.366605)
			(xy 455.673393 -73.396073) (xy 455.623817 -73.418717) (xy 455.571524 -73.434075) (xy 455.517577 -73.441834)
			(xy 455.490326 -73.442322) (xy 455.462616 -73.441843) (xy 455.407781 -73.43381) (xy 455.354686 -73.417924)
			(xy 455.30445 -73.39452) (xy 455.258131 -73.364091) (xy 455.237088 -73.346056) (xy 455.225686 -73.336588)
			(xy 455.198836 -73.324071) (xy 455.169524 -73.319778) (xy 455.140212 -73.324071) (xy 455.113362 -73.336588)
			(xy 455.10196 -73.346056) (xy 455.08091 -73.364082) (xy 455.034593 -73.394511) (xy 454.984358 -73.417914)
			(xy 454.931265 -73.433796) (xy 454.876431 -73.441823) (xy 454.848722 -73.442322) (xy 454.821469 -73.441832)
			(xy 454.767518 -73.434078) (xy 454.715219 -73.418724) (xy 454.665638 -73.396084) (xy 454.619784 -73.366618)
			(xy 454.57859 -73.330925) (xy 454.542895 -73.289734) (xy 454.513426 -73.243881) (xy 454.490783 -73.194301)
			(xy 454.475427 -73.142004) (xy 454.467669 -73.088053) (xy 454.047636 -73.088053) (xy 454.03988 -73.142001)
			(xy 454.024524 -73.194297) (xy 454.001883 -73.243876) (xy 453.972416 -73.289728) (xy 453.936724 -73.330919)
			(xy 453.895533 -73.366612) (xy 453.849681 -73.39608) (xy 453.800103 -73.418722) (xy 453.747807 -73.434078)
			(xy 453.693858 -73.441836) (xy 453.666606 -73.442322) (xy 453.638898 -73.441795) (xy 453.584065 -73.433774)
			(xy 453.530971 -73.4179) (xy 453.480734 -73.394506) (xy 453.434413 -73.364087) (xy 453.413368 -73.346056)
			(xy 453.401966 -73.336588) (xy 453.375116 -73.324071) (xy 453.345804 -73.319778) (xy 453.316492 -73.324071)
			(xy 453.289642 -73.336588) (xy 453.27824 -73.346056) (xy 453.257197 -73.364091) (xy 453.210879 -73.394519)
			(xy 453.160642 -73.41792) (xy 453.107547 -73.4338) (xy 453.052712 -73.441825) (xy 453.025002 -73.442322)
			(xy 452.99775 -73.441831) (xy 452.943801 -73.434074) (xy 452.891505 -73.418719) (xy 452.841926 -73.396078)
			(xy 452.796074 -73.366611) (xy 452.754883 -73.330918) (xy 452.719191 -73.289727) (xy 452.689723 -73.243876)
			(xy 452.667082 -73.194297) (xy 452.651726 -73.142001) (xy 452.643969 -73.088052) (xy 440.246008 -73.088052)
			(xy 440.246008 -74.640948) (xy 443.978282 -74.640948) (xy 443.982353 -74.585326) (xy 443.994479 -74.530889)
			(xy 444.014402 -74.478798) (xy 444.041698 -74.430163) (xy 444.075784 -74.38602) (xy 444.115933 -74.347311)
			(xy 444.161291 -74.31486) (xy 444.210891 -74.289359) (xy 444.263675 -74.271352) (xy 444.318518 -74.261222)
			(xy 444.374252 -74.259185) (xy 444.429689 -74.265285) (xy 444.483646 -74.279391) (xy 444.534975 -74.301203)
			(xy 444.582581 -74.330257) (xy 444.625449 -74.365932) (xy 444.662666 -74.407469) (xy 444.693439 -74.453982)
			(xy 444.717111 -74.504479) (xy 444.733179 -74.557886) (xy 444.741299 -74.613062) (xy 444.741808 -74.640948)
			(xy 444.741299 -74.668834) (xy 444.733179 -74.72401) (xy 444.717111 -74.777417) (xy 444.693439 -74.827914)
			(xy 444.662666 -74.874427) (xy 444.625449 -74.915964) (xy 444.582581 -74.951639) (xy 444.534975 -74.980693)
			(xy 444.483646 -75.002505) (xy 444.429689 -75.016611) (xy 444.374252 -75.022711) (xy 444.318518 -75.020674)
			(xy 444.263675 -75.010544) (xy 444.210891 -74.992537) (xy 444.161291 -74.967036) (xy 444.115933 -74.934585)
			(xy 444.075784 -74.895876) (xy 444.041698 -74.851733) (xy 444.014402 -74.803098) (xy 443.994479 -74.751007)
			(xy 443.982353 -74.69657) (xy 443.978282 -74.640948) (xy 440.246008 -74.640948) (xy 440.246008 -75.054206)
			(xy 451.065898 -75.054206) (xy 451.069969 -74.998584) (xy 451.082095 -74.944147) (xy 451.102018 -74.892056)
			(xy 451.129314 -74.843421) (xy 451.1634 -74.799278) (xy 451.203549 -74.760569) (xy 451.248907 -74.728118)
			(xy 451.298507 -74.702617) (xy 451.351291 -74.68461) (xy 451.406134 -74.67448) (xy 451.461868 -74.672443)
			(xy 451.517305 -74.678543) (xy 451.571262 -74.692649) (xy 451.622591 -74.714461) (xy 451.670197 -74.743515)
			(xy 451.713065 -74.77919) (xy 451.745377 -74.815253) (xy 454.048569 -74.815253) (xy 454.048569 -74.760747)
			(xy 454.056327 -74.706796) (xy 454.071683 -74.654499) (xy 454.094326 -74.604919) (xy 454.123795 -74.559066)
			(xy 454.15949 -74.517875) (xy 454.200684 -74.482182) (xy 454.246538 -74.452716) (xy 454.296119 -74.430076)
			(xy 454.348418 -74.414722) (xy 454.402369 -74.406968) (xy 454.429622 -74.406506) (xy 454.457331 -74.407009)
			(xy 454.512165 -74.415035) (xy 454.56526 -74.430915) (xy 454.615496 -74.454313) (xy 454.661816 -74.484738)
			(xy 454.68286 -74.502772) (xy 454.694262 -74.51224) (xy 454.721112 -74.524757) (xy 454.750424 -74.52905)
			(xy 454.779736 -74.524757) (xy 454.806586 -74.51224) (xy 454.817988 -74.502772) (xy 454.839024 -74.484728)
			(xy 454.885344 -74.4543) (xy 454.935582 -74.430901) (xy 454.988679 -74.415023) (xy 455.043516 -74.407001)
			(xy 455.071226 -74.406506) (xy 455.098477 -74.406966) (xy 455.152424 -74.414725) (xy 455.204717 -74.430083)
			(xy 455.254293 -74.452727) (xy 455.300142 -74.482195) (xy 455.341331 -74.517888) (xy 455.377021 -74.559079)
			(xy 455.406486 -74.60493) (xy 455.429126 -74.654507) (xy 455.44448 -74.706802) (xy 455.452236 -74.760749)
			(xy 455.452236 -74.815251) (xy 455.44448 -74.869198) (xy 455.429126 -74.921493) (xy 455.406486 -74.97107)
			(xy 455.377021 -75.016921) (xy 455.341331 -75.058112) (xy 455.300142 -75.093805) (xy 455.254293 -75.123273)
			(xy 455.204717 -75.145917) (xy 455.152424 -75.161275) (xy 455.098477 -75.169034) (xy 455.071226 -75.169522)
			(xy 455.043516 -75.169043) (xy 454.988681 -75.16101) (xy 454.935586 -75.145124) (xy 454.88535 -75.12172)
			(xy 454.839031 -75.091291) (xy 454.817988 -75.073256) (xy 454.806586 -75.063788) (xy 454.779736 -75.051271)
			(xy 454.750424 -75.046978) (xy 454.721112 -75.051271) (xy 454.694262 -75.063788) (xy 454.68286 -75.073256)
			(xy 454.66181 -75.091282) (xy 454.615493 -75.121711) (xy 454.565258 -75.145114) (xy 454.512165 -75.160996)
			(xy 454.457331 -75.169023) (xy 454.429622 -75.169522) (xy 454.402369 -75.169032) (xy 454.348418 -75.161278)
			(xy 454.296119 -75.145924) (xy 454.246538 -75.123284) (xy 454.200684 -75.093818) (xy 454.15949 -75.058125)
			(xy 454.123795 -75.016934) (xy 454.094326 -74.971081) (xy 454.071683 -74.921501) (xy 454.056327 -74.869204)
			(xy 454.048569 -74.815253) (xy 451.745377 -74.815253) (xy 451.750282 -74.820727) (xy 451.781055 -74.86724)
			(xy 451.804727 -74.917737) (xy 451.820795 -74.971144) (xy 451.828915 -75.02632) (xy 451.829424 -75.054206)
			(xy 451.828915 -75.082092) (xy 451.820795 -75.137268) (xy 451.804727 -75.190675) (xy 451.781055 -75.241172)
			(xy 451.750282 -75.287685) (xy 451.713065 -75.329222) (xy 451.670197 -75.364897) (xy 451.622591 -75.393951)
			(xy 451.571262 -75.415763) (xy 451.517305 -75.429869) (xy 451.461868 -75.435969) (xy 451.406134 -75.433932)
			(xy 451.351291 -75.423802) (xy 451.298507 -75.405795) (xy 451.248907 -75.380294) (xy 451.203549 -75.347843)
			(xy 451.1634 -75.309134) (xy 451.129314 -75.264991) (xy 451.102018 -75.216356) (xy 451.082095 -75.164265)
			(xy 451.069969 -75.109828) (xy 451.065898 -75.054206) (xy 440.246008 -75.054206) (xy 440.246008 -76.002572)
			(xy 463.017866 -76.002572) (xy 463.017866 -75.917876) (xy 463.025917 -75.833562) (xy 463.041946 -75.750396)
			(xy 463.065807 -75.669129) (xy 463.097286 -75.590499) (xy 463.136097 -75.515218) (xy 463.181887 -75.443966)
			(xy 463.234243 -75.37739) (xy 463.292691 -75.316092) (xy 463.356701 -75.260627) (xy 463.425693 -75.211498)
			(xy 463.499043 -75.169149) (xy 463.576086 -75.133965) (xy 463.656125 -75.106263) (xy 463.738434 -75.086295)
			(xy 463.822269 -75.074242) (xy 463.90687 -75.070212) (xy 463.991471 -75.074242) (xy 464.075306 -75.086295)
			(xy 464.157615 -75.106263) (xy 464.237654 -75.133965) (xy 464.314697 -75.169149) (xy 464.388047 -75.211498)
			(xy 464.457039 -75.260627) (xy 464.521049 -75.316092) (xy 464.579497 -75.37739) (xy 464.631853 -75.443966)
			(xy 464.677643 -75.515218) (xy 464.716454 -75.590499) (xy 464.747933 -75.669129) (xy 464.771794 -75.750396)
			(xy 464.787823 -75.833562) (xy 464.795874 -75.917876) (xy 464.796378 -75.960224) (xy 465.542379 -75.960224)
			(xy 465.546415 -75.876777) (xy 465.558487 -75.794109) (xy 465.57848 -75.712992) (xy 465.606209 -75.634183)
			(xy 465.641415 -75.558418) (xy 465.683769 -75.486405) (xy 465.732875 -75.418816) (xy 465.788276 -75.356282)
			(xy 465.849453 -75.299387) (xy 465.915836 -75.248661) (xy 465.986804 -75.20458) (xy 466.061696 -75.167554)
			(xy 466.139812 -75.137928) (xy 466.220422 -75.11598) (xy 466.302774 -75.101915) (xy 466.3861 -75.095863)
			(xy 466.46962 -75.097882) (xy 466.552556 -75.107952) (xy 466.634132 -75.12598) (xy 466.713588 -75.151797)
			(xy 466.790181 -75.185162) (xy 466.863197 -75.225763) (xy 466.931953 -75.273222) (xy 466.995807 -75.327095)
			(xy 467.054164 -75.38688) (xy 467.106479 -75.452017) (xy 467.152262 -75.5219) (xy 467.191087 -75.595875)
			(xy 467.222592 -75.673252) (xy 467.246481 -75.753309) (xy 467.262532 -75.835297) (xy 467.270595 -75.918452)
			(xy 467.2711 -75.960224) (xy 467.270595 -76.001996) (xy 467.262532 -76.085151) (xy 467.246481 -76.167139)
			(xy 467.222592 -76.247196) (xy 467.191087 -76.324573) (xy 467.152262 -76.398548) (xy 467.106479 -76.468431)
			(xy 467.054164 -76.533568) (xy 466.995807 -76.593353) (xy 466.931953 -76.647226) (xy 466.863197 -76.694685)
			(xy 466.790181 -76.735286) (xy 466.713588 -76.768651) (xy 466.634132 -76.794468) (xy 466.552556 -76.812496)
			(xy 466.46962 -76.822566) (xy 466.3861 -76.824585) (xy 466.302774 -76.818533) (xy 466.220422 -76.804468)
			(xy 466.139812 -76.78252) (xy 466.061696 -76.752894) (xy 465.986804 -76.715868) (xy 465.915836 -76.671787)
			(xy 465.849453 -76.621061) (xy 465.788276 -76.564166) (xy 465.732875 -76.501632) (xy 465.683769 -76.434043)
			(xy 465.641415 -76.36203) (xy 465.606209 -76.286265) (xy 465.57848 -76.207456) (xy 465.558487 -76.126339)
			(xy 465.546415 -76.043671) (xy 465.542379 -75.960224) (xy 464.796378 -75.960224) (xy 464.795874 -76.002572)
			(xy 464.787823 -76.086886) (xy 464.771794 -76.170052) (xy 464.747933 -76.251319) (xy 464.716454 -76.329949)
			(xy 464.677643 -76.40523) (xy 464.631853 -76.476482) (xy 464.579497 -76.543058) (xy 464.521049 -76.604356)
			(xy 464.457039 -76.659821) (xy 464.388047 -76.70895) (xy 464.314697 -76.751299) (xy 464.237654 -76.786483)
			(xy 464.157615 -76.814185) (xy 464.075306 -76.834153) (xy 463.991471 -76.846206) (xy 463.90687 -76.850237)
			(xy 463.822269 -76.846206) (xy 463.738434 -76.834153) (xy 463.656125 -76.814185) (xy 463.576086 -76.786483)
			(xy 463.499043 -76.751299) (xy 463.425693 -76.70895) (xy 463.356701 -76.659821) (xy 463.292691 -76.604356)
			(xy 463.234243 -76.543058) (xy 463.181887 -76.476482) (xy 463.136097 -76.40523) (xy 463.097286 -76.329949)
			(xy 463.065807 -76.251319) (xy 463.041946 -76.170052) (xy 463.025917 -76.086886) (xy 463.017866 -76.002572)
			(xy 440.246008 -76.002572) (xy 440.246008 -76.63053) (xy 445.693798 -76.63053) (xy 445.697869 -76.574908)
			(xy 445.709995 -76.520471) (xy 445.729918 -76.46838) (xy 445.757214 -76.419745) (xy 445.7913 -76.375602)
			(xy 445.831449 -76.336893) (xy 445.876807 -76.304442) (xy 445.926407 -76.278941) (xy 445.979191 -76.260934)
			(xy 446.034034 -76.250804) (xy 446.089768 -76.248767) (xy 446.145205 -76.254867) (xy 446.199162 -76.268973)
			(xy 446.250491 -76.290785) (xy 446.298097 -76.319839) (xy 446.340965 -76.355514) (xy 446.378182 -76.397051)
			(xy 446.408955 -76.443564) (xy 446.432627 -76.494061) (xy 446.448695 -76.547468) (xy 446.456815 -76.602644)
			(xy 446.457106 -76.618592) (xy 446.684398 -76.618592) (xy 446.688469 -76.56297) (xy 446.700595 -76.508533)
			(xy 446.720518 -76.456442) (xy 446.747814 -76.407807) (xy 446.7819 -76.363664) (xy 446.822049 -76.324955)
			(xy 446.867407 -76.292504) (xy 446.917007 -76.267003) (xy 446.969791 -76.248996) (xy 447.024634 -76.238866)
			(xy 447.080368 -76.236829) (xy 447.135805 -76.242929) (xy 447.189762 -76.257035) (xy 447.241091 -76.278847)
			(xy 447.288697 -76.307901) (xy 447.331565 -76.343576) (xy 447.368782 -76.385113) (xy 447.399555 -76.431626)
			(xy 447.423227 -76.482123) (xy 447.439295 -76.53553) (xy 447.447415 -76.590706) (xy 447.447924 -76.618592)
			(xy 447.447415 -76.646478) (xy 447.439295 -76.701654) (xy 447.423227 -76.755061) (xy 447.399555 -76.805558)
			(xy 447.368782 -76.852071) (xy 447.331565 -76.893608) (xy 447.288697 -76.929283) (xy 447.241091 -76.958337)
			(xy 447.189762 -76.980149) (xy 447.135805 -76.994255) (xy 447.080368 -77.000355) (xy 447.024634 -76.998318)
			(xy 446.969791 -76.988188) (xy 446.917007 -76.970181) (xy 446.867407 -76.94468) (xy 446.822049 -76.912229)
			(xy 446.7819 -76.87352) (xy 446.747814 -76.829377) (xy 446.720518 -76.780742) (xy 446.700595 -76.728651)
			(xy 446.688469 -76.674214) (xy 446.684398 -76.618592) (xy 446.457106 -76.618592) (xy 446.457324 -76.63053)
			(xy 446.456815 -76.658416) (xy 446.448695 -76.713592) (xy 446.432627 -76.766999) (xy 446.408955 -76.817496)
			(xy 446.378182 -76.864009) (xy 446.340965 -76.905546) (xy 446.298097 -76.941221) (xy 446.250491 -76.970275)
			(xy 446.199162 -76.992087) (xy 446.145205 -77.006193) (xy 446.089768 -77.012293) (xy 446.034034 -77.010256)
			(xy 445.979191 -77.000126) (xy 445.926407 -76.982119) (xy 445.876807 -76.956618) (xy 445.831449 -76.924167)
			(xy 445.7913 -76.885458) (xy 445.757214 -76.841315) (xy 445.729918 -76.79268) (xy 445.709995 -76.740589)
			(xy 445.697869 -76.686152) (xy 445.693798 -76.63053) (xy 440.246008 -76.63053) (xy 440.246008 -77.866748)
			(xy 444.625982 -77.866748) (xy 444.630053 -77.811126) (xy 444.642179 -77.756689) (xy 444.662102 -77.704598)
			(xy 444.689398 -77.655963) (xy 444.723484 -77.61182) (xy 444.763633 -77.573111) (xy 444.808991 -77.54066)
			(xy 444.858591 -77.515159) (xy 444.911375 -77.497152) (xy 444.966218 -77.487022) (xy 445.021952 -77.484985)
			(xy 445.077389 -77.491085) (xy 445.131346 -77.505191) (xy 445.182675 -77.527003) (xy 445.230281 -77.556057)
			(xy 445.273149 -77.591732) (xy 445.310366 -77.633269) (xy 445.341139 -77.679782) (xy 445.364811 -77.730279)
			(xy 445.380879 -77.783686) (xy 445.388999 -77.838862) (xy 445.389508 -77.866748) (xy 445.388999 -77.894634)
			(xy 445.380879 -77.94981) (xy 445.364811 -78.003217) (xy 445.341139 -78.053714) (xy 445.310366 -78.100227)
			(xy 445.273149 -78.141764) (xy 445.230281 -78.177439) (xy 445.182675 -78.206493) (xy 445.131346 -78.228305)
			(xy 445.077389 -78.242411) (xy 445.021952 -78.248511) (xy 444.966218 -78.246474) (xy 444.911375 -78.236344)
			(xy 444.858591 -78.218337) (xy 444.808991 -78.192836) (xy 444.763633 -78.160385) (xy 444.723484 -78.121676)
			(xy 444.689398 -78.077533) (xy 444.662102 -78.028898) (xy 444.642179 -77.976807) (xy 444.630053 -77.92237)
			(xy 444.625982 -77.866748) (xy 440.246008 -77.866748) (xy 440.246008 -77.912976) (xy 441.253118 -78.920086)
			(xy 447.149726 -78.920086) (xy 447.153797 -78.864464) (xy 447.165923 -78.810027) (xy 447.185846 -78.757936)
			(xy 447.213142 -78.709301) (xy 447.247228 -78.665158) (xy 447.287377 -78.626449) (xy 447.332735 -78.593998)
			(xy 447.382335 -78.568497) (xy 447.435119 -78.55049) (xy 447.489962 -78.54036) (xy 447.545696 -78.538323)
			(xy 447.601133 -78.544423) (xy 447.65509 -78.558529) (xy 447.706419 -78.580341) (xy 447.754025 -78.609395)
			(xy 447.796893 -78.64507) (xy 447.83411 -78.686607) (xy 447.864883 -78.73312) (xy 447.888555 -78.783617)
			(xy 447.904623 -78.837024) (xy 447.912743 -78.8922) (xy 447.913252 -78.920086) (xy 447.912743 -78.947972)
			(xy 447.904623 -79.003148) (xy 447.888555 -79.056555) (xy 447.864883 -79.107052) (xy 447.83411 -79.153565)
			(xy 447.796893 -79.195102) (xy 447.754025 -79.230777) (xy 447.706419 -79.259831) (xy 447.65509 -79.281643)
			(xy 447.601133 -79.295749) (xy 447.545696 -79.301849) (xy 447.489962 -79.299812) (xy 447.435119 -79.289682)
			(xy 447.382335 -79.271675) (xy 447.332735 -79.246174) (xy 447.287377 -79.213723) (xy 447.247228 -79.175014)
			(xy 447.213142 -79.130871) (xy 447.185846 -79.082236) (xy 447.165923 -79.030145) (xy 447.153797 -78.975708)
			(xy 447.149726 -78.920086) (xy 441.253118 -78.920086) (xy 441.989972 -79.65694) (xy 448.139312 -79.65694)
			(xy 449.010024 -78.786228) (xy 449.01358 -78.772258) (xy 449.020681 -78.744851) (xy 449.041874 -78.692351)
			(xy 449.070596 -78.643562) (xy 449.106215 -78.599556) (xy 449.147949 -78.561299) (xy 449.194881 -78.529634)
			(xy 449.245979 -78.505254) (xy 449.300119 -78.488698) (xy 449.356112 -78.480327) (xy 449.412728 -78.480327)
			(xy 449.468721 -78.488698) (xy 449.522861 -78.505254) (xy 449.573959 -78.529634) (xy 449.620891 -78.561299)
			(xy 449.662625 -78.599556) (xy 449.698244 -78.643562) (xy 449.726966 -78.692351) (xy 449.748159 -78.744851)
			(xy 449.75526 -78.772258) (xy 449.758816 -78.786228) (xy 450.451728 -79.47914) (xy 451.759828 -79.47914)
			(xy 452.568564 -78.670404) (xy 452.568564 -78.27772) (xy 452.569121 -78.250876) (xy 452.578135 -78.197949)
			(xy 452.595911 -78.147288) (xy 452.608442 -78.123542) (xy 452.614792 -78.112112) (xy 452.614792 -77.376274)
			(xy 452.608442 -77.364844) (xy 452.595911 -77.341096) (xy 452.578128 -77.290437) (xy 452.569102 -77.237511)
			(xy 452.568564 -77.210666) (xy 452.568564 -76.85024) (xy 452.553518 -76.826662) (xy 452.529751 -76.776032)
			(xy 452.513639 -76.722472) (xy 452.505528 -76.667132) (xy 452.505064 -76.639166) (xy 452.50555 -76.611915)
			(xy 452.513306 -76.557967) (xy 452.528661 -76.505672) (xy 452.551303 -76.456095) (xy 452.580769 -76.410245)
			(xy 452.61646 -76.369054) (xy 452.657651 -76.333363) (xy 452.703501 -76.303897) (xy 452.753078 -76.281255)
			(xy 452.805373 -76.2659) (xy 452.859321 -76.258144) (xy 452.913823 -76.258144) (xy 452.967771 -76.2659)
			(xy 453.020066 -76.281255) (xy 453.069643 -76.303897) (xy 453.115493 -76.333363) (xy 453.156684 -76.369054)
			(xy 453.192375 -76.410245) (xy 453.221841 -76.456095) (xy 453.244483 -76.505672) (xy 453.259838 -76.557967)
			(xy 453.267594 -76.611915) (xy 453.26808 -76.639166) (xy 453.267609 -76.667131) (xy 453.259485 -76.722467)
			(xy 453.243376 -76.776027) (xy 453.219627 -76.826664) (xy 453.20458 -76.85024) (xy 453.20458 -77.091286)
			(xy 453.21093 -77.102716) (xy 453.223457 -77.126464) (xy 453.241233 -77.177124) (xy 453.250249 -77.23005)
			(xy 453.250808 -77.256894) (xy 453.250808 -78.231492) (xy 453.25025 -78.258336) (xy 453.241233 -78.311261)
			(xy 453.223454 -78.36192) (xy 453.21093 -78.38567) (xy 453.20458 -78.3971) (xy 453.20458 -78.801976)
			(xy 453.204063 -78.826957) (xy 453.196203 -78.876299) (xy 453.180733 -78.923808) (xy 453.158035 -78.968319)
			(xy 453.128664 -79.008738) (xy 453.111362 -79.026766) (xy 452.11619 -80.021938) (xy 452.098207 -80.039296)
			(xy 452.057797 -80.068706) (xy 452.013279 -80.091423) (xy 451.965752 -80.106887) (xy 451.91639 -80.114715)
			(xy 451.8914 -80.115156) (xy 450.320156 -80.115156) (xy 450.295174 -80.114642) (xy 450.24583 -80.106785)
			(xy 450.198319 -80.091318) (xy 450.153806 -80.068621) (xy 450.113384 -80.039251) (xy 450.095366 -80.021938)
			(xy 449.38442 -79.310992) (xy 448.495674 -80.199738) (xy 448.477691 -80.217096) (xy 448.43728 -80.246503)
			(xy 448.392762 -80.269218) (xy 448.345235 -80.284679) (xy 448.295873 -80.292505) (xy 448.270884 -80.292956)
			(xy 441.8584 -80.292956) (xy 441.833416 -80.292445) (xy 441.784069 -80.284594) (xy 441.736553 -80.269133)
			(xy 441.692035 -80.24644) (xy 441.651608 -80.217072) (xy 441.63361 -80.199738) (xy 440.200542 -78.76667)
			(xy 440.189577 -78.756452) (xy 440.163161 -78.742322) (xy 440.133782 -78.736461) (xy 440.103967 -78.739374)
			(xy 440.076278 -78.750809) (xy 440.053096 -78.769785) (xy 440.036415 -78.794668) (xy 440.027669 -78.82332)
			(xy 440.02706 -78.838298) (xy 440.02706 -80.124808) (xy 441.65774 -81.755488) (xy 464.54314 -81.755488)
		)
		(stroke
			(width 0)
			(type solid)
		)
		(fill yes)
		(layer "In13.Cu")
		(net "GND")
	)
	(gr_poly
		(pts
			(xy 190.6524 -366.740948) (xy 190.6524 -334.254348) (xy 188.7728 -332.374748) (xy 167.4876 -332.374748)
			(xy 167.1828 -332.679548) (xy 167.1828 -333.762604) (xy 167.05199 -333.893414) (xy 167.030908 -333.893414)
			(xy 167.015922 -333.9084) (xy 165.889432 -335.03489) (xy 165.926233 -335.51996) (xy 170.076618 -335.51996)
			(xy 170.076618 -335.435264) (xy 170.084669 -335.35095) (xy 170.100698 -335.267784) (xy 170.124559 -335.186517)
			(xy 170.156038 -335.107887) (xy 170.194849 -335.032606) (xy 170.240639 -334.961354) (xy 170.292995 -334.894778)
			(xy 170.351443 -334.83348) (xy 170.415453 -334.778015) (xy 170.484445 -334.728886) (xy 170.557795 -334.686537)
			(xy 170.634838 -334.651353) (xy 170.714877 -334.623651) (xy 170.797186 -334.603683) (xy 170.881021 -334.59163)
			(xy 170.965622 -334.5876) (xy 171.050223 -334.59163) (xy 171.134058 -334.603683) (xy 171.216367 -334.623651)
			(xy 171.296406 -334.651353) (xy 171.373449 -334.686537) (xy 171.446799 -334.728886) (xy 171.515791 -334.778015)
			(xy 171.579801 -334.83348) (xy 171.638249 -334.894778) (xy 171.690605 -334.961354) (xy 171.736395 -335.032606)
			(xy 171.775206 -335.107887) (xy 171.806685 -335.186517) (xy 171.830546 -335.267784) (xy 171.846575 -335.35095)
			(xy 171.854626 -335.435264) (xy 171.85513 -335.477612) (xy 171.854626 -335.51996) (xy 171.85402 -335.52631)
			(xy 176.26736 -335.52631) (xy 176.26736 -335.441614) (xy 176.275411 -335.3573) (xy 176.29144 -335.274134)
			(xy 176.315301 -335.192867) (xy 176.34678 -335.114237) (xy 176.385591 -335.038956) (xy 176.431381 -334.967704)
			(xy 176.483737 -334.901128) (xy 176.542185 -334.83983) (xy 176.606195 -334.784365) (xy 176.675187 -334.735236)
			(xy 176.748537 -334.692887) (xy 176.82558 -334.657703) (xy 176.905619 -334.630001) (xy 176.987928 -334.610033)
			(xy 177.071763 -334.59798) (xy 177.156364 -334.59395) (xy 177.240965 -334.59798) (xy 177.3248 -334.610033)
			(xy 177.407109 -334.630001) (xy 177.487148 -334.657703) (xy 177.564191 -334.692887) (xy 177.637541 -334.735236)
			(xy 177.706533 -334.784365) (xy 177.770543 -334.83983) (xy 177.828991 -334.901128) (xy 177.881347 -334.967704)
			(xy 177.927137 -335.038956) (xy 177.965948 -335.114237) (xy 177.997427 -335.192867) (xy 178.021288 -335.274134)
			(xy 178.037317 -335.3573) (xy 178.045368 -335.441614) (xy 178.045872 -335.483962) (xy 178.045368 -335.52631)
			(xy 182.46496 -335.52631) (xy 182.46496 -335.441614) (xy 182.473011 -335.3573) (xy 182.48904 -335.274134)
			(xy 182.512901 -335.192867) (xy 182.54438 -335.114237) (xy 182.583191 -335.038956) (xy 182.628981 -334.967704)
			(xy 182.681337 -334.901128) (xy 182.739785 -334.83983) (xy 182.803795 -334.784365) (xy 182.872787 -334.735236)
			(xy 182.946137 -334.692887) (xy 183.02318 -334.657703) (xy 183.103219 -334.630001) (xy 183.185528 -334.610033)
			(xy 183.269363 -334.59798) (xy 183.353964 -334.59395) (xy 183.438565 -334.59798) (xy 183.5224 -334.610033)
			(xy 183.604709 -334.630001) (xy 183.684748 -334.657703) (xy 183.761791 -334.692887) (xy 183.835141 -334.735236)
			(xy 183.904133 -334.784365) (xy 183.968143 -334.83983) (xy 184.026591 -334.901128) (xy 184.078947 -334.967704)
			(xy 184.124737 -335.038956) (xy 184.163548 -335.114237) (xy 184.195027 -335.192867) (xy 184.218888 -335.274134)
			(xy 184.234917 -335.3573) (xy 184.242968 -335.441614) (xy 184.243472 -335.483962) (xy 184.242968 -335.52631)
			(xy 184.234917 -335.610624) (xy 184.218888 -335.69379) (xy 184.195027 -335.775057) (xy 184.163548 -335.853687)
			(xy 184.124737 -335.928968) (xy 184.078947 -336.00022) (xy 184.026591 -336.066796) (xy 183.968143 -336.128094)
			(xy 183.904133 -336.183559) (xy 183.835141 -336.232688) (xy 183.761791 -336.275037) (xy 183.684748 -336.310221)
			(xy 183.604709 -336.337923) (xy 183.5224 -336.357891) (xy 183.438565 -336.369944) (xy 183.353964 -336.373975)
			(xy 183.269363 -336.369944) (xy 183.185528 -336.357891) (xy 183.103219 -336.337923) (xy 183.02318 -336.310221)
			(xy 182.946137 -336.275037) (xy 182.872787 -336.232688) (xy 182.803795 -336.183559) (xy 182.739785 -336.128094)
			(xy 182.681337 -336.066796) (xy 182.628981 -336.00022) (xy 182.583191 -335.928968) (xy 182.54438 -335.853687)
			(xy 182.512901 -335.775057) (xy 182.48904 -335.69379) (xy 182.473011 -335.610624) (xy 182.46496 -335.52631)
			(xy 178.045368 -335.52631) (xy 178.037317 -335.610624) (xy 178.021288 -335.69379) (xy 177.997427 -335.775057)
			(xy 177.965948 -335.853687) (xy 177.927137 -335.928968) (xy 177.881347 -336.00022) (xy 177.828991 -336.066796)
			(xy 177.770543 -336.128094) (xy 177.706533 -336.183559) (xy 177.637541 -336.232688) (xy 177.564191 -336.275037)
			(xy 177.487148 -336.310221) (xy 177.407109 -336.337923) (xy 177.3248 -336.357891) (xy 177.240965 -336.369944)
			(xy 177.156364 -336.373975) (xy 177.071763 -336.369944) (xy 176.987928 -336.357891) (xy 176.905619 -336.337923)
			(xy 176.82558 -336.310221) (xy 176.748537 -336.275037) (xy 176.675187 -336.232688) (xy 176.606195 -336.183559)
			(xy 176.542185 -336.128094) (xy 176.483737 -336.066796) (xy 176.431381 -336.00022) (xy 176.385591 -335.928968)
			(xy 176.34678 -335.853687) (xy 176.315301 -335.775057) (xy 176.29144 -335.69379) (xy 176.275411 -335.610624)
			(xy 176.26736 -335.52631) (xy 171.85402 -335.52631) (xy 171.846575 -335.604274) (xy 171.830546 -335.68744)
			(xy 171.806685 -335.768707) (xy 171.775206 -335.847337) (xy 171.736395 -335.922618) (xy 171.690605 -335.99387)
			(xy 171.638249 -336.060446) (xy 171.579801 -336.121744) (xy 171.515791 -336.177209) (xy 171.446799 -336.226338)
			(xy 171.373449 -336.268687) (xy 171.296406 -336.303871) (xy 171.216367 -336.331573) (xy 171.134058 -336.351541)
			(xy 171.050223 -336.363594) (xy 170.965622 -336.367625) (xy 170.881021 -336.363594) (xy 170.797186 -336.351541)
			(xy 170.714877 -336.331573) (xy 170.634838 -336.303871) (xy 170.557795 -336.268687) (xy 170.484445 -336.226338)
			(xy 170.415453 -336.177209) (xy 170.351443 -336.121744) (xy 170.292995 -336.060446) (xy 170.240639 -335.99387)
			(xy 170.194849 -335.922618) (xy 170.156038 -335.847337) (xy 170.124559 -335.768707) (xy 170.100698 -335.68744)
			(xy 170.084669 -335.604274) (xy 170.076618 -335.51996) (xy 165.926233 -335.51996) (xy 166.074755 -337.477608)
			(xy 170.050211 -337.477608) (xy 170.054233 -337.391888) (xy 170.066264 -337.30692) (xy 170.0862 -337.223453)
			(xy 170.113863 -337.142219) (xy 170.149012 -337.063933) (xy 170.191338 -336.989282) (xy 170.240467 -336.918923)
			(xy 170.29597 -336.853473) (xy 170.357357 -336.793509) (xy 170.42409 -336.739556) (xy 170.495582 -336.692089)
			(xy 170.571204 -336.651525) (xy 170.650293 -336.618221) (xy 170.732153 -336.592469) (xy 170.816064 -336.574496)
			(xy 170.90129 -336.56446) (xy 170.987082 -336.562448) (xy 171.072684 -336.568479) (xy 171.157346 -336.582499)
			(xy 171.240323 -336.604385) (xy 171.320886 -336.633946) (xy 171.398326 -336.67092) (xy 171.471965 -336.714984)
			(xy 171.541153 -336.76575) (xy 171.605284 -336.822771) (xy 171.663793 -336.885547) (xy 171.716166 -336.953527)
			(xy 171.761944 -337.026112) (xy 171.800724 -337.102664) (xy 171.832165 -337.182512) (xy 171.855991 -337.264953)
			(xy 171.871992 -337.349263) (xy 171.880027 -337.434701) (xy 171.88053 -337.477608) (xy 171.880456 -337.483958)
			(xy 176.240953 -337.483958) (xy 176.244975 -337.398238) (xy 176.257006 -337.31327) (xy 176.276942 -337.229803)
			(xy 176.304605 -337.148569) (xy 176.339754 -337.070283) (xy 176.38208 -336.995632) (xy 176.431209 -336.925273)
			(xy 176.486712 -336.859823) (xy 176.548099 -336.799859) (xy 176.614832 -336.745906) (xy 176.686324 -336.698439)
			(xy 176.761946 -336.657875) (xy 176.841035 -336.624571) (xy 176.922895 -336.598819) (xy 177.006806 -336.580846)
			(xy 177.092032 -336.57081) (xy 177.177824 -336.568798) (xy 177.263426 -336.574829) (xy 177.348088 -336.588849)
			(xy 177.431065 -336.610735) (xy 177.511628 -336.640296) (xy 177.589068 -336.67727) (xy 177.662707 -336.721334)
			(xy 177.731895 -336.7721) (xy 177.796026 -336.829121) (xy 177.854535 -336.891897) (xy 177.906908 -336.959877)
			(xy 177.952686 -337.032462) (xy 177.991466 -337.109014) (xy 178.022907 -337.188862) (xy 178.046733 -337.271303)
			(xy 178.062734 -337.355613) (xy 178.070769 -337.441051) (xy 178.071272 -337.483958) (xy 182.439056 -337.483958)
			(xy 182.439544 -337.441682) (xy 182.447346 -337.35749) (xy 182.462882 -337.274377) (xy 182.486021 -337.193053)
			(xy 182.516565 -337.11421) (xy 182.554253 -337.038522) (xy 182.598764 -336.966634) (xy 182.649718 -336.89916)
			(xy 182.706681 -336.836675) (xy 182.769166 -336.779712) (xy 182.83664 -336.728758) (xy 182.908528 -336.684247)
			(xy 182.984216 -336.646559) (xy 183.063059 -336.616015) (xy 183.144383 -336.592876) (xy 183.227496 -336.57734)
			(xy 183.311688 -336.569538) (xy 183.39624 -336.569538) (xy 183.480432 -336.57734) (xy 183.563545 -336.592876)
			(xy 183.644869 -336.616015) (xy 183.723712 -336.646559) (xy 183.7994 -336.684247) (xy 183.871288 -336.728758)
			(xy 183.938762 -336.779712) (xy 184.001247 -336.836675) (xy 184.05821 -336.89916) (xy 184.109164 -336.966634)
			(xy 184.153675 -337.038522) (xy 184.191363 -337.11421) (xy 184.221907 -337.193053) (xy 184.245046 -337.274377)
			(xy 184.260582 -337.35749) (xy 184.268384 -337.441682) (xy 184.268872 -337.483958) (xy 184.268338 -337.527902)
			(xy 184.259914 -337.615385) (xy 184.243138 -337.701657) (xy 184.218167 -337.785923) (xy 184.185229 -337.867405)
			(xy 184.144629 -337.945353) (xy 184.096741 -338.019048) (xy 184.042007 -338.087812) (xy 183.98093 -338.151009)
			(xy 183.914074 -338.208057) (xy 183.842055 -338.258431) (xy 183.804052 -338.280502) (xy 183.792022 -338.28775)
			(xy 183.772209 -338.307642) (xy 183.758568 -338.332181) (xy 183.752134 -338.35951) (xy 183.753394 -338.387557)
			(xy 183.762252 -338.414199) (xy 183.778037 -338.437416) (xy 183.799554 -338.455452) (xy 183.81218 -338.461604)
			(xy 183.839112 -338.474322) (xy 183.889 -338.506852) (xy 183.911494 -338.526374) (xy 183.922936 -338.536019)
			(xy 183.949979 -338.548799) (xy 183.979566 -338.553185) (xy 184.009153 -338.548799) (xy 184.036196 -338.536019)
			(xy 184.047638 -338.526374) (xy 184.068792 -338.507958) (xy 184.115469 -338.476864) (xy 184.166199 -338.452947)
			(xy 184.219887 -338.436726) (xy 184.275373 -338.428551) (xy 184.303416 -338.428076) (xy 184.330787 -338.428514)
			(xy 184.384968 -338.436336) (xy 184.437473 -338.45183) (xy 184.487219 -338.474679) (xy 184.533184 -338.504411)
			(xy 184.554114 -338.522056) (xy 184.565442 -338.531292) (xy 184.591999 -338.543468) (xy 184.620916 -338.547641)
			(xy 184.649833 -338.543468) (xy 184.67639 -338.531292) (xy 184.687718 -338.522056) (xy 184.708664 -338.504435)
			(xy 184.754634 -338.474722) (xy 184.804378 -338.451883) (xy 184.856875 -338.436387) (xy 184.911048 -338.428553)
			(xy 184.938416 -338.428076) (xy 184.965667 -338.428563) (xy 185.019614 -338.436321) (xy 185.071908 -338.451677)
			(xy 185.121484 -338.474319) (xy 185.167333 -338.503786) (xy 185.208523 -338.539477) (xy 185.244214 -338.580667)
			(xy 185.273681 -338.626516) (xy 185.296323 -338.676092) (xy 185.311679 -338.728386) (xy 185.319437 -338.782333)
			(xy 185.319924 -338.809584) (xy 185.319467 -338.836955) (xy 185.31165 -338.891135) (xy 185.29616 -338.943639)
			(xy 185.273315 -338.993386) (xy 185.243587 -339.039351) (xy 185.225944 -339.060282) (xy 185.216727 -339.071623)
			(xy 185.204555 -339.098177) (xy 185.200381 -339.127088) (xy 185.204548 -339.156) (xy 185.216714 -339.182557)
			(xy 185.225944 -339.193886) (xy 185.24357 -339.214831) (xy 185.273298 -339.260796) (xy 185.296146 -339.31054)
			(xy 185.311645 -339.36304) (xy 185.319475 -339.417218) (xy 185.319477 -339.471958) (xy 185.31165 -339.526136)
			(xy 185.296154 -339.578637) (xy 185.273309 -339.628383) (xy 185.243585 -339.67435) (xy 185.225944 -339.695282)
			(xy 185.216727 -339.706623) (xy 185.204555 -339.733177) (xy 185.200381 -339.762088) (xy 185.204548 -339.791)
			(xy 185.216714 -339.817557) (xy 185.225944 -339.828886) (xy 185.24357 -339.849831) (xy 185.273298 -339.895796)
			(xy 185.296146 -339.94554) (xy 185.311645 -339.99804) (xy 185.319475 -340.052218) (xy 185.319477 -340.106958)
			(xy 185.31165 -340.161136) (xy 185.296154 -340.213637) (xy 185.273309 -340.263383) (xy 185.243585 -340.30935)
			(xy 185.225944 -340.330282) (xy 185.216727 -340.341623) (xy 185.204555 -340.368177) (xy 185.200381 -340.397088)
			(xy 185.204548 -340.426) (xy 185.216714 -340.452557) (xy 185.225944 -340.463886) (xy 185.24357 -340.484831)
			(xy 185.273298 -340.530796) (xy 185.296146 -340.58054) (xy 185.311645 -340.63304) (xy 185.319475 -340.687218)
			(xy 185.319477 -340.741958) (xy 185.31165 -340.796136) (xy 185.296154 -340.848637) (xy 185.273309 -340.898383)
			(xy 185.243585 -340.94435) (xy 185.225944 -340.965282) (xy 185.216727 -340.976623) (xy 185.204555 -341.003177)
			(xy 185.200381 -341.032088) (xy 185.204548 -341.061) (xy 185.216714 -341.087557) (xy 185.225944 -341.098886)
			(xy 185.24357 -341.119831) (xy 185.273298 -341.165796) (xy 185.296146 -341.21554) (xy 185.311645 -341.26804)
			(xy 185.319475 -341.322218) (xy 185.319477 -341.376958) (xy 185.31165 -341.431136) (xy 185.296154 -341.483637)
			(xy 185.273309 -341.533383) (xy 185.243585 -341.57935) (xy 185.225944 -341.600282) (xy 185.216727 -341.611623)
			(xy 185.204555 -341.638177) (xy 185.200381 -341.667088) (xy 185.204548 -341.696) (xy 185.216714 -341.722557)
			(xy 185.225944 -341.733886) (xy 185.24357 -341.754831) (xy 185.273298 -341.800796) (xy 185.296146 -341.85054)
			(xy 185.311645 -341.90304) (xy 185.319475 -341.957218) (xy 185.319477 -342.011958) (xy 185.31165 -342.066136)
			(xy 185.296154 -342.118637) (xy 185.273309 -342.168383) (xy 185.243585 -342.21435) (xy 185.225944 -342.235282)
			(xy 185.216727 -342.246623) (xy 185.204555 -342.273177) (xy 185.200381 -342.302088) (xy 185.204548 -342.331)
			(xy 185.216714 -342.357557) (xy 185.225944 -342.368886) (xy 185.243597 -342.389807) (xy 185.273306 -342.435783)
			(xy 185.296138 -342.485534) (xy 185.311626 -342.538037) (xy 185.319452 -342.592214) (xy 185.319924 -342.619584)
			(xy 185.319407 -342.646834) (xy 185.311653 -342.70078) (xy 185.296301 -342.753073) (xy 185.273663 -342.802649)
			(xy 185.2442 -342.848499) (xy 185.208511 -342.889689) (xy 185.167324 -342.92538) (xy 185.121477 -342.954847)
			(xy 185.071903 -342.97749) (xy 185.019611 -342.992846) (xy 184.965666 -343.000605) (xy 184.938416 -343.001092)
			(xy 184.911046 -343.000619) (xy 184.856867 -342.992803) (xy 184.804364 -342.977316) (xy 184.754617 -342.954475)
			(xy 184.70865 -342.924752) (xy 184.687718 -342.907112) (xy 184.67639 -342.897876) (xy 184.649833 -342.8857)
			(xy 184.620916 -342.881527) (xy 184.591999 -342.8857) (xy 184.565442 -342.897876) (xy 184.554114 -342.907112)
			(xy 184.533189 -342.92476) (xy 184.487214 -342.95447) (xy 184.437465 -342.977304) (xy 184.384963 -342.992793)
			(xy 184.330786 -343.000619) (xy 184.303416 -343.001092) (xy 184.275376 -343.000597) (xy 184.219898 -342.992398)
			(xy 184.166215 -342.976172) (xy 184.115483 -342.952271) (xy 184.068792 -342.921207) (xy 184.047638 -342.902794)
			(xy 184.036196 -342.893149) (xy 184.009153 -342.880369) (xy 183.979566 -342.875983) (xy 183.949979 -342.880369)
			(xy 183.922936 -342.893149) (xy 183.911494 -342.902794) (xy 183.890362 -342.921237) (xy 183.84368 -342.952329)
			(xy 183.792944 -342.97624) (xy 183.739251 -342.992455) (xy 183.683761 -343.000622) (xy 183.655716 -343.001092)
			(xy 183.628463 -343.00063) (xy 183.574511 -342.992875) (xy 183.522212 -342.97752) (xy 183.472631 -342.954878)
			(xy 183.426777 -342.92541) (xy 183.385584 -342.889716) (xy 183.34989 -342.848523) (xy 183.320422 -342.802669)
			(xy 183.29778 -342.753088) (xy 183.282425 -342.700789) (xy 183.27467 -342.646837) (xy 183.274208 -342.619584)
			(xy 183.274663 -342.592213) (xy 183.282483 -342.538034) (xy 183.297975 -342.48553) (xy 183.320819 -342.435784)
			(xy 183.350546 -342.389817) (xy 183.368188 -342.368886) (xy 183.377441 -342.357571) (xy 183.389618 -342.331009)
			(xy 183.393788 -342.302088) (xy 183.389611 -342.273168) (xy 183.377428 -342.246609) (xy 183.368188 -342.235282)
			(xy 183.350533 -342.214361) (xy 183.320812 -342.16839) (xy 183.29797 -342.118642) (xy 183.282477 -342.066138)
			(xy 183.27465 -342.011959) (xy 183.274652 -341.957217) (xy 183.282482 -341.903038) (xy 183.297979 -341.850535)
			(xy 183.320824 -341.800788) (xy 183.350548 -341.75482) (xy 183.368188 -341.733886) (xy 183.377441 -341.722571)
			(xy 183.389618 -341.696009) (xy 183.393788 -341.667088) (xy 183.389611 -341.638168) (xy 183.377428 -341.611609)
			(xy 183.368188 -341.600282) (xy 183.350533 -341.579361) (xy 183.320812 -341.53339) (xy 183.29797 -341.483642)
			(xy 183.282477 -341.431138) (xy 183.27465 -341.376959) (xy 183.274652 -341.322217) (xy 183.282482 -341.268038)
			(xy 183.297979 -341.215535) (xy 183.320824 -341.165788) (xy 183.350548 -341.11982) (xy 183.368188 -341.098886)
			(xy 183.377441 -341.087571) (xy 183.389618 -341.061009) (xy 183.393788 -341.032088) (xy 183.389611 -341.003168)
			(xy 183.377428 -340.976609) (xy 183.368188 -340.965282) (xy 183.350533 -340.944361) (xy 183.320812 -340.89839)
			(xy 183.29797 -340.848642) (xy 183.282477 -340.796138) (xy 183.27465 -340.741959) (xy 183.274652 -340.687217)
			(xy 183.282482 -340.633038) (xy 183.297979 -340.580535) (xy 183.320824 -340.530788) (xy 183.350548 -340.48482)
			(xy 183.368188 -340.463886) (xy 183.377441 -340.452571) (xy 183.389618 -340.426009) (xy 183.393788 -340.397088)
			(xy 183.389611 -340.368168) (xy 183.377428 -340.341609) (xy 183.368188 -340.330282) (xy 183.350533 -340.309361)
			(xy 183.320812 -340.26339) (xy 183.29797 -340.213642) (xy 183.282477 -340.161138) (xy 183.27465 -340.106959)
			(xy 183.274652 -340.052217) (xy 183.282482 -339.998038) (xy 183.297979 -339.945535) (xy 183.320824 -339.895788)
			(xy 183.350548 -339.84982) (xy 183.368188 -339.828886) (xy 183.377441 -339.817571) (xy 183.389618 -339.791009)
			(xy 183.393788 -339.762088) (xy 183.389611 -339.733168) (xy 183.377428 -339.706609) (xy 183.368188 -339.695282)
			(xy 183.350533 -339.674361) (xy 183.320812 -339.62839) (xy 183.29797 -339.578642) (xy 183.282477 -339.526138)
			(xy 183.27465 -339.471959) (xy 183.274652 -339.417217) (xy 183.282482 -339.363038) (xy 183.297979 -339.310535)
			(xy 183.320824 -339.260788) (xy 183.350548 -339.21482) (xy 183.368188 -339.193886) (xy 183.377441 -339.182571)
			(xy 183.389618 -339.156009) (xy 183.393788 -339.127088) (xy 183.389611 -339.098168) (xy 183.377428 -339.071609)
			(xy 183.368188 -339.060282) (xy 183.350572 -339.039331) (xy 183.320857 -338.993363) (xy 183.298017 -338.943621)
			(xy 183.28252 -338.891124) (xy 183.274686 -338.836952) (xy 183.274208 -338.809584) (xy 183.274668 -338.782851)
			(xy 183.282177 -338.729914) (xy 183.296991 -338.67854) (xy 183.318821 -338.629732) (xy 183.347239 -338.584443)
			(xy 183.364124 -338.563712) (xy 183.372832 -338.552699) (xy 183.384366 -338.527111) (xy 183.388505 -338.499351)
			(xy 183.384937 -338.471511) (xy 183.373932 -338.445692) (xy 183.356318 -338.423839) (xy 183.333425 -338.407602)
			(xy 183.306978 -338.398203) (xy 183.293004 -338.396834) (xy 183.250113 -338.393549) (xy 183.165193 -338.379781)
			(xy 183.081941 -338.358103) (xy 183.001091 -338.328705) (xy 182.923357 -338.291848) (xy 182.849427 -338.247857)
			(xy 182.779952 -338.19712) (xy 182.715547 -338.140086) (xy 182.65678 -338.077258) (xy 182.604169 -338.009191)
			(xy 182.558181 -337.936486) (xy 182.51922 -337.859785) (xy 182.487632 -337.779766) (xy 182.463694 -337.697135)
			(xy 182.447618 -337.612622) (xy 182.439547 -337.526972) (xy 182.439056 -337.483958) (xy 178.071272 -337.483958)
			(xy 178.070769 -337.526865) (xy 178.062734 -337.612303) (xy 178.046733 -337.696613) (xy 178.022907 -337.779054)
			(xy 177.991466 -337.858902) (xy 177.952686 -337.935454) (xy 177.906908 -338.008039) (xy 177.854535 -338.076019)
			(xy 177.796026 -338.138795) (xy 177.731895 -338.195816) (xy 177.662707 -338.246582) (xy 177.589068 -338.290646)
			(xy 177.511628 -338.32762) (xy 177.431065 -338.357181) (xy 177.348088 -338.379067) (xy 177.263426 -338.393087)
			(xy 177.177824 -338.399118) (xy 177.092032 -338.397106) (xy 177.006806 -338.38707) (xy 176.922895 -338.369097)
			(xy 176.841035 -338.343345) (xy 176.761946 -338.310041) (xy 176.686324 -338.269477) (xy 176.614832 -338.22201)
			(xy 176.548099 -338.168057) (xy 176.486712 -338.108093) (xy 176.431209 -338.042643) (xy 176.38208 -337.972284)
			(xy 176.339754 -337.897633) (xy 176.304605 -337.819347) (xy 176.276942 -337.738113) (xy 176.257006 -337.654646)
			(xy 176.244975 -337.569678) (xy 176.240953 -337.483958) (xy 171.880456 -337.483958) (xy 171.880027 -337.520515)
			(xy 171.871992 -337.605953) (xy 171.855991 -337.690263) (xy 171.832165 -337.772704) (xy 171.800724 -337.852552)
			(xy 171.761944 -337.929104) (xy 171.716166 -338.001689) (xy 171.663793 -338.069669) (xy 171.605284 -338.132445)
			(xy 171.541153 -338.189466) (xy 171.471965 -338.240232) (xy 171.398326 -338.284296) (xy 171.320886 -338.32127)
			(xy 171.240323 -338.350831) (xy 171.157346 -338.372717) (xy 171.072684 -338.386737) (xy 170.987082 -338.392768)
			(xy 170.90129 -338.390756) (xy 170.816064 -338.38072) (xy 170.732153 -338.362747) (xy 170.650293 -338.336995)
			(xy 170.571204 -338.303691) (xy 170.495582 -338.263127) (xy 170.42409 -338.21566) (xy 170.357357 -338.161707)
			(xy 170.29597 -338.101743) (xy 170.240467 -338.036293) (xy 170.191338 -337.965934) (xy 170.149012 -337.891283)
			(xy 170.113863 -337.812997) (xy 170.0862 -337.731763) (xy 170.066264 -337.648296) (xy 170.054233 -337.563328)
			(xy 170.050211 -337.477608) (xy 166.074755 -337.477608) (xy 166.464863 -342.619584) (xy 168.52519 -342.619584)
			(xy 168.525649 -342.592214) (xy 168.533469 -342.538034) (xy 168.54896 -342.485531) (xy 168.571803 -342.435784)
			(xy 168.601528 -342.389818) (xy 168.61917 -342.368886) (xy 168.628425 -342.357571) (xy 168.640604 -342.33101)
			(xy 168.644775 -342.302088) (xy 168.640597 -342.273167) (xy 168.628412 -342.246608) (xy 168.61917 -342.235282)
			(xy 168.601512 -342.214363) (xy 168.571784 -342.168394) (xy 168.548937 -342.118645) (xy 168.53344 -342.066141)
			(xy 168.525612 -342.01196) (xy 168.525614 -341.957216) (xy 168.533446 -341.903035) (xy 168.548946 -341.850532)
			(xy 168.571796 -341.800785) (xy 168.601526 -341.754818) (xy 168.61917 -341.733886) (xy 168.628425 -341.722571)
			(xy 168.640604 -341.69601) (xy 168.644775 -341.667088) (xy 168.640597 -341.638167) (xy 168.628412 -341.611608)
			(xy 168.61917 -341.600282) (xy 168.601512 -341.579363) (xy 168.571784 -341.533394) (xy 168.548937 -341.483645)
			(xy 168.53344 -341.431141) (xy 168.525612 -341.37696) (xy 168.525614 -341.322216) (xy 168.533446 -341.268035)
			(xy 168.548946 -341.215532) (xy 168.571796 -341.165785) (xy 168.601526 -341.119818) (xy 168.61917 -341.098886)
			(xy 168.628425 -341.087571) (xy 168.640604 -341.06101) (xy 168.644775 -341.032088) (xy 168.640597 -341.003167)
			(xy 168.628412 -340.976608) (xy 168.61917 -340.965282) (xy 168.601512 -340.944363) (xy 168.571784 -340.898394)
			(xy 168.548937 -340.848645) (xy 168.53344 -340.796141) (xy 168.525612 -340.74196) (xy 168.525614 -340.687216)
			(xy 168.533446 -340.633035) (xy 168.548946 -340.580532) (xy 168.571796 -340.530785) (xy 168.601526 -340.484818)
			(xy 168.61917 -340.463886) (xy 168.628425 -340.452571) (xy 168.640604 -340.42601) (xy 168.644775 -340.397088)
			(xy 168.640597 -340.368167) (xy 168.628412 -340.341608) (xy 168.61917 -340.330282) (xy 168.601512 -340.309363)
			(xy 168.571784 -340.263394) (xy 168.548937 -340.213645) (xy 168.53344 -340.161141) (xy 168.525612 -340.10696)
			(xy 168.525614 -340.052216) (xy 168.533446 -339.998035) (xy 168.548946 -339.945532) (xy 168.571796 -339.895785)
			(xy 168.601526 -339.849818) (xy 168.61917 -339.828886) (xy 168.628425 -339.817571) (xy 168.640604 -339.79101)
			(xy 168.644775 -339.762088) (xy 168.640597 -339.733167) (xy 168.628412 -339.706608) (xy 168.61917 -339.695282)
			(xy 168.601512 -339.674363) (xy 168.571784 -339.628394) (xy 168.548937 -339.578645) (xy 168.53344 -339.526141)
			(xy 168.525612 -339.47196) (xy 168.525614 -339.417216) (xy 168.533446 -339.363035) (xy 168.548946 -339.310532)
			(xy 168.571796 -339.260785) (xy 168.601526 -339.214818) (xy 168.61917 -339.193886) (xy 168.628425 -339.182571)
			(xy 168.640604 -339.15601) (xy 168.644775 -339.127088) (xy 168.640597 -339.098167) (xy 168.628412 -339.071608)
			(xy 168.61917 -339.060282) (xy 168.601551 -339.039334) (xy 168.571837 -338.993365) (xy 168.548998 -338.943621)
			(xy 168.533502 -338.891125) (xy 168.525668 -338.836952) (xy 168.52519 -338.809584) (xy 168.525663 -338.782332)
			(xy 168.533422 -338.728384) (xy 168.548779 -338.676089) (xy 168.571421 -338.626512) (xy 168.600889 -338.580662)
			(xy 168.636582 -338.539472) (xy 168.677773 -338.503781) (xy 168.723625 -338.474315) (xy 168.773203 -338.451674)
			(xy 168.825498 -338.436319) (xy 168.879446 -338.428562) (xy 168.906698 -338.428076) (xy 168.934069 -338.428525)
			(xy 168.98825 -338.436344) (xy 169.040754 -338.451836) (xy 169.0905 -338.474682) (xy 169.136466 -338.504412)
			(xy 169.157396 -338.522056) (xy 169.168724 -338.531292) (xy 169.195281 -338.543468) (xy 169.224198 -338.547641)
			(xy 169.253115 -338.543468) (xy 169.279672 -338.531292) (xy 169.291 -338.522056) (xy 169.311915 -338.504396)
			(xy 169.357893 -338.474689) (xy 169.407645 -338.451858) (xy 169.460149 -338.436371) (xy 169.514328 -338.428547)
			(xy 169.541698 -338.428076) (xy 169.569738 -338.428571) (xy 169.625216 -338.436772) (xy 169.678898 -338.452997)
			(xy 169.72963 -338.476899) (xy 169.776322 -338.507962) (xy 169.797476 -338.526374) (xy 169.808918 -338.536019)
			(xy 169.835961 -338.548799) (xy 169.865548 -338.553185) (xy 169.895135 -338.548799) (xy 169.922178 -338.536019)
			(xy 169.93362 -338.526374) (xy 169.954781 -338.507967) (xy 170.001456 -338.476871) (xy 170.052184 -338.452953)
			(xy 170.105871 -338.43673) (xy 170.161356 -338.428552) (xy 170.189398 -338.428076) (xy 170.216648 -338.42858)
			(xy 170.270595 -338.436335) (xy 170.322888 -338.451689) (xy 170.372464 -338.474329) (xy 170.418314 -338.503794)
			(xy 170.459504 -338.539483) (xy 170.495195 -338.580672) (xy 170.524662 -338.62652) (xy 170.547304 -338.676095)
			(xy 170.562661 -338.728388) (xy 170.570419 -338.782334) (xy 170.570906 -338.809584) (xy 170.570429 -338.836954)
			(xy 170.562614 -338.891132) (xy 170.547127 -338.943635) (xy 170.524288 -338.993382) (xy 170.494566 -339.03935)
			(xy 170.476926 -339.060282) (xy 170.467702 -339.07162) (xy 170.45552 -339.098173) (xy 170.451343 -339.127088)
			(xy 170.455513 -339.156003) (xy 170.467689 -339.18256) (xy 170.476926 -339.193886) (xy 170.494553 -339.214831)
			(xy 170.524282 -339.260795) (xy 170.547131 -339.310539) (xy 170.562631 -339.36304) (xy 170.570462 -339.417218)
			(xy 170.570464 -339.471958) (xy 170.562636 -339.526137) (xy 170.54714 -339.578638) (xy 170.524294 -339.628384)
			(xy 170.494568 -339.67435) (xy 170.476926 -339.695282) (xy 170.467702 -339.70662) (xy 170.45552 -339.733173)
			(xy 170.451343 -339.762088) (xy 170.455513 -339.791003) (xy 170.467689 -339.81756) (xy 170.476926 -339.828886)
			(xy 170.494553 -339.849831) (xy 170.524282 -339.895795) (xy 170.547131 -339.945539) (xy 170.562631 -339.99804)
			(xy 170.570462 -340.052218) (xy 170.570464 -340.106958) (xy 170.562636 -340.161137) (xy 170.54714 -340.213638)
			(xy 170.524294 -340.263384) (xy 170.494568 -340.30935) (xy 170.476926 -340.330282) (xy 170.467702 -340.34162)
			(xy 170.45552 -340.368173) (xy 170.451343 -340.397088) (xy 170.455513 -340.426003) (xy 170.467689 -340.45256)
			(xy 170.476926 -340.463886) (xy 170.494553 -340.484831) (xy 170.524282 -340.530795) (xy 170.547131 -340.580539)
			(xy 170.562631 -340.63304) (xy 170.570462 -340.687218) (xy 170.570464 -340.741958) (xy 170.562636 -340.796137)
			(xy 170.54714 -340.848638) (xy 170.524294 -340.898384) (xy 170.494568 -340.94435) (xy 170.476926 -340.965282)
			(xy 170.467702 -340.97662) (xy 170.45552 -341.003173) (xy 170.451343 -341.032088) (xy 170.455513 -341.061003)
			(xy 170.467689 -341.08756) (xy 170.476926 -341.098886) (xy 170.494553 -341.119831) (xy 170.524282 -341.165795)
			(xy 170.547131 -341.215539) (xy 170.562631 -341.26804) (xy 170.570462 -341.322218) (xy 170.570464 -341.376958)
			(xy 170.562636 -341.431137) (xy 170.54714 -341.483638) (xy 170.524294 -341.533384) (xy 170.494568 -341.57935)
			(xy 170.476926 -341.600282) (xy 170.467702 -341.61162) (xy 170.45552 -341.638173) (xy 170.451343 -341.667088)
			(xy 170.455513 -341.696003) (xy 170.467689 -341.72256) (xy 170.476926 -341.733886) (xy 170.494553 -341.754831)
			(xy 170.524282 -341.800795) (xy 170.547131 -341.850539) (xy 170.562631 -341.90304) (xy 170.570462 -341.957218)
			(xy 170.570464 -342.011958) (xy 170.562636 -342.066137) (xy 170.54714 -342.118638) (xy 170.524294 -342.168384)
			(xy 170.494568 -342.21435) (xy 170.476926 -342.235282) (xy 170.467702 -342.24662) (xy 170.45552 -342.273173)
			(xy 170.451343 -342.302088) (xy 170.455513 -342.331003) (xy 170.467689 -342.35756) (xy 170.476926 -342.368886)
			(xy 170.494576 -342.389809) (xy 170.524285 -342.435785) (xy 170.547119 -342.485535) (xy 170.562607 -342.538037)
			(xy 170.570433 -342.592214) (xy 170.570906 -342.619584) (xy 173.495462 -342.619584) (xy 173.495904 -342.592213)
			(xy 173.503725 -342.538032) (xy 173.519219 -342.485528) (xy 173.542067 -342.435781) (xy 173.571797 -342.389816)
			(xy 173.589442 -342.368886) (xy 173.598691 -342.357569) (xy 173.610861 -342.331007) (xy 173.615029 -342.302088)
			(xy 173.610854 -342.27317) (xy 173.598678 -342.246611) (xy 173.589442 -342.235282) (xy 173.571785 -342.214362)
			(xy 173.54206 -342.168393) (xy 173.519214 -342.118644) (xy 173.503719 -342.06614) (xy 173.495891 -342.011959)
			(xy 173.495893 -341.957216) (xy 173.503724 -341.903036) (xy 173.519223 -341.850533) (xy 173.542071 -341.800786)
			(xy 173.5718 -341.754818) (xy 173.589442 -341.733886) (xy 173.598691 -341.722569) (xy 173.610861 -341.696007)
			(xy 173.615029 -341.667088) (xy 173.610854 -341.63817) (xy 173.598678 -341.611611) (xy 173.589442 -341.600282)
			(xy 173.571785 -341.579362) (xy 173.54206 -341.533393) (xy 173.519214 -341.483644) (xy 173.503719 -341.43114)
			(xy 173.495891 -341.376959) (xy 173.495893 -341.322216) (xy 173.503724 -341.268036) (xy 173.519223 -341.215533)
			(xy 173.542071 -341.165786) (xy 173.5718 -341.119818) (xy 173.589442 -341.098886) (xy 173.598691 -341.087569)
			(xy 173.610861 -341.061007) (xy 173.615029 -341.032088) (xy 173.610854 -341.00317) (xy 173.598678 -340.976611)
			(xy 173.589442 -340.965282) (xy 173.571785 -340.944362) (xy 173.54206 -340.898393) (xy 173.519214 -340.848644)
			(xy 173.503719 -340.79614) (xy 173.495891 -340.741959) (xy 173.495893 -340.687216) (xy 173.503724 -340.633036)
			(xy 173.519223 -340.580533) (xy 173.542071 -340.530786) (xy 173.5718 -340.484818) (xy 173.589442 -340.463886)
			(xy 173.598691 -340.452569) (xy 173.610861 -340.426007) (xy 173.615029 -340.397088) (xy 173.610854 -340.36817)
			(xy 173.598678 -340.341611) (xy 173.589442 -340.330282) (xy 173.571785 -340.309362) (xy 173.54206 -340.263393)
			(xy 173.519214 -340.213644) (xy 173.503719 -340.16114) (xy 173.495891 -340.106959) (xy 173.495893 -340.052216)
			(xy 173.503724 -339.998036) (xy 173.519223 -339.945533) (xy 173.542071 -339.895786) (xy 173.5718 -339.849818)
			(xy 173.589442 -339.828886) (xy 173.598691 -339.817569) (xy 173.610861 -339.791007) (xy 173.615029 -339.762088)
			(xy 173.610854 -339.73317) (xy 173.598678 -339.706611) (xy 173.589442 -339.695282) (xy 173.571785 -339.674362)
			(xy 173.54206 -339.628393) (xy 173.519214 -339.578644) (xy 173.503719 -339.52614) (xy 173.495891 -339.471959)
			(xy 173.495893 -339.417216) (xy 173.503724 -339.363036) (xy 173.519223 -339.310533) (xy 173.542071 -339.260786)
			(xy 173.5718 -339.214818) (xy 173.589442 -339.193886) (xy 173.598691 -339.182569) (xy 173.610861 -339.156007)
			(xy 173.615029 -339.127088) (xy 173.610854 -339.09817) (xy 173.598678 -339.071611) (xy 173.589442 -339.060282)
			(xy 173.571834 -339.039324) (xy 173.542116 -338.993359) (xy 173.519274 -338.943618) (xy 173.503775 -338.891123)
			(xy 173.49594 -338.836952) (xy 173.495462 -338.809584) (xy 173.495963 -338.782334) (xy 173.503721 -338.728388)
			(xy 173.519076 -338.676095) (xy 173.541717 -338.62652) (xy 173.571182 -338.580671) (xy 173.606872 -338.539482)
			(xy 173.64806 -338.503791) (xy 173.693908 -338.474324) (xy 173.743482 -338.451681) (xy 173.795774 -338.436324)
			(xy 173.84972 -338.428564) (xy 173.87697 -338.428076) (xy 173.90501 -338.428587) (xy 173.960487 -338.436784)
			(xy 174.014169 -338.453006) (xy 174.064901 -338.476904) (xy 174.111593 -338.507964) (xy 174.132748 -338.526374)
			(xy 174.14419 -338.536019) (xy 174.171233 -338.548799) (xy 174.20082 -338.553185) (xy 174.230407 -338.548799)
			(xy 174.25745 -338.536019) (xy 174.268892 -338.526374) (xy 174.290025 -338.507932) (xy 174.336707 -338.476842)
			(xy 174.387443 -338.45293) (xy 174.441136 -338.436715) (xy 174.496626 -338.428547) (xy 174.52467 -338.428076)
			(xy 174.55204 -338.428541) (xy 174.60622 -338.436356) (xy 174.658724 -338.451845) (xy 174.708471 -338.474687)
			(xy 174.754437 -338.504413) (xy 174.775368 -338.522056) (xy 174.786696 -338.531292) (xy 174.813253 -338.543468)
			(xy 174.84217 -338.547641) (xy 174.871087 -338.543468) (xy 174.897644 -338.531292) (xy 174.908972 -338.522056)
			(xy 174.929898 -338.504409) (xy 174.975873 -338.4747) (xy 175.025622 -338.451866) (xy 175.078124 -338.436377)
			(xy 175.132301 -338.428549) (xy 175.15967 -338.428076) (xy 175.186921 -338.428583) (xy 175.24087 -338.436336)
			(xy 175.293166 -338.451687) (xy 175.342745 -338.474325) (xy 175.388597 -338.503788) (xy 175.42979 -338.539477)
			(xy 175.465484 -338.580666) (xy 175.494953 -338.626515) (xy 175.517597 -338.676091) (xy 175.532955 -338.728385)
			(xy 175.540714 -338.782333) (xy 175.541178 -338.809584) (xy 175.540708 -338.836954) (xy 175.532892 -338.891133)
			(xy 175.517404 -338.943637) (xy 175.494563 -338.993383) (xy 175.464839 -339.03935) (xy 175.447198 -339.060282)
			(xy 175.437977 -339.071621) (xy 175.425798 -339.098174) (xy 175.421622 -339.127088) (xy 175.425791 -339.156002)
			(xy 175.437964 -339.182559) (xy 175.447198 -339.193886) (xy 175.464822 -339.214832) (xy 175.494546 -339.260798)
			(xy 175.51739 -339.310542) (xy 175.532887 -339.363042) (xy 175.540716 -339.417218) (xy 175.540718 -339.471958)
			(xy 175.532892 -339.526134) (xy 175.517399 -339.578635) (xy 175.494557 -339.628381) (xy 175.464837 -339.674349)
			(xy 175.447198 -339.695282) (xy 175.437977 -339.706621) (xy 175.425798 -339.733174) (xy 175.421622 -339.762088)
			(xy 175.425791 -339.791002) (xy 175.437964 -339.817559) (xy 175.447198 -339.828886) (xy 175.464822 -339.849832)
			(xy 175.494546 -339.895798) (xy 175.51739 -339.945542) (xy 175.532887 -339.998042) (xy 175.540716 -340.052218)
			(xy 175.540718 -340.106958) (xy 175.532892 -340.161134) (xy 175.517399 -340.213635) (xy 175.494557 -340.263381)
			(xy 175.464837 -340.309349) (xy 175.447198 -340.330282) (xy 175.437977 -340.341621) (xy 175.425798 -340.368174)
			(xy 175.421622 -340.397088) (xy 175.425791 -340.426002) (xy 175.437964 -340.452559) (xy 175.447198 -340.463886)
			(xy 175.464822 -340.484832) (xy 175.494546 -340.530798) (xy 175.51739 -340.580542) (xy 175.532887 -340.633042)
			(xy 175.540716 -340.687218) (xy 175.540718 -340.741958) (xy 175.532892 -340.796134) (xy 175.517399 -340.848635)
			(xy 175.494557 -340.898381) (xy 175.464837 -340.944349) (xy 175.447198 -340.965282) (xy 175.437977 -340.976621)
			(xy 175.425798 -341.003174) (xy 175.421622 -341.032088) (xy 175.425791 -341.061002) (xy 175.437964 -341.087559)
			(xy 175.447198 -341.098886) (xy 175.464822 -341.119832) (xy 175.494546 -341.165798) (xy 175.51739 -341.215542)
			(xy 175.532887 -341.268042) (xy 175.540716 -341.322218) (xy 175.540718 -341.376958) (xy 175.532892 -341.431134)
			(xy 175.517399 -341.483635) (xy 175.494557 -341.533381) (xy 175.464837 -341.579349) (xy 175.447198 -341.600282)
			(xy 175.437977 -341.611621) (xy 175.425798 -341.638174) (xy 175.421622 -341.667088) (xy 175.425791 -341.696002)
			(xy 175.437964 -341.722559) (xy 175.447198 -341.733886) (xy 175.464822 -341.754832) (xy 175.494546 -341.800798)
			(xy 175.51739 -341.850542) (xy 175.532887 -341.903042) (xy 175.540716 -341.957218) (xy 175.540718 -342.011958)
			(xy 175.532892 -342.066134) (xy 175.517399 -342.118635) (xy 175.494557 -342.168381) (xy 175.464837 -342.214349)
			(xy 175.447198 -342.235282) (xy 175.437977 -342.246621) (xy 175.425798 -342.273174) (xy 175.421622 -342.302088)
			(xy 175.425791 -342.331002) (xy 175.437964 -342.357559) (xy 175.447198 -342.368886) (xy 175.464844 -342.389813)
			(xy 175.494555 -342.435787) (xy 175.517389 -342.485536) (xy 175.532879 -342.538038) (xy 175.540705 -342.592214)
			(xy 175.541178 -342.619584) (xy 178.20259 -342.619584) (xy 178.203049 -342.592214) (xy 178.210869 -342.538034)
			(xy 178.22636 -342.485531) (xy 178.249203 -342.435784) (xy 178.278928 -342.389818) (xy 178.29657 -342.368886)
			(xy 178.305825 -342.357571) (xy 178.318004 -342.33101) (xy 178.322175 -342.302088) (xy 178.317997 -342.273167)
			(xy 178.305812 -342.246608) (xy 178.29657 -342.235282) (xy 178.278912 -342.214363) (xy 178.249184 -342.168394)
			(xy 178.226337 -342.118645) (xy 178.21084 -342.066141) (xy 178.203012 -342.01196) (xy 178.203014 -341.957216)
			(xy 178.210846 -341.903035) (xy 178.226346 -341.850532) (xy 178.249196 -341.800785) (xy 178.278926 -341.754818)
			(xy 178.29657 -341.733886) (xy 178.305825 -341.722571) (xy 178.318004 -341.69601) (xy 178.322175 -341.667088)
			(xy 178.317997 -341.638167) (xy 178.305812 -341.611608) (xy 178.29657 -341.600282) (xy 178.278912 -341.579363)
			(xy 178.249184 -341.533394) (xy 178.226337 -341.483645) (xy 178.21084 -341.431141) (xy 178.203012 -341.37696)
			(xy 178.203014 -341.322216) (xy 178.210846 -341.268035) (xy 178.226346 -341.215532) (xy 178.249196 -341.165785)
			(xy 178.278926 -341.119818) (xy 178.29657 -341.098886) (xy 178.305825 -341.087571) (xy 178.318004 -341.06101)
			(xy 178.322175 -341.032088) (xy 178.317997 -341.003167) (xy 178.305812 -340.976608) (xy 178.29657 -340.965282)
			(xy 178.278912 -340.944363) (xy 178.249184 -340.898394) (xy 178.226337 -340.848645) (xy 178.21084 -340.796141)
			(xy 178.203012 -340.74196) (xy 178.203014 -340.687216) (xy 178.210846 -340.633035) (xy 178.226346 -340.580532)
			(xy 178.249196 -340.530785) (xy 178.278926 -340.484818) (xy 178.29657 -340.463886) (xy 178.305825 -340.452571)
			(xy 178.318004 -340.42601) (xy 178.322175 -340.397088) (xy 178.317997 -340.368167) (xy 178.305812 -340.341608)
			(xy 178.29657 -340.330282) (xy 178.278912 -340.309363) (xy 178.249184 -340.263394) (xy 178.226337 -340.213645)
			(xy 178.21084 -340.161141) (xy 178.203012 -340.10696) (xy 178.203014 -340.052216) (xy 178.210846 -339.998035)
			(xy 178.226346 -339.945532) (xy 178.249196 -339.895785) (xy 178.278926 -339.849818) (xy 178.29657 -339.828886)
			(xy 178.305825 -339.817571) (xy 178.318004 -339.79101) (xy 178.322175 -339.762088) (xy 178.317997 -339.733167)
			(xy 178.305812 -339.706608) (xy 178.29657 -339.695282) (xy 178.278912 -339.674363) (xy 178.249184 -339.628394)
			(xy 178.226337 -339.578645) (xy 178.21084 -339.526141) (xy 178.203012 -339.47196) (xy 178.203014 -339.417216)
			(xy 178.210846 -339.363035) (xy 178.226346 -339.310532) (xy 178.249196 -339.260785) (xy 178.278926 -339.214818)
			(xy 178.29657 -339.193886) (xy 178.305825 -339.182571) (xy 178.318004 -339.15601) (xy 178.322175 -339.127088)
			(xy 178.317997 -339.098167) (xy 178.305812 -339.071608) (xy 178.29657 -339.060282) (xy 178.278951 -339.039334)
			(xy 178.249237 -338.993365) (xy 178.226398 -338.943621) (xy 178.210902 -338.891125) (xy 178.203068 -338.836952)
			(xy 178.20259 -338.809584) (xy 178.203063 -338.782332) (xy 178.210822 -338.728384) (xy 178.226179 -338.676089)
			(xy 178.248821 -338.626512) (xy 178.278289 -338.580662) (xy 178.313982 -338.539472) (xy 178.355173 -338.503781)
			(xy 178.401025 -338.474315) (xy 178.450603 -338.451674) (xy 178.502898 -338.436319) (xy 178.556846 -338.428562)
			(xy 178.584098 -338.428076) (xy 178.611469 -338.428525) (xy 178.66565 -338.436344) (xy 178.718154 -338.451836)
			(xy 178.7679 -338.474682) (xy 178.813866 -338.504412) (xy 178.834796 -338.522056) (xy 178.846124 -338.531292)
			(xy 178.872681 -338.543468) (xy 178.901598 -338.547641) (xy 178.930515 -338.543468) (xy 178.957072 -338.531292)
			(xy 178.9684 -338.522056) (xy 178.989315 -338.504396) (xy 179.035293 -338.474689) (xy 179.085045 -338.451858)
			(xy 179.137549 -338.436371) (xy 179.191728 -338.428547) (xy 179.219098 -338.428076) (xy 179.247138 -338.428571)
			(xy 179.302616 -338.436772) (xy 179.356298 -338.452997) (xy 179.40703 -338.476899) (xy 179.453722 -338.507962)
			(xy 179.474876 -338.526374) (xy 179.486318 -338.536019) (xy 179.513361 -338.548799) (xy 179.542948 -338.553185)
			(xy 179.572535 -338.548799) (xy 179.599578 -338.536019) (xy 179.61102 -338.526374) (xy 179.632181 -338.507967)
			(xy 179.678856 -338.476871) (xy 179.729584 -338.452953) (xy 179.783271 -338.43673) (xy 179.838756 -338.428552)
			(xy 179.866798 -338.428076) (xy 179.894048 -338.42858) (xy 179.947995 -338.436335) (xy 180.000288 -338.451689)
			(xy 180.049864 -338.474329) (xy 180.095714 -338.503794) (xy 180.136904 -338.539483) (xy 180.172595 -338.580672)
			(xy 180.202062 -338.62652) (xy 180.224704 -338.676095) (xy 180.240061 -338.728388) (xy 180.247819 -338.782334)
			(xy 180.248306 -338.809584) (xy 180.247829 -338.836954) (xy 180.240014 -338.891132) (xy 180.224527 -338.943635)
			(xy 180.201688 -338.993382) (xy 180.171966 -339.03935) (xy 180.154326 -339.060282) (xy 180.145102 -339.07162)
			(xy 180.13292 -339.098173) (xy 180.128743 -339.127088) (xy 180.132913 -339.156003) (xy 180.145089 -339.18256)
			(xy 180.154326 -339.193886) (xy 180.171953 -339.214831) (xy 180.201682 -339.260795) (xy 180.224531 -339.310539)
			(xy 180.240031 -339.36304) (xy 180.247862 -339.417218) (xy 180.247864 -339.471958) (xy 180.240036 -339.526137)
			(xy 180.22454 -339.578638) (xy 180.201694 -339.628384) (xy 180.171968 -339.67435) (xy 180.154326 -339.695282)
			(xy 180.145102 -339.70662) (xy 180.13292 -339.733173) (xy 180.128743 -339.762088) (xy 180.132913 -339.791003)
			(xy 180.145089 -339.81756) (xy 180.154326 -339.828886) (xy 180.171953 -339.849831) (xy 180.201682 -339.895795)
			(xy 180.224531 -339.945539) (xy 180.240031 -339.99804) (xy 180.247862 -340.052218) (xy 180.247864 -340.106958)
			(xy 180.240036 -340.161137) (xy 180.22454 -340.213638) (xy 180.201694 -340.263384) (xy 180.171968 -340.30935)
			(xy 180.154326 -340.330282) (xy 180.145102 -340.34162) (xy 180.13292 -340.368173) (xy 180.128743 -340.397088)
			(xy 180.132913 -340.426003) (xy 180.145089 -340.45256) (xy 180.154326 -340.463886) (xy 180.171953 -340.484831)
			(xy 180.201682 -340.530795) (xy 180.224531 -340.580539) (xy 180.240031 -340.63304) (xy 180.247862 -340.687218)
			(xy 180.247864 -340.741958) (xy 180.240036 -340.796137) (xy 180.22454 -340.848638) (xy 180.201694 -340.898384)
			(xy 180.171968 -340.94435) (xy 180.154326 -340.965282) (xy 180.145102 -340.97662) (xy 180.13292 -341.003173)
			(xy 180.128743 -341.032088) (xy 180.132913 -341.061003) (xy 180.145089 -341.08756) (xy 180.154326 -341.098886)
			(xy 180.171953 -341.119831) (xy 180.201682 -341.165795) (xy 180.224531 -341.215539) (xy 180.240031 -341.26804)
			(xy 180.247862 -341.322218) (xy 180.247864 -341.376958) (xy 180.240036 -341.431137) (xy 180.22454 -341.483638)
			(xy 180.201694 -341.533384) (xy 180.171968 -341.57935) (xy 180.154326 -341.600282) (xy 180.145102 -341.61162)
			(xy 180.13292 -341.638173) (xy 180.128743 -341.667088) (xy 180.132913 -341.696003) (xy 180.145089 -341.72256)
			(xy 180.154326 -341.733886) (xy 180.171953 -341.754831) (xy 180.201682 -341.800795) (xy 180.224531 -341.850539)
			(xy 180.240031 -341.90304) (xy 180.247862 -341.957218) (xy 180.247864 -342.011958) (xy 180.240036 -342.066137)
			(xy 180.22454 -342.118638) (xy 180.201694 -342.168384) (xy 180.171968 -342.21435) (xy 180.154326 -342.235282)
			(xy 180.145102 -342.24662) (xy 180.13292 -342.273173) (xy 180.128743 -342.302088) (xy 180.132913 -342.331003)
			(xy 180.145089 -342.35756) (xy 180.154326 -342.368886) (xy 180.171976 -342.389809) (xy 180.201685 -342.435785)
			(xy 180.224519 -342.485535) (xy 180.240007 -342.538037) (xy 180.247833 -342.592214) (xy 180.248306 -342.619584)
			(xy 180.24783 -342.646837) (xy 180.240075 -342.700787) (xy 180.224721 -342.753085) (xy 180.20208 -342.802665)
			(xy 180.172614 -342.848518) (xy 180.136921 -342.889711) (xy 180.09573 -342.925405) (xy 180.049877 -342.954873)
			(xy 180.000298 -342.977516) (xy 179.948001 -342.992872) (xy 179.894051 -343.000629) (xy 179.866798 -343.001092)
			(xy 179.838757 -343.000608) (xy 179.783279 -342.992406) (xy 179.729596 -342.976178) (xy 179.678864 -342.952274)
			(xy 179.632173 -342.921208) (xy 179.61102 -342.902794) (xy 179.599578 -342.893149) (xy 179.572535 -342.880369)
			(xy 179.542948 -342.875983) (xy 179.513361 -342.880369) (xy 179.486318 -342.893149) (xy 179.474876 -342.902794)
			(xy 179.453712 -342.921198) (xy 179.407039 -342.952296) (xy 179.356311 -342.976215) (xy 179.302625 -342.992438)
			(xy 179.24714 -343.000616) (xy 179.219098 -343.001092) (xy 179.191728 -343.000629) (xy 179.137548 -342.992811)
			(xy 179.085045 -342.977321) (xy 179.035298 -342.954479) (xy 178.989332 -342.924753) (xy 178.9684 -342.907112)
			(xy 178.957072 -342.897876) (xy 178.930515 -342.8857) (xy 178.901598 -342.881527) (xy 178.872681 -342.8857)
			(xy 178.846124 -342.897876) (xy 178.834796 -342.907112) (xy 178.813878 -342.924768) (xy 178.767901 -342.954477)
			(xy 178.71815 -342.97731) (xy 178.665646 -342.992797) (xy 178.611468 -343.00062) (xy 178.584098 -343.001092)
			(xy 178.556844 -343.000646) (xy 178.502892 -342.992889) (xy 178.450593 -342.977532) (xy 178.401012 -342.954888)
			(xy 178.355158 -342.925418) (xy 178.313965 -342.889723) (xy 178.278271 -342.848528) (xy 178.248804 -342.802673)
			(xy 178.226162 -342.75309) (xy 178.210807 -342.70079) (xy 178.203052 -342.646838) (xy 178.20259 -342.619584)
			(xy 175.541178 -342.619584) (xy 175.54073 -342.646838) (xy 175.532974 -342.700791) (xy 175.517619 -342.753091)
			(xy 175.494976 -342.802673) (xy 175.465507 -342.848528) (xy 175.429811 -342.889721) (xy 175.388616 -342.925415)
			(xy 175.342761 -342.954883) (xy 175.293178 -342.977524) (xy 175.240877 -342.992877) (xy 175.186924 -343.000631)
			(xy 175.15967 -343.001092) (xy 175.132299 -343.000645) (xy 175.078119 -342.992823) (xy 175.025616 -342.97733)
			(xy 174.975869 -342.954484) (xy 174.929903 -342.924755) (xy 174.908972 -342.907112) (xy 174.897644 -342.897876)
			(xy 174.871087 -342.8857) (xy 174.84217 -342.881527) (xy 174.813253 -342.8857) (xy 174.786696 -342.897876)
			(xy 174.775368 -342.907112) (xy 174.754423 -342.924735) (xy 174.708453 -342.954448) (xy 174.658709 -342.977287)
			(xy 174.606211 -342.992782) (xy 174.552038 -343.000615) (xy 174.52467 -343.001092) (xy 174.496629 -343.000624)
			(xy 174.441149 -342.992418) (xy 174.387467 -342.976187) (xy 174.336735 -342.952279) (xy 174.290045 -342.921209)
			(xy 174.268892 -342.902794) (xy 174.25745 -342.893149) (xy 174.230407 -342.880369) (xy 174.20082 -342.875983)
			(xy 174.171233 -342.880369) (xy 174.14419 -342.893149) (xy 174.132748 -342.902794) (xy 174.111595 -342.921212)
			(xy 174.064919 -342.952307) (xy 174.014188 -342.976223) (xy 173.9605 -342.992444) (xy 173.905013 -343.000618)
			(xy 173.87697 -343.001092) (xy 173.849717 -343.00065) (xy 173.795767 -342.992889) (xy 173.743471 -342.977529)
			(xy 173.693892 -342.954883) (xy 173.648041 -342.925413) (xy 173.606851 -342.889717) (xy 173.57116 -342.848522)
			(xy 173.541694 -342.802667) (xy 173.519055 -342.753086) (xy 173.503701 -342.700788) (xy 173.495947 -342.646837)
			(xy 173.495462 -342.619584) (xy 170.570906 -342.619584) (xy 170.57043 -342.646837) (xy 170.562675 -342.700787)
			(xy 170.547321 -342.753085) (xy 170.52468 -342.802665) (xy 170.495214 -342.848518) (xy 170.459521 -342.889711)
			(xy 170.41833 -342.925405) (xy 170.372477 -342.954873) (xy 170.322898 -342.977516) (xy 170.270601 -342.992872)
			(xy 170.216651 -343.000629) (xy 170.189398 -343.001092) (xy 170.161357 -343.000608) (xy 170.105879 -342.992406)
			(xy 170.052196 -342.976178) (xy 170.001464 -342.952274) (xy 169.954773 -342.921208) (xy 169.93362 -342.902794)
			(xy 169.922178 -342.893149) (xy 169.895135 -342.880369) (xy 169.865548 -342.875983) (xy 169.835961 -342.880369)
			(xy 169.808918 -342.893149) (xy 169.797476 -342.902794) (xy 169.776312 -342.921198) (xy 169.729639 -342.952296)
			(xy 169.678911 -342.976215) (xy 169.625225 -342.992438) (xy 169.56974 -343.000616) (xy 169.541698 -343.001092)
			(xy 169.514328 -343.000629) (xy 169.460148 -342.992811) (xy 169.407645 -342.977321) (xy 169.357898 -342.954479)
			(xy 169.311932 -342.924753) (xy 169.291 -342.907112) (xy 169.279672 -342.897876) (xy 169.253115 -342.8857)
			(xy 169.224198 -342.881527) (xy 169.195281 -342.8857) (xy 169.168724 -342.897876) (xy 169.157396 -342.907112)
			(xy 169.136478 -342.924768) (xy 169.090501 -342.954477) (xy 169.04075 -342.97731) (xy 168.988246 -342.992797)
			(xy 168.934068 -343.00062) (xy 168.906698 -343.001092) (xy 168.879444 -343.000646) (xy 168.825492 -342.992889)
			(xy 168.773193 -342.977532) (xy 168.723612 -342.954888) (xy 168.677758 -342.925418) (xy 168.636565 -342.889723)
			(xy 168.600871 -342.848528) (xy 168.571404 -342.802673) (xy 168.548762 -342.75309) (xy 168.533407 -342.70079)
			(xy 168.525652 -342.646838) (xy 168.52519 -342.619584) (xy 166.464863 -342.619584) (xy 166.71925 -345.972638)
			(xy 166.720562 -345.991279) (xy 166.721959 -346.028627) (xy 166.722044 -346.047314) (xy 166.722033 -346.064089)
			(xy 166.721016 -346.097625) (xy 166.720012 -346.11437) (xy 166.71925 -346.136468) (xy 166.388542 -353.51085)
			(xy 166.392606 -353.52101) (xy 166.403728 -353.551374) (xy 166.416759 -353.614705) (xy 166.418514 -353.646994)
			(xy 166.427034 -353.675385) (xy 166.436218 -353.733944) (xy 166.436802 -353.76358) (xy 166.43634 -353.791129)
			(xy 166.428455 -353.84566) (xy 166.412804 -353.898488) (xy 166.389713 -353.948514) (xy 166.37508 -353.97186)
			(xy 166.36746 -353.98329) (xy 166.348156 -354.414836) (xy 166.359078 -354.429568) (xy 166.37735 -354.454598)
			(xy 166.406384 -354.509343) (xy 166.426175 -354.568065) (xy 166.436203 -354.629216) (xy 166.436802 -354.6602)
			(xy 166.436274 -354.688391) (xy 166.427936 -354.744154) (xy 166.411485 -354.798084) (xy 166.38728 -354.849007)
			(xy 166.355848 -354.895815) (xy 166.337234 -354.916994) (xy 166.325042 -354.93071) (xy 166.320997 -355.02088)
			(xy 168.06799 -355.02088) (xy 168.068468 -354.992839) (xy 168.076672 -354.93736) (xy 168.092902 -354.883678)
			(xy 168.116807 -354.832946) (xy 168.147874 -354.786255) (xy 168.166288 -354.765102) (xy 168.175903 -354.753637)
			(xy 168.188686 -354.726603) (xy 168.193077 -354.697022) (xy 168.188699 -354.66744) (xy 168.175928 -354.6404)
			(xy 168.166288 -354.628958) (xy 168.147872 -354.607803) (xy 168.116777 -354.561127) (xy 168.092861 -354.510397)
			(xy 168.07664 -354.456709) (xy 168.068464 -354.401223) (xy 168.06799 -354.37318) (xy 168.068476 -354.345929)
			(xy 168.076232 -354.291981) (xy 168.091587 -354.239686) (xy 168.114229 -354.190109) (xy 168.143695 -354.144259)
			(xy 168.179386 -354.103068) (xy 168.220577 -354.067377) (xy 168.266427 -354.037911) (xy 168.316004 -354.015269)
			(xy 168.368299 -353.999914) (xy 168.422247 -353.992158) (xy 168.476749 -353.992158) (xy 168.530697 -353.999914)
			(xy 168.582992 -354.015269) (xy 168.632569 -354.037911) (xy 168.678419 -354.067377) (xy 168.71961 -354.103068)
			(xy 168.755301 -354.144259) (xy 168.784767 -354.190109) (xy 168.807409 -354.239686) (xy 168.822764 -354.291981)
			(xy 168.83052 -354.345929) (xy 168.831006 -354.37318) (xy 168.830505 -354.40122) (xy 168.822306 -354.456698)
			(xy 168.806083 -354.51038) (xy 168.782182 -354.561112) (xy 168.75112 -354.607804) (xy 168.732708 -354.628958)
			(xy 168.728189 -354.634292) (xy 176.045366 -354.634292) (xy 176.049437 -354.57867) (xy 176.061563 -354.524233)
			(xy 176.081486 -354.472142) (xy 176.108782 -354.423507) (xy 176.142868 -354.379364) (xy 176.183017 -354.340655)
			(xy 176.228375 -354.308204) (xy 176.277975 -354.282703) (xy 176.330759 -354.264696) (xy 176.385602 -354.254566)
			(xy 176.441336 -354.252529) (xy 176.496773 -354.258629) (xy 176.55073 -354.272735) (xy 176.602059 -354.294547)
			(xy 176.649665 -354.323601) (xy 176.692533 -354.359276) (xy 176.72975 -354.400813) (xy 176.760523 -354.447326)
			(xy 176.784195 -354.497823) (xy 176.800263 -354.55123) (xy 176.808383 -354.606406) (xy 176.808892 -354.634292)
			(xy 176.808383 -354.662178) (xy 176.800263 -354.717354) (xy 176.784195 -354.770761) (xy 176.760523 -354.821258)
			(xy 176.72975 -354.867771) (xy 176.692533 -354.909308) (xy 176.649665 -354.944983) (xy 176.602059 -354.974037)
			(xy 176.55073 -354.995849) (xy 176.496773 -355.009955) (xy 176.455195 -355.01453) (xy 177.756312 -355.01453)
			(xy 177.756793 -354.98716) (xy 177.764607 -354.932982) (xy 177.780092 -354.880479) (xy 177.802931 -354.830732)
			(xy 177.832652 -354.784764) (xy 177.850292 -354.763832) (xy 177.859501 -354.752483) (xy 177.871683 -354.725934)
			(xy 177.875861 -354.697023) (xy 177.871695 -354.66811) (xy 177.859525 -354.641555) (xy 177.850292 -354.630228)
			(xy 177.832651 -354.609297) (xy 177.80294 -354.563324) (xy 177.780104 -354.513576) (xy 177.764614 -354.461075)
			(xy 177.756786 -354.406899) (xy 177.756312 -354.37953) (xy 177.756798 -354.352279) (xy 177.764554 -354.298331)
			(xy 177.779909 -354.246036) (xy 177.802551 -354.196459) (xy 177.832017 -354.150609) (xy 177.867708 -354.109418)
			(xy 177.908899 -354.073727) (xy 177.954749 -354.044261) (xy 178.004326 -354.021619) (xy 178.056621 -354.006264)
			(xy 178.110569 -353.998508) (xy 178.165071 -353.998508) (xy 178.219019 -354.006264) (xy 178.271314 -354.021619)
			(xy 178.320891 -354.044261) (xy 178.366741 -354.073727) (xy 178.407932 -354.109418) (xy 178.443623 -354.150609)
			(xy 178.473089 -354.196459) (xy 178.495731 -354.246036) (xy 178.511086 -354.298331) (xy 178.518842 -354.352279)
			(xy 178.519328 -354.37953) (xy 178.518897 -354.406902) (xy 178.511073 -354.461083) (xy 178.495577 -354.513587)
			(xy 178.472727 -354.563334) (xy 178.442994 -354.609298) (xy 178.425348 -354.630228) (xy 178.419106 -354.637848)
			(xy 185.603386 -354.637848) (xy 185.607457 -354.582226) (xy 185.619583 -354.527789) (xy 185.639506 -354.475698)
			(xy 185.666802 -354.427063) (xy 185.700888 -354.38292) (xy 185.741037 -354.344211) (xy 185.786395 -354.31176)
			(xy 185.835995 -354.286259) (xy 185.888779 -354.268252) (xy 185.943622 -354.258122) (xy 185.999356 -354.256085)
			(xy 186.054793 -354.262185) (xy 186.10875 -354.276291) (xy 186.160079 -354.298103) (xy 186.207685 -354.327157)
			(xy 186.250553 -354.362832) (xy 186.28777 -354.404369) (xy 186.318543 -354.450882) (xy 186.342215 -354.501379)
			(xy 186.358283 -354.554786) (xy 186.366403 -354.609962) (xy 186.366912 -354.637848) (xy 186.366403 -354.665734)
			(xy 186.358283 -354.72091) (xy 186.342215 -354.774317) (xy 186.318543 -354.824814) (xy 186.28777 -354.871327)
			(xy 186.250553 -354.912864) (xy 186.207685 -354.948539) (xy 186.160079 -354.977593) (xy 186.10875 -354.999405)
			(xy 186.054793 -355.013511) (xy 185.999356 -355.019611) (xy 185.943622 -355.017574) (xy 185.888779 -355.007444)
			(xy 185.835995 -354.989437) (xy 185.786395 -354.963936) (xy 185.741037 -354.931485) (xy 185.700888 -354.892776)
			(xy 185.666802 -354.848633) (xy 185.639506 -354.799998) (xy 185.619583 -354.747907) (xy 185.607457 -354.69347)
			(xy 185.603386 -354.637848) (xy 178.419106 -354.637848) (xy 178.416086 -354.641535) (xy 178.403918 -354.668101)
			(xy 178.399754 -354.697023) (xy 178.403931 -354.725942) (xy 178.416111 -354.752503) (xy 178.425348 -354.763832)
			(xy 178.442961 -354.784786) (xy 178.472678 -354.830752) (xy 178.49552 -354.880494) (xy 178.511017 -354.93299)
			(xy 178.518851 -354.987162) (xy 178.519328 -355.01453) (xy 178.518842 -355.041781) (xy 178.511086 -355.095729)
			(xy 178.495731 -355.148024) (xy 178.473089 -355.197601) (xy 178.443623 -355.243451) (xy 178.407932 -355.284642)
			(xy 178.366741 -355.320333) (xy 178.320891 -355.349799) (xy 178.271314 -355.372441) (xy 178.219019 -355.387796)
			(xy 178.165071 -355.395552) (xy 178.110569 -355.395552) (xy 178.056621 -355.387796) (xy 178.004326 -355.372441)
			(xy 177.954749 -355.349799) (xy 177.908899 -355.320333) (xy 177.867708 -355.284642) (xy 177.832017 -355.243451)
			(xy 177.802551 -355.197601) (xy 177.779909 -355.148024) (xy 177.764554 -355.095729) (xy 177.756798 -355.041781)
			(xy 177.756312 -355.01453) (xy 176.455195 -355.01453) (xy 176.441336 -355.016055) (xy 176.385602 -355.014018)
			(xy 176.330759 -355.003888) (xy 176.277975 -354.985881) (xy 176.228375 -354.96038) (xy 176.183017 -354.927929)
			(xy 176.142868 -354.88922) (xy 176.108782 -354.845077) (xy 176.081486 -354.796442) (xy 176.061563 -354.744351)
			(xy 176.049437 -354.689914) (xy 176.045366 -354.634292) (xy 168.728189 -354.634292) (xy 168.723034 -354.640377)
			(xy 168.710259 -354.667429) (xy 168.705879 -354.697022) (xy 168.710272 -354.726614) (xy 168.723059 -354.75366)
			(xy 168.732708 -354.765102) (xy 168.751151 -354.786234) (xy 168.782243 -354.832916) (xy 168.806154 -354.883652)
			(xy 168.822368 -354.937345) (xy 168.830536 -354.992835) (xy 168.831006 -355.02088) (xy 168.83052 -355.048131)
			(xy 168.822764 -355.102079) (xy 168.807409 -355.154374) (xy 168.784767 -355.203951) (xy 168.755301 -355.249801)
			(xy 168.71961 -355.290992) (xy 168.678419 -355.326683) (xy 168.632569 -355.356149) (xy 168.582992 -355.378791)
			(xy 168.530697 -355.394146) (xy 168.476749 -355.401902) (xy 168.422247 -355.401902) (xy 168.368299 -355.394146)
			(xy 168.316004 -355.378791) (xy 168.266427 -355.356149) (xy 168.220577 -355.326683) (xy 168.179386 -355.290992)
			(xy 168.143695 -355.249801) (xy 168.114229 -355.203951) (xy 168.091587 -355.154374) (xy 168.076232 -355.102079)
			(xy 168.068476 -355.048131) (xy 168.06799 -355.02088) (xy 166.320997 -355.02088) (xy 166.303223 -355.4171)
			(xy 172.316679 -355.4171) (xy 172.320847 -355.361492) (xy 172.333255 -355.307126) (xy 172.353627 -355.255216)
			(xy 172.381508 -355.206922) (xy 172.416275 -355.163323) (xy 172.457152 -355.125392) (xy 172.503225 -355.093977)
			(xy 172.553465 -355.069779) (xy 172.606751 -355.053339) (xy 172.661892 -355.045025) (xy 172.689774 -355.044502)
			(xy 172.717106 -355.044977) (xy 172.771185 -355.052948) (xy 172.823518 -355.068736) (xy 172.872982 -355.092004)
			(xy 172.918514 -355.122251) (xy 172.959137 -355.158828) (xy 172.993977 -355.200949) (xy 173.008544 -355.22408)
			(xy 173.016453 -355.236315) (xy 173.037926 -355.255989) (xy 173.064084 -355.268794) (xy 173.092794 -355.273686)
			(xy 173.121716 -355.270266) (xy 173.13529 -355.264974) (xy 173.158503 -355.255494) (xy 173.206835 -355.24214)
			(xy 173.256523 -355.235408) (xy 173.281594 -355.235002) (xy 173.306663 -355.235442) (xy 173.356345 -355.242185)
			(xy 173.40468 -355.255511) (xy 173.427898 -355.264974) (xy 173.441482 -355.270214) (xy 173.470388 -355.273597)
			(xy 173.499075 -355.268699) (xy 173.52522 -355.255916) (xy 173.546704 -355.236283) (xy 173.554644 -355.22408)
			(xy 173.569213 -355.200949) (xy 173.604056 -355.158828) (xy 173.644679 -355.122249) (xy 173.69021 -355.091998)
			(xy 173.739672 -355.068722) (xy 173.792003 -355.052922) (xy 173.846082 -355.044936) (xy 173.900746 -355.044936)
			(xy 173.954825 -355.052922) (xy 174.007156 -355.068722) (xy 174.056618 -355.091998) (xy 174.102149 -355.122249)
			(xy 174.142772 -355.158828) (xy 174.177615 -355.200949) (xy 174.192184 -355.22408) (xy 174.20015 -355.236274)
			(xy 174.221608 -355.255948) (xy 174.24775 -355.268758) (xy 174.276446 -355.273661) (xy 174.305358 -355.270257)
			(xy 174.31893 -355.264974) (xy 174.342139 -355.255482) (xy 174.390472 -355.242132) (xy 174.440162 -355.235405)
			(xy 174.465234 -355.235002) (xy 174.492078 -355.23542) (xy 174.545211 -355.24313) (xy 174.596686 -355.258385)
			(xy 174.64544 -355.280868) (xy 174.690463 -355.310116) (xy 174.730823 -355.345522) (xy 174.765683 -355.386354)
			(xy 174.794323 -355.431765) (xy 174.81615 -355.480817) (xy 174.823882 -355.506528) (xy 174.828594 -355.521008)
			(xy 174.845101 -355.546571) (xy 174.868405 -355.566137) (xy 174.896439 -355.577971) (xy 174.926716 -355.58102)
			(xy 174.956547 -355.575016) (xy 174.970186 -355.56825) (xy 174.998325 -355.553603) (xy 175.05828 -355.532881)
			(xy 175.120841 -355.522389) (xy 175.152558 -355.521768) (xy 175.170577 -355.521985) (xy 175.206452 -355.525422)
			(xy 175.224186 -355.528626) (xy 175.239394 -355.530974) (xy 175.269951 -355.527449) (xy 175.298072 -355.514987)
			(xy 175.321208 -355.494718) (xy 175.337261 -355.46848) (xy 175.341534 -355.453696) (xy 175.348943 -355.426655)
			(xy 175.370568 -355.374927) (xy 175.399529 -355.32692) (xy 175.435203 -355.283666) (xy 175.476821 -355.246098)
			(xy 175.523487 -355.215023) (xy 175.574199 -355.191111) (xy 175.627863 -355.174875) (xy 175.683325 -355.166666)
			(xy 175.711358 -355.166168) (xy 175.738609 -355.166694) (xy 175.792556 -355.174445) (xy 175.844851 -355.189794)
			(xy 175.89443 -355.21243) (xy 175.940282 -355.241892) (xy 175.981474 -355.277579) (xy 176.017169 -355.318765)
			(xy 176.046638 -355.364612) (xy 176.069282 -355.414187) (xy 176.070138 -355.4171) (xy 182.004979 -355.4171)
			(xy 182.009147 -355.36149) (xy 182.021556 -355.307122) (xy 182.04193 -355.25521) (xy 182.069813 -355.206915)
			(xy 182.104582 -355.163315) (xy 182.145461 -355.125384) (xy 182.191537 -355.09397) (xy 182.241781 -355.069773)
			(xy 182.29507 -355.053335) (xy 182.350213 -355.045023) (xy 182.378096 -355.044502) (xy 182.405428 -355.044959)
			(xy 182.459508 -355.052933) (xy 182.511842 -355.068725) (xy 182.561306 -355.091995) (xy 182.606838 -355.122245)
			(xy 182.64746 -355.158824) (xy 182.6823 -355.200947) (xy 182.696866 -355.22408) (xy 182.704754 -355.23633)
			(xy 182.726233 -355.256004) (xy 182.752397 -355.268807) (xy 182.781111 -355.273695) (xy 182.810037 -355.27027)
			(xy 182.823612 -355.264974) (xy 182.846823 -355.255487) (xy 182.895155 -355.242135) (xy 182.944844 -355.235406)
			(xy 182.969916 -355.235002) (xy 182.994985 -355.235435) (xy 183.044668 -355.242181) (xy 183.093002 -355.25551)
			(xy 183.11622 -355.264974) (xy 183.129796 -355.270237) (xy 183.158706 -355.273615) (xy 183.187396 -355.268712)
			(xy 183.213543 -355.255923) (xy 183.235026 -355.236286) (xy 183.242966 -355.22408) (xy 183.257535 -355.200949)
			(xy 183.292378 -355.158828) (xy 183.333001 -355.122249) (xy 183.378532 -355.091998) (xy 183.427994 -355.068722)
			(xy 183.480325 -355.052922) (xy 183.534404 -355.044936) (xy 183.589068 -355.044936) (xy 183.643147 -355.052922)
			(xy 183.695478 -355.068722) (xy 183.74494 -355.091998) (xy 183.790471 -355.122249) (xy 183.831094 -355.158828)
			(xy 183.865937 -355.200949) (xy 183.880506 -355.22408) (xy 183.888451 -355.236289) (xy 183.909915 -355.255963)
			(xy 183.936063 -355.268771) (xy 183.964764 -355.27367) (xy 183.99368 -355.270261) (xy 184.007252 -355.264974)
			(xy 184.030458 -355.255475) (xy 184.078793 -355.242128) (xy 184.128484 -355.235403) (xy 184.153556 -355.235002)
			(xy 184.180398 -355.23549) (xy 184.233527 -355.243189) (xy 184.285002 -355.258433) (xy 184.333755 -355.280907)
			(xy 184.378778 -355.310146) (xy 184.419139 -355.345544) (xy 184.454001 -355.386368) (xy 184.482643 -355.431774)
			(xy 184.504471 -355.48082) (xy 184.512204 -355.506528) (xy 184.516888 -355.521018) (xy 184.533399 -355.546585)
			(xy 184.55671 -355.566152) (xy 184.58475 -355.577984) (xy 184.615032 -355.58103) (xy 184.644867 -355.575019)
			(xy 184.658508 -355.56825) (xy 184.686661 -355.553631) (xy 184.746609 -355.5329) (xy 184.809164 -355.522395)
			(xy 184.84088 -355.521768) (xy 184.8589 -355.521982) (xy 184.894774 -355.525421) (xy 184.912508 -355.528626)
			(xy 184.927714 -355.530997) (xy 184.958273 -355.527466) (xy 184.986395 -355.514998) (xy 185.009532 -355.494724)
			(xy 185.025584 -355.468482) (xy 185.029856 -355.453696) (xy 185.037245 -355.426649) (xy 185.058872 -355.374919)
			(xy 185.087835 -355.326911) (xy 185.123511 -355.283658) (xy 185.165131 -355.24609) (xy 185.211801 -355.215015)
			(xy 185.262515 -355.191104) (xy 185.316182 -355.174871) (xy 185.371646 -355.166664) (xy 185.39968 -355.166168)
			(xy 185.42693 -355.166697) (xy 185.480875 -355.17445) (xy 185.533167 -355.189801) (xy 185.582742 -355.212438)
			(xy 185.628592 -355.2419) (xy 185.669782 -355.277587) (xy 185.705473 -355.318773) (xy 185.734941 -355.364619)
			(xy 185.757583 -355.414192) (xy 185.772941 -355.466482) (xy 185.7807 -355.520426) (xy 185.781188 -355.547676)
			(xy 185.78071 -355.57525) (xy 185.772761 -355.629823) (xy 185.757038 -355.682682) (xy 185.733871 -355.732729)
			(xy 185.70374 -355.778918) (xy 185.667274 -355.82029) (xy 185.646568 -355.838506) (xy 185.635698 -355.848431)
			(xy 185.61963 -355.873075) (xy 185.611247 -355.901275) (xy 185.611243 -355.930694) (xy 185.619617 -355.958897)
			(xy 185.635678 -355.983546) (xy 185.646568 -355.993446) (xy 185.667251 -356.011687) (xy 185.703717 -356.053054)
			(xy 185.733847 -356.09924) (xy 185.757012 -356.149284) (xy 185.77273 -356.202142) (xy 185.780673 -356.256712)
			(xy 185.780675 -356.311857) (xy 185.772737 -356.366428) (xy 185.757023 -356.419287) (xy 185.733862 -356.469333)
			(xy 185.703736 -356.515521) (xy 185.667273 -356.556891) (xy 185.646568 -356.575106) (xy 185.635698 -356.585031)
			(xy 185.61963 -356.609675) (xy 185.611247 -356.637875) (xy 185.611243 -356.667294) (xy 185.619617 -356.695497)
			(xy 185.635678 -356.720146) (xy 185.646568 -356.730046) (xy 185.66725 -356.748289) (xy 185.703724 -356.78965)
			(xy 185.73386 -356.835833) (xy 185.757032 -356.885875) (xy 185.772754 -356.938732) (xy 185.7807 -356.993303)
			(xy 185.781188 -357.020876) (xy 185.780722 -357.048129) (xy 185.772968 -357.102081) (xy 185.757614 -357.15438)
			(xy 185.734973 -357.203961) (xy 185.705506 -357.249816) (xy 185.669812 -357.291009) (xy 185.628619 -357.326703)
			(xy 185.582765 -357.356171) (xy 185.533184 -357.378813) (xy 185.480885 -357.394167) (xy 185.426933 -357.401922)
			(xy 185.39968 -357.402384) (xy 185.371824 -357.401891) (xy 185.316706 -357.393764) (xy 185.263355 -357.377715)
			(xy 185.212901 -357.354085) (xy 185.166416 -357.323374) (xy 185.124887 -357.286235) (xy 185.089195 -357.243456)
			(xy 185.060097 -357.195945) (xy 185.038211 -357.144711) (xy 185.030618 -357.117904) (xy 185.026394 -357.10377)
			(xy 185.010993 -357.078621) (xy 184.989063 -357.058905) (xy 184.962422 -357.046259) (xy 184.933281 -357.041732)
			(xy 184.918604 -357.043228) (xy 184.905587 -357.044895) (xy 184.879403 -357.046676) (xy 184.86628 -357.046784)
			(xy 184.852131 -357.046693) (xy 184.823908 -357.044657) (xy 184.809892 -357.04272) (xy 184.79654 -357.041169)
			(xy 184.769851 -357.044258) (xy 184.744897 -357.054218) (xy 184.723417 -357.070357) (xy 184.706905 -357.091552)
			(xy 184.696509 -357.116327) (xy 184.694322 -357.129588) (xy 184.690263 -357.156746) (xy 184.675284 -357.209576)
			(xy 184.652888 -357.259714) (xy 184.623536 -357.306124) (xy 184.587835 -357.347847) (xy 184.546523 -357.384023)
			(xy 184.500452 -357.413903) (xy 184.450573 -357.436871) (xy 184.397918 -357.452452) (xy 184.343572 -357.460326)
			(xy 184.316116 -357.460804) (xy 184.288863 -357.46033) (xy 184.234913 -357.452575) (xy 184.182615 -357.437221)
			(xy 184.133034 -357.41458) (xy 184.087181 -357.385113) (xy 184.045988 -357.34942) (xy 184.010294 -357.308229)
			(xy 183.980826 -357.262376) (xy 183.958184 -357.212797) (xy 183.942828 -357.160499) (xy 183.935071 -357.106549)
			(xy 183.934608 -357.079296) (xy 183.935068 -357.051721) (xy 183.943021 -356.997148) (xy 183.958747 -356.944288)
			(xy 183.981918 -356.894242) (xy 184.012052 -356.848052) (xy 184.04852 -356.806682) (xy 184.069228 -356.788466)
			(xy 184.080126 -356.77857) (xy 184.096194 -356.753918) (xy 184.104574 -356.72571) (xy 184.104573 -356.696284)
			(xy 184.096191 -356.668078) (xy 184.080123 -356.643426) (xy 184.069228 -356.633526) (xy 184.048532 -356.615298)
			(xy 184.012059 -356.573934) (xy 183.981924 -356.527748) (xy 183.958756 -356.477703) (xy 183.943037 -356.424843)
			(xy 183.935094 -356.37027) (xy 183.934608 -356.342696) (xy 183.935076 -356.316195) (xy 183.942417 -356.263705)
			(xy 183.956958 -356.212737) (xy 183.978418 -356.164275) (xy 184.006384 -356.119251) (xy 184.023 -356.098602)
			(xy 184.032398 -356.086423) (xy 184.0442 -356.058034) (xy 184.047035 -356.027421) (xy 184.040647 -355.997347)
			(xy 184.025613 -355.970529) (xy 184.003291 -355.949389) (xy 183.989726 -355.942138) (xy 183.96604 -355.93003)
			(xy 183.922058 -355.900108) (xy 183.882776 -355.864239) (xy 183.848991 -355.823151) (xy 183.834786 -355.80066)
			(xy 183.826864 -355.788436) (xy 183.80539 -355.76877) (xy 183.779237 -355.755968) (xy 183.750533 -355.751072)
			(xy 183.721614 -355.754481) (xy 183.70804 -355.759766) (xy 183.684836 -355.76927) (xy 183.6365 -355.782615)
			(xy 183.586808 -355.789337) (xy 183.561736 -355.789738) (xy 183.536666 -355.789326) (xy 183.486983 -355.782572)
			(xy 183.438649 -355.769235) (xy 183.415432 -355.759766) (xy 183.401852 -355.754528) (xy 183.372954 -355.751164)
			(xy 183.344277 -355.756074) (xy 183.318144 -355.76886) (xy 183.296668 -355.788488) (xy 183.288686 -355.80066)
			(xy 183.274117 -355.823791) (xy 183.239274 -355.865912) (xy 183.198651 -355.902491) (xy 183.15312 -355.932742)
			(xy 183.103658 -355.956018) (xy 183.051327 -355.971818) (xy 182.997248 -355.979804) (xy 182.942584 -355.979804)
			(xy 182.888505 -355.971818) (xy 182.836174 -355.956018) (xy 182.786712 -355.932742) (xy 182.741181 -355.902491)
			(xy 182.700558 -355.865912) (xy 182.665715 -355.823791) (xy 182.651146 -355.80066) (xy 182.643262 -355.788408)
			(xy 182.621778 -355.768742) (xy 182.595614 -355.755943) (xy 182.566901 -355.751055) (xy 182.537976 -355.754474)
			(xy 182.5244 -355.759766) (xy 182.501189 -355.769251) (xy 182.452856 -355.782603) (xy 182.403167 -355.789333)
			(xy 182.378096 -355.789738) (xy 182.350213 -355.789177) (xy 182.29507 -355.780865) (xy 182.241781 -355.764427)
			(xy 182.191537 -355.74023) (xy 182.145461 -355.708816) (xy 182.104582 -355.670885) (xy 182.069813 -355.627285)
			(xy 182.04193 -355.57899) (xy 182.021556 -355.527078) (xy 182.009147 -355.47271) (xy 182.004979 -355.4171)
			(xy 176.070138 -355.4171) (xy 176.084641 -355.466479) (xy 176.092401 -355.520425) (xy 176.092866 -355.547676)
			(xy 176.092396 -355.575251) (xy 176.084446 -355.629824) (xy 176.068722 -355.682684) (xy 176.045553 -355.73273)
			(xy 176.015421 -355.77892) (xy 175.978953 -355.820291) (xy 175.958246 -355.838506) (xy 175.947369 -355.848427)
			(xy 175.931289 -355.873069) (xy 175.922898 -355.901272) (xy 175.922894 -355.930697) (xy 175.931276 -355.958903)
			(xy 175.947348 -355.98355) (xy 175.958246 -355.993446) (xy 175.97893 -356.011686) (xy 176.015398 -356.053052)
			(xy 176.04553 -356.099239) (xy 176.068696 -356.149282) (xy 176.084415 -356.202141) (xy 176.092358 -356.256712)
			(xy 176.092361 -356.311857) (xy 176.084422 -356.366429) (xy 176.068707 -356.419288) (xy 176.045545 -356.469334)
			(xy 176.036694 -356.482904) (xy 178.547266 -356.482904) (xy 178.551337 -356.427282) (xy 178.563463 -356.372845)
			(xy 178.583386 -356.320754) (xy 178.610682 -356.272119) (xy 178.644768 -356.227976) (xy 178.684917 -356.189267)
			(xy 178.730275 -356.156816) (xy 178.779875 -356.131315) (xy 178.832659 -356.113308) (xy 178.887502 -356.103178)
			(xy 178.943236 -356.101141) (xy 178.998673 -356.107241) (xy 179.05263 -356.121347) (xy 179.103959 -356.143159)
			(xy 179.151565 -356.172213) (xy 179.194433 -356.207888) (xy 179.23165 -356.249425) (xy 179.262423 -356.295938)
			(xy 179.286095 -356.346435) (xy 179.302163 -356.399842) (xy 179.310283 -356.455018) (xy 179.310792 -356.482904)
			(xy 179.310283 -356.51079) (xy 179.302163 -356.565966) (xy 179.286095 -356.619373) (xy 179.262423 -356.66987)
			(xy 179.23165 -356.716383) (xy 179.194433 -356.75792) (xy 179.151565 -356.793595) (xy 179.103959 -356.822649)
			(xy 179.05263 -356.844461) (xy 178.998673 -356.858567) (xy 178.943236 -356.864667) (xy 178.887502 -356.86263)
			(xy 178.832659 -356.8525) (xy 178.779875 -356.834493) (xy 178.730275 -356.808992) (xy 178.684917 -356.776541)
			(xy 178.644768 -356.737832) (xy 178.610682 -356.693689) (xy 178.583386 -356.645054) (xy 178.563463 -356.592963)
			(xy 178.551337 -356.538526) (xy 178.547266 -356.482904) (xy 176.036694 -356.482904) (xy 176.015417 -356.515523)
			(xy 175.978952 -356.556892) (xy 175.958246 -356.575106) (xy 175.947369 -356.585027) (xy 175.931289 -356.609669)
			(xy 175.922898 -356.637872) (xy 175.922894 -356.667297) (xy 175.931276 -356.695503) (xy 175.947348 -356.72015)
			(xy 175.958246 -356.730046) (xy 175.978943 -356.748272) (xy 176.015413 -356.789639) (xy 176.045546 -356.835826)
			(xy 176.068713 -356.885871) (xy 176.084433 -356.93873) (xy 176.092378 -356.993302) (xy 176.092866 -357.020876)
			(xy 176.092422 -357.04813) (xy 176.084667 -357.102084) (xy 176.069312 -357.154385) (xy 176.04667 -357.203968)
			(xy 176.0172 -357.249823) (xy 175.981504 -357.291017) (xy 175.940308 -357.326711) (xy 175.894452 -357.356178)
			(xy 175.844868 -357.378819) (xy 175.792566 -357.394171) (xy 175.738612 -357.401924) (xy 175.711358 -357.402384)
			(xy 175.683501 -357.401911) (xy 175.628383 -357.393781) (xy 175.575031 -357.377729) (xy 175.524577 -357.354095)
			(xy 175.478092 -357.323382) (xy 175.436563 -357.286241) (xy 175.400871 -357.24346) (xy 175.371774 -357.195948)
			(xy 175.349889 -357.144711) (xy 175.342296 -357.117904) (xy 175.337994 -357.103798) (xy 175.322609 -357.078656)
			(xy 175.300697 -357.058941) (xy 175.274076 -357.046287) (xy 175.244953 -357.041743) (xy 175.230282 -357.043228)
			(xy 175.217265 -357.044897) (xy 175.191081 -357.046677) (xy 175.177958 -357.046784) (xy 175.163809 -357.046695)
			(xy 175.135586 -357.044658) (xy 175.12157 -357.04272) (xy 175.10822 -357.041147) (xy 175.081529 -357.044241)
			(xy 175.056574 -357.054206) (xy 175.035094 -357.070349) (xy 175.018582 -357.091547) (xy 175.008187 -357.116326)
			(xy 175.006 -357.129588) (xy 175.001962 -357.15675) (xy 174.986983 -357.209582) (xy 174.964584 -357.259721)
			(xy 174.935231 -357.306132) (xy 174.899527 -357.347855) (xy 174.858212 -357.384031) (xy 174.812138 -357.41391)
			(xy 174.762257 -357.436877) (xy 174.709599 -357.452457) (xy 174.655251 -357.460327) (xy 174.627794 -357.460804)
			(xy 177.882802 -357.460804) (xy 177.886873 -357.405182) (xy 177.898999 -357.350745) (xy 177.918922 -357.298654)
			(xy 177.946218 -357.250019) (xy 177.980304 -357.205876) (xy 178.020453 -357.167167) (xy 178.065811 -357.134716)
			(xy 178.115411 -357.109215) (xy 178.168195 -357.091208) (xy 178.223038 -357.081078) (xy 178.278772 -357.079041)
			(xy 178.334209 -357.085141) (xy 178.388166 -357.099247) (xy 178.439495 -357.121059) (xy 178.487101 -357.150113)
			(xy 178.529969 -357.185788) (xy 178.567186 -357.227325) (xy 178.597959 -357.273838) (xy 178.621631 -357.324335)
			(xy 178.637699 -357.377742) (xy 178.645819 -357.432918) (xy 178.646328 -357.460804) (xy 178.645819 -357.48869)
			(xy 178.637699 -357.543866) (xy 178.621631 -357.597273) (xy 178.597959 -357.64777) (xy 178.567186 -357.694283)
			(xy 178.529969 -357.73582) (xy 178.487101 -357.771495) (xy 178.439495 -357.800549) (xy 178.388166 -357.822361)
			(xy 178.334209 -357.836467) (xy 178.278772 -357.842567) (xy 178.223038 -357.84053) (xy 178.168195 -357.8304)
			(xy 178.115411 -357.812393) (xy 178.065811 -357.786892) (xy 178.020453 -357.754441) (xy 177.980304 -357.715732)
			(xy 177.946218 -357.671589) (xy 177.918922 -357.622954) (xy 177.898999 -357.570863) (xy 177.886873 -357.516426)
			(xy 177.882802 -357.460804) (xy 174.627794 -357.460804) (xy 174.600542 -357.460328) (xy 174.546594 -357.45257)
			(xy 174.494299 -357.437214) (xy 174.444721 -357.414572) (xy 174.398871 -357.385105) (xy 174.357681 -357.349412)
			(xy 174.321989 -357.308221) (xy 174.292523 -357.26237) (xy 174.269882 -357.212792) (xy 174.254528 -357.160496)
			(xy 174.246772 -357.106548) (xy 174.246286 -357.079296) (xy 174.246754 -357.051722) (xy 174.254707 -356.997149)
			(xy 174.270432 -356.944289) (xy 174.293601 -356.894244) (xy 174.323733 -356.848054) (xy 174.3602 -356.806682)
			(xy 174.380906 -356.788466) (xy 174.391806 -356.778571) (xy 174.407877 -356.753919) (xy 174.41626 -356.725711)
			(xy 174.416259 -356.696284) (xy 174.407875 -356.668076) (xy 174.391803 -356.643425) (xy 174.380906 -356.633526)
			(xy 174.360205 -356.615303) (xy 174.323734 -356.573937) (xy 174.2936 -356.52775) (xy 174.270433 -356.477704)
			(xy 174.254714 -356.424843) (xy 174.246772 -356.37027) (xy 174.246286 -356.342696) (xy 174.246759 -356.316196)
			(xy 174.2541 -356.263705) (xy 174.26864 -356.212738) (xy 174.290099 -356.164275) (xy 174.318063 -356.119252)
			(xy 174.334678 -356.098602) (xy 174.344049 -356.086407) (xy 174.355839 -356.058023) (xy 174.35867 -356.027419)
			(xy 174.352287 -355.997354) (xy 174.337266 -355.97054) (xy 174.31496 -355.949395) (xy 174.301404 -355.942138)
			(xy 174.277714 -355.930037) (xy 174.233734 -355.900113) (xy 174.194453 -355.864242) (xy 174.160669 -355.823152)
			(xy 174.146464 -355.80066) (xy 174.138563 -355.788421) (xy 174.117083 -355.768755) (xy 174.090924 -355.755954)
			(xy 174.062215 -355.751063) (xy 174.033293 -355.754477) (xy 174.019718 -355.759766) (xy 173.996504 -355.769246)
			(xy 173.948173 -355.7826) (xy 173.898485 -355.789332) (xy 173.873414 -355.789738) (xy 173.848345 -355.7893)
			(xy 173.798662 -355.782557) (xy 173.750328 -355.76923) (xy 173.72711 -355.759766) (xy 173.713502 -355.75461)
			(xy 173.684618 -355.751229) (xy 173.655952 -355.756121) (xy 173.629823 -355.768887) (xy 173.608347 -355.788496)
			(xy 173.600364 -355.80066) (xy 173.585795 -355.823791) (xy 173.550952 -355.865912) (xy 173.510329 -355.902491)
			(xy 173.464798 -355.932742) (xy 173.415336 -355.956018) (xy 173.363005 -355.971818) (xy 173.308926 -355.979804)
			(xy 173.254262 -355.979804) (xy 173.200183 -355.971818) (xy 173.147852 -355.956018) (xy 173.09839 -355.932742)
			(xy 173.052859 -355.902491) (xy 173.012236 -355.865912) (xy 172.977393 -355.823791) (xy 172.962824 -355.80066)
			(xy 172.954866 -355.788462) (xy 172.933402 -355.768796) (xy 172.907258 -355.75599) (xy 172.878563 -355.751087)
			(xy 172.849651 -355.754487) (xy 172.836078 -355.759766) (xy 172.812869 -355.769258) (xy 172.764536 -355.782607)
			(xy 172.714846 -355.789335) (xy 172.689774 -355.789738) (xy 172.661892 -355.789175) (xy 172.606751 -355.780861)
			(xy 172.553465 -355.764421) (xy 172.503225 -355.740223) (xy 172.457152 -355.708808) (xy 172.416275 -355.670877)
			(xy 172.381508 -355.627278) (xy 172.353627 -355.578984) (xy 172.333255 -355.527074) (xy 172.320847 -355.472708)
			(xy 172.316679 -355.4171) (xy 166.303223 -355.4171) (xy 166.255413 -356.482904) (xy 168.858944 -356.482904)
			(xy 168.863015 -356.427282) (xy 168.875141 -356.372845) (xy 168.895064 -356.320754) (xy 168.92236 -356.272119)
			(xy 168.956446 -356.227976) (xy 168.996595 -356.189267) (xy 169.041953 -356.156816) (xy 169.091553 -356.131315)
			(xy 169.144337 -356.113308) (xy 169.19918 -356.103178) (xy 169.254914 -356.101141) (xy 169.310351 -356.107241)
			(xy 169.364308 -356.121347) (xy 169.415637 -356.143159) (xy 169.463243 -356.172213) (xy 169.506111 -356.207888)
			(xy 169.543328 -356.249425) (xy 169.574101 -356.295938) (xy 169.597773 -356.346435) (xy 169.613841 -356.399842)
			(xy 169.621961 -356.455018) (xy 169.62247 -356.482904) (xy 169.621961 -356.51079) (xy 169.613841 -356.565966)
			(xy 169.597773 -356.619373) (xy 169.574101 -356.66987) (xy 169.543328 -356.716383) (xy 169.506111 -356.75792)
			(xy 169.463243 -356.793595) (xy 169.415637 -356.822649) (xy 169.364308 -356.844461) (xy 169.310351 -356.858567)
			(xy 169.254914 -356.864667) (xy 169.19918 -356.86263) (xy 169.144337 -356.8525) (xy 169.091553 -356.834493)
			(xy 169.041953 -356.808992) (xy 168.996595 -356.776541) (xy 168.956446 -356.737832) (xy 168.92236 -356.693689)
			(xy 168.895064 -356.645054) (xy 168.875141 -356.592963) (xy 168.863015 -356.538526) (xy 168.858944 -356.482904)
			(xy 166.255413 -356.482904) (xy 166.212082 -357.448866) (xy 168.19448 -357.448866) (xy 168.198551 -357.393244)
			(xy 168.210677 -357.338807) (xy 168.2306 -357.286716) (xy 168.257896 -357.238081) (xy 168.291982 -357.193938)
			(xy 168.332131 -357.155229) (xy 168.377489 -357.122778) (xy 168.427089 -357.097277) (xy 168.479873 -357.07927)
			(xy 168.534716 -357.06914) (xy 168.59045 -357.067103) (xy 168.645887 -357.073203) (xy 168.699844 -357.087309)
			(xy 168.751173 -357.109121) (xy 168.798779 -357.138175) (xy 168.841647 -357.17385) (xy 168.878864 -357.215387)
			(xy 168.909637 -357.2619) (xy 168.933309 -357.312397) (xy 168.949377 -357.365804) (xy 168.957497 -357.42098)
			(xy 168.958006 -357.448866) (xy 168.957497 -357.476752) (xy 168.949377 -357.531928) (xy 168.933309 -357.585335)
			(xy 168.909637 -357.635832) (xy 168.878864 -357.682345) (xy 168.841647 -357.723882) (xy 168.798779 -357.759557)
			(xy 168.751173 -357.788611) (xy 168.699844 -357.810423) (xy 168.645887 -357.824529) (xy 168.59045 -357.830629)
			(xy 168.534716 -357.828592) (xy 168.479873 -357.818462) (xy 168.427089 -357.800455) (xy 168.377489 -357.774954)
			(xy 168.332131 -357.742503) (xy 168.291982 -357.703794) (xy 168.257896 -357.659651) (xy 168.2306 -357.611016)
			(xy 168.210677 -357.558925) (xy 168.198551 -357.504488) (xy 168.19448 -357.448866) (xy 166.212082 -357.448866)
			(xy 166.187745 -357.99141) (xy 169.66565 -357.99141) (xy 169.666086 -357.966072) (xy 169.672793 -357.915843)
			(xy 169.686091 -357.866943) (xy 169.705744 -357.820235) (xy 169.731409 -357.776539) (xy 169.762632 -357.736625)
			(xy 169.780458 -357.718614) (xy 169.789846 -357.708834) (xy 169.803642 -357.685512) (xy 169.810797 -357.659378)
			(xy 169.810805 -357.632282) (xy 169.803665 -357.606143) (xy 169.789883 -357.582814) (xy 169.780458 -357.573072)
			(xy 169.762627 -357.555065) (xy 169.731397 -357.515153) (xy 169.705728 -357.471458) (xy 169.68607 -357.424748)
			(xy 169.67277 -357.375847) (xy 169.666063 -357.325615) (xy 169.66565 -357.300276) (xy 169.666136 -357.273025)
			(xy 169.673892 -357.219077) (xy 169.689247 -357.166782) (xy 169.711889 -357.117205) (xy 169.741355 -357.071355)
			(xy 169.777046 -357.030164) (xy 169.818237 -356.994473) (xy 169.864087 -356.965007) (xy 169.913664 -356.942365)
			(xy 169.965959 -356.92701) (xy 170.019907 -356.919254) (xy 170.074409 -356.919254) (xy 170.128357 -356.92701)
			(xy 170.180652 -356.942365) (xy 170.230229 -356.965007) (xy 170.276079 -356.994473) (xy 170.31727 -357.030164)
			(xy 170.352961 -357.071355) (xy 170.382427 -357.117205) (xy 170.405069 -357.166782) (xy 170.420424 -357.219077)
			(xy 170.42818 -357.273025) (xy 170.428326 -357.281226) (xy 171.290996 -357.281226) (xy 171.291482 -357.253975)
			(xy 171.299238 -357.200027) (xy 171.314593 -357.147732) (xy 171.337235 -357.098155) (xy 171.366701 -357.052305)
			(xy 171.402392 -357.011114) (xy 171.443583 -356.975423) (xy 171.489433 -356.945957) (xy 171.53901 -356.923315)
			(xy 171.591305 -356.90796) (xy 171.645253 -356.900204) (xy 171.699755 -356.900204) (xy 171.753703 -356.90796)
			(xy 171.805998 -356.923315) (xy 171.855575 -356.945957) (xy 171.901425 -356.975423) (xy 171.942616 -357.011114)
			(xy 171.978307 -357.052305) (xy 172.007773 -357.098155) (xy 172.030415 -357.147732) (xy 172.04577 -357.200027)
			(xy 172.053526 -357.253975) (xy 172.054012 -357.281226) (xy 172.05377 -357.299893) (xy 172.050079 -357.337044)
			(xy 172.046646 -357.355394) (xy 172.044279 -357.369658) (xy 172.046811 -357.398451) (xy 172.057314 -357.425379)
			(xy 172.074943 -357.448283) (xy 172.098287 -357.465328) (xy 172.125472 -357.475145) (xy 172.139864 -357.476552)
			(xy 172.168516 -357.478943) (xy 172.224682 -357.491225) (xy 172.278369 -357.511796) (xy 172.328362 -357.54019)
			(xy 172.373528 -357.575762) (xy 172.412846 -357.61771) (xy 172.445425 -357.665081) (xy 172.470528 -357.716805)
			(xy 172.487586 -357.771709) (xy 172.496212 -357.828551) (xy 172.496734 -357.857298) (xy 172.496248 -357.884549)
			(xy 172.488492 -357.938497) (xy 172.473137 -357.990792) (xy 172.450495 -358.040369) (xy 172.441966 -358.05364)
			(xy 179.353972 -358.05364) (xy 179.35445 -358.025192) (xy 179.362913 -357.96893) (xy 179.379643 -357.91455)
			(xy 179.404268 -357.86326) (xy 179.436242 -357.816198) (xy 179.474853 -357.77441) (xy 179.49672 -357.756206)
			(xy 179.508238 -357.746308) (xy 179.525265 -357.721175) (xy 179.534167 -357.692153) (xy 179.534159 -357.661795)
			(xy 179.525242 -357.632777) (xy 179.508202 -357.607653) (xy 179.49672 -357.59771) (xy 179.474849 -357.579513)
			(xy 179.436246 -357.537721) (xy 179.404282 -357.490657) (xy 179.379667 -357.439365) (xy 179.362948 -357.384984)
			(xy 179.354497 -357.328722) (xy 179.353972 -357.300276) (xy 179.354458 -357.273025) (xy 179.362214 -357.219077)
			(xy 179.377569 -357.166782) (xy 179.400211 -357.117205) (xy 179.429677 -357.071355) (xy 179.465368 -357.030164)
			(xy 179.506559 -356.994473) (xy 179.552409 -356.965007) (xy 179.601986 -356.942365) (xy 179.654281 -356.92701)
			(xy 179.708229 -356.919254) (xy 179.762731 -356.919254) (xy 179.816679 -356.92701) (xy 179.868974 -356.942365)
			(xy 179.918551 -356.965007) (xy 179.964401 -356.994473) (xy 180.005592 -357.030164) (xy 180.041283 -357.071355)
			(xy 180.070749 -357.117205) (xy 180.093391 -357.166782) (xy 180.108746 -357.219077) (xy 180.116502 -357.273025)
			(xy 180.116648 -357.281226) (xy 180.979318 -357.281226) (xy 180.979804 -357.253975) (xy 180.98756 -357.200027)
			(xy 181.002915 -357.147732) (xy 181.025557 -357.098155) (xy 181.055023 -357.052305) (xy 181.090714 -357.011114)
			(xy 181.131905 -356.975423) (xy 181.177755 -356.945957) (xy 181.227332 -356.923315) (xy 181.279627 -356.90796)
			(xy 181.333575 -356.900204) (xy 181.388077 -356.900204) (xy 181.442025 -356.90796) (xy 181.49432 -356.923315)
			(xy 181.543897 -356.945957) (xy 181.589747 -356.975423) (xy 181.630938 -357.011114) (xy 181.666629 -357.052305)
			(xy 181.696095 -357.098155) (xy 181.718737 -357.147732) (xy 181.734092 -357.200027) (xy 181.741848 -357.253975)
			(xy 181.742334 -357.281226) (xy 181.742101 -357.299893) (xy 181.738409 -357.337045) (xy 181.734968 -357.355394)
			(xy 181.73258 -357.369656) (xy 181.735113 -357.398452) (xy 181.745618 -357.425384) (xy 181.763252 -357.44829)
			(xy 181.786601 -357.465334) (xy 181.813792 -357.475148) (xy 181.828186 -357.476552) (xy 181.85684 -357.478924)
			(xy 181.913006 -357.49121) (xy 181.966693 -357.511783) (xy 182.016686 -357.540179) (xy 182.061852 -357.575754)
			(xy 182.10117 -357.617703) (xy 182.133748 -357.665077) (xy 182.158851 -357.716802) (xy 182.175908 -357.771707)
			(xy 182.184534 -357.828551) (xy 182.185056 -357.857298) (xy 182.18457 -357.884549) (xy 182.176814 -357.938497)
			(xy 182.161459 -357.990792) (xy 182.138817 -358.040369) (xy 182.109351 -358.086219) (xy 182.07366 -358.12741)
			(xy 182.032469 -358.163101) (xy 181.986619 -358.192567) (xy 181.937042 -358.215209) (xy 181.884747 -358.230564)
			(xy 181.830799 -358.23832) (xy 181.776297 -358.23832) (xy 181.722349 -358.230564) (xy 181.670054 -358.215209)
			(xy 181.620477 -358.192567) (xy 181.574627 -358.163101) (xy 181.533436 -358.12741) (xy 181.497745 -358.086219)
			(xy 181.468279 -358.040369) (xy 181.445637 -357.990792) (xy 181.430282 -357.938497) (xy 181.422526 -357.884549)
			(xy 181.42204 -357.857298) (xy 181.422277 -357.838631) (xy 181.425967 -357.801479) (xy 181.429406 -357.78313)
			(xy 181.431793 -357.768867) (xy 181.429265 -357.740068) (xy 181.418763 -357.713134) (xy 181.401128 -357.690227)
			(xy 181.377777 -357.673184) (xy 181.350583 -357.663373) (xy 181.336188 -357.661972) (xy 181.307535 -357.659599)
			(xy 181.25137 -357.64731) (xy 181.197685 -357.626735) (xy 181.147693 -357.598338) (xy 181.102528 -357.562763)
			(xy 181.063211 -357.520815) (xy 181.030633 -357.473442) (xy 181.00553 -357.421719) (xy 180.98847 -357.366815)
			(xy 180.979841 -357.309973) (xy 180.979318 -357.281226) (xy 180.116648 -357.281226) (xy 180.116988 -357.300276)
			(xy 180.116428 -357.32872) (xy 180.107979 -357.384978) (xy 180.091264 -357.439356) (xy 180.066654 -357.490646)
			(xy 180.034696 -357.53771) (xy 179.9961 -357.579502) (xy 179.97424 -357.59771) (xy 179.96281 -357.6077)
			(xy 179.945787 -357.632808) (xy 179.93688 -357.661806) (xy 179.936872 -357.692141) (xy 179.945764 -357.721144)
			(xy 179.962774 -357.746261) (xy 179.97424 -357.756206) (xy 179.99611 -357.774404) (xy 180.034716 -357.816194)
			(xy 180.066681 -357.863258) (xy 180.091296 -357.914551) (xy 180.108014 -357.968932) (xy 180.110284 -357.984044)
			(xy 180.369462 -357.984044) (xy 180.373533 -357.928422) (xy 180.385659 -357.873985) (xy 180.405582 -357.821894)
			(xy 180.432878 -357.773259) (xy 180.466964 -357.729116) (xy 180.507113 -357.690407) (xy 180.552471 -357.657956)
			(xy 180.602071 -357.632455) (xy 180.654855 -357.614448) (xy 180.709698 -357.604318) (xy 180.765432 -357.602281)
			(xy 180.820869 -357.608381) (xy 180.874826 -357.622487) (xy 180.926155 -357.644299) (xy 180.973761 -357.673353)
			(xy 181.016629 -357.709028) (xy 181.053846 -357.750565) (xy 181.084619 -357.797078) (xy 181.108291 -357.847575)
			(xy 181.124359 -357.900982) (xy 181.132479 -357.956158) (xy 181.132988 -357.984044) (xy 181.132479 -358.01193)
			(xy 181.124359 -358.067106) (xy 181.108291 -358.120513) (xy 181.084619 -358.17101) (xy 181.053846 -358.217523)
			(xy 181.016629 -358.25906) (xy 180.973761 -358.294735) (xy 180.926155 -358.323789) (xy 180.874826 -358.345601)
			(xy 180.820869 -358.359707) (xy 180.765432 -358.365807) (xy 180.709698 -358.36377) (xy 180.654855 -358.35364)
			(xy 180.602071 -358.335633) (xy 180.552471 -358.310132) (xy 180.507113 -358.277681) (xy 180.466964 -358.238972)
			(xy 180.432878 -358.194829) (xy 180.405582 -358.146194) (xy 180.385659 -358.094103) (xy 180.373533 -358.039666)
			(xy 180.369462 -357.984044) (xy 180.110284 -357.984044) (xy 180.116464 -358.025193) (xy 180.116988 -358.05364)
			(xy 180.116502 -358.080891) (xy 180.108746 -358.134839) (xy 180.093391 -358.187134) (xy 180.070749 -358.236711)
			(xy 180.041283 -358.282561) (xy 180.005592 -358.323752) (xy 179.964401 -358.359443) (xy 179.918551 -358.388909)
			(xy 179.868974 -358.411551) (xy 179.816679 -358.426906) (xy 179.762731 -358.434662) (xy 179.708229 -358.434662)
			(xy 179.654281 -358.426906) (xy 179.601986 -358.411551) (xy 179.552409 -358.388909) (xy 179.506559 -358.359443)
			(xy 179.465368 -358.323752) (xy 179.429677 -358.282561) (xy 179.400211 -358.236711) (xy 179.377569 -358.187134)
			(xy 179.362214 -358.134839) (xy 179.354458 -358.080891) (xy 179.353972 -358.05364) (xy 172.441966 -358.05364)
			(xy 172.421029 -358.086219) (xy 172.385338 -358.12741) (xy 172.344147 -358.163101) (xy 172.298297 -358.192567)
			(xy 172.24872 -358.215209) (xy 172.196425 -358.230564) (xy 172.142477 -358.23832) (xy 172.087975 -358.23832)
			(xy 172.034027 -358.230564) (xy 171.981732 -358.215209) (xy 171.932155 -358.192567) (xy 171.886305 -358.163101)
			(xy 171.845114 -358.12741) (xy 171.809423 -358.086219) (xy 171.779957 -358.040369) (xy 171.757315 -357.990792)
			(xy 171.74196 -357.938497) (xy 171.734204 -357.884549) (xy 171.733718 -357.857298) (xy 171.733956 -357.838631)
			(xy 171.737645 -357.801479) (xy 171.741084 -357.78313) (xy 171.743398 -357.76886) (xy 171.740872 -357.740075)
			(xy 171.730379 -357.713153) (xy 171.71276 -357.690251) (xy 171.689428 -357.673205) (xy 171.662253 -357.663383)
			(xy 171.647866 -357.661972) (xy 171.619211 -357.659618) (xy 171.563046 -357.647326) (xy 171.50936 -357.626748)
			(xy 171.459369 -357.598348) (xy 171.414205 -357.562771) (xy 171.374888 -357.520821) (xy 171.34231 -357.473447)
			(xy 171.317207 -357.421722) (xy 171.300148 -357.366816) (xy 171.291519 -357.309973) (xy 171.290996 -357.281226)
			(xy 170.428326 -357.281226) (xy 170.428666 -357.300276) (xy 170.428216 -357.325613) (xy 170.421511 -357.375842)
			(xy 170.408216 -357.424741) (xy 170.388565 -357.47145) (xy 170.362903 -357.515146) (xy 170.331683 -357.555061)
			(xy 170.313858 -357.573072) (xy 170.30443 -357.582799) (xy 170.290719 -357.606154) (xy 170.283619 -357.632289)
			(xy 170.283627 -357.659371) (xy 170.290743 -357.685502) (xy 170.304467 -357.708849) (xy 170.313858 -357.718614)
			(xy 170.331685 -357.736625) (xy 170.362915 -357.776536) (xy 170.388585 -357.820231) (xy 170.408243 -357.86694)
			(xy 170.421543 -357.91584) (xy 170.428252 -357.966071) (xy 170.428546 -357.984044) (xy 170.68114 -357.984044)
			(xy 170.685211 -357.928422) (xy 170.697337 -357.873985) (xy 170.71726 -357.821894) (xy 170.744556 -357.773259)
			(xy 170.778642 -357.729116) (xy 170.818791 -357.690407) (xy 170.864149 -357.657956) (xy 170.913749 -357.632455)
			(xy 170.966533 -357.614448) (xy 171.021376 -357.604318) (xy 171.07711 -357.602281) (xy 171.132547 -357.608381)
			(xy 171.186504 -357.622487) (xy 171.237833 -357.644299) (xy 171.285439 -357.673353) (xy 171.328307 -357.709028)
			(xy 171.365524 -357.750565) (xy 171.396297 -357.797078) (xy 171.419969 -357.847575) (xy 171.436037 -357.900982)
			(xy 171.444157 -357.956158) (xy 171.444666 -357.984044) (xy 171.444157 -358.01193) (xy 171.436037 -358.067106)
			(xy 171.419969 -358.120513) (xy 171.396297 -358.17101) (xy 171.365524 -358.217523) (xy 171.328307 -358.25906)
			(xy 171.285439 -358.294735) (xy 171.237833 -358.323789) (xy 171.186504 -358.345601) (xy 171.132547 -358.359707)
			(xy 171.07711 -358.365807) (xy 171.021376 -358.36377) (xy 170.966533 -358.35364) (xy 170.913749 -358.335633)
			(xy 170.864149 -358.310132) (xy 170.818791 -358.277681) (xy 170.778642 -358.238972) (xy 170.744556 -358.194829)
			(xy 170.71726 -358.146194) (xy 170.697337 -358.094103) (xy 170.685211 -358.039666) (xy 170.68114 -357.984044)
			(xy 170.428546 -357.984044) (xy 170.428666 -357.99141) (xy 170.42818 -358.018661) (xy 170.420424 -358.072609)
			(xy 170.405069 -358.124904) (xy 170.382427 -358.174481) (xy 170.352961 -358.220331) (xy 170.31727 -358.261522)
			(xy 170.276079 -358.297213) (xy 170.230229 -358.326679) (xy 170.180652 -358.349321) (xy 170.128357 -358.364676)
			(xy 170.074409 -358.372432) (xy 170.019907 -358.372432) (xy 169.965959 -358.364676) (xy 169.913664 -358.349321)
			(xy 169.864087 -358.326679) (xy 169.818237 -358.297213) (xy 169.777046 -358.261522) (xy 169.741355 -358.220331)
			(xy 169.711889 -358.174481) (xy 169.689247 -358.124904) (xy 169.673892 -358.072609) (xy 169.666136 -358.018661)
			(xy 169.66565 -357.99141) (xy 166.187745 -357.99141) (xy 166.096696 -360.021124) (xy 166.39794 -360.322368)
			(xy 173.48454 -360.322368) (xy 174.27194 -361.109768) (xy 174.27194 -361.518962) (xy 175.165258 -361.518962)
			(xy 175.165781 -361.489792) (xy 175.174688 -361.432135) (xy 175.192271 -361.376507) (xy 175.218122 -361.324205)
			(xy 175.251636 -361.276451) (xy 175.292033 -361.234359) (xy 175.314864 -361.216194) (xy 175.325211 -361.207738)
			(xy 175.341501 -361.186567) (xy 175.351744 -361.161896) (xy 175.355241 -361.135413) (xy 175.351751 -361.10893)
			(xy 175.341514 -361.084257) (xy 175.32523 -361.063081) (xy 175.314864 -361.05465) (xy 175.292028 -361.036491)
			(xy 175.251629 -360.994402) (xy 175.218116 -360.946647) (xy 175.192271 -360.894343) (xy 175.1747 -360.838712)
			(xy 175.165812 -360.781052) (xy 175.165258 -360.751882) (xy 175.165761 -360.724632) (xy 175.173519 -360.670687)
			(xy 175.188875 -360.618394) (xy 175.211515 -360.568819) (xy 175.24098 -360.52297) (xy 175.27667 -360.481781)
			(xy 175.317858 -360.44609) (xy 175.363705 -360.416623) (xy 175.413279 -360.39398) (xy 175.465571 -360.378622)
			(xy 175.519516 -360.370862) (xy 175.546766 -360.370374) (xy 175.575683 -360.370889) (xy 175.632856 -360.379614)
			(xy 175.688056 -360.396871) (xy 175.740019 -360.422263) (xy 175.787552 -360.455209) (xy 175.829567 -360.494953)
			(xy 175.847756 -360.51744) (xy 175.857653 -360.529245) (xy 175.882977 -360.546764) (xy 175.91237 -360.55594)
			(xy 175.943162 -360.55594) (xy 175.972555 -360.546764) (xy 175.997879 -360.529245) (xy 176.007776 -360.51744)
			(xy 176.025991 -360.494976) (xy 176.068004 -360.455238) (xy 176.115534 -360.422296) (xy 176.167491 -360.396903)
			(xy 176.222685 -360.379643) (xy 176.279851 -360.370911) (xy 176.308766 -360.370374) (xy 176.337312 -360.37093)
			(xy 176.393765 -360.379443) (xy 176.44832 -360.396269) (xy 176.499761 -360.421033) (xy 176.52365 -360.436668)
			(xy 176.534772 -360.443765) (xy 176.559632 -360.452568) (xy 176.585919 -360.45469) (xy 176.61187 -360.449989)
			(xy 176.635742 -360.438781) (xy 176.655935 -360.421817) (xy 176.663858 -360.411268) (xy 176.679265 -360.390252)
			(xy 176.714864 -360.352198) (xy 176.75531 -360.31934) (xy 176.799849 -360.29229) (xy 176.847654 -360.27155)
			(xy 176.897835 -360.257507) (xy 176.949461 -360.25042) (xy 176.975516 -360.249978) (xy 177.004432 -360.250527)
			(xy 177.061603 -360.259246) (xy 177.116803 -360.276496) (xy 177.168765 -360.301881) (xy 177.2163 -360.334821)
			(xy 177.258316 -360.37456) (xy 177.276506 -360.397044) (xy 177.286403 -360.408849) (xy 177.311727 -360.426368)
			(xy 177.34112 -360.435544) (xy 177.371912 -360.435544) (xy 177.401305 -360.426368) (xy 177.426629 -360.408849)
			(xy 177.436526 -360.397044) (xy 177.454713 -360.374557) (xy 177.496733 -360.33482) (xy 177.544268 -360.30188)
			(xy 177.59623 -360.276492) (xy 177.651429 -360.259237) (xy 177.7086 -360.250511) (xy 177.737516 -360.249978)
			(xy 177.764767 -360.250463) (xy 177.818714 -360.258221) (xy 177.871008 -360.273578) (xy 177.920584 -360.29622)
			(xy 177.966434 -360.325686) (xy 178.007624 -360.361378) (xy 178.043315 -360.402568) (xy 178.072781 -360.448417)
			(xy 178.095423 -360.497994) (xy 178.110779 -360.550288) (xy 178.118537 -360.604235) (xy 178.119024 -360.631486)
			(xy 178.118573 -360.657529) (xy 178.111489 -360.70913) (xy 178.097451 -360.759287) (xy 178.076719 -360.807069)
			(xy 178.04968 -360.851586) (xy 178.016836 -360.89201) (xy 177.99812 -360.910124) (xy 177.988141 -360.920052)
			(xy 177.973673 -360.94419) (xy 177.966332 -360.971357) (xy 177.966673 -360.999497) (xy 177.97467 -361.026479)
			(xy 177.989718 -361.050259) (xy 177.999898 -361.059984) (xy 178.019495 -361.07813) (xy 178.053888 -361.118993)
			(xy 178.082244 -361.164254) (xy 178.104009 -361.213028) (xy 178.118757 -361.264362) (xy 178.1262 -361.317251)
			(xy 178.126644 -361.343956) (xy 178.126102 -361.371724) (xy 178.118056 -361.426674) (xy 178.102127 -361.479877)
			(xy 178.078653 -361.530208) (xy 178.048129 -361.576604) (xy 178.011201 -361.618083) (xy 177.990246 -361.63631)
			(xy 177.979642 -361.645881) (xy 177.963652 -361.66953) (xy 177.954852 -361.696687) (xy 177.953933 -361.725219)
			(xy 177.960967 -361.752886) (xy 177.975402 -361.777515) (xy 177.98542 -361.787694) (xy 178.003747 -361.805801)
			(xy 178.035923 -361.846035) (xy 178.062396 -361.890231) (xy 178.082685 -361.937585) (xy 178.096422 -361.987238)
			(xy 178.103357 -362.038287) (xy 178.103784 -362.064046) (xy 178.10329 -362.091415) (xy 178.09548 -362.145593)
			(xy 178.079997 -362.198096) (xy 178.057162 -362.247844) (xy 178.027443 -362.293812) (xy 178.009804 -362.314744)
			(xy 178.000523 -362.326038) (xy 177.98835 -362.352608) (xy 177.984186 -362.381535) (xy 177.98837 -362.410459)
			(xy 178.00056 -362.437021) (xy 178.009804 -362.448348) (xy 178.027488 -362.469245) (xy 178.057209 -362.51522)
			(xy 178.08005 -362.564972) (xy 178.095541 -362.617479) (xy 178.103365 -362.671662) (xy 178.10336 -362.726407)
			(xy 178.095526 -362.780589) (xy 178.080025 -362.833093) (xy 178.057176 -362.882841) (xy 178.027447 -362.928811)
			(xy 178.009804 -362.949744) (xy 178.000523 -362.961038) (xy 177.98835 -362.987608) (xy 177.984186 -363.016535)
			(xy 177.98837 -363.045459) (xy 178.00056 -363.072021) (xy 178.009804 -363.083348) (xy 178.027433 -363.104288)
			(xy 178.057146 -363.150259) (xy 178.059513 -363.155414) (xy 179.144926 -363.155414) (xy 179.144926 -363.070718)
			(xy 179.152977 -362.986404) (xy 179.169006 -362.903238) (xy 179.192867 -362.821971) (xy 179.224346 -362.743341)
			(xy 179.263157 -362.66806) (xy 179.308947 -362.596808) (xy 179.361303 -362.530232) (xy 179.419751 -362.468934)
			(xy 179.483761 -362.413469) (xy 179.552753 -362.36434) (xy 179.626103 -362.321991) (xy 179.703146 -362.286807)
			(xy 179.783185 -362.259105) (xy 179.865494 -362.239137) (xy 179.949329 -362.227084) (xy 180.03393 -362.223054)
			(xy 180.118531 -362.227084) (xy 180.202366 -362.239137) (xy 180.284675 -362.259105) (xy 180.364714 -362.286807)
			(xy 180.441757 -362.321991) (xy 180.515107 -362.36434) (xy 180.584099 -362.413469) (xy 180.648109 -362.468934)
			(xy 180.706557 -362.530232) (xy 180.758913 -362.596808) (xy 180.804703 -362.66806) (xy 180.843514 -362.743341)
			(xy 180.874993 -362.821971) (xy 180.898854 -362.903238) (xy 180.914883 -362.986404) (xy 180.922934 -363.070718)
			(xy 180.923438 -363.113066) (xy 181.669439 -363.113066) (xy 181.673475 -363.029619) (xy 181.685547 -362.946951)
			(xy 181.70554 -362.865834) (xy 181.733269 -362.787025) (xy 181.768475 -362.71126) (xy 181.810829 -362.639247)
			(xy 181.859935 -362.571658) (xy 181.915336 -362.509124) (xy 181.976513 -362.452229) (xy 182.042896 -362.401503)
			(xy 182.113864 -362.357422) (xy 182.188756 -362.320396) (xy 182.266872 -362.29077) (xy 182.347482 -362.268822)
			(xy 182.429834 -362.254757) (xy 182.51316 -362.248705) (xy 182.59668 -362.250724) (xy 182.679616 -362.260794)
			(xy 182.761192 -362.278822) (xy 182.840648 -362.304639) (xy 182.917241 -362.338004) (xy 182.990257 -362.378605)
			(xy 183.059013 -362.426064) (xy 183.122867 -362.479937) (xy 183.181224 -362.539722) (xy 183.233539 -362.604859)
			(xy 183.279322 -362.674742) (xy 183.318147 -362.748717) (xy 183.349652 -362.826094) (xy 183.373541 -362.906151)
			(xy 183.389592 -362.988139) (xy 183.397655 -363.071294) (xy 183.39816 -363.113066) (xy 183.397655 -363.154838)
			(xy 183.389592 -363.237993) (xy 183.373541 -363.319981) (xy 183.349652 -363.400038) (xy 183.318147 -363.477415)
			(xy 183.279322 -363.55139) (xy 183.233539 -363.621273) (xy 183.181224 -363.68641) (xy 183.122867 -363.746195)
			(xy 183.059013 -363.800068) (xy 182.990257 -363.847527) (xy 182.917241 -363.888128) (xy 182.840648 -363.921493)
			(xy 182.761192 -363.94731) (xy 182.679616 -363.965338) (xy 182.59668 -363.975408) (xy 182.51316 -363.977427)
			(xy 182.429834 -363.971375) (xy 182.347482 -363.95731) (xy 182.266872 -363.935362) (xy 182.188756 -363.905736)
			(xy 182.113864 -363.86871) (xy 182.042896 -363.824629) (xy 181.976513 -363.773903) (xy 181.915336 -363.717008)
			(xy 181.859935 -363.654474) (xy 181.810829 -363.586885) (xy 181.768475 -363.514872) (xy 181.733269 -363.439107)
			(xy 181.70554 -363.360298) (xy 181.685547 -363.279181) (xy 181.673475 -363.196513) (xy 181.669439 -363.113066)
			(xy 180.923438 -363.113066) (xy 180.922934 -363.155414) (xy 180.914883 -363.239728) (xy 180.898854 -363.322894)
			(xy 180.874993 -363.404161) (xy 180.843514 -363.482791) (xy 180.804703 -363.558072) (xy 180.758913 -363.629324)
			(xy 180.706557 -363.6959) (xy 180.648109 -363.757198) (xy 180.584099 -363.812663) (xy 180.515107 -363.861792)
			(xy 180.441757 -363.904141) (xy 180.364714 -363.939325) (xy 180.284675 -363.967027) (xy 180.202366 -363.986995)
			(xy 180.118531 -363.999048) (xy 180.03393 -364.003079) (xy 179.949329 -363.999048) (xy 179.865494 -363.986995)
			(xy 179.783185 -363.967027) (xy 179.703146 -363.939325) (xy 179.626103 -363.904141) (xy 179.552753 -363.861792)
			(xy 179.483761 -363.812663) (xy 179.419751 -363.757198) (xy 179.361303 -363.6959) (xy 179.308947 -363.629324)
			(xy 179.263157 -363.558072) (xy 179.224346 -363.482791) (xy 179.192867 -363.404161) (xy 179.169006 -363.322894)
			(xy 179.152977 -363.239728) (xy 179.144926 -363.155414) (xy 178.059513 -363.155414) (xy 178.079984 -363.200004)
			(xy 178.095477 -363.252503) (xy 178.103308 -363.306677) (xy 178.103784 -363.334046) (xy 178.103365 -363.361299)
			(xy 178.095601 -363.415251) (xy 178.080239 -363.467548) (xy 178.057591 -363.517127) (xy 178.028118 -363.562979)
			(xy 177.992419 -363.604169) (xy 177.951222 -363.63986) (xy 177.905366 -363.669325) (xy 177.855783 -363.691964)
			(xy 177.803482 -363.707316) (xy 177.74953 -363.71507) (xy 177.722276 -363.715554) (xy 177.69336 -363.714998)
			(xy 177.63619 -363.706279) (xy 177.580991 -363.68903) (xy 177.529029 -363.663645) (xy 177.481494 -363.630708)
			(xy 177.439477 -363.590971) (xy 177.421286 -363.568488) (xy 177.411389 -363.556683) (xy 177.386065 -363.539164)
			(xy 177.356672 -363.529988) (xy 177.32588 -363.529988) (xy 177.296487 -363.539164) (xy 177.271163 -363.556683)
			(xy 177.261266 -363.568488) (xy 177.243091 -363.590985) (xy 177.201068 -363.63072) (xy 177.15353 -363.663658)
			(xy 177.101566 -363.689044) (xy 177.046365 -363.706297) (xy 176.989193 -363.715022) (xy 176.960276 -363.715554)
			(xy 176.933026 -363.715045) (xy 176.879082 -363.707286) (xy 176.82679 -363.69193) (xy 176.777216 -363.66929)
			(xy 176.731368 -363.639825) (xy 176.690179 -363.604136) (xy 176.654488 -363.56295) (xy 176.625021 -363.517103)
			(xy 176.602377 -363.46753) (xy 176.587019 -363.41524) (xy 176.579257 -363.361296) (xy 176.578768 -363.334046)
			(xy 176.579244 -363.306676) (xy 176.587057 -363.252497) (xy 176.602543 -363.199993) (xy 176.625383 -363.150246)
			(xy 176.655107 -363.104279) (xy 176.672748 -363.083348) (xy 176.681937 -363.071986) (xy 176.694114 -363.04544)
			(xy 176.698293 -363.016535) (xy 176.694133 -362.987627) (xy 176.681975 -362.961073) (xy 176.672748 -362.949744)
			(xy 176.655151 -362.928775) (xy 176.625423 -362.882814) (xy 176.602574 -362.833074) (xy 176.587073 -362.780577)
			(xy 176.57924 -362.726403) (xy 176.579235 -362.671666) (xy 176.587058 -362.617491) (xy 176.60255 -362.564991)
			(xy 176.62539 -362.515247) (xy 176.65511 -362.46928) (xy 176.672748 -362.448348) (xy 176.681937 -362.436986)
			(xy 176.694114 -362.41044) (xy 176.698293 -362.381535) (xy 176.694133 -362.352627) (xy 176.681975 -362.326073)
			(xy 176.672748 -362.314744) (xy 176.655124 -362.2938) (xy 176.625408 -362.247831) (xy 176.602568 -362.198087)
			(xy 176.587074 -362.145589) (xy 176.579243 -362.091414) (xy 176.578768 -362.064046) (xy 176.578999 -362.044991)
			(xy 176.582819 -362.007073) (xy 176.586388 -361.988354) (xy 176.588705 -361.97488) (xy 176.586854 -361.947611)
			(xy 176.577837 -361.92181) (xy 176.562301 -361.899324) (xy 176.541357 -361.881763) (xy 176.516507 -361.870386)
			(xy 176.489529 -361.866007) (xy 176.462355 -361.868939) (xy 176.449482 -361.873546) (xy 176.427016 -361.882082)
			(xy 176.380475 -361.894068) (xy 176.332796 -361.900107) (xy 176.308766 -361.90047) (xy 176.27985 -361.899916)
			(xy 176.22268 -361.891196) (xy 176.167482 -361.873946) (xy 176.115519 -361.848561) (xy 176.067985 -361.815623)
			(xy 176.025967 -361.775887) (xy 176.007776 -361.753404) (xy 175.997879 -361.741599) (xy 175.972555 -361.72408)
			(xy 175.943162 -361.714904) (xy 175.91237 -361.714904) (xy 175.882977 -361.72408) (xy 175.857653 -361.741599)
			(xy 175.847756 -361.753404) (xy 175.829591 -361.775909) (xy 175.787566 -361.815643) (xy 175.740025 -361.848579)
			(xy 175.688059 -361.873964) (xy 175.632857 -361.891215) (xy 175.575684 -361.899938) (xy 175.546766 -361.90047)
			(xy 175.519511 -361.900077) (xy 175.465555 -361.892314) (xy 175.413254 -361.876952) (xy 175.363671 -361.854303)
			(xy 175.317816 -361.824827) (xy 175.276623 -361.789126) (xy 175.240929 -361.747926) (xy 175.211463 -361.702066)
			(xy 175.188823 -361.652479) (xy 175.173471 -361.600174) (xy 175.165718 -361.546218) (xy 175.165258 -361.518962)
			(xy 174.27194 -361.518962) (xy 174.27194 -365.150146) (xy 174.288245 -365.171311) (xy 174.314995 -365.217558)
			(xy 174.334541 -365.26728) (xy 174.346444 -365.319363) (xy 174.350437 -365.372639) (xy 174.346432 -365.425915)
			(xy 174.334518 -365.477995) (xy 174.314961 -365.527713) (xy 174.288201 -365.573954) (xy 174.27194 -365.595154)
			(xy 174.27194 -365.940848) (xy 175.71974 -367.388648) (xy 190.0047 -367.388648)
		)
		(stroke
			(width 0)
			(type solid)
		)
		(fill yes)
		(layer "In13.Cu")
		(net "GND")
	)
	(gr_poly
		(pts
			(xy 310.7944 -439.039) (xy 310.7944 -431.404268) (xy 307.07457 -415.32683) (xy 305.198526 -413.450786)
			(xy 305.188163 -413.441144) (xy 305.163389 -413.427476) (xy 305.135816 -413.421127) (xy 305.107559 -413.422585)
			(xy 305.080786 -413.431737) (xy 305.05755 -413.447882) (xy 305.039633 -413.46978) (xy 305.02841 -413.495754)
			(xy 305.02606 -413.509714) (xy 305.022076 -413.536974) (xy 305.007282 -413.590041) (xy 304.985008 -413.640427)
			(xy 304.955718 -413.687086) (xy 304.92002 -413.729046) (xy 304.878657 -413.765434) (xy 304.83249 -413.795493)
			(xy 304.782479 -413.818599) (xy 304.729665 -413.83427) (xy 304.675145 -413.84218) (xy 304.6476 -413.842708)
			(xy 304.620349 -413.842222) (xy 304.566401 -413.834466) (xy 304.514106 -413.819111) (xy 304.464529 -413.796469)
			(xy 304.418679 -413.767003) (xy 304.377488 -413.731312) (xy 304.341797 -413.690121) (xy 304.312331 -413.644271)
			(xy 304.289689 -413.594694) (xy 304.274334 -413.542399) (xy 304.266578 -413.488451) (xy 304.266092 -413.4612)
			(xy 304.266576 -413.433653) (xy 304.274498 -413.379132) (xy 304.290179 -413.326317) (xy 304.313292 -413.276306)
			(xy 304.343356 -413.230139) (xy 304.379747 -413.188775) (xy 304.421708 -413.153073) (xy 304.468367 -413.123777)
			(xy 304.518753 -413.101496) (xy 304.57182 -413.086691) (xy 304.599086 -413.08274) (xy 304.613084 -413.08049)
			(xy 304.639129 -413.069318) (xy 304.661094 -413.05141) (xy 304.677281 -413.028148) (xy 304.686441 -413.001329)
			(xy 304.687866 -412.973025) (xy 304.681446 -412.945422) (xy 304.667676 -412.920652) (xy 304.658014 -412.910274)
			(xy 303.297336 -411.549596) (xy 303.286355 -411.539417) (xy 303.259932 -411.525364) (xy 303.23057 -411.519574)
			(xy 303.200791 -411.522541) (xy 303.173149 -411.534013) (xy 303.150019 -411.553003) (xy 303.133386 -411.577883)
			(xy 303.124677 -411.606515) (xy 303.124108 -411.621478) (xy 303.124108 -411.9245) (xy 303.12355 -411.95448)
			(xy 303.114165 -412.013701) (xy 303.095628 -412.070723) (xy 303.068395 -412.124141) (xy 303.033138 -412.172639)
			(xy 303.012348 -412.194248) (xy 302.273208 -412.933388) (xy 302.251593 -412.954166) (xy 302.203087 -412.989401)
			(xy 302.149668 -413.016618) (xy 302.09265 -413.035146) (xy 302.033436 -413.044531) (xy 302.00346 -413.045148)
			(xy 300.99762 -413.045148) (xy 300.970363 -413.044686) (xy 300.916405 -413.036931) (xy 300.864099 -413.021575)
			(xy 300.814511 -412.998931) (xy 300.76865 -412.969461) (xy 300.727451 -412.933763) (xy 300.691751 -412.892566)
			(xy 300.662278 -412.846707) (xy 300.639632 -412.79712) (xy 300.624273 -412.744815) (xy 300.616515 -412.690857)
			(xy 300.616515 -412.636343) (xy 300.624273 -412.582385) (xy 300.639632 -412.53008) (xy 300.662278 -412.480493)
			(xy 300.691751 -412.434634) (xy 300.727451 -412.393437) (xy 300.76865 -412.357739) (xy 300.814511 -412.328269)
			(xy 300.864099 -412.305625) (xy 300.916405 -412.290269) (xy 300.970363 -412.282514) (xy 300.99762 -412.282132)
			(xy 301.200566 -412.282132) (xy 301.214729 -412.281713) (xy 301.241987 -412.274018) (xy 301.26608 -412.259128)
			(xy 301.285153 -412.23819) (xy 301.297737 -412.212815) (xy 301.302861 -412.184959) (xy 301.300133 -412.156768)
			(xy 301.295308 -412.143448) (xy 301.286965 -412.1212) (xy 301.275227 -412.075157) (xy 301.26929 -412.028014)
			(xy 301.268892 -412.004256) (xy 301.269381 -411.977007) (xy 301.277142 -411.923064) (xy 301.292501 -411.870774)
			(xy 301.315145 -411.821203) (xy 301.344612 -411.775358) (xy 301.380304 -411.734173) (xy 301.421493 -411.698486)
			(xy 301.467341 -411.669024) (xy 301.516916 -411.646386) (xy 301.569207 -411.631033) (xy 301.623151 -411.623278)
			(xy 301.6504 -411.622748) (xy 301.67773 -411.623223) (xy 301.73183 -411.631033) (xy 301.784263 -411.64648)
			(xy 301.833957 -411.669247) (xy 301.879896 -411.698869) (xy 301.92114 -411.73474) (xy 301.956846 -411.776127)
			(xy 301.986284 -411.822183) (xy 302.008852 -411.871968) (xy 302.016922 -411.898084) (xy 302.021667 -411.912399)
			(xy 302.038185 -411.937613) (xy 302.061338 -411.956914) (xy 302.089114 -411.968622) (xy 302.119097 -411.971721)
			(xy 302.148681 -411.965941) (xy 302.175292 -411.951784) (xy 302.18634 -411.941518) (xy 302.361092 -411.766512)
			(xy 302.361092 -410.613606) (xy 301.60976 -409.86202) (xy 286.128968 -409.86202) (xy 286.11554 -409.862434)
			(xy 286.089615 -409.869448) (xy 286.066418 -409.882982) (xy 286.047555 -409.902099) (xy 286.034331 -409.925474)
			(xy 286.027664 -409.95149) (xy 286.028013 -409.978344) (xy 286.035356 -410.004178) (xy 286.041846 -410.015944)
			(xy 286.054798 -410.038296) (xy 286.075218 -410.085749) (xy 286.089046 -410.135524) (xy 286.096028 -410.18671)
			(xy 286.096456 -410.21254) (xy 286.09597 -410.239791) (xy 286.088214 -410.293739) (xy 286.072859 -410.346034)
			(xy 286.050217 -410.395611) (xy 286.020751 -410.441461) (xy 285.98506 -410.482652) (xy 285.943869 -410.518343)
			(xy 285.898019 -410.547809) (xy 285.848442 -410.570451) (xy 285.796147 -410.585806) (xy 285.742199 -410.593562)
			(xy 285.687697 -410.593562) (xy 285.633749 -410.585806) (xy 285.581454 -410.570451) (xy 285.531877 -410.547809)
			(xy 285.486027 -410.518343) (xy 285.444836 -410.482652) (xy 285.409145 -410.441461) (xy 285.379679 -410.395611)
			(xy 285.357037 -410.346034) (xy 285.341682 -410.293739) (xy 285.333926 -410.239791) (xy 285.33344 -410.21254)
			(xy 285.333867 -410.186709) (xy 285.34084 -410.13552) (xy 285.354662 -410.085742) (xy 285.375082 -410.038287)
			(xy 285.38805 -410.015944) (xy 285.394622 -410.004216) (xy 285.401979 -409.978368) (xy 285.402333 -409.951495)
			(xy 285.395659 -409.925462) (xy 285.382421 -409.902073) (xy 285.363536 -409.882952) (xy 285.340314 -409.869423)
			(xy 285.314366 -409.862426) (xy 285.300928 -409.86202) (xy 283.827728 -409.86202) (xy 283.814294 -409.862427)
			(xy 283.788355 -409.869431) (xy 283.765143 -409.882963) (xy 283.746267 -409.902083) (xy 283.733035 -409.925466)
			(xy 283.726363 -409.951493) (xy 283.726715 -409.978358) (xy 283.734066 -410.004201) (xy 283.740606 -410.015944)
			(xy 283.753556 -410.038297) (xy 283.773973 -410.08575) (xy 283.787799 -410.135525) (xy 283.79478 -410.18671)
			(xy 283.795216 -410.21254) (xy 283.79473 -410.239791) (xy 283.786974 -410.293739) (xy 283.771619 -410.346034)
			(xy 283.748977 -410.395611) (xy 283.719511 -410.441461) (xy 283.68382 -410.482652) (xy 283.642629 -410.518343)
			(xy 283.596779 -410.547809) (xy 283.547202 -410.570451) (xy 283.494907 -410.585806) (xy 283.440959 -410.593562)
			(xy 283.386457 -410.593562) (xy 283.332509 -410.585806) (xy 283.280214 -410.570451) (xy 283.230637 -410.547809)
			(xy 283.184787 -410.518343) (xy 283.143596 -410.482652) (xy 283.107905 -410.441461) (xy 283.078439 -410.395611)
			(xy 283.055797 -410.346034) (xy 283.040442 -410.293739) (xy 283.032686 -410.239791) (xy 283.0322 -410.21254)
			(xy 283.032777 -410.183304) (xy 283.041732 -410.125522) (xy 283.059393 -410.06978) (xy 283.085347 -410.017383)
			(xy 283.118986 -409.969556) (xy 283.13888 -409.948126) (xy 283.15285 -409.933394) (xy 283.15285 -409.86202)
			(xy 283.02966 -409.86202) (xy 282.26766 -410.62402) (xy 296.660822 -410.62402) (xy 296.664893 -410.568398)
			(xy 296.677019 -410.513961) (xy 296.696942 -410.46187) (xy 296.724238 -410.413235) (xy 296.758324 -410.369092)
			(xy 296.798473 -410.330383) (xy 296.843831 -410.297932) (xy 296.893431 -410.272431) (xy 296.946215 -410.254424)
			(xy 297.001058 -410.244294) (xy 297.056792 -410.242257) (xy 297.112229 -410.248357) (xy 297.166186 -410.262463)
			(xy 297.217515 -410.284275) (xy 297.265121 -410.313329) (xy 297.307989 -410.349004) (xy 297.326819 -410.37002)
			(xy 297.953682 -410.37002) (xy 297.957753 -410.314398) (xy 297.969879 -410.259961) (xy 297.989802 -410.20787)
			(xy 298.017098 -410.159235) (xy 298.051184 -410.115092) (xy 298.091333 -410.076383) (xy 298.136691 -410.043932)
			(xy 298.186291 -410.018431) (xy 298.239075 -410.000424) (xy 298.293918 -409.990294) (xy 298.349652 -409.988257)
			(xy 298.405089 -409.994357) (xy 298.459046 -410.008463) (xy 298.510375 -410.030275) (xy 298.557981 -410.059329)
			(xy 298.600849 -410.095004) (xy 298.638066 -410.136541) (xy 298.668839 -410.183054) (xy 298.692511 -410.233551)
			(xy 298.708579 -410.286958) (xy 298.716699 -410.342134) (xy 298.717208 -410.37002) (xy 298.716699 -410.397906)
			(xy 298.708579 -410.453082) (xy 298.692511 -410.506489) (xy 298.668839 -410.556986) (xy 298.638066 -410.603499)
			(xy 298.600849 -410.645036) (xy 298.557981 -410.680711) (xy 298.510375 -410.709765) (xy 298.459046 -410.731577)
			(xy 298.405089 -410.745683) (xy 298.349652 -410.751783) (xy 298.293918 -410.749746) (xy 298.239075 -410.739616)
			(xy 298.186291 -410.721609) (xy 298.136691 -410.696108) (xy 298.091333 -410.663657) (xy 298.051184 -410.624948)
			(xy 298.017098 -410.580805) (xy 297.989802 -410.53217) (xy 297.969879 -410.480079) (xy 297.957753 -410.425642)
			(xy 297.953682 -410.37002) (xy 297.326819 -410.37002) (xy 297.345206 -410.390541) (xy 297.375979 -410.437054)
			(xy 297.399651 -410.487551) (xy 297.415719 -410.540958) (xy 297.423839 -410.596134) (xy 297.424348 -410.62402)
			(xy 297.423839 -410.651906) (xy 297.415719 -410.707082) (xy 297.399651 -410.760489) (xy 297.375979 -410.810986)
			(xy 297.345206 -410.857499) (xy 297.307989 -410.899036) (xy 297.265121 -410.934711) (xy 297.217515 -410.963765)
			(xy 297.166186 -410.985577) (xy 297.112229 -410.999683) (xy 297.056792 -411.005783) (xy 297.001058 -411.003746)
			(xy 296.946215 -410.993616) (xy 296.893431 -410.975609) (xy 296.843831 -410.950108) (xy 296.798473 -410.917657)
			(xy 296.758324 -410.878948) (xy 296.724238 -410.834805) (xy 296.696942 -410.78617) (xy 296.677019 -410.734079)
			(xy 296.664893 -410.679642) (xy 296.660822 -410.62402) (xy 282.26766 -410.62402) (xy 281.67584 -411.21584)
			(xy 290.945822 -411.21584) (xy 290.949893 -411.160218) (xy 290.962019 -411.105781) (xy 290.981942 -411.05369)
			(xy 291.009238 -411.005055) (xy 291.043324 -410.960912) (xy 291.083473 -410.922203) (xy 291.128831 -410.889752)
			(xy 291.178431 -410.864251) (xy 291.231215 -410.846244) (xy 291.286058 -410.836114) (xy 291.341792 -410.834077)
			(xy 291.397229 -410.840177) (xy 291.451186 -410.854283) (xy 291.502515 -410.876095) (xy 291.550121 -410.905149)
			(xy 291.592989 -410.940824) (xy 291.630206 -410.982361) (xy 291.660979 -411.028874) (xy 291.684651 -411.079371)
			(xy 291.700719 -411.132778) (xy 291.708839 -411.187954) (xy 291.709348 -411.21584) (xy 291.708839 -411.243726)
			(xy 291.702103 -411.2895) (xy 293.757602 -411.2895) (xy 293.761673 -411.233878) (xy 293.773799 -411.179441)
			(xy 293.793722 -411.12735) (xy 293.821018 -411.078715) (xy 293.855104 -411.034572) (xy 293.895253 -410.995863)
			(xy 293.940611 -410.963412) (xy 293.990211 -410.937911) (xy 294.042995 -410.919904) (xy 294.097838 -410.909774)
			(xy 294.153572 -410.907737) (xy 294.209009 -410.913837) (xy 294.262966 -410.927943) (xy 294.314295 -410.949755)
			(xy 294.361901 -410.978809) (xy 294.404769 -411.014484) (xy 294.441986 -411.056021) (xy 294.472759 -411.102534)
			(xy 294.496431 -411.153031) (xy 294.512499 -411.206438) (xy 294.520619 -411.261614) (xy 294.521128 -411.2895)
			(xy 294.520619 -411.317386) (xy 294.512499 -411.372562) (xy 294.496431 -411.425969) (xy 294.472759 -411.476466)
			(xy 294.441986 -411.522979) (xy 294.404769 -411.564516) (xy 294.361901 -411.600191) (xy 294.314295 -411.629245)
			(xy 294.306871 -411.6324) (xy 295.266362 -411.6324) (xy 295.270433 -411.576778) (xy 295.282559 -411.522341)
			(xy 295.302482 -411.47025) (xy 295.329778 -411.421615) (xy 295.363864 -411.377472) (xy 295.404013 -411.338763)
			(xy 295.449371 -411.306312) (xy 295.498971 -411.280811) (xy 295.551755 -411.262804) (xy 295.606598 -411.252674)
			(xy 295.662332 -411.250637) (xy 295.717769 -411.256737) (xy 295.771726 -411.270843) (xy 295.823055 -411.292655)
			(xy 295.870661 -411.321709) (xy 295.913529 -411.357384) (xy 295.950746 -411.398921) (xy 295.981519 -411.445434)
			(xy 296.005191 -411.495931) (xy 296.021259 -411.549338) (xy 296.029379 -411.604514) (xy 296.029888 -411.6324)
			(xy 296.029379 -411.660286) (xy 296.021259 -411.715462) (xy 296.005191 -411.768869) (xy 295.981519 -411.819366)
			(xy 295.950746 -411.865879) (xy 295.913529 -411.907416) (xy 295.870661 -411.943091) (xy 295.823055 -411.972145)
			(xy 295.771726 -411.993957) (xy 295.717769 -412.008063) (xy 295.662332 -412.014163) (xy 295.606598 -412.012126)
			(xy 295.551755 -412.001996) (xy 295.498971 -411.983989) (xy 295.449371 -411.958488) (xy 295.404013 -411.926037)
			(xy 295.363864 -411.887328) (xy 295.329778 -411.843185) (xy 295.302482 -411.79455) (xy 295.282559 -411.742459)
			(xy 295.270433 -411.688022) (xy 295.266362 -411.6324) (xy 294.306871 -411.6324) (xy 294.262966 -411.651057)
			(xy 294.209009 -411.665163) (xy 294.153572 -411.671263) (xy 294.097838 -411.669226) (xy 294.042995 -411.659096)
			(xy 293.990211 -411.641089) (xy 293.940611 -411.615588) (xy 293.895253 -411.583137) (xy 293.855104 -411.544428)
			(xy 293.821018 -411.500285) (xy 293.793722 -411.45165) (xy 293.773799 -411.399559) (xy 293.761673 -411.345122)
			(xy 293.757602 -411.2895) (xy 291.702103 -411.2895) (xy 291.700719 -411.298902) (xy 291.684651 -411.352309)
			(xy 291.660979 -411.402806) (xy 291.630206 -411.449319) (xy 291.592989 -411.490856) (xy 291.550121 -411.526531)
			(xy 291.502515 -411.555585) (xy 291.451186 -411.577397) (xy 291.397229 -411.591503) (xy 291.341792 -411.597603)
			(xy 291.286058 -411.595566) (xy 291.231215 -411.585436) (xy 291.178431 -411.567429) (xy 291.128831 -411.541928)
			(xy 291.083473 -411.509477) (xy 291.043324 -411.470768) (xy 291.009238 -411.426625) (xy 290.981942 -411.37799)
			(xy 290.962019 -411.325899) (xy 290.949893 -411.271462) (xy 290.945822 -411.21584) (xy 281.67584 -411.21584)
			(xy 281.5082 -411.38348) (xy 281.5082 -412.86684) (xy 283.38272 -412.86684) (xy 283.383206 -412.839589)
			(xy 283.390962 -412.785641) (xy 283.406317 -412.733346) (xy 283.428959 -412.683769) (xy 283.458425 -412.637919)
			(xy 283.494116 -412.596728) (xy 283.535307 -412.561037) (xy 283.581157 -412.531571) (xy 283.630734 -412.508929)
			(xy 283.683029 -412.493574) (xy 283.736977 -412.485818) (xy 283.791479 -412.485818) (xy 283.845427 -412.493574)
			(xy 283.897722 -412.508929) (xy 283.947299 -412.531571) (xy 283.993149 -412.561037) (xy 284.03434 -412.596728)
			(xy 284.070031 -412.637919) (xy 284.099497 -412.683769) (xy 284.122139 -412.733346) (xy 284.137494 -412.785641)
			(xy 284.14525 -412.839589) (xy 284.145736 -412.86684) (xy 284.145275 -412.893992) (xy 284.137557 -412.947746)
			(xy 284.122299 -412.999863) (xy 284.099807 -413.049292) (xy 284.070536 -413.095033) (xy 284.035077 -413.136163)
			(xy 284.014926 -413.154368) (xy 284.005015 -413.16352) (xy 283.990064 -413.185966) (xy 283.981518 -413.211546)
			(xy 283.979973 -413.238471) (xy 283.985538 -413.26486) (xy 283.997824 -413.288869) (xy 284.015972 -413.308819)
			(xy 284.027118 -413.31642) (xy 284.049827 -413.331576) (xy 284.091135 -413.367269) (xy 284.126935 -413.408486)
			(xy 284.156496 -413.454384) (xy 284.179214 -413.504026) (xy 284.194625 -413.556399) (xy 284.202415 -413.610433)
			(xy 284.202886 -413.63773) (xy 284.2024 -413.664981) (xy 284.194644 -413.718929) (xy 284.187535 -413.74314)
			(xy 292.29126 -413.74314) (xy 292.295331 -413.687518) (xy 292.307457 -413.633081) (xy 292.32738 -413.58099)
			(xy 292.354676 -413.532355) (xy 292.388762 -413.488212) (xy 292.428911 -413.449503) (xy 292.474269 -413.417052)
			(xy 292.523869 -413.391551) (xy 292.576653 -413.373544) (xy 292.631496 -413.363414) (xy 292.68723 -413.361377)
			(xy 292.742667 -413.367477) (xy 292.796624 -413.381583) (xy 292.847953 -413.403395) (xy 292.895559 -413.432449)
			(xy 292.938427 -413.468124) (xy 292.975644 -413.509661) (xy 293.006417 -413.556174) (xy 293.030089 -413.606671)
			(xy 293.046157 -413.660078) (xy 293.054277 -413.715254) (xy 293.054415 -413.72282) (xy 295.484802 -413.72282)
			(xy 295.488873 -413.667198) (xy 295.500999 -413.612761) (xy 295.520922 -413.56067) (xy 295.548218 -413.512035)
			(xy 295.582304 -413.467892) (xy 295.622453 -413.429183) (xy 295.667811 -413.396732) (xy 295.717411 -413.371231)
			(xy 295.770195 -413.353224) (xy 295.825038 -413.343094) (xy 295.880772 -413.341057) (xy 295.936209 -413.347157)
			(xy 295.990166 -413.361263) (xy 296.041495 -413.383075) (xy 296.089101 -413.412129) (xy 296.131969 -413.447804)
			(xy 296.169186 -413.489341) (xy 296.199959 -413.535854) (xy 296.223631 -413.586351) (xy 296.239699 -413.639758)
			(xy 296.247819 -413.694934) (xy 296.248328 -413.72282) (xy 296.247819 -413.750706) (xy 296.239699 -413.805882)
			(xy 296.223631 -413.859289) (xy 296.199959 -413.909786) (xy 296.169186 -413.956299) (xy 296.131969 -413.997836)
			(xy 296.089101 -414.033511) (xy 296.041495 -414.062565) (xy 295.990166 -414.084377) (xy 295.936209 -414.098483)
			(xy 295.880772 -414.104583) (xy 295.825038 -414.102546) (xy 295.770195 -414.092416) (xy 295.717411 -414.074409)
			(xy 295.667811 -414.048908) (xy 295.622453 -414.016457) (xy 295.582304 -413.977748) (xy 295.548218 -413.933605)
			(xy 295.520922 -413.88497) (xy 295.500999 -413.832879) (xy 295.488873 -413.778442) (xy 295.484802 -413.72282)
			(xy 293.054415 -413.72282) (xy 293.054786 -413.74314) (xy 293.054277 -413.771026) (xy 293.046157 -413.826202)
			(xy 293.030089 -413.879609) (xy 293.006417 -413.930106) (xy 292.975644 -413.976619) (xy 292.938427 -414.018156)
			(xy 292.895559 -414.053831) (xy 292.847953 -414.082885) (xy 292.796624 -414.104697) (xy 292.742667 -414.118803)
			(xy 292.68723 -414.124903) (xy 292.631496 -414.122866) (xy 292.576653 -414.112736) (xy 292.523869 -414.094729)
			(xy 292.474269 -414.069228) (xy 292.428911 -414.036777) (xy 292.388762 -413.998068) (xy 292.354676 -413.953925)
			(xy 292.32738 -413.90529) (xy 292.307457 -413.853199) (xy 292.295331 -413.798762) (xy 292.29126 -413.74314)
			(xy 284.187535 -413.74314) (xy 284.179289 -413.771224) (xy 284.156647 -413.820801) (xy 284.127181 -413.866651)
			(xy 284.09149 -413.907842) (xy 284.050299 -413.943533) (xy 284.004449 -413.972999) (xy 283.954872 -413.995641)
			(xy 283.902577 -414.010996) (xy 283.848629 -414.018752) (xy 283.794127 -414.018752) (xy 283.740179 -414.010996)
			(xy 283.687884 -413.995641) (xy 283.638307 -413.972999) (xy 283.592457 -413.943533) (xy 283.551266 -413.907842)
			(xy 283.515575 -413.866651) (xy 283.486109 -413.820801) (xy 283.463467 -413.771224) (xy 283.448112 -413.718929)
			(xy 283.440356 -413.664981) (xy 283.43987 -413.63773) (xy 283.440377 -413.610579) (xy 283.448085 -413.556827)
			(xy 283.463334 -413.504711) (xy 283.485817 -413.455282) (xy 283.51508 -413.40954) (xy 283.550532 -413.368408)
			(xy 283.57068 -413.350202) (xy 283.580515 -413.340975) (xy 283.595467 -413.318547) (xy 283.604019 -413.292985)
			(xy 283.605574 -413.266076) (xy 283.600023 -413.239699) (xy 283.587754 -413.215698) (xy 283.569625 -413.195752)
			(xy 283.558488 -413.18815) (xy 283.535767 -413.173012) (xy 283.494458 -413.137316) (xy 283.458659 -413.096096)
			(xy 283.4291 -413.050195) (xy 283.406384 -413.00055) (xy 283.390975 -412.948175) (xy 283.383189 -412.894138)
			(xy 283.38272 -412.86684) (xy 281.5082 -412.86684) (xy 281.5082 -413.50565) (xy 282.402532 -413.50565)
			(xy 282.406603 -413.450028) (xy 282.418729 -413.395591) (xy 282.438652 -413.3435) (xy 282.465948 -413.294865)
			(xy 282.500034 -413.250722) (xy 282.540183 -413.212013) (xy 282.585541 -413.179562) (xy 282.635141 -413.154061)
			(xy 282.687925 -413.136054) (xy 282.742768 -413.125924) (xy 282.798502 -413.123887) (xy 282.853939 -413.129987)
			(xy 282.907896 -413.144093) (xy 282.959225 -413.165905) (xy 283.006831 -413.194959) (xy 283.049699 -413.230634)
			(xy 283.086916 -413.272171) (xy 283.117689 -413.318684) (xy 283.141361 -413.369181) (xy 283.157429 -413.422588)
			(xy 283.165549 -413.477764) (xy 283.166058 -413.50565) (xy 283.165549 -413.533536) (xy 283.157429 -413.588712)
			(xy 283.141361 -413.642119) (xy 283.117689 -413.692616) (xy 283.086916 -413.739129) (xy 283.049699 -413.780666)
			(xy 283.006831 -413.816341) (xy 282.959225 -413.845395) (xy 282.907896 -413.867207) (xy 282.853939 -413.881313)
			(xy 282.798502 -413.887413) (xy 282.742768 -413.885376) (xy 282.687925 -413.875246) (xy 282.635141 -413.857239)
			(xy 282.585541 -413.831738) (xy 282.540183 -413.799287) (xy 282.500034 -413.760578) (xy 282.465948 -413.716435)
			(xy 282.438652 -413.6678) (xy 282.418729 -413.615709) (xy 282.406603 -413.561272) (xy 282.402532 -413.50565)
			(xy 281.5082 -413.50565) (xy 281.5082 -414.36798) (xy 282.571442 -414.36798) (xy 282.575513 -414.312358)
			(xy 282.587639 -414.257921) (xy 282.607562 -414.20583) (xy 282.634858 -414.157195) (xy 282.668944 -414.113052)
			(xy 282.709093 -414.074343) (xy 282.754451 -414.041892) (xy 282.804051 -414.016391) (xy 282.856835 -413.998384)
			(xy 282.911678 -413.988254) (xy 282.967412 -413.986217) (xy 283.022849 -413.992317) (xy 283.076806 -414.006423)
			(xy 283.128135 -414.028235) (xy 283.175741 -414.057289) (xy 283.218609 -414.092964) (xy 283.255826 -414.134501)
			(xy 283.286599 -414.181014) (xy 283.310271 -414.231511) (xy 283.326339 -414.284918) (xy 283.334459 -414.340094)
			(xy 283.334968 -414.36798) (xy 283.334459 -414.395866) (xy 283.326339 -414.451042) (xy 283.310271 -414.504449)
			(xy 283.286599 -414.554946) (xy 283.255826 -414.601459) (xy 283.218609 -414.642996) (xy 283.175741 -414.678671)
			(xy 283.128135 -414.707725) (xy 283.076806 -414.729537) (xy 283.022849 -414.743643) (xy 282.967412 -414.749743)
			(xy 282.911678 -414.747706) (xy 282.856835 -414.737576) (xy 282.804051 -414.719569) (xy 282.754451 -414.694068)
			(xy 282.709093 -414.661617) (xy 282.668944 -414.622908) (xy 282.634858 -414.578765) (xy 282.607562 -414.53013)
			(xy 282.587639 -414.478039) (xy 282.575513 -414.423602) (xy 282.571442 -414.36798) (xy 281.5082 -414.36798)
			(xy 281.5082 -414.98266) (xy 304.824382 -414.98266) (xy 304.828453 -414.927038) (xy 304.840579 -414.872601)
			(xy 304.860502 -414.82051) (xy 304.887798 -414.771875) (xy 304.921884 -414.727732) (xy 304.962033 -414.689023)
			(xy 305.007391 -414.656572) (xy 305.056991 -414.631071) (xy 305.109775 -414.613064) (xy 305.164618 -414.602934)
			(xy 305.220352 -414.600897) (xy 305.275789 -414.606997) (xy 305.329746 -414.621103) (xy 305.381075 -414.642915)
			(xy 305.428681 -414.671969) (xy 305.471549 -414.707644) (xy 305.508766 -414.749181) (xy 305.539539 -414.795694)
			(xy 305.563211 -414.846191) (xy 305.579279 -414.899598) (xy 305.587399 -414.954774) (xy 305.587908 -414.98266)
			(xy 305.587399 -415.010546) (xy 305.579279 -415.065722) (xy 305.563211 -415.119129) (xy 305.539539 -415.169626)
			(xy 305.508766 -415.216139) (xy 305.471549 -415.257676) (xy 305.428681 -415.293351) (xy 305.381075 -415.322405)
			(xy 305.329746 -415.344217) (xy 305.275789 -415.358323) (xy 305.220352 -415.364423) (xy 305.164618 -415.362386)
			(xy 305.109775 -415.352256) (xy 305.056991 -415.334249) (xy 305.007391 -415.308748) (xy 304.962033 -415.276297)
			(xy 304.921884 -415.237588) (xy 304.887798 -415.193445) (xy 304.860502 -415.14481) (xy 304.840579 -415.092719)
			(xy 304.828453 -415.038282) (xy 304.824382 -414.98266) (xy 281.5082 -414.98266) (xy 281.5082 -415.37382)
			(xy 280.96718 -415.91484) (xy 276.97684 -415.91484) (xy 275.86686 -417.02482) (xy 276.170642 -417.02482)
			(xy 276.174713 -416.969198) (xy 276.186839 -416.914761) (xy 276.206762 -416.86267) (xy 276.234058 -416.814035)
			(xy 276.268144 -416.769892) (xy 276.308293 -416.731183) (xy 276.353651 -416.698732) (xy 276.403251 -416.673231)
			(xy 276.456035 -416.655224) (xy 276.510878 -416.645094) (xy 276.566612 -416.643057) (xy 276.622049 -416.649157)
			(xy 276.676006 -416.663263) (xy 276.727335 -416.685075) (xy 276.774941 -416.714129) (xy 276.817809 -416.749804)
			(xy 276.855026 -416.791341) (xy 276.885799 -416.837854) (xy 276.907361 -416.88385) (xy 280.663902 -416.88385)
			(xy 280.667973 -416.828228) (xy 280.680099 -416.773791) (xy 280.700022 -416.7217) (xy 280.727318 -416.673065)
			(xy 280.761404 -416.628922) (xy 280.801553 -416.590213) (xy 280.846911 -416.557762) (xy 280.896511 -416.532261)
			(xy 280.949295 -416.514254) (xy 281.004138 -416.504124) (xy 281.059872 -416.502087) (xy 281.115309 -416.508187)
			(xy 281.169266 -416.522293) (xy 281.220595 -416.544105) (xy 281.24664 -416.56) (xy 300.861982 -416.56)
			(xy 300.866053 -416.504378) (xy 300.878179 -416.449941) (xy 300.898102 -416.39785) (xy 300.925398 -416.349215)
			(xy 300.959484 -416.305072) (xy 300.999633 -416.266363) (xy 301.044991 -416.233912) (xy 301.094591 -416.208411)
			(xy 301.147375 -416.190404) (xy 301.202218 -416.180274) (xy 301.257952 -416.178237) (xy 301.313389 -416.184337)
			(xy 301.367346 -416.198443) (xy 301.418675 -416.220255) (xy 301.466281 -416.249309) (xy 301.509149 -416.284984)
			(xy 301.546366 -416.326521) (xy 301.577139 -416.373034) (xy 301.600811 -416.423531) (xy 301.616879 -416.476938)
			(xy 301.624999 -416.532114) (xy 301.625508 -416.56) (xy 301.624999 -416.587886) (xy 301.616879 -416.643062)
			(xy 301.600811 -416.696469) (xy 301.577139 -416.746966) (xy 301.546366 -416.793479) (xy 301.509149 -416.835016)
			(xy 301.466281 -416.870691) (xy 301.418675 -416.899745) (xy 301.367346 -416.921557) (xy 301.313389 -416.935663)
			(xy 301.257952 -416.941763) (xy 301.202218 -416.939726) (xy 301.147375 -416.929596) (xy 301.094591 -416.911589)
			(xy 301.044991 -416.886088) (xy 300.999633 -416.853637) (xy 300.959484 -416.814928) (xy 300.925398 -416.770785)
			(xy 300.898102 -416.72215) (xy 300.878179 -416.670059) (xy 300.866053 -416.615622) (xy 300.861982 -416.56)
			(xy 281.24664 -416.56) (xy 281.268201 -416.573159) (xy 281.311069 -416.608834) (xy 281.348286 -416.650371)
			(xy 281.379059 -416.696884) (xy 281.402731 -416.747381) (xy 281.418799 -416.800788) (xy 281.426919 -416.855964)
			(xy 281.427428 -416.88385) (xy 281.426919 -416.911736) (xy 281.418799 -416.966912) (xy 281.402731 -417.020319)
			(xy 281.379059 -417.070816) (xy 281.348286 -417.117329) (xy 281.311069 -417.158866) (xy 281.268201 -417.194541)
			(xy 281.22583 -417.2204) (xy 293.832532 -417.2204) (xy 293.836603 -417.164778) (xy 293.848729 -417.110341)
			(xy 293.868652 -417.05825) (xy 293.895948 -417.009615) (xy 293.930034 -416.965472) (xy 293.970183 -416.926763)
			(xy 294.015541 -416.894312) (xy 294.065141 -416.868811) (xy 294.117925 -416.850804) (xy 294.172768 -416.840674)
			(xy 294.228502 -416.838637) (xy 294.283939 -416.844737) (xy 294.337896 -416.858843) (xy 294.389225 -416.880655)
			(xy 294.436831 -416.909709) (xy 294.479699 -416.945384) (xy 294.516916 -416.986921) (xy 294.547689 -417.033434)
			(xy 294.571361 -417.083931) (xy 294.587429 -417.137338) (xy 294.595549 -417.192514) (xy 294.596058 -417.2204)
			(xy 296.626532 -417.2204) (xy 296.630603 -417.164778) (xy 296.642729 -417.110341) (xy 296.662652 -417.05825)
			(xy 296.689948 -417.009615) (xy 296.724034 -416.965472) (xy 296.764183 -416.926763) (xy 296.809541 -416.894312)
			(xy 296.859141 -416.868811) (xy 296.911925 -416.850804) (xy 296.966768 -416.840674) (xy 297.022502 -416.838637)
			(xy 297.077939 -416.844737) (xy 297.131896 -416.858843) (xy 297.183225 -416.880655) (xy 297.230831 -416.909709)
			(xy 297.273699 -416.945384) (xy 297.310916 -416.986921) (xy 297.341689 -417.033434) (xy 297.365361 -417.083931)
			(xy 297.381429 -417.137338) (xy 297.389549 -417.192514) (xy 297.390058 -417.2204) (xy 299.420532 -417.2204)
			(xy 299.424603 -417.164778) (xy 299.436729 -417.110341) (xy 299.456652 -417.05825) (xy 299.483948 -417.009615)
			(xy 299.518034 -416.965472) (xy 299.558183 -416.926763) (xy 299.603541 -416.894312) (xy 299.653141 -416.868811)
			(xy 299.705925 -416.850804) (xy 299.760768 -416.840674) (xy 299.816502 -416.838637) (xy 299.871939 -416.844737)
			(xy 299.925896 -416.858843) (xy 299.977225 -416.880655) (xy 300.024831 -416.909709) (xy 300.067699 -416.945384)
			(xy 300.104916 -416.986921) (xy 300.135689 -417.033434) (xy 300.159361 -417.083931) (xy 300.175429 -417.137338)
			(xy 300.183549 -417.192514) (xy 300.184058 -417.2204) (xy 300.183549 -417.248286) (xy 300.176065 -417.29914)
			(xy 302.105312 -417.29914) (xy 302.109383 -417.243518) (xy 302.121509 -417.189081) (xy 302.141432 -417.13699)
			(xy 302.168728 -417.088355) (xy 302.202814 -417.044212) (xy 302.242963 -417.005503) (xy 302.288321 -416.973052)
			(xy 302.337921 -416.947551) (xy 302.390705 -416.929544) (xy 302.445548 -416.919414) (xy 302.501282 -416.917377)
			(xy 302.556719 -416.923477) (xy 302.610676 -416.937583) (xy 302.662005 -416.959395) (xy 302.709611 -416.988449)
			(xy 302.752479 -417.024124) (xy 302.789696 -417.065661) (xy 302.820469 -417.112174) (xy 302.844141 -417.162671)
			(xy 302.860209 -417.216078) (xy 302.868329 -417.271254) (xy 302.868838 -417.29914) (xy 302.868329 -417.327026)
			(xy 302.860209 -417.382202) (xy 302.844141 -417.435609) (xy 302.820469 -417.486106) (xy 302.789696 -417.532619)
			(xy 302.752479 -417.574156) (xy 302.709611 -417.609831) (xy 302.662005 -417.638885) (xy 302.610676 -417.660697)
			(xy 302.556719 -417.674803) (xy 302.501282 -417.680903) (xy 302.445548 -417.678866) (xy 302.390705 -417.668736)
			(xy 302.337921 -417.650729) (xy 302.288321 -417.625228) (xy 302.242963 -417.592777) (xy 302.202814 -417.554068)
			(xy 302.168728 -417.509925) (xy 302.141432 -417.46129) (xy 302.121509 -417.409199) (xy 302.109383 -417.354762)
			(xy 302.105312 -417.29914) (xy 300.176065 -417.29914) (xy 300.175429 -417.303462) (xy 300.159361 -417.356869)
			(xy 300.135689 -417.407366) (xy 300.104916 -417.453879) (xy 300.067699 -417.495416) (xy 300.024831 -417.531091)
			(xy 299.977225 -417.560145) (xy 299.925896 -417.581957) (xy 299.871939 -417.596063) (xy 299.816502 -417.602163)
			(xy 299.760768 -417.600126) (xy 299.705925 -417.589996) (xy 299.653141 -417.571989) (xy 299.603541 -417.546488)
			(xy 299.558183 -417.514037) (xy 299.518034 -417.475328) (xy 299.483948 -417.431185) (xy 299.456652 -417.38255)
			(xy 299.436729 -417.330459) (xy 299.424603 -417.276022) (xy 299.420532 -417.2204) (xy 297.390058 -417.2204)
			(xy 297.389549 -417.248286) (xy 297.381429 -417.303462) (xy 297.365361 -417.356869) (xy 297.341689 -417.407366)
			(xy 297.310916 -417.453879) (xy 297.273699 -417.495416) (xy 297.230831 -417.531091) (xy 297.183225 -417.560145)
			(xy 297.131896 -417.581957) (xy 297.077939 -417.596063) (xy 297.022502 -417.602163) (xy 296.966768 -417.600126)
			(xy 296.911925 -417.589996) (xy 296.859141 -417.571989) (xy 296.809541 -417.546488) (xy 296.764183 -417.514037)
			(xy 296.724034 -417.475328) (xy 296.689948 -417.431185) (xy 296.662652 -417.38255) (xy 296.642729 -417.330459)
			(xy 296.630603 -417.276022) (xy 296.626532 -417.2204) (xy 294.596058 -417.2204) (xy 294.595549 -417.248286)
			(xy 294.587429 -417.303462) (xy 294.571361 -417.356869) (xy 294.547689 -417.407366) (xy 294.516916 -417.453879)
			(xy 294.479699 -417.495416) (xy 294.436831 -417.531091) (xy 294.389225 -417.560145) (xy 294.337896 -417.581957)
			(xy 294.283939 -417.596063) (xy 294.228502 -417.602163) (xy 294.172768 -417.600126) (xy 294.117925 -417.589996)
			(xy 294.065141 -417.571989) (xy 294.015541 -417.546488) (xy 293.970183 -417.514037) (xy 293.930034 -417.475328)
			(xy 293.895948 -417.431185) (xy 293.868652 -417.38255) (xy 293.848729 -417.330459) (xy 293.836603 -417.276022)
			(xy 293.832532 -417.2204) (xy 281.22583 -417.2204) (xy 281.220595 -417.223595) (xy 281.169266 -417.245407)
			(xy 281.115309 -417.259513) (xy 281.059872 -417.265613) (xy 281.004138 -417.263576) (xy 280.949295 -417.253446)
			(xy 280.896511 -417.235439) (xy 280.846911 -417.209938) (xy 280.801553 -417.177487) (xy 280.761404 -417.138778)
			(xy 280.727318 -417.094635) (xy 280.700022 -417.046) (xy 280.680099 -416.993909) (xy 280.667973 -416.939472)
			(xy 280.663902 -416.88385) (xy 276.907361 -416.88385) (xy 276.909471 -416.888351) (xy 276.925539 -416.941758)
			(xy 276.933659 -416.996934) (xy 276.934168 -417.02482) (xy 276.933659 -417.052706) (xy 276.925539 -417.107882)
			(xy 276.909471 -417.161289) (xy 276.885799 -417.211786) (xy 276.855026 -417.258299) (xy 276.817809 -417.299836)
			(xy 276.774941 -417.335511) (xy 276.727335 -417.364565) (xy 276.676006 -417.386377) (xy 276.622049 -417.400483)
			(xy 276.566612 -417.406583) (xy 276.510878 -417.404546) (xy 276.456035 -417.394416) (xy 276.403251 -417.376409)
			(xy 276.353651 -417.350908) (xy 276.308293 -417.318457) (xy 276.268144 -417.279748) (xy 276.234058 -417.235605)
			(xy 276.206762 -417.18697) (xy 276.186839 -417.134879) (xy 276.174713 -417.080442) (xy 276.170642 -417.02482)
			(xy 275.86686 -417.02482) (xy 274.52574 -418.36594) (xy 274.953982 -418.36594) (xy 274.958053 -418.310318)
			(xy 274.970179 -418.255881) (xy 274.990102 -418.20379) (xy 275.017398 -418.155155) (xy 275.051484 -418.111012)
			(xy 275.091633 -418.072303) (xy 275.136991 -418.039852) (xy 275.186591 -418.014351) (xy 275.239375 -417.996344)
			(xy 275.294218 -417.986214) (xy 275.349952 -417.984177) (xy 275.405389 -417.990277) (xy 275.459346 -418.004383)
			(xy 275.510675 -418.026195) (xy 275.558281 -418.055249) (xy 275.601149 -418.090924) (xy 275.638366 -418.132461)
			(xy 275.669139 -418.178974) (xy 275.692811 -418.229471) (xy 275.708879 -418.282878) (xy 275.716999 -418.338054)
			(xy 275.717508 -418.36594) (xy 275.716999 -418.393826) (xy 275.708879 -418.449002) (xy 275.692811 -418.502409)
			(xy 275.669139 -418.552906) (xy 275.638366 -418.599419) (xy 275.601149 -418.640956) (xy 275.558281 -418.676631)
			(xy 275.510675 -418.705685) (xy 275.459346 -418.727497) (xy 275.405389 -418.741603) (xy 275.349952 -418.747703)
			(xy 275.294218 -418.745666) (xy 275.239375 -418.735536) (xy 275.186591 -418.717529) (xy 275.136991 -418.692028)
			(xy 275.091633 -418.659577) (xy 275.051484 -418.620868) (xy 275.017398 -418.576725) (xy 274.990102 -418.52809)
			(xy 274.970179 -418.475999) (xy 274.958053 -418.421562) (xy 274.953982 -418.36594) (xy 274.52574 -418.36594)
			(xy 272.587954 -420.303726) (xy 294.241205 -420.303726) (xy 294.241208 -420.249228) (xy 294.248967 -420.195285)
			(xy 294.264324 -420.142996) (xy 294.286966 -420.093424) (xy 294.316433 -420.047578) (xy 294.352124 -420.006393)
			(xy 294.393313 -419.970707) (xy 294.439161 -419.941246) (xy 294.488736 -419.918609) (xy 294.541027 -419.903258)
			(xy 294.594971 -419.895505) (xy 294.62222 -419.89502) (xy 294.651656 -419.895588) (xy 294.70983 -419.90464)
			(xy 294.738044 -419.913054) (xy 294.752364 -419.917131) (xy 294.78212 -419.917649) (xy 294.810762 -419.909563)
			(xy 294.835856 -419.893561) (xy 294.855268 -419.871002) (xy 294.867349 -419.843803) (xy 294.871073 -419.814275)
			(xy 294.869108 -419.799516) (xy 294.866618 -419.783823) (xy 294.863947 -419.752158) (xy 294.863774 -419.73627)
			(xy 294.86426 -419.709019) (xy 294.872016 -419.655071) (xy 294.887371 -419.602776) (xy 294.910013 -419.553199)
			(xy 294.939479 -419.507349) (xy 294.97517 -419.466158) (xy 295.016361 -419.430467) (xy 295.062211 -419.401001)
			(xy 295.111788 -419.378359) (xy 295.164083 -419.363004) (xy 295.218031 -419.355248) (xy 295.272533 -419.355248)
			(xy 295.326481 -419.363004) (xy 295.378776 -419.378359) (xy 295.428353 -419.401001) (xy 295.474203 -419.430467)
			(xy 295.515394 -419.466158) (xy 295.551085 -419.507349) (xy 295.580551 -419.553199) (xy 295.603193 -419.602776)
			(xy 295.618548 -419.655071) (xy 295.626304 -419.709019) (xy 295.62679 -419.73627) (xy 295.626653 -419.752026)
			(xy 295.624109 -419.783435) (xy 295.62171 -419.799008) (xy 295.619819 -419.813724) (xy 295.62353 -419.843142)
			(xy 295.635546 -419.87025) (xy 295.654851 -419.892757) (xy 295.679813 -419.90876) (xy 295.708323 -419.916908)
			(xy 295.737972 -419.916513) (xy 295.752266 -419.912546) (xy 295.780195 -419.904361) (xy 295.837721 -419.895552)
			(xy 295.86682 -419.89502) (xy 295.894069 -419.8955) (xy 295.948012 -419.903258) (xy 296.000302 -419.918614)
			(xy 296.049874 -419.941256) (xy 296.09572 -419.970721) (xy 296.136906 -420.006411) (xy 296.172593 -420.047599)
			(xy 296.202056 -420.093447) (xy 296.224694 -420.143021) (xy 296.240047 -420.195311) (xy 296.247802 -420.249255)
			(xy 296.247802 -420.303726) (xy 297.035205 -420.303726) (xy 297.035208 -420.249228) (xy 297.042967 -420.195285)
			(xy 297.058324 -420.142996) (xy 297.080966 -420.093424) (xy 297.110433 -420.047578) (xy 297.146124 -420.006393)
			(xy 297.187313 -419.970707) (xy 297.233161 -419.941246) (xy 297.282736 -419.918609) (xy 297.335027 -419.903258)
			(xy 297.388971 -419.895505) (xy 297.41622 -419.89502) (xy 297.445656 -419.895588) (xy 297.50383 -419.90464)
			(xy 297.532044 -419.913054) (xy 297.546364 -419.917131) (xy 297.57612 -419.917649) (xy 297.604762 -419.909563)
			(xy 297.629856 -419.893561) (xy 297.649268 -419.871002) (xy 297.661349 -419.843803) (xy 297.665073 -419.814275)
			(xy 297.663108 -419.799516) (xy 297.660618 -419.783823) (xy 297.657947 -419.752158) (xy 297.657774 -419.73627)
			(xy 297.65826 -419.709019) (xy 297.666016 -419.655071) (xy 297.681371 -419.602776) (xy 297.704013 -419.553199)
			(xy 297.733479 -419.507349) (xy 297.76917 -419.466158) (xy 297.810361 -419.430467) (xy 297.856211 -419.401001)
			(xy 297.905788 -419.378359) (xy 297.958083 -419.363004) (xy 298.012031 -419.355248) (xy 298.066533 -419.355248)
			(xy 298.120481 -419.363004) (xy 298.172776 -419.378359) (xy 298.222353 -419.401001) (xy 298.268203 -419.430467)
			(xy 298.309394 -419.466158) (xy 298.345085 -419.507349) (xy 298.374551 -419.553199) (xy 298.397193 -419.602776)
			(xy 298.412548 -419.655071) (xy 298.420304 -419.709019) (xy 298.42079 -419.73627) (xy 298.420653 -419.752026)
			(xy 298.418109 -419.783435) (xy 298.41571 -419.799008) (xy 298.413819 -419.813724) (xy 298.41753 -419.843142)
			(xy 298.429546 -419.87025) (xy 298.448851 -419.892757) (xy 298.473813 -419.90876) (xy 298.502323 -419.916908)
			(xy 298.531972 -419.916513) (xy 298.546266 -419.912546) (xy 298.574195 -419.904361) (xy 298.631721 -419.895552)
			(xy 298.66082 -419.89502) (xy 298.688069 -419.8955) (xy 298.742012 -419.903258) (xy 298.794302 -419.918614)
			(xy 298.843874 -419.941256) (xy 298.88972 -419.970721) (xy 298.930906 -420.006411) (xy 298.966593 -420.047599)
			(xy 298.996056 -420.093447) (xy 299.018694 -420.143021) (xy 299.034047 -420.195311) (xy 299.041802 -420.249255)
			(xy 299.041802 -420.303726) (xy 299.829205 -420.303726) (xy 299.829208 -420.249228) (xy 299.836967 -420.195285)
			(xy 299.852324 -420.142996) (xy 299.874966 -420.093424) (xy 299.904433 -420.047578) (xy 299.940124 -420.006393)
			(xy 299.981313 -419.970707) (xy 300.027161 -419.941246) (xy 300.076736 -419.918609) (xy 300.129027 -419.903258)
			(xy 300.182971 -419.895505) (xy 300.21022 -419.89502) (xy 300.239656 -419.895588) (xy 300.29783 -419.90464)
			(xy 300.326044 -419.913054) (xy 300.340364 -419.917131) (xy 300.37012 -419.917649) (xy 300.398762 -419.909563)
			(xy 300.423856 -419.893561) (xy 300.443268 -419.871002) (xy 300.455349 -419.843803) (xy 300.459073 -419.814275)
			(xy 300.457108 -419.799516) (xy 300.454618 -419.783823) (xy 300.451947 -419.752158) (xy 300.451774 -419.73627)
			(xy 300.45226 -419.709019) (xy 300.460016 -419.655071) (xy 300.475371 -419.602776) (xy 300.498013 -419.553199)
			(xy 300.527479 -419.507349) (xy 300.56317 -419.466158) (xy 300.604361 -419.430467) (xy 300.650211 -419.401001)
			(xy 300.699788 -419.378359) (xy 300.752083 -419.363004) (xy 300.806031 -419.355248) (xy 300.860533 -419.355248)
			(xy 300.914481 -419.363004) (xy 300.966776 -419.378359) (xy 301.016353 -419.401001) (xy 301.062203 -419.430467)
			(xy 301.103394 -419.466158) (xy 301.139085 -419.507349) (xy 301.168551 -419.553199) (xy 301.191193 -419.602776)
			(xy 301.206548 -419.655071) (xy 301.214304 -419.709019) (xy 301.21479 -419.73627) (xy 301.214653 -419.752026)
			(xy 301.212109 -419.783435) (xy 301.20971 -419.799008) (xy 301.207819 -419.813724) (xy 301.211025 -419.83914)
			(xy 305.896262 -419.83914) (xy 305.900333 -419.783518) (xy 305.912459 -419.729081) (xy 305.932382 -419.67699)
			(xy 305.959678 -419.628355) (xy 305.993764 -419.584212) (xy 306.033913 -419.545503) (xy 306.079271 -419.513052)
			(xy 306.128871 -419.487551) (xy 306.181655 -419.469544) (xy 306.236498 -419.459414) (xy 306.292232 -419.457377)
			(xy 306.347669 -419.463477) (xy 306.401626 -419.477583) (xy 306.452955 -419.499395) (xy 306.500561 -419.528449)
			(xy 306.543429 -419.564124) (xy 306.580646 -419.605661) (xy 306.611419 -419.652174) (xy 306.635091 -419.702671)
			(xy 306.651159 -419.756078) (xy 306.659279 -419.811254) (xy 306.659788 -419.83914) (xy 306.659279 -419.867026)
			(xy 306.651159 -419.922202) (xy 306.635091 -419.975609) (xy 306.611419 -420.026106) (xy 306.580646 -420.072619)
			(xy 306.543429 -420.114156) (xy 306.500561 -420.149831) (xy 306.452955 -420.178885) (xy 306.401626 -420.200697)
			(xy 306.347669 -420.214803) (xy 306.292232 -420.220903) (xy 306.236498 -420.218866) (xy 306.181655 -420.208736)
			(xy 306.128871 -420.190729) (xy 306.079271 -420.165228) (xy 306.033913 -420.132777) (xy 305.993764 -420.094068)
			(xy 305.959678 -420.049925) (xy 305.932382 -420.00129) (xy 305.912459 -419.949199) (xy 305.900333 -419.894762)
			(xy 305.896262 -419.83914) (xy 301.211025 -419.83914) (xy 301.21153 -419.843142) (xy 301.223546 -419.87025)
			(xy 301.242851 -419.892757) (xy 301.267813 -419.90876) (xy 301.296323 -419.916908) (xy 301.325972 -419.916513)
			(xy 301.340266 -419.912546) (xy 301.368195 -419.904361) (xy 301.425721 -419.895552) (xy 301.45482 -419.89502)
			(xy 301.482069 -419.8955) (xy 301.536012 -419.903258) (xy 301.588302 -419.918614) (xy 301.637874 -419.941256)
			(xy 301.68372 -419.970721) (xy 301.724906 -420.006411) (xy 301.760593 -420.047599) (xy 301.790056 -420.093447)
			(xy 301.812694 -420.143021) (xy 301.828047 -420.195311) (xy 301.835802 -420.249255) (xy 301.835802 -420.303753)
			(xy 301.828394 -420.355268) (xy 302.512982 -420.355268) (xy 302.517053 -420.299646) (xy 302.529179 -420.245209)
			(xy 302.549102 -420.193118) (xy 302.576398 -420.144483) (xy 302.610484 -420.10034) (xy 302.650633 -420.061631)
			(xy 302.695991 -420.02918) (xy 302.745591 -420.003679) (xy 302.798375 -419.985672) (xy 302.853218 -419.975542)
			(xy 302.908952 -419.973505) (xy 302.964389 -419.979605) (xy 303.018346 -419.993711) (xy 303.069675 -420.015523)
			(xy 303.117281 -420.044577) (xy 303.160149 -420.080252) (xy 303.197366 -420.121789) (xy 303.228139 -420.168302)
			(xy 303.251811 -420.218799) (xy 303.267879 -420.272206) (xy 303.275999 -420.327382) (xy 303.276508 -420.355268)
			(xy 303.757582 -420.355268) (xy 303.761653 -420.299646) (xy 303.773779 -420.245209) (xy 303.793702 -420.193118)
			(xy 303.820998 -420.144483) (xy 303.855084 -420.10034) (xy 303.895233 -420.061631) (xy 303.940591 -420.02918)
			(xy 303.990191 -420.003679) (xy 304.042975 -419.985672) (xy 304.097818 -419.975542) (xy 304.153552 -419.973505)
			(xy 304.208989 -419.979605) (xy 304.262946 -419.993711) (xy 304.314275 -420.015523) (xy 304.361881 -420.044577)
			(xy 304.404749 -420.080252) (xy 304.441966 -420.121789) (xy 304.472739 -420.168302) (xy 304.496411 -420.218799)
			(xy 304.512479 -420.272206) (xy 304.520599 -420.327382) (xy 304.521108 -420.355268) (xy 304.520599 -420.383154)
			(xy 304.512479 -420.43833) (xy 304.496411 -420.491737) (xy 304.472739 -420.542234) (xy 304.441966 -420.588747)
			(xy 304.404749 -420.630284) (xy 304.361881 -420.665959) (xy 304.314275 -420.695013) (xy 304.262946 -420.716825)
			(xy 304.208989 -420.730931) (xy 304.153552 -420.737031) (xy 304.097818 -420.734994) (xy 304.042975 -420.724864)
			(xy 303.990191 -420.706857) (xy 303.940591 -420.681356) (xy 303.895233 -420.648905) (xy 303.855084 -420.610196)
			(xy 303.820998 -420.566053) (xy 303.793702 -420.517418) (xy 303.773779 -420.465327) (xy 303.761653 -420.41089)
			(xy 303.757582 -420.355268) (xy 303.276508 -420.355268) (xy 303.275999 -420.383154) (xy 303.267879 -420.43833)
			(xy 303.251811 -420.491737) (xy 303.228139 -420.542234) (xy 303.197366 -420.588747) (xy 303.160149 -420.630284)
			(xy 303.117281 -420.665959) (xy 303.069675 -420.695013) (xy 303.018346 -420.716825) (xy 302.964389 -420.730931)
			(xy 302.908952 -420.737031) (xy 302.853218 -420.734994) (xy 302.798375 -420.724864) (xy 302.745591 -420.706857)
			(xy 302.695991 -420.681356) (xy 302.650633 -420.648905) (xy 302.610484 -420.610196) (xy 302.576398 -420.566053)
			(xy 302.549102 -420.517418) (xy 302.529179 -420.465327) (xy 302.517053 -420.41089) (xy 302.512982 -420.355268)
			(xy 301.828394 -420.355268) (xy 301.828045 -420.357696) (xy 301.812691 -420.409987) (xy 301.790052 -420.45956)
			(xy 301.760588 -420.505407) (xy 301.7249 -420.546594) (xy 301.683713 -420.582283) (xy 301.637867 -420.611748)
			(xy 301.588294 -420.634388) (xy 301.536004 -420.649744) (xy 301.482061 -420.657501) (xy 301.427563 -420.657503)
			(xy 301.373619 -420.649749) (xy 301.321328 -420.634397) (xy 301.271754 -420.61176) (xy 301.225906 -420.582298)
			(xy 301.184717 -420.546611) (xy 301.149026 -420.505426) (xy 301.11956 -420.459581) (xy 301.096917 -420.410009)
			(xy 301.08156 -420.35772) (xy 301.0738 -420.303777) (xy 301.073312 -420.276528) (xy 301.073448 -420.260772)
			(xy 301.075992 -420.229363) (xy 301.078392 -420.21379) (xy 301.080283 -420.199074) (xy 301.076571 -420.169656)
			(xy 301.064555 -420.142549) (xy 301.04525 -420.120043) (xy 301.020289 -420.104039) (xy 300.991779 -420.095891)
			(xy 300.96213 -420.096286) (xy 300.947836 -420.100252) (xy 300.919907 -420.108437) (xy 300.862381 -420.117246)
			(xy 300.833282 -420.117778) (xy 300.803846 -420.11721) (xy 300.745672 -420.108157) (xy 300.717458 -420.099744)
			(xy 300.703137 -420.095672) (xy 300.673381 -420.095153) (xy 300.64474 -420.103238) (xy 300.619647 -420.11924)
			(xy 300.600235 -420.141798) (xy 300.588154 -420.168996) (xy 300.584429 -420.198523) (xy 300.586394 -420.213282)
			(xy 300.588884 -420.228975) (xy 300.591555 -420.26064) (xy 300.591728 -420.276528) (xy 300.591192 -420.303777)
			(xy 300.583432 -420.35772) (xy 300.568074 -420.410009) (xy 300.545431 -420.459581) (xy 300.515964 -420.505426)
			(xy 300.480273 -420.54661) (xy 300.439083 -420.582296) (xy 300.393234 -420.611757) (xy 300.343659 -420.634393)
			(xy 300.291368 -420.649743) (xy 300.237424 -420.657496) (xy 300.182926 -420.657492) (xy 300.128983 -420.649733)
			(xy 300.076693 -420.634375) (xy 300.027121 -420.611733) (xy 299.981276 -420.582266) (xy 299.940092 -420.546574)
			(xy 299.904405 -420.505385) (xy 299.874944 -420.459537) (xy 299.852308 -420.409962) (xy 299.836957 -420.35767)
			(xy 299.829205 -420.303726) (xy 299.041802 -420.303726) (xy 299.041802 -420.303753) (xy 299.034045 -420.357696)
			(xy 299.018691 -420.409987) (xy 298.996052 -420.45956) (xy 298.966588 -420.505407) (xy 298.9309 -420.546594)
			(xy 298.889713 -420.582283) (xy 298.843867 -420.611748) (xy 298.794294 -420.634388) (xy 298.742004 -420.649744)
			(xy 298.688061 -420.657501) (xy 298.633563 -420.657503) (xy 298.579619 -420.649749) (xy 298.527328 -420.634397)
			(xy 298.477754 -420.61176) (xy 298.431906 -420.582298) (xy 298.390717 -420.546611) (xy 298.355026 -420.505426)
			(xy 298.32556 -420.459581) (xy 298.302917 -420.410009) (xy 298.28756 -420.35772) (xy 298.2798 -420.303777)
			(xy 298.279312 -420.276528) (xy 298.279448 -420.260772) (xy 298.281992 -420.229363) (xy 298.284392 -420.21379)
			(xy 298.286283 -420.199074) (xy 298.282571 -420.169656) (xy 298.270555 -420.142549) (xy 298.25125 -420.120043)
			(xy 298.226289 -420.104039) (xy 298.197779 -420.095891) (xy 298.16813 -420.096286) (xy 298.153836 -420.100252)
			(xy 298.125907 -420.108437) (xy 298.068381 -420.117246) (xy 298.039282 -420.117778) (xy 298.009846 -420.11721)
			(xy 297.951672 -420.108157) (xy 297.923458 -420.099744) (xy 297.909137 -420.095672) (xy 297.879381 -420.095153)
			(xy 297.85074 -420.103238) (xy 297.825647 -420.11924) (xy 297.806235 -420.141798) (xy 297.794154 -420.168996)
			(xy 297.790429 -420.198523) (xy 297.792394 -420.213282) (xy 297.794884 -420.228975) (xy 297.797555 -420.26064)
			(xy 297.797728 -420.276528) (xy 297.797192 -420.303777) (xy 297.789432 -420.35772) (xy 297.774074 -420.410009)
			(xy 297.751431 -420.459581) (xy 297.721964 -420.505426) (xy 297.686273 -420.54661) (xy 297.645083 -420.582296)
			(xy 297.599234 -420.611757) (xy 297.549659 -420.634393) (xy 297.497368 -420.649743) (xy 297.443424 -420.657496)
			(xy 297.388926 -420.657492) (xy 297.334983 -420.649733) (xy 297.282693 -420.634375) (xy 297.233121 -420.611733)
			(xy 297.187276 -420.582266) (xy 297.146092 -420.546574) (xy 297.110405 -420.505385) (xy 297.080944 -420.459537)
			(xy 297.058308 -420.409962) (xy 297.042957 -420.35767) (xy 297.035205 -420.303726) (xy 296.247802 -420.303726)
			(xy 296.247802 -420.303753) (xy 296.240045 -420.357696) (xy 296.224691 -420.409987) (xy 296.202052 -420.45956)
			(xy 296.172588 -420.505407) (xy 296.1369 -420.546594) (xy 296.095713 -420.582283) (xy 296.049867 -420.611748)
			(xy 296.000294 -420.634388) (xy 295.948004 -420.649744) (xy 295.894061 -420.657501) (xy 295.839563 -420.657503)
			(xy 295.785619 -420.649749) (xy 295.733328 -420.634397) (xy 295.683754 -420.61176) (xy 295.637906 -420.582298)
			(xy 295.596717 -420.546611) (xy 295.561026 -420.505426) (xy 295.53156 -420.459581) (xy 295.508917 -420.410009)
			(xy 295.49356 -420.35772) (xy 295.4858 -420.303777) (xy 295.485312 -420.276528) (xy 295.485448 -420.260772)
			(xy 295.487992 -420.229363) (xy 295.490392 -420.21379) (xy 295.492283 -420.199074) (xy 295.488571 -420.169656)
			(xy 295.476555 -420.142549) (xy 295.45725 -420.120043) (xy 295.432289 -420.104039) (xy 295.403779 -420.095891)
			(xy 295.37413 -420.096286) (xy 295.359836 -420.100252) (xy 295.331907 -420.108437) (xy 295.274381 -420.117246)
			(xy 295.245282 -420.117778) (xy 295.215846 -420.11721) (xy 295.157672 -420.108157) (xy 295.129458 -420.099744)
			(xy 295.115137 -420.095672) (xy 295.085381 -420.095153) (xy 295.05674 -420.103238) (xy 295.031647 -420.11924)
			(xy 295.012235 -420.141798) (xy 295.000154 -420.168996) (xy 294.996429 -420.198523) (xy 294.998394 -420.213282)
			(xy 295.000884 -420.228975) (xy 295.003555 -420.26064) (xy 295.003728 -420.276528) (xy 295.003192 -420.303777)
			(xy 294.995432 -420.35772) (xy 294.980074 -420.410009) (xy 294.957431 -420.459581) (xy 294.927964 -420.505426)
			(xy 294.892273 -420.54661) (xy 294.851083 -420.582296) (xy 294.805234 -420.611757) (xy 294.755659 -420.634393)
			(xy 294.703368 -420.649743) (xy 294.649424 -420.657496) (xy 294.594926 -420.657492) (xy 294.540983 -420.649733)
			(xy 294.488693 -420.634375) (xy 294.439121 -420.611733) (xy 294.393276 -420.582266) (xy 294.352092 -420.546574)
			(xy 294.316405 -420.505385) (xy 294.286944 -420.459537) (xy 294.264308 -420.409962) (xy 294.248957 -420.35767)
			(xy 294.241205 -420.303726) (xy 272.587954 -420.303726) (xy 270.7894 -422.10228) (xy 243.0526 -422.10228)
			(xy 242.998752 -422.156128) (xy 243.04752 -422.204642) (xy 243.065554 -422.206674) (xy 243.09341 -422.209994)
			(xy 243.147793 -422.223758) (xy 243.199575 -422.245337) (xy 243.247639 -422.274265) (xy 243.290949 -422.309918)
			(xy 243.328573 -422.351529) (xy 243.359698 -422.3982) (xy 243.383655 -422.448925) (xy 243.399926 -422.502611)
			(xy 243.408162 -422.558101) (xy 243.408708 -422.58615) (xy 243.408189 -422.614558) (xy 243.39977 -422.670747)
			(xy 243.383112 -422.725065) (xy 243.358582 -422.776313) (xy 243.326723 -422.823356) (xy 243.288239 -422.865154)
			(xy 243.243983 -422.900782) (xy 243.219732 -422.915588) (xy 243.2077 -422.923181) (xy 243.188072 -422.943761)
			(xy 243.174877 -422.968954) (xy 243.169137 -422.996808) (xy 243.171298 -423.025165) (xy 243.181191 -423.051828)
			(xy 243.198051 -423.074731) (xy 243.209064 -423.083736) (xy 243.231804 -423.101929) (xy 243.272023 -423.144043)
			(xy 243.305378 -423.191778) (xy 243.331094 -423.244026) (xy 243.342679 -423.28084) (xy 282.347922 -423.28084)
			(xy 282.351993 -423.225218) (xy 282.364119 -423.170781) (xy 282.384042 -423.11869) (xy 282.411338 -423.070055)
			(xy 282.445424 -423.025912) (xy 282.485573 -422.987203) (xy 282.530931 -422.954752) (xy 282.580531 -422.929251)
			(xy 282.633315 -422.911244) (xy 282.688158 -422.901114) (xy 282.743892 -422.899077) (xy 282.799329 -422.905177)
			(xy 282.853286 -422.919283) (xy 282.904615 -422.941095) (xy 282.952221 -422.970149) (xy 282.995089 -423.005824)
			(xy 283.032306 -423.047361) (xy 283.063079 -423.093874) (xy 283.086751 -423.144371) (xy 283.102819 -423.197778)
			(xy 283.110939 -423.252954) (xy 283.111448 -423.28084) (xy 283.110939 -423.308726) (xy 283.102819 -423.363902)
			(xy 283.086751 -423.417309) (xy 283.063079 -423.467806) (xy 283.032306 -423.514319) (xy 282.995089 -423.555856)
			(xy 282.952221 -423.591531) (xy 282.904615 -423.620585) (xy 282.853286 -423.642397) (xy 282.799329 -423.656503)
			(xy 282.743892 -423.662603) (xy 282.688158 -423.660566) (xy 282.633315 -423.650436) (xy 282.580531 -423.632429)
			(xy 282.530931 -423.606928) (xy 282.485573 -423.574477) (xy 282.445424 -423.535768) (xy 282.411338 -423.491625)
			(xy 282.384042 -423.44299) (xy 282.364119 -423.390899) (xy 282.351993 -423.336462) (xy 282.347922 -423.28084)
			(xy 243.342679 -423.28084) (xy 243.348575 -423.299574) (xy 243.357414 -423.357133) (xy 243.357908 -423.38625)
			(xy 243.357422 -423.413501) (xy 243.349666 -423.467449) (xy 243.334311 -423.519744) (xy 243.311669 -423.569321)
			(xy 243.282203 -423.615171) (xy 243.246512 -423.656362) (xy 243.205321 -423.692053) (xy 243.159471 -423.721519)
			(xy 243.109894 -423.744161) (xy 243.057599 -423.759516) (xy 243.003651 -423.767272) (xy 242.949149 -423.767272)
			(xy 242.895201 -423.759516) (xy 242.842906 -423.744161) (xy 242.793329 -423.721519) (xy 242.747479 -423.692053)
			(xy 242.706288 -423.656362) (xy 242.670597 -423.615171) (xy 242.641131 -423.569321) (xy 242.618489 -423.519744)
			(xy 242.603134 -423.467449) (xy 242.595378 -423.413501) (xy 242.594892 -423.38625) (xy 242.595411 -423.357842)
			(xy 242.60383 -423.301653) (xy 242.620488 -423.247335) (xy 242.645018 -423.196087) (xy 242.676877 -423.149044)
			(xy 242.715361 -423.107246) (xy 242.759617 -423.071618) (xy 242.783868 -423.056812) (xy 242.7959 -423.049219)
			(xy 242.815528 -423.028639) (xy 242.828723 -423.003446) (xy 242.834463 -422.975592) (xy 242.832302 -422.947235)
			(xy 242.822409 -422.920572) (xy 242.805549 -422.897669) (xy 242.794536 -422.888664) (xy 242.771845 -422.870512)
			(xy 242.73171 -422.828496) (xy 242.698416 -422.780876) (xy 242.672737 -422.728753) (xy 242.663472 -422.701212)
			(xy 242.658458 -422.687184) (xy 242.641622 -422.662623) (xy 242.618423 -422.643954) (xy 242.59083 -422.632761)
			(xy 242.561182 -422.629992) (xy 242.531994 -422.635883) (xy 242.50574 -422.649933) (xy 242.494816 -422.660064)
			(xy 241.1095 -424.04538) (xy 241.1095 -425.152148) (xy 276.956434 -425.152148) (xy 276.956435 -425.097638)
			(xy 276.964194 -425.043684) (xy 276.979553 -424.991382) (xy 277.002198 -424.941799) (xy 277.03167 -424.895943)
			(xy 277.067367 -424.854749) (xy 277.108565 -424.819054) (xy 277.154422 -424.789585) (xy 277.204007 -424.766943)
			(xy 277.25631 -424.751588) (xy 277.310265 -424.743834) (xy 277.33752 -424.743372) (xy 277.360289 -424.743721)
			(xy 277.405495 -424.749201) (xy 277.42769 -424.754294) (xy 277.441172 -424.757127) (xy 277.468696 -424.756194)
			(xy 277.494973 -424.747948) (xy 277.518097 -424.732989) (xy 277.536389 -424.7124) (xy 277.548522 -424.687677)
			(xy 277.553617 -424.660612) (xy 277.552912 -424.646852) (xy 277.551642 -424.61434) (xy 277.552112 -424.587083)
			(xy 277.559865 -424.533123) (xy 277.575219 -424.480815) (xy 277.597861 -424.431226) (xy 277.62733 -424.385363)
			(xy 277.663026 -424.344162) (xy 277.704223 -424.30846) (xy 277.750082 -424.278985) (xy 277.799668 -424.256336)
			(xy 277.851974 -424.240976) (xy 277.905933 -424.233216) (xy 277.960447 -424.233214) (xy 278.014407 -424.240971)
			(xy 278.066713 -424.256329) (xy 278.116301 -424.278975) (xy 278.162161 -424.308448) (xy 278.20336 -424.344147)
			(xy 278.239058 -424.385347) (xy 278.26853 -424.431208) (xy 278.291174 -424.480797) (xy 278.306531 -424.533103)
			(xy 278.314286 -424.587063) (xy 278.314284 -424.641577) (xy 278.306522 -424.695536) (xy 278.29116 -424.747841)
			(xy 278.268511 -424.797427) (xy 278.239034 -424.843285) (xy 278.203331 -424.884481) (xy 278.162129 -424.920176)
			(xy 278.116266 -424.949644) (xy 278.066675 -424.972285) (xy 278.014367 -424.987637) (xy 277.960407 -424.995389)
			(xy 277.93315 -424.995848) (xy 277.910382 -424.995486) (xy 277.865175 -424.990015) (xy 277.84298 -424.984926)
			(xy 277.829492 -424.982146) (xy 277.80198 -424.983087) (xy 277.775716 -424.991331) (xy 277.752601 -425.006283)
			(xy 277.734312 -425.026857) (xy 277.722173 -425.051564) (xy 277.717063 -425.078614) (xy 277.717758 -425.092368)
			(xy 277.719028 -425.12488) (xy 277.718566 -425.152135) (xy 277.710812 -425.20609) (xy 277.695457 -425.258393)
			(xy 277.672815 -425.307978) (xy 277.643346 -425.353835) (xy 277.607651 -425.395033) (xy 277.566457 -425.43073)
			(xy 277.520601 -425.460202) (xy 277.471018 -425.482847) (xy 277.418716 -425.498206) (xy 277.364762 -425.505965)
			(xy 277.310252 -425.505966) (xy 277.256297 -425.498209) (xy 277.203995 -425.482852) (xy 277.154411 -425.460208)
			(xy 277.108554 -425.430738) (xy 277.067358 -425.395042) (xy 277.031662 -425.353846) (xy 277.002192 -425.307989)
			(xy 276.979548 -425.258405) (xy 276.964191 -425.206103) (xy 276.956434 -425.152148) (xy 241.1095 -425.152148)
			(xy 241.1095 -426.179742) (xy 304.698906 -426.179742) (xy 304.702977 -426.12412) (xy 304.715103 -426.069683)
			(xy 304.735026 -426.017592) (xy 304.762322 -425.968957) (xy 304.796408 -425.924814) (xy 304.836557 -425.886105)
			(xy 304.881915 -425.853654) (xy 304.931515 -425.828153) (xy 304.984299 -425.810146) (xy 305.039142 -425.800016)
			(xy 305.094876 -425.797979) (xy 305.150313 -425.804079) (xy 305.20427 -425.818185) (xy 305.234427 -425.831)
			(xy 307.168802 -425.831) (xy 307.172873 -425.775378) (xy 307.184999 -425.720941) (xy 307.204922 -425.66885)
			(xy 307.232218 -425.620215) (xy 307.266304 -425.576072) (xy 307.306453 -425.537363) (xy 307.351811 -425.504912)
			(xy 307.401411 -425.479411) (xy 307.454195 -425.461404) (xy 307.509038 -425.451274) (xy 307.564772 -425.449237)
			(xy 307.620209 -425.455337) (xy 307.674166 -425.469443) (xy 307.725495 -425.491255) (xy 307.773101 -425.520309)
			(xy 307.815969 -425.555984) (xy 307.853186 -425.597521) (xy 307.883959 -425.644034) (xy 307.907631 -425.694531)
			(xy 307.923699 -425.747938) (xy 307.931819 -425.803114) (xy 307.932328 -425.831) (xy 307.931819 -425.858886)
			(xy 307.923699 -425.914062) (xy 307.907631 -425.967469) (xy 307.883959 -426.017966) (xy 307.853186 -426.064479)
			(xy 307.815969 -426.106016) (xy 307.773101 -426.141691) (xy 307.725495 -426.170745) (xy 307.674166 -426.192557)
			(xy 307.620209 -426.206663) (xy 307.564772 -426.212763) (xy 307.509038 -426.210726) (xy 307.454195 -426.200596)
			(xy 307.401411 -426.182589) (xy 307.351811 -426.157088) (xy 307.306453 -426.124637) (xy 307.266304 -426.085928)
			(xy 307.232218 -426.041785) (xy 307.204922 -425.99315) (xy 307.184999 -425.941059) (xy 307.172873 -425.886622)
			(xy 307.168802 -425.831) (xy 305.234427 -425.831) (xy 305.255599 -425.839997) (xy 305.303205 -425.869051)
			(xy 305.346073 -425.904726) (xy 305.38329 -425.946263) (xy 305.414063 -425.992776) (xy 305.437735 -426.043273)
			(xy 305.453803 -426.09668) (xy 305.461923 -426.151856) (xy 305.462432 -426.179742) (xy 305.461923 -426.207628)
			(xy 305.453803 -426.262804) (xy 305.437735 -426.316211) (xy 305.414063 -426.366708) (xy 305.38329 -426.413221)
			(xy 305.346073 -426.454758) (xy 305.303205 -426.490433) (xy 305.255599 -426.519487) (xy 305.20427 -426.541299)
			(xy 305.150313 -426.555405) (xy 305.094876 -426.561505) (xy 305.039142 -426.559468) (xy 304.984299 -426.549338)
			(xy 304.931515 -426.531331) (xy 304.881915 -426.50583) (xy 304.836557 -426.473379) (xy 304.796408 -426.43467)
			(xy 304.762322 -426.390527) (xy 304.735026 -426.341892) (xy 304.715103 -426.289801) (xy 304.702977 -426.235364)
			(xy 304.698906 -426.179742) (xy 241.1095 -426.179742) (xy 241.1095 -426.7708) (xy 281.131262 -426.7708)
			(xy 281.135333 -426.715178) (xy 281.147459 -426.660741) (xy 281.167382 -426.60865) (xy 281.194678 -426.560015)
			(xy 281.228764 -426.515872) (xy 281.268913 -426.477163) (xy 281.314271 -426.444712) (xy 281.363871 -426.419211)
			(xy 281.416655 -426.401204) (xy 281.471498 -426.391074) (xy 281.527232 -426.389037) (xy 281.582669 -426.395137)
			(xy 281.636626 -426.409243) (xy 281.687955 -426.431055) (xy 281.735561 -426.460109) (xy 281.778429 -426.495784)
			(xy 281.815646 -426.537321) (xy 281.846419 -426.583834) (xy 281.870091 -426.634331) (xy 281.886159 -426.687738)
			(xy 281.894279 -426.742914) (xy 281.894788 -426.7708) (xy 281.894279 -426.798686) (xy 281.886159 -426.853862)
			(xy 281.870091 -426.907269) (xy 281.846419 -426.957766) (xy 281.818874 -426.9994) (xy 293.673782 -426.9994)
			(xy 293.677853 -426.943778) (xy 293.689979 -426.889341) (xy 293.709902 -426.83725) (xy 293.737198 -426.788615)
			(xy 293.771284 -426.744472) (xy 293.811433 -426.705763) (xy 293.856791 -426.673312) (xy 293.906391 -426.647811)
			(xy 293.959175 -426.629804) (xy 294.014018 -426.619674) (xy 294.069752 -426.617637) (xy 294.125189 -426.623737)
			(xy 294.179146 -426.637843) (xy 294.230475 -426.659655) (xy 294.278081 -426.688709) (xy 294.320949 -426.724384)
			(xy 294.358166 -426.765921) (xy 294.388939 -426.812434) (xy 294.412611 -426.862931) (xy 294.417294 -426.878496)
			(xy 294.531286 -426.878496) (xy 294.535357 -426.822874) (xy 294.547483 -426.768437) (xy 294.567406 -426.716346)
			(xy 294.594702 -426.667711) (xy 294.628788 -426.623568) (xy 294.668937 -426.584859) (xy 294.714295 -426.552408)
			(xy 294.763895 -426.526907) (xy 294.816679 -426.5089) (xy 294.871522 -426.49877) (xy 294.927256 -426.496733)
			(xy 294.982693 -426.502833) (xy 295.03665 -426.516939) (xy 295.087979 -426.538751) (xy 295.135585 -426.567805)
			(xy 295.178453 -426.60348) (xy 295.21567 -426.645017) (xy 295.246443 -426.69153) (xy 295.270115 -426.742027)
			(xy 295.286183 -426.795434) (xy 295.294303 -426.85061) (xy 295.294812 -426.878496) (xy 297.325286 -426.878496)
			(xy 297.329357 -426.822874) (xy 297.341483 -426.768437) (xy 297.361406 -426.716346) (xy 297.388702 -426.667711)
			(xy 297.422788 -426.623568) (xy 297.462937 -426.584859) (xy 297.508295 -426.552408) (xy 297.557895 -426.526907)
			(xy 297.610679 -426.5089) (xy 297.665522 -426.49877) (xy 297.721256 -426.496733) (xy 297.776693 -426.502833)
			(xy 297.83065 -426.516939) (xy 297.881979 -426.538751) (xy 297.929585 -426.567805) (xy 297.972453 -426.60348)
			(xy 298.00967 -426.645017) (xy 298.040443 -426.69153) (xy 298.064115 -426.742027) (xy 298.080183 -426.795434)
			(xy 298.088303 -426.85061) (xy 298.088812 -426.878496) (xy 300.119286 -426.878496) (xy 300.123357 -426.822874)
			(xy 300.135483 -426.768437) (xy 300.155406 -426.716346) (xy 300.182702 -426.667711) (xy 300.216788 -426.623568)
			(xy 300.256937 -426.584859) (xy 300.302295 -426.552408) (xy 300.351895 -426.526907) (xy 300.404679 -426.5089)
			(xy 300.459522 -426.49877) (xy 300.515256 -426.496733) (xy 300.570693 -426.502833) (xy 300.62465 -426.516939)
			(xy 300.675979 -426.538751) (xy 300.723585 -426.567805) (xy 300.766453 -426.60348) (xy 300.80367 -426.645017)
			(xy 300.834443 -426.69153) (xy 300.858115 -426.742027) (xy 300.874183 -426.795434) (xy 300.882303 -426.85061)
			(xy 300.882812 -426.878496) (xy 300.882303 -426.906382) (xy 300.874819 -426.957236) (xy 302.804066 -426.957236)
			(xy 302.808137 -426.901614) (xy 302.820263 -426.847177) (xy 302.840186 -426.795086) (xy 302.867482 -426.746451)
			(xy 302.901568 -426.702308) (xy 302.941717 -426.663599) (xy 302.987075 -426.631148) (xy 303.036675 -426.605647)
			(xy 303.089459 -426.58764) (xy 303.144302 -426.57751) (xy 303.200036 -426.575473) (xy 303.255473 -426.581573)
			(xy 303.30943 -426.595679) (xy 303.360759 -426.617491) (xy 303.408365 -426.646545) (xy 303.451233 -426.68222)
			(xy 303.48845 -426.723757) (xy 303.519223 -426.77027) (xy 303.542895 -426.820767) (xy 303.558963 -426.874174)
			(xy 303.567083 -426.92935) (xy 303.567592 -426.957236) (xy 303.567083 -426.985122) (xy 303.558963 -427.040298)
			(xy 303.542895 -427.093705) (xy 303.519223 -427.144202) (xy 303.48845 -427.190715) (xy 303.451233 -427.232252)
			(xy 303.408365 -427.267927) (xy 303.360759 -427.296981) (xy 303.30943 -427.318793) (xy 303.255473 -427.332899)
			(xy 303.200036 -427.338999) (xy 303.144302 -427.336962) (xy 303.089459 -427.326832) (xy 303.036675 -427.308825)
			(xy 302.987075 -427.283324) (xy 302.941717 -427.250873) (xy 302.901568 -427.212164) (xy 302.867482 -427.168021)
			(xy 302.840186 -427.119386) (xy 302.820263 -427.067295) (xy 302.808137 -427.012858) (xy 302.804066 -426.957236)
			(xy 300.874819 -426.957236) (xy 300.874183 -426.961558) (xy 300.858115 -427.014965) (xy 300.834443 -427.065462)
			(xy 300.80367 -427.111975) (xy 300.766453 -427.153512) (xy 300.723585 -427.189187) (xy 300.675979 -427.218241)
			(xy 300.62465 -427.240053) (xy 300.570693 -427.254159) (xy 300.515256 -427.260259) (xy 300.459522 -427.258222)
			(xy 300.404679 -427.248092) (xy 300.351895 -427.230085) (xy 300.302295 -427.204584) (xy 300.256937 -427.172133)
			(xy 300.216788 -427.133424) (xy 300.182702 -427.089281) (xy 300.155406 -427.040646) (xy 300.135483 -426.988555)
			(xy 300.123357 -426.934118) (xy 300.119286 -426.878496) (xy 298.088812 -426.878496) (xy 298.088303 -426.906382)
			(xy 298.080183 -426.961558) (xy 298.064115 -427.014965) (xy 298.040443 -427.065462) (xy 298.00967 -427.111975)
			(xy 297.972453 -427.153512) (xy 297.929585 -427.189187) (xy 297.881979 -427.218241) (xy 297.83065 -427.240053)
			(xy 297.776693 -427.254159) (xy 297.721256 -427.260259) (xy 297.665522 -427.258222) (xy 297.610679 -427.248092)
			(xy 297.557895 -427.230085) (xy 297.508295 -427.204584) (xy 297.462937 -427.172133) (xy 297.422788 -427.133424)
			(xy 297.388702 -427.089281) (xy 297.361406 -427.040646) (xy 297.341483 -426.988555) (xy 297.329357 -426.934118)
			(xy 297.325286 -426.878496) (xy 295.294812 -426.878496) (xy 295.294303 -426.906382) (xy 295.286183 -426.961558)
			(xy 295.270115 -427.014965) (xy 295.246443 -427.065462) (xy 295.21567 -427.111975) (xy 295.178453 -427.153512)
			(xy 295.135585 -427.189187) (xy 295.087979 -427.218241) (xy 295.03665 -427.240053) (xy 294.982693 -427.254159)
			(xy 294.927256 -427.260259) (xy 294.871522 -427.258222) (xy 294.816679 -427.248092) (xy 294.763895 -427.230085)
			(xy 294.714295 -427.204584) (xy 294.668937 -427.172133) (xy 294.628788 -427.133424) (xy 294.594702 -427.089281)
			(xy 294.567406 -427.040646) (xy 294.547483 -426.988555) (xy 294.535357 -426.934118) (xy 294.531286 -426.878496)
			(xy 294.417294 -426.878496) (xy 294.428679 -426.916338) (xy 294.436799 -426.971514) (xy 294.437308 -426.9994)
			(xy 294.436799 -427.027286) (xy 294.428679 -427.082462) (xy 294.412611 -427.135869) (xy 294.388939 -427.186366)
			(xy 294.358166 -427.232879) (xy 294.320949 -427.274416) (xy 294.278081 -427.310091) (xy 294.230475 -427.339145)
			(xy 294.179146 -427.360957) (xy 294.125189 -427.375063) (xy 294.069752 -427.381163) (xy 294.014018 -427.379126)
			(xy 293.959175 -427.368996) (xy 293.906391 -427.350989) (xy 293.856791 -427.325488) (xy 293.811433 -427.293037)
			(xy 293.771284 -427.254328) (xy 293.737198 -427.210185) (xy 293.709902 -427.16155) (xy 293.689979 -427.109459)
			(xy 293.677853 -427.055022) (xy 293.673782 -426.9994) (xy 281.818874 -426.9994) (xy 281.815646 -427.004279)
			(xy 281.778429 -427.045816) (xy 281.735561 -427.081491) (xy 281.687955 -427.110545) (xy 281.636626 -427.132357)
			(xy 281.582669 -427.146463) (xy 281.527232 -427.152563) (xy 281.471498 -427.150526) (xy 281.416655 -427.140396)
			(xy 281.363871 -427.122389) (xy 281.314271 -427.096888) (xy 281.268913 -427.064437) (xy 281.228764 -427.025728)
			(xy 281.194678 -426.981585) (xy 281.167382 -426.93295) (xy 281.147459 -426.880859) (xy 281.135333 -426.826422)
			(xy 281.131262 -426.7708) (xy 241.1095 -426.7708) (xy 241.1095 -428.16272) (xy 306.241702 -428.16272)
			(xy 306.245773 -428.107098) (xy 306.257899 -428.052661) (xy 306.277822 -428.00057) (xy 306.305118 -427.951935)
			(xy 306.339204 -427.907792) (xy 306.379353 -427.869083) (xy 306.424711 -427.836632) (xy 306.474311 -427.811131)
			(xy 306.527095 -427.793124) (xy 306.581938 -427.782994) (xy 306.637672 -427.780957) (xy 306.693109 -427.787057)
			(xy 306.747066 -427.801163) (xy 306.798395 -427.822975) (xy 306.846001 -427.852029) (xy 306.865288 -427.86808)
			(xy 308.789322 -427.86808) (xy 308.793393 -427.812458) (xy 308.805519 -427.758021) (xy 308.825442 -427.70593)
			(xy 308.852738 -427.657295) (xy 308.886824 -427.613152) (xy 308.926973 -427.574443) (xy 308.972331 -427.541992)
			(xy 309.021931 -427.516491) (xy 309.074715 -427.498484) (xy 309.129558 -427.488354) (xy 309.185292 -427.486317)
			(xy 309.240729 -427.492417) (xy 309.294686 -427.506523) (xy 309.346015 -427.528335) (xy 309.393621 -427.557389)
			(xy 309.436489 -427.593064) (xy 309.473706 -427.634601) (xy 309.504479 -427.681114) (xy 309.528151 -427.731611)
			(xy 309.544219 -427.785018) (xy 309.552339 -427.840194) (xy 309.552848 -427.86808) (xy 309.552339 -427.895966)
			(xy 309.544219 -427.951142) (xy 309.528151 -428.004549) (xy 309.504479 -428.055046) (xy 309.473706 -428.101559)
			(xy 309.436489 -428.143096) (xy 309.393621 -428.178771) (xy 309.346015 -428.207825) (xy 309.294686 -428.229637)
			(xy 309.240729 -428.243743) (xy 309.185292 -428.249843) (xy 309.129558 -428.247806) (xy 309.074715 -428.237676)
			(xy 309.021931 -428.219669) (xy 308.972331 -428.194168) (xy 308.926973 -428.161717) (xy 308.886824 -428.123008)
			(xy 308.852738 -428.078865) (xy 308.825442 -428.03023) (xy 308.805519 -427.978139) (xy 308.793393 -427.923702)
			(xy 308.789322 -427.86808) (xy 306.865288 -427.86808) (xy 306.888869 -427.887704) (xy 306.926086 -427.929241)
			(xy 306.956859 -427.975754) (xy 306.980531 -428.026251) (xy 306.996599 -428.079658) (xy 307.004719 -428.134834)
			(xy 307.005228 -428.16272) (xy 307.004719 -428.190606) (xy 306.996599 -428.245782) (xy 306.980531 -428.299189)
			(xy 306.956859 -428.349686) (xy 306.926086 -428.396199) (xy 306.888869 -428.437736) (xy 306.846001 -428.473411)
			(xy 306.798395 -428.502465) (xy 306.747066 -428.524277) (xy 306.693109 -428.538383) (xy 306.637672 -428.544483)
			(xy 306.581938 -428.542446) (xy 306.527095 -428.532316) (xy 306.474311 -428.514309) (xy 306.424711 -428.488808)
			(xy 306.379353 -428.456357) (xy 306.339204 -428.417648) (xy 306.305118 -428.373505) (xy 306.277822 -428.32487)
			(xy 306.257899 -428.272779) (xy 306.245773 -428.218342) (xy 306.241702 -428.16272) (xy 241.1095 -428.16272)
			(xy 241.1095 -428.85106) (xy 302.064672 -428.85106) (xy 302.068743 -428.795438) (xy 302.080869 -428.741001)
			(xy 302.100792 -428.68891) (xy 302.128088 -428.640275) (xy 302.162174 -428.596132) (xy 302.202323 -428.557423)
			(xy 302.247681 -428.524972) (xy 302.297281 -428.499471) (xy 302.350065 -428.481464) (xy 302.404908 -428.471334)
			(xy 302.460642 -428.469297) (xy 302.516079 -428.475397) (xy 302.570036 -428.489503) (xy 302.621365 -428.511315)
			(xy 302.668971 -428.540369) (xy 302.711839 -428.576044) (xy 302.749056 -428.617581) (xy 302.779829 -428.664094)
			(xy 302.803501 -428.714591) (xy 302.819569 -428.767998) (xy 302.827689 -428.823174) (xy 302.828198 -428.85106)
			(xy 302.827989 -428.86249) (xy 304.800252 -428.86249) (xy 304.804323 -428.806868) (xy 304.816449 -428.752431)
			(xy 304.836372 -428.70034) (xy 304.863668 -428.651705) (xy 304.897754 -428.607562) (xy 304.937903 -428.568853)
			(xy 304.983261 -428.536402) (xy 305.032861 -428.510901) (xy 305.085645 -428.492894) (xy 305.140488 -428.482764)
			(xy 305.196222 -428.480727) (xy 305.251659 -428.486827) (xy 305.305616 -428.500933) (xy 305.356945 -428.522745)
			(xy 305.404551 -428.551799) (xy 305.447419 -428.587474) (xy 305.484636 -428.629011) (xy 305.515409 -428.675524)
			(xy 305.539081 -428.726021) (xy 305.555149 -428.779428) (xy 305.563269 -428.834604) (xy 305.563778 -428.86249)
			(xy 305.563269 -428.890376) (xy 305.557467 -428.9298) (xy 307.543452 -428.9298) (xy 307.547523 -428.874178)
			(xy 307.559649 -428.819741) (xy 307.579572 -428.76765) (xy 307.606868 -428.719015) (xy 307.640954 -428.674872)
			(xy 307.681103 -428.636163) (xy 307.726461 -428.603712) (xy 307.776061 -428.578211) (xy 307.828845 -428.560204)
			(xy 307.883688 -428.550074) (xy 307.939422 -428.548037) (xy 307.994859 -428.554137) (xy 308.048816 -428.568243)
			(xy 308.100145 -428.590055) (xy 308.147751 -428.619109) (xy 308.190619 -428.654784) (xy 308.227836 -428.696321)
			(xy 308.258609 -428.742834) (xy 308.282281 -428.793331) (xy 308.298349 -428.846738) (xy 308.306469 -428.901914)
			(xy 308.306978 -428.9298) (xy 308.306469 -428.957686) (xy 308.298349 -429.012862) (xy 308.282281 -429.066269)
			(xy 308.258609 -429.116766) (xy 308.227836 -429.163279) (xy 308.190619 -429.204816) (xy 308.147751 -429.240491)
			(xy 308.100145 -429.269545) (xy 308.048816 -429.291357) (xy 307.994859 -429.305463) (xy 307.939422 -429.311563)
			(xy 307.883688 -429.309526) (xy 307.828845 -429.299396) (xy 307.776061 -429.281389) (xy 307.726461 -429.255888)
			(xy 307.681103 -429.223437) (xy 307.640954 -429.184728) (xy 307.606868 -429.140585) (xy 307.579572 -429.09195)
			(xy 307.559649 -429.039859) (xy 307.547523 -428.985422) (xy 307.543452 -428.9298) (xy 305.557467 -428.9298)
			(xy 305.555149 -428.945552) (xy 305.539081 -428.998959) (xy 305.515409 -429.049456) (xy 305.484636 -429.095969)
			(xy 305.447419 -429.137506) (xy 305.404551 -429.173181) (xy 305.356945 -429.202235) (xy 305.305616 -429.224047)
			(xy 305.251659 -429.238153) (xy 305.196222 -429.244253) (xy 305.140488 -429.242216) (xy 305.085645 -429.232086)
			(xy 305.032861 -429.214079) (xy 304.983261 -429.188578) (xy 304.937903 -429.156127) (xy 304.897754 -429.117418)
			(xy 304.863668 -429.073275) (xy 304.836372 -429.02464) (xy 304.816449 -428.972549) (xy 304.804323 -428.918112)
			(xy 304.800252 -428.86249) (xy 302.827989 -428.86249) (xy 302.827689 -428.878946) (xy 302.819569 -428.934122)
			(xy 302.803501 -428.987529) (xy 302.779829 -429.038026) (xy 302.749056 -429.084539) (xy 302.711839 -429.126076)
			(xy 302.668971 -429.161751) (xy 302.621365 -429.190805) (xy 302.570036 -429.212617) (xy 302.516079 -429.226723)
			(xy 302.460642 -429.232823) (xy 302.404908 -429.230786) (xy 302.350065 -429.220656) (xy 302.297281 -429.202649)
			(xy 302.247681 -429.177148) (xy 302.202323 -429.144697) (xy 302.162174 -429.105988) (xy 302.128088 -429.061845)
			(xy 302.100792 -429.01321) (xy 302.080869 -428.961119) (xy 302.068743 -428.906682) (xy 302.064672 -428.85106)
			(xy 241.1095 -428.85106) (xy 241.1095 -433.04206) (xy 267.01141 -433.04206) (xy 267.01543 -432.866756)
			(xy 267.027484 -432.69182) (xy 267.047545 -432.517622) (xy 267.075571 -432.344526) (xy 267.111504 -432.172897)
			(xy 267.155267 -432.003095) (xy 267.20677 -431.835479) (xy 267.265903 -431.6704) (xy 267.332542 -431.508206)
			(xy 267.406547 -431.349238) (xy 267.487762 -431.19383) (xy 267.576017 -431.042308) (xy 267.671126 -430.894992)
			(xy 267.772888 -430.752191) (xy 267.881091 -430.614206) (xy 267.995506 -430.481327) (xy 268.115893 -430.353833)
			(xy 268.241998 -430.231992) (xy 268.373557 -430.116061) (xy 268.510292 -430.006284) (xy 268.651917 -429.902891)
			(xy 268.798133 -429.806099) (xy 268.948632 -429.716113) (xy 269.103099 -429.633121) (xy 269.261209 -429.557298)
			(xy 269.422628 -429.488804) (xy 269.587018 -429.427782) (xy 269.754033 -429.374362) (xy 269.923321 -429.328654)
			(xy 270.094527 -429.290756) (xy 270.26729 -429.260747) (xy 270.441247 -429.23869) (xy 270.616033 -429.224631)
			(xy 270.79128 -429.218601) (xy 270.966618 -429.220611) (xy 271.14168 -429.230658) (xy 271.316098 -429.248721)
			(xy 271.489504 -429.274761) (xy 271.661533 -429.308723) (xy 271.831825 -429.350537) (xy 272.000021 -429.400114)
			(xy 272.165767 -429.457351) (xy 272.328714 -429.522126) (xy 272.488521 -429.594303) (xy 272.64485 -429.673731)
			(xy 272.797374 -429.760243) (xy 272.94577 -429.853656) (xy 273.089728 -429.953775) (xy 273.228945 -430.060389)
			(xy 273.363127 -430.173273) (xy 273.491993 -430.29219) (xy 273.615272 -430.41689) (xy 273.732703 -430.547111)
			(xy 273.844042 -430.682578) (xy 273.949052 -430.823008) (xy 274.047513 -430.968105) (xy 274.139219 -431.117563)
			(xy 274.223977 -431.271068) (xy 274.301607 -431.428298) (xy 274.371948 -431.588921) (xy 274.43485 -431.752601)
			(xy 274.477209 -431.879979) (xy 302.473364 -431.879979) (xy 302.481116 -431.82603) (xy 302.496467 -431.773733)
			(xy 302.519104 -431.724153) (xy 302.548567 -431.678299) (xy 302.584255 -431.637105) (xy 302.625442 -431.601409)
			(xy 302.671291 -431.571938) (xy 302.720867 -431.549291) (xy 302.773161 -431.533931) (xy 302.827108 -431.526169)
			(xy 302.85436 -431.52568) (xy 302.883797 -431.52624) (xy 302.94197 -431.535298) (xy 302.970184 -431.543714)
			(xy 302.984506 -431.547768) (xy 303.014254 -431.548274) (xy 303.042886 -431.540185) (xy 303.067971 -431.524186)
			(xy 303.087381 -431.501636) (xy 303.099467 -431.474449) (xy 303.103204 -431.444932) (xy 303.101248 -431.430176)
			(xy 303.098752 -431.414484) (xy 303.096085 -431.382819) (xy 303.095914 -431.36693) (xy 303.0964 -431.339679)
			(xy 303.104156 -431.285731) (xy 303.119511 -431.233436) (xy 303.142153 -431.183859) (xy 303.171619 -431.138009)
			(xy 303.20731 -431.096818) (xy 303.248501 -431.061127) (xy 303.294351 -431.031661) (xy 303.343928 -431.009019)
			(xy 303.396223 -430.993664) (xy 303.450171 -430.985908) (xy 303.504673 -430.985908) (xy 303.558621 -430.993664)
			(xy 303.610916 -431.009019) (xy 303.660493 -431.031661) (xy 303.706343 -431.061127) (xy 303.747534 -431.096818)
			(xy 303.783225 -431.138009) (xy 303.812691 -431.183859) (xy 303.835333 -431.233436) (xy 303.850688 -431.285731)
			(xy 303.858444 -431.339679) (xy 303.85893 -431.36693) (xy 303.858788 -431.382686) (xy 303.856248 -431.414095)
			(xy 303.85385 -431.429668) (xy 303.851848 -431.444373) (xy 303.855576 -431.473805) (xy 303.86761 -431.500922)
			(xy 303.886933 -431.523433) (xy 303.911913 -431.539436) (xy 303.94044 -431.547581) (xy 303.970105 -431.547177)
			(xy 303.984406 -431.543206) (xy 304.012332 -431.535011) (xy 304.069861 -431.526209) (xy 304.09896 -431.52568)
			(xy 304.126217 -431.526112) (xy 304.180176 -431.533865) (xy 304.232482 -431.549218) (xy 304.282071 -431.571859)
			(xy 304.327933 -431.601327) (xy 304.369134 -431.637022) (xy 304.404836 -431.678217) (xy 304.434311 -431.724074)
			(xy 304.45696 -431.773659) (xy 304.472322 -431.825963) (xy 304.480083 -431.879921) (xy 304.480087 -431.934434)
			(xy 304.478451 -431.945819) (xy 305.208871 -431.945819) (xy 305.208876 -431.891315) (xy 305.216637 -431.837367)
			(xy 305.231997 -431.785072) (xy 305.254643 -431.735496) (xy 305.284115 -431.689647) (xy 305.319811 -431.648459)
			(xy 305.361006 -431.612771) (xy 305.40686 -431.583309) (xy 305.456441 -431.560672) (xy 305.508738 -431.545322)
			(xy 305.562688 -431.53757) (xy 305.58994 -431.53711) (xy 305.619377 -431.537674) (xy 305.67755 -431.546729)
			(xy 305.705764 -431.555144) (xy 305.720099 -431.559141) (xy 305.749838 -431.559651) (xy 305.778462 -431.551569)
			(xy 305.803541 -431.535579) (xy 305.822949 -431.51304) (xy 305.835037 -431.485865) (xy 305.83878 -431.456358)
			(xy 305.836828 -431.441606) (xy 305.834337 -431.425913) (xy 305.831667 -431.394248) (xy 305.831494 -431.37836)
			(xy 305.83198 -431.351109) (xy 305.839736 -431.297161) (xy 305.855091 -431.244866) (xy 305.877733 -431.195289)
			(xy 305.907199 -431.149439) (xy 305.94289 -431.108248) (xy 305.984081 -431.072557) (xy 306.029931 -431.043091)
			(xy 306.079508 -431.020449) (xy 306.131803 -431.005094) (xy 306.185751 -430.997338) (xy 306.240253 -430.997338)
			(xy 306.294201 -431.005094) (xy 306.346496 -431.020449) (xy 306.396073 -431.043091) (xy 306.441923 -431.072557)
			(xy 306.483114 -431.108248) (xy 306.518805 -431.149439) (xy 306.548271 -431.195289) (xy 306.570913 -431.244866)
			(xy 306.586268 -431.297161) (xy 306.594024 -431.351109) (xy 306.59451 -431.37836) (xy 306.594372 -431.394116)
			(xy 306.591829 -431.425525) (xy 306.58943 -431.441098) (xy 306.587425 -431.455801) (xy 306.591159 -431.48523)
			(xy 306.603196 -431.512343) (xy 306.622519 -431.534852) (xy 306.647498 -431.550855) (xy 306.676022 -431.559001)
			(xy 306.705685 -431.558604) (xy 306.719986 -431.554636) (xy 306.747914 -431.546446) (xy 306.805441 -431.537641)
			(xy 306.83454 -431.53711) (xy 306.861787 -431.537621) (xy 306.915727 -431.545382) (xy 306.968013 -431.56074)
			(xy 307.017581 -431.583382) (xy 307.063423 -431.612849) (xy 307.104604 -431.648539) (xy 307.140288 -431.689726)
			(xy 307.169747 -431.735572) (xy 307.192381 -431.785144) (xy 307.207731 -431.837432) (xy 307.215483 -431.891373)
			(xy 307.21548 -431.945868) (xy 307.207722 -431.999808) (xy 307.203814 -432.013115) (xy 307.952081 -432.013115)
			(xy 307.952086 -431.958613) (xy 307.959847 -431.904666) (xy 307.975207 -431.852374) (xy 307.997853 -431.802799)
			(xy 308.027324 -431.756952) (xy 308.063019 -431.715765) (xy 308.104213 -431.680078) (xy 308.150066 -431.650617)
			(xy 308.199645 -431.627981) (xy 308.251941 -431.612631) (xy 308.305889 -431.60488) (xy 308.33314 -431.60442)
			(xy 308.362577 -431.604983) (xy 308.42075 -431.614039) (xy 308.448964 -431.622454) (xy 308.463278 -431.626553)
			(xy 308.493037 -431.627066) (xy 308.521681 -431.618977) (xy 308.546774 -431.602971) (xy 308.566187 -431.580408)
			(xy 308.578268 -431.553207) (xy 308.581993 -431.523677) (xy 308.580028 -431.508916) (xy 308.577538 -431.493223)
			(xy 308.574867 -431.461558) (xy 308.574694 -431.44567) (xy 308.57518 -431.418419) (xy 308.582936 -431.364471)
			(xy 308.598291 -431.312176) (xy 308.620933 -431.262599) (xy 308.650399 -431.216749) (xy 308.68609 -431.175558)
			(xy 308.727281 -431.139867) (xy 308.773131 -431.110401) (xy 308.822708 -431.087759) (xy 308.875003 -431.072404)
			(xy 308.928951 -431.064648) (xy 308.983453 -431.064648) (xy 309.037401 -431.072404) (xy 309.089696 -431.087759)
			(xy 309.139273 -431.110401) (xy 309.185123 -431.139867) (xy 309.226314 -431.175558) (xy 309.262005 -431.216749)
			(xy 309.291471 -431.262599) (xy 309.314113 -431.312176) (xy 309.329468 -431.364471) (xy 309.337224 -431.418419)
			(xy 309.33771 -431.44567) (xy 309.337573 -431.461426) (xy 309.335029 -431.492835) (xy 309.33263 -431.508408)
			(xy 309.330713 -431.523122) (xy 309.334425 -431.552545) (xy 309.346443 -431.579657) (xy 309.365753 -431.602166)
			(xy 309.39072 -431.61817) (xy 309.419236 -431.626316) (xy 309.44889 -431.625916) (xy 309.463186 -431.621946)
			(xy 309.491114 -431.613756) (xy 309.548641 -431.604951) (xy 309.57774 -431.60442) (xy 309.604987 -431.604921)
			(xy 309.658926 -431.612682) (xy 309.711212 -431.62804) (xy 309.76078 -431.650682) (xy 309.806622 -431.680148)
			(xy 309.847803 -431.715837) (xy 309.883487 -431.757024) (xy 309.912946 -431.80287) (xy 309.93558 -431.852442)
			(xy 309.95093 -431.90473) (xy 309.958683 -431.95867) (xy 309.958681 -432.013165) (xy 309.950923 -432.067104)
			(xy 309.935568 -432.119391) (xy 309.912929 -432.16896) (xy 309.883466 -432.214804) (xy 309.847779 -432.255987)
			(xy 309.806594 -432.291673) (xy 309.76075 -432.321135) (xy 309.71118 -432.343773) (xy 309.658893 -432.359126)
			(xy 309.604953 -432.366882) (xy 309.550458 -432.366882) (xy 309.496518 -432.359128) (xy 309.44423 -432.343776)
			(xy 309.394659 -432.32114) (xy 309.348815 -432.291679) (xy 309.307629 -432.255995) (xy 309.271941 -432.214812)
			(xy 309.242476 -432.16897) (xy 309.219835 -432.119401) (xy 309.204479 -432.067115) (xy 309.19672 -432.013175)
			(xy 309.196232 -431.985928) (xy 309.196368 -431.970172) (xy 309.198912 -431.938763) (xy 309.201312 -431.92319)
			(xy 309.203177 -431.908473) (xy 309.199465 -431.879059) (xy 309.187452 -431.851956) (xy 309.168152 -431.829452)
			(xy 309.143196 -431.813449) (xy 309.114692 -431.805298) (xy 309.085049 -431.805689) (xy 309.070756 -431.809652)
			(xy 309.042831 -431.817854) (xy 308.985302 -431.826652) (xy 308.956202 -431.827178) (xy 308.926765 -431.826628)
			(xy 308.868591 -431.817563) (xy 308.840378 -431.809144) (xy 308.826051 -431.805095) (xy 308.796298 -431.804572)
			(xy 308.767658 -431.812652) (xy 308.742566 -431.82865) (xy 308.723155 -431.851205) (xy 308.711073 -431.8784)
			(xy 308.707349 -431.907924) (xy 308.709314 -431.922682) (xy 308.711804 -431.938375) (xy 308.714475 -431.97004)
			(xy 308.714648 -431.985928) (xy 308.714115 -432.013179) (xy 308.706354 -432.067126) (xy 308.690995 -432.119419)
			(xy 308.668351 -432.168994) (xy 308.638881 -432.214842) (xy 308.603186 -432.256029) (xy 308.561994 -432.291717)
			(xy 308.516141 -432.321179) (xy 308.466563 -432.343816) (xy 308.414267 -432.359167) (xy 308.360319 -432.366919)
			(xy 308.305817 -432.366914) (xy 308.25187 -432.359153) (xy 308.199577 -432.343794) (xy 308.150002 -432.321149)
			(xy 308.104155 -432.291679) (xy 308.062968 -432.255984) (xy 308.027281 -432.214791) (xy 307.997819 -432.168938)
			(xy 307.975182 -432.119359) (xy 307.959832 -432.067063) (xy 307.952081 -432.013115) (xy 307.203814 -432.013115)
			(xy 307.192367 -432.052095) (xy 307.169727 -432.101664) (xy 307.140263 -432.147507) (xy 307.104575 -432.188691)
			(xy 307.06339 -432.224376) (xy 307.017545 -432.253837) (xy 306.967974 -432.276475) (xy 306.915686 -432.291827)
			(xy 306.861746 -432.299582) (xy 306.807251 -432.299582) (xy 306.753311 -432.291826) (xy 306.701023 -432.276474)
			(xy 306.651453 -432.253836) (xy 306.605608 -432.224375) (xy 306.564423 -432.188689) (xy 306.528735 -432.147505)
			(xy 306.499272 -432.101662) (xy 306.476632 -432.052092) (xy 306.461277 -431.999805) (xy 306.453519 -431.945865)
			(xy 306.453032 -431.918618) (xy 306.453167 -431.902862) (xy 306.455712 -431.871453) (xy 306.458112 -431.85588)
			(xy 306.459987 -431.841164) (xy 306.456273 -431.81175) (xy 306.444257 -431.784647) (xy 306.424956 -431.762143)
			(xy 306.399999 -431.74614) (xy 306.371494 -431.737989) (xy 306.341849 -431.738379) (xy 306.327556 -431.742342)
			(xy 306.299632 -431.750547) (xy 306.242102 -431.759342) (xy 306.213002 -431.759868) (xy 306.183565 -431.759318)
			(xy 306.125391 -431.750254) (xy 306.097178 -431.741834) (xy 306.082849 -431.737796) (xy 306.053098 -431.737273)
			(xy 306.02446 -431.745353) (xy 305.99937 -431.761349) (xy 305.979959 -431.783901) (xy 305.967877 -431.811094)
			(xy 305.964151 -431.840615) (xy 305.966114 -431.855372) (xy 305.968603 -431.871065) (xy 305.971274 -431.90273)
			(xy 305.971448 -431.918618) (xy 305.970925 -431.94587) (xy 305.963166 -431.999819) (xy 305.947808 -432.052114)
			(xy 305.925164 -432.101691) (xy 305.895694 -432.147541) (xy 305.859999 -432.18873) (xy 305.818806 -432.22442)
			(xy 305.772953 -432.253884) (xy 305.723373 -432.276523) (xy 305.671076 -432.291875) (xy 305.617127 -432.299628)
			(xy 305.562623 -432.299625) (xy 305.508674 -432.291864) (xy 305.456379 -432.276505) (xy 305.406803 -432.25386)
			(xy 305.360953 -432.22439) (xy 305.319765 -432.188694) (xy 305.284075 -432.1475) (xy 305.254612 -432.101646)
			(xy 305.231974 -432.052066) (xy 305.216623 -431.999769) (xy 305.208871 -431.945819) (xy 304.478451 -431.945819)
			(xy 304.472332 -431.988393) (xy 304.456976 -432.040698) (xy 304.434333 -432.090286) (xy 304.404863 -432.136147)
			(xy 304.369166 -432.177346) (xy 304.327969 -432.213046) (xy 304.282111 -432.24252) (xy 304.232524 -432.265166)
			(xy 304.18022 -432.280526) (xy 304.126262 -432.288285) (xy 304.071749 -432.288285) (xy 304.017791 -432.280528)
			(xy 303.965486 -432.26517) (xy 303.915899 -432.242525) (xy 303.870039 -432.213053) (xy 303.828841 -432.177354)
			(xy 303.793143 -432.136155) (xy 303.763672 -432.090295) (xy 303.741028 -432.040708) (xy 303.725671 -431.988403)
			(xy 303.717914 -431.934445) (xy 303.717452 -431.907188) (xy 303.717595 -431.891432) (xy 303.720135 -431.860023)
			(xy 303.722532 -431.84445) (xy 303.72454 -431.829745) (xy 303.720816 -431.800309) (xy 303.708783 -431.773189)
			(xy 303.689459 -431.750675) (xy 303.664476 -431.734671) (xy 303.635945 -431.726529) (xy 303.606278 -431.726937)
			(xy 303.591976 -431.730912) (xy 303.564051 -431.739112) (xy 303.506522 -431.747911) (xy 303.477422 -431.748438)
			(xy 303.447985 -431.747885) (xy 303.389811 -431.738823) (xy 303.361598 -431.730404) (xy 303.347285 -431.72631)
			(xy 303.317531 -431.725807) (xy 303.288894 -431.733902) (xy 303.263805 -431.749907) (xy 303.244394 -431.772464)
			(xy 303.232309 -431.799659) (xy 303.228576 -431.829183) (xy 303.230534 -431.843942) (xy 303.233019 -431.859636)
			(xy 303.235693 -431.8913) (xy 303.235868 -431.907188) (xy 303.235435 -431.93444) (xy 303.22768 -431.988389)
			(xy 303.212327 -432.040685) (xy 303.189687 -432.090264) (xy 303.160222 -432.136116) (xy 303.124532 -432.177308)
			(xy 303.083343 -432.213002) (xy 303.037493 -432.242471) (xy 302.987916 -432.265115) (xy 302.935621 -432.280473)
			(xy 302.881673 -432.288233) (xy 302.82717 -432.288236) (xy 302.773221 -432.280482) (xy 302.720924 -432.26513)
			(xy 302.671345 -432.242492) (xy 302.625492 -432.213028) (xy 302.584298 -432.177339) (xy 302.548603 -432.13615)
			(xy 302.519133 -432.090301) (xy 302.496488 -432.040725) (xy 302.481129 -431.98843) (xy 302.473368 -431.934482)
			(xy 302.473364 -431.879979) (xy 274.477209 -431.879979) (xy 274.490182 -431.918992) (xy 274.537828 -432.087745)
			(xy 274.577686 -432.258505) (xy 274.609674 -432.430913) (xy 274.633724 -432.604606) (xy 274.649786 -432.779219)
			(xy 274.657825 -432.954385) (xy 274.658328 -433.04206) (xy 274.657825 -433.129735) (xy 274.649786 -433.304901)
			(xy 274.633724 -433.479514) (xy 274.609674 -433.653207) (xy 274.577686 -433.825615) (xy 274.537828 -433.996375)
			(xy 274.490182 -434.165128) (xy 274.43485 -434.331519) (xy 274.371948 -434.495199) (xy 274.301607 -434.655822)
			(xy 274.223977 -434.813052) (xy 274.139219 -434.966557) (xy 274.123129 -434.99278) (xy 278.489676 -434.99278)
			(xy 278.493642 -434.908249) (xy 278.505507 -434.824462) (xy 278.525165 -434.742153) (xy 278.552445 -434.662047)
			(xy 278.587106 -434.584848) (xy 278.628844 -434.511233) (xy 278.677291 -434.44185) (xy 278.732023 -434.377309)
			(xy 278.792559 -434.318177) (xy 278.858365 -434.264973) (xy 278.928865 -434.218165) (xy 279.003437 -434.178164)
			(xy 279.081428 -434.145322) (xy 279.162152 -434.119928) (xy 279.244899 -434.102205) (xy 279.328941 -434.092307)
			(xy 279.413542 -434.090324) (xy 279.497956 -434.096271) (xy 279.581443 -434.110096) (xy 279.663268 -434.131679)
			(xy 279.742712 -434.160829) (xy 279.819078 -434.19729) (xy 279.891694 -434.240742) (xy 279.959922 -434.290803)
			(xy 280.023162 -434.347033) (xy 280.080859 -434.408938) (xy 280.132506 -434.475974) (xy 280.177648 -434.547551)
			(xy 280.21589 -434.623041) (xy 280.246894 -434.70178) (xy 280.259789 -434.7464) (xy 282.099512 -434.7464)
			(xy 282.100064 -434.716636) (xy 282.109322 -434.657834) (xy 282.127599 -434.601182) (xy 282.154451 -434.548054)
			(xy 282.189226 -434.499741) (xy 282.209748 -434.478176) (xy 282.220182 -434.466921) (xy 282.234296 -434.439682)
			(xy 282.239712 -434.409485) (xy 282.235945 -434.379038) (xy 282.223332 -434.351072) (xy 282.213558 -434.339238)
			(xy 282.195524 -434.318194) (xy 282.165095 -434.271876) (xy 282.141694 -434.22164) (xy 282.125814 -434.168545)
			(xy 282.117789 -434.11371) (xy 282.117292 -434.086) (xy 282.117782 -434.058727) (xy 282.125557 -434.004736)
			(xy 282.140935 -433.952402) (xy 282.163602 -433.902787) (xy 282.193098 -433.856903) (xy 282.228823 -433.815682)
			(xy 282.249118 -433.797456) (xy 282.259544 -433.787753) (xy 282.275115 -433.763926) (xy 282.283494 -433.736722)
			(xy 282.284027 -433.708263) (xy 282.276674 -433.680765) (xy 282.262007 -433.65637) (xy 282.251912 -433.646326)
			(xy 282.233129 -433.628194) (xy 282.200149 -433.587724) (xy 282.172992 -433.543137) (xy 282.152166 -433.495265)
			(xy 282.138058 -433.445001) (xy 282.130932 -433.393283) (xy 282.1305 -433.36718) (xy 282.130986 -433.339929)
			(xy 282.138742 -433.285981) (xy 282.154097 -433.233686) (xy 282.176739 -433.184109) (xy 282.206205 -433.138259)
			(xy 282.241896 -433.097068) (xy 282.283087 -433.061377) (xy 282.328937 -433.031911) (xy 282.378514 -433.009269)
			(xy 282.430809 -432.993914) (xy 282.484757 -432.986158) (xy 282.539259 -432.986158) (xy 282.593207 -432.993914)
			(xy 282.645502 -433.009269) (xy 282.695079 -433.031911) (xy 282.740929 -433.061377) (xy 282.78212 -433.097068)
			(xy 282.817811 -433.138259) (xy 282.847277 -433.184109) (xy 282.869919 -433.233686) (xy 282.885274 -433.285981)
			(xy 282.89303 -433.339929) (xy 282.893516 -433.36718) (xy 282.893044 -433.394454) (xy 282.885269 -433.448447)
			(xy 282.86989 -433.500783) (xy 282.847219 -433.550398) (xy 282.817718 -433.596281) (xy 282.781988 -433.637499)
			(xy 282.76169 -433.655724) (xy 282.751184 -433.665347) (xy 282.735615 -433.689197) (xy 282.727245 -433.716421)
			(xy 282.726726 -433.744898) (xy 282.734099 -433.772409) (xy 282.748789 -433.79681) (xy 282.758896 -433.806854)
			(xy 282.77772 -433.824946) (xy 282.810695 -433.865425) (xy 282.837846 -433.91002) (xy 282.858666 -433.9579)
			(xy 282.872765 -434.008171) (xy 282.879881 -434.059895) (xy 282.880308 -434.086) (xy 282.87975 -434.115763)
			(xy 282.870492 -434.174566) (xy 282.852217 -434.231217) (xy 282.825366 -434.284345) (xy 282.790593 -434.332658)
			(xy 282.770072 -434.354224) (xy 282.759637 -434.365478) (xy 282.74552 -434.392717) (xy 282.740103 -434.422915)
			(xy 282.743871 -434.453363) (xy 282.756486 -434.481329) (xy 282.766262 -434.493162) (xy 282.784283 -434.514217)
			(xy 282.814716 -434.560531) (xy 282.838121 -434.610764) (xy 282.854004 -434.663857) (xy 282.86203 -434.718691)
			(xy 282.862528 -434.7464) (xy 282.862042 -434.773651) (xy 282.854286 -434.827599) (xy 282.838931 -434.879894)
			(xy 282.816289 -434.929471) (xy 282.786823 -434.975321) (xy 282.751132 -435.016512) (xy 282.709941 -435.052203)
			(xy 282.664091 -435.081669) (xy 282.614514 -435.104311) (xy 282.562219 -435.119666) (xy 282.508271 -435.127422)
			(xy 282.453769 -435.127422) (xy 282.399821 -435.119666) (xy 282.347526 -435.104311) (xy 282.297949 -435.081669)
			(xy 282.252099 -435.052203) (xy 282.210908 -435.016512) (xy 282.175217 -434.975321) (xy 282.145751 -434.929471)
			(xy 282.123109 -434.879894) (xy 282.107754 -434.827599) (xy 282.099998 -434.773651) (xy 282.099512 -434.7464)
			(xy 280.259789 -434.7464) (xy 280.270389 -434.783077) (xy 280.286168 -434.866216) (xy 280.294092 -434.950468)
			(xy 280.294588 -434.99278) (xy 280.294092 -435.035092) (xy 280.286168 -435.119344) (xy 280.270389 -435.202483)
			(xy 280.246894 -435.28378) (xy 280.21589 -435.362519) (xy 280.177648 -435.438009) (xy 280.132506 -435.509586)
			(xy 280.080859 -435.576622) (xy 280.023162 -435.638527) (xy 279.959922 -435.694757) (xy 279.891694 -435.744818)
			(xy 279.819078 -435.78827) (xy 279.806231 -435.794404) (xy 282.612082 -435.794404) (xy 282.616153 -435.738782)
			(xy 282.628279 -435.684345) (xy 282.648202 -435.632254) (xy 282.675498 -435.583619) (xy 282.709584 -435.539476)
			(xy 282.749733 -435.500767) (xy 282.795091 -435.468316) (xy 282.844691 -435.442815) (xy 282.897475 -435.424808)
			(xy 282.952318 -435.414678) (xy 283.008052 -435.412641) (xy 283.063489 -435.418741) (xy 283.117446 -435.432847)
			(xy 283.168775 -435.454659) (xy 283.216381 -435.483713) (xy 283.259249 -435.519388) (xy 283.296466 -435.560925)
			(xy 283.327239 -435.607438) (xy 283.350911 -435.657935) (xy 283.366979 -435.711342) (xy 283.375099 -435.766518)
			(xy 283.375608 -435.794404) (xy 283.375099 -435.82229) (xy 283.366979 -435.877466) (xy 283.350911 -435.930873)
			(xy 283.327239 -435.98137) (xy 283.296466 -436.027883) (xy 283.259249 -436.06942) (xy 283.216381 -436.105095)
			(xy 283.168775 -436.134149) (xy 283.117446 -436.155961) (xy 283.063489 -436.170067) (xy 283.008052 -436.176167)
			(xy 282.952318 -436.17413) (xy 282.897475 -436.164) (xy 282.844691 -436.145993) (xy 282.795091 -436.120492)
			(xy 282.749733 -436.088041) (xy 282.709584 -436.049332) (xy 282.675498 -436.005189) (xy 282.648202 -435.956554)
			(xy 282.628279 -435.904463) (xy 282.616153 -435.850026) (xy 282.612082 -435.794404) (xy 279.806231 -435.794404)
			(xy 279.742712 -435.824731) (xy 279.663268 -435.853881) (xy 279.581443 -435.875464) (xy 279.497956 -435.889289)
			(xy 279.413542 -435.895236) (xy 279.328941 -435.893253) (xy 279.244899 -435.883355) (xy 279.162152 -435.865632)
			(xy 279.081428 -435.840238) (xy 279.003437 -435.807396) (xy 278.928865 -435.767395) (xy 278.858365 -435.720587)
			(xy 278.792559 -435.667383) (xy 278.732023 -435.608251) (xy 278.677291 -435.54371) (xy 278.628844 -435.474327)
			(xy 278.587106 -435.400712) (xy 278.552445 -435.323513) (xy 278.525165 -435.243407) (xy 278.505507 -435.161098)
			(xy 278.493642 -435.077311) (xy 278.489676 -434.99278) (xy 274.123129 -434.99278) (xy 274.047513 -435.116015)
			(xy 273.949052 -435.261112) (xy 273.844042 -435.401542) (xy 273.732703 -435.537009) (xy 273.615272 -435.66723)
			(xy 273.491993 -435.79193) (xy 273.363127 -435.910847) (xy 273.228945 -436.023731) (xy 273.089728 -436.130345)
			(xy 272.94577 -436.230464) (xy 272.797374 -436.323877) (xy 272.64485 -436.410389) (xy 272.488521 -436.489817)
			(xy 272.328714 -436.561994) (xy 272.165767 -436.626769) (xy 272.000021 -436.684006) (xy 271.831825 -436.733583)
			(xy 271.661533 -436.775397) (xy 271.489504 -436.809359) (xy 271.316098 -436.835399) (xy 271.14168 -436.853462)
			(xy 270.966618 -436.863509) (xy 270.79128 -436.865519) (xy 270.616033 -436.859489) (xy 270.441247 -436.84543)
			(xy 270.26729 -436.823373) (xy 270.094527 -436.793364) (xy 269.923321 -436.755466) (xy 269.754033 -436.709758)
			(xy 269.587018 -436.656338) (xy 269.422628 -436.595316) (xy 269.261209 -436.526822) (xy 269.103099 -436.450999)
			(xy 268.948632 -436.368007) (xy 268.798133 -436.278021) (xy 268.651917 -436.181229) (xy 268.510292 -436.077836)
			(xy 268.373557 -435.968059) (xy 268.241998 -435.852128) (xy 268.115893 -435.730287) (xy 267.995506 -435.602793)
			(xy 267.881091 -435.469914) (xy 267.772888 -435.331929) (xy 267.671126 -435.189128) (xy 267.576017 -435.041812)
			(xy 267.487762 -434.89029) (xy 267.406547 -434.734882) (xy 267.332542 -434.575914) (xy 267.265903 -434.41372)
			(xy 267.20677 -434.248641) (xy 267.155267 -434.081025) (xy 267.111504 -433.911223) (xy 267.075571 -433.739594)
			(xy 267.047545 -433.566498) (xy 267.027484 -433.3923) (xy 267.01543 -433.217364) (xy 267.01141 -433.04206)
			(xy 241.1095 -433.04206) (xy 241.1095 -437.33466) (xy 241.307777 -437.53278) (xy 278.489676 -437.53278)
			(xy 278.493642 -437.448249) (xy 278.505507 -437.364462) (xy 278.525165 -437.282153) (xy 278.552445 -437.202047)
			(xy 278.587106 -437.124848) (xy 278.628844 -437.051233) (xy 278.677291 -436.98185) (xy 278.732023 -436.917309)
			(xy 278.792559 -436.858177) (xy 278.858365 -436.804973) (xy 278.928865 -436.758165) (xy 279.003437 -436.718164)
			(xy 279.081428 -436.685322) (xy 279.162152 -436.659928) (xy 279.244899 -436.642205) (xy 279.328941 -436.632307)
			(xy 279.413542 -436.630324) (xy 279.497956 -436.636271) (xy 279.581443 -436.650096) (xy 279.663268 -436.671679)
			(xy 279.66961 -436.674006) (xy 281.726384 -436.674006) (xy 281.730455 -436.618384) (xy 281.742581 -436.563947)
			(xy 281.762504 -436.511856) (xy 281.7898 -436.463221) (xy 281.823886 -436.419078) (xy 281.864035 -436.380369)
			(xy 281.909393 -436.347918) (xy 281.958993 -436.322417) (xy 282.011777 -436.30441) (xy 282.06662 -436.29428)
			(xy 282.122354 -436.292243) (xy 282.177791 -436.298343) (xy 282.231748 -436.312449) (xy 282.283077 -436.334261)
			(xy 282.330683 -436.363315) (xy 282.373551 -436.39899) (xy 282.410768 -436.440527) (xy 282.441541 -436.48704)
			(xy 282.465213 -436.537537) (xy 282.481281 -436.590944) (xy 282.489401 -436.64612) (xy 282.48991 -436.674006)
			(xy 282.489401 -436.701892) (xy 282.481281 -436.757068) (xy 282.465213 -436.810475) (xy 282.441541 -436.860972)
			(xy 282.410768 -436.907485) (xy 282.373551 -436.949022) (xy 282.330683 -436.984697) (xy 282.283077 -437.013751)
			(xy 282.231748 -437.035563) (xy 282.177791 -437.049669) (xy 282.122354 -437.055769) (xy 282.06662 -437.053732)
			(xy 282.011777 -437.043602) (xy 281.958993 -437.025595) (xy 281.909393 -437.000094) (xy 281.864035 -436.967643)
			(xy 281.823886 -436.928934) (xy 281.7898 -436.884791) (xy 281.762504 -436.836156) (xy 281.742581 -436.784065)
			(xy 281.730455 -436.729628) (xy 281.726384 -436.674006) (xy 279.66961 -436.674006) (xy 279.742712 -436.700829)
			(xy 279.819078 -436.73729) (xy 279.891694 -436.780742) (xy 279.959922 -436.830803) (xy 280.023162 -436.887033)
			(xy 280.080859 -436.948938) (xy 280.132506 -437.015974) (xy 280.177648 -437.087551) (xy 280.21589 -437.163041)
			(xy 280.246894 -437.24178) (xy 280.270389 -437.323077) (xy 280.286168 -437.406216) (xy 280.294092 -437.490468)
			(xy 280.294588 -437.53278) (xy 280.294092 -437.575092) (xy 280.286168 -437.659344) (xy 280.270389 -437.742483)
			(xy 280.246894 -437.82378) (xy 280.21589 -437.902519) (xy 280.177648 -437.978009) (xy 280.132506 -438.049586)
			(xy 280.080859 -438.116622) (xy 280.023162 -438.178527) (xy 279.959922 -438.234757) (xy 279.891694 -438.284818)
			(xy 279.819078 -438.32827) (xy 279.742712 -438.364731) (xy 279.663268 -438.393881) (xy 279.581443 -438.415464)
			(xy 279.497956 -438.429289) (xy 279.413542 -438.435236) (xy 279.328941 -438.433253) (xy 279.244899 -438.423355)
			(xy 279.162152 -438.405632) (xy 279.081428 -438.380238) (xy 279.003437 -438.347396) (xy 278.928865 -438.307395)
			(xy 278.858365 -438.260587) (xy 278.792559 -438.207383) (xy 278.732023 -438.148251) (xy 278.677291 -438.08371)
			(xy 278.628844 -438.014327) (xy 278.587106 -437.940712) (xy 278.552445 -437.863513) (xy 278.525165 -437.783407)
			(xy 278.505507 -437.701098) (xy 278.493642 -437.617311) (xy 278.489676 -437.53278) (xy 241.307777 -437.53278)
			(xy 241.429286 -437.654192) (xy 277.8506 -437.654192) (xy 277.875587 -437.654659) (xy 277.924945 -437.662487)
			(xy 277.972466 -437.677951) (xy 278.016979 -437.700669) (xy 278.057383 -437.730079) (xy 278.07539 -437.74741)
			(xy 279.150572 -438.822592) (xy 281.325828 -438.822592) (xy 282.657804 -437.490616) (xy 282.66136 -437.476646)
			(xy 282.668455 -437.449237) (xy 282.689639 -437.396736) (xy 282.718356 -437.347946) (xy 282.753975 -437.30394)
			(xy 282.795712 -437.265688) (xy 282.842649 -437.234032) (xy 282.893752 -437.209666) (xy 282.947897 -437.193129)
			(xy 283.003893 -437.184783) (xy 283.0322 -437.184292) (xy 283.058934 -437.184735) (xy 283.11188 -437.192189)
			(xy 283.163266 -437.206964) (xy 283.212085 -437.228771) (xy 283.25738 -437.257183) (xy 283.298263 -437.291642)
			(xy 283.333932 -437.331474) (xy 283.363689 -437.375896) (xy 283.386949 -437.42404) (xy 283.403258 -437.47496)
			(xy 283.412296 -437.527659) (xy 283.413454 -437.55437) (xy 283.414978 -437.603392) (xy 284.091126 -437.603392)
			(xy 284.114703 -437.588343) (xy 284.165332 -437.56457) (xy 284.218892 -437.548451) (xy 284.274233 -437.540335)
			(xy 284.3022 -437.539892) (xy 284.329451 -437.540378) (xy 284.383399 -437.548134) (xy 284.435694 -437.563489)
			(xy 284.485271 -437.586131) (xy 284.531121 -437.615597) (xy 284.572312 -437.651288) (xy 284.608003 -437.692479)
			(xy 284.637469 -437.738329) (xy 284.660111 -437.787906) (xy 284.675466 -437.840201) (xy 284.683222 -437.894149)
			(xy 284.683708 -437.9214) (xy 284.68325 -437.948265) (xy 284.675713 -438.001465) (xy 284.660788 -438.053081)
			(xy 284.63877 -438.102093) (xy 284.610095 -438.147533) (xy 284.57533 -438.1885) (xy 284.535161 -438.224186)
			(xy 284.51302 -438.239408) (xy 284.501748 -438.247469) (xy 284.483659 -438.268445) (xy 284.471864 -438.293508)
			(xy 284.467232 -438.320817) (xy 284.470102 -438.348368) (xy 284.480263 -438.374136) (xy 284.496969 -438.39623)
			(xy 284.507686 -438.405016) (xy 284.530673 -438.423181) (xy 284.571327 -438.465368) (xy 284.602165 -438.509156)
			(xy 302.684178 -438.509156) (xy 302.688249 -438.453534) (xy 302.700375 -438.399097) (xy 302.720298 -438.347006)
			(xy 302.747594 -438.298371) (xy 302.78168 -438.254228) (xy 302.821829 -438.215519) (xy 302.867187 -438.183068)
			(xy 302.916787 -438.157567) (xy 302.969571 -438.13956) (xy 303.024414 -438.12943) (xy 303.080148 -438.127393)
			(xy 303.135585 -438.133493) (xy 303.189542 -438.147599) (xy 303.240871 -438.169411) (xy 303.288477 -438.198465)
			(xy 303.331345 -438.23414) (xy 303.368562 -438.275677) (xy 303.399335 -438.32219) (xy 303.423007 -438.372687)
			(xy 303.439075 -438.426094) (xy 303.447195 -438.48127) (xy 303.447704 -438.509156) (xy 303.447495 -438.520586)
			(xy 305.418488 -438.520586) (xy 305.422559 -438.464964) (xy 305.434685 -438.410527) (xy 305.454608 -438.358436)
			(xy 305.481904 -438.309801) (xy 305.51599 -438.265658) (xy 305.556139 -438.226949) (xy 305.601497 -438.194498)
			(xy 305.651097 -438.168997) (xy 305.703881 -438.15099) (xy 305.758724 -438.14086) (xy 305.814458 -438.138823)
			(xy 305.869895 -438.144923) (xy 305.923852 -438.159029) (xy 305.975181 -438.180841) (xy 306.022787 -438.209895)
			(xy 306.065655 -438.24557) (xy 306.102872 -438.287107) (xy 306.133645 -438.33362) (xy 306.157317 -438.384117)
			(xy 306.173385 -438.437524) (xy 306.181505 -438.4927) (xy 306.182014 -438.520586) (xy 306.181505 -438.548472)
			(xy 306.175703 -438.587896) (xy 308.185818 -438.587896) (xy 308.189889 -438.532274) (xy 308.202015 -438.477837)
			(xy 308.221938 -438.425746) (xy 308.249234 -438.377111) (xy 308.28332 -438.332968) (xy 308.323469 -438.294259)
			(xy 308.368827 -438.261808) (xy 308.418427 -438.236307) (xy 308.471211 -438.2183) (xy 308.526054 -438.20817)
			(xy 308.581788 -438.206133) (xy 308.637225 -438.212233) (xy 308.691182 -438.226339) (xy 308.742511 -438.248151)
			(xy 308.790117 -438.277205) (xy 308.832985 -438.31288) (xy 308.870202 -438.354417) (xy 308.900975 -438.40093)
			(xy 308.924647 -438.451427) (xy 308.940715 -438.504834) (xy 308.948835 -438.56001) (xy 308.949344 -438.587896)
			(xy 308.948835 -438.615782) (xy 308.940715 -438.670958) (xy 308.924647 -438.724365) (xy 308.900975 -438.774862)
			(xy 308.870202 -438.821375) (xy 308.832985 -438.862912) (xy 308.790117 -438.898587) (xy 308.742511 -438.927641)
			(xy 308.691182 -438.949453) (xy 308.637225 -438.963559) (xy 308.581788 -438.969659) (xy 308.526054 -438.967622)
			(xy 308.471211 -438.957492) (xy 308.418427 -438.939485) (xy 308.368827 -438.913984) (xy 308.323469 -438.881533)
			(xy 308.28332 -438.842824) (xy 308.249234 -438.798681) (xy 308.221938 -438.750046) (xy 308.202015 -438.697955)
			(xy 308.189889 -438.643518) (xy 308.185818 -438.587896) (xy 306.175703 -438.587896) (xy 306.173385 -438.603648)
			(xy 306.157317 -438.657055) (xy 306.133645 -438.707552) (xy 306.102872 -438.754065) (xy 306.065655 -438.795602)
			(xy 306.022787 -438.831277) (xy 305.975181 -438.860331) (xy 305.923852 -438.882143) (xy 305.869895 -438.896249)
			(xy 305.814458 -438.902349) (xy 305.758724 -438.900312) (xy 305.703881 -438.890182) (xy 305.651097 -438.872175)
			(xy 305.601497 -438.846674) (xy 305.556139 -438.814223) (xy 305.51599 -438.775514) (xy 305.481904 -438.731371)
			(xy 305.454608 -438.682736) (xy 305.434685 -438.630645) (xy 305.422559 -438.576208) (xy 305.418488 -438.520586)
			(xy 303.447495 -438.520586) (xy 303.447195 -438.537042) (xy 303.439075 -438.592218) (xy 303.423007 -438.645625)
			(xy 303.399335 -438.696122) (xy 303.368562 -438.742635) (xy 303.331345 -438.784172) (xy 303.288477 -438.819847)
			(xy 303.240871 -438.848901) (xy 303.189542 -438.870713) (xy 303.135585 -438.884819) (xy 303.080148 -438.890919)
			(xy 303.024414 -438.888882) (xy 302.969571 -438.878752) (xy 302.916787 -438.860745) (xy 302.867187 -438.835244)
			(xy 302.821829 -438.802793) (xy 302.78168 -438.764084) (xy 302.747594 -438.719941) (xy 302.720298 -438.671306)
			(xy 302.700375 -438.619215) (xy 302.688249 -438.564778) (xy 302.684178 -438.509156) (xy 284.602165 -438.509156)
			(xy 284.605062 -438.513269) (xy 284.631084 -438.56576) (xy 284.648785 -438.621609) (xy 284.657748 -438.679507)
			(xy 284.658308 -438.7088) (xy 284.657869 -438.734775) (xy 284.650817 -438.786246) (xy 284.636845 -438.836282)
			(xy 284.61621 -438.88396) (xy 284.589295 -438.928395) (xy 284.556597 -438.968765) (xy 284.518722 -439.004323)
			(xy 284.49778 -439.019696) (xy 284.486767 -439.028105) (xy 284.469345 -439.049637) (xy 284.458352 -439.075059)
			(xy 284.454595 -439.1025) (xy 284.458352 -439.129941) (xy 284.469345 -439.155363) (xy 284.486767 -439.176895)
			(xy 284.49778 -439.185304) (xy 284.518709 -439.200697) (xy 284.556598 -439.236242) (xy 284.589307 -439.276604)
			(xy 284.616231 -439.321036) (xy 284.636869 -439.368713) (xy 284.65084 -439.418751) (xy 284.657883 -439.470224)
			(xy 284.658308 -439.4962) (xy 284.657822 -439.523451) (xy 284.650066 -439.577399) (xy 284.634711 -439.629694)
			(xy 284.612069 -439.679271) (xy 284.582603 -439.725121) (xy 284.546912 -439.766312) (xy 284.505721 -439.802003)
			(xy 284.459871 -439.831469) (xy 284.410294 -439.854111) (xy 284.357999 -439.869466) (xy 284.304051 -439.877222)
			(xy 284.2768 -439.877708) (xy 284.248836 -439.877234) (xy 284.193501 -439.869106) (xy 284.139944 -439.852995)
			(xy 284.089309 -439.829244) (xy 284.065726 -439.814208) (xy 283.316172 -439.814208) (xy 282.819602 -440.310778)
			(xy 282.809386 -440.321741) (xy 282.795257 -440.348151) (xy 282.789398 -440.377524) (xy 282.792312 -440.407333)
			(xy 282.803749 -440.435016) (xy 282.822724 -440.45819) (xy 282.847606 -440.474862) (xy 282.876255 -440.483599)
			(xy 282.89123 -440.48426) (xy 309.34914 -440.48426)
		)
		(stroke
			(width 0)
			(type solid)
		)
		(fill yes)
		(layer "In13.Cu")
		(net "GND")
	)
	(gr_poly
		(pts
			(xy 303.360836 -376.412252) (xy 303.360836 -362.208318) (xy 303.329594 -362.195364) (xy 303.305601 -362.184867)
			(xy 303.26073 -362.157866) (xy 303.220298 -362.124583) (xy 303.185178 -362.085736) (xy 303.156127 -362.042163)
			(xy 303.133772 -361.994806) (xy 303.118596 -361.944684) (xy 303.110925 -361.89288) (xy 303.110926 -361.840511)
			(xy 303.118598 -361.788707) (xy 303.133775 -361.738586) (xy 303.156132 -361.691228) (xy 303.185184 -361.647657)
			(xy 303.220305 -361.608811) (xy 303.260737 -361.575529) (xy 303.305609 -361.548529) (xy 303.329594 -361.538012)
			(xy 303.360836 -361.525058) (xy 303.360836 -359.40365) (xy 302.527462 -350.40316) (xy 302.204374 -350.080072)
			(xy 302.194318 -350.070664) (xy 302.170359 -350.057113) (xy 302.143652 -350.050449) (xy 302.116135 -350.051158)
			(xy 302.089806 -350.059187) (xy 302.066577 -350.073954) (xy 302.048133 -350.094387) (xy 302.04156 -350.106488)
			(xy 302.030423 -350.127918) (xy 302.003549 -350.168047) (xy 301.987966 -350.186498) (xy 301.978732 -350.197826)
			(xy 301.966559 -350.224384) (xy 301.962388 -350.2533) (xy 301.966559 -350.282216) (xy 301.978732 -350.308774)
			(xy 301.987966 -350.320102) (xy 302.005607 -350.341035) (xy 302.035332 -350.387002) (xy 302.058178 -350.436748)
			(xy 302.073675 -350.489251) (xy 302.081503 -350.543429) (xy 302.081503 -350.598171) (xy 302.073675 -350.652349)
			(xy 302.058178 -350.704852) (xy 302.035332 -350.754598) (xy 302.005607 -350.800565) (xy 301.987966 -350.821498)
			(xy 301.978732 -350.832826) (xy 301.966559 -350.859384) (xy 301.962388 -350.8883) (xy 301.966559 -350.917216)
			(xy 301.978732 -350.943774) (xy 301.987966 -350.955102) (xy 302.005607 -350.976035) (xy 302.035332 -351.022002)
			(xy 302.058178 -351.071748) (xy 302.073675 -351.124251) (xy 302.081503 -351.178429) (xy 302.081503 -351.233171)
			(xy 302.073675 -351.287349) (xy 302.058178 -351.339852) (xy 302.035332 -351.389598) (xy 302.005607 -351.435565)
			(xy 301.987966 -351.456498) (xy 301.978732 -351.467826) (xy 301.966559 -351.494384) (xy 301.962388 -351.5233)
			(xy 301.966559 -351.552216) (xy 301.978732 -351.578774) (xy 301.987966 -351.590102) (xy 302.005609 -351.611033)
			(xy 302.035338 -351.656998) (xy 302.058183 -351.706745) (xy 302.073674 -351.759249) (xy 302.081493 -351.813429)
			(xy 302.081946 -351.8408) (xy 302.08146 -351.868052) (xy 302.073704 -351.922002) (xy 302.058349 -351.974299)
			(xy 302.035709 -352.023879) (xy 302.006243 -352.069732) (xy 301.970552 -352.110925) (xy 301.929362 -352.14662)
			(xy 301.883512 -352.17609) (xy 301.833935 -352.198736) (xy 301.781639 -352.214096) (xy 301.72769 -352.221858)
			(xy 301.700438 -352.222308) (xy 301.673069 -352.221832) (xy 301.618895 -352.214) (xy 301.566397 -352.198507)
			(xy 301.516651 -352.175669) (xy 301.47068 -352.145957) (xy 301.44974 -352.128328) (xy 301.438412 -352.119092)
			(xy 301.411855 -352.106916) (xy 301.382938 -352.102743) (xy 301.354021 -352.106916) (xy 301.327464 -352.119092)
			(xy 301.316136 -352.128328) (xy 301.295203 -352.145965) (xy 301.249234 -352.175681) (xy 301.199487 -352.198515)
			(xy 301.146984 -352.213995) (xy 301.092807 -352.221804) (xy 301.065438 -352.222308) (xy 301.037395 -352.221835)
			(xy 300.981907 -352.213662) (xy 300.928217 -352.197443) (xy 300.877486 -352.173528) (xy 300.830808 -352.142434)
			(xy 300.80966 -352.12401) (xy 300.798218 -352.114365) (xy 300.771175 -352.101585) (xy 300.741588 -352.097199)
			(xy 300.712001 -352.101585) (xy 300.684958 -352.114365) (xy 300.673516 -352.12401) (xy 300.652363 -352.142425)
			(xy 300.605673 -352.173495) (xy 300.554941 -352.197402) (xy 300.501259 -352.213634) (xy 300.445779 -352.221841)
			(xy 300.417738 -352.222308) (xy 300.390483 -352.221847) (xy 300.336528 -352.214095) (xy 300.284226 -352.198742)
			(xy 300.234641 -352.176102) (xy 300.188783 -352.146635) (xy 300.147586 -352.110941) (xy 300.111888 -352.069747)
			(xy 300.082417 -352.023892) (xy 300.059771 -351.97431) (xy 300.044413 -351.922009) (xy 300.036655 -351.868055)
			(xy 300.03623 -351.8408) (xy 300.036702 -351.81343) (xy 300.044526 -351.759252) (xy 300.060014 -351.706749)
			(xy 300.082848 -351.656999) (xy 300.112558 -351.611024) (xy 300.13021 -351.590102) (xy 300.139446 -351.578774)
			(xy 300.151622 -351.552217) (xy 300.155794 -351.5233) (xy 300.151622 -351.494383) (xy 300.139446 -351.467826)
			(xy 300.13021 -351.456498) (xy 300.11257 -351.435565) (xy 300.082847 -351.389597) (xy 300.060002 -351.33985)
			(xy 300.044507 -351.287349) (xy 300.036678 -351.23317) (xy 300.036678 -351.17843) (xy 300.044507 -351.124251)
			(xy 300.060002 -351.07175) (xy 300.082847 -351.022003) (xy 300.11257 -350.976035) (xy 300.13021 -350.955102)
			(xy 300.139446 -350.943774) (xy 300.151622 -350.917217) (xy 300.155794 -350.8883) (xy 300.151622 -350.859383)
			(xy 300.139446 -350.832826) (xy 300.13021 -350.821498) (xy 300.11257 -350.800565) (xy 300.082847 -350.754597)
			(xy 300.060002 -350.70485) (xy 300.044507 -350.652349) (xy 300.036678 -350.59817) (xy 300.036678 -350.54343)
			(xy 300.044507 -350.489251) (xy 300.060002 -350.43675) (xy 300.082847 -350.387003) (xy 300.11257 -350.341035)
			(xy 300.13021 -350.320102) (xy 300.139446 -350.308774) (xy 300.151622 -350.282217) (xy 300.155794 -350.2533)
			(xy 300.151622 -350.224383) (xy 300.139446 -350.197826) (xy 300.13021 -350.186498) (xy 300.11257 -350.165565)
			(xy 300.082847 -350.119597) (xy 300.060002 -350.06985) (xy 300.044507 -350.017349) (xy 300.036678 -349.96317)
			(xy 300.036678 -349.90843) (xy 300.044507 -349.854251) (xy 300.060002 -349.80175) (xy 300.082847 -349.752003)
			(xy 300.11257 -349.706035) (xy 300.13021 -349.685102) (xy 300.139446 -349.673774) (xy 300.151622 -349.647217)
			(xy 300.155794 -349.6183) (xy 300.151622 -349.589383) (xy 300.139446 -349.562826) (xy 300.13021 -349.551498)
			(xy 300.11257 -349.530565) (xy 300.082847 -349.484597) (xy 300.060002 -349.43485) (xy 300.044507 -349.382349)
			(xy 300.036678 -349.32817) (xy 300.036678 -349.27343) (xy 300.044507 -349.219251) (xy 300.060002 -349.16675)
			(xy 300.082847 -349.117003) (xy 300.11257 -349.071035) (xy 300.13021 -349.050102) (xy 300.139446 -349.038774)
			(xy 300.151622 -349.012217) (xy 300.155794 -348.9833) (xy 300.151622 -348.954383) (xy 300.139446 -348.927826)
			(xy 300.13021 -348.916498) (xy 300.11257 -348.895565) (xy 300.082847 -348.849597) (xy 300.060002 -348.79985)
			(xy 300.044507 -348.747349) (xy 300.036678 -348.69317) (xy 300.036678 -348.63843) (xy 300.044507 -348.584251)
			(xy 300.060002 -348.53175) (xy 300.082847 -348.482003) (xy 300.11257 -348.436035) (xy 300.13021 -348.415102)
			(xy 300.139446 -348.403774) (xy 300.151622 -348.377217) (xy 300.155794 -348.3483) (xy 300.151622 -348.319383)
			(xy 300.139446 -348.292826) (xy 300.13021 -348.281498) (xy 300.112568 -348.260567) (xy 300.082841 -348.214601)
			(xy 300.059998 -348.164854) (xy 300.044507 -348.11235) (xy 300.036689 -348.058171) (xy 300.03623 -348.0308)
			(xy 300.036693 -348.003548) (xy 300.044451 -347.949599) (xy 300.059807 -347.897304) (xy 300.08245 -347.847726)
			(xy 300.111919 -347.801875) (xy 300.147613 -347.760686) (xy 300.188806 -347.724996) (xy 300.234659 -347.695532)
			(xy 300.284239 -347.672894) (xy 300.336536 -347.657542) (xy 300.390486 -347.649791) (xy 300.417738 -347.649292)
			(xy 300.445782 -347.649763) (xy 300.501271 -347.657933) (xy 300.554963 -347.67415) (xy 300.605697 -347.698063)
			(xy 300.652378 -347.729155) (xy 300.673516 -347.74759) (xy 300.684958 -347.757235) (xy 300.712001 -347.770015)
			(xy 300.741588 -347.774401) (xy 300.771175 -347.770015) (xy 300.798218 -347.757235) (xy 300.80966 -347.74759)
			(xy 300.830814 -347.729179) (xy 300.877507 -347.698119) (xy 300.928239 -347.674221) (xy 300.981921 -347.658)
			(xy 301.037398 -347.649804) (xy 301.065438 -347.649292) (xy 301.092807 -347.649766) (xy 301.146983 -347.657595)
			(xy 301.199484 -347.673086) (xy 301.249231 -347.695921) (xy 301.295205 -347.725632) (xy 301.316136 -347.743272)
			(xy 301.327464 -347.752508) (xy 301.354021 -347.764684) (xy 301.382938 -347.768857) (xy 301.411855 -347.764684)
			(xy 301.438412 -347.752508) (xy 301.44974 -347.743272) (xy 301.470673 -347.725633) (xy 301.516641 -347.695914)
			(xy 301.566388 -347.673078) (xy 301.618891 -347.657595) (xy 301.673069 -347.649782) (xy 301.700438 -347.649292)
			(xy 301.729602 -347.649849) (xy 301.787248 -347.658735) (xy 301.84287 -347.676295) (xy 301.895169 -347.702119)
			(xy 301.919386 -347.71838) (xy 301.931012 -347.725979) (xy 301.957186 -347.735234) (xy 301.984886 -347.737091)
			(xy 302.012061 -347.731414) (xy 302.036701 -347.718621) (xy 302.05698 -347.699661) (xy 302.071397 -347.675936)
			(xy 302.078886 -347.649203) (xy 302.079406 -347.635322) (xy 302.079406 -345.564206) (xy 302.056292 -345.313762)
			(xy 301.866808 -344.236294) (xy 300.41723 -342.786716) (xy 284.279848 -342.786716) (xy 282.894786 -344.171778)
			(xy 282.894786 -344.7427) (xy 286.410396 -344.7427) (xy 286.410396 -344.658004) (xy 286.418447 -344.57369)
			(xy 286.434476 -344.490524) (xy 286.458337 -344.409257) (xy 286.489816 -344.330627) (xy 286.528627 -344.255346)
			(xy 286.574417 -344.184094) (xy 286.626773 -344.117518) (xy 286.685221 -344.05622) (xy 286.749231 -344.000755)
			(xy 286.818223 -343.951626) (xy 286.891573 -343.909277) (xy 286.968616 -343.874093) (xy 287.048655 -343.846391)
			(xy 287.130964 -343.826423) (xy 287.214799 -343.81437) (xy 287.2994 -343.81034) (xy 287.384001 -343.81437)
			(xy 287.467836 -343.826423) (xy 287.550145 -343.846391) (xy 287.630184 -343.874093) (xy 287.707227 -343.909277)
			(xy 287.780577 -343.951626) (xy 287.849569 -344.000755) (xy 287.913579 -344.05622) (xy 287.972027 -344.117518)
			(xy 288.024383 -344.184094) (xy 288.070173 -344.255346) (xy 288.108984 -344.330627) (xy 288.140463 -344.409257)
			(xy 288.164324 -344.490524) (xy 288.180353 -344.57369) (xy 288.188404 -344.658004) (xy 288.188908 -344.700352)
			(xy 288.188404 -344.7427) (xy 292.607996 -344.7427) (xy 292.607996 -344.658004) (xy 292.616047 -344.57369)
			(xy 292.632076 -344.490524) (xy 292.655937 -344.409257) (xy 292.687416 -344.330627) (xy 292.726227 -344.255346)
			(xy 292.772017 -344.184094) (xy 292.824373 -344.117518) (xy 292.882821 -344.05622) (xy 292.946831 -344.000755)
			(xy 293.015823 -343.951626) (xy 293.089173 -343.909277) (xy 293.166216 -343.874093) (xy 293.246255 -343.846391)
			(xy 293.328564 -343.826423) (xy 293.412399 -343.81437) (xy 293.497 -343.81034) (xy 293.581601 -343.81437)
			(xy 293.665436 -343.826423) (xy 293.747745 -343.846391) (xy 293.827784 -343.874093) (xy 293.904827 -343.909277)
			(xy 293.978177 -343.951626) (xy 294.047169 -344.000755) (xy 294.111179 -344.05622) (xy 294.169627 -344.117518)
			(xy 294.221983 -344.184094) (xy 294.267773 -344.255346) (xy 294.306584 -344.330627) (xy 294.338063 -344.409257)
			(xy 294.361924 -344.490524) (xy 294.377953 -344.57369) (xy 294.386004 -344.658004) (xy 294.386508 -344.700352)
			(xy 294.386004 -344.7427) (xy 298.805596 -344.7427) (xy 298.805596 -344.658004) (xy 298.813647 -344.57369)
			(xy 298.829676 -344.490524) (xy 298.853537 -344.409257) (xy 298.885016 -344.330627) (xy 298.923827 -344.255346)
			(xy 298.969617 -344.184094) (xy 299.021973 -344.117518) (xy 299.080421 -344.05622) (xy 299.144431 -344.000755)
			(xy 299.213423 -343.951626) (xy 299.286773 -343.909277) (xy 299.363816 -343.874093) (xy 299.443855 -343.846391)
			(xy 299.526164 -343.826423) (xy 299.609999 -343.81437) (xy 299.6946 -343.81034) (xy 299.779201 -343.81437)
			(xy 299.863036 -343.826423) (xy 299.945345 -343.846391) (xy 300.025384 -343.874093) (xy 300.102427 -343.909277)
			(xy 300.175777 -343.951626) (xy 300.244769 -344.000755) (xy 300.308779 -344.05622) (xy 300.367227 -344.117518)
			(xy 300.419583 -344.184094) (xy 300.465373 -344.255346) (xy 300.504184 -344.330627) (xy 300.535663 -344.409257)
			(xy 300.559524 -344.490524) (xy 300.575553 -344.57369) (xy 300.583604 -344.658004) (xy 300.584108 -344.700352)
			(xy 300.583604 -344.7427) (xy 300.575553 -344.827014) (xy 300.559524 -344.91018) (xy 300.535663 -344.991447)
			(xy 300.504184 -345.070077) (xy 300.465373 -345.145358) (xy 300.419583 -345.21661) (xy 300.367227 -345.283186)
			(xy 300.308779 -345.344484) (xy 300.244769 -345.399949) (xy 300.175777 -345.449078) (xy 300.102427 -345.491427)
			(xy 300.025384 -345.526611) (xy 299.945345 -345.554313) (xy 299.863036 -345.574281) (xy 299.779201 -345.586334)
			(xy 299.6946 -345.590365) (xy 299.609999 -345.586334) (xy 299.526164 -345.574281) (xy 299.443855 -345.554313)
			(xy 299.363816 -345.526611) (xy 299.286773 -345.491427) (xy 299.213423 -345.449078) (xy 299.144431 -345.399949)
			(xy 299.080421 -345.344484) (xy 299.021973 -345.283186) (xy 298.969617 -345.21661) (xy 298.923827 -345.145358)
			(xy 298.885016 -345.070077) (xy 298.853537 -344.991447) (xy 298.829676 -344.91018) (xy 298.813647 -344.827014)
			(xy 298.805596 -344.7427) (xy 294.386004 -344.7427) (xy 294.377953 -344.827014) (xy 294.361924 -344.91018)
			(xy 294.338063 -344.991447) (xy 294.306584 -345.070077) (xy 294.267773 -345.145358) (xy 294.221983 -345.21661)
			(xy 294.169627 -345.283186) (xy 294.111179 -345.344484) (xy 294.047169 -345.399949) (xy 293.978177 -345.449078)
			(xy 293.904827 -345.491427) (xy 293.827784 -345.526611) (xy 293.747745 -345.554313) (xy 293.665436 -345.574281)
			(xy 293.581601 -345.586334) (xy 293.497 -345.590365) (xy 293.412399 -345.586334) (xy 293.328564 -345.574281)
			(xy 293.246255 -345.554313) (xy 293.166216 -345.526611) (xy 293.089173 -345.491427) (xy 293.015823 -345.449078)
			(xy 292.946831 -345.399949) (xy 292.882821 -345.344484) (xy 292.824373 -345.283186) (xy 292.772017 -345.21661)
			(xy 292.726227 -345.145358) (xy 292.687416 -345.070077) (xy 292.655937 -344.991447) (xy 292.632076 -344.91018)
			(xy 292.616047 -344.827014) (xy 292.607996 -344.7427) (xy 288.188404 -344.7427) (xy 288.180353 -344.827014)
			(xy 288.164324 -344.91018) (xy 288.140463 -344.991447) (xy 288.108984 -345.070077) (xy 288.070173 -345.145358)
			(xy 288.024383 -345.21661) (xy 287.972027 -345.283186) (xy 287.913579 -345.344484) (xy 287.849569 -345.399949)
			(xy 287.780577 -345.449078) (xy 287.707227 -345.491427) (xy 287.630184 -345.526611) (xy 287.550145 -345.554313)
			(xy 287.467836 -345.574281) (xy 287.384001 -345.586334) (xy 287.2994 -345.590365) (xy 287.214799 -345.586334)
			(xy 287.130964 -345.574281) (xy 287.048655 -345.554313) (xy 286.968616 -345.526611) (xy 286.891573 -345.491427)
			(xy 286.818223 -345.449078) (xy 286.749231 -345.399949) (xy 286.685221 -345.344484) (xy 286.626773 -345.283186)
			(xy 286.574417 -345.21661) (xy 286.528627 -345.145358) (xy 286.489816 -345.070077) (xy 286.458337 -344.991447)
			(xy 286.434476 -344.91018) (xy 286.418447 -344.827014) (xy 286.410396 -344.7427) (xy 282.894786 -344.7427)
			(xy 282.894786 -351.8408) (xy 285.286958 -351.8408) (xy 285.28741 -351.813429) (xy 285.295229 -351.759249)
			(xy 285.310721 -351.706745) (xy 285.333566 -351.656998) (xy 285.363295 -351.611033) (xy 285.380938 -351.590102)
			(xy 285.390172 -351.578773) (xy 285.402345 -351.552215) (xy 285.406515 -351.5233) (xy 285.402345 -351.494385)
			(xy 285.390172 -351.467827) (xy 285.380938 -351.456498) (xy 285.363297 -351.435565) (xy 285.333571 -351.389598)
			(xy 285.310725 -351.339852) (xy 285.295228 -351.28735) (xy 285.2874 -351.233171) (xy 285.2874 -351.178429)
			(xy 285.295228 -351.12425) (xy 285.310725 -351.071748) (xy 285.333571 -351.022002) (xy 285.363297 -350.976035)
			(xy 285.380938 -350.955102) (xy 285.390172 -350.943773) (xy 285.402345 -350.917215) (xy 285.406515 -350.8883)
			(xy 285.402345 -350.859385) (xy 285.390172 -350.832827) (xy 285.380938 -350.821498) (xy 285.363297 -350.800565)
			(xy 285.333571 -350.754598) (xy 285.310725 -350.704852) (xy 285.295228 -350.65235) (xy 285.2874 -350.598171)
			(xy 285.2874 -350.543429) (xy 285.295228 -350.48925) (xy 285.310725 -350.436748) (xy 285.333571 -350.387002)
			(xy 285.363297 -350.341035) (xy 285.380938 -350.320102) (xy 285.390172 -350.308773) (xy 285.402345 -350.282215)
			(xy 285.406515 -350.2533) (xy 285.402345 -350.224385) (xy 285.390172 -350.197827) (xy 285.380938 -350.186498)
			(xy 285.363297 -350.165565) (xy 285.333571 -350.119598) (xy 285.310725 -350.069852) (xy 285.295228 -350.01735)
			(xy 285.2874 -349.963171) (xy 285.2874 -349.908429) (xy 285.295228 -349.85425) (xy 285.310725 -349.801748)
			(xy 285.333571 -349.752002) (xy 285.363297 -349.706035) (xy 285.380938 -349.685102) (xy 285.390172 -349.673773)
			(xy 285.402345 -349.647215) (xy 285.406515 -349.6183) (xy 285.402345 -349.589385) (xy 285.390172 -349.562827)
			(xy 285.380938 -349.551498) (xy 285.363297 -349.530565) (xy 285.333571 -349.484598) (xy 285.310725 -349.434852)
			(xy 285.295228 -349.38235) (xy 285.2874 -349.328171) (xy 285.2874 -349.273429) (xy 285.295228 -349.21925)
			(xy 285.310725 -349.166748) (xy 285.333571 -349.117002) (xy 285.363297 -349.071035) (xy 285.380938 -349.050102)
			(xy 285.390172 -349.038773) (xy 285.402345 -349.012215) (xy 285.406515 -348.9833) (xy 285.402345 -348.954385)
			(xy 285.390172 -348.927827) (xy 285.380938 -348.916498) (xy 285.363297 -348.895565) (xy 285.333571 -348.849598)
			(xy 285.310725 -348.799852) (xy 285.295228 -348.74735) (xy 285.2874 -348.693171) (xy 285.2874 -348.638429)
			(xy 285.295228 -348.58425) (xy 285.310725 -348.531748) (xy 285.333571 -348.482002) (xy 285.363297 -348.436035)
			(xy 285.380938 -348.415102) (xy 285.390172 -348.403773) (xy 285.402345 -348.377215) (xy 285.406515 -348.3483)
			(xy 285.402345 -348.319385) (xy 285.390172 -348.292827) (xy 285.380938 -348.281498) (xy 285.36329 -348.260573)
			(xy 285.333579 -348.214599) (xy 285.310744 -348.164849) (xy 285.295255 -348.112347) (xy 285.28743 -348.05817)
			(xy 285.286958 -348.0308) (xy 285.287478 -348.00355) (xy 285.295233 -347.949606) (xy 285.310587 -347.897314)
			(xy 285.333225 -347.847739) (xy 285.362689 -347.80189) (xy 285.398376 -347.7607) (xy 285.439563 -347.725009)
			(xy 285.485409 -347.695542) (xy 285.534982 -347.672899) (xy 285.587272 -347.657541) (xy 285.641216 -347.64978)
			(xy 285.668466 -347.649292) (xy 285.695835 -347.64978) (xy 285.750013 -347.657593) (xy 285.802516 -347.673077)
			(xy 285.852263 -347.695914) (xy 285.898231 -347.725633) (xy 285.919164 -347.743272) (xy 285.930492 -347.752508)
			(xy 285.957049 -347.764684) (xy 285.985966 -347.768857) (xy 286.014883 -347.764684) (xy 286.04144 -347.752508)
			(xy 286.052768 -347.743272) (xy 286.073698 -347.72563) (xy 286.119672 -347.69592) (xy 286.16942 -347.673085)
			(xy 286.221921 -347.657594) (xy 286.276097 -347.649766) (xy 286.303466 -347.649292) (xy 286.331506 -347.649802)
			(xy 286.386983 -347.657998) (xy 286.440665 -347.67422) (xy 286.491398 -347.698118) (xy 286.53809 -347.729179)
			(xy 286.559244 -347.74759) (xy 286.570686 -347.757235) (xy 286.597729 -347.770015) (xy 286.627316 -347.774401)
			(xy 286.656903 -347.770015) (xy 286.683946 -347.757235) (xy 286.695388 -347.74759) (xy 286.71379 -347.731553)
			(xy 286.753943 -347.703798) (xy 286.797303 -347.68138) (xy 286.820102 -347.67266) (xy 286.833437 -347.667262)
			(xy 286.856596 -347.650215) (xy 286.874094 -347.627394) (xy 286.884546 -347.600604) (xy 286.887126 -347.571964)
			(xy 286.88163 -347.543737) (xy 286.868493 -347.518156) (xy 286.848753 -347.497245) (xy 286.836612 -347.489526)
			(xy 286.799538 -347.467197) (xy 286.729339 -347.416569) (xy 286.664236 -347.359536) (xy 286.604811 -347.296608)
			(xy 286.551597 -347.228348) (xy 286.505069 -347.155367) (xy 286.465642 -347.078317) (xy 286.433671 -346.997887)
			(xy 286.40944 -346.914797) (xy 286.393166 -346.829789) (xy 286.384995 -346.743624) (xy 286.384492 -346.700348)
			(xy 286.38498 -346.658072) (xy 286.392782 -346.57388) (xy 286.408318 -346.490767) (xy 286.431457 -346.409443)
			(xy 286.462001 -346.3306) (xy 286.499689 -346.254912) (xy 286.5442 -346.183024) (xy 286.595154 -346.11555)
			(xy 286.652117 -346.053065) (xy 286.714602 -345.996102) (xy 286.782076 -345.945148) (xy 286.853964 -345.900637)
			(xy 286.929652 -345.862949) (xy 287.008495 -345.832405) (xy 287.089819 -345.809266) (xy 287.172932 -345.79373)
			(xy 287.257124 -345.785928) (xy 287.341676 -345.785928) (xy 287.425868 -345.79373) (xy 287.508981 -345.809266)
			(xy 287.590305 -345.832405) (xy 287.669148 -345.862949) (xy 287.744836 -345.900637) (xy 287.816724 -345.945148)
			(xy 287.884198 -345.996102) (xy 287.946683 -346.053065) (xy 288.003646 -346.11555) (xy 288.0546 -346.183024)
			(xy 288.099111 -346.254912) (xy 288.136799 -346.3306) (xy 288.167343 -346.409443) (xy 288.190482 -346.490767)
			(xy 288.206018 -346.57388) (xy 288.21382 -346.658072) (xy 288.214308 -346.700348) (xy 292.581589 -346.700348)
			(xy 292.585611 -346.614628) (xy 292.597642 -346.52966) (xy 292.617578 -346.446193) (xy 292.645241 -346.364959)
			(xy 292.68039 -346.286673) (xy 292.722716 -346.212022) (xy 292.771845 -346.141663) (xy 292.827348 -346.076213)
			(xy 292.888735 -346.016249) (xy 292.955468 -345.962296) (xy 293.02696 -345.914829) (xy 293.102582 -345.874265)
			(xy 293.181671 -345.840961) (xy 293.263531 -345.815209) (xy 293.347442 -345.797236) (xy 293.432668 -345.7872)
			(xy 293.51846 -345.785188) (xy 293.604062 -345.791219) (xy 293.688724 -345.805239) (xy 293.771701 -345.827125)
			(xy 293.852264 -345.856686) (xy 293.929704 -345.89366) (xy 294.003343 -345.937724) (xy 294.072531 -345.98849)
			(xy 294.136662 -346.045511) (xy 294.195171 -346.108287) (xy 294.247544 -346.176267) (xy 294.293322 -346.248852)
			(xy 294.332102 -346.325404) (xy 294.363543 -346.405252) (xy 294.387369 -346.487693) (xy 294.40337 -346.572003)
			(xy 294.411405 -346.657441) (xy 294.411908 -346.700348) (xy 298.779189 -346.700348) (xy 298.783211 -346.614628)
			(xy 298.795242 -346.52966) (xy 298.815178 -346.446193) (xy 298.842841 -346.364959) (xy 298.87799 -346.286673)
			(xy 298.920316 -346.212022) (xy 298.969445 -346.141663) (xy 299.024948 -346.076213) (xy 299.086335 -346.016249)
			(xy 299.153068 -345.962296) (xy 299.22456 -345.914829) (xy 299.300182 -345.874265) (xy 299.379271 -345.840961)
			(xy 299.461131 -345.815209) (xy 299.545042 -345.797236) (xy 299.630268 -345.7872) (xy 299.71606 -345.785188)
			(xy 299.801662 -345.791219) (xy 299.886324 -345.805239) (xy 299.969301 -345.827125) (xy 300.049864 -345.856686)
			(xy 300.127304 -345.89366) (xy 300.200943 -345.937724) (xy 300.270131 -345.98849) (xy 300.334262 -346.045511)
			(xy 300.392771 -346.108287) (xy 300.445144 -346.176267) (xy 300.490922 -346.248852) (xy 300.529702 -346.325404)
			(xy 300.561143 -346.405252) (xy 300.584969 -346.487693) (xy 300.60097 -346.572003) (xy 300.609005 -346.657441)
			(xy 300.609508 -346.700348) (xy 300.609005 -346.743255) (xy 300.60097 -346.828693) (xy 300.584969 -346.913003)
			(xy 300.561143 -346.995444) (xy 300.529702 -347.075292) (xy 300.490922 -347.151844) (xy 300.445144 -347.224429)
			(xy 300.392771 -347.292409) (xy 300.334262 -347.355185) (xy 300.270131 -347.412206) (xy 300.200943 -347.462972)
			(xy 300.127304 -347.507036) (xy 300.049864 -347.54401) (xy 299.969301 -347.573571) (xy 299.886324 -347.595457)
			(xy 299.801662 -347.609477) (xy 299.71606 -347.615508) (xy 299.630268 -347.613496) (xy 299.545042 -347.60346)
			(xy 299.461131 -347.585487) (xy 299.379271 -347.559735) (xy 299.300182 -347.526431) (xy 299.22456 -347.485867)
			(xy 299.153068 -347.4384) (xy 299.086335 -347.384447) (xy 299.024948 -347.324483) (xy 298.969445 -347.259033)
			(xy 298.920316 -347.188674) (xy 298.87799 -347.114023) (xy 298.842841 -347.035737) (xy 298.815178 -346.954503)
			(xy 298.795242 -346.871036) (xy 298.783211 -346.786068) (xy 298.779189 -346.700348) (xy 294.411908 -346.700348)
			(xy 294.411405 -346.743255) (xy 294.40337 -346.828693) (xy 294.387369 -346.913003) (xy 294.363543 -346.995444)
			(xy 294.332102 -347.075292) (xy 294.293322 -347.151844) (xy 294.247544 -347.224429) (xy 294.195171 -347.292409)
			(xy 294.136662 -347.355185) (xy 294.072531 -347.412206) (xy 294.003343 -347.462972) (xy 293.929704 -347.507036)
			(xy 293.852264 -347.54401) (xy 293.771701 -347.573571) (xy 293.688724 -347.595457) (xy 293.604062 -347.609477)
			(xy 293.51846 -347.615508) (xy 293.432668 -347.613496) (xy 293.347442 -347.60346) (xy 293.263531 -347.585487)
			(xy 293.181671 -347.559735) (xy 293.102582 -347.526431) (xy 293.02696 -347.485867) (xy 292.955468 -347.4384)
			(xy 292.888735 -347.384447) (xy 292.827348 -347.324483) (xy 292.771845 -347.259033) (xy 292.722716 -347.188674)
			(xy 292.68039 -347.114023) (xy 292.645241 -347.035737) (xy 292.617578 -346.954503) (xy 292.597642 -346.871036)
			(xy 292.585611 -346.786068) (xy 292.581589 -346.700348) (xy 288.214308 -346.700348) (xy 288.21379 -346.742119)
			(xy 288.206161 -346.825312) (xy 288.190979 -346.907463) (xy 288.168372 -346.987888) (xy 288.138526 -347.065917)
			(xy 288.101692 -347.140901) (xy 288.058175 -347.212214) (xy 288.008338 -347.279263) (xy 287.952597 -347.34149)
			(xy 287.891415 -347.398376) (xy 287.825301 -347.449448) (xy 287.754807 -347.49428) (xy 287.68052 -347.532499)
			(xy 287.603058 -347.563786) (xy 287.523066 -347.587882) (xy 287.44121 -347.604585) (xy 287.358173 -347.613756)
			(xy 287.316418 -347.615002) (xy 287.302046 -347.615754) (xy 287.274565 -347.624259) (xy 287.250547 -347.640089)
			(xy 287.231895 -347.661989) (xy 287.22009 -347.688222) (xy 287.216068 -347.716706) (xy 287.220149 -347.745181)
			(xy 287.232008 -347.771389) (xy 287.24098 -347.782642) (xy 287.258186 -347.803491) (xy 287.287192 -347.849105)
			(xy 287.309471 -347.898356) (xy 287.324576 -347.950258) (xy 287.332204 -348.003772) (xy 287.332674 -348.0308)
			(xy 287.332214 -348.058171) (xy 287.324396 -348.11235) (xy 287.308906 -348.164854) (xy 287.286062 -348.2146)
			(xy 287.256336 -348.260567) (xy 287.238694 -348.281498) (xy 287.229458 -348.292825) (xy 287.217281 -348.319383)
			(xy 287.213109 -348.3483) (xy 287.217281 -348.377217) (xy 287.229458 -348.403775) (xy 287.238694 -348.415102)
			(xy 287.256334 -348.436035) (xy 287.286057 -348.482003) (xy 287.308901 -348.53175) (xy 287.324396 -348.584252)
			(xy 287.332225 -348.63843) (xy 287.332225 -348.69317) (xy 287.324396 -348.747348) (xy 287.308901 -348.79985)
			(xy 287.286057 -348.849597) (xy 287.256334 -348.895565) (xy 287.238694 -348.916498) (xy 287.229458 -348.927825)
			(xy 287.217281 -348.954383) (xy 287.213109 -348.9833) (xy 287.217281 -349.012217) (xy 287.229458 -349.038775)
			(xy 287.238694 -349.050102) (xy 287.256334 -349.071035) (xy 287.286057 -349.117003) (xy 287.308901 -349.16675)
			(xy 287.324396 -349.219252) (xy 287.332225 -349.27343) (xy 287.332225 -349.32817) (xy 287.324396 -349.382348)
			(xy 287.308901 -349.43485) (xy 287.286057 -349.484597) (xy 287.256334 -349.530565) (xy 287.238694 -349.551498)
			(xy 287.229458 -349.562825) (xy 287.217281 -349.589383) (xy 287.213109 -349.6183) (xy 287.217281 -349.647217)
			(xy 287.229458 -349.673775) (xy 287.238694 -349.685102) (xy 287.256334 -349.706035) (xy 287.286057 -349.752003)
			(xy 287.308901 -349.80175) (xy 287.324396 -349.854252) (xy 287.332225 -349.90843) (xy 287.332225 -349.96317)
			(xy 287.324396 -350.017348) (xy 287.308901 -350.06985) (xy 287.286057 -350.119597) (xy 287.256334 -350.165565)
			(xy 287.238694 -350.186498) (xy 287.229458 -350.197825) (xy 287.217281 -350.224383) (xy 287.213109 -350.2533)
			(xy 287.217281 -350.282217) (xy 287.229458 -350.308775) (xy 287.238694 -350.320102) (xy 287.256334 -350.341035)
			(xy 287.286057 -350.387003) (xy 287.308901 -350.43675) (xy 287.324396 -350.489252) (xy 287.332225 -350.54343)
			(xy 287.332225 -350.59817) (xy 287.324396 -350.652348) (xy 287.308901 -350.70485) (xy 287.286057 -350.754597)
			(xy 287.256334 -350.800565) (xy 287.238694 -350.821498) (xy 287.229458 -350.832825) (xy 287.217281 -350.859383)
			(xy 287.213109 -350.8883) (xy 287.217281 -350.917217) (xy 287.229458 -350.943775) (xy 287.238694 -350.955102)
			(xy 287.256334 -350.976035) (xy 287.286057 -351.022003) (xy 287.308901 -351.07175) (xy 287.324396 -351.124252)
			(xy 287.332225 -351.17843) (xy 287.332225 -351.23317) (xy 287.324396 -351.287348) (xy 287.308901 -351.33985)
			(xy 287.286057 -351.389597) (xy 287.256334 -351.435565) (xy 287.238694 -351.456498) (xy 287.229458 -351.467825)
			(xy 287.217281 -351.494383) (xy 287.213109 -351.5233) (xy 287.217281 -351.552217) (xy 287.229458 -351.578775)
			(xy 287.238694 -351.590102) (xy 287.256347 -351.611023) (xy 287.286057 -351.656999) (xy 287.30889 -351.706749)
			(xy 287.324378 -351.759252) (xy 287.332202 -351.81343) (xy 287.332674 -351.8408) (xy 290.25723 -351.8408)
			(xy 290.257689 -351.813429) (xy 290.265507 -351.75925) (xy 290.280998 -351.706746) (xy 290.303841 -351.656999)
			(xy 290.333568 -351.611033) (xy 290.35121 -351.590102) (xy 290.360446 -351.578774) (xy 290.372622 -351.552217)
			(xy 290.376794 -351.5233) (xy 290.372622 -351.494383) (xy 290.360446 -351.467826) (xy 290.35121 -351.456498)
			(xy 290.33357 -351.435565) (xy 290.303847 -351.389597) (xy 290.281002 -351.33985) (xy 290.265507 -351.287349)
			(xy 290.257678 -351.23317) (xy 290.257678 -351.17843) (xy 290.265507 -351.124251) (xy 290.281002 -351.07175)
			(xy 290.303847 -351.022003) (xy 290.33357 -350.976035) (xy 290.35121 -350.955102) (xy 290.360446 -350.943774)
			(xy 290.372622 -350.917217) (xy 290.376794 -350.8883) (xy 290.372622 -350.859383) (xy 290.360446 -350.832826)
			(xy 290.35121 -350.821498) (xy 290.33357 -350.800565) (xy 290.303847 -350.754597) (xy 290.281002 -350.70485)
			(xy 290.265507 -350.652349) (xy 290.257678 -350.59817) (xy 290.257678 -350.54343) (xy 290.265507 -350.489251)
			(xy 290.281002 -350.43675) (xy 290.303847 -350.387003) (xy 290.33357 -350.341035) (xy 290.35121 -350.320102)
			(xy 290.360446 -350.308774) (xy 290.372622 -350.282217) (xy 290.376794 -350.2533) (xy 290.372622 -350.224383)
			(xy 290.360446 -350.197826) (xy 290.35121 -350.186498) (xy 290.33357 -350.165565) (xy 290.303847 -350.119597)
			(xy 290.281002 -350.06985) (xy 290.265507 -350.017349) (xy 290.257678 -349.96317) (xy 290.257678 -349.90843)
			(xy 290.265507 -349.854251) (xy 290.281002 -349.80175) (xy 290.303847 -349.752003) (xy 290.33357 -349.706035)
			(xy 290.35121 -349.685102) (xy 290.360446 -349.673774) (xy 290.372622 -349.647217) (xy 290.376794 -349.6183)
			(xy 290.372622 -349.589383) (xy 290.360446 -349.562826) (xy 290.35121 -349.551498) (xy 290.33357 -349.530565)
			(xy 290.303847 -349.484597) (xy 290.281002 -349.43485) (xy 290.265507 -349.382349) (xy 290.257678 -349.32817)
			(xy 290.257678 -349.27343) (xy 290.265507 -349.219251) (xy 290.281002 -349.16675) (xy 290.303847 -349.117003)
			(xy 290.33357 -349.071035) (xy 290.35121 -349.050102) (xy 290.360446 -349.038774) (xy 290.372622 -349.012217)
			(xy 290.376794 -348.9833) (xy 290.372622 -348.954383) (xy 290.360446 -348.927826) (xy 290.35121 -348.916498)
			(xy 290.33357 -348.895565) (xy 290.303847 -348.849597) (xy 290.281002 -348.79985) (xy 290.265507 -348.747349)
			(xy 290.257678 -348.69317) (xy 290.257678 -348.63843) (xy 290.265507 -348.584251) (xy 290.281002 -348.53175)
			(xy 290.303847 -348.482003) (xy 290.33357 -348.436035) (xy 290.35121 -348.415102) (xy 290.360446 -348.403774)
			(xy 290.372622 -348.377217) (xy 290.376794 -348.3483) (xy 290.372622 -348.319383) (xy 290.360446 -348.292826)
			(xy 290.35121 -348.281498) (xy 290.333558 -348.260576) (xy 290.303848 -348.214601) (xy 290.281014 -348.164851)
			(xy 290.265526 -348.112348) (xy 290.257702 -348.05817) (xy 290.25723 -348.0308) (xy 290.257655 -348.003545)
			(xy 290.265413 -347.949591) (xy 290.280771 -347.89729) (xy 290.303417 -347.847708) (xy 290.332888 -347.801853)
			(xy 290.368586 -347.760659) (xy 290.409783 -347.724965) (xy 290.455641 -347.695498) (xy 290.505226 -347.672858)
			(xy 290.557528 -347.657505) (xy 290.611483 -347.649753) (xy 290.638738 -347.649292) (xy 290.666779 -347.649759)
			(xy 290.722259 -347.657966) (xy 290.775941 -347.674198) (xy 290.826673 -347.698105) (xy 290.873363 -347.729175)
			(xy 290.894516 -347.74759) (xy 290.905958 -347.757235) (xy 290.933001 -347.770015) (xy 290.962588 -347.774401)
			(xy 290.992175 -347.770015) (xy 291.019218 -347.757235) (xy 291.03066 -347.74759) (xy 291.051808 -347.729166)
			(xy 291.098486 -347.698072) (xy 291.149217 -347.674157) (xy 291.202907 -347.657938) (xy 291.258395 -347.649765)
			(xy 291.286438 -347.649292) (xy 291.313807 -347.649796) (xy 291.367984 -347.657605) (xy 291.420487 -347.673085)
			(xy 291.470234 -347.695919) (xy 291.516203 -347.725635) (xy 291.537136 -347.743272) (xy 291.548464 -347.752508)
			(xy 291.575021 -347.764684) (xy 291.603938 -347.768857) (xy 291.632855 -347.764684) (xy 291.659412 -347.752508)
			(xy 291.67074 -347.743272) (xy 291.69168 -347.725643) (xy 291.737651 -347.695931) (xy 291.787397 -347.673093)
			(xy 291.839895 -347.6576) (xy 291.894069 -347.649768) (xy 291.921438 -347.649292) (xy 291.94869 -347.649742)
			(xy 292.002639 -347.657504) (xy 292.054935 -347.672864) (xy 292.104512 -347.69551) (xy 292.150362 -347.72498)
			(xy 292.191552 -347.760675) (xy 292.227243 -347.801868) (xy 292.256709 -347.847721) (xy 292.279349 -347.897301)
			(xy 292.294704 -347.949598) (xy 292.30246 -348.003548) (xy 292.302946 -348.0308) (xy 292.302493 -348.058171)
			(xy 292.294674 -348.112351) (xy 292.279183 -348.164855) (xy 292.256338 -348.214602) (xy 292.226609 -348.260567)
			(xy 292.208966 -348.281498) (xy 292.199732 -348.292826) (xy 292.187559 -348.319384) (xy 292.183388 -348.3483)
			(xy 292.187559 -348.377216) (xy 292.199732 -348.403774) (xy 292.208966 -348.415102) (xy 292.226607 -348.436035)
			(xy 292.256332 -348.482002) (xy 292.279178 -348.531748) (xy 292.294675 -348.584251) (xy 292.302503 -348.638429)
			(xy 292.302503 -348.693171) (xy 292.294675 -348.747349) (xy 292.279178 -348.799852) (xy 292.256332 -348.849598)
			(xy 292.226607 -348.895565) (xy 292.208966 -348.916498) (xy 292.199732 -348.927826) (xy 292.187559 -348.954384)
			(xy 292.183388 -348.9833) (xy 292.187559 -349.012216) (xy 292.199732 -349.038774) (xy 292.208966 -349.050102)
			(xy 292.226607 -349.071035) (xy 292.256332 -349.117002) (xy 292.279178 -349.166748) (xy 292.294675 -349.219251)
			(xy 292.302503 -349.273429) (xy 292.302503 -349.328171) (xy 292.294675 -349.382349) (xy 292.279178 -349.434852)
			(xy 292.256332 -349.484598) (xy 292.226607 -349.530565) (xy 292.208966 -349.551498) (xy 292.199732 -349.562826)
			(xy 292.187559 -349.589384) (xy 292.183388 -349.6183) (xy 292.187559 -349.647216) (xy 292.199732 -349.673774)
			(xy 292.208966 -349.685102) (xy 292.226607 -349.706035) (xy 292.256332 -349.752002) (xy 292.279178 -349.801748)
			(xy 292.294675 -349.854251) (xy 292.302503 -349.908429) (xy 292.302503 -349.963171) (xy 292.294675 -350.017349)
			(xy 292.279178 -350.069852) (xy 292.256332 -350.119598) (xy 292.226607 -350.165565) (xy 292.208966 -350.186498)
			(xy 292.199732 -350.197826) (xy 292.187559 -350.224384) (xy 292.183388 -350.2533) (xy 292.187559 -350.282216)
			(xy 292.199732 -350.308774) (xy 292.208966 -350.320102) (xy 292.226607 -350.341035) (xy 292.256332 -350.387002)
			(xy 292.279178 -350.436748) (xy 292.294675 -350.489251) (xy 292.302503 -350.543429) (xy 292.302503 -350.598171)
			(xy 292.294675 -350.652349) (xy 292.279178 -350.704852) (xy 292.256332 -350.754598) (xy 292.226607 -350.800565)
			(xy 292.208966 -350.821498) (xy 292.199732 -350.832826) (xy 292.187559 -350.859384) (xy 292.183388 -350.8883)
			(xy 292.187559 -350.917216) (xy 292.199732 -350.943774) (xy 292.208966 -350.955102) (xy 292.226607 -350.976035)
			(xy 292.256332 -351.022002) (xy 292.279178 -351.071748) (xy 292.294675 -351.124251) (xy 292.302503 -351.178429)
			(xy 292.302503 -351.233171) (xy 292.294675 -351.287349) (xy 292.279178 -351.339852) (xy 292.256332 -351.389598)
			(xy 292.226607 -351.435565) (xy 292.208966 -351.456498) (xy 292.199732 -351.467826) (xy 292.187559 -351.494384)
			(xy 292.183388 -351.5233) (xy 292.187559 -351.552216) (xy 292.199732 -351.578774) (xy 292.208966 -351.590102)
			(xy 292.226614 -351.611027) (xy 292.256326 -351.657001) (xy 292.279161 -351.70675) (xy 292.294649 -351.759253)
			(xy 292.302474 -351.81343) (xy 292.302946 -351.8408) (xy 294.964358 -351.8408) (xy 294.96481 -351.813429)
			(xy 294.972629 -351.759249) (xy 294.988121 -351.706745) (xy 295.010966 -351.656998) (xy 295.040695 -351.611033)
			(xy 295.058338 -351.590102) (xy 295.067572 -351.578773) (xy 295.079745 -351.552215) (xy 295.083915 -351.5233)
			(xy 295.079745 -351.494385) (xy 295.067572 -351.467827) (xy 295.058338 -351.456498) (xy 295.040697 -351.435565)
			(xy 295.010971 -351.389598) (xy 294.988125 -351.339852) (xy 294.972628 -351.28735) (xy 294.9648 -351.233171)
			(xy 294.9648 -351.178429) (xy 294.972628 -351.12425) (xy 294.988125 -351.071748) (xy 295.010971 -351.022002)
			(xy 295.040697 -350.976035) (xy 295.058338 -350.955102) (xy 295.067572 -350.943773) (xy 295.079745 -350.917215)
			(xy 295.083915 -350.8883) (xy 295.079745 -350.859385) (xy 295.067572 -350.832827) (xy 295.058338 -350.821498)
			(xy 295.040697 -350.800565) (xy 295.010971 -350.754598) (xy 294.988125 -350.704852) (xy 294.972628 -350.65235)
			(xy 294.9648 -350.598171) (xy 294.9648 -350.543429) (xy 294.972628 -350.48925) (xy 294.988125 -350.436748)
			(xy 295.010971 -350.387002) (xy 295.040697 -350.341035) (xy 295.058338 -350.320102) (xy 295.067572 -350.308773)
			(xy 295.079745 -350.282215) (xy 295.083915 -350.2533) (xy 295.079745 -350.224385) (xy 295.067572 -350.197827)
			(xy 295.058338 -350.186498) (xy 295.040697 -350.165565) (xy 295.010971 -350.119598) (xy 294.988125 -350.069852)
			(xy 294.972628 -350.01735) (xy 294.9648 -349.963171) (xy 294.9648 -349.908429) (xy 294.972628 -349.85425)
			(xy 294.988125 -349.801748) (xy 295.010971 -349.752002) (xy 295.040697 -349.706035) (xy 295.058338 -349.685102)
			(xy 295.067572 -349.673773) (xy 295.079745 -349.647215) (xy 295.083915 -349.6183) (xy 295.079745 -349.589385)
			(xy 295.067572 -349.562827) (xy 295.058338 -349.551498) (xy 295.040697 -349.530565) (xy 295.010971 -349.484598)
			(xy 294.988125 -349.434852) (xy 294.972628 -349.38235) (xy 294.9648 -349.328171) (xy 294.9648 -349.273429)
			(xy 294.972628 -349.21925) (xy 294.988125 -349.166748) (xy 295.010971 -349.117002) (xy 295.040697 -349.071035)
			(xy 295.058338 -349.050102) (xy 295.067572 -349.038773) (xy 295.079745 -349.012215) (xy 295.083915 -348.9833)
			(xy 295.079745 -348.954385) (xy 295.067572 -348.927827) (xy 295.058338 -348.916498) (xy 295.040697 -348.895565)
			(xy 295.010971 -348.849598) (xy 294.988125 -348.799852) (xy 294.972628 -348.74735) (xy 294.9648 -348.693171)
			(xy 294.9648 -348.638429) (xy 294.972628 -348.58425) (xy 294.988125 -348.531748) (xy 295.010971 -348.482002)
			(xy 295.040697 -348.436035) (xy 295.058338 -348.415102) (xy 295.067572 -348.403773) (xy 295.079745 -348.377215)
			(xy 295.083915 -348.3483) (xy 295.079745 -348.319385) (xy 295.067572 -348.292827) (xy 295.058338 -348.281498)
			(xy 295.04069 -348.260573) (xy 295.010979 -348.214599) (xy 294.988144 -348.164849) (xy 294.972655 -348.112347)
			(xy 294.96483 -348.05817) (xy 294.964358 -348.0308) (xy 294.964878 -348.00355) (xy 294.972633 -347.949606)
			(xy 294.987987 -347.897314) (xy 295.010625 -347.847739) (xy 295.040089 -347.80189) (xy 295.075776 -347.7607)
			(xy 295.116963 -347.725009) (xy 295.162809 -347.695542) (xy 295.212382 -347.672899) (xy 295.264672 -347.657541)
			(xy 295.318616 -347.64978) (xy 295.345866 -347.649292) (xy 295.373235 -347.64978) (xy 295.427413 -347.657593)
			(xy 295.479916 -347.673077) (xy 295.529663 -347.695914) (xy 295.575631 -347.725633) (xy 295.596564 -347.743272)
			(xy 295.607892 -347.752508) (xy 295.634449 -347.764684) (xy 295.663366 -347.768857) (xy 295.692283 -347.764684)
			(xy 295.71884 -347.752508) (xy 295.730168 -347.743272) (xy 295.751098 -347.72563) (xy 295.797072 -347.69592)
			(xy 295.84682 -347.673085) (xy 295.899321 -347.657594) (xy 295.953497 -347.649766) (xy 295.980866 -347.649292)
			(xy 296.008906 -347.649802) (xy 296.064383 -347.657998) (xy 296.118065 -347.67422) (xy 296.168798 -347.698118)
			(xy 296.21549 -347.729179) (xy 296.236644 -347.74759) (xy 296.248086 -347.757235) (xy 296.275129 -347.770015)
			(xy 296.304716 -347.774401) (xy 296.334303 -347.770015) (xy 296.361346 -347.757235) (xy 296.372788 -347.74759)
			(xy 296.393925 -347.729153) (xy 296.440606 -347.698061) (xy 296.49134 -347.674149) (xy 296.545032 -347.657932)
			(xy 296.600522 -347.649763) (xy 296.628566 -347.649292) (xy 296.655818 -347.649787) (xy 296.709768 -347.657539)
			(xy 296.762065 -347.672891) (xy 296.811645 -347.69553) (xy 296.857498 -347.724994) (xy 296.898691 -347.760684)
			(xy 296.934386 -347.801874) (xy 296.963854 -347.847725) (xy 296.986497 -347.897303) (xy 297.001853 -347.949599)
			(xy 297.009611 -348.003548) (xy 297.010074 -348.0308) (xy 297.009614 -348.058171) (xy 297.001796 -348.11235)
			(xy 296.986306 -348.164854) (xy 296.963462 -348.2146) (xy 296.933736 -348.260567) (xy 296.916094 -348.281498)
			(xy 296.906858 -348.292825) (xy 296.894681 -348.319383) (xy 296.890509 -348.3483) (xy 296.894681 -348.377217)
			(xy 296.906858 -348.403775) (xy 296.916094 -348.415102) (xy 296.933734 -348.436035) (xy 296.963457 -348.482003)
			(xy 296.986301 -348.53175) (xy 297.001796 -348.584252) (xy 297.009625 -348.63843) (xy 297.009625 -348.69317)
			(xy 297.001796 -348.747348) (xy 296.986301 -348.79985) (xy 296.963457 -348.849597) (xy 296.933734 -348.895565)
			(xy 296.916094 -348.916498) (xy 296.906858 -348.927825) (xy 296.894681 -348.954383) (xy 296.890509 -348.9833)
			(xy 296.894681 -349.012217) (xy 296.906858 -349.038775) (xy 296.916094 -349.050102) (xy 296.933734 -349.071035)
			(xy 296.963457 -349.117003) (xy 296.986301 -349.16675) (xy 297.001796 -349.219252) (xy 297.009625 -349.27343)
			(xy 297.009625 -349.32817) (xy 297.001796 -349.382348) (xy 296.986301 -349.43485) (xy 296.963457 -349.484597)
			(xy 296.933734 -349.530565) (xy 296.916094 -349.551498) (xy 296.906858 -349.562825) (xy 296.894681 -349.589383)
			(xy 296.890509 -349.6183) (xy 296.894681 -349.647217) (xy 296.906858 -349.673775) (xy 296.916094 -349.685102)
			(xy 296.933734 -349.706035) (xy 296.963457 -349.752003) (xy 296.986301 -349.80175) (xy 297.001796 -349.854252)
			(xy 297.009625 -349.90843) (xy 297.009625 -349.96317) (xy 297.001796 -350.017348) (xy 296.986301 -350.06985)
			(xy 296.963457 -350.119597) (xy 296.933734 -350.165565) (xy 296.916094 -350.186498) (xy 296.906858 -350.197825)
			(xy 296.894681 -350.224383) (xy 296.890509 -350.2533) (xy 296.894681 -350.282217) (xy 296.906858 -350.308775)
			(xy 296.916094 -350.320102) (xy 296.933734 -350.341035) (xy 296.963457 -350.387003) (xy 296.986301 -350.43675)
			(xy 297.001796 -350.489252) (xy 297.009625 -350.54343) (xy 297.009625 -350.59817) (xy 297.001796 -350.652348)
			(xy 296.986301 -350.70485) (xy 296.963457 -350.754597) (xy 296.933734 -350.800565) (xy 296.916094 -350.821498)
			(xy 296.906858 -350.832825) (xy 296.894681 -350.859383) (xy 296.890509 -350.8883) (xy 296.894681 -350.917217)
			(xy 296.906858 -350.943775) (xy 296.916094 -350.955102) (xy 296.933734 -350.976035) (xy 296.963457 -351.022003)
			(xy 296.986301 -351.07175) (xy 297.001796 -351.124252) (xy 297.009625 -351.17843) (xy 297.009625 -351.23317)
			(xy 297.001796 -351.287348) (xy 296.986301 -351.33985) (xy 296.963457 -351.389597) (xy 296.933734 -351.435565)
			(xy 296.916094 -351.456498) (xy 296.906858 -351.467825) (xy 296.894681 -351.494383) (xy 296.890509 -351.5233)
			(xy 296.894681 -351.552217) (xy 296.906858 -351.578775) (xy 296.916094 -351.590102) (xy 296.933747 -351.611023)
			(xy 296.963457 -351.656999) (xy 296.98629 -351.706749) (xy 297.001778 -351.759252) (xy 297.009602 -351.81343)
			(xy 297.010074 -351.8408) (xy 297.009645 -351.868054) (xy 297.001887 -351.922008) (xy 296.986529 -351.974309)
			(xy 296.963884 -352.023891) (xy 296.934413 -352.069746) (xy 296.898715 -352.11094) (xy 296.857519 -352.146633)
			(xy 296.811661 -352.1761) (xy 296.762077 -352.198741) (xy 296.709775 -352.214094) (xy 296.65582 -352.221847)
			(xy 296.628566 -352.222308) (xy 296.600525 -352.221839) (xy 296.545046 -352.213632) (xy 296.491363 -352.197401)
			(xy 296.440631 -352.173494) (xy 296.393941 -352.142425) (xy 296.372788 -352.12401) (xy 296.361346 -352.114365)
			(xy 296.334303 -352.101585) (xy 296.304716 -352.097199) (xy 296.275129 -352.101585) (xy 296.248086 -352.114365)
			(xy 296.236644 -352.12401) (xy 296.215495 -352.142432) (xy 296.168817 -352.173526) (xy 296.118086 -352.197441)
			(xy 296.064396 -352.213661) (xy 296.008909 -352.221835) (xy 295.980866 -352.222308) (xy 295.953495 -352.22186)
			(xy 295.899315 -352.214037) (xy 295.846812 -352.198544) (xy 295.797066 -352.175698) (xy 295.751099 -352.145971)
			(xy 295.730168 -352.128328) (xy 295.71884 -352.119092) (xy 295.692283 -352.106916) (xy 295.663366 -352.102743)
			(xy 295.634449 -352.106916) (xy 295.607892 -352.119092) (xy 295.596564 -352.128328) (xy 295.575622 -352.145955)
			(xy 295.529652 -352.175668) (xy 295.479907 -352.198505) (xy 295.427408 -352.213999) (xy 295.373234 -352.221832)
			(xy 295.345866 -352.222308) (xy 295.318614 -352.221854) (xy 295.264665 -352.214093) (xy 295.21237 -352.198733)
			(xy 295.162792 -352.176088) (xy 295.116942 -352.146618) (xy 295.075752 -352.110924) (xy 295.040061 -352.069731)
			(xy 295.010596 -352.023878) (xy 294.987955 -351.974298) (xy 294.9726 -351.922002) (xy 294.964844 -351.868052)
			(xy 294.964358 -351.8408) (xy 292.302946 -351.8408) (xy 292.302422 -351.86805) (xy 292.294667 -351.921994)
			(xy 292.279314 -351.974286) (xy 292.256675 -352.02386) (xy 292.227212 -352.069709) (xy 292.191525 -352.110898)
			(xy 292.150339 -352.14659) (xy 292.104494 -352.176057) (xy 292.054921 -352.1987) (xy 292.002631 -352.214059)
			(xy 291.948687 -352.22182) (xy 291.921438 -352.222308) (xy 291.894069 -352.221818) (xy 291.839891 -352.214005)
			(xy 291.787388 -352.198522) (xy 291.737641 -352.175686) (xy 291.691673 -352.145967) (xy 291.67074 -352.128328)
			(xy 291.659412 -352.119092) (xy 291.632855 -352.106916) (xy 291.603938 -352.102743) (xy 291.575021 -352.106916)
			(xy 291.548464 -352.119092) (xy 291.537136 -352.128328) (xy 291.516205 -352.145968) (xy 291.470231 -352.175679)
			(xy 291.420484 -352.198514) (xy 291.367983 -352.214005) (xy 291.313807 -352.221834) (xy 291.286438 -352.222308)
			(xy 291.258398 -352.221796) (xy 291.202921 -352.2136) (xy 291.149239 -352.197379) (xy 291.098507 -352.173481)
			(xy 291.051814 -352.142421) (xy 291.03066 -352.12401) (xy 291.019218 -352.114365) (xy 290.992175 -352.101585)
			(xy 290.962588 -352.097199) (xy 290.933001 -352.101585) (xy 290.905958 -352.114365) (xy 290.894516 -352.12401)
			(xy 290.873378 -352.142445) (xy 290.826697 -352.173537) (xy 290.775963 -352.19745) (xy 290.722271 -352.213667)
			(xy 290.666782 -352.221837) (xy 290.638738 -352.222308) (xy 290.611486 -352.221809) (xy 290.557536 -352.214058)
			(xy 290.505239 -352.198706) (xy 290.455659 -352.176068) (xy 290.409806 -352.146604) (xy 290.368613 -352.110914)
			(xy 290.332919 -352.069725) (xy 290.30345 -352.023874) (xy 290.280807 -351.974296) (xy 290.265451 -351.922001)
			(xy 290.257693 -351.868052) (xy 290.25723 -351.8408) (xy 287.332674 -351.8408) (xy 287.332245 -351.868054)
			(xy 287.324487 -351.922008) (xy 287.309129 -351.974309) (xy 287.286484 -352.023891) (xy 287.257013 -352.069746)
			(xy 287.221315 -352.11094) (xy 287.180119 -352.146633) (xy 287.134261 -352.1761) (xy 287.084677 -352.198741)
			(xy 287.032375 -352.214094) (xy 286.97842 -352.221847) (xy 286.951166 -352.222308) (xy 286.923125 -352.221839)
			(xy 286.867646 -352.213632) (xy 286.813963 -352.197401) (xy 286.763231 -352.173494) (xy 286.716541 -352.142425)
			(xy 286.695388 -352.12401) (xy 286.683946 -352.114365) (xy 286.656903 -352.101585) (xy 286.627316 -352.097199)
			(xy 286.597729 -352.101585) (xy 286.570686 -352.114365) (xy 286.559244 -352.12401) (xy 286.538095 -352.142432)
			(xy 286.491417 -352.173526) (xy 286.440686 -352.197441) (xy 286.386996 -352.213661) (xy 286.331509 -352.221835)
			(xy 286.303466 -352.222308) (xy 286.276095 -352.22186) (xy 286.221915 -352.214037) (xy 286.169412 -352.198544)
			(xy 286.119666 -352.175698) (xy 286.073699 -352.145971) (xy 286.052768 -352.128328) (xy 286.04144 -352.119092)
			(xy 286.014883 -352.106916) (xy 285.985966 -352.102743) (xy 285.957049 -352.106916) (xy 285.930492 -352.119092)
			(xy 285.919164 -352.128328) (xy 285.898222 -352.145955) (xy 285.852252 -352.175668) (xy 285.802507 -352.198505)
			(xy 285.750008 -352.213999) (xy 285.695834 -352.221832) (xy 285.668466 -352.222308) (xy 285.641214 -352.221854)
			(xy 285.587265 -352.214093) (xy 285.53497 -352.198733) (xy 285.485392 -352.176088) (xy 285.439542 -352.146618)
			(xy 285.398352 -352.110924) (xy 285.362661 -352.069731) (xy 285.333196 -352.023878) (xy 285.310555 -351.974298)
			(xy 285.2952 -351.922002) (xy 285.287444 -351.868052) (xy 285.286958 -351.8408) (xy 282.894786 -351.8408)
			(xy 282.894786 -362.290868) (xy 283.044644 -362.290868) (xy 283.048715 -362.235246) (xy 283.060841 -362.180809)
			(xy 283.080764 -362.128718) (xy 283.10806 -362.080083) (xy 283.142146 -362.03594) (xy 283.182295 -361.997231)
			(xy 283.227653 -361.96478) (xy 283.277253 -361.939279) (xy 283.330037 -361.921272) (xy 283.38488 -361.911142)
			(xy 283.440614 -361.909105) (xy 283.496051 -361.915205) (xy 283.550008 -361.929311) (xy 283.601337 -361.951123)
			(xy 283.648943 -361.980177) (xy 283.691811 -362.015852) (xy 283.729028 -362.057389) (xy 283.759801 -362.103902)
			(xy 283.783473 -362.154399) (xy 283.799541 -362.207806) (xy 283.807661 -362.262982) (xy 283.80817 -362.290868)
			(xy 283.807661 -362.318754) (xy 283.799541 -362.37393) (xy 283.783473 -362.427337) (xy 283.759801 -362.477834)
			(xy 283.729028 -362.524347) (xy 283.691811 -362.565884) (xy 283.648943 -362.601559) (xy 283.601337 -362.630613)
			(xy 283.550008 -362.652425) (xy 283.496051 -362.666531) (xy 283.440614 -362.672631) (xy 283.38488 -362.670594)
			(xy 283.330037 -362.660464) (xy 283.277253 -362.642457) (xy 283.227653 -362.616956) (xy 283.182295 -362.584505)
			(xy 283.142146 -362.545796) (xy 283.10806 -362.501653) (xy 283.080764 -362.453018) (xy 283.060841 -362.400927)
			(xy 283.048715 -362.34649) (xy 283.044644 -362.290868) (xy 282.894786 -362.290868) (xy 282.894786 -364.242096)
			(xy 284.829758 -364.242096) (xy 284.830254 -364.214056) (xy 284.838455 -364.158578) (xy 284.854681 -364.104896)
			(xy 284.878582 -364.054164) (xy 284.909644 -364.007472) (xy 284.928056 -363.986318) (xy 284.937658 -363.974842)
			(xy 284.950447 -363.947812) (xy 284.954843 -363.918234) (xy 284.950467 -363.888653) (xy 284.937697 -363.861615)
			(xy 284.928056 -363.850174) (xy 284.909643 -363.829017) (xy 284.878549 -363.782341) (xy 284.854632 -363.731612)
			(xy 284.83841 -363.677924) (xy 284.830233 -363.622439) (xy 284.829758 -363.594396) (xy 284.830244 -363.567145)
			(xy 284.838 -363.513197) (xy 284.853355 -363.460902) (xy 284.875997 -363.411325) (xy 284.905463 -363.365475)
			(xy 284.941154 -363.324284) (xy 284.982345 -363.288593) (xy 285.028195 -363.259127) (xy 285.077772 -363.236485)
			(xy 285.130067 -363.22113) (xy 285.184015 -363.213374) (xy 285.238517 -363.213374) (xy 285.292465 -363.22113)
			(xy 285.34476 -363.236485) (xy 285.394337 -363.259127) (xy 285.440187 -363.288593) (xy 285.481378 -363.324284)
			(xy 285.517069 -363.365475) (xy 285.546535 -363.411325) (xy 285.569177 -363.460902) (xy 285.584532 -363.513197)
			(xy 285.592288 -363.567145) (xy 285.592774 -363.594396) (xy 285.592291 -363.622437) (xy 285.584089 -363.677916)
			(xy 285.567862 -363.731598) (xy 285.543957 -363.78233) (xy 285.51289 -363.829021) (xy 285.494476 -363.850174)
			(xy 285.489947 -363.855508) (xy 292.807134 -363.855508) (xy 292.811205 -363.799886) (xy 292.823331 -363.745449)
			(xy 292.843254 -363.693358) (xy 292.87055 -363.644723) (xy 292.904636 -363.60058) (xy 292.944785 -363.561871)
			(xy 292.990143 -363.52942) (xy 293.039743 -363.503919) (xy 293.092527 -363.485912) (xy 293.14737 -363.475782)
			(xy 293.203104 -363.473745) (xy 293.258541 -363.479845) (xy 293.312498 -363.493951) (xy 293.363827 -363.515763)
			(xy 293.411433 -363.544817) (xy 293.454301 -363.580492) (xy 293.491518 -363.622029) (xy 293.522291 -363.668542)
			(xy 293.545963 -363.719039) (xy 293.562031 -363.772446) (xy 293.570151 -363.827622) (xy 293.57066 -363.855508)
			(xy 293.570151 -363.883394) (xy 293.562031 -363.93857) (xy 293.545963 -363.991977) (xy 293.522291 -364.042474)
			(xy 293.491518 -364.088987) (xy 293.454301 -364.130524) (xy 293.411433 -364.166199) (xy 293.363827 -364.195253)
			(xy 293.312498 -364.217065) (xy 293.258541 -364.231171) (xy 293.216963 -364.235746) (xy 294.51808 -364.235746)
			(xy 294.518554 -364.208376) (xy 294.526367 -364.154196) (xy 294.541853 -364.101692) (xy 294.564693 -364.051945)
			(xy 294.594418 -364.005979) (xy 294.61206 -363.985048) (xy 294.621255 -363.973689) (xy 294.633443 -363.947143)
			(xy 294.637626 -363.918235) (xy 294.633463 -363.889324) (xy 294.621293 -363.86277) (xy 294.61206 -363.851444)
			(xy 294.594421 -363.830512) (xy 294.564711 -363.784538) (xy 294.541875 -363.734791) (xy 294.526384 -363.68229)
			(xy 294.518554 -363.628115) (xy 294.51808 -363.600746) (xy 294.518566 -363.573495) (xy 294.526322 -363.519547)
			(xy 294.541677 -363.467252) (xy 294.564319 -363.417675) (xy 294.593785 -363.371825) (xy 294.629476 -363.330634)
			(xy 294.670667 -363.294943) (xy 294.716517 -363.265477) (xy 294.766094 -363.242835) (xy 294.818389 -363.22748)
			(xy 294.872337 -363.219724) (xy 294.926839 -363.219724) (xy 294.980787 -363.22748) (xy 295.033082 -363.242835)
			(xy 295.082659 -363.265477) (xy 295.128509 -363.294943) (xy 295.1697 -363.330634) (xy 295.205391 -363.371825)
			(xy 295.234857 -363.417675) (xy 295.257499 -363.467252) (xy 295.272854 -363.519547) (xy 295.28061 -363.573495)
			(xy 295.281096 -363.600746) (xy 295.280599 -363.628115) (xy 295.272789 -363.682293) (xy 295.257307 -363.734796)
			(xy 295.234472 -363.784543) (xy 295.204754 -363.830511) (xy 295.187116 -363.851444) (xy 295.180853 -363.859064)
			(xy 302.365154 -363.859064) (xy 302.369225 -363.803442) (xy 302.381351 -363.749005) (xy 302.401274 -363.696914)
			(xy 302.42857 -363.648279) (xy 302.462656 -363.604136) (xy 302.502805 -363.565427) (xy 302.548163 -363.532976)
			(xy 302.597763 -363.507475) (xy 302.650547 -363.489468) (xy 302.70539 -363.479338) (xy 302.761124 -363.477301)
			(xy 302.816561 -363.483401) (xy 302.870518 -363.497507) (xy 302.921847 -363.519319) (xy 302.969453 -363.548373)
			(xy 303.012321 -363.584048) (xy 303.049538 -363.625585) (xy 303.080311 -363.672098) (xy 303.103983 -363.722595)
			(xy 303.120051 -363.776002) (xy 303.128171 -363.831178) (xy 303.12868 -363.859064) (xy 303.128171 -363.88695)
			(xy 303.120051 -363.942126) (xy 303.103983 -363.995533) (xy 303.080311 -364.04603) (xy 303.049538 -364.092543)
			(xy 303.012321 -364.13408) (xy 302.969453 -364.169755) (xy 302.921847 -364.198809) (xy 302.870518 -364.220621)
			(xy 302.816561 -364.234727) (xy 302.761124 -364.240827) (xy 302.70539 -364.23879) (xy 302.650547 -364.22866)
			(xy 302.597763 -364.210653) (xy 302.548163 -364.185152) (xy 302.502805 -364.152701) (xy 302.462656 -364.113992)
			(xy 302.42857 -364.069849) (xy 302.401274 -364.021214) (xy 302.381351 -363.969123) (xy 302.369225 -363.914686)
			(xy 302.365154 -363.859064) (xy 295.180853 -363.859064) (xy 295.177834 -363.862738) (xy 295.16566 -363.889307)
			(xy 295.161495 -363.918235) (xy 295.165679 -363.94716) (xy 295.177871 -363.973721) (xy 295.187116 -363.985048)
			(xy 295.204747 -364.005987) (xy 295.234459 -364.051958) (xy 295.257297 -364.101704) (xy 295.27279 -364.154203)
			(xy 295.28062 -364.208377) (xy 295.281096 -364.235746) (xy 295.28061 -364.262997) (xy 295.272854 -364.316945)
			(xy 295.257499 -364.36924) (xy 295.234857 -364.418817) (xy 295.205391 -364.464667) (xy 295.1697 -364.505858)
			(xy 295.128509 -364.541549) (xy 295.082659 -364.571015) (xy 295.033082 -364.593657) (xy 294.980787 -364.609012)
			(xy 294.926839 -364.616768) (xy 294.872337 -364.616768) (xy 294.818389 -364.609012) (xy 294.766094 -364.593657)
			(xy 294.716517 -364.571015) (xy 294.670667 -364.541549) (xy 294.629476 -364.505858) (xy 294.593785 -364.464667)
			(xy 294.564319 -364.418817) (xy 294.541677 -364.36924) (xy 294.526322 -364.316945) (xy 294.518566 -364.262997)
			(xy 294.51808 -364.235746) (xy 293.216963 -364.235746) (xy 293.203104 -364.237271) (xy 293.14737 -364.235234)
			(xy 293.092527 -364.225104) (xy 293.039743 -364.207097) (xy 292.990143 -364.181596) (xy 292.944785 -364.149145)
			(xy 292.904636 -364.110436) (xy 292.87055 -364.066293) (xy 292.843254 -364.017658) (xy 292.823331 -363.965567)
			(xy 292.811205 -363.91113) (xy 292.807134 -363.855508) (xy 285.489947 -363.855508) (xy 285.484789 -363.861583)
			(xy 285.47202 -363.888638) (xy 285.467644 -363.918234) (xy 285.47204 -363.947827) (xy 285.484827 -363.974874)
			(xy 285.494476 -363.986318) (xy 285.512891 -364.007473) (xy 285.543984 -364.05415) (xy 285.567899 -364.10488)
			(xy 285.584121 -364.158568) (xy 285.592299 -364.214053) (xy 285.592774 -364.242096) (xy 285.592288 -364.269347)
			(xy 285.584532 -364.323295) (xy 285.569177 -364.37559) (xy 285.546535 -364.425167) (xy 285.517069 -364.471017)
			(xy 285.481378 -364.512208) (xy 285.440187 -364.547899) (xy 285.394337 -364.577365) (xy 285.34476 -364.600007)
			(xy 285.292465 -364.615362) (xy 285.238517 -364.623118) (xy 285.184015 -364.623118) (xy 285.130067 -364.615362)
			(xy 285.077772 -364.600007) (xy 285.028195 -364.577365) (xy 284.982345 -364.547899) (xy 284.941154 -364.512208)
			(xy 284.905463 -364.471017) (xy 284.875997 -364.425167) (xy 284.853355 -364.37559) (xy 284.838 -364.323295)
			(xy 284.830244 -364.269347) (xy 284.829758 -364.242096) (xy 282.894786 -364.242096) (xy 282.894786 -364.625128)
			(xy 283.044644 -364.625128) (xy 283.048715 -364.569506) (xy 283.060841 -364.515069) (xy 283.080764 -364.462978)
			(xy 283.10806 -364.414343) (xy 283.142146 -364.3702) (xy 283.182295 -364.331491) (xy 283.227653 -364.29904)
			(xy 283.277253 -364.273539) (xy 283.330037 -364.255532) (xy 283.38488 -364.245402) (xy 283.440614 -364.243365)
			(xy 283.496051 -364.249465) (xy 283.550008 -364.263571) (xy 283.601337 -364.285383) (xy 283.648943 -364.314437)
			(xy 283.691811 -364.350112) (xy 283.729028 -364.391649) (xy 283.759801 -364.438162) (xy 283.783473 -364.488659)
			(xy 283.799541 -364.542066) (xy 283.807661 -364.597242) (xy 283.80817 -364.625128) (xy 283.80793 -364.6383)
			(xy 289.07837 -364.6383) (xy 289.082538 -364.582684) (xy 289.094949 -364.52831) (xy 289.115327 -364.476394)
			(xy 289.143215 -364.428095) (xy 289.17799 -364.384492) (xy 289.218876 -364.34656) (xy 289.264959 -364.315146)
			(xy 289.31521 -364.290951) (xy 289.368506 -364.274517) (xy 289.423656 -364.26621) (xy 289.451542 -364.265718)
			(xy 289.478873 -364.26621) (xy 289.532952 -364.274177) (xy 289.585285 -364.289962) (xy 289.634749 -364.313227)
			(xy 289.680282 -364.343471) (xy 289.720905 -364.380046) (xy 289.755745 -364.422165) (xy 289.770312 -364.445296)
			(xy 289.778247 -364.457512) (xy 289.799715 -364.477184) (xy 289.825865 -364.48999) (xy 289.854568 -364.494887)
			(xy 289.883485 -364.491477) (xy 289.897058 -364.48619) (xy 289.920264 -364.47669) (xy 289.968599 -364.463343)
			(xy 290.01829 -364.456619) (xy 290.043362 -364.456218) (xy 290.068432 -364.456634) (xy 290.118115 -364.463387)
			(xy 290.166449 -364.476723) (xy 290.189666 -364.48619) (xy 290.203241 -364.491445) (xy 290.232143 -364.494811)
			(xy 290.260823 -364.4899) (xy 290.286959 -364.477108) (xy 290.308433 -364.457473) (xy 290.316412 -364.445296)
			(xy 290.330981 -364.422165) (xy 290.365824 -364.380044) (xy 290.406447 -364.343465) (xy 290.451978 -364.313214)
			(xy 290.50144 -364.289938) (xy 290.553771 -364.274138) (xy 290.60785 -364.266152) (xy 290.662514 -364.266152)
			(xy 290.716593 -364.274138) (xy 290.768924 -364.289938) (xy 290.818386 -364.313214) (xy 290.863917 -364.343465)
			(xy 290.90454 -364.380044) (xy 290.939383 -364.422165) (xy 290.953952 -364.445296) (xy 290.961849 -364.457539)
			(xy 290.983327 -364.477211) (xy 291.009488 -364.490013) (xy 291.038199 -364.494904) (xy 291.067123 -364.491483)
			(xy 291.080698 -364.48619) (xy 291.103911 -364.476708) (xy 291.152242 -364.463354) (xy 291.201931 -364.456623)
			(xy 291.227002 -364.456218) (xy 291.254319 -364.456686) (xy 291.308365 -364.464677) (xy 291.360665 -364.480472)
			(xy 291.410099 -364.503733) (xy 291.455607 -364.533963) (xy 291.496215 -364.570512) (xy 291.531052 -364.612598)
			(xy 291.559371 -364.659318) (xy 291.57041 -364.68431) (xy 291.575959 -364.69653) (xy 291.592461 -364.717688)
			(xy 291.613901 -364.733822) (xy 291.638801 -364.74382) (xy 291.665445 -364.746992) (xy 291.691997 -364.743119)
			(xy 291.716625 -364.73247) (xy 291.727382 -364.724442) (xy 291.747719 -364.708764) (xy 291.791824 -364.682466)
			(xy 291.839056 -364.662316) (xy 291.888563 -364.648679) (xy 291.939451 -364.641799) (xy 291.965126 -364.641384)
			(xy 291.983145 -364.641606) (xy 292.01902 -364.645039) (xy 292.036754 -364.648242) (xy 292.051967 -364.650546)
			(xy 292.082518 -364.64703) (xy 292.110636 -364.634578) (xy 292.133772 -364.614319) (xy 292.149827 -364.588091)
			(xy 292.154102 -364.573312) (xy 292.161484 -364.546264) (xy 292.183118 -364.494539) (xy 292.212086 -364.446535)
			(xy 292.247764 -364.403285) (xy 292.289385 -364.365719) (xy 292.336054 -364.334645) (xy 292.386766 -364.310733)
			(xy 292.44043 -364.294496) (xy 292.495893 -364.286284) (xy 292.523926 -364.285784) (xy 292.551178 -364.286254)
			(xy 292.605125 -364.294013) (xy 292.65742 -364.309371) (xy 292.706997 -364.332015) (xy 292.752847 -364.361483)
			(xy 292.794036 -364.397176) (xy 292.829728 -364.438368) (xy 292.859194 -364.484219) (xy 292.881835 -364.533797)
			(xy 292.89719 -364.586092) (xy 292.904698 -364.6383) (xy 298.766795 -364.6383) (xy 298.770962 -364.582695)
			(xy 298.783369 -364.528332) (xy 298.80374 -364.476425) (xy 298.831619 -364.428134) (xy 298.866383 -364.384537)
			(xy 298.907257 -364.346608) (xy 298.953327 -364.315194) (xy 299.003564 -364.290997) (xy 299.056846 -364.274557)
			(xy 299.111984 -364.266241) (xy 299.139864 -364.265718) (xy 299.167196 -364.266193) (xy 299.221275 -364.274163)
			(xy 299.273609 -364.289951) (xy 299.323073 -364.313218) (xy 299.368605 -364.343465) (xy 299.409228 -364.380043)
			(xy 299.444068 -364.422164) (xy 299.458634 -364.445296) (xy 299.466548 -364.457527) (xy 299.488021 -364.477199)
			(xy 299.514177 -364.490003) (xy 299.542885 -364.494896) (xy 299.571806 -364.49148) (xy 299.58538 -364.48619)
			(xy 299.608595 -364.476714) (xy 299.656925 -364.463358) (xy 299.706613 -364.456624) (xy 299.731684 -364.456218)
			(xy 299.756753 -364.45666) (xy 299.806435 -364.463402) (xy 299.85477 -364.476727) (xy 299.877988 -364.48619)
			(xy 299.891578 -364.491412) (xy 299.92048 -364.494797) (xy 299.949165 -364.489902) (xy 299.975309 -364.477123)
			(xy 299.996793 -364.457496) (xy 300.004734 -364.445296) (xy 300.019303 -364.422165) (xy 300.054146 -364.380044)
			(xy 300.094769 -364.343465) (xy 300.1403 -364.313214) (xy 300.189762 -364.289938) (xy 300.242093 -364.274138)
			(xy 300.296172 -364.266152) (xy 300.350836 -364.266152) (xy 300.404915 -364.274138) (xy 300.457246 -364.289938)
			(xy 300.506708 -364.313214) (xy 300.552239 -364.343465) (xy 300.592862 -364.380044) (xy 300.627705 -364.422165)
			(xy 300.642274 -364.445296) (xy 300.650245 -364.457486) (xy 300.671703 -364.477157) (xy 300.697843 -364.489967)
			(xy 300.726538 -364.494871) (xy 300.755449 -364.491471) (xy 300.76902 -364.48619) (xy 300.79223 -364.476701)
			(xy 300.840563 -364.46335) (xy 300.890252 -364.456622) (xy 300.915324 -364.456218) (xy 300.942169 -364.456634)
			(xy 300.995301 -364.464342) (xy 301.046778 -364.479596) (xy 301.095533 -364.50208) (xy 301.140556 -364.531328)
			(xy 301.180915 -364.566735) (xy 301.215776 -364.607567) (xy 301.244415 -364.65298) (xy 301.266241 -364.702032)
			(xy 301.273972 -364.727744) (xy 301.27869 -364.742221) (xy 301.295197 -364.767781) (xy 301.318501 -364.787346)
			(xy 301.346533 -364.799179) (xy 301.376807 -364.80223) (xy 301.406637 -364.796229) (xy 301.420276 -364.789466)
			(xy 301.448418 -364.774824) (xy 301.508371 -364.7541) (xy 301.570931 -364.743605) (xy 301.602648 -364.742984)
			(xy 301.620667 -364.743202) (xy 301.656542 -364.746638) (xy 301.674276 -364.749842) (xy 301.689487 -364.752168)
			(xy 301.720039 -364.748646) (xy 301.748159 -364.736189) (xy 301.771295 -364.715925) (xy 301.787349 -364.689693)
			(xy 301.791624 -364.674912) (xy 301.798986 -364.647858) (xy 301.820622 -364.596131) (xy 301.849592 -364.548127)
			(xy 301.885273 -364.504876) (xy 301.926896 -364.46731) (xy 301.973568 -364.436238) (xy 302.024282 -364.412327)
			(xy 302.077949 -364.396092) (xy 302.133414 -364.387882) (xy 302.161448 -364.387384) (xy 302.1887 -364.387833)
			(xy 302.242649 -364.395596) (xy 302.294944 -364.410957) (xy 302.34452 -364.433603) (xy 302.39037 -364.463073)
			(xy 302.43156 -364.498769) (xy 302.467251 -364.539962) (xy 302.496716 -364.585815) (xy 302.519357 -364.635394)
			(xy 302.534713 -364.68769) (xy 302.54247 -364.74164) (xy 302.542956 -364.768892) (xy 302.5425 -364.796467)
			(xy 302.534548 -364.851041) (xy 302.518822 -364.903902) (xy 302.49565 -364.953948) (xy 302.465515 -365.000137)
			(xy 302.429045 -365.041507) (xy 302.408336 -365.059722) (xy 302.397444 -365.069627) (xy 302.381366 -365.094274)
			(xy 302.372978 -365.122481) (xy 302.372977 -365.151909) (xy 302.381361 -365.180116) (xy 302.397437 -365.204765)
			(xy 302.408336 -365.214662) (xy 302.429032 -365.232888) (xy 302.465492 -365.274259) (xy 302.495616 -365.320449)
			(xy 302.518776 -365.370494) (xy 302.53449 -365.423352) (xy 302.54243 -365.477922) (xy 302.542431 -365.533067)
			(xy 302.534492 -365.587637) (xy 302.51878 -365.640496) (xy 302.495621 -365.690542) (xy 302.465498 -365.736733)
			(xy 302.429039 -365.778105) (xy 302.408336 -365.796322) (xy 302.397444 -365.806227) (xy 302.381366 -365.830874)
			(xy 302.372978 -365.859081) (xy 302.372977 -365.888509) (xy 302.381361 -365.916716) (xy 302.397437 -365.941365)
			(xy 302.408336 -365.951262) (xy 302.429039 -365.969482) (xy 302.465509 -366.010849) (xy 302.495641 -366.057038)
			(xy 302.518808 -366.107084) (xy 302.534526 -366.159945) (xy 302.542469 -366.214518) (xy 302.542956 -366.242092)
			(xy 302.542415 -366.269341) (xy 302.534661 -366.323284) (xy 302.519309 -366.375575) (xy 302.496672 -366.425149)
			(xy 302.467211 -366.470997) (xy 302.431526 -366.512186) (xy 302.390342 -366.547878) (xy 302.344498 -366.577345)
			(xy 302.294927 -366.599989) (xy 302.242639 -366.615349) (xy 302.188697 -366.623111) (xy 302.161448 -366.6236)
			(xy 302.133594 -366.623034) (xy 302.07848 -366.614917) (xy 302.025131 -366.598878) (xy 301.974679 -366.575257)
			(xy 301.928194 -366.544555) (xy 301.886664 -366.507425) (xy 301.85097 -366.464655) (xy 301.82187 -366.417151)
			(xy 301.799981 -366.365923) (xy 301.792386 -366.33912) (xy 301.788085 -366.325013) (xy 301.772701 -366.29987)
			(xy 301.75079 -366.280153) (xy 301.724168 -366.2675) (xy 301.695043 -366.262958) (xy 301.680372 -366.264444)
			(xy 301.667356 -366.266114) (xy 301.641171 -366.267893) (xy 301.628048 -366.268) (xy 301.613899 -366.267901)
			(xy 301.585676 -366.26587) (xy 301.57166 -366.263936) (xy 301.558312 -366.262339) (xy 301.531617 -366.265436)
			(xy 301.506661 -366.275405) (xy 301.485179 -366.291553) (xy 301.468668 -366.312756) (xy 301.458275 -366.337539)
			(xy 301.45609 -366.350804) (xy 301.451996 -366.377957) (xy 301.437027 -366.430789) (xy 301.414638 -366.480929)
			(xy 301.385293 -366.527342) (xy 301.349596 -366.569067) (xy 301.308286 -366.605245) (xy 301.262217 -366.635126)
			(xy 301.21234 -366.658094) (xy 301.159685 -366.673674) (xy 301.10534 -366.681544) (xy 301.077884 -366.68202)
			(xy 301.050633 -366.681537) (xy 300.996686 -366.673779) (xy 300.944392 -366.658422) (xy 300.894815 -366.63578)
			(xy 300.848965 -366.606313) (xy 300.807776 -366.570622) (xy 300.772084 -366.529431) (xy 300.742618 -366.483581)
			(xy 300.719976 -366.434005) (xy 300.70462 -366.38171) (xy 300.696863 -366.327763) (xy 300.696376 -366.300512)
			(xy 300.696858 -366.272938) (xy 300.704809 -366.218366) (xy 300.720531 -366.165507) (xy 300.743698 -366.115461)
			(xy 300.773827 -366.069271) (xy 300.810291 -366.027899) (xy 300.830996 -366.009682) (xy 300.841881 -365.999771)
			(xy 300.857954 -365.975124) (xy 300.866339 -365.94692) (xy 300.866342 -365.917495) (xy 300.857961 -365.88929)
			(xy 300.841891 -365.864641) (xy 300.830996 -365.854742) (xy 300.810301 -365.836513) (xy 300.77383 -365.795148)
			(xy 300.743696 -365.748962) (xy 300.720527 -365.698917) (xy 300.704807 -365.646058) (xy 300.696864 -365.591486)
			(xy 300.696376 -365.563912) (xy 300.69686 -365.537412) (xy 300.704199 -365.484922) (xy 300.718737 -365.433955)
			(xy 300.740193 -365.385492) (xy 300.768154 -365.340468) (xy 300.784768 -365.319818) (xy 300.79424 -365.307695)
			(xy 300.806022 -365.279286) (xy 300.808838 -365.248661) (xy 300.802436 -365.218581) (xy 300.787392 -365.191757)
			(xy 300.765062 -365.170609) (xy 300.751494 -365.163354) (xy 300.727822 -365.15122) (xy 300.683837 -365.121307)
			(xy 300.644551 -365.085446) (xy 300.610762 -365.044364) (xy 300.596554 -365.021876) (xy 300.588658 -365.009633)
			(xy 300.567178 -364.989964) (xy 300.541017 -364.977164) (xy 300.512307 -364.972273) (xy 300.483383 -364.975691)
			(xy 300.469808 -364.980982) (xy 300.446594 -364.99046) (xy 300.398263 -365.003816) (xy 300.348575 -365.010548)
			(xy 300.323504 -365.010954) (xy 300.298435 -365.010518) (xy 300.248752 -365.003774) (xy 300.200418 -364.990446)
			(xy 300.1772 -364.980982) (xy 300.163598 -364.975809) (xy 300.13471 -364.972429) (xy 300.106041 -364.977324)
			(xy 300.079911 -364.990095) (xy 300.058436 -365.009709) (xy 300.050454 -365.021876) (xy 300.035885 -365.045007)
			(xy 300.001042 -365.087128) (xy 299.960419 -365.123707) (xy 299.914888 -365.153958) (xy 299.865426 -365.177234)
			(xy 299.813095 -365.193034) (xy 299.759016 -365.20102) (xy 299.704352 -365.20102) (xy 299.650273 -365.193034)
			(xy 299.597942 -365.177234) (xy 299.54848 -365.153958) (xy 299.502949 -365.123707) (xy 299.462326 -365.087128)
			(xy 299.427483 -365.045007) (xy 299.412914 -365.021876) (xy 299.404961 -365.009674) (xy 299.383497 -364.990005)
			(xy 299.357351 -364.977199) (xy 299.328654 -364.972298) (xy 299.299741 -364.9757) (xy 299.286168 -364.980982)
			(xy 299.262959 -364.990473) (xy 299.214626 -365.003824) (xy 299.164936 -365.010551) (xy 299.139864 -365.010954)
			(xy 299.111984 -365.010359) (xy 299.056846 -365.002043) (xy 299.003564 -364.985603) (xy 298.953327 -364.961406)
			(xy 298.907257 -364.929992) (xy 298.866383 -364.892063) (xy 298.831619 -364.848466) (xy 298.80374 -364.800175)
			(xy 298.783369 -364.748268) (xy 298.770962 -364.693905) (xy 298.766795 -364.6383) (xy 292.904698 -364.6383)
			(xy 292.904948 -364.64004) (xy 292.905434 -364.667292) (xy 292.904986 -364.694867) (xy 292.897033 -364.749442)
			(xy 292.881306 -364.802303) (xy 292.858133 -364.85235) (xy 292.827996 -364.898539) (xy 292.791524 -364.939908)
			(xy 292.770814 -364.958122) (xy 292.759924 -364.968028) (xy 292.743849 -364.992676) (xy 292.735464 -365.020882)
			(xy 292.735462 -365.050308) (xy 292.743845 -365.078515) (xy 292.759917 -365.103164) (xy 292.770814 -365.113062)
			(xy 292.791511 -365.131287) (xy 292.827973 -365.172658) (xy 292.858099 -365.218847) (xy 292.88126 -365.268892)
			(xy 292.896975 -365.321751) (xy 292.904916 -365.376322) (xy 292.904916 -365.431468) (xy 292.896977 -365.486038)
			(xy 292.881264 -365.538898) (xy 292.858104 -365.588944) (xy 292.827979 -365.635134) (xy 292.791518 -365.676506)
			(xy 292.770814 -365.694722) (xy 292.760482 -365.70412) (xy 295.309034 -365.70412) (xy 295.313105 -365.648498)
			(xy 295.325231 -365.594061) (xy 295.345154 -365.54197) (xy 295.37245 -365.493335) (xy 295.406536 -365.449192)
			(xy 295.446685 -365.410483) (xy 295.492043 -365.378032) (xy 295.541643 -365.352531) (xy 295.594427 -365.334524)
			(xy 295.64927 -365.324394) (xy 295.705004 -365.322357) (xy 295.760441 -365.328457) (xy 295.814398 -365.342563)
			(xy 295.865727 -365.364375) (xy 295.913333 -365.393429) (xy 295.956201 -365.429104) (xy 295.993418 -365.470641)
			(xy 296.024191 -365.517154) (xy 296.047863 -365.567651) (xy 296.063931 -365.621058) (xy 296.072051 -365.676234)
			(xy 296.07256 -365.70412) (xy 296.072051 -365.732006) (xy 296.063931 -365.787182) (xy 296.047863 -365.840589)
			(xy 296.024191 -365.891086) (xy 295.993418 -365.937599) (xy 295.956201 -365.979136) (xy 295.913333 -366.014811)
			(xy 295.865727 -366.043865) (xy 295.814398 -366.065677) (xy 295.760441 -366.079783) (xy 295.705004 -366.085883)
			(xy 295.64927 -366.083846) (xy 295.594427 -366.073716) (xy 295.541643 -366.055709) (xy 295.492043 -366.030208)
			(xy 295.446685 -365.997757) (xy 295.406536 -365.959048) (xy 295.37245 -365.914905) (xy 295.345154 -365.86627)
			(xy 295.325231 -365.814179) (xy 295.313105 -365.759742) (xy 295.309034 -365.70412) (xy 292.760482 -365.70412)
			(xy 292.759924 -365.704628) (xy 292.743849 -365.729276) (xy 292.735464 -365.757482) (xy 292.735462 -365.786908)
			(xy 292.743845 -365.815115) (xy 292.759917 -365.839764) (xy 292.770814 -365.849662) (xy 292.791513 -365.867886)
			(xy 292.827983 -365.909253) (xy 292.858117 -365.95544) (xy 292.881285 -366.005485) (xy 292.897004 -366.058345)
			(xy 292.904947 -366.112918) (xy 292.905434 -366.140492) (xy 292.904915 -366.167742) (xy 292.89716 -366.221687)
			(xy 292.881807 -366.27398) (xy 292.859169 -366.323555) (xy 292.829706 -366.369404) (xy 292.794018 -366.410594)
			(xy 292.752832 -366.446286) (xy 292.706985 -366.475753) (xy 292.657412 -366.498395) (xy 292.60512 -366.513753)
			(xy 292.551176 -366.521512) (xy 292.523926 -366.522) (xy 292.496072 -366.521453) (xy 292.440957 -366.513334)
			(xy 292.387607 -366.497291) (xy 292.337155 -366.473668) (xy 292.29067 -366.442964) (xy 292.24914 -366.405831)
			(xy 292.213447 -366.363059) (xy 292.184347 -366.315553) (xy 292.162459 -366.264324) (xy 292.154864 -366.23752)
			(xy 292.150585 -366.223406) (xy 292.135197 -366.19826) (xy 292.11328 -366.178543) (xy 292.086652 -366.165892)
			(xy 292.057523 -366.161355) (xy 292.04285 -366.162844) (xy 292.029834 -366.164516) (xy 292.003649 -366.166294)
			(xy 291.990526 -366.1664) (xy 291.966978 -366.166093) (xy 291.920234 -366.160356) (xy 291.897308 -366.15497)
			(xy 291.884306 -366.152198) (xy 291.857736 -366.152613) (xy 291.832177 -366.159878) (xy 291.809361 -366.1735)
			(xy 291.79084 -366.192554) (xy 291.77787 -366.215746) (xy 291.771332 -366.241501) (xy 291.77107 -366.254792)
			(xy 291.77107 -366.259872) (xy 291.770584 -366.287123) (xy 291.762828 -366.341071) (xy 291.747473 -366.393366)
			(xy 291.724831 -366.442943) (xy 291.695365 -366.488793) (xy 291.659674 -366.529984) (xy 291.618483 -366.565675)
			(xy 291.572633 -366.595141) (xy 291.523056 -366.617783) (xy 291.470761 -366.633138) (xy 291.416813 -366.640894)
			(xy 291.362311 -366.640894) (xy 291.308363 -366.633138) (xy 291.256068 -366.617783) (xy 291.206491 -366.595141)
			(xy 291.160641 -366.565675) (xy 291.11945 -366.529984) (xy 291.083759 -366.488793) (xy 291.054293 -366.442943)
			(xy 291.031651 -366.393366) (xy 291.016296 -366.341071) (xy 291.00854 -366.287123) (xy 291.008054 -366.259872)
			(xy 291.00855 -366.232298) (xy 291.016494 -366.177726) (xy 291.032212 -366.124866) (xy 291.055376 -366.074819)
			(xy 291.085504 -366.028629) (xy 291.121968 -365.987258) (xy 291.142674 -365.969042) (xy 291.153601 -365.959173)
			(xy 291.169676 -365.934515) (xy 291.178059 -365.906299) (xy 291.178054 -365.876865) (xy 291.169661 -365.848652)
			(xy 291.153577 -365.824) (xy 291.142674 -365.814102) (xy 291.121955 -365.795899) (xy 291.085487 -365.754528)
			(xy 291.055356 -365.708336) (xy 291.032192 -365.658287) (xy 291.016477 -365.605423) (xy 291.008539 -365.550847)
			(xy 291.008054 -365.523272) (xy 291.008619 -365.493749) (xy 291.017752 -365.435413) (xy 291.035766 -365.379181)
			(xy 291.062229 -365.326397) (xy 291.07892 -365.302038) (xy 291.08686 -365.290159) (xy 291.096379 -365.263229)
			(xy 291.098067 -365.234716) (xy 291.09179 -365.206852) (xy 291.078041 -365.181816) (xy 291.057895 -365.161568)
			(xy 291.045646 -365.15421) (xy 291.024749 -365.14215) (xy 290.985971 -365.113443) (xy 290.951219 -365.079973)
			(xy 290.921074 -365.042301) (xy 290.908232 -365.021876) (xy 290.900357 -365.009618) (xy 290.878871 -364.989949)
			(xy 290.852705 -364.977151) (xy 290.823989 -364.972264) (xy 290.795062 -364.975688) (xy 290.781486 -364.980982)
			(xy 290.758274 -364.990467) (xy 290.709942 -365.00382) (xy 290.660253 -365.01055) (xy 290.635182 -365.010954)
			(xy 290.610113 -365.010525) (xy 290.56043 -365.003778) (xy 290.512095 -364.990447) (xy 290.488878 -364.980982)
			(xy 290.475284 -364.975785) (xy 290.446392 -364.972411) (xy 290.41772 -364.977311) (xy 290.391589 -364.990088)
			(xy 290.370114 -365.009707) (xy 290.362132 -365.021876) (xy 290.347563 -365.045007) (xy 290.31272 -365.087128)
			(xy 290.272097 -365.123707) (xy 290.226566 -365.153958) (xy 290.177104 -365.177234) (xy 290.124773 -365.193034)
			(xy 290.070694 -365.20102) (xy 290.01603 -365.20102) (xy 289.961951 -365.193034) (xy 289.90962 -365.177234)
			(xy 289.860158 -365.153958) (xy 289.814627 -365.123707) (xy 289.774004 -365.087128) (xy 289.739161 -365.045007)
			(xy 289.724592 -365.021876) (xy 289.71666 -365.009659) (xy 289.69519 -364.98999) (xy 289.669039 -364.977186)
			(xy 289.640337 -364.972289) (xy 289.61142 -364.975697) (xy 289.597846 -364.980982) (xy 289.574639 -364.99048)
			(xy 289.526305 -365.003828) (xy 289.476614 -365.010553) (xy 289.451542 -365.010954) (xy 289.423656 -365.01039)
			(xy 289.368506 -365.002083) (xy 289.31521 -364.985649) (xy 289.264959 -364.961454) (xy 289.218876 -364.93004)
			(xy 289.17799 -364.892108) (xy 289.143215 -364.848505) (xy 289.115327 -364.800206) (xy 289.094949 -364.74829)
			(xy 289.082538 -364.693916) (xy 289.07837 -364.6383) (xy 283.80793 -364.6383) (xy 283.807661 -364.653014)
			(xy 283.799541 -364.70819) (xy 283.783473 -364.761597) (xy 283.759801 -364.812094) (xy 283.729028 -364.858607)
			(xy 283.691811 -364.900144) (xy 283.648943 -364.935819) (xy 283.601337 -364.964873) (xy 283.550008 -364.986685)
			(xy 283.496051 -365.000791) (xy 283.440614 -365.006891) (xy 283.38488 -365.004854) (xy 283.330037 -364.994724)
			(xy 283.277253 -364.976717) (xy 283.227653 -364.951216) (xy 283.182295 -364.918765) (xy 283.142146 -364.880056)
			(xy 283.10806 -364.835913) (xy 283.080764 -364.787278) (xy 283.060841 -364.735187) (xy 283.048715 -364.68075)
			(xy 283.044644 -364.625128) (xy 282.894786 -364.625128) (xy 282.894786 -365.05388) (xy 283.545026 -365.70412)
			(xy 285.620712 -365.70412) (xy 285.624783 -365.648498) (xy 285.636909 -365.594061) (xy 285.656832 -365.54197)
			(xy 285.684128 -365.493335) (xy 285.718214 -365.449192) (xy 285.758363 -365.410483) (xy 285.803721 -365.378032)
			(xy 285.853321 -365.352531) (xy 285.906105 -365.334524) (xy 285.960948 -365.324394) (xy 286.016682 -365.322357)
			(xy 286.072119 -365.328457) (xy 286.126076 -365.342563) (xy 286.177405 -365.364375) (xy 286.225011 -365.393429)
			(xy 286.267879 -365.429104) (xy 286.305096 -365.470641) (xy 286.335869 -365.517154) (xy 286.359541 -365.567651)
			(xy 286.375609 -365.621058) (xy 286.383729 -365.676234) (xy 286.384238 -365.70412) (xy 286.383729 -365.732006)
			(xy 286.375609 -365.787182) (xy 286.359541 -365.840589) (xy 286.335869 -365.891086) (xy 286.305096 -365.937599)
			(xy 286.267879 -365.979136) (xy 286.225011 -366.014811) (xy 286.177405 -366.043865) (xy 286.126076 -366.065677)
			(xy 286.072119 -366.079783) (xy 286.016682 -366.085883) (xy 285.960948 -366.083846) (xy 285.906105 -366.073716)
			(xy 285.853321 -366.055709) (xy 285.803721 -366.030208) (xy 285.758363 -365.997757) (xy 285.718214 -365.959048)
			(xy 285.684128 -365.914905) (xy 285.656832 -365.86627) (xy 285.636909 -365.814179) (xy 285.624783 -365.759742)
			(xy 285.620712 -365.70412) (xy 283.545026 -365.70412) (xy 284.510988 -366.670082) (xy 284.956248 -366.670082)
			(xy 284.960319 -366.61446) (xy 284.972445 -366.560023) (xy 284.992368 -366.507932) (xy 285.019664 -366.459297)
			(xy 285.05375 -366.415154) (xy 285.093899 -366.376445) (xy 285.139257 -366.343994) (xy 285.188857 -366.318493)
			(xy 285.241641 -366.300486) (xy 285.296484 -366.290356) (xy 285.352218 -366.288319) (xy 285.407655 -366.294419)
			(xy 285.461612 -366.308525) (xy 285.512941 -366.330337) (xy 285.560547 -366.359391) (xy 285.603415 -366.395066)
			(xy 285.640632 -366.436603) (xy 285.671405 -366.483116) (xy 285.695077 -366.533613) (xy 285.711145 -366.58702)
			(xy 285.719265 -366.642196) (xy 285.719774 -366.670082) (xy 285.719265 -366.697968) (xy 285.711145 -366.753144)
			(xy 285.695077 -366.806551) (xy 285.671405 -366.857048) (xy 285.640632 -366.903561) (xy 285.603415 -366.945098)
			(xy 285.560547 -366.980773) (xy 285.512941 -367.009827) (xy 285.461612 -367.031639) (xy 285.407655 -367.045745)
			(xy 285.352218 -367.051845) (xy 285.296484 -367.049808) (xy 285.241641 -367.039678) (xy 285.188857 -367.021671)
			(xy 285.139257 -366.99617) (xy 285.093899 -366.963719) (xy 285.05375 -366.92501) (xy 285.019664 -366.880867)
			(xy 284.992368 -366.832232) (xy 284.972445 -366.780141) (xy 284.960319 -366.725704) (xy 284.956248 -366.670082)
			(xy 284.510988 -366.670082) (xy 285.318708 -367.477802) (xy 286.354266 -367.477802) (xy 286.36819 -367.477363)
			(xy 286.394999 -367.46983) (xy 286.418781 -367.455342) (xy 286.43777 -367.434973) (xy 286.450557 -367.410235)
			(xy 286.456194 -367.382964) (xy 286.454262 -367.355183) (xy 286.450024 -367.341912) (xy 286.439503 -367.31063)
			(xy 286.428141 -367.245622) (xy 286.427418 -367.212626) (xy 286.427831 -367.187287) (xy 286.434537 -367.137055)
			(xy 286.447836 -367.088152) (xy 286.467492 -367.041442) (xy 286.49316 -366.997745) (xy 286.524388 -366.957831)
			(xy 286.542226 -366.93983) (xy 286.551607 -366.930066) (xy 286.565312 -366.906725) (xy 286.57241 -366.880605)
			(xy 286.572402 -366.853538) (xy 286.56529 -366.827422) (xy 286.551571 -366.804089) (xy 286.542226 -366.794288)
			(xy 286.524397 -366.776279) (xy 286.493168 -366.736367) (xy 286.467499 -366.692672) (xy 286.447841 -366.645962)
			(xy 286.434541 -366.597062) (xy 286.427832 -366.546831) (xy 286.427418 -366.521492) (xy 286.427904 -366.494241)
			(xy 286.43566 -366.440293) (xy 286.451015 -366.387998) (xy 286.473657 -366.338421) (xy 286.503123 -366.292571)
			(xy 286.538814 -366.25138) (xy 286.580005 -366.215689) (xy 286.625855 -366.186223) (xy 286.675432 -366.163581)
			(xy 286.727727 -366.148226) (xy 286.781675 -366.14047) (xy 286.836177 -366.14047) (xy 286.890125 -366.148226)
			(xy 286.94242 -366.163581) (xy 286.991997 -366.186223) (xy 287.037847 -366.215689) (xy 287.079038 -366.25138)
			(xy 287.114729 -366.292571) (xy 287.144195 -366.338421) (xy 287.166837 -366.387998) (xy 287.182192 -366.440293)
			(xy 287.189948 -366.494241) (xy 287.190434 -366.521492) (xy 287.19002 -366.546831) (xy 287.183312 -366.597063)
			(xy 287.170013 -366.645965) (xy 287.150357 -366.692676) (xy 287.124691 -366.736373) (xy 287.093465 -366.776288)
			(xy 287.075626 -366.794288) (xy 287.066191 -366.804031) (xy 287.05239 -366.827366) (xy 287.045232 -366.853516)
			(xy 287.045224 -366.880627) (xy 287.052367 -366.906781) (xy 287.066156 -366.930124) (xy 287.075626 -366.93983)
			(xy 287.093452 -366.957841) (xy 287.124675 -366.997755) (xy 287.150338 -367.041451) (xy 287.169991 -367.088159)
			(xy 287.183287 -367.137059) (xy 287.189993 -367.187288) (xy 287.190434 -367.212626) (xy 287.189737 -367.245624)
			(xy 287.178368 -367.310634) (xy 287.167828 -367.341912) (xy 287.163531 -367.355172) (xy 287.161566 -367.382966)
			(xy 287.167191 -367.410256) (xy 287.179987 -367.435007) (xy 287.199001 -367.455375) (xy 287.222815 -367.469842)
			(xy 287.249653 -367.477329) (xy 287.263586 -367.477802) (xy 287.37306 -367.477802) (xy 287.387124 -367.477357)
			(xy 287.414189 -367.469694) (xy 287.438136 -367.454938) (xy 287.45715 -367.434209) (xy 287.469787 -367.409079)
			(xy 287.475089 -367.381455) (xy 287.472654 -367.353432) (xy 287.468056 -367.340134) (xy 287.456553 -367.307609)
			(xy 287.44415 -367.239751) (xy 287.443418 -367.20526) (xy 287.443904 -367.178009) (xy 287.45166 -367.124061)
			(xy 287.467015 -367.071766) (xy 287.489657 -367.022189) (xy 287.519123 -366.976339) (xy 287.554814 -366.935148)
			(xy 287.596005 -366.899457) (xy 287.641855 -366.869991) (xy 287.691432 -366.847349) (xy 287.743727 -366.831994)
			(xy 287.797675 -366.824238) (xy 287.852177 -366.824238) (xy 287.906125 -366.831994) (xy 287.95842 -366.847349)
			(xy 288.007997 -366.869991) (xy 288.053847 -366.899457) (xy 288.095038 -366.935148) (xy 288.130729 -366.976339)
			(xy 288.160195 -367.022189) (xy 288.182837 -367.071766) (xy 288.198192 -367.124061) (xy 288.205948 -367.178009)
			(xy 288.206434 -367.20526) (xy 288.205695 -367.239751) (xy 288.193305 -367.307611) (xy 288.181796 -367.340134)
			(xy 288.177226 -367.35344) (xy 288.174794 -367.381459) (xy 288.180094 -367.409079) (xy 288.192727 -367.434206)
			(xy 288.211733 -367.454936) (xy 288.235673 -367.469696) (xy 288.26273 -367.477368) (xy 288.276792 -367.477802)
			(xy 288.322004 -367.477802) (xy 288.335466 -367.46815) (xy 288.356052 -367.453648) (xy 288.400489 -367.429966)
			(xy 288.44782 -367.412782) (xy 288.472372 -367.40719) (xy 288.485542 -367.404057) (xy 288.509688 -367.391839)
			(xy 288.529768 -367.373698) (xy 288.544368 -367.350912) (xy 288.552457 -367.325088) (xy 288.553466 -367.298045)
			(xy 288.547323 -367.27169) (xy 288.541206 -367.259616) (xy 288.526831 -367.231614) (xy 288.506444 -367.172068)
			(xy 288.49611 -367.109984) (xy 288.495486 -367.078514) (xy 288.495739 -367.059848) (xy 288.499429 -367.022697)
			(xy 288.502852 -367.004346) (xy 288.505179 -366.990072) (xy 288.502656 -366.961275) (xy 288.492165 -366.934339)
			(xy 288.474546 -366.911421) (xy 288.451213 -366.894358) (xy 288.424032 -366.884516) (xy 288.409634 -366.883188)
			(xy 288.380977 -366.880816) (xy 288.324802 -366.868543) (xy 288.271104 -366.847979) (xy 288.221102 -366.819588)
			(xy 288.175926 -366.784014) (xy 288.136602 -366.742064) (xy 288.104018 -366.694686) (xy 288.078914 -366.642955)
			(xy 288.061859 -366.588043) (xy 288.053238 -366.531192) (xy 288.052764 -366.502442) (xy 288.05325 -366.475191)
			(xy 288.061006 -366.421243) (xy 288.076361 -366.368948) (xy 288.099003 -366.319371) (xy 288.128469 -366.273521)
			(xy 288.16416 -366.23233) (xy 288.205351 -366.196639) (xy 288.251201 -366.167173) (xy 288.300778 -366.144531)
			(xy 288.353073 -366.129176) (xy 288.407021 -366.12142) (xy 288.461523 -366.12142) (xy 288.515471 -366.129176)
			(xy 288.567766 -366.144531) (xy 288.617343 -366.167173) (xy 288.663193 -366.196639) (xy 288.704384 -366.23233)
			(xy 288.740075 -366.273521) (xy 288.769541 -366.319371) (xy 288.792183 -366.368948) (xy 288.807538 -366.421243)
			(xy 288.815294 -366.475191) (xy 288.81578 -366.502442) (xy 288.81553 -366.521108) (xy 288.811843 -366.55826)
			(xy 288.808414 -366.57661) (xy 288.806094 -366.590877) (xy 288.80863 -366.619655) (xy 288.819128 -366.64657)
			(xy 288.836748 -366.669465) (xy 288.853938 -366.68202) (xy 294.64457 -366.68202) (xy 294.648641 -366.626398)
			(xy 294.660767 -366.571961) (xy 294.68069 -366.51987) (xy 294.707986 -366.471235) (xy 294.742072 -366.427092)
			(xy 294.782221 -366.388383) (xy 294.827579 -366.355932) (xy 294.877179 -366.330431) (xy 294.929963 -366.312424)
			(xy 294.984806 -366.302294) (xy 295.04054 -366.300257) (xy 295.095977 -366.306357) (xy 295.149934 -366.320463)
			(xy 295.201263 -366.342275) (xy 295.248869 -366.371329) (xy 295.291737 -366.407004) (xy 295.328954 -366.448541)
			(xy 295.359727 -366.495054) (xy 295.383399 -366.545551) (xy 295.399467 -366.598958) (xy 295.407587 -366.654134)
			(xy 295.408096 -366.68202) (xy 295.407587 -366.709906) (xy 295.399467 -366.765082) (xy 295.383399 -366.818489)
			(xy 295.359727 -366.868986) (xy 295.328954 -366.915499) (xy 295.291737 -366.957036) (xy 295.248869 -366.992711)
			(xy 295.201263 -367.021765) (xy 295.149934 -367.043577) (xy 295.095977 -367.057683) (xy 295.04054 -367.063783)
			(xy 294.984806 -367.061746) (xy 294.929963 -367.051616) (xy 294.877179 -367.033609) (xy 294.827579 -367.008108)
			(xy 294.782221 -366.975657) (xy 294.742072 -366.936948) (xy 294.707986 -366.892805) (xy 294.68069 -366.84417)
			(xy 294.660767 -366.792079) (xy 294.648641 -366.737642) (xy 294.64457 -366.68202) (xy 288.853938 -366.68202)
			(xy 288.860079 -366.686505) (xy 288.887249 -366.696323) (xy 288.901632 -366.697768) (xy 288.930287 -366.700145)
			(xy 288.986457 -366.712424) (xy 289.040149 -366.732993) (xy 289.090146 -366.761386) (xy 289.135317 -366.79696)
			(xy 289.174639 -366.838909) (xy 289.20722 -366.886284) (xy 289.232324 -366.938011) (xy 289.249382 -366.992919)
			(xy 289.258007 -367.049766) (xy 289.258502 -367.078514) (xy 289.258002 -367.106608) (xy 289.249763 -367.162188)
			(xy 289.233465 -367.21596) (xy 289.20946 -367.266762) (xy 289.204058 -367.274856) (xy 296.11574 -367.274856)
			(xy 296.116241 -367.246409) (xy 296.124701 -367.190149) (xy 296.141428 -367.13577) (xy 296.166048 -367.084479)
			(xy 296.198017 -367.037417) (xy 296.236624 -366.995627) (xy 296.258488 -366.977422) (xy 296.269983 -366.967503)
			(xy 296.287 -366.942374) (xy 296.295897 -366.913358) (xy 296.295892 -366.883009) (xy 296.286985 -366.853997)
			(xy 296.269961 -366.828873) (xy 296.258488 -366.818926) (xy 296.236618 -366.800728) (xy 296.198016 -366.758936)
			(xy 296.166053 -366.711871) (xy 296.141438 -366.660579) (xy 296.124719 -366.606199) (xy 296.116266 -366.549938)
			(xy 296.11574 -366.521492) (xy 296.116226 -366.494241) (xy 296.123982 -366.440293) (xy 296.139337 -366.387998)
			(xy 296.161979 -366.338421) (xy 296.191445 -366.292571) (xy 296.227136 -366.25138) (xy 296.268327 -366.215689)
			(xy 296.314177 -366.186223) (xy 296.363754 -366.163581) (xy 296.416049 -366.148226) (xy 296.469997 -366.14047)
			(xy 296.524499 -366.14047) (xy 296.578447 -366.148226) (xy 296.630742 -366.163581) (xy 296.680319 -366.186223)
			(xy 296.726169 -366.215689) (xy 296.76736 -366.25138) (xy 296.803051 -366.292571) (xy 296.832517 -366.338421)
			(xy 296.855159 -366.387998) (xy 296.870514 -366.440293) (xy 296.87827 -366.494241) (xy 296.878416 -366.502442)
			(xy 297.741086 -366.502442) (xy 297.741572 -366.475191) (xy 297.749328 -366.421243) (xy 297.764683 -366.368948)
			(xy 297.787325 -366.319371) (xy 297.816791 -366.273521) (xy 297.852482 -366.23233) (xy 297.893673 -366.196639)
			(xy 297.939523 -366.167173) (xy 297.9891 -366.144531) (xy 298.041395 -366.129176) (xy 298.095343 -366.12142)
			(xy 298.149845 -366.12142) (xy 298.203793 -366.129176) (xy 298.256088 -366.144531) (xy 298.305665 -366.167173)
			(xy 298.351515 -366.196639) (xy 298.392706 -366.23233) (xy 298.428397 -366.273521) (xy 298.457863 -366.319371)
			(xy 298.480505 -366.368948) (xy 298.49586 -366.421243) (xy 298.503616 -366.475191) (xy 298.504102 -366.502442)
			(xy 298.503863 -366.521109) (xy 298.50017 -366.55826) (xy 298.496736 -366.57661) (xy 298.494466 -366.590887)
			(xy 298.496978 -366.619669) (xy 298.50746 -366.646591) (xy 298.525071 -366.669494) (xy 298.548398 -366.686539)
			(xy 298.575569 -366.696359) (xy 298.589954 -366.697768) (xy 298.618607 -366.700151) (xy 298.674774 -366.712433)
			(xy 298.728462 -366.733004) (xy 298.778456 -366.761398) (xy 298.823623 -366.796971) (xy 298.862942 -366.83892)
			(xy 298.895521 -366.886292) (xy 298.920622 -366.938017) (xy 298.937679 -366.992923) (xy 298.946304 -367.049767)
			(xy 298.946824 -367.078514) (xy 298.946338 -367.105765) (xy 298.938582 -367.159713) (xy 298.923227 -367.212008)
			(xy 298.900585 -367.261585) (xy 298.871119 -367.307435) (xy 298.835428 -367.348626) (xy 298.794237 -367.384317)
			(xy 298.748387 -367.413783) (xy 298.69881 -367.436425) (xy 298.646515 -367.45178) (xy 298.592567 -367.459536)
			(xy 298.538065 -367.459536) (xy 298.484117 -367.45178) (xy 298.431822 -367.436425) (xy 298.382245 -367.413783)
			(xy 298.336395 -367.384317) (xy 298.295204 -367.348626) (xy 298.259513 -367.307435) (xy 298.230047 -367.261585)
			(xy 298.207405 -367.212008) (xy 298.19205 -367.159713) (xy 298.184294 -367.105765) (xy 298.183808 -367.078514)
			(xy 298.184048 -367.059847) (xy 298.187736 -367.022695) (xy 298.191174 -367.004346) (xy 298.193481 -366.990074)
			(xy 298.190958 -366.96129) (xy 298.180467 -366.934367) (xy 298.16285 -366.911464) (xy 298.139518 -366.894419)
			(xy 298.112343 -366.884598) (xy 298.097956 -366.883188) (xy 298.069302 -366.880827) (xy 298.013138 -366.868534)
			(xy 297.959454 -366.847956) (xy 297.909464 -366.819557) (xy 297.864299 -366.78398) (xy 297.824983 -366.742031)
			(xy 297.792405 -366.694658) (xy 297.767301 -366.642935) (xy 297.750241 -366.588031) (xy 297.74161 -366.531189)
			(xy 297.741086 -366.502442) (xy 296.878416 -366.502442) (xy 296.878756 -366.521492) (xy 296.87822 -366.549937)
			(xy 296.869767 -366.606197) (xy 296.853048 -366.660575) (xy 296.828434 -366.711865) (xy 296.796471 -366.758929)
			(xy 296.75787 -366.80072) (xy 296.736008 -366.818926) (xy 296.724565 -366.8289) (xy 296.707548 -366.854015)
			(xy 296.698646 -366.883016) (xy 296.698641 -366.913352) (xy 296.707534 -366.942356) (xy 296.724543 -366.967475)
			(xy 296.736008 -366.977422) (xy 296.757852 -366.995649) (xy 296.796456 -367.037436) (xy 296.828422 -367.084494)
			(xy 296.853041 -367.13578) (xy 296.869766 -367.190155) (xy 296.87051 -367.1951) (xy 297.13885 -367.1951)
			(xy 297.142921 -367.139478) (xy 297.155047 -367.085041) (xy 297.17497 -367.03295) (xy 297.202266 -366.984315)
			(xy 297.236352 -366.940172) (xy 297.276501 -366.901463) (xy 297.321859 -366.869012) (xy 297.371459 -366.843511)
			(xy 297.424243 -366.825504) (xy 297.479086 -366.815374) (xy 297.53482 -366.813337) (xy 297.590257 -366.819437)
			(xy 297.644214 -366.833543) (xy 297.695543 -366.855355) (xy 297.743149 -366.884409) (xy 297.786017 -366.920084)
			(xy 297.823234 -366.961621) (xy 297.854007 -367.008134) (xy 297.877679 -367.058631) (xy 297.893747 -367.112038)
			(xy 297.901867 -367.167214) (xy 297.902376 -367.1951) (xy 297.901867 -367.222986) (xy 297.893747 -367.278162)
			(xy 297.877679 -367.331569) (xy 297.854007 -367.382066) (xy 297.823234 -367.428579) (xy 297.786017 -367.470116)
			(xy 297.743149 -367.505791) (xy 297.695543 -367.534845) (xy 297.644214 -367.556657) (xy 297.590257 -367.570763)
			(xy 297.53482 -367.576863) (xy 297.479086 -367.574826) (xy 297.424243 -367.564696) (xy 297.371459 -367.546689)
			(xy 297.321859 -367.521188) (xy 297.276501 -367.488737) (xy 297.236352 -367.450028) (xy 297.202266 -367.405885)
			(xy 297.17497 -367.35725) (xy 297.155047 -367.305159) (xy 297.142921 -367.250722) (xy 297.13885 -367.1951)
			(xy 296.87051 -367.1951) (xy 296.878226 -367.246412) (xy 296.878756 -367.274856) (xy 296.87827 -367.302107)
			(xy 296.870514 -367.356055) (xy 296.855159 -367.40835) (xy 296.832517 -367.457927) (xy 296.803051 -367.503777)
			(xy 296.76736 -367.544968) (xy 296.726169 -367.580659) (xy 296.680319 -367.610125) (xy 296.630742 -367.632767)
			(xy 296.578447 -367.648122) (xy 296.524499 -367.655878) (xy 296.469997 -367.655878) (xy 296.416049 -367.648122)
			(xy 296.363754 -367.632767) (xy 296.314177 -367.610125) (xy 296.268327 -367.580659) (xy 296.227136 -367.544968)
			(xy 296.191445 -367.503777) (xy 296.161979 -367.457927) (xy 296.139337 -367.40835) (xy 296.123982 -367.356055)
			(xy 296.116226 -367.302107) (xy 296.11574 -367.274856) (xy 289.204058 -367.274856) (xy 289.178267 -367.313496)
			(xy 289.140559 -367.355152) (xy 289.097153 -367.39083) (xy 289.048985 -367.419759) (xy 288.997096 -367.441314)
			(xy 288.969958 -367.448592) (xy 288.957035 -367.452234) (xy 288.933587 -367.465291) (xy 288.914355 -367.484012)
			(xy 288.900674 -367.507102) (xy 288.893488 -367.532962) (xy 288.893298 -367.5598) (xy 288.900114 -367.58576)
			(xy 288.913466 -367.609042) (xy 288.922714 -367.618772) (xy 291.448236 -370.144294) (xy 291.448236 -370.740178)
			(xy 291.927026 -370.740178) (xy 291.927573 -370.711009) (xy 291.936476 -370.653353) (xy 291.954056 -370.597726)
			(xy 291.979902 -370.545425) (xy 292.013412 -370.497671) (xy 292.053803 -370.455576) (xy 292.076632 -370.43741)
			(xy 292.086966 -370.428937) (xy 292.103261 -370.407771) (xy 292.113508 -370.383104) (xy 292.117008 -370.356623)
			(xy 292.113521 -370.330141) (xy 292.103284 -370.305469) (xy 292.086999 -370.284296) (xy 292.076632 -370.275866)
			(xy 292.053819 -370.25768) (xy 292.013415 -370.215598) (xy 291.979897 -370.16785) (xy 291.954048 -370.115551)
			(xy 291.936473 -370.059924) (xy 291.927582 -370.002267) (xy 291.927026 -369.973098) (xy 291.927454 -369.945844)
			(xy 291.935212 -369.89189) (xy 291.95057 -369.839589) (xy 291.973215 -369.790007) (xy 292.002686 -369.744152)
			(xy 292.038384 -369.702958) (xy 292.079581 -369.667265) (xy 292.125438 -369.637798) (xy 292.175023 -369.615157)
			(xy 292.227325 -369.599804) (xy 292.28128 -369.592051) (xy 292.308534 -369.59159) (xy 292.337451 -369.592122)
			(xy 292.394623 -369.600843) (xy 292.449823 -369.618096) (xy 292.501786 -369.643485) (xy 292.549319 -369.676428)
			(xy 292.591335 -369.71617) (xy 292.609524 -369.738656) (xy 292.619421 -369.750461) (xy 292.644745 -369.76798)
			(xy 292.674138 -369.777156) (xy 292.70493 -369.777156) (xy 292.734323 -369.76798) (xy 292.759647 -369.750461)
			(xy 292.769544 -369.738656) (xy 292.787699 -369.716142) (xy 292.829728 -369.676411) (xy 292.87727 -369.643477)
			(xy 292.929239 -369.618094) (xy 292.984442 -369.600844) (xy 293.041616 -369.592122) (xy 293.070534 -369.59159)
			(xy 293.099081 -369.59211) (xy 293.155536 -369.600633) (xy 293.210091 -369.61747) (xy 293.26153 -369.642244)
			(xy 293.285418 -369.657884) (xy 293.296563 -369.664941) (xy 293.321415 -369.673747) (xy 293.347695 -369.675874)
			(xy 293.37364 -369.671181) (xy 293.39751 -369.659982) (xy 293.417702 -369.643028) (xy 293.425626 -369.632484)
			(xy 293.441057 -369.611486) (xy 293.476652 -369.573431) (xy 293.517093 -369.540572) (xy 293.561628 -369.513519)
			(xy 293.609429 -369.492776) (xy 293.659607 -369.478729) (xy 293.71123 -369.471638) (xy 293.737284 -369.471194)
			(xy 293.766202 -369.471688) (xy 293.823376 -369.480417) (xy 293.878577 -369.497677) (xy 293.93054 -369.523073)
			(xy 293.978072 -369.556023) (xy 294.020086 -369.595771) (xy 294.038274 -369.61826) (xy 294.048171 -369.630065)
			(xy 294.073495 -369.647584) (xy 294.102888 -369.65676) (xy 294.13368 -369.65676) (xy 294.163073 -369.647584)
			(xy 294.188397 -369.630065) (xy 294.198294 -369.61826) (xy 294.216478 -369.595771) (xy 294.258501 -369.556038)
			(xy 294.306037 -369.523101) (xy 294.358 -369.497714) (xy 294.413198 -369.480458) (xy 294.470368 -369.471729)
			(xy 294.499284 -369.471194) (xy 294.526537 -369.47167) (xy 294.580487 -369.479425) (xy 294.632785 -369.494779)
			(xy 294.682365 -369.51742) (xy 294.728218 -369.546886) (xy 294.769411 -369.582579) (xy 294.805105 -369.62377)
			(xy 294.834573 -369.669623) (xy 294.857216 -369.719202) (xy 294.872572 -369.771499) (xy 294.880329 -369.825449)
			(xy 294.880792 -369.852702) (xy 294.880362 -369.878745) (xy 294.873275 -369.930348) (xy 294.859233 -369.980506)
			(xy 294.838498 -370.028288) (xy 294.811455 -370.072804) (xy 294.778606 -370.113227) (xy 294.759888 -370.13134)
			(xy 294.749997 -370.141348) (xy 294.735529 -370.165464) (xy 294.72818 -370.19261) (xy 294.728505 -370.220731)
			(xy 294.73648 -370.247699) (xy 294.7515 -370.271474) (xy 294.761666 -370.2812) (xy 294.781236 -370.299374)
			(xy 294.815628 -370.340233) (xy 294.843987 -370.385488) (xy 294.865756 -370.434257) (xy 294.880511 -370.485585)
			(xy 294.887963 -370.538469) (xy 294.888412 -370.565172) (xy 294.887892 -370.592941) (xy 294.879843 -370.647893)
			(xy 294.863911 -370.701096) (xy 294.840433 -370.751428) (xy 294.809904 -370.797823) (xy 294.772971 -370.8393)
			(xy 294.752014 -370.857526) (xy 294.741396 -370.867082) (xy 294.725411 -370.890736) (xy 294.716616 -370.917896)
			(xy 294.7157 -370.94643) (xy 294.722736 -370.974099) (xy 294.737171 -370.998729) (xy 294.747188 -371.00891)
			(xy 294.765535 -371.026997) (xy 294.797707 -371.067237) (xy 294.824176 -371.111437) (xy 294.844461 -371.158796)
			(xy 294.858194 -371.208451) (xy 294.865127 -371.259502) (xy 294.865552 -371.285262) (xy 294.865075 -371.312632)
			(xy 294.857262 -371.366811) (xy 294.841776 -371.419315) (xy 294.818936 -371.469062) (xy 294.789213 -371.515028)
			(xy 294.771572 -371.53596) (xy 294.762374 -371.547316) (xy 294.750196 -371.573864) (xy 294.746017 -371.602771)
			(xy 294.750179 -371.631681) (xy 294.762343 -371.658236) (xy 294.771572 -371.669564) (xy 294.789176 -371.690527)
			(xy 294.818902 -371.736489) (xy 294.84175 -371.786231) (xy 294.857249 -371.838728) (xy 294.865081 -371.892903)
			(xy 294.865085 -371.94764) (xy 294.857261 -372.001816) (xy 294.84177 -372.054316) (xy 294.81893 -372.10406)
			(xy 294.78921 -372.150027) (xy 294.771572 -372.17096) (xy 294.762374 -372.182316) (xy 294.750196 -372.208864)
			(xy 294.746017 -372.237771) (xy 294.750179 -372.266681) (xy 294.762343 -372.293236) (xy 294.771572 -372.304564)
			(xy 294.789176 -372.325527) (xy 294.818902 -372.371489) (xy 294.84175 -372.421231) (xy 294.857249 -372.473728)
			(xy 294.860837 -372.49855) (xy 295.942254 -372.49855) (xy 295.942254 -372.413854) (xy 295.950305 -372.32954)
			(xy 295.966334 -372.246374) (xy 295.990195 -372.165107) (xy 296.021674 -372.086477) (xy 296.060485 -372.011196)
			(xy 296.106275 -371.939944) (xy 296.158631 -371.873368) (xy 296.217079 -371.81207) (xy 296.281089 -371.756605)
			(xy 296.350081 -371.707476) (xy 296.423431 -371.665127) (xy 296.500474 -371.629943) (xy 296.580513 -371.602241)
			(xy 296.662822 -371.582273) (xy 296.746657 -371.57022) (xy 296.831258 -371.56619) (xy 296.915859 -371.57022)
			(xy 296.999694 -371.582273) (xy 297.082003 -371.602241) (xy 297.162042 -371.629943) (xy 297.239085 -371.665127)
			(xy 297.312435 -371.707476) (xy 297.381427 -371.756605) (xy 297.445437 -371.81207) (xy 297.503885 -371.873368)
			(xy 297.556241 -371.939944) (xy 297.602031 -372.011196) (xy 297.640842 -372.086477) (xy 297.672321 -372.165107)
			(xy 297.696182 -372.246374) (xy 297.712211 -372.32954) (xy 297.720262 -372.413854) (xy 297.720766 -372.456202)
			(xy 298.466767 -372.456202) (xy 298.470803 -372.372755) (xy 298.482875 -372.290087) (xy 298.502868 -372.20897)
			(xy 298.530597 -372.130161) (xy 298.565803 -372.054396) (xy 298.608157 -371.982383) (xy 298.657263 -371.914794)
			(xy 298.712664 -371.85226) (xy 298.773841 -371.795365) (xy 298.840224 -371.744639) (xy 298.911192 -371.700558)
			(xy 298.986084 -371.663532) (xy 299.0642 -371.633906) (xy 299.14481 -371.611958) (xy 299.227162 -371.597893)
			(xy 299.310488 -371.591841) (xy 299.394008 -371.59386) (xy 299.476944 -371.60393) (xy 299.55852 -371.621958)
			(xy 299.637976 -371.647775) (xy 299.714569 -371.68114) (xy 299.787585 -371.721741) (xy 299.856341 -371.7692)
			(xy 299.920195 -371.823073) (xy 299.978552 -371.882858) (xy 300.030867 -371.947995) (xy 300.07665 -372.017878)
			(xy 300.115475 -372.091853) (xy 300.14698 -372.16923) (xy 300.170869 -372.249287) (xy 300.18692 -372.331275)
			(xy 300.194983 -372.41443) (xy 300.195488 -372.456202) (xy 300.194983 -372.497974) (xy 300.18692 -372.581129)
			(xy 300.170869 -372.663117) (xy 300.14698 -372.743174) (xy 300.115475 -372.820551) (xy 300.07665 -372.894526)
			(xy 300.030867 -372.964409) (xy 299.978552 -373.029546) (xy 299.920195 -373.089331) (xy 299.856341 -373.143204)
			(xy 299.787585 -373.190663) (xy 299.714569 -373.231264) (xy 299.637976 -373.264629) (xy 299.55852 -373.290446)
			(xy 299.476944 -373.308474) (xy 299.394008 -373.318544) (xy 299.310488 -373.320563) (xy 299.227162 -373.314511)
			(xy 299.14481 -373.300446) (xy 299.0642 -373.278498) (xy 298.986084 -373.248872) (xy 298.911192 -373.211846)
			(xy 298.840224 -373.167765) (xy 298.773841 -373.117039) (xy 298.712664 -373.060144) (xy 298.657263 -372.99761)
			(xy 298.608157 -372.930021) (xy 298.565803 -372.858008) (xy 298.530597 -372.782243) (xy 298.502868 -372.703434)
			(xy 298.482875 -372.622317) (xy 298.470803 -372.539649) (xy 298.466767 -372.456202) (xy 297.720766 -372.456202)
			(xy 297.720262 -372.49855) (xy 297.712211 -372.582864) (xy 297.696182 -372.66603) (xy 297.672321 -372.747297)
			(xy 297.640842 -372.825927) (xy 297.602031 -372.901208) (xy 297.556241 -372.97246) (xy 297.503885 -373.039036)
			(xy 297.445437 -373.100334) (xy 297.381427 -373.155799) (xy 297.312435 -373.204928) (xy 297.239085 -373.247277)
			(xy 297.162042 -373.282461) (xy 297.082003 -373.310163) (xy 296.999694 -373.330131) (xy 296.915859 -373.342184)
			(xy 296.831258 -373.346215) (xy 296.746657 -373.342184) (xy 296.662822 -373.330131) (xy 296.580513 -373.310163)
			(xy 296.500474 -373.282461) (xy 296.423431 -373.247277) (xy 296.350081 -373.204928) (xy 296.281089 -373.155799)
			(xy 296.217079 -373.100334) (xy 296.158631 -373.039036) (xy 296.106275 -372.97246) (xy 296.060485 -372.901208)
			(xy 296.021674 -372.825927) (xy 295.990195 -372.747297) (xy 295.966334 -372.66603) (xy 295.950305 -372.582864)
			(xy 295.942254 -372.49855) (xy 294.860837 -372.49855) (xy 294.865081 -372.527903) (xy 294.865085 -372.58264)
			(xy 294.857261 -372.636816) (xy 294.84177 -372.689316) (xy 294.81893 -372.73906) (xy 294.78921 -372.785027)
			(xy 294.771572 -372.80596) (xy 294.762374 -372.817316) (xy 294.750196 -372.843864) (xy 294.746017 -372.872771)
			(xy 294.750179 -372.901681) (xy 294.762343 -372.928236) (xy 294.771572 -372.939564) (xy 294.789203 -372.960502)
			(xy 294.818917 -373.006473) (xy 294.841755 -373.056219) (xy 294.857248 -373.108718) (xy 294.865077 -373.162893)
			(xy 294.865552 -373.190262) (xy 294.864987 -373.21751) (xy 294.857236 -373.271453) (xy 294.841888 -373.323743)
			(xy 294.819255 -373.373317) (xy 294.789797 -373.419166) (xy 294.754113 -373.460355) (xy 294.712932 -373.496047)
			(xy 294.667089 -373.525515) (xy 294.61752 -373.54816) (xy 294.565233 -373.563519) (xy 294.511292 -373.571281)
			(xy 294.484044 -373.57177) (xy 294.455128 -373.571232) (xy 294.397957 -373.562508) (xy 294.342758 -373.545255)
			(xy 294.290796 -373.519867) (xy 294.243262 -373.486927) (xy 294.201244 -373.447188) (xy 294.183054 -373.424704)
			(xy 294.173157 -373.412899) (xy 294.147833 -373.39538) (xy 294.11844 -373.386204) (xy 294.087648 -373.386204)
			(xy 294.058255 -373.39538) (xy 294.032931 -373.412899) (xy 294.023034 -373.424704) (xy 294.004825 -373.447172)
			(xy 293.962809 -373.486908) (xy 293.915278 -373.519849) (xy 293.86332 -373.54524) (xy 293.808126 -373.562499)
			(xy 293.750959 -373.571233) (xy 293.722044 -373.57177) (xy 293.694791 -373.571304) (xy 293.640838 -373.563552)
			(xy 293.588538 -373.548199) (xy 293.538955 -373.525559) (xy 293.4931 -373.496092) (xy 293.451906 -373.460399)
			(xy 293.416211 -373.419205) (xy 293.386744 -373.37335) (xy 293.364103 -373.323768) (xy 293.34875 -373.271468)
			(xy 293.340997 -373.217515) (xy 293.340536 -373.190262) (xy 293.34103 -373.162893) (xy 293.348839 -373.108714)
			(xy 293.364322 -373.056211) (xy 293.387157 -373.006464) (xy 293.416877 -372.960496) (xy 293.434516 -372.939564)
			(xy 293.443788 -372.928264) (xy 293.455959 -372.901696) (xy 293.460124 -372.872771) (xy 293.455943 -372.843849)
			(xy 293.443757 -372.817288) (xy 293.434516 -372.80596) (xy 293.416839 -372.785057) (xy 293.387116 -372.739084)
			(xy 293.364274 -372.689333) (xy 293.348781 -372.636826) (xy 293.340956 -372.582644) (xy 293.34096 -372.527899)
			(xy 293.348793 -372.473718) (xy 293.364294 -372.421214) (xy 293.387144 -372.371466) (xy 293.416873 -372.325497)
			(xy 293.434516 -372.304564) (xy 293.443788 -372.293264) (xy 293.455959 -372.266696) (xy 293.460124 -372.237771)
			(xy 293.455943 -372.208849) (xy 293.443757 -372.182288) (xy 293.434516 -372.17096) (xy 293.416839 -372.150057)
			(xy 293.387116 -372.104084) (xy 293.364274 -372.054333) (xy 293.348781 -372.001826) (xy 293.340956 -371.947644)
			(xy 293.34096 -371.892899) (xy 293.348793 -371.838718) (xy 293.364294 -371.786214) (xy 293.387144 -371.736466)
			(xy 293.416873 -371.690497) (xy 293.434516 -371.669564) (xy 293.443788 -371.658264) (xy 293.455959 -371.631696)
			(xy 293.460124 -371.602771) (xy 293.455943 -371.573849) (xy 293.443757 -371.547288) (xy 293.434516 -371.53596)
			(xy 293.416894 -371.515014) (xy 293.387179 -371.469045) (xy 293.36434 -371.419301) (xy 293.348845 -371.366804)
			(xy 293.341012 -371.31263) (xy 293.340536 -371.285262) (xy 293.340768 -371.266207) (xy 293.344587 -371.228289)
			(xy 293.348156 -371.20957) (xy 293.3505 -371.196098) (xy 293.348653 -371.168823) (xy 293.339636 -371.143015)
			(xy 293.324096 -371.120524) (xy 293.303147 -371.102961) (xy 293.278289 -371.091584) (xy 293.251304 -371.087209)
			(xy 293.224125 -371.09015) (xy 293.21125 -371.094762) (xy 293.188788 -371.103308) (xy 293.142245 -371.11529)
			(xy 293.094564 -371.121325) (xy 293.070534 -371.121686) (xy 293.041618 -371.121149) (xy 292.984447 -371.112424)
			(xy 292.929249 -371.09517) (xy 292.877287 -371.069782) (xy 292.829752 -371.036842) (xy 292.787735 -370.997104)
			(xy 292.769544 -370.97462) (xy 292.759647 -370.962815) (xy 292.734323 -370.945296) (xy 292.70493 -370.93612)
			(xy 292.674138 -370.93612) (xy 292.644745 -370.945296) (xy 292.619421 -370.962815) (xy 292.609524 -370.97462)
			(xy 292.591324 -370.997096) (xy 292.549306 -371.036831) (xy 292.501773 -371.06977) (xy 292.449813 -371.09516)
			(xy 292.394617 -371.112418) (xy 292.337449 -371.121149) (xy 292.308534 -371.121686) (xy 292.281281 -371.121213)
			(xy 292.227329 -371.11346) (xy 292.17503 -371.098107) (xy 292.125449 -371.075467) (xy 292.079594 -371.046001)
			(xy 292.038401 -371.010308) (xy 292.002707 -370.969115) (xy 291.973239 -370.923262) (xy 291.950597 -370.873681)
			(xy 291.935242 -370.821382) (xy 291.927488 -370.767431) (xy 291.927026 -370.740178) (xy 291.448236 -370.740178)
			(xy 291.448236 -377.277884) (xy 292.24478 -378.074428) (xy 301.69866 -378.074428)
		)
		(stroke
			(width 0)
			(type solid)
		)
		(fill yes)
		(layer "In13.Cu")
		(net "GND")
	)
	(gr_poly
		(pts
			(xy 433.394358 -375.483882) (xy 433.394358 -341.747856) (xy 431.939954 -340.293452) (xy 413.447992 -340.293452)
			(xy 411.43936 -342.302084) (xy 411.43936 -344.053344) (xy 414.212782 -344.053344) (xy 414.212782 -343.968648)
			(xy 414.220833 -343.884334) (xy 414.236862 -343.801168) (xy 414.260723 -343.719901) (xy 414.292202 -343.641271)
			(xy 414.331013 -343.56599) (xy 414.376803 -343.494738) (xy 414.429159 -343.428162) (xy 414.487607 -343.366864)
			(xy 414.551617 -343.311399) (xy 414.620609 -343.26227) (xy 414.693959 -343.219921) (xy 414.771002 -343.184737)
			(xy 414.851041 -343.157035) (xy 414.93335 -343.137067) (xy 415.017185 -343.125014) (xy 415.101786 -343.120984)
			(xy 415.186387 -343.125014) (xy 415.270222 -343.137067) (xy 415.352531 -343.157035) (xy 415.43257 -343.184737)
			(xy 415.509613 -343.219921) (xy 415.582963 -343.26227) (xy 415.651955 -343.311399) (xy 415.715965 -343.366864)
			(xy 415.774413 -343.428162) (xy 415.826769 -343.494738) (xy 415.872559 -343.56599) (xy 415.91137 -343.641271)
			(xy 415.942849 -343.719901) (xy 415.96671 -343.801168) (xy 415.982739 -343.884334) (xy 415.99079 -343.968648)
			(xy 415.991294 -344.010996) (xy 415.99079 -344.053344) (xy 415.990184 -344.059694) (xy 420.403524 -344.059694)
			(xy 420.403524 -343.974998) (xy 420.411575 -343.890684) (xy 420.427604 -343.807518) (xy 420.451465 -343.726251)
			(xy 420.482944 -343.647621) (xy 420.521755 -343.57234) (xy 420.567545 -343.501088) (xy 420.619901 -343.434512)
			(xy 420.678349 -343.373214) (xy 420.742359 -343.317749) (xy 420.811351 -343.26862) (xy 420.884701 -343.226271)
			(xy 420.961744 -343.191087) (xy 421.041783 -343.163385) (xy 421.124092 -343.143417) (xy 421.207927 -343.131364)
			(xy 421.292528 -343.127334) (xy 421.377129 -343.131364) (xy 421.460964 -343.143417) (xy 421.543273 -343.163385)
			(xy 421.623312 -343.191087) (xy 421.700355 -343.226271) (xy 421.773705 -343.26862) (xy 421.842697 -343.317749)
			(xy 421.906707 -343.373214) (xy 421.965155 -343.434512) (xy 422.017511 -343.501088) (xy 422.063301 -343.57234)
			(xy 422.102112 -343.647621) (xy 422.133591 -343.726251) (xy 422.157452 -343.807518) (xy 422.173481 -343.890684)
			(xy 422.181532 -343.974998) (xy 422.182036 -344.017346) (xy 422.181532 -344.059694) (xy 426.601124 -344.059694)
			(xy 426.601124 -343.974998) (xy 426.609175 -343.890684) (xy 426.625204 -343.807518) (xy 426.649065 -343.726251)
			(xy 426.680544 -343.647621) (xy 426.719355 -343.57234) (xy 426.765145 -343.501088) (xy 426.817501 -343.434512)
			(xy 426.875949 -343.373214) (xy 426.939959 -343.317749) (xy 427.008951 -343.26862) (xy 427.082301 -343.226271)
			(xy 427.159344 -343.191087) (xy 427.239383 -343.163385) (xy 427.321692 -343.143417) (xy 427.405527 -343.131364)
			(xy 427.490128 -343.127334) (xy 427.574729 -343.131364) (xy 427.658564 -343.143417) (xy 427.740873 -343.163385)
			(xy 427.820912 -343.191087) (xy 427.897955 -343.226271) (xy 427.971305 -343.26862) (xy 428.040297 -343.317749)
			(xy 428.104307 -343.373214) (xy 428.162755 -343.434512) (xy 428.215111 -343.501088) (xy 428.260901 -343.57234)
			(xy 428.299712 -343.647621) (xy 428.331191 -343.726251) (xy 428.355052 -343.807518) (xy 428.371081 -343.890684)
			(xy 428.379132 -343.974998) (xy 428.379636 -344.017346) (xy 428.379132 -344.059694) (xy 428.371081 -344.144008)
			(xy 428.355052 -344.227174) (xy 428.331191 -344.308441) (xy 428.299712 -344.387071) (xy 428.260901 -344.462352)
			(xy 428.215111 -344.533604) (xy 428.162755 -344.60018) (xy 428.104307 -344.661478) (xy 428.040297 -344.716943)
			(xy 427.971305 -344.766072) (xy 427.897955 -344.808421) (xy 427.820912 -344.843605) (xy 427.740873 -344.871307)
			(xy 427.658564 -344.891275) (xy 427.574729 -344.903328) (xy 427.490128 -344.907359) (xy 427.405527 -344.903328)
			(xy 427.321692 -344.891275) (xy 427.239383 -344.871307) (xy 427.159344 -344.843605) (xy 427.082301 -344.808421)
			(xy 427.008951 -344.766072) (xy 426.939959 -344.716943) (xy 426.875949 -344.661478) (xy 426.817501 -344.60018)
			(xy 426.765145 -344.533604) (xy 426.719355 -344.462352) (xy 426.680544 -344.387071) (xy 426.649065 -344.308441)
			(xy 426.625204 -344.227174) (xy 426.609175 -344.144008) (xy 426.601124 -344.059694) (xy 422.181532 -344.059694)
			(xy 422.173481 -344.144008) (xy 422.157452 -344.227174) (xy 422.133591 -344.308441) (xy 422.102112 -344.387071)
			(xy 422.063301 -344.462352) (xy 422.017511 -344.533604) (xy 421.965155 -344.60018) (xy 421.906707 -344.661478)
			(xy 421.842697 -344.716943) (xy 421.773705 -344.766072) (xy 421.700355 -344.808421) (xy 421.623312 -344.843605)
			(xy 421.543273 -344.871307) (xy 421.460964 -344.891275) (xy 421.377129 -344.903328) (xy 421.292528 -344.907359)
			(xy 421.207927 -344.903328) (xy 421.124092 -344.891275) (xy 421.041783 -344.871307) (xy 420.961744 -344.843605)
			(xy 420.884701 -344.808421) (xy 420.811351 -344.766072) (xy 420.742359 -344.716943) (xy 420.678349 -344.661478)
			(xy 420.619901 -344.60018) (xy 420.567545 -344.533604) (xy 420.521755 -344.462352) (xy 420.482944 -344.387071)
			(xy 420.451465 -344.308441) (xy 420.427604 -344.227174) (xy 420.411575 -344.144008) (xy 420.403524 -344.059694)
			(xy 415.990184 -344.059694) (xy 415.982739 -344.137658) (xy 415.96671 -344.220824) (xy 415.942849 -344.302091)
			(xy 415.91137 -344.380721) (xy 415.872559 -344.456002) (xy 415.826769 -344.527254) (xy 415.774413 -344.59383)
			(xy 415.715965 -344.655128) (xy 415.651955 -344.710593) (xy 415.582963 -344.759722) (xy 415.509613 -344.802071)
			(xy 415.43257 -344.837255) (xy 415.352531 -344.864957) (xy 415.270222 -344.884925) (xy 415.186387 -344.896978)
			(xy 415.101786 -344.901009) (xy 415.017185 -344.896978) (xy 414.93335 -344.884925) (xy 414.851041 -344.864957)
			(xy 414.771002 -344.837255) (xy 414.693959 -344.802071) (xy 414.620609 -344.759722) (xy 414.551617 -344.710593)
			(xy 414.487607 -344.655128) (xy 414.429159 -344.59383) (xy 414.376803 -344.527254) (xy 414.331013 -344.456002)
			(xy 414.292202 -344.380721) (xy 414.260723 -344.302091) (xy 414.236862 -344.220824) (xy 414.220833 -344.137658)
			(xy 414.212782 -344.053344) (xy 411.43936 -344.053344) (xy 411.43936 -346.010992) (xy 414.186375 -346.010992)
			(xy 414.190397 -345.925272) (xy 414.202428 -345.840304) (xy 414.222364 -345.756837) (xy 414.250027 -345.675603)
			(xy 414.285176 -345.597317) (xy 414.327502 -345.522666) (xy 414.376631 -345.452307) (xy 414.432134 -345.386857)
			(xy 414.493521 -345.326893) (xy 414.560254 -345.27294) (xy 414.631746 -345.225473) (xy 414.707368 -345.184909)
			(xy 414.786457 -345.151605) (xy 414.868317 -345.125853) (xy 414.952228 -345.10788) (xy 415.037454 -345.097844)
			(xy 415.123246 -345.095832) (xy 415.208848 -345.101863) (xy 415.29351 -345.115883) (xy 415.376487 -345.137769)
			(xy 415.45705 -345.16733) (xy 415.53449 -345.204304) (xy 415.608129 -345.248368) (xy 415.677317 -345.299134)
			(xy 415.741448 -345.356155) (xy 415.799957 -345.418931) (xy 415.85233 -345.486911) (xy 415.898108 -345.559496)
			(xy 415.936888 -345.636048) (xy 415.968329 -345.715896) (xy 415.992155 -345.798337) (xy 416.008156 -345.882647)
			(xy 416.016191 -345.968085) (xy 416.016694 -346.010992) (xy 416.01662 -346.017342) (xy 420.377117 -346.017342)
			(xy 420.381139 -345.931622) (xy 420.39317 -345.846654) (xy 420.413106 -345.763187) (xy 420.440769 -345.681953)
			(xy 420.475918 -345.603667) (xy 420.518244 -345.529016) (xy 420.567373 -345.458657) (xy 420.622876 -345.393207)
			(xy 420.684263 -345.333243) (xy 420.750996 -345.27929) (xy 420.822488 -345.231823) (xy 420.89811 -345.191259)
			(xy 420.977199 -345.157955) (xy 421.059059 -345.132203) (xy 421.14297 -345.11423) (xy 421.228196 -345.104194)
			(xy 421.313988 -345.102182) (xy 421.39959 -345.108213) (xy 421.484252 -345.122233) (xy 421.567229 -345.144119)
			(xy 421.647792 -345.17368) (xy 421.725232 -345.210654) (xy 421.798871 -345.254718) (xy 421.868059 -345.305484)
			(xy 421.93219 -345.362505) (xy 421.990699 -345.425281) (xy 422.043072 -345.493261) (xy 422.08885 -345.565846)
			(xy 422.12763 -345.642398) (xy 422.159071 -345.722246) (xy 422.182897 -345.804687) (xy 422.198898 -345.888997)
			(xy 422.206933 -345.974435) (xy 422.207436 -346.017342) (xy 426.574717 -346.017342) (xy 426.578739 -345.931622)
			(xy 426.59077 -345.846654) (xy 426.610706 -345.763187) (xy 426.638369 -345.681953) (xy 426.673518 -345.603667)
			(xy 426.715844 -345.529016) (xy 426.764973 -345.458657) (xy 426.820476 -345.393207) (xy 426.881863 -345.333243)
			(xy 426.948596 -345.27929) (xy 427.020088 -345.231823) (xy 427.09571 -345.191259) (xy 427.174799 -345.157955)
			(xy 427.256659 -345.132203) (xy 427.34057 -345.11423) (xy 427.425796 -345.104194) (xy 427.511588 -345.102182)
			(xy 427.59719 -345.108213) (xy 427.681852 -345.122233) (xy 427.764829 -345.144119) (xy 427.845392 -345.17368)
			(xy 427.922832 -345.210654) (xy 427.996471 -345.254718) (xy 428.065659 -345.305484) (xy 428.12979 -345.362505)
			(xy 428.188299 -345.425281) (xy 428.240672 -345.493261) (xy 428.28645 -345.565846) (xy 428.32523 -345.642398)
			(xy 428.356671 -345.722246) (xy 428.380497 -345.804687) (xy 428.396498 -345.888997) (xy 428.404533 -345.974435)
			(xy 428.405036 -346.017342) (xy 428.404533 -346.060249) (xy 428.396498 -346.145687) (xy 428.380497 -346.229997)
			(xy 428.356671 -346.312438) (xy 428.32523 -346.392286) (xy 428.28645 -346.468838) (xy 428.240672 -346.541423)
			(xy 428.188299 -346.609403) (xy 428.12979 -346.672179) (xy 428.065659 -346.7292) (xy 427.996471 -346.779966)
			(xy 427.922832 -346.82403) (xy 427.845392 -346.861004) (xy 427.764829 -346.890565) (xy 427.681852 -346.912451)
			(xy 427.59719 -346.926471) (xy 427.511588 -346.932502) (xy 427.425796 -346.93049) (xy 427.34057 -346.920454)
			(xy 427.256659 -346.902481) (xy 427.174799 -346.876729) (xy 427.09571 -346.843425) (xy 427.020088 -346.802861)
			(xy 426.948596 -346.755394) (xy 426.881863 -346.701441) (xy 426.820476 -346.641477) (xy 426.764973 -346.576027)
			(xy 426.715844 -346.505668) (xy 426.673518 -346.431017) (xy 426.638369 -346.352731) (xy 426.610706 -346.271497)
			(xy 426.59077 -346.18803) (xy 426.578739 -346.103062) (xy 426.574717 -346.017342) (xy 422.207436 -346.017342)
			(xy 422.206933 -346.060249) (xy 422.198898 -346.145687) (xy 422.182897 -346.229997) (xy 422.159071 -346.312438)
			(xy 422.12763 -346.392286) (xy 422.08885 -346.468838) (xy 422.043072 -346.541423) (xy 421.990699 -346.609403)
			(xy 421.93219 -346.672179) (xy 421.868059 -346.7292) (xy 421.798871 -346.779966) (xy 421.725232 -346.82403)
			(xy 421.647792 -346.861004) (xy 421.567229 -346.890565) (xy 421.484252 -346.912451) (xy 421.39959 -346.926471)
			(xy 421.313988 -346.932502) (xy 421.228196 -346.93049) (xy 421.14297 -346.920454) (xy 421.059059 -346.902481)
			(xy 420.977199 -346.876729) (xy 420.89811 -346.843425) (xy 420.822488 -346.802861) (xy 420.750996 -346.755394)
			(xy 420.684263 -346.701441) (xy 420.622876 -346.641477) (xy 420.567373 -346.576027) (xy 420.518244 -346.505668)
			(xy 420.475918 -346.431017) (xy 420.440769 -346.352731) (xy 420.413106 -346.271497) (xy 420.39317 -346.18803)
			(xy 420.381139 -346.103062) (xy 420.377117 -346.017342) (xy 416.01662 -346.017342) (xy 416.016191 -346.053899)
			(xy 416.008156 -346.139337) (xy 415.992155 -346.223647) (xy 415.968329 -346.306088) (xy 415.936888 -346.385936)
			(xy 415.898108 -346.462488) (xy 415.85233 -346.535073) (xy 415.799957 -346.603053) (xy 415.741448 -346.665829)
			(xy 415.677317 -346.72285) (xy 415.608129 -346.773616) (xy 415.53449 -346.81768) (xy 415.45705 -346.854654)
			(xy 415.376487 -346.884215) (xy 415.29351 -346.906101) (xy 415.208848 -346.920121) (xy 415.123246 -346.926152)
			(xy 415.037454 -346.92414) (xy 414.952228 -346.914104) (xy 414.868317 -346.896131) (xy 414.786457 -346.870379)
			(xy 414.707368 -346.837075) (xy 414.631746 -346.796511) (xy 414.560254 -346.749044) (xy 414.493521 -346.695091)
			(xy 414.432134 -346.635127) (xy 414.376631 -346.569677) (xy 414.327502 -346.499318) (xy 414.285176 -346.424667)
			(xy 414.250027 -346.346381) (xy 414.222364 -346.265147) (xy 414.202428 -346.18168) (xy 414.190397 -346.096712)
			(xy 414.186375 -346.010992) (xy 411.43936 -346.010992) (xy 411.43936 -351.152968) (xy 412.661354 -351.152968)
			(xy 412.661788 -351.125596) (xy 412.669612 -351.071415) (xy 412.685107 -351.018912) (xy 412.707957 -350.969165)
			(xy 412.737689 -350.9232) (xy 412.755334 -350.90227) (xy 412.764599 -350.890965) (xy 412.776768 -350.864398)
			(xy 412.780933 -350.835476) (xy 412.776755 -350.806555) (xy 412.764573 -350.779995) (xy 412.755334 -350.768666)
			(xy 412.737662 -350.747759) (xy 412.707938 -350.701787) (xy 412.685094 -350.652036) (xy 412.6696 -350.59953)
			(xy 412.661774 -350.545348) (xy 412.661777 -350.490604) (xy 412.66961 -350.436423) (xy 412.685111 -350.383918)
			(xy 412.707961 -350.334171) (xy 412.737691 -350.288203) (xy 412.755334 -350.26727) (xy 412.764599 -350.255965)
			(xy 412.776768 -350.229398) (xy 412.780933 -350.200476) (xy 412.776755 -350.171555) (xy 412.764573 -350.144995)
			(xy 412.755334 -350.133666) (xy 412.737662 -350.112759) (xy 412.707938 -350.066787) (xy 412.685094 -350.017036)
			(xy 412.6696 -349.96453) (xy 412.661774 -349.910348) (xy 412.661777 -349.855604) (xy 412.66961 -349.801423)
			(xy 412.685111 -349.748918) (xy 412.707961 -349.699171) (xy 412.737691 -349.653203) (xy 412.755334 -349.63227)
			(xy 412.764599 -349.620965) (xy 412.776768 -349.594398) (xy 412.780933 -349.565476) (xy 412.776755 -349.536555)
			(xy 412.764573 -349.509995) (xy 412.755334 -349.498666) (xy 412.737662 -349.477759) (xy 412.707938 -349.431787)
			(xy 412.685094 -349.382036) (xy 412.6696 -349.32953) (xy 412.661774 -349.275348) (xy 412.661777 -349.220604)
			(xy 412.66961 -349.166423) (xy 412.685111 -349.113918) (xy 412.707961 -349.064171) (xy 412.737691 -349.018203)
			(xy 412.755334 -348.99727) (xy 412.764599 -348.985965) (xy 412.776768 -348.959398) (xy 412.780933 -348.930476)
			(xy 412.776755 -348.901555) (xy 412.764573 -348.874995) (xy 412.755334 -348.863666) (xy 412.737662 -348.842759)
			(xy 412.707938 -348.796787) (xy 412.685094 -348.747036) (xy 412.6696 -348.69453) (xy 412.661774 -348.640348)
			(xy 412.661777 -348.585604) (xy 412.66961 -348.531423) (xy 412.685111 -348.478918) (xy 412.707961 -348.429171)
			(xy 412.737691 -348.383203) (xy 412.755334 -348.36227) (xy 412.764599 -348.350965) (xy 412.776768 -348.324398)
			(xy 412.780933 -348.295476) (xy 412.776755 -348.266555) (xy 412.764573 -348.239995) (xy 412.755334 -348.228666)
			(xy 412.737662 -348.207759) (xy 412.707938 -348.161787) (xy 412.685094 -348.112036) (xy 412.6696 -348.05953)
			(xy 412.661774 -348.005348) (xy 412.661777 -347.950604) (xy 412.66961 -347.896423) (xy 412.685111 -347.843918)
			(xy 412.707961 -347.794171) (xy 412.737691 -347.748203) (xy 412.755334 -347.72727) (xy 412.764599 -347.715965)
			(xy 412.776768 -347.689398) (xy 412.780933 -347.660476) (xy 412.776755 -347.631555) (xy 412.764573 -347.604995)
			(xy 412.755334 -347.593666) (xy 412.737718 -347.572715) (xy 412.708001 -347.526748) (xy 412.68516 -347.477006)
			(xy 412.669664 -347.424509) (xy 412.661831 -347.370336) (xy 412.661354 -347.342968) (xy 412.661848 -347.315718)
			(xy 412.669608 -347.261772) (xy 412.684965 -347.20948) (xy 412.707607 -347.159905) (xy 412.737073 -347.114057)
			(xy 412.772764 -347.072868) (xy 412.813952 -347.037177) (xy 412.8598 -347.00771) (xy 412.909374 -346.985067)
			(xy 412.961666 -346.969709) (xy 413.015612 -346.961948) (xy 413.042862 -346.96146) (xy 413.070232 -346.961934)
			(xy 413.124411 -346.969747) (xy 413.176915 -346.985234) (xy 413.226662 -347.008074) (xy 413.272629 -347.037799)
			(xy 413.29356 -347.05544) (xy 413.304888 -347.064676) (xy 413.331445 -347.076852) (xy 413.360362 -347.081025)
			(xy 413.389279 -347.076852) (xy 413.415836 -347.064676) (xy 413.427164 -347.05544) (xy 413.448104 -347.037811)
			(xy 413.494074 -347.008096) (xy 413.543819 -346.985257) (xy 413.596319 -346.969764) (xy 413.650493 -346.961935)
			(xy 413.677862 -346.96146) (xy 413.705901 -346.96198) (xy 413.761378 -346.970176) (xy 413.815059 -346.986395)
			(xy 413.865792 -347.010291) (xy 413.912485 -347.041349) (xy 413.93364 -347.059758) (xy 413.945082 -347.069403)
			(xy 413.972125 -347.082183) (xy 414.001712 -347.086569) (xy 414.031299 -347.082183) (xy 414.058342 -347.069403)
			(xy 414.069784 -347.059758) (xy 414.090918 -347.041318) (xy 414.1376 -347.010227) (xy 414.188336 -346.986316)
			(xy 414.242028 -346.970101) (xy 414.297518 -346.961931) (xy 414.325562 -346.96146) (xy 414.352812 -346.961991)
			(xy 414.406759 -346.969742) (xy 414.459054 -346.985091) (xy 414.508632 -347.007727) (xy 414.554484 -347.037188)
			(xy 414.595676 -347.072875) (xy 414.63137 -347.11406) (xy 414.66084 -347.159907) (xy 414.683484 -347.20948)
			(xy 414.698844 -347.261772) (xy 414.706604 -347.315718) (xy 414.70707 -347.342968) (xy 414.706592 -347.370338)
			(xy 414.698779 -347.424517) (xy 414.683293 -347.47702) (xy 414.660453 -347.526767) (xy 414.63073 -347.572734)
			(xy 414.61309 -347.593666) (xy 414.603885 -347.605017) (xy 414.591705 -347.631566) (xy 414.587527 -347.660476)
			(xy 414.591691 -347.689387) (xy 414.603858 -347.715943) (xy 414.61309 -347.72727) (xy 414.630699 -347.748228)
			(xy 414.660423 -347.794192) (xy 414.68327 -347.843934) (xy 414.698768 -347.896432) (xy 414.706599 -347.950607)
			(xy 414.706602 -348.005345) (xy 414.698778 -348.059521) (xy 414.683287 -348.11202) (xy 414.660447 -348.161765)
			(xy 414.630728 -348.207733) (xy 414.61309 -348.228666) (xy 414.603885 -348.240017) (xy 414.591705 -348.266566)
			(xy 414.587527 -348.295476) (xy 414.591691 -348.324387) (xy 414.603858 -348.350943) (xy 414.61309 -348.36227)
			(xy 414.630699 -348.383228) (xy 414.660423 -348.429192) (xy 414.68327 -348.478934) (xy 414.698768 -348.531432)
			(xy 414.706599 -348.585607) (xy 414.706602 -348.640345) (xy 414.698778 -348.694521) (xy 414.683287 -348.74702)
			(xy 414.660447 -348.796765) (xy 414.630728 -348.842733) (xy 414.61309 -348.863666) (xy 414.603885 -348.875017)
			(xy 414.591705 -348.901566) (xy 414.587527 -348.930476) (xy 414.591691 -348.959387) (xy 414.603858 -348.985943)
			(xy 414.61309 -348.99727) (xy 414.630699 -349.018228) (xy 414.660423 -349.064192) (xy 414.68327 -349.113934)
			(xy 414.698768 -349.166432) (xy 414.706599 -349.220607) (xy 414.706602 -349.275345) (xy 414.698778 -349.329521)
			(xy 414.683287 -349.38202) (xy 414.660447 -349.431765) (xy 414.630728 -349.477733) (xy 414.61309 -349.498666)
			(xy 414.603885 -349.510017) (xy 414.591705 -349.536566) (xy 414.587527 -349.565476) (xy 414.591691 -349.594387)
			(xy 414.603858 -349.620943) (xy 414.61309 -349.63227) (xy 414.630699 -349.653228) (xy 414.660423 -349.699192)
			(xy 414.68327 -349.748934) (xy 414.698768 -349.801432) (xy 414.706599 -349.855607) (xy 414.706602 -349.910345)
			(xy 414.698778 -349.964521) (xy 414.683287 -350.01702) (xy 414.660447 -350.066765) (xy 414.630728 -350.112733)
			(xy 414.61309 -350.133666) (xy 414.603885 -350.145017) (xy 414.591705 -350.171566) (xy 414.587527 -350.200476)
			(xy 414.591691 -350.229387) (xy 414.603858 -350.255943) (xy 414.61309 -350.26727) (xy 414.630699 -350.288228)
			(xy 414.660423 -350.334192) (xy 414.68327 -350.383934) (xy 414.698768 -350.436432) (xy 414.706599 -350.490607)
			(xy 414.706602 -350.545345) (xy 414.698778 -350.599521) (xy 414.683287 -350.65202) (xy 414.660447 -350.701765)
			(xy 414.630728 -350.747733) (xy 414.61309 -350.768666) (xy 414.603885 -350.780017) (xy 414.591705 -350.806566)
			(xy 414.587527 -350.835476) (xy 414.591691 -350.864387) (xy 414.603858 -350.890943) (xy 414.61309 -350.90227)
			(xy 414.630727 -350.923204) (xy 414.660439 -350.969176) (xy 414.683276 -351.018923) (xy 414.698767 -351.071423)
			(xy 414.706596 -351.125599) (xy 414.70707 -351.152968) (xy 417.631626 -351.152968) (xy 417.632067 -351.125597)
			(xy 417.63989 -351.071416) (xy 417.655384 -351.018913) (xy 417.678232 -350.969166) (xy 417.707962 -350.923201)
			(xy 417.725606 -350.90227) (xy 417.734873 -350.890966) (xy 417.747046 -350.864399) (xy 417.751212 -350.835476)
			(xy 417.747032 -350.806554) (xy 417.734847 -350.779994) (xy 417.725606 -350.768666) (xy 417.707935 -350.747758)
			(xy 417.678213 -350.701786) (xy 417.655371 -350.652035) (xy 417.639878 -350.599529) (xy 417.632053 -350.545348)
			(xy 417.632056 -350.490604) (xy 417.639888 -350.436423) (xy 417.655388 -350.38392) (xy 417.678236 -350.334172)
			(xy 417.707964 -350.288203) (xy 417.725606 -350.26727) (xy 417.734873 -350.255966) (xy 417.747046 -350.229399)
			(xy 417.751212 -350.200476) (xy 417.747032 -350.171554) (xy 417.734847 -350.144994) (xy 417.725606 -350.133666)
			(xy 417.707935 -350.112758) (xy 417.678213 -350.066786) (xy 417.655371 -350.017035) (xy 417.639878 -349.964529)
			(xy 417.632053 -349.910348) (xy 417.632056 -349.855604) (xy 417.639888 -349.801423) (xy 417.655388 -349.74892)
			(xy 417.678236 -349.699172) (xy 417.707964 -349.653203) (xy 417.725606 -349.63227) (xy 417.734873 -349.620966)
			(xy 417.747046 -349.594399) (xy 417.751212 -349.565476) (xy 417.747032 -349.536554) (xy 417.734847 -349.509994)
			(xy 417.725606 -349.498666) (xy 417.707935 -349.477758) (xy 417.678213 -349.431786) (xy 417.655371 -349.382035)
			(xy 417.639878 -349.329529) (xy 417.632053 -349.275348) (xy 417.632056 -349.220604) (xy 417.639888 -349.166423)
			(xy 417.655388 -349.11392) (xy 417.678236 -349.064172) (xy 417.707964 -349.018203) (xy 417.725606 -348.99727)
			(xy 417.734873 -348.985966) (xy 417.747046 -348.959399) (xy 417.751212 -348.930476) (xy 417.747032 -348.901554)
			(xy 417.734847 -348.874994) (xy 417.725606 -348.863666) (xy 417.707935 -348.842758) (xy 417.678213 -348.796786)
			(xy 417.655371 -348.747035) (xy 417.639878 -348.694529) (xy 417.632053 -348.640348) (xy 417.632056 -348.585604)
			(xy 417.639888 -348.531423) (xy 417.655388 -348.47892) (xy 417.678236 -348.429172) (xy 417.707964 -348.383203)
			(xy 417.725606 -348.36227) (xy 417.734873 -348.350966) (xy 417.747046 -348.324399) (xy 417.751212 -348.295476)
			(xy 417.747032 -348.266554) (xy 417.734847 -348.239994) (xy 417.725606 -348.228666) (xy 417.707935 -348.207758)
			(xy 417.678213 -348.161786) (xy 417.655371 -348.112035) (xy 417.639878 -348.059529) (xy 417.632053 -348.005348)
			(xy 417.632056 -347.950604) (xy 417.639888 -347.896423) (xy 417.655388 -347.84392) (xy 417.678236 -347.794172)
			(xy 417.707964 -347.748203) (xy 417.725606 -347.72727) (xy 417.734873 -347.715966) (xy 417.747046 -347.689399)
			(xy 417.751212 -347.660476) (xy 417.747032 -347.631554) (xy 417.734847 -347.604994) (xy 417.725606 -347.593666)
			(xy 417.707985 -347.572719) (xy 417.678271 -347.52675) (xy 417.655431 -347.477007) (xy 417.639936 -347.424509)
			(xy 417.632103 -347.370336) (xy 417.631626 -347.342968) (xy 417.632025 -347.315713) (xy 417.639787 -347.261758)
			(xy 417.655149 -347.209457) (xy 417.677798 -347.159874) (xy 417.707273 -347.114019) (xy 417.742973 -347.072826)
			(xy 417.784172 -347.037133) (xy 417.830032 -347.007666) (xy 417.879619 -346.985026) (xy 417.931922 -346.969673)
			(xy 417.985879 -346.96192) (xy 418.013134 -346.96146) (xy 418.041175 -346.961937) (xy 418.096653 -346.970143)
			(xy 418.150335 -346.986373) (xy 418.201067 -347.010278) (xy 418.247758 -347.041345) (xy 418.268912 -347.059758)
			(xy 418.280354 -347.069403) (xy 418.307397 -347.082183) (xy 418.336984 -347.086569) (xy 418.366571 -347.082183)
			(xy 418.393614 -347.069403) (xy 418.405056 -347.059758) (xy 418.426201 -347.041331) (xy 418.47288 -347.010239)
			(xy 418.523613 -346.986325) (xy 418.577303 -346.970106) (xy 418.63279 -346.961933) (xy 418.660834 -346.96146)
			(xy 418.688206 -346.961892) (xy 418.742387 -346.969715) (xy 418.794891 -346.985212) (xy 418.844637 -347.008062)
			(xy 418.890602 -347.037795) (xy 418.911532 -347.05544) (xy 418.92286 -347.064676) (xy 418.949417 -347.076852)
			(xy 418.978334 -347.081025) (xy 419.007251 -347.076852) (xy 419.033808 -347.064676) (xy 419.045136 -347.05544)
			(xy 419.066087 -347.037824) (xy 419.112054 -347.008107) (xy 419.161796 -346.985266) (xy 419.214293 -346.96977)
			(xy 419.268466 -346.961937) (xy 419.295834 -346.96146) (xy 419.323085 -346.961946) (xy 419.377031 -346.969706)
			(xy 419.429323 -346.985064) (xy 419.478899 -347.007707) (xy 419.524747 -347.037174) (xy 419.565936 -347.072865)
			(xy 419.601627 -347.114054) (xy 419.631094 -347.159903) (xy 419.653736 -347.209478) (xy 419.669094 -347.261771)
			(xy 419.676854 -347.315717) (xy 419.677342 -347.342968) (xy 419.676871 -347.370338) (xy 419.669057 -347.424518)
			(xy 419.65357 -347.477021) (xy 419.630728 -347.526768) (xy 419.601004 -347.572735) (xy 419.583362 -347.593666)
			(xy 419.574159 -347.605018) (xy 419.561982 -347.631567) (xy 419.557806 -347.660476) (xy 419.561969 -347.689386)
			(xy 419.574133 -347.715942) (xy 419.583362 -347.72727) (xy 419.600972 -347.748228) (xy 419.630699 -347.794191)
			(xy 419.653547 -347.843933) (xy 419.669046 -347.896431) (xy 419.676878 -347.950607) (xy 419.676881 -348.005345)
			(xy 419.669056 -348.059521) (xy 419.653564 -348.112022) (xy 419.630722 -348.161767) (xy 419.601001 -348.207734)
			(xy 419.583362 -348.228666) (xy 419.574159 -348.240018) (xy 419.561982 -348.266567) (xy 419.557806 -348.295476)
			(xy 419.561969 -348.324386) (xy 419.574133 -348.350942) (xy 419.583362 -348.36227) (xy 419.600972 -348.383228)
			(xy 419.630699 -348.429191) (xy 419.653547 -348.478933) (xy 419.669046 -348.531431) (xy 419.676878 -348.585607)
			(xy 419.676881 -348.640345) (xy 419.669056 -348.694521) (xy 419.653564 -348.747022) (xy 419.630722 -348.796767)
			(xy 419.601001 -348.842734) (xy 419.583362 -348.863666) (xy 419.574159 -348.875018) (xy 419.561982 -348.901567)
			(xy 419.557806 -348.930476) (xy 419.561969 -348.959386) (xy 419.574133 -348.985942) (xy 419.583362 -348.99727)
			(xy 419.600972 -349.018228) (xy 419.630699 -349.064191) (xy 419.653547 -349.113933) (xy 419.669046 -349.166431)
			(xy 419.676878 -349.220607) (xy 419.676881 -349.275345) (xy 419.669056 -349.329521) (xy 419.653564 -349.382022)
			(xy 419.630722 -349.431767) (xy 419.601001 -349.477734) (xy 419.583362 -349.498666) (xy 419.574159 -349.510018)
			(xy 419.561982 -349.536567) (xy 419.557806 -349.565476) (xy 419.561969 -349.594386) (xy 419.574133 -349.620942)
			(xy 419.583362 -349.63227) (xy 419.600972 -349.653228) (xy 419.630699 -349.699191) (xy 419.653547 -349.748933)
			(xy 419.669046 -349.801431) (xy 419.676878 -349.855607) (xy 419.676881 -349.910345) (xy 419.669056 -349.964521)
			(xy 419.653564 -350.017022) (xy 419.630722 -350.066767) (xy 419.601001 -350.112734) (xy 419.583362 -350.133666)
			(xy 419.574159 -350.145018) (xy 419.561982 -350.171567) (xy 419.557806 -350.200476) (xy 419.561969 -350.229386)
			(xy 419.574133 -350.255942) (xy 419.583362 -350.26727) (xy 419.600972 -350.288228) (xy 419.630699 -350.334191)
			(xy 419.653547 -350.383933) (xy 419.669046 -350.436431) (xy 419.676878 -350.490607) (xy 419.676881 -350.545345)
			(xy 419.669056 -350.599521) (xy 419.653564 -350.652022) (xy 419.630722 -350.701767) (xy 419.601001 -350.747734)
			(xy 419.583362 -350.768666) (xy 419.574159 -350.780018) (xy 419.561982 -350.806567) (xy 419.557806 -350.835476)
			(xy 419.561969 -350.864386) (xy 419.574133 -350.890942) (xy 419.583362 -350.90227) (xy 419.600995 -350.923207)
			(xy 419.630709 -350.969178) (xy 419.653547 -351.018924) (xy 419.669039 -351.071424) (xy 419.676868 -351.125599)
			(xy 419.677342 -351.152968) (xy 422.338754 -351.152968) (xy 422.339188 -351.125596) (xy 422.347012 -351.071415)
			(xy 422.362507 -351.018912) (xy 422.385357 -350.969165) (xy 422.415089 -350.9232) (xy 422.432734 -350.90227)
			(xy 422.441999 -350.890965) (xy 422.454168 -350.864398) (xy 422.458333 -350.835476) (xy 422.454155 -350.806555)
			(xy 422.441973 -350.779995) (xy 422.432734 -350.768666) (xy 422.415062 -350.747759) (xy 422.385338 -350.701787)
			(xy 422.362494 -350.652036) (xy 422.347 -350.59953) (xy 422.339174 -350.545348) (xy 422.339177 -350.490604)
			(xy 422.34701 -350.436423) (xy 422.362511 -350.383918) (xy 422.385361 -350.334171) (xy 422.415091 -350.288203)
			(xy 422.432734 -350.26727) (xy 422.441999 -350.255965) (xy 422.454168 -350.229398) (xy 422.458333 -350.200476)
			(xy 422.454155 -350.171555) (xy 422.441973 -350.144995) (xy 422.432734 -350.133666) (xy 422.415062 -350.112759)
			(xy 422.385338 -350.066787) (xy 422.362494 -350.017036) (xy 422.347 -349.96453) (xy 422.339174 -349.910348)
			(xy 422.339177 -349.855604) (xy 422.34701 -349.801423) (xy 422.362511 -349.748918) (xy 422.385361 -349.699171)
			(xy 422.415091 -349.653203) (xy 422.432734 -349.63227) (xy 422.441999 -349.620965) (xy 422.454168 -349.594398)
			(xy 422.458333 -349.565476) (xy 422.454155 -349.536555) (xy 422.441973 -349.509995) (xy 422.432734 -349.498666)
			(xy 422.415062 -349.477759) (xy 422.385338 -349.431787) (xy 422.362494 -349.382036) (xy 422.347 -349.32953)
			(xy 422.339174 -349.275348) (xy 422.339177 -349.220604) (xy 422.34701 -349.166423) (xy 422.362511 -349.113918)
			(xy 422.385361 -349.064171) (xy 422.415091 -349.018203) (xy 422.432734 -348.99727) (xy 422.441999 -348.985965)
			(xy 422.454168 -348.959398) (xy 422.458333 -348.930476) (xy 422.454155 -348.901555) (xy 422.441973 -348.874995)
			(xy 422.432734 -348.863666) (xy 422.415062 -348.842759) (xy 422.385338 -348.796787) (xy 422.362494 -348.747036)
			(xy 422.347 -348.69453) (xy 422.339174 -348.640348) (xy 422.339177 -348.585604) (xy 422.34701 -348.531423)
			(xy 422.362511 -348.478918) (xy 422.385361 -348.429171) (xy 422.415091 -348.383203) (xy 422.432734 -348.36227)
			(xy 422.441999 -348.350965) (xy 422.454168 -348.324398) (xy 422.458333 -348.295476) (xy 422.454155 -348.266555)
			(xy 422.441973 -348.239995) (xy 422.432734 -348.228666) (xy 422.415062 -348.207759) (xy 422.385338 -348.161787)
			(xy 422.362494 -348.112036) (xy 422.347 -348.05953) (xy 422.339174 -348.005348) (xy 422.339177 -347.950604)
			(xy 422.34701 -347.896423) (xy 422.362511 -347.843918) (xy 422.385361 -347.794171) (xy 422.415091 -347.748203)
			(xy 422.432734 -347.72727) (xy 422.441999 -347.715965) (xy 422.454168 -347.689398) (xy 422.458333 -347.660476)
			(xy 422.454155 -347.631555) (xy 422.441973 -347.604995) (xy 422.432734 -347.593666) (xy 422.415118 -347.572715)
			(xy 422.385401 -347.526748) (xy 422.36256 -347.477006) (xy 422.347064 -347.424509) (xy 422.339231 -347.370336)
			(xy 422.338754 -347.342968) (xy 422.339248 -347.315718) (xy 422.347008 -347.261772) (xy 422.362365 -347.20948)
			(xy 422.385007 -347.159905) (xy 422.414473 -347.114057) (xy 422.450164 -347.072868) (xy 422.491352 -347.037177)
			(xy 422.5372 -347.00771) (xy 422.586774 -346.985067) (xy 422.639066 -346.969709) (xy 422.693012 -346.961948)
			(xy 422.720262 -346.96146) (xy 422.747632 -346.961934) (xy 422.801811 -346.969747) (xy 422.854315 -346.985234)
			(xy 422.904062 -347.008074) (xy 422.950029 -347.037799) (xy 422.97096 -347.05544) (xy 422.982288 -347.064676)
			(xy 423.008845 -347.076852) (xy 423.037762 -347.081025) (xy 423.066679 -347.076852) (xy 423.093236 -347.064676)
			(xy 423.104564 -347.05544) (xy 423.125504 -347.037811) (xy 423.171474 -347.008096) (xy 423.221219 -346.985257)
			(xy 423.273719 -346.969764) (xy 423.327893 -346.961935) (xy 423.355262 -346.96146) (xy 423.383301 -346.96198)
			(xy 423.438778 -346.970176) (xy 423.492459 -346.986395) (xy 423.543192 -347.010291) (xy 423.589885 -347.041349)
			(xy 423.61104 -347.059758) (xy 423.622482 -347.069403) (xy 423.649525 -347.082183) (xy 423.679112 -347.086569)
			(xy 423.708699 -347.082183) (xy 423.735742 -347.069403) (xy 423.747184 -347.059758) (xy 423.768318 -347.041318)
			(xy 423.815 -347.010227) (xy 423.865736 -346.986316) (xy 423.919428 -346.970101) (xy 423.974918 -346.961931)
			(xy 424.002962 -346.96146) (xy 424.030212 -346.961991) (xy 424.084159 -346.969742) (xy 424.136454 -346.985091)
			(xy 424.186032 -347.007727) (xy 424.231884 -347.037188) (xy 424.273076 -347.072875) (xy 424.30877 -347.11406)
			(xy 424.33824 -347.159907) (xy 424.360884 -347.20948) (xy 424.376244 -347.261772) (xy 424.384004 -347.315718)
			(xy 424.38447 -347.342968) (xy 424.383992 -347.370338) (xy 424.376179 -347.424517) (xy 424.360693 -347.47702)
			(xy 424.337853 -347.526767) (xy 424.30813 -347.572734) (xy 424.29049 -347.593666) (xy 424.281285 -347.605017)
			(xy 424.269105 -347.631566) (xy 424.264927 -347.660476) (xy 424.269091 -347.689387) (xy 424.281258 -347.715943)
			(xy 424.29049 -347.72727) (xy 424.308099 -347.748228) (xy 424.337823 -347.794192) (xy 424.36067 -347.843934)
			(xy 424.376168 -347.896432) (xy 424.383999 -347.950607) (xy 424.384002 -348.005345) (xy 424.376178 -348.059521)
			(xy 424.360687 -348.11202) (xy 424.337847 -348.161765) (xy 424.308128 -348.207733) (xy 424.29049 -348.228666)
			(xy 424.281285 -348.240017) (xy 424.269105 -348.266566) (xy 424.264927 -348.295476) (xy 424.269091 -348.324387)
			(xy 424.281258 -348.350943) (xy 424.29049 -348.36227) (xy 424.308099 -348.383228) (xy 424.337823 -348.429192)
			(xy 424.36067 -348.478934) (xy 424.376168 -348.531432) (xy 424.383999 -348.585607) (xy 424.384002 -348.640345)
			(xy 424.376178 -348.694521) (xy 424.360687 -348.74702) (xy 424.337847 -348.796765) (xy 424.308128 -348.842733)
			(xy 424.29049 -348.863666) (xy 424.281285 -348.875017) (xy 424.269105 -348.901566) (xy 424.264927 -348.930476)
			(xy 424.269091 -348.959387) (xy 424.281258 -348.985943) (xy 424.29049 -348.99727) (xy 424.308099 -349.018228)
			(xy 424.337823 -349.064192) (xy 424.36067 -349.113934) (xy 424.376168 -349.166432) (xy 424.383999 -349.220607)
			(xy 424.384002 -349.275345) (xy 424.376178 -349.329521) (xy 424.360687 -349.38202) (xy 424.337847 -349.431765)
			(xy 424.308128 -349.477733) (xy 424.29049 -349.498666) (xy 424.281285 -349.510017) (xy 424.269105 -349.536566)
			(xy 424.264927 -349.565476) (xy 424.269091 -349.594387) (xy 424.281258 -349.620943) (xy 424.29049 -349.63227)
			(xy 424.308099 -349.653228) (xy 424.337823 -349.699192) (xy 424.36067 -349.748934) (xy 424.376168 -349.801432)
			(xy 424.383999 -349.855607) (xy 424.384002 -349.910345) (xy 424.376178 -349.964521) (xy 424.360687 -350.01702)
			(xy 424.337847 -350.066765) (xy 424.308128 -350.112733) (xy 424.29049 -350.133666) (xy 424.281285 -350.145017)
			(xy 424.269105 -350.171566) (xy 424.264927 -350.200476) (xy 424.269091 -350.229387) (xy 424.281258 -350.255943)
			(xy 424.29049 -350.26727) (xy 424.308099 -350.288228) (xy 424.337823 -350.334192) (xy 424.36067 -350.383934)
			(xy 424.376168 -350.436432) (xy 424.383999 -350.490607) (xy 424.384002 -350.545345) (xy 424.376178 -350.599521)
			(xy 424.360687 -350.65202) (xy 424.337847 -350.701765) (xy 424.308128 -350.747733) (xy 424.29049 -350.768666)
			(xy 424.281285 -350.780017) (xy 424.269105 -350.806566) (xy 424.264927 -350.835476) (xy 424.269091 -350.864387)
			(xy 424.281258 -350.890943) (xy 424.29049 -350.90227) (xy 424.308127 -350.923204) (xy 424.337839 -350.969176)
			(xy 424.360676 -351.018923) (xy 424.376167 -351.071423) (xy 424.383996 -351.125599) (xy 424.38447 -351.152968)
			(xy 427.95444 -351.152968) (xy 427.954878 -351.125597) (xy 427.962701 -351.071416) (xy 427.978196 -351.018912)
			(xy 428.001044 -350.969166) (xy 428.030775 -350.9232) (xy 428.04842 -350.90227) (xy 428.057686 -350.890965)
			(xy 428.069857 -350.864399) (xy 428.074023 -350.835476) (xy 428.069843 -350.806555) (xy 428.05766 -350.779994)
			(xy 428.04842 -350.768666) (xy 428.030748 -350.747758) (xy 428.001025 -350.701786) (xy 427.978182 -350.652036)
			(xy 427.962689 -350.59953) (xy 427.954863 -350.545348) (xy 427.954867 -350.490604) (xy 427.962699 -350.436423)
			(xy 427.978199 -350.383919) (xy 428.001049 -350.334172) (xy 428.030777 -350.288203) (xy 428.04842 -350.26727)
			(xy 428.057686 -350.255965) (xy 428.069857 -350.229399) (xy 428.074023 -350.200476) (xy 428.069843 -350.171555)
			(xy 428.05766 -350.144994) (xy 428.04842 -350.133666) (xy 428.030748 -350.112758) (xy 428.001025 -350.066786)
			(xy 427.978182 -350.017036) (xy 427.962689 -349.96453) (xy 427.954863 -349.910348) (xy 427.954867 -349.855604)
			(xy 427.962699 -349.801423) (xy 427.978199 -349.748919) (xy 428.001049 -349.699172) (xy 428.030777 -349.653203)
			(xy 428.04842 -349.63227) (xy 428.057686 -349.620965) (xy 428.069857 -349.594399) (xy 428.074023 -349.565476)
			(xy 428.069843 -349.536555) (xy 428.05766 -349.509994) (xy 428.04842 -349.498666) (xy 428.030748 -349.477758)
			(xy 428.001025 -349.431786) (xy 427.978182 -349.382036) (xy 427.962689 -349.32953) (xy 427.954863 -349.275348)
			(xy 427.954867 -349.220604) (xy 427.962699 -349.166423) (xy 427.978199 -349.113919) (xy 428.001049 -349.064172)
			(xy 428.030777 -349.018203) (xy 428.04842 -348.99727) (xy 428.057686 -348.985965) (xy 428.069857 -348.959399)
			(xy 428.074023 -348.930476) (xy 428.069843 -348.901555) (xy 428.05766 -348.874994) (xy 428.04842 -348.863666)
			(xy 428.030748 -348.842758) (xy 428.001025 -348.796786) (xy 427.978182 -348.747036) (xy 427.962689 -348.69453)
			(xy 427.954863 -348.640348) (xy 427.954867 -348.585604) (xy 427.962699 -348.531423) (xy 427.978199 -348.478919)
			(xy 428.001049 -348.429172) (xy 428.030777 -348.383203) (xy 428.04842 -348.36227) (xy 428.057686 -348.350965)
			(xy 428.069857 -348.324399) (xy 428.074023 -348.295476) (xy 428.069843 -348.266555) (xy 428.05766 -348.239994)
			(xy 428.04842 -348.228666) (xy 428.030748 -348.207758) (xy 428.001025 -348.161786) (xy 427.978182 -348.112036)
			(xy 427.962689 -348.05953) (xy 427.954863 -348.005348) (xy 427.954867 -347.950604) (xy 427.962699 -347.896423)
			(xy 427.978199 -347.843919) (xy 428.001049 -347.794172) (xy 428.030777 -347.748203) (xy 428.04842 -347.72727)
			(xy 428.057686 -347.715965) (xy 428.069857 -347.689399) (xy 428.074023 -347.660476) (xy 428.069843 -347.631555)
			(xy 428.05766 -347.604994) (xy 428.04842 -347.593666) (xy 428.030801 -347.572717) (xy 428.001086 -347.526749)
			(xy 427.978246 -347.477006) (xy 427.96275 -347.424509) (xy 427.954917 -347.370336) (xy 427.95444 -347.342968)
			(xy 427.954825 -347.315712) (xy 427.962588 -347.261756) (xy 427.97795 -347.209454) (xy 428.0006 -347.15987)
			(xy 428.030076 -347.114015) (xy 428.065778 -347.072821) (xy 428.106979 -347.037128) (xy 428.15284 -347.007662)
			(xy 428.202429 -346.985022) (xy 428.254734 -346.969671) (xy 428.308692 -346.96192) (xy 428.335948 -346.96146)
			(xy 428.363987 -346.961989) (xy 428.419463 -346.970182) (xy 428.473145 -346.9864) (xy 428.523877 -347.010293)
			(xy 428.570571 -347.041349) (xy 428.591726 -347.059758) (xy 428.603168 -347.069403) (xy 428.630211 -347.082183)
			(xy 428.659798 -347.086569) (xy 428.689385 -347.082183) (xy 428.716428 -347.069403) (xy 428.72787 -347.059758)
			(xy 428.74901 -347.041324) (xy 428.79569 -347.010233) (xy 428.846424 -346.98632) (xy 428.900115 -346.970103)
			(xy 428.955604 -346.961932) (xy 428.983648 -346.96146) (xy 429.011018 -346.961942) (xy 429.065197 -346.969754)
			(xy 429.1177 -346.985238) (xy 429.167448 -347.008077) (xy 429.213414 -347.037799) (xy 429.234346 -347.05544)
			(xy 429.245674 -347.064676) (xy 429.272231 -347.076852) (xy 429.301148 -347.081025) (xy 429.330065 -347.076852)
			(xy 429.356622 -347.064676) (xy 429.36795 -347.05544) (xy 429.388895 -347.037817) (xy 429.434864 -347.008101)
			(xy 429.484608 -346.985262) (xy 429.537106 -346.969767) (xy 429.59128 -346.961936) (xy 429.618648 -346.96146)
			(xy 429.645899 -346.961933) (xy 429.699845 -346.969695) (xy 429.752138 -346.985055) (xy 429.801714 -347.007699)
			(xy 429.847562 -347.037168) (xy 429.888751 -347.07286) (xy 429.924442 -347.11405) (xy 429.953908 -347.1599)
			(xy 429.976551 -347.209477) (xy 429.991908 -347.26177) (xy 429.999668 -347.315717) (xy 430.000156 -347.342968)
			(xy 429.999682 -347.370338) (xy 429.991868 -347.424517) (xy 429.976381 -347.477021) (xy 429.953541 -347.526768)
			(xy 429.923817 -347.572734) (xy 429.906176 -347.593666) (xy 429.896972 -347.605017) (xy 429.884794 -347.631567)
			(xy 429.880616 -347.660476) (xy 429.88478 -347.689387) (xy 429.896946 -347.715942) (xy 429.906176 -347.72727)
			(xy 429.923785 -347.748228) (xy 429.953511 -347.794192) (xy 429.976358 -347.843934) (xy 429.991857 -347.896432)
			(xy 429.999688 -347.950607) (xy 429.999692 -348.005345) (xy 429.991867 -348.059521) (xy 429.976375 -348.112021)
			(xy 429.953534 -348.161766) (xy 429.923814 -348.207733) (xy 429.906176 -348.228666) (xy 429.896972 -348.240017)
			(xy 429.884794 -348.266567) (xy 429.880616 -348.295476) (xy 429.88478 -348.324387) (xy 429.896946 -348.350942)
			(xy 429.906176 -348.36227) (xy 429.923785 -348.383228) (xy 429.953511 -348.429192) (xy 429.976358 -348.478934)
			(xy 429.991857 -348.531432) (xy 429.999688 -348.585607) (xy 429.999692 -348.640345) (xy 429.991867 -348.694521)
			(xy 429.976375 -348.747021) (xy 429.953534 -348.796766) (xy 429.923814 -348.842733) (xy 429.906176 -348.863666)
			(xy 429.896972 -348.875017) (xy 429.884794 -348.901567) (xy 429.880616 -348.930476) (xy 429.88478 -348.959387)
			(xy 429.896946 -348.985942) (xy 429.906176 -348.99727) (xy 429.923785 -349.018228) (xy 429.953511 -349.064192)
			(xy 429.976358 -349.113934) (xy 429.991857 -349.166432) (xy 429.999688 -349.220607) (xy 429.999692 -349.275345)
			(xy 429.991867 -349.329521) (xy 429.976375 -349.382021) (xy 429.953534 -349.431766) (xy 429.923814 -349.477733)
			(xy 429.906176 -349.498666) (xy 429.896972 -349.510017) (xy 429.884794 -349.536567) (xy 429.880616 -349.565476)
			(xy 429.88478 -349.594387) (xy 429.896946 -349.620942) (xy 429.906176 -349.63227) (xy 429.923785 -349.653228)
			(xy 429.953511 -349.699192) (xy 429.976358 -349.748934) (xy 429.991857 -349.801432) (xy 429.999688 -349.855607)
			(xy 429.999692 -349.910345) (xy 429.991867 -349.964521) (xy 429.976375 -350.017021) (xy 429.953534 -350.066766)
			(xy 429.923814 -350.112733) (xy 429.906176 -350.133666) (xy 429.896972 -350.145017) (xy 429.884794 -350.171567)
			(xy 429.880616 -350.200476) (xy 429.88478 -350.229387) (xy 429.896946 -350.255942) (xy 429.906176 -350.26727)
			(xy 429.923785 -350.288228) (xy 429.953511 -350.334192) (xy 429.976358 -350.383934) (xy 429.991857 -350.436432)
			(xy 429.999688 -350.490607) (xy 429.999692 -350.545345) (xy 429.991867 -350.599521) (xy 429.976375 -350.652021)
			(xy 429.953534 -350.701766) (xy 429.923814 -350.747733) (xy 429.906176 -350.768666) (xy 429.896972 -350.780017)
			(xy 429.884794 -350.806567) (xy 429.880616 -350.835476) (xy 429.88478 -350.864387) (xy 429.896946 -350.890942)
			(xy 429.906176 -350.90227) (xy 429.923811 -350.923206) (xy 429.953524 -350.969177) (xy 429.976361 -351.018924)
			(xy 429.991853 -351.071424) (xy 429.999682 -351.125599) (xy 430.000156 -351.152968) (xy 429.999592 -351.180216)
			(xy 429.991841 -351.234159) (xy 429.976493 -351.286449) (xy 429.953859 -351.336023) (xy 429.9244 -351.381871)
			(xy 429.888717 -351.42306) (xy 429.847535 -351.458752) (xy 429.801693 -351.48822) (xy 429.752124 -351.510865)
			(xy 429.699837 -351.526224) (xy 429.645896 -351.533986) (xy 429.618648 -351.534476) (xy 429.591279 -351.533988)
			(xy 429.5371 -351.526176) (xy 429.484597 -351.510693) (xy 429.43485 -351.487856) (xy 429.388882 -351.458135)
			(xy 429.36795 -351.440496) (xy 429.356622 -351.43126) (xy 429.330065 -351.419084) (xy 429.301148 -351.414911)
			(xy 429.272231 -351.419084) (xy 429.245674 -351.43126) (xy 429.234346 -351.440496) (xy 429.213407 -351.458126)
			(xy 429.167436 -351.48784) (xy 429.11769 -351.510677) (xy 429.065191 -351.52617) (xy 429.011017 -351.534001)
			(xy 428.983648 -351.534476) (xy 428.955608 -351.533966) (xy 428.900131 -351.525771) (xy 428.846448 -351.509549)
			(xy 428.795716 -351.485651) (xy 428.749024 -351.45459) (xy 428.72787 -351.436178) (xy 428.716428 -351.426533)
			(xy 428.689385 -351.413753) (xy 428.659798 -351.409367) (xy 428.630211 -351.413753) (xy 428.603168 -351.426533)
			(xy 428.591726 -351.436178) (xy 428.570593 -351.45462) (xy 428.52391 -351.485709) (xy 428.473174 -351.509619)
			(xy 428.419482 -351.525835) (xy 428.363992 -351.534005) (xy 428.335948 -351.534476) (xy 428.308695 -351.534)
			(xy 428.254743 -351.526249) (xy 428.202443 -351.510897) (xy 428.152861 -351.488258) (xy 428.107006 -351.458792)
			(xy 428.065812 -351.423099) (xy 428.030118 -351.381907) (xy 428.00065 -351.336053) (xy 427.978008 -351.286472)
			(xy 427.962655 -351.234173) (xy 427.954901 -351.180221) (xy 427.95444 -351.152968) (xy 424.38447 -351.152968)
			(xy 424.384015 -351.180222) (xy 424.376261 -351.234175) (xy 424.360907 -351.286475) (xy 424.338266 -351.336058)
			(xy 424.308798 -351.381913) (xy 424.273103 -351.423107) (xy 424.231908 -351.458801) (xy 424.186053 -351.488269)
			(xy 424.13647 -351.510909) (xy 424.084169 -351.526262) (xy 424.030216 -351.534015) (xy 424.002962 -351.534476)
			(xy 423.97492 -351.534017) (xy 423.91944 -351.52581) (xy 423.865757 -351.509576) (xy 423.815026 -351.485667)
			(xy 423.768336 -351.454594) (xy 423.747184 -351.436178) (xy 423.735742 -351.426533) (xy 423.708699 -351.413753)
			(xy 423.679112 -351.409367) (xy 423.649525 -351.413753) (xy 423.622482 -351.426533) (xy 423.61104 -351.436178)
			(xy 423.589902 -351.454613) (xy 423.54322 -351.485703) (xy 423.492486 -351.509615) (xy 423.438794 -351.525832)
			(xy 423.383306 -351.534004) (xy 423.355262 -351.534476) (xy 423.327893 -351.533979) (xy 423.273715 -351.52617)
			(xy 423.221212 -351.510688) (xy 423.171464 -351.487853) (xy 423.125496 -351.458135) (xy 423.104564 -351.440496)
			(xy 423.093236 -351.43126) (xy 423.066679 -351.419084) (xy 423.037762 -351.414911) (xy 423.008845 -351.419084)
			(xy 422.982288 -351.43126) (xy 422.97096 -351.440496) (xy 422.950016 -351.45812) (xy 422.904046 -351.487834)
			(xy 422.854302 -351.510673) (xy 422.801804 -351.526168) (xy 422.74763 -351.534) (xy 422.720262 -351.534476)
			(xy 422.693008 -351.534057) (xy 422.639057 -351.526295) (xy 422.586759 -351.510933) (xy 422.537179 -351.488285)
			(xy 422.491327 -351.458812) (xy 422.450137 -351.423114) (xy 422.414446 -351.381917) (xy 422.384981 -351.336059)
			(xy 422.362342 -351.286476) (xy 422.34699 -351.234175) (xy 422.339238 -351.180222) (xy 422.338754 -351.152968)
			(xy 419.677342 -351.152968) (xy 419.676792 -351.180217) (xy 419.669041 -351.234161) (xy 419.653691 -351.286452)
			(xy 419.631057 -351.336027) (xy 419.601597 -351.381876) (xy 419.565912 -351.423065) (xy 419.524728 -351.458757)
			(xy 419.478885 -351.488225) (xy 419.429314 -351.510868) (xy 419.377025 -351.526227) (xy 419.323083 -351.533987)
			(xy 419.295834 -351.534476) (xy 419.268464 -351.533996) (xy 419.214285 -351.526182) (xy 419.161782 -351.510697)
			(xy 419.112035 -351.487858) (xy 419.066068 -351.458136) (xy 419.045136 -351.440496) (xy 419.033808 -351.43126)
			(xy 419.007251 -351.419084) (xy 418.978334 -351.414911) (xy 418.949417 -351.419084) (xy 418.92286 -351.43126)
			(xy 418.911532 -351.440496) (xy 418.890598 -351.458133) (xy 418.844626 -351.487845) (xy 418.794879 -351.510682)
			(xy 418.742379 -351.526173) (xy 418.688203 -351.534002) (xy 418.660834 -351.534476) (xy 418.632794 -351.533974)
			(xy 418.577316 -351.525777) (xy 418.523633 -351.509554) (xy 418.472901 -351.485654) (xy 418.42621 -351.45459)
			(xy 418.405056 -351.436178) (xy 418.393614 -351.426533) (xy 418.366571 -351.413753) (xy 418.336984 -351.409367)
			(xy 418.307397 -351.413753) (xy 418.280354 -351.426533) (xy 418.268912 -351.436178) (xy 418.247785 -351.454626)
			(xy 418.2011 -351.485714) (xy 418.150363 -351.509624) (xy 418.096669 -351.525837) (xy 418.041179 -351.534006)
			(xy 418.013134 -351.534476) (xy 417.985881 -351.534013) (xy 417.931928 -351.52626) (xy 417.879628 -351.510906)
			(xy 417.830046 -351.488266) (xy 417.784191 -351.458798) (xy 417.742997 -351.423104) (xy 417.707303 -351.38191)
			(xy 417.677835 -351.336056) (xy 417.655194 -351.286474) (xy 417.639841 -351.234174) (xy 417.632087 -351.180221)
			(xy 417.631626 -351.152968) (xy 414.70707 -351.152968) (xy 414.706615 -351.180222) (xy 414.698861 -351.234175)
			(xy 414.683507 -351.286475) (xy 414.660866 -351.336058) (xy 414.631398 -351.381913) (xy 414.595703 -351.423107)
			(xy 414.554508 -351.458801) (xy 414.508653 -351.488269) (xy 414.45907 -351.510909) (xy 414.406769 -351.526262)
			(xy 414.352816 -351.534015) (xy 414.325562 -351.534476) (xy 414.29752 -351.534017) (xy 414.24204 -351.52581)
			(xy 414.188357 -351.509576) (xy 414.137626 -351.485667) (xy 414.090936 -351.454594) (xy 414.069784 -351.436178)
			(xy 414.058342 -351.426533) (xy 414.031299 -351.413753) (xy 414.001712 -351.409367) (xy 413.972125 -351.413753)
			(xy 413.945082 -351.426533) (xy 413.93364 -351.436178) (xy 413.912502 -351.454613) (xy 413.86582 -351.485703)
			(xy 413.815086 -351.509615) (xy 413.761394 -351.525832) (xy 413.705906 -351.534004) (xy 413.677862 -351.534476)
			(xy 413.650493 -351.533979) (xy 413.596315 -351.52617) (xy 413.543812 -351.510688) (xy 413.494064 -351.487853)
			(xy 413.448096 -351.458135) (xy 413.427164 -351.440496) (xy 413.415836 -351.43126) (xy 413.389279 -351.419084)
			(xy 413.360362 -351.414911) (xy 413.331445 -351.419084) (xy 413.304888 -351.43126) (xy 413.29356 -351.440496)
			(xy 413.272616 -351.45812) (xy 413.226646 -351.487834) (xy 413.176902 -351.510673) (xy 413.124404 -351.526168)
			(xy 413.07023 -351.534) (xy 413.042862 -351.534476) (xy 413.015608 -351.534057) (xy 412.961657 -351.526295)
			(xy 412.909359 -351.510933) (xy 412.859779 -351.488285) (xy 412.813927 -351.458812) (xy 412.772737 -351.423114)
			(xy 412.737046 -351.381917) (xy 412.707581 -351.336059) (xy 412.684942 -351.286476) (xy 412.66959 -351.234175)
			(xy 412.661838 -351.180222) (xy 412.661354 -351.152968) (xy 411.43936 -351.152968) (xy 411.43936 -363.554264)
			(xy 412.204154 -363.554264) (xy 412.204632 -363.526223) (xy 412.212837 -363.470745) (xy 412.229067 -363.417063)
			(xy 412.252972 -363.366331) (xy 412.284039 -363.31964) (xy 412.302452 -363.298486) (xy 412.312086 -363.287035)
			(xy 412.324872 -363.259996) (xy 412.329261 -363.23041) (xy 412.324878 -363.200824) (xy 412.312097 -363.173783)
			(xy 412.302452 -363.162342) (xy 412.284023 -363.141199) (xy 412.252931 -363.094519) (xy 412.229018 -363.043786)
			(xy 412.2128 -362.990095) (xy 412.204627 -362.934608) (xy 412.204154 -362.906564) (xy 412.20464 -362.879313)
			(xy 412.212396 -362.825365) (xy 412.227751 -362.77307) (xy 412.250393 -362.723493) (xy 412.279859 -362.677643)
			(xy 412.31555 -362.636452) (xy 412.356741 -362.600761) (xy 412.402591 -362.571295) (xy 412.452168 -362.548653)
			(xy 412.504463 -362.533298) (xy 412.558411 -362.525542) (xy 412.612913 -362.525542) (xy 412.666861 -362.533298)
			(xy 412.719156 -362.548653) (xy 412.768733 -362.571295) (xy 412.814583 -362.600761) (xy 412.855774 -362.636452)
			(xy 412.891465 -362.677643) (xy 412.920931 -362.723493) (xy 412.943573 -362.77307) (xy 412.958928 -362.825365)
			(xy 412.966684 -362.879313) (xy 412.96717 -362.906564) (xy 412.966669 -362.934604) (xy 412.958472 -362.990082)
			(xy 412.942248 -363.043765) (xy 412.918348 -363.094497) (xy 412.887284 -363.141188) (xy 412.868872 -363.162342)
			(xy 412.864368 -363.167676) (xy 420.18153 -363.167676) (xy 420.185601 -363.112054) (xy 420.197727 -363.057617)
			(xy 420.21765 -363.005526) (xy 420.244946 -362.956891) (xy 420.279032 -362.912748) (xy 420.319181 -362.874039)
			(xy 420.364539 -362.841588) (xy 420.414139 -362.816087) (xy 420.466923 -362.79808) (xy 420.521766 -362.78795)
			(xy 420.5775 -362.785913) (xy 420.632937 -362.792013) (xy 420.686894 -362.806119) (xy 420.738223 -362.827931)
			(xy 420.785829 -362.856985) (xy 420.828697 -362.89266) (xy 420.865914 -362.934197) (xy 420.896687 -362.98071)
			(xy 420.920359 -363.031207) (xy 420.936427 -363.084614) (xy 420.944547 -363.13979) (xy 420.945056 -363.167676)
			(xy 420.944547 -363.195562) (xy 420.936427 -363.250738) (xy 420.920359 -363.304145) (xy 420.896687 -363.354642)
			(xy 420.865914 -363.401155) (xy 420.828697 -363.442692) (xy 420.785829 -363.478367) (xy 420.738223 -363.507421)
			(xy 420.686894 -363.529233) (xy 420.632937 -363.543339) (xy 420.591359 -363.547914) (xy 421.892476 -363.547914)
			(xy 421.892932 -363.520543) (xy 421.900749 -363.466363) (xy 421.91624 -363.413859) (xy 421.939084 -363.364112)
			(xy 421.968813 -363.318147) (xy 421.986456 -363.297216) (xy 421.995675 -363.285877) (xy 422.007847 -363.259322)
			(xy 422.01202 -363.230411) (xy 422.007853 -363.201498) (xy 421.995686 -363.174941) (xy 421.986456 -363.163612)
			(xy 421.968802 -363.142692) (xy 421.939094 -363.096715) (xy 421.916261 -363.046965) (xy 421.900773 -362.994462)
			(xy 421.892948 -362.940284) (xy 421.892476 -362.912914) (xy 421.892962 -362.885663) (xy 421.900718 -362.831715)
			(xy 421.916073 -362.77942) (xy 421.938715 -362.729843) (xy 421.968181 -362.683993) (xy 422.003872 -362.642802)
			(xy 422.045063 -362.607111) (xy 422.090913 -362.577645) (xy 422.14049 -362.555003) (xy 422.192785 -362.539648)
			(xy 422.246733 -362.531892) (xy 422.301235 -362.531892) (xy 422.355183 -362.539648) (xy 422.407478 -362.555003)
			(xy 422.457055 -362.577645) (xy 422.502905 -362.607111) (xy 422.544096 -362.642802) (xy 422.579787 -362.683993)
			(xy 422.609253 -362.729843) (xy 422.631895 -362.77942) (xy 422.64725 -362.831715) (xy 422.655006 -362.885663)
			(xy 422.655492 -362.912914) (xy 422.655036 -362.940285) (xy 422.647216 -362.994464) (xy 422.631725 -363.046968)
			(xy 422.608881 -363.096714) (xy 422.579154 -363.142681) (xy 422.561512 -363.163612) (xy 422.555283 -363.171232)
			(xy 429.73955 -363.171232) (xy 429.743621 -363.11561) (xy 429.755747 -363.061173) (xy 429.77567 -363.009082)
			(xy 429.802966 -362.960447) (xy 429.837052 -362.916304) (xy 429.877201 -362.877595) (xy 429.922559 -362.845144)
			(xy 429.972159 -362.819643) (xy 430.024943 -362.801636) (xy 430.079786 -362.791506) (xy 430.13552 -362.789469)
			(xy 430.190957 -362.795569) (xy 430.244914 -362.809675) (xy 430.296243 -362.831487) (xy 430.343849 -362.860541)
			(xy 430.386717 -362.896216) (xy 430.423934 -362.937753) (xy 430.454707 -362.984266) (xy 430.478379 -363.034763)
			(xy 430.494447 -363.08817) (xy 430.502567 -363.143346) (xy 430.503076 -363.171232) (xy 430.502567 -363.199118)
			(xy 430.494447 -363.254294) (xy 430.478379 -363.307701) (xy 430.454707 -363.358198) (xy 430.423934 -363.404711)
			(xy 430.386717 -363.446248) (xy 430.343849 -363.481923) (xy 430.296243 -363.510977) (xy 430.244914 -363.532789)
			(xy 430.190957 -363.546895) (xy 430.13552 -363.552995) (xy 430.079786 -363.550958) (xy 430.024943 -363.540828)
			(xy 429.972159 -363.522821) (xy 429.922559 -363.49732) (xy 429.877201 -363.464869) (xy 429.837052 -363.42616)
			(xy 429.802966 -363.382017) (xy 429.77567 -363.333382) (xy 429.755747 -363.281291) (xy 429.743621 -363.226854)
			(xy 429.73955 -363.171232) (xy 422.555283 -363.171232) (xy 422.552261 -363.174929) (xy 422.540084 -363.20149)
			(xy 422.535913 -363.230411) (xy 422.54009 -363.25933) (xy 422.552272 -363.285889) (xy 422.561512 -363.297216)
			(xy 422.579127 -363.318167) (xy 422.608842 -363.364135) (xy 422.631682 -363.413878) (xy 422.647179 -363.466374)
			(xy 422.655014 -363.520546) (xy 422.655492 -363.547914) (xy 422.655006 -363.575165) (xy 422.64725 -363.629113)
			(xy 422.631895 -363.681408) (xy 422.609253 -363.730985) (xy 422.579787 -363.776835) (xy 422.544096 -363.818026)
			(xy 422.502905 -363.853717) (xy 422.457055 -363.883183) (xy 422.407478 -363.905825) (xy 422.355183 -363.92118)
			(xy 422.301235 -363.928936) (xy 422.246733 -363.928936) (xy 422.192785 -363.92118) (xy 422.14049 -363.905825)
			(xy 422.090913 -363.883183) (xy 422.045063 -363.853717) (xy 422.003872 -363.818026) (xy 421.968181 -363.776835)
			(xy 421.938715 -363.730985) (xy 421.916073 -363.681408) (xy 421.900718 -363.629113) (xy 421.892962 -363.575165)
			(xy 421.892476 -363.547914) (xy 420.591359 -363.547914) (xy 420.5775 -363.549439) (xy 420.521766 -363.547402)
			(xy 420.466923 -363.537272) (xy 420.414139 -363.519265) (xy 420.364539 -363.493764) (xy 420.319181 -363.461313)
			(xy 420.279032 -363.422604) (xy 420.244946 -363.378461) (xy 420.21765 -363.329826) (xy 420.197727 -363.277735)
			(xy 420.185601 -363.223298) (xy 420.18153 -363.167676) (xy 412.864368 -363.167676) (xy 412.859217 -363.173775)
			(xy 412.846444 -363.200822) (xy 412.842063 -363.23041) (xy 412.84645 -363.259998) (xy 412.859228 -363.287043)
			(xy 412.868872 -363.298486) (xy 412.887318 -363.319615) (xy 412.918407 -363.366299) (xy 412.942317 -363.417036)
			(xy 412.958531 -363.470729) (xy 412.966699 -363.526219) (xy 412.96717 -363.554264) (xy 412.966684 -363.581515)
			(xy 412.958928 -363.635463) (xy 412.943573 -363.687758) (xy 412.920931 -363.737335) (xy 412.891465 -363.783185)
			(xy 412.855774 -363.824376) (xy 412.814583 -363.860067) (xy 412.768733 -363.889533) (xy 412.719156 -363.912175)
			(xy 412.666861 -363.92753) (xy 412.612913 -363.935286) (xy 412.558411 -363.935286) (xy 412.504463 -363.92753)
			(xy 412.452168 -363.912175) (xy 412.402591 -363.889533) (xy 412.356741 -363.860067) (xy 412.31555 -363.824376)
			(xy 412.279859 -363.783185) (xy 412.250393 -363.737335) (xy 412.227751 -363.687758) (xy 412.212396 -363.635463)
			(xy 412.20464 -363.581515) (xy 412.204154 -363.554264) (xy 411.43936 -363.554264) (xy 411.43936 -363.9505)
			(xy 416.452737 -363.9505) (xy 416.456906 -363.894879) (xy 416.469318 -363.840501) (xy 416.489697 -363.788581)
			(xy 416.517587 -363.740278) (xy 416.552365 -363.696672) (xy 416.593254 -363.658736) (xy 416.639341 -363.627319)
			(xy 416.689595 -363.603122) (xy 416.742895 -363.586686) (xy 416.79805 -363.578378) (xy 416.825938 -363.577886)
			(xy 416.853268 -363.578397) (xy 416.907345 -363.586362) (xy 416.959677 -363.602145) (xy 417.009141 -363.625407)
			(xy 417.054673 -363.655648) (xy 417.095297 -363.692219) (xy 417.13014 -363.734335) (xy 417.144708 -363.757464)
			(xy 417.152655 -363.769672) (xy 417.174117 -363.789348) (xy 417.200265 -363.802157) (xy 417.228966 -363.807056)
			(xy 417.257882 -363.803645) (xy 417.271454 -363.798358) (xy 417.29466 -363.788857) (xy 417.342995 -363.775511)
			(xy 417.392686 -363.768787) (xy 417.417758 -363.768386) (xy 417.442827 -363.768806) (xy 417.49251 -363.775558)
			(xy 417.540845 -363.788892) (xy 417.564062 -363.798358) (xy 417.577647 -363.803579) (xy 417.606542 -363.806943)
			(xy 417.635215 -363.802036) (xy 417.661347 -363.789254) (xy 417.682824 -363.769633) (xy 417.690808 -363.757464)
			(xy 417.705377 -363.734333) (xy 417.74022 -363.692212) (xy 417.780843 -363.655633) (xy 417.826374 -363.625382)
			(xy 417.875836 -363.602106) (xy 417.928167 -363.586306) (xy 417.982246 -363.57832) (xy 418.03691 -363.57832)
			(xy 418.090989 -363.586306) (xy 418.14332 -363.602106) (xy 418.192782 -363.625382) (xy 418.238313 -363.655633)
			(xy 418.278936 -363.692212) (xy 418.313779 -363.734333) (xy 418.328348 -363.757464) (xy 418.336257 -363.7697)
			(xy 418.35773 -363.789375) (xy 418.383887 -363.802181) (xy 418.412598 -363.807072) (xy 418.44152 -363.803652)
			(xy 418.455094 -363.798358) (xy 418.478307 -363.788876) (xy 418.526638 -363.775523) (xy 418.576327 -363.768791)
			(xy 418.601398 -363.768386) (xy 418.627622 -363.768832) (xy 418.679552 -363.776174) (xy 418.72994 -363.790728)
			(xy 418.777787 -363.812206) (xy 418.822149 -363.840183) (xy 418.862149 -363.874105) (xy 418.896994 -363.913303)
			(xy 418.925997 -363.957001) (xy 418.937694 -363.980476) (xy 418.9441 -363.992667) (xy 418.962164 -364.013433)
			(xy 418.985123 -364.028613) (xy 419.011303 -364.037104) (xy 419.038801 -364.038288) (xy 419.065615 -364.032078)
			(xy 419.089792 -364.018927) (xy 419.1 -364.009686) (xy 419.121475 -363.98975) (xy 419.169373 -363.956)
			(xy 419.221866 -363.929965) (xy 419.277721 -363.912257) (xy 419.335625 -363.903292) (xy 419.364922 -363.902752)
			(xy 419.382941 -363.902975) (xy 419.418816 -363.906408) (xy 419.43655 -363.90961) (xy 419.451762 -363.911934)
			(xy 419.482317 -363.908418) (xy 419.510438 -363.895963) (xy 419.533574 -363.875698) (xy 419.549626 -363.849463)
			(xy 419.553898 -363.83468) (xy 419.561329 -363.807646) (xy 419.582954 -363.75592) (xy 419.611913 -363.707915)
			(xy 419.647584 -363.664662) (xy 419.689199 -363.627094) (xy 419.735863 -363.596019) (xy 419.78657 -363.572104)
			(xy 419.840231 -363.555866) (xy 419.89569 -363.547652) (xy 419.923722 -363.547152) (xy 419.950972 -363.547657)
			(xy 420.004917 -363.555416) (xy 420.057209 -363.570772) (xy 420.106783 -363.593412) (xy 420.152632 -363.622877)
			(xy 420.193821 -363.658566) (xy 420.229512 -363.699754) (xy 420.258979 -363.745601) (xy 420.281622 -363.795174)
			(xy 420.29698 -363.847465) (xy 420.304742 -363.90141) (xy 420.30523 -363.92866) (xy 420.304831 -363.9505)
			(xy 426.141163 -363.9505) (xy 426.145331 -363.894891) (xy 426.157739 -363.840523) (xy 426.178111 -363.788612)
			(xy 426.205992 -363.740317) (xy 426.240759 -363.696717) (xy 426.281635 -363.658784) (xy 426.327709 -363.627368)
			(xy 426.37795 -363.603168) (xy 426.431236 -363.586726) (xy 426.486377 -363.57841) (xy 426.51426 -363.577886)
			(xy 426.541591 -363.57838) (xy 426.595669 -363.586348) (xy 426.648001 -363.602134) (xy 426.697465 -363.625399)
			(xy 426.742997 -363.655643) (xy 426.78362 -363.692216) (xy 426.818463 -363.734334) (xy 426.83303 -363.757464)
			(xy 426.840956 -363.769687) (xy 426.862424 -363.789363) (xy 426.888577 -363.80217) (xy 426.917283 -363.807065)
			(xy 426.946203 -363.803649) (xy 426.959776 -363.798358) (xy 426.982991 -363.788881) (xy 427.031321 -363.775526)
			(xy 427.081009 -363.768793) (xy 427.10608 -363.768386) (xy 427.131148 -363.768832) (xy 427.180831 -363.775573)
			(xy 427.229166 -363.788896) (xy 427.252384 -363.798358) (xy 427.265997 -363.803497) (xy 427.294878 -363.806878)
			(xy 427.323541 -363.801989) (xy 427.349668 -363.789227) (xy 427.371145 -363.769625) (xy 427.37913 -363.757464)
			(xy 427.393699 -363.734333) (xy 427.428542 -363.692212) (xy 427.469165 -363.655633) (xy 427.514696 -363.625382)
			(xy 427.564158 -363.602106) (xy 427.616489 -363.586306) (xy 427.670568 -363.57832) (xy 427.725232 -363.57832)
			(xy 427.779311 -363.586306) (xy 427.831642 -363.602106) (xy 427.881104 -363.625382) (xy 427.926635 -363.655633)
			(xy 427.967258 -363.692212) (xy 428.002101 -363.734333) (xy 428.01667 -363.757464) (xy 428.024558 -363.769715)
			(xy 428.046036 -363.78939) (xy 428.0722 -363.802194) (xy 428.100915 -363.807082) (xy 428.129841 -363.803655)
			(xy 428.143416 -363.798358) (xy 428.166626 -363.788869) (xy 428.214959 -363.775518) (xy 428.264648 -363.76879)
			(xy 428.28972 -363.768386) (xy 428.316563 -363.768828) (xy 428.369694 -363.776536) (xy 428.421169 -363.791788)
			(xy 428.469922 -363.814269) (xy 428.514944 -363.843513) (xy 428.555304 -363.878916) (xy 428.590165 -363.919745)
			(xy 428.618807 -363.965153) (xy 428.640635 -364.014202) (xy 428.648368 -364.039912) (xy 428.653106 -364.054383)
			(xy 428.669606 -364.079945) (xy 428.692905 -364.099513) (xy 428.720934 -364.111348) (xy 428.751206 -364.1144)
			(xy 428.781034 -364.108398) (xy 428.794672 -364.101634) (xy 428.822813 -364.086991) (xy 428.882767 -364.066268)
			(xy 428.945327 -364.055774) (xy 428.977044 -364.055152) (xy 428.995063 -364.055372) (xy 429.030938 -364.058807)
			(xy 429.048672 -364.06201) (xy 429.063881 -364.064356) (xy 429.094438 -364.060834) (xy 429.122561 -364.048373)
			(xy 429.145697 -364.028104) (xy 429.161749 -364.001864) (xy 429.16602 -363.98708) (xy 429.173431 -363.960039)
			(xy 429.195057 -363.908313) (xy 429.224019 -363.860306) (xy 429.259692 -363.817054) (xy 429.30131 -363.779486)
			(xy 429.347976 -363.748411) (xy 429.398687 -363.724498) (xy 429.45235 -363.708261) (xy 429.507811 -363.700051)
			(xy 429.535844 -363.699552) (xy 429.563095 -363.700037) (xy 429.61704 -363.707798) (xy 429.669332 -363.723157)
			(xy 429.718907 -363.7458) (xy 429.764755 -363.775267) (xy 429.805944 -363.810959) (xy 429.841635 -363.852148)
			(xy 429.871102 -363.897996) (xy 429.893744 -363.947571) (xy 429.909103 -363.999864) (xy 429.916864 -364.053809)
			(xy 429.917352 -364.08106) (xy 429.916876 -364.108634) (xy 429.908928 -364.163207) (xy 429.893206 -364.216068)
			(xy 429.870038 -364.266114) (xy 429.839906 -364.312304) (xy 429.803439 -364.353675) (xy 429.782732 -364.37189)
			(xy 429.771872 -364.381828) (xy 429.755794 -364.406466) (xy 429.747403 -364.434664) (xy 429.747395 -364.464084)
			(xy 429.755772 -364.492287) (xy 429.771838 -364.516933) (xy 429.782732 -364.52683) (xy 429.803396 -364.54509)
			(xy 429.839856 -364.586457) (xy 429.869981 -364.632642) (xy 429.893143 -364.682683) (xy 429.908859 -364.735537)
			(xy 429.916801 -364.790103) (xy 429.916805 -364.845245) (xy 429.90887 -364.899812) (xy 429.893161 -364.952669)
			(xy 429.870006 -365.002713) (xy 429.839888 -365.048902) (xy 429.803433 -365.090273) (xy 429.782732 -365.10849)
			(xy 429.771872 -365.118428) (xy 429.755794 -365.143066) (xy 429.747403 -365.171264) (xy 429.747395 -365.200684)
			(xy 429.755772 -365.228887) (xy 429.771838 -365.253533) (xy 429.782732 -365.26343) (xy 429.803467 -365.281615)
			(xy 429.839934 -365.32299) (xy 429.870063 -365.369186) (xy 429.893224 -365.419239) (xy 429.908935 -365.472105)
			(xy 429.91687 -365.526684) (xy 429.917352 -365.55426) (xy 429.916785 -365.581508) (xy 429.909035 -365.635451)
			(xy 429.893687 -365.687741) (xy 429.871054 -365.737315) (xy 429.841596 -365.783164) (xy 429.805913 -365.824353)
			(xy 429.764731 -365.860045) (xy 429.718889 -365.889513) (xy 429.66932 -365.912158) (xy 429.617033 -365.927517)
			(xy 429.563092 -365.935279) (xy 429.535844 -365.935768) (xy 429.507989 -365.935229) (xy 429.452873 -365.927111)
			(xy 429.399522 -365.91107) (xy 429.349068 -365.887446) (xy 429.302582 -365.856741) (xy 429.261052 -365.819607)
			(xy 429.225359 -365.776832) (xy 429.196261 -365.729325) (xy 429.174375 -365.678093) (xy 429.166782 -365.651288)
			(xy 429.162503 -365.637174) (xy 429.147112 -365.612032) (xy 429.125194 -365.592318) (xy 429.098568 -365.579666)
			(xy 429.069441 -365.575125) (xy 429.054768 -365.576612) (xy 429.041752 -365.578282) (xy 429.015567 -365.580061)
			(xy 429.002444 -365.580168) (xy 428.988295 -365.58007) (xy 428.960072 -365.578039) (xy 428.946056 -365.576104)
			(xy 428.932707 -365.574531) (xy 428.906016 -365.577627) (xy 428.881063 -365.587594) (xy 428.859584 -365.603737)
			(xy 428.843071 -365.624934) (xy 428.832675 -365.64971) (xy 428.830486 -365.662972) (xy 428.826449 -365.690134)
			(xy 428.811471 -365.742967) (xy 428.789074 -365.793107) (xy 428.75972 -365.839519) (xy 428.724017 -365.881243)
			(xy 428.682701 -365.917419) (xy 428.636627 -365.947298) (xy 428.586745 -365.970264) (xy 428.534086 -365.985843)
			(xy 428.479738 -365.993712) (xy 428.45228 -365.994188) (xy 428.425027 -365.993741) (xy 428.371077 -365.985981)
			(xy 428.318781 -365.970622) (xy 428.269202 -365.947977) (xy 428.223351 -365.918507) (xy 428.18216 -365.882812)
			(xy 428.146469 -365.841617) (xy 428.117003 -365.795763) (xy 428.094364 -365.746182) (xy 428.07901 -365.693884)
			(xy 428.071256 -365.639933) (xy 428.070772 -365.61268) (xy 428.071303 -365.585108) (xy 428.079243 -365.530538)
			(xy 428.094956 -365.47768) (xy 428.118114 -365.427634) (xy 428.148235 -365.381443) (xy 428.18469 -365.340068)
			(xy 428.205392 -365.32185) (xy 428.21631 -365.311972) (xy 428.232382 -365.287316) (xy 428.240764 -365.259103)
			(xy 428.24076 -365.229671) (xy 428.232371 -365.20146) (xy 428.216292 -365.176809) (xy 428.205392 -365.16691)
			(xy 428.184681 -365.148699) (xy 428.148211 -365.10733) (xy 428.118079 -365.06114) (xy 428.094913 -365.011092)
			(xy 428.079197 -364.95823) (xy 428.071257 -364.903655) (xy 428.070772 -364.87608) (xy 428.071239 -364.849579)
			(xy 428.078582 -364.797089) (xy 428.093124 -364.746122) (xy 428.114584 -364.697659) (xy 428.142548 -364.652636)
			(xy 428.159164 -364.631986) (xy 428.168558 -364.619807) (xy 428.180349 -364.591418) (xy 428.183178 -364.560808)
			(xy 428.17679 -364.530739) (xy 428.161762 -364.503922) (xy 428.13945 -364.482778) (xy 428.12589 -364.475522)
			(xy 428.102212 -364.463399) (xy 428.058228 -364.433483) (xy 428.018943 -364.397619) (xy 427.985156 -364.356534)
			(xy 427.97095 -364.334044) (xy 427.963041 -364.321808) (xy 427.941569 -364.302132) (xy 427.915411 -364.289326)
			(xy 427.8867 -364.284434) (xy 427.857778 -364.287856) (xy 427.844204 -364.29315) (xy 427.820992 -364.302633)
			(xy 427.77266 -364.315986) (xy 427.722971 -364.322717) (xy 427.6979 -364.323122) (xy 427.672831 -364.32269)
			(xy 427.623148 -364.315945) (xy 427.574814 -364.302615) (xy 427.551596 -364.29315) (xy 427.537991 -364.287986)
			(xy 427.509106 -364.28461) (xy 427.480439 -364.289503) (xy 427.45431 -364.302271) (xy 427.432834 -364.32188)
			(xy 427.42485 -364.334044) (xy 427.410281 -364.357175) (xy 427.375438 -364.399296) (xy 427.334815 -364.435875)
			(xy 427.289284 -364.466126) (xy 427.239822 -364.489402) (xy 427.187491 -364.505202) (xy 427.133412 -364.513188)
			(xy 427.078748 -364.513188) (xy 427.024669 -364.505202) (xy 426.972338 -364.489402) (xy 426.922876 -364.466126)
			(xy 426.877345 -364.435875) (xy 426.836722 -364.399296) (xy 426.801879 -364.357175) (xy 426.78731 -364.334044)
			(xy 426.779344 -364.321849) (xy 426.757887 -364.302173) (xy 426.731745 -364.289362) (xy 426.703048 -364.284459)
			(xy 426.674135 -364.287865) (xy 426.660564 -364.29315) (xy 426.637357 -364.302646) (xy 426.589022 -364.315994)
			(xy 426.539332 -364.32272) (xy 426.51426 -364.323122) (xy 426.486377 -364.32259) (xy 426.431236 -364.314274)
			(xy 426.37795 -364.297832) (xy 426.327709 -364.273632) (xy 426.281635 -364.242216) (xy 426.240759 -364.204283)
			(xy 426.205992 -364.160683) (xy 426.178111 -364.112388) (xy 426.157739 -364.060477) (xy 426.145331 -364.006109)
			(xy 426.141163 -363.9505) (xy 420.304831 -363.9505) (xy 420.304726 -363.956233) (xy 420.29678 -364.010804)
			(xy 420.281062 -364.063662) (xy 420.257899 -364.113708) (xy 420.227774 -364.159899) (xy 420.191314 -364.201273)
			(xy 420.17061 -364.21949) (xy 420.159752 -364.229429) (xy 420.143677 -364.254067) (xy 420.135288 -364.282265)
			(xy 420.135281 -364.311684) (xy 420.143655 -364.339885) (xy 420.159718 -364.364532) (xy 420.17061 -364.37443)
			(xy 420.191275 -364.39269) (xy 420.227737 -364.434056) (xy 420.257864 -364.48024) (xy 420.281027 -364.530281)
			(xy 420.296744 -364.583136) (xy 420.304687 -364.637703) (xy 420.304691 -364.692845) (xy 420.296755 -364.747413)
			(xy 420.281046 -364.80027) (xy 420.257889 -364.850314) (xy 420.227769 -364.896503) (xy 420.191312 -364.937874)
			(xy 420.17061 -364.95609) (xy 420.159752 -364.966029) (xy 420.143677 -364.990667) (xy 420.136055 -365.016288)
			(xy 422.68343 -365.016288) (xy 422.687501 -364.960666) (xy 422.699627 -364.906229) (xy 422.71955 -364.854138)
			(xy 422.746846 -364.805503) (xy 422.780932 -364.76136) (xy 422.821081 -364.722651) (xy 422.866439 -364.6902)
			(xy 422.916039 -364.664699) (xy 422.968823 -364.646692) (xy 423.023666 -364.636562) (xy 423.0794 -364.634525)
			(xy 423.134837 -364.640625) (xy 423.188794 -364.654731) (xy 423.240123 -364.676543) (xy 423.287729 -364.705597)
			(xy 423.330597 -364.741272) (xy 423.367814 -364.782809) (xy 423.398587 -364.829322) (xy 423.422259 -364.879819)
			(xy 423.438327 -364.933226) (xy 423.446447 -364.988402) (xy 423.446956 -365.016288) (xy 423.446447 -365.044174)
			(xy 423.438327 -365.09935) (xy 423.422259 -365.152757) (xy 423.398587 -365.203254) (xy 423.367814 -365.249767)
			(xy 423.330597 -365.291304) (xy 423.287729 -365.326979) (xy 423.240123 -365.356033) (xy 423.188794 -365.377845)
			(xy 423.134837 -365.391951) (xy 423.0794 -365.398051) (xy 423.023666 -365.396014) (xy 422.968823 -365.385884)
			(xy 422.916039 -365.367877) (xy 422.866439 -365.342376) (xy 422.821081 -365.309925) (xy 422.780932 -365.271216)
			(xy 422.746846 -365.227073) (xy 422.71955 -365.178438) (xy 422.699627 -365.126347) (xy 422.687501 -365.07191)
			(xy 422.68343 -365.016288) (xy 420.136055 -365.016288) (xy 420.135288 -365.018865) (xy 420.135281 -365.048284)
			(xy 420.143655 -365.076485) (xy 420.159718 -365.101132) (xy 420.17061 -365.11103) (xy 420.191341 -365.12922)
			(xy 420.227809 -365.170593) (xy 420.257939 -365.216788) (xy 420.281101 -365.26684) (xy 420.296813 -365.319706)
			(xy 420.304748 -365.374284) (xy 420.30523 -365.40186) (xy 420.304708 -365.429111) (xy 420.296957 -365.483059)
			(xy 420.281607 -365.535354) (xy 420.258971 -365.584932) (xy 420.229509 -365.630785) (xy 420.193821 -365.671977)
			(xy 420.152634 -365.707672) (xy 420.106787 -365.737141) (xy 420.057212 -365.759785) (xy 420.004919 -365.775143)
			(xy 419.950973 -365.782903) (xy 419.923722 -365.783368) (xy 419.895866 -365.782849) (xy 419.840749 -365.774727)
			(xy 419.787398 -365.758683) (xy 419.736944 -365.735057) (xy 419.690459 -365.704349) (xy 419.648929 -365.667213)
			(xy 419.613236 -365.624437) (xy 419.584138 -365.576927) (xy 419.562253 -365.525694) (xy 419.55466 -365.498888)
			(xy 419.550403 -365.484766) (xy 419.535007 -365.459622) (xy 419.513085 -365.439908) (xy 419.486453 -365.427258)
			(xy 419.45732 -365.422722) (xy 419.442646 -365.424212) (xy 419.42963 -365.425885) (xy 419.403445 -365.427662)
			(xy 419.390322 -365.427768) (xy 419.361422 -365.427257) (xy 419.304278 -365.418587) (xy 419.27653 -365.410496)
			(xy 419.262999 -365.40669) (xy 419.234907 -365.405954) (xy 419.207676 -365.412891) (xy 419.183359 -365.426976)
			(xy 419.163794 -365.447148) (xy 419.150457 -365.471882) (xy 419.144354 -365.499313) (xy 419.144704 -365.513366)
			(xy 419.145466 -365.53648) (xy 419.14498 -365.563731) (xy 419.137224 -365.617679) (xy 419.121869 -365.669974)
			(xy 419.099227 -365.719551) (xy 419.069761 -365.765401) (xy 419.03407 -365.806592) (xy 418.992879 -365.842283)
			(xy 418.947029 -365.871749) (xy 418.897452 -365.894391) (xy 418.845157 -365.909746) (xy 418.791209 -365.917502)
			(xy 418.736707 -365.917502) (xy 418.682759 -365.909746) (xy 418.630464 -365.894391) (xy 418.580887 -365.871749)
			(xy 418.535037 -365.842283) (xy 418.493846 -365.806592) (xy 418.458155 -365.765401) (xy 418.428689 -365.719551)
			(xy 418.406047 -365.669974) (xy 418.390692 -365.617679) (xy 418.382936 -365.563731) (xy 418.38245 -365.53648)
			(xy 418.382953 -365.508907) (xy 418.390896 -365.454335) (xy 418.406612 -365.401475) (xy 418.429775 -365.351428)
			(xy 418.459902 -365.305238) (xy 418.496365 -365.263866) (xy 418.51707 -365.24565) (xy 418.52799 -365.235773)
			(xy 418.544066 -365.211118) (xy 418.552449 -365.182904) (xy 418.552446 -365.15347) (xy 418.544055 -365.125259)
			(xy 418.527972 -365.100607) (xy 418.51707 -365.09071) (xy 418.496354 -365.072504) (xy 418.459886 -365.031133)
			(xy 418.429755 -364.984942) (xy 418.40659 -364.934893) (xy 418.390874 -364.88203) (xy 418.382935 -364.827455)
			(xy 418.38245 -364.79988) (xy 418.38292 -364.77338) (xy 418.390262 -364.720892) (xy 418.404802 -364.669925)
			(xy 418.42626 -364.621464) (xy 418.439854 -364.598712) (xy 418.446578 -364.587148) (xy 418.454271 -364.561535)
			(xy 418.455055 -364.534802) (xy 418.448875 -364.508782) (xy 418.436156 -364.485257) (xy 418.417769 -364.465837)
			(xy 418.40658 -364.458504) (xy 418.381664 -364.442569) (xy 418.336742 -364.404103) (xy 418.298456 -364.359028)
			(xy 418.282628 -364.334044) (xy 418.27474 -364.321793) (xy 418.253262 -364.302117) (xy 418.227099 -364.289313)
			(xy 418.198383 -364.284425) (xy 418.169457 -364.287852) (xy 418.155882 -364.29315) (xy 418.132672 -364.30264)
			(xy 418.084339 -364.31599) (xy 418.03465 -364.322718) (xy 418.009578 -364.323122) (xy 417.984509 -364.322697)
			(xy 417.934826 -364.315949) (xy 417.886491 -364.302616) (xy 417.863274 -364.29315) (xy 417.849677 -364.287963)
			(xy 417.820788 -364.284591) (xy 417.792118 -364.28949) (xy 417.765988 -364.302264) (xy 417.744512 -364.321878)
			(xy 417.736528 -364.334044) (xy 417.721959 -364.357175) (xy 417.687116 -364.399296) (xy 417.646493 -364.435875)
			(xy 417.600962 -364.466126) (xy 417.5515 -364.489402) (xy 417.499169 -364.505202) (xy 417.44509 -364.513188)
			(xy 417.390426 -364.513188) (xy 417.336347 -364.505202) (xy 417.284016 -364.489402) (xy 417.234554 -364.466126)
			(xy 417.189023 -364.435875) (xy 417.1484 -364.399296) (xy 417.113557 -364.357175) (xy 417.098988 -364.334044)
			(xy 417.091043 -364.321834) (xy 417.06958 -364.302158) (xy 417.043432 -364.289349) (xy 417.014731 -364.28445)
			(xy 416.985814 -364.287862) (xy 416.972242 -364.29315) (xy 416.949037 -364.302652) (xy 416.900702 -364.315998)
			(xy 416.85101 -364.322721) (xy 416.825938 -364.323122) (xy 416.79805 -364.322622) (xy 416.742895 -364.314314)
			(xy 416.689595 -364.297878) (xy 416.639341 -364.273681) (xy 416.593254 -364.242264) (xy 416.552365 -364.204328)
			(xy 416.517587 -364.160722) (xy 416.489697 -364.112419) (xy 416.469318 -364.060499) (xy 416.456906 -364.006121)
			(xy 416.452737 -363.9505) (xy 411.43936 -363.9505) (xy 411.43936 -365.016288) (xy 412.995108 -365.016288)
			(xy 412.999179 -364.960666) (xy 413.011305 -364.906229) (xy 413.031228 -364.854138) (xy 413.058524 -364.805503)
			(xy 413.09261 -364.76136) (xy 413.132759 -364.722651) (xy 413.178117 -364.6902) (xy 413.227717 -364.664699)
			(xy 413.280501 -364.646692) (xy 413.335344 -364.636562) (xy 413.391078 -364.634525) (xy 413.446515 -364.640625)
			(xy 413.500472 -364.654731) (xy 413.551801 -364.676543) (xy 413.599407 -364.705597) (xy 413.642275 -364.741272)
			(xy 413.679492 -364.782809) (xy 413.710265 -364.829322) (xy 413.733937 -364.879819) (xy 413.750005 -364.933226)
			(xy 413.758125 -364.988402) (xy 413.758634 -365.016288) (xy 413.758125 -365.044174) (xy 413.750005 -365.09935)
			(xy 413.733937 -365.152757) (xy 413.710265 -365.203254) (xy 413.679492 -365.249767) (xy 413.642275 -365.291304)
			(xy 413.599407 -365.326979) (xy 413.551801 -365.356033) (xy 413.500472 -365.377845) (xy 413.446515 -365.391951)
			(xy 413.391078 -365.398051) (xy 413.335344 -365.396014) (xy 413.280501 -365.385884) (xy 413.227717 -365.367877)
			(xy 413.178117 -365.342376) (xy 413.132759 -365.309925) (xy 413.09261 -365.271216) (xy 413.058524 -365.227073)
			(xy 413.031228 -365.178438) (xy 413.011305 -365.126347) (xy 412.999179 -365.07191) (xy 412.995108 -365.016288)
			(xy 411.43936 -365.016288) (xy 411.43936 -365.98225) (xy 412.330644 -365.98225) (xy 412.334715 -365.926628)
			(xy 412.346841 -365.872191) (xy 412.366764 -365.8201) (xy 412.39406 -365.771465) (xy 412.428146 -365.727322)
			(xy 412.468295 -365.688613) (xy 412.513653 -365.656162) (xy 412.563253 -365.630661) (xy 412.616037 -365.612654)
			(xy 412.67088 -365.602524) (xy 412.726614 -365.600487) (xy 412.782051 -365.606587) (xy 412.836008 -365.620693)
			(xy 412.887337 -365.642505) (xy 412.934943 -365.671559) (xy 412.977811 -365.707234) (xy 413.015028 -365.748771)
			(xy 413.045801 -365.795284) (xy 413.069473 -365.845781) (xy 413.085541 -365.899188) (xy 413.093661 -365.954364)
			(xy 413.09417 -365.98225) (xy 413.093661 -366.010136) (xy 413.085541 -366.065312) (xy 413.069473 -366.118719)
			(xy 413.045801 -366.169216) (xy 413.015028 -366.215729) (xy 412.977811 -366.257266) (xy 412.934943 -366.292941)
			(xy 412.887337 -366.321995) (xy 412.836008 -366.343807) (xy 412.782051 -366.357913) (xy 412.726614 -366.364013)
			(xy 412.67088 -366.361976) (xy 412.616037 -366.351846) (xy 412.563253 -366.333839) (xy 412.513653 -366.308338)
			(xy 412.468295 -366.275887) (xy 412.428146 -366.237178) (xy 412.39406 -366.193035) (xy 412.366764 -366.1444)
			(xy 412.346841 -366.092309) (xy 412.334715 -366.037872) (xy 412.330644 -365.98225) (xy 411.43936 -365.98225)
			(xy 411.43936 -366.54486) (xy 413.801814 -366.54486) (xy 413.802256 -366.518544) (xy 413.809478 -366.466409)
			(xy 413.823793 -366.41576) (xy 413.844929 -366.367558) (xy 413.872487 -366.322717) (xy 413.905943 -366.282086)
			(xy 413.925004 -366.263936) (xy 413.935064 -366.254162) (xy 413.949759 -366.230278) (xy 413.957391 -366.203294)
			(xy 413.957384 -366.175252) (xy 413.949737 -366.148272) (xy 413.935029 -366.124396) (xy 413.925004 -366.114584)
			(xy 413.905918 -366.096456) (xy 413.87244 -366.055834) (xy 413.84487 -366.010993) (xy 413.823733 -365.962784)
			(xy 413.80943 -365.912125) (xy 413.802234 -365.85998) (xy 413.801814 -365.83366) (xy 413.8023 -365.806409)
			(xy 413.810056 -365.752461) (xy 413.825411 -365.700166) (xy 413.848053 -365.650589) (xy 413.877519 -365.604739)
			(xy 413.91321 -365.563548) (xy 413.954401 -365.527857) (xy 414.000251 -365.498391) (xy 414.049828 -365.475749)
			(xy 414.102123 -365.460394) (xy 414.156071 -365.452638) (xy 414.210573 -365.452638) (xy 414.264521 -365.460394)
			(xy 414.316816 -365.475749) (xy 414.366393 -365.498391) (xy 414.412243 -365.527857) (xy 414.453434 -365.563548)
			(xy 414.489125 -365.604739) (xy 414.518591 -365.650589) (xy 414.541233 -365.700166) (xy 414.556588 -365.752461)
			(xy 414.564344 -365.806409) (xy 414.56449 -365.81461) (xy 415.42716 -365.81461) (xy 415.427646 -365.787359)
			(xy 415.435402 -365.733411) (xy 415.450757 -365.681116) (xy 415.473399 -365.631539) (xy 415.502865 -365.585689)
			(xy 415.538556 -365.544498) (xy 415.579747 -365.508807) (xy 415.625597 -365.479341) (xy 415.675174 -365.456699)
			(xy 415.727469 -365.441344) (xy 415.781417 -365.433588) (xy 415.835919 -365.433588) (xy 415.889867 -365.441344)
			(xy 415.942162 -365.456699) (xy 415.991739 -365.479341) (xy 416.037589 -365.508807) (xy 416.07878 -365.544498)
			(xy 416.114471 -365.585689) (xy 416.143937 -365.631539) (xy 416.166579 -365.681116) (xy 416.181934 -365.733411)
			(xy 416.18969 -365.787359) (xy 416.190176 -365.81461) (xy 416.189939 -365.833277) (xy 416.18625 -365.870429)
			(xy 416.18281 -365.888778) (xy 416.180493 -365.903048) (xy 416.183021 -365.931832) (xy 416.193516 -365.958754)
			(xy 416.211135 -365.981656) (xy 416.228289 -365.994188) (xy 422.018966 -365.994188) (xy 422.023037 -365.938566)
			(xy 422.035163 -365.884129) (xy 422.055086 -365.832038) (xy 422.082382 -365.783403) (xy 422.116468 -365.73926)
			(xy 422.156617 -365.700551) (xy 422.201975 -365.6681) (xy 422.251575 -365.642599) (xy 422.304359 -365.624592)
			(xy 422.359202 -365.614462) (xy 422.414936 -365.612425) (xy 422.470373 -365.618525) (xy 422.52433 -365.632631)
			(xy 422.575659 -365.654443) (xy 422.623265 -365.683497) (xy 422.666133 -365.719172) (xy 422.70335 -365.760709)
			(xy 422.734123 -365.807222) (xy 422.757795 -365.857719) (xy 422.773863 -365.911126) (xy 422.781983 -365.966302)
			(xy 422.782492 -365.994188) (xy 422.781983 -366.022074) (xy 422.773863 -366.07725) (xy 422.757795 -366.130657)
			(xy 422.734123 -366.181154) (xy 422.70335 -366.227667) (xy 422.666133 -366.269204) (xy 422.623265 -366.304879)
			(xy 422.575659 -366.333933) (xy 422.52433 -366.355745) (xy 422.470373 -366.369851) (xy 422.414936 -366.375951)
			(xy 422.359202 -366.373914) (xy 422.304359 -366.363784) (xy 422.251575 -366.345777) (xy 422.201975 -366.320276)
			(xy 422.156617 -366.287825) (xy 422.116468 -366.249116) (xy 422.082382 -366.204973) (xy 422.055086 -366.156338)
			(xy 422.035163 -366.104247) (xy 422.023037 -366.04981) (xy 422.018966 -365.994188) (xy 416.228289 -365.994188)
			(xy 416.234467 -365.998701) (xy 416.261641 -366.008525) (xy 416.276028 -366.009936) (xy 416.304683 -366.012287)
			(xy 416.360849 -366.024579) (xy 416.414535 -366.045157) (xy 416.464527 -366.073556) (xy 416.509692 -366.109134)
			(xy 416.549008 -366.151085) (xy 416.581587 -366.198459) (xy 416.606689 -366.250185) (xy 416.623747 -366.305091)
			(xy 416.632375 -366.361935) (xy 416.632898 -366.390682) (xy 416.632412 -366.417933) (xy 416.624656 -366.471881)
			(xy 416.609301 -366.524176) (xy 416.586659 -366.573753) (xy 416.57813 -366.587024) (xy 423.490136 -366.587024)
			(xy 423.490687 -366.558579) (xy 423.499137 -366.502321) (xy 423.515853 -366.447943) (xy 423.540465 -366.396652)
			(xy 423.572425 -366.349589) (xy 423.611023 -366.307797) (xy 423.632884 -366.28959) (xy 423.644312 -366.279599)
			(xy 423.66133 -366.25449) (xy 423.670235 -366.225493) (xy 423.670243 -366.19516) (xy 423.661353 -366.166158)
			(xy 423.644348 -366.14104) (xy 423.632884 -366.131094) (xy 423.610998 -366.112915) (xy 423.572397 -366.071118)
			(xy 423.540436 -366.02405) (xy 423.515824 -365.972754) (xy 423.499109 -365.918371) (xy 423.49066 -365.862107)
			(xy 423.490136 -365.83366) (xy 423.490622 -365.806409) (xy 423.498378 -365.752461) (xy 423.513733 -365.700166)
			(xy 423.536375 -365.650589) (xy 423.565841 -365.604739) (xy 423.601532 -365.563548) (xy 423.642723 -365.527857)
			(xy 423.688573 -365.498391) (xy 423.73815 -365.475749) (xy 423.790445 -365.460394) (xy 423.844393 -365.452638)
			(xy 423.898895 -365.452638) (xy 423.952843 -365.460394) (xy 424.005138 -365.475749) (xy 424.054715 -365.498391)
			(xy 424.100565 -365.527857) (xy 424.141756 -365.563548) (xy 424.177447 -365.604739) (xy 424.206913 -365.650589)
			(xy 424.229555 -365.700166) (xy 424.24491 -365.752461) (xy 424.252666 -365.806409) (xy 424.252812 -365.81461)
			(xy 425.115482 -365.81461) (xy 425.115968 -365.787359) (xy 425.123724 -365.733411) (xy 425.139079 -365.681116)
			(xy 425.161721 -365.631539) (xy 425.191187 -365.585689) (xy 425.226878 -365.544498) (xy 425.268069 -365.508807)
			(xy 425.313919 -365.479341) (xy 425.363496 -365.456699) (xy 425.415791 -365.441344) (xy 425.469739 -365.433588)
			(xy 425.524241 -365.433588) (xy 425.578189 -365.441344) (xy 425.630484 -365.456699) (xy 425.680061 -365.479341)
			(xy 425.725911 -365.508807) (xy 425.767102 -365.544498) (xy 425.802793 -365.585689) (xy 425.832259 -365.631539)
			(xy 425.854901 -365.681116) (xy 425.870256 -365.733411) (xy 425.878012 -365.787359) (xy 425.878498 -365.81461)
			(xy 425.878261 -365.833277) (xy 425.874571 -365.870429) (xy 425.871132 -365.888778) (xy 425.868794 -365.903046)
			(xy 425.871323 -365.931834) (xy 425.88182 -365.958759) (xy 425.899444 -365.981662) (xy 425.922781 -365.998707)
			(xy 425.94996 -366.008527) (xy 425.96435 -366.009936) (xy 425.993007 -366.012269) (xy 426.049173 -366.024563)
			(xy 426.10286 -366.045144) (xy 426.152851 -366.073546) (xy 426.198016 -366.109126) (xy 426.237332 -366.151079)
			(xy 426.26991 -366.198455) (xy 426.295011 -366.250182) (xy 426.312069 -366.305089) (xy 426.320697 -366.361934)
			(xy 426.32122 -366.390682) (xy 426.320734 -366.417933) (xy 426.312978 -366.471881) (xy 426.297623 -366.524176)
			(xy 426.274981 -366.573753) (xy 426.245515 -366.619603) (xy 426.209824 -366.660794) (xy 426.168633 -366.696485)
			(xy 426.122783 -366.725951) (xy 426.073206 -366.748593) (xy 426.020911 -366.763948) (xy 425.966963 -366.771704)
			(xy 425.912461 -366.771704) (xy 425.858513 -366.763948) (xy 425.806218 -366.748593) (xy 425.756641 -366.725951)
			(xy 425.710791 -366.696485) (xy 425.6696 -366.660794) (xy 425.633909 -366.619603) (xy 425.604443 -366.573753)
			(xy 425.581801 -366.524176) (xy 425.566446 -366.471881) (xy 425.55869 -366.417933) (xy 425.558204 -366.390682)
			(xy 425.55844 -366.372015) (xy 425.56213 -366.334863) (xy 425.56557 -366.316514) (xy 425.567914 -366.302247)
			(xy 425.565383 -366.273459) (xy 425.554885 -366.246533) (xy 425.53726 -366.22363) (xy 425.513922 -366.206585)
			(xy 425.486742 -366.196765) (xy 425.472352 -366.195356) (xy 425.443694 -366.19303) (xy 425.387527 -366.180735)
			(xy 425.33384 -366.160154) (xy 425.283849 -366.131752) (xy 425.238684 -366.096171) (xy 425.199367 -366.054217)
			(xy 425.16679 -366.00684) (xy 425.141688 -365.955112) (xy 425.124631 -365.900204) (xy 425.116004 -365.843358)
			(xy 425.115482 -365.81461) (xy 424.252812 -365.81461) (xy 424.253152 -365.83366) (xy 424.252665 -365.862107)
			(xy 424.244202 -365.918369) (xy 424.227473 -365.972748) (xy 424.20285 -366.024038) (xy 424.170879 -366.0711)
			(xy 424.13227 -366.112889) (xy 424.110404 -366.131094) (xy 424.098893 -366.140996) (xy 424.081878 -366.166131)
			(xy 424.072984 -366.19515) (xy 424.072992 -366.225502) (xy 424.081901 -366.254517) (xy 424.098929 -366.279643)
			(xy 424.110404 -366.28959) (xy 424.13228 -366.307781) (xy 424.170882 -366.349575) (xy 424.202845 -366.396641)
			(xy 424.227458 -366.447934) (xy 424.244176 -366.502315) (xy 424.246446 -366.517428) (xy 424.505626 -366.517428)
			(xy 424.509697 -366.461806) (xy 424.521823 -366.407369) (xy 424.541746 -366.355278) (xy 424.569042 -366.306643)
			(xy 424.603128 -366.2625) (xy 424.643277 -366.223791) (xy 424.688635 -366.19134) (xy 424.738235 -366.165839)
			(xy 424.791019 -366.147832) (xy 424.845862 -366.137702) (xy 424.901596 -366.135665) (xy 424.957033 -366.141765)
			(xy 425.01099 -366.155871) (xy 425.062319 -366.177683) (xy 425.109925 -366.206737) (xy 425.152793 -366.242412)
			(xy 425.19001 -366.283949) (xy 425.220783 -366.330462) (xy 425.244455 -366.380959) (xy 425.260523 -366.434366)
			(xy 425.268643 -366.489542) (xy 425.269152 -366.517428) (xy 425.268643 -366.545314) (xy 425.260523 -366.60049)
			(xy 425.244455 -366.653897) (xy 425.220783 -366.704394) (xy 425.19001 -366.750907) (xy 425.152793 -366.792444)
			(xy 425.109925 -366.828119) (xy 425.062319 -366.857173) (xy 425.01099 -366.878985) (xy 424.957033 -366.893091)
			(xy 424.901596 -366.899191) (xy 424.845862 -366.897154) (xy 424.791019 -366.887024) (xy 424.738235 -366.869017)
			(xy 424.688635 -366.843516) (xy 424.643277 -366.811065) (xy 424.603128 -366.772356) (xy 424.569042 -366.728213)
			(xy 424.541746 -366.679578) (xy 424.521823 -366.627487) (xy 424.509697 -366.57305) (xy 424.505626 -366.517428)
			(xy 424.246446 -366.517428) (xy 424.252627 -366.558577) (xy 424.253152 -366.587024) (xy 424.252666 -366.614275)
			(xy 424.24491 -366.668223) (xy 424.229555 -366.720518) (xy 424.206913 -366.770095) (xy 424.177447 -366.815945)
			(xy 424.141756 -366.857136) (xy 424.100565 -366.892827) (xy 424.054715 -366.922293) (xy 424.005138 -366.944935)
			(xy 423.952843 -366.96029) (xy 423.898895 -366.968046) (xy 423.844393 -366.968046) (xy 423.790445 -366.96029)
			(xy 423.73815 -366.944935) (xy 423.688573 -366.922293) (xy 423.642723 -366.892827) (xy 423.601532 -366.857136)
			(xy 423.565841 -366.815945) (xy 423.536375 -366.770095) (xy 423.513733 -366.720518) (xy 423.498378 -366.668223)
			(xy 423.490622 -366.614275) (xy 423.490136 -366.587024) (xy 416.57813 -366.587024) (xy 416.557193 -366.619603)
			(xy 416.521502 -366.660794) (xy 416.480311 -366.696485) (xy 416.434461 -366.725951) (xy 416.384884 -366.748593)
			(xy 416.332589 -366.763948) (xy 416.278641 -366.771704) (xy 416.224139 -366.771704) (xy 416.170191 -366.763948)
			(xy 416.117896 -366.748593) (xy 416.068319 -366.725951) (xy 416.022469 -366.696485) (xy 415.981278 -366.660794)
			(xy 415.945587 -366.619603) (xy 415.916121 -366.573753) (xy 415.893479 -366.524176) (xy 415.878124 -366.471881)
			(xy 415.870368 -366.417933) (xy 415.869882 -366.390682) (xy 415.870116 -366.372015) (xy 415.873808 -366.334863)
			(xy 415.877248 -366.316514) (xy 415.879613 -366.302249) (xy 415.877082 -366.273457) (xy 415.86658 -366.246528)
			(xy 415.848951 -366.223623) (xy 415.825608 -366.206579) (xy 415.798422 -366.196762) (xy 415.78403 -366.195356)
			(xy 415.755378 -366.192963) (xy 415.699213 -366.180679) (xy 415.645527 -366.160108) (xy 415.595534 -366.131715)
			(xy 415.550368 -366.096142) (xy 415.51105 -366.054196) (xy 415.478471 -366.006825) (xy 415.453368 -365.955102)
			(xy 415.43631 -365.900198) (xy 415.427682 -365.843356) (xy 415.42716 -365.81461) (xy 414.56449 -365.81461)
			(xy 414.56483 -365.83366) (xy 414.564387 -365.859976) (xy 414.557164 -365.91211) (xy 414.542848 -365.962758)
			(xy 414.521711 -366.01096) (xy 414.494155 -366.055802) (xy 414.4607 -366.096434) (xy 414.44164 -366.114584)
			(xy 414.431657 -366.124432) (xy 414.416951 -366.148293) (xy 414.409305 -366.175259) (xy 414.409298 -366.203287)
			(xy 414.416929 -366.230257) (xy 414.431622 -366.254126) (xy 414.44164 -366.263936) (xy 414.460725 -366.282065)
			(xy 414.494205 -366.322685) (xy 414.521776 -366.367527) (xy 414.542914 -366.415735) (xy 414.557217 -366.466394)
			(xy 414.564259 -366.517428) (xy 414.817304 -366.517428) (xy 414.821375 -366.461806) (xy 414.833501 -366.407369)
			(xy 414.853424 -366.355278) (xy 414.88072 -366.306643) (xy 414.914806 -366.2625) (xy 414.954955 -366.223791)
			(xy 415.000313 -366.19134) (xy 415.049913 -366.165839) (xy 415.102697 -366.147832) (xy 415.15754 -366.137702)
			(xy 415.213274 -366.135665) (xy 415.268711 -366.141765) (xy 415.322668 -366.155871) (xy 415.373997 -366.177683)
			(xy 415.421603 -366.206737) (xy 415.464471 -366.242412) (xy 415.501688 -366.283949) (xy 415.532461 -366.330462)
			(xy 415.556133 -366.380959) (xy 415.572201 -366.434366) (xy 415.580321 -366.489542) (xy 415.58083 -366.517428)
			(xy 415.580321 -366.545314) (xy 415.572201 -366.60049) (xy 415.556133 -366.653897) (xy 415.532461 -366.704394)
			(xy 415.501688 -366.750907) (xy 415.464471 -366.792444) (xy 415.421603 -366.828119) (xy 415.373997 -366.857173)
			(xy 415.322668 -366.878985) (xy 415.268711 -366.893091) (xy 415.213274 -366.899191) (xy 415.15754 -366.897154)
			(xy 415.102697 -366.887024) (xy 415.049913 -366.869017) (xy 415.000313 -366.843516) (xy 414.954955 -366.811065)
			(xy 414.914806 -366.772356) (xy 414.88072 -366.728213) (xy 414.853424 -366.679578) (xy 414.833501 -366.627487)
			(xy 414.821375 -366.57305) (xy 414.817304 -366.517428) (xy 414.564259 -366.517428) (xy 414.564412 -366.51854)
			(xy 414.56483 -366.54486) (xy 414.564344 -366.572111) (xy 414.556588 -366.626059) (xy 414.541233 -366.678354)
			(xy 414.518591 -366.727931) (xy 414.489125 -366.773781) (xy 414.453434 -366.814972) (xy 414.412243 -366.850663)
			(xy 414.366393 -366.880129) (xy 414.316816 -366.902771) (xy 414.264521 -366.918126) (xy 414.210573 -366.925882)
			(xy 414.156071 -366.925882) (xy 414.102123 -366.918126) (xy 414.049828 -366.902771) (xy 414.000251 -366.880129)
			(xy 413.954401 -366.850663) (xy 413.91321 -366.814972) (xy 413.877519 -366.773781) (xy 413.848053 -366.727931)
			(xy 413.825411 -366.678354) (xy 413.810056 -366.626059) (xy 413.8023 -366.572111) (xy 413.801814 -366.54486)
			(xy 411.43936 -366.54486) (xy 411.43936 -372.299218) (xy 413.591022 -372.299218) (xy 413.594749 -372.24597)
			(xy 413.605863 -372.193761) (xy 413.624146 -372.143611) (xy 413.649242 -372.096499) (xy 413.68066 -372.053346)
			(xy 413.717787 -372.014993) (xy 413.738568 -371.99824) (xy 413.750345 -371.988311) (xy 413.767866 -371.962997)
			(xy 413.777047 -371.933611) (xy 413.777053 -371.902825) (xy 413.767883 -371.873436) (xy 413.75037 -371.848116)
			(xy 413.738568 -371.83822) (xy 413.716087 -371.820026) (xy 413.676354 -371.778006) (xy 413.643415 -371.730471)
			(xy 413.618027 -371.678511) (xy 413.600769 -371.623314) (xy 413.592038 -371.566146) (xy 413.591502 -371.53723)
			(xy 413.591985 -371.50986) (xy 413.599799 -371.455682) (xy 413.615284 -371.403179) (xy 413.638122 -371.353432)
			(xy 413.667843 -371.307464) (xy 413.685482 -371.286532) (xy 413.694691 -371.275184) (xy 413.706874 -371.248634)
			(xy 413.711053 -371.219723) (xy 413.706887 -371.19081) (xy 413.694716 -371.164255) (xy 413.685482 -371.152928)
			(xy 413.667873 -371.131971) (xy 413.63815 -371.086006) (xy 413.615306 -371.036264) (xy 413.599809 -370.983766)
			(xy 413.591979 -370.929591) (xy 413.591975 -370.874854) (xy 413.599799 -370.820679) (xy 413.61529 -370.768179)
			(xy 413.638128 -370.718434) (xy 413.667845 -370.672466) (xy 413.685482 -370.651532) (xy 413.694691 -370.640184)
			(xy 413.706874 -370.613634) (xy 413.711053 -370.584723) (xy 413.706887 -370.55581) (xy 413.694716 -370.529255)
			(xy 413.685482 -370.517928) (xy 413.66784 -370.496999) (xy 413.638129 -370.451025) (xy 413.615294 -370.401277)
			(xy 413.599804 -370.348775) (xy 413.591976 -370.294599) (xy 413.591502 -370.26723) (xy 413.591983 -370.239977)
			(xy 413.599736 -370.186027) (xy 413.615089 -370.133728) (xy 413.637729 -370.084148) (xy 413.667195 -370.038294)
			(xy 413.702887 -369.997101) (xy 413.744078 -369.961407) (xy 413.78993 -369.931938) (xy 413.83951 -369.909296)
			(xy 413.891807 -369.893941) (xy 413.945757 -369.886185) (xy 413.97301 -369.885722) (xy 414.000381 -369.886177)
			(xy 414.05456 -369.893997) (xy 414.107064 -369.909488) (xy 414.156811 -369.932332) (xy 414.202777 -369.962059)
			(xy 414.223708 -369.979702) (xy 414.235036 -369.988938) (xy 414.261593 -370.001114) (xy 414.29051 -370.005287)
			(xy 414.319427 -370.001114) (xy 414.345984 -369.988938) (xy 414.357312 -369.979702) (xy 414.378267 -369.962091)
			(xy 414.424233 -369.932375) (xy 414.473975 -369.909533) (xy 414.526471 -369.894036) (xy 414.580642 -369.8862)
			(xy 414.60801 -369.885722) (xy 414.636925 -369.886297) (xy 414.694094 -369.895013) (xy 414.749292 -369.912259)
			(xy 414.801254 -369.93764) (xy 414.848789 -369.970574) (xy 414.890808 -370.010307) (xy 414.909 -370.032788)
			(xy 414.918897 -370.044593) (xy 414.944221 -370.062112) (xy 414.973614 -370.071288) (xy 415.004406 -370.071288)
			(xy 415.033799 -370.062112) (xy 415.059123 -370.044593) (xy 415.06902 -370.032788) (xy 415.087197 -370.010292)
			(xy 415.12922 -369.970559) (xy 415.176758 -369.937621) (xy 415.228722 -369.912235) (xy 415.283922 -369.894981)
			(xy 415.341093 -369.886255) (xy 415.37001 -369.885722) (xy 415.397264 -369.886146) (xy 415.451218 -369.893905)
			(xy 415.503519 -369.909264) (xy 415.553101 -369.931909) (xy 415.598956 -369.961381) (xy 415.640149 -369.997079)
			(xy 415.675843 -370.038276) (xy 415.70531 -370.084134) (xy 415.72795 -370.133719) (xy 415.743304 -370.186021)
			(xy 415.751057 -370.239975) (xy 415.751518 -370.26723) (xy 415.75109 -370.294602) (xy 415.743266 -370.348783)
			(xy 415.727769 -370.401288) (xy 415.704918 -370.451034) (xy 415.675184 -370.496998) (xy 415.657538 -370.517928)
			(xy 415.648269 -370.529232) (xy 415.636091 -370.555798) (xy 415.631922 -370.584723) (xy 415.636104 -370.613646)
			(xy 415.648294 -370.640206) (xy 415.657538 -370.651532) (xy 415.67521 -370.67244) (xy 415.704936 -370.718411)
			(xy 415.727782 -370.768162) (xy 415.743277 -370.820668) (xy 415.751104 -370.87485) (xy 415.7511 -370.929595)
			(xy 415.743267 -370.983777) (xy 415.727766 -371.036281) (xy 415.704914 -371.086028) (xy 415.675182 -371.131996)
			(xy 415.657538 -371.152928) (xy 415.648269 -371.164232) (xy 415.636091 -371.190798) (xy 415.631922 -371.219723)
			(xy 415.636104 -371.248646) (xy 415.648294 -371.275206) (xy 415.657538 -371.286532) (xy 415.675165 -371.307474)
			(xy 415.704877 -371.353444) (xy 415.727715 -371.40319) (xy 415.743209 -371.455688) (xy 415.751042 -371.509862)
			(xy 415.751518 -371.53723) (xy 415.75098 -371.566147) (xy 415.74226 -371.623318) (xy 415.725008 -371.678518)
			(xy 415.69962 -371.730481) (xy 415.666678 -371.778015) (xy 415.626937 -371.820031) (xy 415.604452 -371.83822)
			(xy 415.592613 -371.848083) (xy 415.575089 -371.873414) (xy 415.565913 -371.902817) (xy 415.565919 -371.933619)
			(xy 415.575106 -371.963019) (xy 415.592639 -371.988344) (xy 415.604452 -371.99824) (xy 415.625264 -372.014958)
			(xy 415.662394 -372.053316) (xy 415.693814 -372.096475) (xy 415.718912 -372.143593) (xy 415.737196 -372.193749)
			(xy 415.748311 -372.245964) (xy 415.75026 -372.273818) (xy 416.956522 -372.273818) (xy 416.960249 -372.22057)
			(xy 416.971363 -372.168361) (xy 416.989646 -372.118211) (xy 417.014742 -372.071099) (xy 417.04616 -372.027946)
			(xy 417.083287 -371.989593) (xy 417.104068 -371.97284) (xy 417.115845 -371.962911) (xy 417.133366 -371.937597)
			(xy 417.142547 -371.908211) (xy 417.142553 -371.877425) (xy 417.133383 -371.848036) (xy 417.11587 -371.822716)
			(xy 417.104068 -371.81282) (xy 417.081587 -371.794626) (xy 417.041854 -371.752606) (xy 417.008915 -371.705071)
			(xy 416.983527 -371.653111) (xy 416.966269 -371.597914) (xy 416.957538 -371.540746) (xy 416.957002 -371.51183)
			(xy 416.957485 -371.48446) (xy 416.965299 -371.430282) (xy 416.980784 -371.377779) (xy 417.003622 -371.328032)
			(xy 417.033343 -371.282064) (xy 417.050982 -371.261132) (xy 417.060191 -371.249784) (xy 417.072374 -371.223234)
			(xy 417.076553 -371.194323) (xy 417.072387 -371.16541) (xy 417.060216 -371.138855) (xy 417.050982 -371.127528)
			(xy 417.033373 -371.106571) (xy 417.00365 -371.060606) (xy 416.980806 -371.010864) (xy 416.965309 -370.958366)
			(xy 416.957479 -370.904191) (xy 416.957475 -370.849454) (xy 416.965299 -370.795279) (xy 416.98079 -370.742779)
			(xy 417.003628 -370.693034) (xy 417.033345 -370.647066) (xy 417.050982 -370.626132) (xy 417.060191 -370.614784)
			(xy 417.072374 -370.588234) (xy 417.076553 -370.559323) (xy 417.072387 -370.53041) (xy 417.060216 -370.503855)
			(xy 417.050982 -370.492528) (xy 417.03334 -370.471599) (xy 417.003629 -370.425625) (xy 416.980794 -370.375877)
			(xy 416.965304 -370.323375) (xy 416.957476 -370.269199) (xy 416.957002 -370.24183) (xy 416.957488 -370.214579)
			(xy 416.965244 -370.160631) (xy 416.980599 -370.108336) (xy 417.003241 -370.058759) (xy 417.032707 -370.012909)
			(xy 417.068398 -369.971718) (xy 417.109589 -369.936027) (xy 417.155439 -369.906561) (xy 417.205016 -369.883919)
			(xy 417.257311 -369.868564) (xy 417.311259 -369.860808) (xy 417.365761 -369.860808) (xy 417.419709 -369.868564)
			(xy 417.472004 -369.883919) (xy 417.521581 -369.906561) (xy 417.567431 -369.936027) (xy 417.608622 -369.971718)
			(xy 417.644313 -370.012909) (xy 417.669658 -370.052346) (xy 419.301422 -370.052346) (xy 419.301948 -370.023176)
			(xy 419.310856 -369.96552) (xy 419.32844 -369.909892) (xy 419.35429 -369.857592) (xy 419.387803 -369.809837)
			(xy 419.428198 -369.767744) (xy 419.451028 -369.749578) (xy 419.461394 -369.741142) (xy 419.47769 -369.719968)
			(xy 419.487936 -369.695292) (xy 419.491432 -369.668804) (xy 419.487938 -369.642315) (xy 419.477693 -369.617638)
			(xy 419.4614 -369.596464) (xy 419.451028 -369.588034) (xy 419.428198 -369.569867) (xy 419.387796 -369.527782)
			(xy 419.35428 -369.480029) (xy 419.328434 -369.427727) (xy 419.310862 -369.372096) (xy 419.301975 -369.314436)
			(xy 419.301422 -369.285266) (xy 419.301846 -369.258013) (xy 419.309608 -369.204061) (xy 419.324969 -369.151763)
			(xy 419.347616 -369.102184) (xy 419.377089 -369.056332) (xy 419.412787 -369.015142) (xy 419.453984 -368.979451)
			(xy 419.49984 -368.949986) (xy 419.549423 -368.927347) (xy 419.601724 -368.911995) (xy 419.655676 -368.904242)
			(xy 419.68293 -368.903758) (xy 419.711846 -368.904305) (xy 419.769017 -368.913025) (xy 419.824216 -368.930276)
			(xy 419.876178 -368.955662) (xy 419.923713 -368.988602) (xy 419.96573 -369.02834) (xy 419.98392 -369.050824)
			(xy 419.993817 -369.062629) (xy 420.019141 -369.080148) (xy 420.048534 -369.089324) (xy 420.079326 -369.089324)
			(xy 420.108719 -369.080148) (xy 420.134043 -369.062629) (xy 420.14394 -369.050824) (xy 420.162115 -369.028326)
			(xy 420.204137 -368.988591) (xy 420.251675 -368.955653) (xy 420.30364 -368.930267) (xy 420.358841 -368.913014)
			(xy 420.416013 -368.90429) (xy 420.44493 -368.903758) (xy 420.473478 -368.904268) (xy 420.529933 -368.912792)
			(xy 420.584489 -368.929632) (xy 420.635927 -368.95441) (xy 420.659814 -368.970052) (xy 420.670957 -368.977114)
			(xy 420.69581 -368.985923) (xy 420.722092 -368.988052) (xy 420.748038 -368.983358) (xy 420.771908 -368.972156)
			(xy 420.792099 -368.955198) (xy 420.800022 -368.944652) (xy 420.815446 -368.923649) (xy 420.851043 -368.885595)
			(xy 420.891486 -368.852737) (xy 420.936022 -368.825686) (xy 420.983824 -368.804944) (xy 421.034003 -368.790897)
			(xy 421.085626 -368.783806) (xy 421.11168 -368.783362) (xy 421.140598 -368.783871) (xy 421.19777 -368.792599)
			(xy 421.25297 -368.809857) (xy 421.304932 -368.83525) (xy 421.352466 -368.868197) (xy 421.394481 -368.907941)
			(xy 421.41267 -368.930428) (xy 421.422567 -368.942233) (xy 421.447891 -368.959752) (xy 421.477284 -368.968928)
			(xy 421.508076 -368.968928) (xy 421.537469 -368.959752) (xy 421.562793 -368.942233) (xy 421.57269 -368.930428)
			(xy 421.590894 -368.907955) (xy 421.63291 -368.868218) (xy 421.680442 -368.835277) (xy 421.732401 -368.809886)
			(xy 421.787597 -368.792628) (xy 421.844765 -368.783898) (xy 421.87368 -368.783362) (xy 421.900929 -368.783897)
			(xy 421.954874 -368.79165) (xy 422.007166 -368.807001) (xy 422.056741 -368.829637) (xy 422.10259 -368.859099)
			(xy 422.143779 -368.894785) (xy 422.179471 -368.93597) (xy 422.208939 -368.981815) (xy 422.231582 -369.031387)
			(xy 422.24694 -369.083677) (xy 422.2547 -369.137621) (xy 422.255188 -369.16487) (xy 422.254738 -369.190913)
			(xy 422.247655 -369.242514) (xy 422.233618 -369.292672) (xy 422.212886 -369.340454) (xy 422.185846 -369.384971)
			(xy 422.153001 -369.425395) (xy 422.134284 -369.443508) (xy 422.124324 -369.453453) (xy 422.109861 -369.477587)
			(xy 422.102521 -369.504749) (xy 422.102859 -369.532884) (xy 422.110849 -369.559862) (xy 422.125888 -369.583642)
			(xy 422.136062 -369.593368) (xy 422.155664 -369.611509) (xy 422.190054 -369.652374) (xy 422.218408 -369.697637)
			(xy 422.240172 -369.746412) (xy 422.25492 -369.797746) (xy 422.262364 -369.850635) (xy 422.262808 -369.87734)
			(xy 422.262337 -369.905111) (xy 422.254279 -369.960065) (xy 422.238337 -370.01327) (xy 422.214849 -370.063601)
			(xy 422.184312 -370.109994) (xy 422.147371 -370.15147) (xy 422.12641 -370.169694) (xy 422.115726 -370.179181)
			(xy 422.099744 -370.202854) (xy 422.090956 -370.230032) (xy 422.090053 -370.258581) (xy 422.097104 -370.28626)
			(xy 422.111557 -370.310897) (xy 422.121584 -370.321078) (xy 422.139964 -370.339133) (xy 422.172132 -370.37938)
			(xy 422.198597 -370.423587) (xy 422.218876 -370.470952) (xy 422.232603 -370.520613) (xy 422.239527 -370.571668)
			(xy 422.239948 -370.59743) (xy 422.239512 -370.624801) (xy 422.231689 -370.678982) (xy 422.216194 -370.731486)
			(xy 422.193345 -370.781233) (xy 422.163613 -370.827198) (xy 422.145968 -370.848128) (xy 422.136705 -370.859435)
			(xy 422.124535 -370.886001) (xy 422.120369 -370.914923) (xy 422.124548 -370.943843) (xy 422.136729 -370.970403)
			(xy 422.145968 -370.981732) (xy 422.163638 -371.002641) (xy 422.193362 -371.048613) (xy 422.216206 -371.098363)
			(xy 422.2317 -371.150869) (xy 422.239526 -371.20505) (xy 422.239523 -371.259795) (xy 422.231691 -371.313976)
			(xy 422.21619 -371.36648) (xy 422.19334 -371.416227) (xy 422.163611 -371.462195) (xy 422.145968 -371.483128)
			(xy 422.136705 -371.494435) (xy 422.124535 -371.521001) (xy 422.120369 -371.549923) (xy 422.124548 -371.578843)
			(xy 422.136729 -371.605403) (xy 422.145968 -371.616732) (xy 422.163638 -371.637641) (xy 422.193362 -371.683613)
			(xy 422.216206 -371.733363) (xy 422.2317 -371.785869) (xy 422.235289 -371.810718) (xy 423.31665 -371.810718)
			(xy 423.31665 -371.726022) (xy 423.324701 -371.641708) (xy 423.34073 -371.558542) (xy 423.364591 -371.477275)
			(xy 423.39607 -371.398645) (xy 423.434881 -371.323364) (xy 423.480671 -371.252112) (xy 423.533027 -371.185536)
			(xy 423.591475 -371.124238) (xy 423.655485 -371.068773) (xy 423.724477 -371.019644) (xy 423.797827 -370.977295)
			(xy 423.87487 -370.942111) (xy 423.954909 -370.914409) (xy 424.037218 -370.894441) (xy 424.121053 -370.882388)
			(xy 424.205654 -370.878358) (xy 424.290255 -370.882388) (xy 424.37409 -370.894441) (xy 424.456399 -370.914409)
			(xy 424.536438 -370.942111) (xy 424.613481 -370.977295) (xy 424.686831 -371.019644) (xy 424.755823 -371.068773)
			(xy 424.819833 -371.124238) (xy 424.878281 -371.185536) (xy 424.930637 -371.252112) (xy 424.976427 -371.323364)
			(xy 425.015238 -371.398645) (xy 425.046717 -371.477275) (xy 425.070578 -371.558542) (xy 425.086607 -371.641708)
			(xy 425.094658 -371.726022) (xy 425.095162 -371.76837) (xy 425.841163 -371.76837) (xy 425.845199 -371.684923)
			(xy 425.857271 -371.602255) (xy 425.877264 -371.521138) (xy 425.904993 -371.442329) (xy 425.940199 -371.366564)
			(xy 425.982553 -371.294551) (xy 426.031659 -371.226962) (xy 426.08706 -371.164428) (xy 426.148237 -371.107533)
			(xy 426.21462 -371.056807) (xy 426.285588 -371.012726) (xy 426.36048 -370.9757) (xy 426.438596 -370.946074)
			(xy 426.519206 -370.924126) (xy 426.601558 -370.910061) (xy 426.684884 -370.904009) (xy 426.768404 -370.906028)
			(xy 426.85134 -370.916098) (xy 426.932916 -370.934126) (xy 427.012372 -370.959943) (xy 427.088965 -370.993308)
			(xy 427.161981 -371.033909) (xy 427.230737 -371.081368) (xy 427.294591 -371.135241) (xy 427.352948 -371.195026)
			(xy 427.405263 -371.260163) (xy 427.451046 -371.330046) (xy 427.489871 -371.404021) (xy 427.521376 -371.481398)
			(xy 427.545265 -371.561455) (xy 427.561316 -371.643443) (xy 427.569379 -371.726598) (xy 427.569884 -371.76837)
			(xy 427.569379 -371.810142) (xy 427.561316 -371.893297) (xy 427.545265 -371.975285) (xy 427.521376 -372.055342)
			(xy 427.489871 -372.132719) (xy 427.451046 -372.206694) (xy 427.405263 -372.276577) (xy 427.352948 -372.341714)
			(xy 427.294591 -372.401499) (xy 427.230737 -372.455372) (xy 427.161981 -372.502831) (xy 427.088965 -372.543432)
			(xy 427.012372 -372.576797) (xy 426.932916 -372.602614) (xy 426.85134 -372.620642) (xy 426.768404 -372.630712)
			(xy 426.684884 -372.632731) (xy 426.601558 -372.626679) (xy 426.519206 -372.612614) (xy 426.438596 -372.590666)
			(xy 426.36048 -372.56104) (xy 426.285588 -372.524014) (xy 426.21462 -372.479933) (xy 426.148237 -372.429207)
			(xy 426.08706 -372.372312) (xy 426.031659 -372.309778) (xy 425.982553 -372.242189) (xy 425.940199 -372.170176)
			(xy 425.904993 -372.094411) (xy 425.877264 -372.015602) (xy 425.857271 -371.934485) (xy 425.845199 -371.851817)
			(xy 425.841163 -371.76837) (xy 425.095162 -371.76837) (xy 425.094658 -371.810718) (xy 425.086607 -371.895032)
			(xy 425.070578 -371.978198) (xy 425.046717 -372.059465) (xy 425.015238 -372.138095) (xy 424.976427 -372.213376)
			(xy 424.930637 -372.284628) (xy 424.878281 -372.351204) (xy 424.819833 -372.412502) (xy 424.755823 -372.467967)
			(xy 424.686831 -372.517096) (xy 424.613481 -372.559445) (xy 424.536438 -372.594629) (xy 424.456399 -372.622331)
			(xy 424.37409 -372.642299) (xy 424.290255 -372.654352) (xy 424.205654 -372.658383) (xy 424.121053 -372.654352)
			(xy 424.037218 -372.642299) (xy 423.954909 -372.622331) (xy 423.87487 -372.594629) (xy 423.797827 -372.559445)
			(xy 423.724477 -372.517096) (xy 423.655485 -372.467967) (xy 423.591475 -372.412502) (xy 423.533027 -372.351204)
			(xy 423.480671 -372.284628) (xy 423.434881 -372.213376) (xy 423.39607 -372.138095) (xy 423.364591 -372.059465)
			(xy 423.34073 -371.978198) (xy 423.324701 -371.895032) (xy 423.31665 -371.810718) (xy 422.235289 -371.810718)
			(xy 422.239526 -371.84005) (xy 422.239523 -371.894795) (xy 422.231691 -371.948976) (xy 422.21619 -372.00148)
			(xy 422.19334 -372.051227) (xy 422.163611 -372.097195) (xy 422.145968 -372.118128) (xy 422.136705 -372.129435)
			(xy 422.124535 -372.156001) (xy 422.120369 -372.184923) (xy 422.124548 -372.213843) (xy 422.136729 -372.240403)
			(xy 422.145968 -372.251732) (xy 422.163584 -372.272683) (xy 422.1933 -372.31865) (xy 422.216141 -372.368393)
			(xy 422.231638 -372.420889) (xy 422.239471 -372.475062) (xy 422.239948 -372.50243) (xy 422.23945 -372.52968)
			(xy 422.231691 -372.583625) (xy 422.216334 -372.635917) (xy 422.193692 -372.685492) (xy 422.164226 -372.73134)
			(xy 422.128536 -372.772529) (xy 422.087348 -372.80822) (xy 422.041501 -372.837687) (xy 421.991927 -372.86033)
			(xy 421.939635 -372.875689) (xy 421.88569 -372.88345) (xy 421.85844 -372.883938) (xy 421.829523 -372.883415)
			(xy 421.772351 -372.87469) (xy 421.717151 -372.857435) (xy 421.665189 -372.832044) (xy 421.617655 -372.7991)
			(xy 421.575639 -372.759358) (xy 421.55745 -372.736872) (xy 421.547553 -372.725067) (xy 421.522229 -372.707548)
			(xy 421.492836 -372.698372) (xy 421.462044 -372.698372) (xy 421.432651 -372.707548) (xy 421.407327 -372.725067)
			(xy 421.39743 -372.736872) (xy 421.379215 -372.759335) (xy 421.337201 -372.799073) (xy 421.289671 -372.832015)
			(xy 421.237715 -372.857407) (xy 421.182521 -372.874668) (xy 421.125355 -372.883401) (xy 421.09644 -372.883938)
			(xy 421.069189 -372.883408) (xy 421.015243 -372.875657) (xy 420.962948 -372.860307) (xy 420.91337 -372.837672)
			(xy 420.867518 -372.808211) (xy 420.826326 -372.772524) (xy 420.790631 -372.731338) (xy 420.761162 -372.685492)
			(xy 420.738517 -372.635918) (xy 420.723158 -372.583626) (xy 420.715397 -372.52968) (xy 420.714932 -372.50243)
			(xy 420.715408 -372.47506) (xy 420.723222 -372.420881) (xy 420.738708 -372.368378) (xy 420.761548 -372.318631)
			(xy 420.791271 -372.272664) (xy 420.808912 -372.251732) (xy 420.818119 -372.240383) (xy 420.830298 -372.213833)
			(xy 420.834476 -372.184923) (xy 420.830311 -372.156011) (xy 420.818144 -372.129455) (xy 420.808912 -372.118128)
			(xy 420.791301 -372.097171) (xy 420.761576 -372.051207) (xy 420.73873 -372.001465) (xy 420.723232 -371.948967)
			(xy 420.715401 -371.894792) (xy 420.715398 -371.840054) (xy 420.723223 -371.785878) (xy 420.738714 -371.733378)
			(xy 420.761555 -371.683632) (xy 420.791274 -371.637665) (xy 420.808912 -371.616732) (xy 420.818119 -371.605383)
			(xy 420.830298 -371.578833) (xy 420.834476 -371.549923) (xy 420.830311 -371.521011) (xy 420.818144 -371.494455)
			(xy 420.808912 -371.483128) (xy 420.791301 -371.462171) (xy 420.761576 -371.416207) (xy 420.73873 -371.366465)
			(xy 420.723232 -371.313967) (xy 420.715401 -371.259792) (xy 420.715398 -371.205054) (xy 420.723223 -371.150878)
			(xy 420.738714 -371.098378) (xy 420.761555 -371.048632) (xy 420.791274 -371.002665) (xy 420.808912 -370.981732)
			(xy 420.818119 -370.970383) (xy 420.830298 -370.943833) (xy 420.834476 -370.914923) (xy 420.830311 -370.886011)
			(xy 420.818144 -370.859455) (xy 420.808912 -370.848128) (xy 420.791274 -370.827195) (xy 420.761562 -370.781222)
			(xy 420.738726 -370.731475) (xy 420.723234 -370.678975) (xy 420.715406 -370.624799) (xy 420.714932 -370.59743)
			(xy 420.71516 -370.578375) (xy 420.718982 -370.540457) (xy 420.722552 -370.521738) (xy 420.724834 -370.508255)
			(xy 420.723002 -370.480984) (xy 420.713998 -370.455177) (xy 420.698467 -370.432685) (xy 420.677525 -370.41512)
			(xy 420.652672 -370.403744) (xy 420.625691 -370.399371) (xy 420.598517 -370.402315) (xy 420.585646 -370.40693)
			(xy 420.563174 -370.415447) (xy 420.516636 -370.42744) (xy 420.468959 -370.433487) (xy 420.44493 -370.433854)
			(xy 420.416013 -370.433332) (xy 420.358841 -370.424606) (xy 420.303642 -370.40735) (xy 420.25168 -370.381959)
			(xy 420.204146 -370.349015) (xy 420.16213 -370.309274) (xy 420.14394 -370.286788) (xy 420.134043 -370.274983)
			(xy 420.108719 -370.257464) (xy 420.079326 -370.248288) (xy 420.048534 -370.248288) (xy 420.019141 -370.257464)
			(xy 419.993817 -370.274983) (xy 419.98392 -370.286788) (xy 419.965715 -370.309259) (xy 419.923698 -370.348996)
			(xy 419.876166 -370.381937) (xy 419.824208 -370.407327) (xy 419.769013 -370.424586) (xy 419.711845 -370.433318)
			(xy 419.68293 -370.433854) (xy 419.655682 -370.433294) (xy 419.601739 -370.425543) (xy 419.549448 -370.410194)
			(xy 419.499874 -370.387559) (xy 419.454026 -370.358101) (xy 419.412837 -370.322417) (xy 419.377145 -370.281235)
			(xy 419.347677 -370.235392) (xy 419.325033 -370.185823) (xy 419.309673 -370.133535) (xy 419.301911 -370.079594)
			(xy 419.301422 -370.052346) (xy 417.669658 -370.052346) (xy 417.673779 -370.058759) (xy 417.696421 -370.108336)
			(xy 417.711776 -370.160631) (xy 417.719532 -370.214579) (xy 417.720018 -370.24183) (xy 417.71959 -370.269202)
			(xy 417.711766 -370.323383) (xy 417.696269 -370.375888) (xy 417.673418 -370.425634) (xy 417.643684 -370.471598)
			(xy 417.626038 -370.492528) (xy 417.616769 -370.503832) (xy 417.604591 -370.530398) (xy 417.600422 -370.559323)
			(xy 417.604604 -370.588246) (xy 417.616794 -370.614806) (xy 417.626038 -370.626132) (xy 417.64371 -370.64704)
			(xy 417.673436 -370.693011) (xy 417.696282 -370.742762) (xy 417.711777 -370.795268) (xy 417.719604 -370.84945)
			(xy 417.7196 -370.904195) (xy 417.711767 -370.958377) (xy 417.696266 -371.010881) (xy 417.673414 -371.060628)
			(xy 417.643682 -371.106596) (xy 417.626038 -371.127528) (xy 417.616769 -371.138832) (xy 417.604591 -371.165398)
			(xy 417.600422 -371.194323) (xy 417.604604 -371.223246) (xy 417.616794 -371.249806) (xy 417.626038 -371.261132)
			(xy 417.643665 -371.282074) (xy 417.673377 -371.328044) (xy 417.696215 -371.37779) (xy 417.711709 -371.430288)
			(xy 417.719542 -371.484462) (xy 417.720018 -371.51183) (xy 417.71948 -371.540747) (xy 417.71076 -371.597918)
			(xy 417.693508 -371.653118) (xy 417.66812 -371.705081) (xy 417.635178 -371.752615) (xy 417.595437 -371.794631)
			(xy 417.572952 -371.81282) (xy 417.561113 -371.822683) (xy 417.543589 -371.848014) (xy 417.534413 -371.877417)
			(xy 417.534419 -371.908219) (xy 417.543606 -371.937619) (xy 417.561139 -371.962944) (xy 417.572952 -371.97284)
			(xy 417.593764 -371.989558) (xy 417.630894 -372.027916) (xy 417.662314 -372.071075) (xy 417.687412 -372.118193)
			(xy 417.705696 -372.168349) (xy 417.716811 -372.220564) (xy 417.720538 -372.273818) (xy 417.716805 -372.327073)
			(xy 417.705686 -372.379287) (xy 417.687397 -372.429441) (xy 417.662295 -372.476556) (xy 417.63087 -372.519712)
			(xy 417.593737 -372.558066) (xy 417.572952 -372.57482) (xy 417.561113 -372.584683) (xy 417.543589 -372.610014)
			(xy 417.534413 -372.639417) (xy 417.534419 -372.670219) (xy 417.543606 -372.699619) (xy 417.561139 -372.724944)
			(xy 417.572952 -372.73484) (xy 417.595465 -372.752995) (xy 417.635196 -372.795024) (xy 417.66813 -372.842567)
			(xy 417.693513 -372.894535) (xy 417.710763 -372.949738) (xy 417.719486 -373.006912) (xy 417.720018 -373.03583)
			(xy 417.719532 -373.063081) (xy 417.711776 -373.117029) (xy 417.696421 -373.169324) (xy 417.673779 -373.218901)
			(xy 417.644313 -373.264751) (xy 417.608622 -373.305942) (xy 417.567431 -373.341633) (xy 417.521581 -373.371099)
			(xy 417.472004 -373.393741) (xy 417.419709 -373.409096) (xy 417.365761 -373.416852) (xy 417.311259 -373.416852)
			(xy 417.257311 -373.409096) (xy 417.205016 -373.393741) (xy 417.155439 -373.371099) (xy 417.109589 -373.341633)
			(xy 417.068398 -373.305942) (xy 417.032707 -373.264751) (xy 417.003241 -373.218901) (xy 416.980599 -373.169324)
			(xy 416.965244 -373.117029) (xy 416.957488 -373.063081) (xy 416.957002 -373.03583) (xy 416.957541 -373.006914)
			(xy 416.966266 -372.949744) (xy 416.98352 -372.894545) (xy 417.008907 -372.842583) (xy 417.041847 -372.795049)
			(xy 417.081584 -372.753031) (xy 417.104068 -372.73484) (xy 417.115845 -372.724911) (xy 417.133366 -372.699597)
			(xy 417.142547 -372.670211) (xy 417.142553 -372.639425) (xy 417.133383 -372.610036) (xy 417.11587 -372.584716)
			(xy 417.104068 -372.57482) (xy 417.083314 -372.558031) (xy 417.046184 -372.519683) (xy 417.014761 -372.476532)
			(xy 416.989661 -372.429423) (xy 416.971373 -372.379275) (xy 416.960254 -372.327067) (xy 416.956522 -372.273818)
			(xy 415.75026 -372.273818) (xy 415.752038 -372.299218) (xy 415.748305 -372.352473) (xy 415.737186 -372.404687)
			(xy 415.718897 -372.454841) (xy 415.693795 -372.501956) (xy 415.66237 -372.545112) (xy 415.625237 -372.583466)
			(xy 415.604452 -372.60022) (xy 415.592613 -372.610083) (xy 415.575089 -372.635414) (xy 415.565913 -372.664817)
			(xy 415.565919 -372.695619) (xy 415.575106 -372.725019) (xy 415.592639 -372.750344) (xy 415.604452 -372.76024)
			(xy 415.626965 -372.778395) (xy 415.666696 -372.820424) (xy 415.69963 -372.867967) (xy 415.725013 -372.919935)
			(xy 415.742263 -372.975138) (xy 415.750986 -373.032312) (xy 415.751518 -373.06123) (xy 415.75105 -373.088482)
			(xy 415.74329 -373.142429) (xy 415.727931 -373.194724) (xy 415.705287 -373.244301) (xy 415.675819 -373.29015)
			(xy 415.640126 -373.33134) (xy 415.598934 -373.367031) (xy 415.553083 -373.396497) (xy 415.503505 -373.419138)
			(xy 415.45121 -373.434494) (xy 415.397262 -373.442252) (xy 415.37001 -373.442738) (xy 415.341092 -373.442236)
			(xy 415.283919 -373.433507) (xy 415.228719 -373.416247) (xy 415.176757 -373.390853) (xy 415.129224 -373.357905)
			(xy 415.087209 -373.31816) (xy 415.06902 -373.295672) (xy 415.059123 -373.283867) (xy 415.033799 -373.266348)
			(xy 415.004406 -373.257172) (xy 414.973614 -373.257172) (xy 414.944221 -373.266348) (xy 414.918897 -373.283867)
			(xy 414.909 -373.295672) (xy 414.890802 -373.31815) (xy 414.848784 -373.357886) (xy 414.801251 -373.390827)
			(xy 414.749291 -373.416217) (xy 414.694095 -373.433474) (xy 414.636926 -373.442203) (xy 414.60801 -373.442738)
			(xy 414.580639 -373.442281) (xy 414.526459 -373.434463) (xy 414.473955 -373.418973) (xy 414.424209 -373.396129)
			(xy 414.378243 -373.366401) (xy 414.357312 -373.348758) (xy 414.345984 -373.339522) (xy 414.319427 -373.327346)
			(xy 414.29051 -373.323173) (xy 414.261593 -373.327346) (xy 414.235036 -373.339522) (xy 414.223708 -373.348758)
			(xy 414.202778 -373.3664) (xy 414.156806 -373.396113) (xy 414.107058 -373.418949) (xy 414.054556 -373.434439)
			(xy 414.000379 -373.442265) (xy 413.97301 -373.442738) (xy 413.94576 -373.442213) (xy 413.891816 -373.434458)
			(xy 413.839524 -373.419106) (xy 413.789948 -373.396468) (xy 413.744099 -373.367006) (xy 413.70291 -373.331318)
			(xy 413.667218 -373.290133) (xy 413.637751 -373.244287) (xy 413.615108 -373.194714) (xy 413.59975 -373.142423)
			(xy 413.59199 -373.08848) (xy 413.591502 -373.06123) (xy 413.592041 -373.032314) (xy 413.600766 -372.975144)
			(xy 413.61802 -372.919945) (xy 413.643407 -372.867983) (xy 413.676347 -372.820449) (xy 413.716084 -372.778431)
			(xy 413.738568 -372.76024) (xy 413.750345 -372.750311) (xy 413.767866 -372.724997) (xy 413.777047 -372.695611)
			(xy 413.777053 -372.664825) (xy 413.767883 -372.635436) (xy 413.75037 -372.610116) (xy 413.738568 -372.60022)
			(xy 413.717814 -372.583431) (xy 413.680684 -372.545083) (xy 413.649261 -372.501932) (xy 413.624161 -372.454823)
			(xy 413.605873 -372.404675) (xy 413.594754 -372.352467) (xy 413.591022 -372.299218) (xy 411.43936 -372.299218)
			(xy 411.43936 -373.953278) (xy 411.819134 -374.333052) (xy 416.088785 -374.333052) (xy 416.088785 -374.278548)
			(xy 416.096542 -374.224599) (xy 416.111899 -374.172302) (xy 416.134542 -374.122724) (xy 416.16401 -374.076873)
			(xy 416.199704 -374.035683) (xy 416.240897 -373.999992) (xy 416.286751 -373.970527) (xy 416.336331 -373.947888)
			(xy 416.388628 -373.932536) (xy 416.442578 -373.924783) (xy 416.46983 -373.924322) (xy 416.498745 -373.924882)
			(xy 416.555915 -373.933601) (xy 416.611113 -373.95085) (xy 416.663076 -373.976234) (xy 416.710611 -374.009171)
			(xy 416.752629 -374.048905) (xy 416.77082 -374.071388) (xy 416.780717 -374.083193) (xy 416.806041 -374.100712)
			(xy 416.835434 -374.109888) (xy 416.866226 -374.109888) (xy 416.895619 -374.100712) (xy 416.920943 -374.083193)
			(xy 416.93084 -374.071388) (xy 416.949005 -374.048883) (xy 416.991031 -374.00915) (xy 417.038571 -373.976213)
			(xy 417.090537 -373.950829) (xy 417.145739 -373.933577) (xy 417.202913 -373.924854) (xy 417.23183 -373.924322)
			(xy 417.259082 -373.92475) (xy 417.313031 -373.93251) (xy 417.365326 -373.947869) (xy 417.414903 -373.970514)
			(xy 417.460754 -373.999983) (xy 417.501943 -374.035678) (xy 417.537635 -374.07687) (xy 417.5671 -374.122723)
			(xy 417.589741 -374.172302) (xy 417.605096 -374.224599) (xy 417.612852 -374.278548) (xy 417.612852 -374.333052)
			(xy 417.605096 -374.387001) (xy 417.589741 -374.439298) (xy 417.5671 -374.488877) (xy 417.537635 -374.53473)
			(xy 417.501943 -374.575922) (xy 417.460754 -374.611617) (xy 417.414903 -374.641086) (xy 417.365326 -374.663731)
			(xy 417.313031 -374.67909) (xy 417.259082 -374.68685) (xy 417.23183 -374.687338) (xy 417.202913 -374.686822)
			(xy 417.14574 -374.678096) (xy 417.09054 -374.660839) (xy 417.038578 -374.635447) (xy 416.991045 -374.602502)
			(xy 416.949029 -374.562759) (xy 416.93084 -374.540272) (xy 416.920943 -374.528467) (xy 416.895619 -374.510948)
			(xy 416.866226 -374.501772) (xy 416.835434 -374.501772) (xy 416.806041 -374.510948) (xy 416.780717 -374.528467)
			(xy 416.77082 -374.540272) (xy 416.752611 -374.56274) (xy 416.710596 -374.602478) (xy 416.663065 -374.635419)
			(xy 416.611107 -374.66081) (xy 416.555912 -374.67807) (xy 416.498745 -374.686802) (xy 416.46983 -374.687338)
			(xy 416.442578 -374.686817) (xy 416.388628 -374.679064) (xy 416.336331 -374.663712) (xy 416.286751 -374.641073)
			(xy 416.240897 -374.611608) (xy 416.199704 -374.575917) (xy 416.16401 -374.534727) (xy 416.134542 -374.488876)
			(xy 416.111899 -374.439298) (xy 416.096542 -374.387001) (xy 416.088785 -374.333052) (xy 411.819134 -374.333052)
			(xy 414.27908 -376.792998) (xy 432.085242 -376.792998)
		)
		(stroke
			(width 0)
			(type solid)
		)
		(fill yes)
		(layer "In13.Cu")
		(net "GND")
	)
	(gr_poly
		(pts
			(xy 55.483506 -366.872266) (xy 55.465218 -366.846866) (xy 55.448354 -366.822399) (xy 55.421604 -366.769339)
			(xy 55.4034 -366.712775) (xy 55.394182 -366.654073) (xy 55.39359 -366.624362) (xy 55.39359 -366.616742)
			(xy 55.394642 -366.588552) (xy 55.404022 -366.532927) (xy 55.42149 -366.479289) (xy 55.446664 -366.428808)
			(xy 55.478995 -366.382583) (xy 55.51778 -366.341621) (xy 55.562173 -366.306816) (xy 55.611206 -366.278926)
			(xy 55.663811 -366.258558) (xy 55.718842 -366.246158) (xy 55.775098 -366.241994) (xy 55.831354 -366.246158)
			(xy 55.886385 -366.258558) (xy 55.93899 -366.278926) (xy 55.988023 -366.306816) (xy 56.032416 -366.341621)
			(xy 56.071201 -366.382583) (xy 56.103532 -366.428808) (xy 56.128706 -366.479289) (xy 56.146174 -366.532927)
			(xy 56.155554 -366.588552) (xy 56.156606 -366.616742) (xy 56.156606 -366.624362) (xy 56.156041 -366.654075)
			(xy 56.146828 -366.712781) (xy 56.128619 -366.769348) (xy 56.101855 -366.822405) (xy 56.084978 -366.846866)
			(xy 56.06669 -366.872266) (xy 56.136286 -367.007648) (xy 56.465978 -367.007648) (xy 57.225946 -362.324142)
			(xy 57.861708 -342.54694) (xy 57.861708 -341.961978) (xy 57.73039 -340.44763) (xy 57.192672 -334.255364)
			(xy 56.931052 -333.993744) (xy 56.931052 -331.24013) (xy 56.894984 -330.824332) (xy 56.261 -330.190348)
			(xy 39.420038 -330.190348) (xy 35.616896 -333.99349) (xy 35.595814 -333.99349) (xy 34.902394 -334.68691)
			(xy 34.902394 -335.51361) (xy 39.617392 -335.51361) (xy 39.617392 -335.428914) (xy 39.625443 -335.3446)
			(xy 39.641472 -335.261434) (xy 39.665333 -335.180167) (xy 39.696812 -335.101537) (xy 39.735623 -335.026256)
			(xy 39.781413 -334.955004) (xy 39.833769 -334.888428) (xy 39.892217 -334.82713) (xy 39.956227 -334.771665)
			(xy 40.025219 -334.722536) (xy 40.098569 -334.680187) (xy 40.175612 -334.645003) (xy 40.255651 -334.617301)
			(xy 40.33796 -334.597333) (xy 40.421795 -334.58528) (xy 40.506396 -334.58125) (xy 40.590997 -334.58528)
			(xy 40.674832 -334.597333) (xy 40.757141 -334.617301) (xy 40.83718 -334.645003) (xy 40.914223 -334.680187)
			(xy 40.987573 -334.722536) (xy 41.056565 -334.771665) (xy 41.120575 -334.82713) (xy 41.179023 -334.888428)
			(xy 41.231379 -334.955004) (xy 41.277169 -335.026256) (xy 41.31598 -335.101537) (xy 41.347459 -335.180167)
			(xy 41.37132 -335.261434) (xy 41.387349 -335.3446) (xy 41.3954 -335.428914) (xy 41.395904 -335.471262)
			(xy 41.3954 -335.51361) (xy 41.394794 -335.51996) (xy 45.808134 -335.51996) (xy 45.808134 -335.435264)
			(xy 45.816185 -335.35095) (xy 45.832214 -335.267784) (xy 45.856075 -335.186517) (xy 45.887554 -335.107887)
			(xy 45.926365 -335.032606) (xy 45.972155 -334.961354) (xy 46.024511 -334.894778) (xy 46.082959 -334.83348)
			(xy 46.146969 -334.778015) (xy 46.215961 -334.728886) (xy 46.289311 -334.686537) (xy 46.366354 -334.651353)
			(xy 46.446393 -334.623651) (xy 46.528702 -334.603683) (xy 46.612537 -334.59163) (xy 46.697138 -334.5876)
			(xy 46.781739 -334.59163) (xy 46.865574 -334.603683) (xy 46.947883 -334.623651) (xy 47.027922 -334.651353)
			(xy 47.104965 -334.686537) (xy 47.178315 -334.728886) (xy 47.247307 -334.778015) (xy 47.311317 -334.83348)
			(xy 47.369765 -334.894778) (xy 47.422121 -334.961354) (xy 47.467911 -335.032606) (xy 47.506722 -335.107887)
			(xy 47.538201 -335.186517) (xy 47.562062 -335.267784) (xy 47.578091 -335.35095) (xy 47.586142 -335.435264)
			(xy 47.586646 -335.477612) (xy 47.586142 -335.51996) (xy 52.005734 -335.51996) (xy 52.005734 -335.435264)
			(xy 52.013785 -335.35095) (xy 52.029814 -335.267784) (xy 52.053675 -335.186517) (xy 52.085154 -335.107887)
			(xy 52.123965 -335.032606) (xy 52.169755 -334.961354) (xy 52.222111 -334.894778) (xy 52.280559 -334.83348)
			(xy 52.344569 -334.778015) (xy 52.413561 -334.728886) (xy 52.486911 -334.686537) (xy 52.563954 -334.651353)
			(xy 52.643993 -334.623651) (xy 52.726302 -334.603683) (xy 52.810137 -334.59163) (xy 52.894738 -334.5876)
			(xy 52.979339 -334.59163) (xy 53.063174 -334.603683) (xy 53.145483 -334.623651) (xy 53.225522 -334.651353)
			(xy 53.302565 -334.686537) (xy 53.375915 -334.728886) (xy 53.444907 -334.778015) (xy 53.508917 -334.83348)
			(xy 53.567365 -334.894778) (xy 53.619721 -334.961354) (xy 53.665511 -335.032606) (xy 53.704322 -335.107887)
			(xy 53.735801 -335.186517) (xy 53.759662 -335.267784) (xy 53.775691 -335.35095) (xy 53.783742 -335.435264)
			(xy 53.784246 -335.477612) (xy 53.783742 -335.51996) (xy 53.775691 -335.604274) (xy 53.759662 -335.68744)
			(xy 53.735801 -335.768707) (xy 53.704322 -335.847337) (xy 53.665511 -335.922618) (xy 53.619721 -335.99387)
			(xy 53.567365 -336.060446) (xy 53.508917 -336.121744) (xy 53.444907 -336.177209) (xy 53.375915 -336.226338)
			(xy 53.302565 -336.268687) (xy 53.225522 -336.303871) (xy 53.145483 -336.331573) (xy 53.063174 -336.351541)
			(xy 52.979339 -336.363594) (xy 52.894738 -336.367625) (xy 52.810137 -336.363594) (xy 52.726302 -336.351541)
			(xy 52.643993 -336.331573) (xy 52.563954 -336.303871) (xy 52.486911 -336.268687) (xy 52.413561 -336.226338)
			(xy 52.344569 -336.177209) (xy 52.280559 -336.121744) (xy 52.222111 -336.060446) (xy 52.169755 -335.99387)
			(xy 52.123965 -335.922618) (xy 52.085154 -335.847337) (xy 52.053675 -335.768707) (xy 52.029814 -335.68744)
			(xy 52.013785 -335.604274) (xy 52.005734 -335.51996) (xy 47.586142 -335.51996) (xy 47.578091 -335.604274)
			(xy 47.562062 -335.68744) (xy 47.538201 -335.768707) (xy 47.506722 -335.847337) (xy 47.467911 -335.922618)
			(xy 47.422121 -335.99387) (xy 47.369765 -336.060446) (xy 47.311317 -336.121744) (xy 47.247307 -336.177209)
			(xy 47.178315 -336.226338) (xy 47.104965 -336.268687) (xy 47.027922 -336.303871) (xy 46.947883 -336.331573)
			(xy 46.865574 -336.351541) (xy 46.781739 -336.363594) (xy 46.697138 -336.367625) (xy 46.612537 -336.363594)
			(xy 46.528702 -336.351541) (xy 46.446393 -336.331573) (xy 46.366354 -336.303871) (xy 46.289311 -336.268687)
			(xy 46.215961 -336.226338) (xy 46.146969 -336.177209) (xy 46.082959 -336.121744) (xy 46.024511 -336.060446)
			(xy 45.972155 -335.99387) (xy 45.926365 -335.922618) (xy 45.887554 -335.847337) (xy 45.856075 -335.768707)
			(xy 45.832214 -335.68744) (xy 45.816185 -335.604274) (xy 45.808134 -335.51996) (xy 41.394794 -335.51996)
			(xy 41.387349 -335.597924) (xy 41.37132 -335.68109) (xy 41.347459 -335.762357) (xy 41.31598 -335.840987)
			(xy 41.277169 -335.916268) (xy 41.231379 -335.98752) (xy 41.179023 -336.054096) (xy 41.120575 -336.115394)
			(xy 41.056565 -336.170859) (xy 40.987573 -336.219988) (xy 40.914223 -336.262337) (xy 40.83718 -336.297521)
			(xy 40.757141 -336.325223) (xy 40.674832 -336.345191) (xy 40.590997 -336.357244) (xy 40.506396 -336.361275)
			(xy 40.421795 -336.357244) (xy 40.33796 -336.345191) (xy 40.255651 -336.325223) (xy 40.175612 -336.297521)
			(xy 40.098569 -336.262337) (xy 40.025219 -336.219988) (xy 39.956227 -336.170859) (xy 39.892217 -336.115394)
			(xy 39.833769 -336.054096) (xy 39.781413 -335.98752) (xy 39.735623 -335.916268) (xy 39.696812 -335.840987)
			(xy 39.665333 -335.762357) (xy 39.641472 -335.68109) (xy 39.625443 -335.597924) (xy 39.617392 -335.51361)
			(xy 34.902394 -335.51361) (xy 34.902394 -337.471258) (xy 39.590985 -337.471258) (xy 39.595007 -337.385538)
			(xy 39.607038 -337.30057) (xy 39.626974 -337.217103) (xy 39.654637 -337.135869) (xy 39.689786 -337.057583)
			(xy 39.732112 -336.982932) (xy 39.781241 -336.912573) (xy 39.836744 -336.847123) (xy 39.898131 -336.787159)
			(xy 39.964864 -336.733206) (xy 40.036356 -336.685739) (xy 40.111978 -336.645175) (xy 40.191067 -336.611871)
			(xy 40.272927 -336.586119) (xy 40.356838 -336.568146) (xy 40.442064 -336.55811) (xy 40.527856 -336.556098)
			(xy 40.613458 -336.562129) (xy 40.69812 -336.576149) (xy 40.781097 -336.598035) (xy 40.86166 -336.627596)
			(xy 40.9391 -336.66457) (xy 41.012739 -336.708634) (xy 41.081927 -336.7594) (xy 41.146058 -336.816421)
			(xy 41.204567 -336.879197) (xy 41.25694 -336.947177) (xy 41.302718 -337.019762) (xy 41.341498 -337.096314)
			(xy 41.372939 -337.176162) (xy 41.396765 -337.258603) (xy 41.412766 -337.342913) (xy 41.420801 -337.428351)
			(xy 41.421304 -337.471258) (xy 41.42123 -337.477608) (xy 45.781727 -337.477608) (xy 45.785749 -337.391888)
			(xy 45.79778 -337.30692) (xy 45.817716 -337.223453) (xy 45.845379 -337.142219) (xy 45.880528 -337.063933)
			(xy 45.922854 -336.989282) (xy 45.971983 -336.918923) (xy 46.027486 -336.853473) (xy 46.088873 -336.793509)
			(xy 46.155606 -336.739556) (xy 46.227098 -336.692089) (xy 46.30272 -336.651525) (xy 46.381809 -336.618221)
			(xy 46.463669 -336.592469) (xy 46.54758 -336.574496) (xy 46.632806 -336.56446) (xy 46.718598 -336.562448)
			(xy 46.8042 -336.568479) (xy 46.888862 -336.582499) (xy 46.971839 -336.604385) (xy 47.052402 -336.633946)
			(xy 47.129842 -336.67092) (xy 47.203481 -336.714984) (xy 47.272669 -336.76575) (xy 47.3368 -336.822771)
			(xy 47.395309 -336.885547) (xy 47.447682 -336.953527) (xy 47.49346 -337.026112) (xy 47.53224 -337.102664)
			(xy 47.563681 -337.182512) (xy 47.587507 -337.264953) (xy 47.603508 -337.349263) (xy 47.611543 -337.434701)
			(xy 47.612046 -337.477608) (xy 51.97983 -337.477608) (xy 51.980318 -337.435332) (xy 51.98812 -337.35114)
			(xy 52.003656 -337.268027) (xy 52.026795 -337.186703) (xy 52.057339 -337.10786) (xy 52.095027 -337.032172)
			(xy 52.139538 -336.960284) (xy 52.190492 -336.89281) (xy 52.247455 -336.830325) (xy 52.30994 -336.773362)
			(xy 52.377414 -336.722408) (xy 52.449302 -336.677897) (xy 52.52499 -336.640209) (xy 52.603833 -336.609665)
			(xy 52.685157 -336.586526) (xy 52.76827 -336.57099) (xy 52.852462 -336.563188) (xy 52.937014 -336.563188)
			(xy 53.021206 -336.57099) (xy 53.104319 -336.586526) (xy 53.185643 -336.609665) (xy 53.264486 -336.640209)
			(xy 53.340174 -336.677897) (xy 53.412062 -336.722408) (xy 53.479536 -336.773362) (xy 53.542021 -336.830325)
			(xy 53.598984 -336.89281) (xy 53.649938 -336.960284) (xy 53.694449 -337.032172) (xy 53.732137 -337.10786)
			(xy 53.762681 -337.186703) (xy 53.78582 -337.268027) (xy 53.801356 -337.35114) (xy 53.809158 -337.435332)
			(xy 53.809646 -337.477608) (xy 53.809142 -337.519569) (xy 53.801456 -337.603139) (xy 53.786148 -337.685654)
			(xy 53.763347 -337.766421) (xy 53.733246 -337.844759) (xy 53.696097 -337.920012) (xy 53.652212 -337.991547)
			(xy 53.60196 -338.058761) (xy 53.545764 -338.121091) (xy 53.484096 -338.178013) (xy 53.417474 -338.229047)
			(xy 53.346458 -338.273766) (xy 53.309266 -338.293202) (xy 53.296167 -338.300524) (xy 53.274558 -338.321321)
			(xy 53.259912 -338.347494) (xy 53.25349 -338.37679) (xy 53.255844 -338.406689) (xy 53.266772 -338.434619)
			(xy 53.285333 -338.458177) (xy 53.297328 -338.467192) (xy 53.308811 -338.475301) (xy 53.330676 -338.492974)
			(xy 53.341016 -338.502498) (xy 53.35255 -338.51257) (xy 53.380096 -338.525912) (xy 53.410358 -338.530497)
			(xy 53.44062 -338.525912) (xy 53.468166 -338.51257) (xy 53.4797 -338.502498) (xy 53.501027 -338.483228)
			(xy 53.54839 -338.450663) (xy 53.600101 -338.425572) (xy 53.654992 -338.408522) (xy 53.711819 -338.3999)
			(xy 53.769297 -338.3999) (xy 53.826124 -338.408522) (xy 53.881015 -338.425572) (xy 53.932726 -338.450663)
			(xy 53.980089 -338.483228) (xy 54.001416 -338.502498) (xy 54.01295 -338.51257) (xy 54.040496 -338.525912)
			(xy 54.070758 -338.530497) (xy 54.10102 -338.525912) (xy 54.128566 -338.51257) (xy 54.1401 -338.502498)
			(xy 54.161412 -338.48321) (xy 54.208777 -338.450644) (xy 54.260493 -338.425554) (xy 54.315387 -338.408508)
			(xy 54.372218 -338.399891) (xy 54.400958 -338.399374) (xy 54.428209 -338.399894) (xy 54.482157 -338.407645)
			(xy 54.534453 -338.422995) (xy 54.584031 -338.445631) (xy 54.629884 -338.475093) (xy 54.671077 -338.510781)
			(xy 54.706771 -338.551968) (xy 54.73624 -338.597816) (xy 54.758884 -338.647391) (xy 54.774242 -338.699684)
			(xy 54.782001 -338.753631) (xy 54.782466 -338.780882) (xy 54.781914 -338.80962) (xy 54.773295 -338.866445)
			(xy 54.756251 -338.921335) (xy 54.731166 -338.973047) (xy 54.698609 -339.020411) (xy 54.679342 -339.04174)
			(xy 54.669287 -339.053288) (xy 54.655941 -339.080829) (xy 54.651353 -339.111087) (xy 54.655934 -339.141346)
			(xy 54.669272 -339.16889) (xy 54.679342 -339.180424) (xy 54.698601 -339.201761) (xy 54.73117 -339.24912)
			(xy 54.756265 -339.300829) (xy 54.773318 -339.355718) (xy 54.781944 -339.412544) (xy 54.782466 -339.441282)
			(xy 54.782015 -339.468272) (xy 54.774408 -339.521712) (xy 54.759344 -339.573547) (xy 54.737124 -339.622741)
			(xy 54.70819 -339.668311) (xy 54.673122 -339.709347) (xy 54.65318 -339.72754) (xy 54.642465 -339.737466)
			(xy 54.626852 -339.762143) (xy 54.618868 -339.790231) (xy 54.619166 -339.819431) (xy 54.627722 -339.84735)
			(xy 54.643835 -339.871703) (xy 54.654704 -339.881464) (xy 54.675503 -339.899686) (xy 54.712176 -339.941068)
			(xy 54.742483 -339.987316) (xy 54.765788 -340.037458) (xy 54.781602 -340.090442) (xy 54.789593 -340.145155)
			(xy 54.790086 -340.172802) (xy 54.789559 -340.202244) (xy 54.780511 -340.26043) (xy 54.76263 -340.316534)
			(xy 54.736341 -340.369224) (xy 54.702268 -340.417249) (xy 54.682136 -340.43874) (xy 54.671747 -340.450216)
			(xy 54.657858 -340.477865) (xy 54.652857 -340.508401) (xy 54.657201 -340.539036) (xy 54.670494 -340.566978)
			(xy 54.680612 -340.578694) (xy 54.699625 -340.600011) (xy 54.731799 -340.647204) (xy 54.75658 -340.698665)
			(xy 54.773417 -340.753245) (xy 54.781931 -340.809723) (xy 54.782466 -340.838282) (xy 54.781998 -340.865652)
			(xy 54.774182 -340.919832) (xy 54.758694 -340.972335) (xy 54.735852 -341.022082) (xy 54.706127 -341.068049)
			(xy 54.688486 -341.08898) (xy 54.679268 -341.100321) (xy 54.66709 -341.126874) (xy 54.662914 -341.155786)
			(xy 54.667082 -341.1847) (xy 54.679253 -341.211256) (xy 54.688486 -341.222584) (xy 54.706109 -341.243531)
			(xy 54.735833 -341.289497) (xy 54.758679 -341.339241) (xy 54.774176 -341.391741) (xy 54.782006 -341.445917)
			(xy 54.782008 -341.500656) (xy 54.774182 -341.554833) (xy 54.758688 -341.607334) (xy 54.735846 -341.657079)
			(xy 54.706125 -341.703047) (xy 54.688486 -341.72398) (xy 54.679268 -341.735321) (xy 54.66709 -341.761874)
			(xy 54.662914 -341.790786) (xy 54.667082 -341.8197) (xy 54.679253 -341.846256) (xy 54.688486 -341.857584)
			(xy 54.706109 -341.878531) (xy 54.735833 -341.924497) (xy 54.758679 -341.974241) (xy 54.774176 -342.026741)
			(xy 54.782006 -342.080917) (xy 54.782008 -342.135656) (xy 54.774182 -342.189833) (xy 54.758688 -342.242334)
			(xy 54.735846 -342.292079) (xy 54.706125 -342.338047) (xy 54.688486 -342.35898) (xy 54.679268 -342.370321)
			(xy 54.66709 -342.396874) (xy 54.662914 -342.425786) (xy 54.667082 -342.4547) (xy 54.679253 -342.481256)
			(xy 54.688486 -342.492584) (xy 54.706129 -342.513513) (xy 54.735841 -342.559486) (xy 54.758676 -342.609235)
			(xy 54.774166 -342.661736) (xy 54.781993 -342.715913) (xy 54.782466 -342.743282) (xy 54.782028 -342.770536)
			(xy 54.774272 -342.82449) (xy 54.758916 -342.876791) (xy 54.736273 -342.926374) (xy 54.706803 -342.972229)
			(xy 54.671106 -343.013423) (xy 54.62991 -343.049117) (xy 54.584053 -343.078584) (xy 54.534469 -343.101225)
			(xy 54.482167 -343.116577) (xy 54.428212 -343.12433) (xy 54.400958 -343.12479) (xy 54.372218 -343.124294)
			(xy 54.315389 -343.115665) (xy 54.260498 -343.098609) (xy 54.208787 -343.073511) (xy 54.161426 -343.04094)
			(xy 54.1401 -343.021666) (xy 54.128566 -343.011594) (xy 54.10102 -342.998252) (xy 54.070758 -342.993667)
			(xy 54.040496 -342.998252) (xy 54.01295 -343.011594) (xy 54.001416 -343.021666) (xy 53.980089 -343.040936)
			(xy 53.932726 -343.073501) (xy 53.881015 -343.098592) (xy 53.826124 -343.115642) (xy 53.769297 -343.124264)
			(xy 53.711819 -343.124264) (xy 53.654992 -343.115642) (xy 53.600101 -343.098592) (xy 53.54839 -343.073501)
			(xy 53.501027 -343.040936) (xy 53.4797 -343.021666) (xy 53.468166 -343.011594) (xy 53.44062 -342.998252)
			(xy 53.410358 -342.993667) (xy 53.380096 -342.998252) (xy 53.35255 -343.011594) (xy 53.341016 -343.021666)
			(xy 53.319707 -343.040957) (xy 53.27234 -343.073521) (xy 53.220624 -343.098609) (xy 53.165729 -343.115655)
			(xy 53.108898 -343.124272) (xy 53.080158 -343.12479) (xy 53.052905 -343.124361) (xy 52.998954 -343.116599)
			(xy 52.946657 -343.101237) (xy 52.897079 -343.07859) (xy 52.851228 -343.049117) (xy 52.810037 -343.01342)
			(xy 52.774347 -342.972224) (xy 52.744881 -342.926369) (xy 52.722242 -342.876786) (xy 52.706889 -342.824487)
			(xy 52.699135 -342.770535) (xy 52.69865 -342.743282) (xy 52.699093 -342.715911) (xy 52.706915 -342.66173)
			(xy 52.722408 -342.609226) (xy 52.745256 -342.55948) (xy 52.774986 -342.513514) (xy 52.79263 -342.492584)
			(xy 52.801882 -342.481269) (xy 52.814053 -342.454706) (xy 52.818221 -342.425786) (xy 52.814046 -342.396868)
			(xy 52.801867 -342.370308) (xy 52.79263 -342.35898) (xy 52.774972 -342.338062) (xy 52.745247 -342.292091)
			(xy 52.722403 -342.242343) (xy 52.706908 -342.189839) (xy 52.699081 -342.135658) (xy 52.699083 -342.080915)
			(xy 52.706914 -342.026735) (xy 52.722412 -341.974232) (xy 52.74526 -341.924485) (xy 52.774988 -341.878517)
			(xy 52.79263 -341.857584) (xy 52.801882 -341.846269) (xy 52.814053 -341.819706) (xy 52.818221 -341.790786)
			(xy 52.814046 -341.761868) (xy 52.801867 -341.735308) (xy 52.79263 -341.72398) (xy 52.774972 -341.703062)
			(xy 52.745247 -341.657091) (xy 52.722403 -341.607343) (xy 52.706908 -341.554839) (xy 52.699081 -341.500658)
			(xy 52.699083 -341.445915) (xy 52.706914 -341.391735) (xy 52.722412 -341.339232) (xy 52.74526 -341.289485)
			(xy 52.774988 -341.243517) (xy 52.79263 -341.222584) (xy 52.801882 -341.211269) (xy 52.814053 -341.184706)
			(xy 52.818221 -341.155786) (xy 52.814046 -341.126868) (xy 52.801867 -341.100308) (xy 52.79263 -341.08898)
			(xy 52.77502 -341.068025) (xy 52.745302 -341.022059) (xy 52.72246 -340.972317) (xy 52.706963 -340.919822)
			(xy 52.699128 -340.86565) (xy 52.69865 -340.838282) (xy 52.69922 -340.808841) (xy 52.708256 -340.750657)
			(xy 52.726126 -340.694554) (xy 52.752406 -340.641862) (xy 52.786471 -340.593836) (xy 52.8066 -340.572344)
			(xy 52.817009 -340.560883) (xy 52.830906 -340.53323) (xy 52.835907 -340.502688) (xy 52.831556 -340.472046)
			(xy 52.81825 -340.444104) (xy 52.808124 -340.43239) (xy 52.789093 -340.411088) (xy 52.756924 -340.36389)
			(xy 52.732147 -340.312425) (xy 52.715315 -340.257843) (xy 52.706803 -340.201361) (xy 52.70627 -340.172802)
			(xy 52.706698 -340.145811) (xy 52.714308 -340.092369) (xy 52.729376 -340.040533) (xy 52.7516 -339.99134)
			(xy 52.780538 -339.94577) (xy 52.815611 -339.904735) (xy 52.835556 -339.886544) (xy 52.846182 -339.876532)
			(xy 52.861793 -339.851879) (xy 52.869785 -339.823814) (xy 52.869503 -339.794635) (xy 52.86097 -339.766729)
			(xy 52.844886 -339.742382) (xy 52.834032 -339.73262) (xy 52.813233 -339.714399) (xy 52.776559 -339.673017)
			(xy 52.74625 -339.62677) (xy 52.722945 -339.576627) (xy 52.707131 -339.523643) (xy 52.699142 -339.468929)
			(xy 52.69865 -339.441282) (xy 52.699176 -339.412543) (xy 52.7078 -339.355717) (xy 52.72485 -339.300827)
			(xy 52.749941 -339.249115) (xy 52.782504 -339.201752) (xy 52.801774 -339.180424) (xy 52.811863 -339.168904)
			(xy 52.825203 -339.141353) (xy 52.829784 -339.111087) (xy 52.825195 -339.080822) (xy 52.811848 -339.053274)
			(xy 52.801774 -339.04174) (xy 52.782501 -339.020415) (xy 52.749933 -338.973053) (xy 52.724841 -338.921341)
			(xy 52.707791 -338.86645) (xy 52.69917 -338.809621) (xy 52.69865 -338.780882) (xy 52.699093 -338.754848)
			(xy 52.706182 -338.703265) (xy 52.720212 -338.653124) (xy 52.740924 -338.605353) (xy 52.767933 -338.560838)
			(xy 52.783994 -338.540344) (xy 52.792995 -338.528305) (xy 52.804369 -338.500505) (xy 52.807153 -338.470597)
			(xy 52.801105 -338.441174) (xy 52.78675 -338.414789) (xy 52.765333 -338.393729) (xy 52.73871 -338.37982)
			(xy 52.72405 -338.376514) (xy 52.682679 -338.368223) (xy 52.601583 -338.344902) (xy 52.522979 -338.314214)
			(xy 52.447534 -338.276419) (xy 52.375889 -338.231838) (xy 52.308653 -338.180851) (xy 52.246397 -338.12389)
			(xy 52.189649 -338.061439) (xy 52.138892 -337.994029) (xy 52.094557 -337.922232) (xy 52.05702 -337.846659)
			(xy 52.0266 -337.76795) (xy 52.003557 -337.686775) (xy 51.988084 -337.603823) (xy 51.980315 -337.519799)
			(xy 51.97983 -337.477608) (xy 47.612046 -337.477608) (xy 47.611543 -337.520515) (xy 47.603508 -337.605953)
			(xy 47.587507 -337.690263) (xy 47.563681 -337.772704) (xy 47.53224 -337.852552) (xy 47.49346 -337.929104)
			(xy 47.447682 -338.001689) (xy 47.395309 -338.069669) (xy 47.3368 -338.132445) (xy 47.272669 -338.189466)
			(xy 47.203481 -338.240232) (xy 47.129842 -338.284296) (xy 47.052402 -338.32127) (xy 46.971839 -338.350831)
			(xy 46.888862 -338.372717) (xy 46.8042 -338.386737) (xy 46.718598 -338.392768) (xy 46.632806 -338.390756)
			(xy 46.54758 -338.38072) (xy 46.463669 -338.362747) (xy 46.381809 -338.336995) (xy 46.30272 -338.303691)
			(xy 46.227098 -338.263127) (xy 46.155606 -338.21566) (xy 46.088873 -338.161707) (xy 46.027486 -338.101743)
			(xy 45.971983 -338.036293) (xy 45.922854 -337.965934) (xy 45.880528 -337.891283) (xy 45.845379 -337.812997)
			(xy 45.817716 -337.731763) (xy 45.79778 -337.648296) (xy 45.785749 -337.563328) (xy 45.781727 -337.477608)
			(xy 41.42123 -337.477608) (xy 41.420801 -337.514165) (xy 41.412766 -337.599603) (xy 41.396765 -337.683913)
			(xy 41.372939 -337.766354) (xy 41.341498 -337.846202) (xy 41.302718 -337.922754) (xy 41.25694 -337.995339)
			(xy 41.204567 -338.063319) (xy 41.146058 -338.126095) (xy 41.081927 -338.183116) (xy 41.012739 -338.233882)
			(xy 40.9391 -338.277946) (xy 40.86166 -338.31492) (xy 40.781097 -338.344481) (xy 40.69812 -338.366367)
			(xy 40.613458 -338.380387) (xy 40.527856 -338.386418) (xy 40.442064 -338.384406) (xy 40.356838 -338.37437)
			(xy 40.272927 -338.356397) (xy 40.191067 -338.330645) (xy 40.111978 -338.297341) (xy 40.036356 -338.256777)
			(xy 39.964864 -338.20931) (xy 39.898131 -338.155357) (xy 39.836744 -338.095393) (xy 39.781241 -338.029943)
			(xy 39.732112 -337.959584) (xy 39.689786 -337.884933) (xy 39.654637 -337.806647) (xy 39.626974 -337.725413)
			(xy 39.607038 -337.641946) (xy 39.595007 -337.556978) (xy 39.590985 -337.471258) (xy 34.902394 -337.471258)
			(xy 34.902394 -339.443822) (xy 38.02761 -339.443822) (xy 38.028087 -339.416452) (xy 38.035901 -339.362273)
			(xy 38.051388 -339.30977) (xy 38.074227 -339.260023) (xy 38.10395 -339.214056) (xy 38.12159 -339.193124)
			(xy 38.130806 -339.181781) (xy 38.142988 -339.155229) (xy 38.147165 -339.126317) (xy 38.142997 -339.097403)
			(xy 38.130825 -339.070847) (xy 38.12159 -339.05952) (xy 38.103945 -339.038593) (xy 38.074235 -338.992618)
			(xy 38.0514 -338.94287) (xy 38.03591 -338.890368) (xy 38.028083 -338.836191) (xy 38.02761 -338.808822)
			(xy 38.028076 -338.781569) (xy 38.03583 -338.727617) (xy 38.051184 -338.675318) (xy 38.073826 -338.625737)
			(xy 38.103293 -338.579883) (xy 38.138987 -338.538689) (xy 38.18018 -338.502995) (xy 38.226033 -338.473528)
			(xy 38.275614 -338.450886) (xy 38.327913 -338.435531) (xy 38.381865 -338.427776) (xy 38.409118 -338.427314)
			(xy 38.437856 -338.42785) (xy 38.494682 -338.436473) (xy 38.549572 -338.453521) (xy 38.601284 -338.47861)
			(xy 38.648648 -338.51117) (xy 38.669976 -338.530438) (xy 38.68151 -338.54051) (xy 38.709056 -338.553852)
			(xy 38.739318 -338.558437) (xy 38.76958 -338.553852) (xy 38.797126 -338.54051) (xy 38.80866 -338.530438)
			(xy 38.829987 -338.511168) (xy 38.87735 -338.478603) (xy 38.929061 -338.453512) (xy 38.983952 -338.436462)
			(xy 39.040779 -338.42784) (xy 39.098257 -338.42784) (xy 39.155084 -338.436462) (xy 39.209975 -338.453512)
			(xy 39.261686 -338.478603) (xy 39.309049 -338.511168) (xy 39.330376 -338.530438) (xy 39.341283 -338.539936)
			(xy 39.367057 -338.553021) (xy 39.395469 -338.558337) (xy 39.42423 -338.555455) (xy 39.437818 -338.550504)
			(xy 39.456048 -338.52959) (xy 39.497498 -338.492717) (xy 39.543854 -338.462239) (xy 39.594137 -338.4388)
			(xy 39.647286 -338.422894) (xy 39.702179 -338.414858) (xy 39.729918 -338.41436) (xy 39.75719 -338.414785)
			(xy 39.81118 -338.42255) (xy 39.863515 -338.43792) (xy 39.913129 -338.460581) (xy 39.959014 -338.490072)
			(xy 40.000234 -338.525794) (xy 40.035952 -338.567018) (xy 40.065438 -338.612906) (xy 40.088094 -338.662523)
			(xy 40.103459 -338.714859) (xy 40.111218 -338.768849) (xy 40.11168 -338.796122) (xy 40.111426 -338.810092)
			(xy 40.110907 -338.837335) (xy 40.102977 -338.891244) (xy 40.087449 -338.943474) (xy 40.06464 -338.99296)
			(xy 40.035015 -339.038692) (xy 40.017446 -339.05952) (xy 40.009031 -339.069826) (xy 39.997353 -339.093722)
			(xy 39.992231 -339.119822) (xy 39.994012 -339.146359) (xy 39.997888 -339.159088) (xy 40.019063 -339.180757)
			(xy 40.054942 -339.229573) (xy 40.082668 -339.283439) (xy 40.101546 -339.341006) (xy 40.111103 -339.40083)
			(xy 40.11168 -339.431122) (xy 40.111426 -339.445092) (xy 40.110952 -339.470505) (xy 40.104043 -339.520863)
			(xy 40.090504 -339.569857) (xy 40.070578 -339.616618) (xy 40.044616 -339.660317) (xy 40.013079 -339.70018)
			(xy 39.995094 -339.718142) (xy 39.985339 -339.728135) (xy 39.971307 -339.752272) (xy 39.964343 -339.779309)
			(xy 39.964969 -339.807221) (xy 39.973137 -339.833919) (xy 39.988236 -339.857403) (xy 39.998396 -339.866986)
			(xy 40.018206 -339.885169) (xy 40.052996 -339.926171) (xy 40.081692 -339.971647) (xy 40.103726 -340.020698)
			(xy 40.118662 -340.072355) (xy 40.126207 -340.125596) (xy 40.126666 -340.152482) (xy 40.126079 -340.182605)
			(xy 40.116601 -340.2421) (xy 40.097894 -340.299368) (xy 40.070422 -340.352985) (xy 40.034867 -340.40162)
			(xy 40.01389 -340.423246) (xy 40.004689 -340.432983) (xy 39.99124 -340.45614) (xy 39.984274 -340.481998)
			(xy 39.984271 -340.508777) (xy 39.99123 -340.534636) (xy 40.004673 -340.557797) (xy 40.01389 -340.567518)
			(xy 40.034854 -340.589158) (xy 40.070425 -340.637782) (xy 40.097908 -340.691395) (xy 40.11662 -340.748662)
			(xy 40.126095 -340.808159) (xy 40.126666 -340.838282) (xy 40.126198 -340.865652) (xy 40.118382 -340.919832)
			(xy 40.102894 -340.972335) (xy 40.080052 -341.022082) (xy 40.050327 -341.068049) (xy 40.032686 -341.08898)
			(xy 40.023468 -341.100321) (xy 40.01129 -341.126874) (xy 40.007114 -341.155786) (xy 40.011282 -341.1847)
			(xy 40.023453 -341.211256) (xy 40.032686 -341.222584) (xy 40.050309 -341.243531) (xy 40.080033 -341.289497)
			(xy 40.102879 -341.339241) (xy 40.118376 -341.391741) (xy 40.126206 -341.445917) (xy 40.126208 -341.500656)
			(xy 40.118382 -341.554833) (xy 40.102888 -341.607334) (xy 40.080046 -341.657079) (xy 40.050325 -341.703047)
			(xy 40.032686 -341.72398) (xy 40.023468 -341.735321) (xy 40.01129 -341.761874) (xy 40.007114 -341.790786)
			(xy 40.011282 -341.8197) (xy 40.023453 -341.846256) (xy 40.032686 -341.857584) (xy 40.050309 -341.878531)
			(xy 40.080033 -341.924497) (xy 40.102879 -341.974241) (xy 40.118376 -342.026741) (xy 40.126206 -342.080917)
			(xy 40.126208 -342.135656) (xy 40.118382 -342.189833) (xy 40.102888 -342.242334) (xy 40.080046 -342.292079)
			(xy 40.050325 -342.338047) (xy 40.032686 -342.35898) (xy 40.023468 -342.370321) (xy 40.01129 -342.396874)
			(xy 40.007114 -342.425786) (xy 40.011282 -342.4547) (xy 40.023453 -342.481256) (xy 40.032686 -342.492584)
			(xy 40.050329 -342.513513) (xy 40.080041 -342.559486) (xy 40.102876 -342.609235) (xy 40.118366 -342.661736)
			(xy 40.126193 -342.715913) (xy 40.126666 -342.743282) (xy 43.02125 -342.743282) (xy 43.021693 -342.715911)
			(xy 43.029515 -342.66173) (xy 43.045008 -342.609226) (xy 43.067856 -342.55948) (xy 43.097586 -342.513514)
			(xy 43.11523 -342.492584) (xy 43.124482 -342.481269) (xy 43.136653 -342.454706) (xy 43.140821 -342.425786)
			(xy 43.136646 -342.396868) (xy 43.124467 -342.370308) (xy 43.11523 -342.35898) (xy 43.097572 -342.338062)
			(xy 43.067847 -342.292091) (xy 43.045003 -342.242343) (xy 43.029508 -342.189839) (xy 43.021681 -342.135658)
			(xy 43.021683 -342.080915) (xy 43.029514 -342.026735) (xy 43.045012 -341.974232) (xy 43.06786 -341.924485)
			(xy 43.097588 -341.878517) (xy 43.11523 -341.857584) (xy 43.124482 -341.846269) (xy 43.136653 -341.819706)
			(xy 43.140821 -341.790786) (xy 43.136646 -341.761868) (xy 43.124467 -341.735308) (xy 43.11523 -341.72398)
			(xy 43.097572 -341.703062) (xy 43.067847 -341.657091) (xy 43.045003 -341.607343) (xy 43.029508 -341.554839)
			(xy 43.021681 -341.500658) (xy 43.021683 -341.445915) (xy 43.029514 -341.391735) (xy 43.045012 -341.339232)
			(xy 43.06786 -341.289485) (xy 43.097588 -341.243517) (xy 43.11523 -341.222584) (xy 43.124482 -341.211269)
			(xy 43.136653 -341.184706) (xy 43.140821 -341.155786) (xy 43.136646 -341.126868) (xy 43.124467 -341.100308)
			(xy 43.11523 -341.08898) (xy 43.09762 -341.068025) (xy 43.067902 -341.022059) (xy 43.04506 -340.972317)
			(xy 43.029563 -340.919822) (xy 43.021728 -340.86565) (xy 43.02125 -340.838282) (xy 43.02125 -340.838028)
			(xy 43.021846 -340.808195) (xy 43.031143 -340.749256) (xy 43.049499 -340.692483) (xy 43.076467 -340.639258)
			(xy 43.11139 -340.590879) (xy 43.131994 -340.569296) (xy 43.142625 -340.557741) (xy 43.157002 -340.529852)
			(xy 43.162226 -340.498914) (xy 43.157801 -340.467851) (xy 43.144146 -340.439601) (xy 43.133772 -340.427818)
			(xy 43.114184 -340.406442) (xy 43.081067 -340.358854) (xy 43.055538 -340.3068) (xy 43.038186 -340.25148)
			(xy 43.02941 -340.194171) (xy 43.02887 -340.165182) (xy 43.029319 -340.138581) (xy 43.036697 -340.085893)
			(xy 43.051322 -340.034741) (xy 43.07291 -339.986116) (xy 43.101043 -339.940961) (xy 43.135174 -339.900151)
			(xy 43.1546 -339.881972) (xy 43.164941 -339.872005) (xy 43.180033 -339.847581) (xy 43.187736 -339.819924)
			(xy 43.187444 -339.791215) (xy 43.179179 -339.76372) (xy 43.163593 -339.739609) (xy 43.153076 -339.729826)
			(xy 43.132762 -339.711618) (xy 43.097025 -339.670401) (xy 43.067521 -339.624515) (xy 43.044852 -339.574896)
			(xy 43.029478 -339.522555) (xy 43.021713 -339.468558) (xy 43.02125 -339.441282) (xy 43.021776 -339.412543)
			(xy 43.0304 -339.355717) (xy 43.04745 -339.300827) (xy 43.072541 -339.249115) (xy 43.105104 -339.201752)
			(xy 43.124374 -339.180424) (xy 43.134463 -339.168904) (xy 43.147803 -339.141353) (xy 43.152384 -339.111087)
			(xy 43.147795 -339.080822) (xy 43.134448 -339.053274) (xy 43.124374 -339.04174) (xy 43.105101 -339.020415)
			(xy 43.072533 -338.973053) (xy 43.047441 -338.921341) (xy 43.030391 -338.86645) (xy 43.02177 -338.809621)
			(xy 43.02125 -338.780882) (xy 43.021761 -338.753632) (xy 43.029519 -338.699688) (xy 43.044874 -338.647396)
			(xy 43.067514 -338.597821) (xy 43.096979 -338.551973) (xy 43.132667 -338.510784) (xy 43.173854 -338.475093)
			(xy 43.2197 -338.445626) (xy 43.269273 -338.422982) (xy 43.321564 -338.407624) (xy 43.375508 -338.399863)
			(xy 43.402758 -338.399374) (xy 43.431498 -338.399869) (xy 43.488326 -338.4085) (xy 43.543217 -338.425557)
			(xy 43.594928 -338.450655) (xy 43.64229 -338.483225) (xy 43.663616 -338.502498) (xy 43.67515 -338.51257)
			(xy 43.702696 -338.525912) (xy 43.732958 -338.530497) (xy 43.76322 -338.525912) (xy 43.790766 -338.51257)
			(xy 43.8023 -338.502498) (xy 43.823627 -338.483228) (xy 43.87099 -338.450663) (xy 43.922701 -338.425572)
			(xy 43.977592 -338.408522) (xy 44.034419 -338.3999) (xy 44.091897 -338.3999) (xy 44.148724 -338.408522)
			(xy 44.203615 -338.425572) (xy 44.255326 -338.450663) (xy 44.302689 -338.483228) (xy 44.324016 -338.502498)
			(xy 44.33555 -338.51257) (xy 44.363096 -338.525912) (xy 44.393358 -338.530497) (xy 44.42362 -338.525912)
			(xy 44.451166 -338.51257) (xy 44.4627 -338.502498) (xy 44.484012 -338.48321) (xy 44.531377 -338.450644)
			(xy 44.583093 -338.425554) (xy 44.637987 -338.408508) (xy 44.694818 -338.399891) (xy 44.723558 -338.399374)
			(xy 44.750809 -338.399894) (xy 44.804757 -338.407645) (xy 44.857053 -338.422995) (xy 44.906631 -338.445631)
			(xy 44.952484 -338.475093) (xy 44.993677 -338.510781) (xy 45.029371 -338.551968) (xy 45.05884 -338.597816)
			(xy 45.081484 -338.647391) (xy 45.096842 -338.699684) (xy 45.104601 -338.753631) (xy 45.105066 -338.780882)
			(xy 45.104514 -338.80962) (xy 45.095895 -338.866445) (xy 45.078851 -338.921335) (xy 45.053766 -338.973047)
			(xy 45.021209 -339.020411) (xy 45.001942 -339.04174) (xy 44.991887 -339.053288) (xy 44.978541 -339.080829)
			(xy 44.973953 -339.111087) (xy 44.978534 -339.141346) (xy 44.991872 -339.16889) (xy 45.001942 -339.180424)
			(xy 45.021201 -339.201761) (xy 45.05377 -339.24912) (xy 45.078865 -339.300829) (xy 45.095918 -339.355718)
			(xy 45.104544 -339.412544) (xy 45.105066 -339.441282) (xy 45.104581 -339.467882) (xy 45.097208 -339.520567)
			(xy 45.08259 -339.571718) (xy 45.061009 -339.620343) (xy 45.032883 -339.665499) (xy 44.998758 -339.706312)
			(xy 44.979336 -339.724492) (xy 44.969028 -339.734492) (xy 44.953929 -339.758905) (xy 44.946218 -339.786555)
			(xy 44.946504 -339.815258) (xy 44.954764 -339.842749) (xy 44.970345 -339.866857) (xy 44.98086 -339.876638)
			(xy 45.001164 -339.894857) (xy 45.0369 -339.936073) (xy 45.066404 -339.981956) (xy 45.089075 -340.031573)
			(xy 45.104452 -340.083912) (xy 45.112221 -340.137907) (xy 45.112686 -340.165182) (xy 45.112686 -340.165436)
			(xy 45.112546 -340.172802) (xy 47.71263 -340.172802) (xy 47.713127 -340.145156) (xy 47.721126 -340.090444)
			(xy 47.736942 -340.037461) (xy 47.760243 -339.987318) (xy 47.790542 -339.941065) (xy 47.827203 -339.899672)
			(xy 47.848012 -339.881464) (xy 47.858786 -339.871635) (xy 47.874807 -339.847284) (xy 47.883311 -339.819404)
			(xy 47.883608 -339.790257) (xy 47.875673 -339.762209) (xy 47.860151 -339.737538) (xy 47.849536 -339.72754)
			(xy 47.829588 -339.709355) (xy 47.794526 -339.668314) (xy 47.765598 -339.622741) (xy 47.743382 -339.573546)
			(xy 47.728321 -339.521712) (xy 47.720716 -339.468271) (xy 47.72025 -339.441282) (xy 47.720776 -339.412543)
			(xy 47.7294 -339.355717) (xy 47.74645 -339.300827) (xy 47.771541 -339.249115) (xy 47.804104 -339.201752)
			(xy 47.823374 -339.180424) (xy 47.833463 -339.168904) (xy 47.846803 -339.141353) (xy 47.851384 -339.111087)
			(xy 47.846795 -339.080822) (xy 47.833448 -339.053274) (xy 47.823374 -339.04174) (xy 47.804101 -339.020415)
			(xy 47.771533 -338.973053) (xy 47.746441 -338.921341) (xy 47.729391 -338.86645) (xy 47.72077 -338.809621)
			(xy 47.72025 -338.780882) (xy 47.720761 -338.753632) (xy 47.728519 -338.699688) (xy 47.743874 -338.647396)
			(xy 47.766514 -338.597821) (xy 47.795979 -338.551973) (xy 47.831667 -338.510784) (xy 47.872854 -338.475093)
			(xy 47.9187 -338.445626) (xy 47.968273 -338.422982) (xy 48.020564 -338.407624) (xy 48.074508 -338.399863)
			(xy 48.101758 -338.399374) (xy 48.130498 -338.399869) (xy 48.187326 -338.4085) (xy 48.242217 -338.425557)
			(xy 48.293928 -338.450655) (xy 48.34129 -338.483225) (xy 48.362616 -338.502498) (xy 48.37415 -338.51257)
			(xy 48.401696 -338.525912) (xy 48.431958 -338.530497) (xy 48.46222 -338.525912) (xy 48.489766 -338.51257)
			(xy 48.5013 -338.502498) (xy 48.522627 -338.483228) (xy 48.56999 -338.450663) (xy 48.621701 -338.425572)
			(xy 48.676592 -338.408522) (xy 48.733419 -338.3999) (xy 48.790897 -338.3999) (xy 48.847724 -338.408522)
			(xy 48.902615 -338.425572) (xy 48.954326 -338.450663) (xy 49.001689 -338.483228) (xy 49.023016 -338.502498)
			(xy 49.03455 -338.51257) (xy 49.062096 -338.525912) (xy 49.092358 -338.530497) (xy 49.12262 -338.525912)
			(xy 49.150166 -338.51257) (xy 49.1617 -338.502498) (xy 49.183012 -338.48321) (xy 49.230377 -338.450644)
			(xy 49.282093 -338.425554) (xy 49.336987 -338.408508) (xy 49.393818 -338.399891) (xy 49.422558 -338.399374)
			(xy 49.449809 -338.399894) (xy 49.503757 -338.407645) (xy 49.556053 -338.422995) (xy 49.605631 -338.445631)
			(xy 49.651484 -338.475093) (xy 49.692677 -338.510781) (xy 49.728371 -338.551968) (xy 49.75784 -338.597816)
			(xy 49.780484 -338.647391) (xy 49.795842 -338.699684) (xy 49.803601 -338.753631) (xy 49.804066 -338.780882)
			(xy 49.803514 -338.80962) (xy 49.794895 -338.866445) (xy 49.777851 -338.921335) (xy 49.752766 -338.973047)
			(xy 49.720209 -339.020411) (xy 49.700942 -339.04174) (xy 49.690887 -339.053288) (xy 49.677541 -339.080829)
			(xy 49.672953 -339.111087) (xy 49.677534 -339.141346) (xy 49.690872 -339.16889) (xy 49.700942 -339.180424)
			(xy 49.720201 -339.201761) (xy 49.75277 -339.24912) (xy 49.777865 -339.300829) (xy 49.794918 -339.355718)
			(xy 49.803544 -339.412544) (xy 49.804066 -339.441282) (xy 49.80356 -339.468928) (xy 49.795563 -339.523639)
			(xy 49.779749 -339.576622) (xy 49.756449 -339.626766) (xy 49.726152 -339.673019) (xy 49.689493 -339.714412)
			(xy 49.668684 -339.73262) (xy 49.657819 -339.742361) (xy 49.641786 -339.766732) (xy 49.633283 -339.794638)
			(xy 49.633002 -339.823809) (xy 49.640965 -339.851874) (xy 49.656525 -339.87655) (xy 49.66716 -339.886544)
			(xy 49.687099 -339.904738) (xy 49.722162 -339.945777) (xy 49.751091 -339.991348) (xy 49.773309 -340.040541)
			(xy 49.788372 -340.092374) (xy 49.795979 -340.145813) (xy 49.796446 -340.172802) (xy 49.795882 -340.20136)
			(xy 49.787374 -340.257838) (xy 49.770547 -340.312419) (xy 49.745777 -340.363885) (xy 49.713618 -340.411086)
			(xy 49.694592 -340.43239) (xy 49.684469 -340.444114) (xy 49.671114 -340.472041) (xy 49.666746 -340.502687)
			(xy 49.671766 -340.533234) (xy 49.685713 -340.56087) (xy 49.696116 -340.572344) (xy 49.71624 -340.593841)
			(xy 49.750307 -340.641867) (xy 49.776592 -340.694557) (xy 49.794471 -340.750658) (xy 49.803519 -340.808841)
			(xy 49.804066 -340.838282) (xy 49.803598 -340.865652) (xy 49.795782 -340.919832) (xy 49.780294 -340.972335)
			(xy 49.757452 -341.022082) (xy 49.727727 -341.068049) (xy 49.710086 -341.08898) (xy 49.700868 -341.100321)
			(xy 49.68869 -341.126874) (xy 49.684514 -341.155786) (xy 49.688682 -341.1847) (xy 49.700853 -341.211256)
			(xy 49.710086 -341.222584) (xy 49.727709 -341.243531) (xy 49.757433 -341.289497) (xy 49.780279 -341.339241)
			(xy 49.795776 -341.391741) (xy 49.803606 -341.445917) (xy 49.803608 -341.500656) (xy 49.795782 -341.554833)
			(xy 49.780288 -341.607334) (xy 49.757446 -341.657079) (xy 49.727725 -341.703047) (xy 49.710086 -341.72398)
			(xy 49.700868 -341.735321) (xy 49.68869 -341.761874) (xy 49.684514 -341.790786) (xy 49.688682 -341.8197)
			(xy 49.700853 -341.846256) (xy 49.710086 -341.857584) (xy 49.727709 -341.878531) (xy 49.757433 -341.924497)
			(xy 49.780279 -341.974241) (xy 49.795776 -342.026741) (xy 49.803606 -342.080917) (xy 49.803608 -342.135656)
			(xy 49.795782 -342.189833) (xy 49.780288 -342.242334) (xy 49.757446 -342.292079) (xy 49.727725 -342.338047)
			(xy 49.710086 -342.35898) (xy 49.700868 -342.370321) (xy 49.68869 -342.396874) (xy 49.684514 -342.425786)
			(xy 49.688682 -342.4547) (xy 49.700853 -342.481256) (xy 49.710086 -342.492584) (xy 49.727729 -342.513513)
			(xy 49.757441 -342.559486) (xy 49.780276 -342.609235) (xy 49.795766 -342.661736) (xy 49.803593 -342.715913)
			(xy 49.804066 -342.743282) (xy 49.803628 -342.770536) (xy 49.795872 -342.82449) (xy 49.780516 -342.876791)
			(xy 49.757873 -342.926374) (xy 49.728403 -342.972229) (xy 49.692706 -343.013423) (xy 49.65151 -343.049117)
			(xy 49.605653 -343.078584) (xy 49.556069 -343.101225) (xy 49.503767 -343.116577) (xy 49.449812 -343.12433)
			(xy 49.422558 -343.12479) (xy 49.393818 -343.124294) (xy 49.336989 -343.115665) (xy 49.282098 -343.098609)
			(xy 49.230387 -343.073511) (xy 49.183026 -343.04094) (xy 49.1617 -343.021666) (xy 49.150166 -343.011594)
			(xy 49.12262 -342.998252) (xy 49.092358 -342.993667) (xy 49.062096 -342.998252) (xy 49.03455 -343.011594)
			(xy 49.023016 -343.021666) (xy 49.001689 -343.040936) (xy 48.954326 -343.073501) (xy 48.902615 -343.098592)
			(xy 48.847724 -343.115642) (xy 48.790897 -343.124264) (xy 48.733419 -343.124264) (xy 48.676592 -343.115642)
			(xy 48.621701 -343.098592) (xy 48.56999 -343.073501) (xy 48.522627 -343.040936) (xy 48.5013 -343.021666)
			(xy 48.489766 -343.011594) (xy 48.46222 -342.998252) (xy 48.431958 -342.993667) (xy 48.401696 -342.998252)
			(xy 48.37415 -343.011594) (xy 48.362616 -343.021666) (xy 48.341307 -343.040957) (xy 48.29394 -343.073521)
			(xy 48.242224 -343.098609) (xy 48.187329 -343.115655) (xy 48.130498 -343.124272) (xy 48.101758 -343.12479)
			(xy 48.074505 -343.124361) (xy 48.020554 -343.116599) (xy 47.968257 -343.101237) (xy 47.918679 -343.07859)
			(xy 47.872828 -343.049117) (xy 47.831637 -343.01342) (xy 47.795947 -342.972224) (xy 47.766481 -342.926369)
			(xy 47.743842 -342.876786) (xy 47.728489 -342.824487) (xy 47.720735 -342.770535) (xy 47.72025 -342.743282)
			(xy 47.720693 -342.715911) (xy 47.728515 -342.66173) (xy 47.744008 -342.609226) (xy 47.766856 -342.55948)
			(xy 47.796586 -342.513514) (xy 47.81423 -342.492584) (xy 47.823482 -342.481269) (xy 47.835653 -342.454706)
			(xy 47.839821 -342.425786) (xy 47.835646 -342.396868) (xy 47.823467 -342.370308) (xy 47.81423 -342.35898)
			(xy 47.796572 -342.338062) (xy 47.766847 -342.292091) (xy 47.744003 -342.242343) (xy 47.728508 -342.189839)
			(xy 47.720681 -342.135658) (xy 47.720683 -342.080915) (xy 47.728514 -342.026735) (xy 47.744012 -341.974232)
			(xy 47.76686 -341.924485) (xy 47.796588 -341.878517) (xy 47.81423 -341.857584) (xy 47.823482 -341.846269)
			(xy 47.835653 -341.819706) (xy 47.839821 -341.790786) (xy 47.835646 -341.761868) (xy 47.823467 -341.735308)
			(xy 47.81423 -341.72398) (xy 47.796572 -341.703062) (xy 47.766847 -341.657091) (xy 47.744003 -341.607343)
			(xy 47.728508 -341.554839) (xy 47.720681 -341.500658) (xy 47.720683 -341.445915) (xy 47.728514 -341.391735)
			(xy 47.744012 -341.339232) (xy 47.76686 -341.289485) (xy 47.796588 -341.243517) (xy 47.81423 -341.222584)
			(xy 47.823482 -341.211269) (xy 47.835653 -341.184706) (xy 47.839821 -341.155786) (xy 47.835646 -341.126868)
			(xy 47.823467 -341.100308) (xy 47.81423 -341.08898) (xy 47.79662 -341.068025) (xy 47.766902 -341.022059)
			(xy 47.74406 -340.972317) (xy 47.728563 -340.919822) (xy 47.720728 -340.86565) (xy 47.72025 -340.838282)
			(xy 47.720805 -340.809724) (xy 47.729316 -340.753245) (xy 47.746145 -340.698664) (xy 47.770916 -340.647199)
			(xy 47.803078 -340.599998) (xy 47.822104 -340.578694) (xy 47.832243 -340.566983) (xy 47.845597 -340.539051)
			(xy 47.849963 -340.508401) (xy 47.844938 -340.477852) (xy 47.830985 -340.450214) (xy 47.82058 -340.43874)
			(xy 47.800448 -340.417251) (xy 47.766382 -340.369222) (xy 47.740099 -340.316531) (xy 47.722222 -340.260427)
			(xy 47.713176 -340.202243) (xy 47.71263 -340.172802) (xy 45.112546 -340.172802) (xy 45.11212 -340.19527)
			(xy 45.102814 -340.254209) (xy 45.08445 -340.310983) (xy 45.057476 -340.364207) (xy 45.022548 -340.412585)
			(xy 45.001942 -340.434168) (xy 44.991253 -340.445671) (xy 44.976891 -340.47358) (xy 44.971683 -340.504532)
			(xy 44.976121 -340.535604) (xy 44.989785 -340.56386) (xy 45.000164 -340.575646) (xy 45.019724 -340.597046)
			(xy 45.052847 -340.644627) (xy 45.078382 -340.696675) (xy 45.095741 -340.751989) (xy 45.104523 -340.809295)
			(xy 45.105066 -340.838282) (xy 45.104598 -340.865652) (xy 45.096782 -340.919832) (xy 45.081294 -340.972335)
			(xy 45.058452 -341.022082) (xy 45.028727 -341.068049) (xy 45.011086 -341.08898) (xy 45.001868 -341.100321)
			(xy 44.98969 -341.126874) (xy 44.985514 -341.155786) (xy 44.989682 -341.1847) (xy 45.001853 -341.211256)
			(xy 45.011086 -341.222584) (xy 45.028709 -341.243531) (xy 45.058433 -341.289497) (xy 45.081279 -341.339241)
			(xy 45.096776 -341.391741) (xy 45.104606 -341.445917) (xy 45.104608 -341.500656) (xy 45.096782 -341.554833)
			(xy 45.081288 -341.607334) (xy 45.058446 -341.657079) (xy 45.028725 -341.703047) (xy 45.011086 -341.72398)
			(xy 45.001868 -341.735321) (xy 44.98969 -341.761874) (xy 44.985514 -341.790786) (xy 44.989682 -341.8197)
			(xy 45.001853 -341.846256) (xy 45.011086 -341.857584) (xy 45.028709 -341.878531) (xy 45.058433 -341.924497)
			(xy 45.081279 -341.974241) (xy 45.096776 -342.026741) (xy 45.104606 -342.080917) (xy 45.104608 -342.135656)
			(xy 45.096782 -342.189833) (xy 45.081288 -342.242334) (xy 45.058446 -342.292079) (xy 45.028725 -342.338047)
			(xy 45.011086 -342.35898) (xy 45.001868 -342.370321) (xy 44.98969 -342.396874) (xy 44.985514 -342.425786)
			(xy 44.989682 -342.4547) (xy 45.001853 -342.481256) (xy 45.011086 -342.492584) (xy 45.028729 -342.513513)
			(xy 45.058441 -342.559486) (xy 45.081276 -342.609235) (xy 45.096766 -342.661736) (xy 45.104593 -342.715913)
			(xy 45.105066 -342.743282) (xy 45.104628 -342.770536) (xy 45.096872 -342.82449) (xy 45.081516 -342.876791)
			(xy 45.058873 -342.926374) (xy 45.029403 -342.972229) (xy 44.993706 -343.013423) (xy 44.95251 -343.049117)
			(xy 44.906653 -343.078584) (xy 44.857069 -343.101225) (xy 44.804767 -343.116577) (xy 44.750812 -343.12433)
			(xy 44.723558 -343.12479) (xy 44.694818 -343.124294) (xy 44.637989 -343.115665) (xy 44.583098 -343.098609)
			(xy 44.531387 -343.073511) (xy 44.484026 -343.04094) (xy 44.4627 -343.021666) (xy 44.451166 -343.011594)
			(xy 44.42362 -342.998252) (xy 44.393358 -342.993667) (xy 44.363096 -342.998252) (xy 44.33555 -343.011594)
			(xy 44.324016 -343.021666) (xy 44.302689 -343.040936) (xy 44.255326 -343.073501) (xy 44.203615 -343.098592)
			(xy 44.148724 -343.115642) (xy 44.091897 -343.124264) (xy 44.034419 -343.124264) (xy 43.977592 -343.115642)
			(xy 43.922701 -343.098592) (xy 43.87099 -343.073501) (xy 43.823627 -343.040936) (xy 43.8023 -343.021666)
			(xy 43.790766 -343.011594) (xy 43.76322 -342.998252) (xy 43.732958 -342.993667) (xy 43.702696 -342.998252)
			(xy 43.67515 -343.011594) (xy 43.663616 -343.021666) (xy 43.642307 -343.040957) (xy 43.59494 -343.073521)
			(xy 43.543224 -343.098609) (xy 43.488329 -343.115655) (xy 43.431498 -343.124272) (xy 43.402758 -343.12479)
			(xy 43.375505 -343.124361) (xy 43.321554 -343.116599) (xy 43.269257 -343.101237) (xy 43.219679 -343.07859)
			(xy 43.173828 -343.049117) (xy 43.132637 -343.01342) (xy 43.096947 -342.972224) (xy 43.067481 -342.926369)
			(xy 43.044842 -342.876786) (xy 43.029489 -342.824487) (xy 43.021735 -342.770535) (xy 43.02125 -342.743282)
			(xy 40.126666 -342.743282) (xy 40.126228 -342.770536) (xy 40.118472 -342.82449) (xy 40.103116 -342.876791)
			(xy 40.080473 -342.926374) (xy 40.051003 -342.972229) (xy 40.015306 -343.013423) (xy 39.97411 -343.049117)
			(xy 39.928253 -343.078584) (xy 39.878669 -343.101225) (xy 39.826367 -343.116577) (xy 39.772412 -343.12433)
			(xy 39.745158 -343.12479) (xy 39.716418 -343.124294) (xy 39.659589 -343.115665) (xy 39.604698 -343.098609)
			(xy 39.552987 -343.073511) (xy 39.505626 -343.04094) (xy 39.4843 -343.021666) (xy 39.472766 -343.011594)
			(xy 39.44522 -342.998252) (xy 39.414958 -342.993667) (xy 39.384696 -342.998252) (xy 39.35715 -343.011594)
			(xy 39.345616 -343.021666) (xy 39.324289 -343.040936) (xy 39.276926 -343.073501) (xy 39.225215 -343.098592)
			(xy 39.170324 -343.115642) (xy 39.113497 -343.124264) (xy 39.056019 -343.124264) (xy 38.999192 -343.115642)
			(xy 38.944301 -343.098592) (xy 38.89259 -343.073501) (xy 38.845227 -343.040936) (xy 38.8239 -343.021666)
			(xy 38.812366 -343.011594) (xy 38.78482 -342.998252) (xy 38.754558 -342.993667) (xy 38.724296 -342.998252)
			(xy 38.69675 -343.011594) (xy 38.685216 -343.021666) (xy 38.663907 -343.040957) (xy 38.61654 -343.073521)
			(xy 38.564824 -343.098609) (xy 38.509929 -343.115655) (xy 38.453098 -343.124272) (xy 38.424358 -343.12479)
			(xy 38.397105 -343.124361) (xy 38.343154 -343.116599) (xy 38.290857 -343.101237) (xy 38.241279 -343.07859)
			(xy 38.195428 -343.049117) (xy 38.154237 -343.01342) (xy 38.118547 -342.972224) (xy 38.089081 -342.926369)
			(xy 38.066442 -342.876786) (xy 38.051089 -342.824487) (xy 38.043335 -342.770535) (xy 38.04285 -342.743282)
			(xy 38.043293 -342.715911) (xy 38.051115 -342.66173) (xy 38.066608 -342.609226) (xy 38.089456 -342.55948)
			(xy 38.119186 -342.513514) (xy 38.13683 -342.492584) (xy 38.146082 -342.481269) (xy 38.158253 -342.454706)
			(xy 38.162421 -342.425786) (xy 38.158246 -342.396868) (xy 38.146067 -342.370308) (xy 38.13683 -342.35898)
			(xy 38.119172 -342.338062) (xy 38.089447 -342.292091) (xy 38.066603 -342.242343) (xy 38.051108 -342.189839)
			(xy 38.043281 -342.135658) (xy 38.043283 -342.080915) (xy 38.051114 -342.026735) (xy 38.066612 -341.974232)
			(xy 38.08946 -341.924485) (xy 38.119188 -341.878517) (xy 38.13683 -341.857584) (xy 38.146082 -341.846269)
			(xy 38.158253 -341.819706) (xy 38.162421 -341.790786) (xy 38.158246 -341.761868) (xy 38.146067 -341.735308)
			(xy 38.13683 -341.72398) (xy 38.119172 -341.703062) (xy 38.089447 -341.657091) (xy 38.066603 -341.607343)
			(xy 38.051108 -341.554839) (xy 38.043281 -341.500658) (xy 38.043283 -341.445915) (xy 38.051114 -341.391735)
			(xy 38.066612 -341.339232) (xy 38.08946 -341.289485) (xy 38.119188 -341.243517) (xy 38.13683 -341.222584)
			(xy 38.146082 -341.211269) (xy 38.158253 -341.184706) (xy 38.162421 -341.155786) (xy 38.158246 -341.126868)
			(xy 38.146067 -341.100308) (xy 38.13683 -341.08898) (xy 38.11922 -341.068025) (xy 38.089502 -341.022059)
			(xy 38.06666 -340.972317) (xy 38.051163 -340.919822) (xy 38.043328 -340.86565) (xy 38.04285 -340.838282)
			(xy 38.043409 -340.808158) (xy 38.052893 -340.748661) (xy 38.071607 -340.691393) (xy 38.099085 -340.637776)
			(xy 38.134646 -340.589142) (xy 38.155626 -340.567518) (xy 38.164862 -340.557812) (xy 38.178306 -340.534645)
			(xy 38.185266 -340.50878) (xy 38.185263 -340.481995) (xy 38.178297 -340.456131) (xy 38.164846 -340.432968)
			(xy 38.155626 -340.423246) (xy 38.134647 -340.40162) (xy 38.099078 -340.352992) (xy 38.071597 -340.299376)
			(xy 38.052888 -340.242106) (xy 38.043418 -340.182606) (xy 38.04285 -340.152482) (xy 38.043236 -340.126961)
			(xy 38.050033 -340.076373) (xy 38.063518 -340.027143) (xy 38.083448 -339.980152) (xy 38.109469 -339.93624)
			(xy 38.141114 -339.896191) (xy 38.159182 -339.878162) (xy 38.168936 -339.868167) (xy 38.182971 -339.844031)
			(xy 38.189938 -339.816994) (xy 38.189313 -339.789081) (xy 38.181143 -339.762383) (xy 38.166041 -339.7389)
			(xy 38.15588 -339.729318) (xy 38.136067 -339.711138) (xy 38.101279 -339.670134) (xy 38.072584 -339.624658)
			(xy 38.05055 -339.575606) (xy 38.035614 -339.523949) (xy 38.02807 -339.470708) (xy 38.02761 -339.443822)
			(xy 34.902394 -339.443822) (xy 34.902394 -353.325176) (xy 35.596068 -353.325176) (xy 35.623302 -353.325636)
			(xy 35.677216 -353.333384) (xy 35.729479 -353.348726) (xy 35.779026 -353.37135) (xy 35.82485 -353.400795)
			(xy 35.866015 -353.436462) (xy 35.901686 -353.477625) (xy 35.931135 -353.523445) (xy 35.953763 -353.572991)
			(xy 35.969109 -353.625252) (xy 35.976861 -353.679166) (xy 35.976861 -353.733634) (xy 35.969109 -353.787548)
			(xy 35.953763 -353.839809) (xy 35.931135 -353.889355) (xy 35.901686 -353.935175) (xy 35.866015 -353.976338)
			(xy 35.82485 -354.012005) (xy 35.779026 -354.04145) (xy 35.729479 -354.064074) (xy 35.677216 -354.079416)
			(xy 35.623302 -354.087164) (xy 35.596068 -354.087684) (xy 34.902394 -354.087684) (xy 34.902394 -354.65385)
			(xy 35.21405 -354.65385) (xy 35.218121 -354.598228) (xy 35.230247 -354.543791) (xy 35.25017 -354.4917)
			(xy 35.277466 -354.443065) (xy 35.311552 -354.398922) (xy 35.351701 -354.360213) (xy 35.397059 -354.327762)
			(xy 35.446659 -354.302261) (xy 35.499443 -354.284254) (xy 35.554286 -354.274124) (xy 35.61002 -354.272087)
			(xy 35.665457 -354.278187) (xy 35.719414 -354.292293) (xy 35.770743 -354.314105) (xy 35.818349 -354.343159)
			(xy 35.861217 -354.378834) (xy 35.898434 -354.420371) (xy 35.929207 -354.466884) (xy 35.952879 -354.517381)
			(xy 35.968947 -354.570788) (xy 35.977067 -354.625964) (xy 35.977576 -354.65385) (xy 35.977067 -354.681736)
			(xy 35.968947 -354.736912) (xy 35.952879 -354.790319) (xy 35.929207 -354.840816) (xy 35.898434 -354.887329)
			(xy 35.861217 -354.928866) (xy 35.818349 -354.964541) (xy 35.770743 -354.993595) (xy 35.721478 -355.01453)
			(xy 37.608764 -355.01453) (xy 37.608764 -355.014276) (xy 37.609295 -354.986262) (xy 37.617514 -354.93084)
			(xy 37.633742 -354.877213) (xy 37.657631 -354.826533) (xy 37.688668 -354.779887) (xy 37.707062 -354.758752)
			(xy 37.716729 -354.747326) (xy 37.729509 -354.720278) (xy 37.733892 -354.690685) (xy 37.7295 -354.661093)
			(xy 37.716712 -354.634049) (xy 37.707062 -354.622608) (xy 37.688634 -354.601497) (xy 37.657566 -354.55486)
			(xy 37.633664 -354.504176) (xy 37.617442 -354.450538) (xy 37.609252 -354.395103) (xy 37.608764 -354.367084)
			(xy 37.608764 -354.36683) (xy 37.60925 -354.339579) (xy 37.617006 -354.285631) (xy 37.632361 -354.233336)
			(xy 37.655003 -354.183759) (xy 37.684469 -354.137909) (xy 37.72016 -354.096718) (xy 37.761351 -354.061027)
			(xy 37.807201 -354.031561) (xy 37.856778 -354.008919) (xy 37.909073 -353.993564) (xy 37.963021 -353.985808)
			(xy 38.017523 -353.985808) (xy 38.071471 -353.993564) (xy 38.123766 -354.008919) (xy 38.173343 -354.031561)
			(xy 38.219193 -354.061027) (xy 38.260384 -354.096718) (xy 38.296075 -354.137909) (xy 38.325541 -354.183759)
			(xy 38.348183 -354.233336) (xy 38.363538 -354.285631) (xy 38.371294 -354.339579) (xy 38.37178 -354.36683)
			(xy 38.37178 -354.367084) (xy 38.371299 -354.3951) (xy 38.36307 -354.450525) (xy 38.346831 -354.504153)
			(xy 38.322931 -354.554832) (xy 38.291882 -354.601475) (xy 38.273482 -354.622608) (xy 38.269002 -354.627942)
			(xy 45.58614 -354.627942) (xy 45.590211 -354.57232) (xy 45.602337 -354.517883) (xy 45.62226 -354.465792)
			(xy 45.649556 -354.417157) (xy 45.683642 -354.373014) (xy 45.723791 -354.334305) (xy 45.769149 -354.301854)
			(xy 45.818749 -354.276353) (xy 45.871533 -354.258346) (xy 45.926376 -354.248216) (xy 45.98211 -354.246179)
			(xy 46.037547 -354.252279) (xy 46.091504 -354.266385) (xy 46.142833 -354.288197) (xy 46.190439 -354.317251)
			(xy 46.233307 -354.352926) (xy 46.270524 -354.394463) (xy 46.301297 -354.440976) (xy 46.324969 -354.491473)
			(xy 46.341037 -354.54488) (xy 46.349157 -354.600056) (xy 46.349666 -354.627942) (xy 46.349157 -354.655828)
			(xy 46.341037 -354.711004) (xy 46.324969 -354.764411) (xy 46.301297 -354.814908) (xy 46.270524 -354.861421)
			(xy 46.233307 -354.902958) (xy 46.190439 -354.938633) (xy 46.142833 -354.967687) (xy 46.091504 -354.989499)
			(xy 46.037547 -355.003605) (xy 45.995969 -355.00818) (xy 47.297086 -355.00818) (xy 47.297544 -354.98081)
			(xy 47.305364 -354.92663) (xy 47.320855 -354.874127) (xy 47.343699 -354.82438) (xy 47.373424 -354.778414)
			(xy 47.391066 -354.757482) (xy 47.400325 -354.74617) (xy 47.412504 -354.719608) (xy 47.416674 -354.690685)
			(xy 47.412495 -354.661763) (xy 47.400308 -354.635204) (xy 47.391066 -354.623878) (xy 47.373445 -354.602932)
			(xy 47.343731 -354.556962) (xy 47.320893 -354.507218) (xy 47.305397 -354.454721) (xy 47.297563 -354.400548)
			(xy 47.297086 -354.37318) (xy 47.297572 -354.345929) (xy 47.305328 -354.291981) (xy 47.320683 -354.239686)
			(xy 47.343325 -354.190109) (xy 47.372791 -354.144259) (xy 47.408482 -354.103068) (xy 47.449673 -354.067377)
			(xy 47.495523 -354.037911) (xy 47.5451 -354.015269) (xy 47.597395 -353.999914) (xy 47.651343 -353.992158)
			(xy 47.705845 -353.992158) (xy 47.759793 -353.999914) (xy 47.812088 -354.015269) (xy 47.861665 -354.037911)
			(xy 47.907515 -354.067377) (xy 47.948706 -354.103068) (xy 47.984397 -354.144259) (xy 48.013863 -354.190109)
			(xy 48.036505 -354.239686) (xy 48.05186 -354.291981) (xy 48.059616 -354.345929) (xy 48.060102 -354.37318)
			(xy 48.059624 -354.40055) (xy 48.051809 -354.454728) (xy 48.036323 -354.507231) (xy 48.013484 -354.556978)
			(xy 47.983762 -354.602946) (xy 47.966122 -354.623878) (xy 47.956903 -354.635219) (xy 47.94472 -354.661771)
			(xy 47.940543 -354.690685) (xy 47.944712 -354.7196) (xy 47.956886 -354.746156) (xy 47.966122 -354.757482)
			(xy 47.98377 -354.778407) (xy 48.013479 -354.824382) (xy 48.036313 -354.874132) (xy 48.051802 -354.926634)
			(xy 48.059629 -354.98081) (xy 48.060102 -355.00818) (xy 48.059616 -355.035431) (xy 48.05186 -355.089379)
			(xy 48.036505 -355.141674) (xy 48.013863 -355.191251) (xy 47.984397 -355.237101) (xy 47.948706 -355.278292)
			(xy 47.907515 -355.313983) (xy 47.861665 -355.343449) (xy 47.812088 -355.366091) (xy 47.759793 -355.381446)
			(xy 47.705845 -355.389202) (xy 47.651343 -355.389202) (xy 47.597395 -355.381446) (xy 47.5451 -355.366091)
			(xy 47.495523 -355.343449) (xy 47.449673 -355.313983) (xy 47.408482 -355.278292) (xy 47.372791 -355.237101)
			(xy 47.343325 -355.191251) (xy 47.320683 -355.141674) (xy 47.305328 -355.089379) (xy 47.297572 -355.035431)
			(xy 47.297086 -355.00818) (xy 45.995969 -355.00818) (xy 45.98211 -355.009705) (xy 45.926376 -355.007668)
			(xy 45.871533 -354.997538) (xy 45.818749 -354.979531) (xy 45.769149 -354.95403) (xy 45.723791 -354.921579)
			(xy 45.683642 -354.88287) (xy 45.649556 -354.838727) (xy 45.62226 -354.790092) (xy 45.602337 -354.738001)
			(xy 45.590211 -354.683564) (xy 45.58614 -354.627942) (xy 38.269002 -354.627942) (xy 38.263859 -354.634066)
			(xy 38.251081 -354.661104) (xy 38.246693 -354.690685) (xy 38.251072 -354.720268) (xy 38.263843 -354.747309)
			(xy 38.273482 -354.758752) (xy 38.291898 -354.779873) (xy 38.322967 -354.826507) (xy 38.346871 -354.877189)
			(xy 38.363095 -354.930825) (xy 38.37129 -354.986258) (xy 38.37178 -355.014276) (xy 38.37178 -355.01453)
			(xy 38.371294 -355.041781) (xy 38.363538 -355.095729) (xy 38.348183 -355.148024) (xy 38.325541 -355.197601)
			(xy 38.296075 -355.243451) (xy 38.260384 -355.284642) (xy 38.219193 -355.320333) (xy 38.173343 -355.349799)
			(xy 38.123766 -355.372441) (xy 38.071471 -355.387796) (xy 38.017523 -355.395552) (xy 37.963021 -355.395552)
			(xy 37.909073 -355.387796) (xy 37.856778 -355.372441) (xy 37.807201 -355.349799) (xy 37.761351 -355.320333)
			(xy 37.72016 -355.284642) (xy 37.684469 -355.243451) (xy 37.655003 -355.197601) (xy 37.632361 -355.148024)
			(xy 37.617006 -355.095729) (xy 37.60925 -355.041781) (xy 37.608764 -355.01453) (xy 35.721478 -355.01453)
			(xy 35.719414 -355.015407) (xy 35.665457 -355.029513) (xy 35.61002 -355.035613) (xy 35.554286 -355.033576)
			(xy 35.499443 -355.023446) (xy 35.446659 -355.005439) (xy 35.397059 -354.979938) (xy 35.351701 -354.947487)
			(xy 35.311552 -354.908778) (xy 35.277466 -354.864635) (xy 35.25017 -354.816) (xy 35.230247 -354.763909)
			(xy 35.218121 -354.709472) (xy 35.21405 -354.65385) (xy 34.902394 -354.65385) (xy 34.902394 -355.4108)
			(xy 41.857303 -355.4108) (xy 41.861472 -355.355173) (xy 41.873886 -355.30079) (xy 41.894268 -355.248864)
			(xy 41.922161 -355.200556) (xy 41.956943 -355.156945) (xy 41.997837 -355.119006) (xy 42.04393 -355.087586)
			(xy 42.09419 -355.063388) (xy 42.147496 -355.046951) (xy 42.202657 -355.038644) (xy 42.230548 -355.038152)
			(xy 42.25788 -355.038623) (xy 42.31196 -355.046592) (xy 42.364295 -355.062379) (xy 42.41376 -355.085647)
			(xy 42.459292 -355.115895) (xy 42.499914 -355.152474) (xy 42.534753 -355.194597) (xy 42.549318 -355.21773)
			(xy 42.557239 -355.229955) (xy 42.578713 -355.249623) (xy 42.604866 -355.262425) (xy 42.633571 -355.267321)
			(xy 42.66249 -355.26391) (xy 42.676064 -355.258624) (xy 42.69928 -355.249149) (xy 42.74761 -355.235794)
			(xy 42.797297 -355.229059) (xy 42.822368 -355.228652) (xy 42.847438 -355.229064) (xy 42.897121 -355.235818)
			(xy 42.945455 -355.249155) (xy 42.968672 -355.258624) (xy 42.982249 -355.263871) (xy 43.011149 -355.267234)
			(xy 43.039827 -355.262322) (xy 43.065961 -355.249534) (xy 43.087437 -355.229904) (xy 43.095418 -355.21773)
			(xy 43.109987 -355.194599) (xy 43.14483 -355.152478) (xy 43.185453 -355.115899) (xy 43.230984 -355.085648)
			(xy 43.280446 -355.062372) (xy 43.332777 -355.046572) (xy 43.386856 -355.038586) (xy 43.44152 -355.038586)
			(xy 43.495599 -355.046572) (xy 43.54793 -355.062372) (xy 43.597392 -355.085648) (xy 43.642923 -355.115899)
			(xy 43.683546 -355.152478) (xy 43.718389 -355.194599) (xy 43.732958 -355.21773) (xy 43.740841 -355.229983)
			(xy 43.762325 -355.24965) (xy 43.788489 -355.262449) (xy 43.817203 -355.267337) (xy 43.846128 -355.263916)
			(xy 43.859704 -355.258624) (xy 43.882915 -355.249137) (xy 43.931247 -355.235786) (xy 43.980937 -355.229057)
			(xy 44.006008 -355.228652) (xy 44.033193 -355.229125) (xy 44.086987 -355.237015) (xy 44.139062 -355.252639)
			(xy 44.188314 -355.275667) (xy 44.233695 -355.305609) (xy 44.274243 -355.34183) (xy 44.309095 -355.383559)
			(xy 44.337512 -355.429911) (xy 44.348654 -355.454712) (xy 44.354556 -355.467303) (xy 44.371962 -355.48897)
			(xy 44.394568 -355.50514) (xy 44.420697 -355.514612) (xy 44.448413 -355.516686) (xy 44.475661 -355.511206)
			(xy 44.500421 -355.498581) (xy 44.51096 -355.48951) (xy 44.532202 -355.470607) (xy 44.579249 -355.438674)
			(xy 44.630518 -355.414084) (xy 44.684871 -355.397383) (xy 44.741102 -355.388941) (xy 44.769532 -355.388418)
			(xy 44.787551 -355.38864) (xy 44.823426 -355.392074) (xy 44.84116 -355.395276) (xy 44.856375 -355.397561)
			(xy 44.88692 -355.394044) (xy 44.915035 -355.381595) (xy 44.93817 -355.361343) (xy 44.954229 -355.335122)
			(xy 44.958508 -355.320346) (xy 44.965907 -355.293302) (xy 44.987537 -355.241577) (xy 45.016502 -355.193572)
			(xy 45.052177 -355.15032) (xy 45.093796 -355.112754) (xy 45.140463 -355.081679) (xy 45.191174 -355.057766)
			(xy 45.244838 -355.041529) (xy 45.300299 -355.033317) (xy 45.328332 -355.032818) (xy 45.355585 -355.033248)
			(xy 45.409536 -355.04101) (xy 45.461834 -355.05637) (xy 45.511413 -355.079017) (xy 45.557264 -355.108489)
			(xy 45.598455 -355.144186) (xy 45.634146 -355.185382) (xy 45.663611 -355.231238) (xy 45.68625 -355.280821)
			(xy 45.701603 -355.33312) (xy 45.709356 -355.387073) (xy 45.709777 -355.4108) (xy 51.545729 -355.4108)
			(xy 51.549897 -355.355185) (xy 51.562307 -355.300812) (xy 51.582681 -355.248895) (xy 51.610566 -355.200595)
			(xy 51.645337 -355.15699) (xy 51.686219 -355.119054) (xy 51.732297 -355.087635) (xy 51.782544 -355.063434)
			(xy 51.835837 -355.046991) (xy 51.890984 -355.038675) (xy 51.91887 -355.038152) (xy 51.946203 -355.038606)
			(xy 52.000284 -355.046577) (xy 52.052619 -355.062368) (xy 52.102083 -355.085639) (xy 52.147616 -355.115889)
			(xy 52.188237 -355.15247) (xy 52.223075 -355.194596) (xy 52.23764 -355.21773) (xy 52.24554 -355.22997)
			(xy 52.267019 -355.249638) (xy 52.293179 -355.262438) (xy 52.321888 -355.26733) (xy 52.350811 -355.263914)
			(xy 52.364386 -355.258624) (xy 52.387599 -355.249143) (xy 52.43593 -355.235789) (xy 52.485619 -355.229058)
			(xy 52.51069 -355.228652) (xy 52.535759 -355.229089) (xy 52.585442 -355.235833) (xy 52.633776 -355.24916)
			(xy 52.656994 -355.258624) (xy 52.670599 -355.263789) (xy 52.699485 -355.267169) (xy 52.728153 -355.262276)
			(xy 52.754282 -355.249507) (xy 52.775757 -355.229895) (xy 52.78374 -355.21773) (xy 52.798309 -355.194599)
			(xy 52.833152 -355.152478) (xy 52.873775 -355.115899) (xy 52.919306 -355.085648) (xy 52.968768 -355.062372)
			(xy 53.021099 -355.046572) (xy 53.075178 -355.038586) (xy 53.129842 -355.038586) (xy 53.183921 -355.046572)
			(xy 53.236252 -355.062372) (xy 53.285714 -355.085648) (xy 53.331245 -355.115899) (xy 53.371868 -355.152478)
			(xy 53.406711 -355.194599) (xy 53.42128 -355.21773) (xy 53.429237 -355.229929) (xy 53.450701 -355.249597)
			(xy 53.476845 -355.262403) (xy 53.505541 -355.267305) (xy 53.534453 -355.263904) (xy 53.548026 -355.258624)
			(xy 53.571234 -355.24913) (xy 53.619568 -355.235782) (xy 53.669258 -355.229055) (xy 53.69433 -355.228652)
			(xy 53.721172 -355.22911) (xy 53.774301 -355.236818) (xy 53.825774 -355.25207) (xy 53.874526 -355.27455)
			(xy 53.919548 -355.303792) (xy 53.959907 -355.339193) (xy 53.994769 -355.380018) (xy 54.023412 -355.425424)
			(xy 54.045244 -355.47447) (xy 54.052978 -355.500178) (xy 54.057673 -355.514662) (xy 54.074188 -355.540221)
			(xy 54.097497 -355.559782) (xy 54.125532 -355.571613) (xy 54.155809 -355.574663) (xy 54.185641 -355.568663)
			(xy 54.199282 -355.5619) (xy 54.227424 -355.547258) (xy 54.287377 -355.526534) (xy 54.349937 -355.516039)
			(xy 54.381654 -355.515418) (xy 54.409825 -355.515918) (xy 54.465554 -355.524209) (xy 54.492652 -355.531928)
			(xy 54.506084 -355.535519) (xy 54.533869 -355.53613) (xy 54.56079 -355.529225) (xy 54.584851 -355.515317)
			(xy 54.60427 -355.495435) (xy 54.617608 -355.471053) (xy 54.623877 -355.443977) (xy 54.623716 -355.430074)
			(xy 54.623208 -355.413056) (xy 54.623208 -355.412802) (xy 54.623654 -355.385561) (xy 54.631447 -355.331638)
			(xy 54.64683 -355.279371) (xy 54.669492 -355.229825) (xy 54.698971 -355.184006) (xy 54.734668 -355.142846)
			(xy 54.775858 -355.107183) (xy 54.821701 -355.077741) (xy 54.871266 -355.05512) (xy 54.923545 -355.03978)
			(xy 54.977474 -355.032032) (xy 55.004716 -355.031548) (xy 55.031966 -355.032063) (xy 55.08591 -355.03982)
			(xy 55.138202 -355.055175) (xy 55.187776 -355.077815) (xy 55.233624 -355.107279) (xy 55.274813 -355.142967)
			(xy 55.310504 -355.184153) (xy 55.339972 -355.229999) (xy 55.362615 -355.279572) (xy 55.377974 -355.331863)
			(xy 55.385735 -355.385806) (xy 55.386224 -355.413056) (xy 55.38572 -355.440629) (xy 55.377774 -355.4952)
			(xy 55.362056 -355.548059) (xy 55.338893 -355.598105) (xy 55.308768 -355.644295) (xy 55.272308 -355.685669)
			(xy 55.251604 -355.703886) (xy 55.240751 -355.713829) (xy 55.224677 -355.738467) (xy 55.216288 -355.766663)
			(xy 55.216279 -355.79608) (xy 55.224653 -355.824281) (xy 55.240713 -355.848928) (xy 55.251604 -355.858826)
			(xy 55.272265 -355.87709) (xy 55.308728 -355.918455) (xy 55.338855 -355.964639) (xy 55.362019 -356.01468)
			(xy 55.377736 -356.067534) (xy 55.38568 -356.122101) (xy 55.385684 -356.177242) (xy 55.377749 -356.23181)
			(xy 55.362039 -356.284667) (xy 55.338883 -356.334711) (xy 55.308763 -356.3809) (xy 55.272306 -356.42227)
			(xy 55.251604 -356.440486) (xy 55.240751 -356.450429) (xy 55.224677 -356.475067) (xy 55.216288 -356.503263)
			(xy 55.216279 -356.53268) (xy 55.224653 -356.560881) (xy 55.240713 -356.585528) (xy 55.251604 -356.595426)
			(xy 55.272332 -356.613619) (xy 55.308801 -356.654992) (xy 55.338931 -356.701185) (xy 55.362093 -356.751237)
			(xy 55.377806 -356.804103) (xy 55.385741 -356.85868) (xy 55.386224 -356.886256) (xy 55.385704 -356.913507)
			(xy 55.377953 -356.967455) (xy 55.362604 -357.019751) (xy 55.339967 -357.06933) (xy 55.310505 -357.115182)
			(xy 55.274818 -357.156375) (xy 55.23363 -357.192069) (xy 55.187783 -357.221539) (xy 55.138207 -357.244183)
			(xy 55.085914 -357.25954) (xy 55.031967 -357.2673) (xy 55.004716 -357.267764) (xy 54.978798 -357.267319)
			(xy 54.927439 -357.26031) (xy 54.877503 -357.246404) (xy 54.829912 -357.22586) (xy 54.785546 -357.199055)
			(xy 54.745221 -357.166484) (xy 54.709682 -357.128749) (xy 54.679585 -357.086546) (xy 54.66715 -357.063802)
			(xy 54.659833 -357.051012) (xy 54.639245 -357.029952) (xy 54.613507 -357.015635) (xy 54.584755 -357.009251)
			(xy 54.555377 -357.011328) (xy 54.54142 -357.01605) (xy 54.509071 -357.027446) (xy 54.441598 -357.039713)
			(xy 54.407308 -357.040434) (xy 54.407054 -357.040434) (xy 54.392905 -357.040345) (xy 54.364682 -357.038308)
			(xy 54.350666 -357.03637) (xy 54.337314 -357.034836) (xy 54.31063 -357.037929) (xy 54.285681 -357.04789)
			(xy 54.264204 -357.064025) (xy 54.24769 -357.085213) (xy 54.237288 -357.10998) (xy 54.235096 -357.123238)
			(xy 54.231023 -357.150394) (xy 54.21605 -357.203226) (xy 54.193657 -357.253366) (xy 54.164308 -357.299777)
			(xy 54.12861 -357.341502) (xy 54.087298 -357.377679) (xy 54.041227 -357.407559) (xy 53.991348 -357.430527)
			(xy 53.938692 -357.446107) (xy 53.884346 -357.453977) (xy 53.85689 -357.454454) (xy 53.829641 -357.453932)
			(xy 53.775697 -357.446175) (xy 53.723405 -357.430821) (xy 53.673831 -357.408182) (xy 53.627983 -357.378719)
			(xy 53.586794 -357.343031) (xy 53.551103 -357.301846) (xy 53.521635 -357.256001) (xy 53.498992 -357.206428)
			(xy 53.483633 -357.154139) (xy 53.475871 -357.100195) (xy 53.475382 -357.072946) (xy 53.475886 -357.045373)
			(xy 53.483831 -356.990802) (xy 53.499549 -356.937943) (xy 53.522712 -356.887897) (xy 53.552838 -356.841707)
			(xy 53.589298 -356.800333) (xy 53.610002 -356.782116) (xy 53.620852 -356.77217) (xy 53.636926 -356.747533)
			(xy 53.645315 -356.719338) (xy 53.645323 -356.689921) (xy 53.636951 -356.661721) (xy 53.620892 -356.637075)
			(xy 53.610002 -356.627176) (xy 53.589276 -356.608981) (xy 53.552807 -356.567609) (xy 53.522677 -356.521415)
			(xy 53.499513 -356.471364) (xy 53.4838 -356.418499) (xy 53.475865 -356.363922) (xy 53.475382 -356.336346)
			(xy 53.475827 -356.309845) (xy 53.483175 -356.257353) (xy 53.497722 -356.206386) (xy 53.519187 -356.157924)
			(xy 53.547156 -356.112901) (xy 53.563774 -356.092252) (xy 53.573204 -356.080099) (xy 53.584989 -356.051701)
			(xy 53.587811 -356.021084) (xy 53.581417 -355.991011) (xy 53.566382 -355.964191) (xy 53.544063 -355.943044)
			(xy 53.5305 -355.935788) (xy 53.506801 -355.923703) (xy 53.462822 -355.893775) (xy 53.423543 -355.857899)
			(xy 53.389762 -355.816804) (xy 53.37556 -355.79431) (xy 53.36765 -355.782076) (xy 53.346176 -355.762403)
			(xy 53.320019 -355.749599) (xy 53.29131 -355.744707) (xy 53.262388 -355.748125) (xy 53.248814 -355.753416)
			(xy 53.2256 -355.762894) (xy 53.177269 -355.776249) (xy 53.127581 -355.782982) (xy 53.10251 -355.783388)
			(xy 53.077441 -355.782948) (xy 53.027759 -355.776205) (xy 52.979424 -355.762879) (xy 52.956206 -355.753416)
			(xy 52.942619 -355.748185) (xy 52.913715 -355.744801) (xy 52.885029 -355.749698) (xy 52.858885 -355.762479)
			(xy 52.837401 -355.782108) (xy 52.82946 -355.79431) (xy 52.814891 -355.817441) (xy 52.780048 -355.859562)
			(xy 52.739425 -355.896141) (xy 52.693894 -355.926392) (xy 52.644432 -355.949668) (xy 52.592101 -355.965468)
			(xy 52.538022 -355.973454) (xy 52.483358 -355.973454) (xy 52.429279 -355.965468) (xy 52.376948 -355.949668)
			(xy 52.327486 -355.926392) (xy 52.281955 -355.896141) (xy 52.241332 -355.859562) (xy 52.206489 -355.817441)
			(xy 52.19192 -355.79431) (xy 52.183953 -355.782117) (xy 52.162494 -355.762445) (xy 52.136353 -355.749635)
			(xy 52.107657 -355.744732) (xy 52.078746 -355.748134) (xy 52.065174 -355.753416) (xy 52.041965 -355.762907)
			(xy 51.993631 -355.776257) (xy 51.943942 -355.782985) (xy 51.91887 -355.783388) (xy 51.890984 -355.782925)
			(xy 51.835837 -355.774609) (xy 51.782544 -355.758166) (xy 51.732297 -355.733965) (xy 51.686219 -355.702546)
			(xy 51.645337 -355.66461) (xy 51.610566 -355.621005) (xy 51.582681 -355.572705) (xy 51.562307 -355.520788)
			(xy 51.549897 -355.466415) (xy 51.545729 -355.4108) (xy 45.709777 -355.4108) (xy 45.70984 -355.414326)
			(xy 45.709344 -355.4419) (xy 45.701401 -355.496472) (xy 45.685683 -355.549332) (xy 45.662519 -355.599379)
			(xy 45.632391 -355.645569) (xy 45.595926 -355.68694) (xy 45.57522 -355.705156) (xy 45.564295 -355.715027)
			(xy 45.548221 -355.739685) (xy 45.539839 -355.7679) (xy 45.539844 -355.797334) (xy 45.548235 -355.825546)
			(xy 45.564318 -355.850198) (xy 45.57522 -355.860096) (xy 45.595951 -355.878284) (xy 45.632412 -355.91966)
			(xy 45.662537 -355.965854) (xy 45.685697 -356.015904) (xy 45.70141 -356.068768) (xy 45.709347 -356.123342)
			(xy 45.709345 -356.178491) (xy 45.701402 -356.233065) (xy 45.685685 -356.285927) (xy 45.662521 -356.335976)
			(xy 45.632392 -356.382167) (xy 45.595927 -356.42354) (xy 45.57522 -356.441756) (xy 45.564295 -356.451627)
			(xy 45.548221 -356.476285) (xy 45.548141 -356.476554) (xy 48.08804 -356.476554) (xy 48.092111 -356.420932)
			(xy 48.104237 -356.366495) (xy 48.12416 -356.314404) (xy 48.151456 -356.265769) (xy 48.185542 -356.221626)
			(xy 48.225691 -356.182917) (xy 48.271049 -356.150466) (xy 48.320649 -356.124965) (xy 48.373433 -356.106958)
			(xy 48.428276 -356.096828) (xy 48.48401 -356.094791) (xy 48.539447 -356.100891) (xy 48.593404 -356.114997)
			(xy 48.644733 -356.136809) (xy 48.692339 -356.165863) (xy 48.735207 -356.201538) (xy 48.772424 -356.243075)
			(xy 48.803197 -356.289588) (xy 48.826869 -356.340085) (xy 48.842937 -356.393492) (xy 48.851057 -356.448668)
			(xy 48.851566 -356.476554) (xy 48.851057 -356.50444) (xy 48.842937 -356.559616) (xy 48.826869 -356.613023)
			(xy 48.803197 -356.66352) (xy 48.772424 -356.710033) (xy 48.735207 -356.75157) (xy 48.692339 -356.787245)
			(xy 48.644733 -356.816299) (xy 48.593404 -356.838111) (xy 48.539447 -356.852217) (xy 48.48401 -356.858317)
			(xy 48.428276 -356.85628) (xy 48.373433 -356.84615) (xy 48.320649 -356.828143) (xy 48.271049 -356.802642)
			(xy 48.225691 -356.770191) (xy 48.185542 -356.731482) (xy 48.151456 -356.687339) (xy 48.12416 -356.638704)
			(xy 48.104237 -356.586613) (xy 48.092111 -356.532176) (xy 48.08804 -356.476554) (xy 45.548141 -356.476554)
			(xy 45.539839 -356.5045) (xy 45.539844 -356.533934) (xy 45.548235 -356.562146) (xy 45.564318 -356.586798)
			(xy 45.57522 -356.596696) (xy 45.595936 -356.614901) (xy 45.632405 -356.656272) (xy 45.662536 -356.702463)
			(xy 45.685701 -356.752512) (xy 45.701417 -356.805375) (xy 45.709355 -356.859951) (xy 45.70984 -356.887526)
			(xy 45.709346 -356.914776) (xy 45.701587 -356.968722) (xy 45.68623 -357.021015) (xy 45.663589 -357.07059)
			(xy 45.634123 -357.116439) (xy 45.598432 -357.157628) (xy 45.557244 -357.193319) (xy 45.511395 -357.222786)
			(xy 45.46182 -357.245428) (xy 45.409528 -357.260786) (xy 45.355582 -357.268546) (xy 45.328332 -357.269034)
			(xy 45.300479 -357.268457) (xy 45.245367 -357.260339) (xy 45.192019 -357.244299) (xy 45.141568 -357.220679)
			(xy 45.095084 -357.189979) (xy 45.053555 -357.15285) (xy 45.01786 -357.110082) (xy 44.988758 -357.062581)
			(xy 44.966867 -357.011356) (xy 44.95927 -356.984554) (xy 44.955023 -356.97043) (xy 44.939621 -356.945288)
			(xy 44.917696 -356.925576) (xy 44.891063 -356.912927) (xy 44.861931 -356.90839) (xy 44.847256 -356.909878)
			(xy 44.834303 -356.911544) (xy 44.808245 -356.913321) (xy 44.795186 -356.913434) (xy 44.794932 -356.913434)
			(xy 44.794678 -356.913434) (xy 44.765642 -356.912893) (xy 44.708242 -356.90409) (xy 44.680378 -356.895908)
			(xy 44.66662 -356.892054) (xy 44.638072 -356.891306) (xy 44.610434 -356.898498) (xy 44.58587 -356.913066)
			(xy 44.566305 -356.933869) (xy 44.553269 -356.959279) (xy 44.547784 -356.987305) (xy 44.548552 -357.001572)
			(xy 44.550076 -357.034846) (xy 44.549665 -357.0621) (xy 44.541901 -357.116052) (xy 44.526539 -357.16835)
			(xy 44.50389 -357.21793) (xy 44.474416 -357.263781) (xy 44.443447 -357.299514) (xy 47.423576 -357.299514)
			(xy 47.427647 -357.243892) (xy 47.439773 -357.189455) (xy 47.459696 -357.137364) (xy 47.486992 -357.088729)
			(xy 47.521078 -357.044586) (xy 47.561227 -357.005877) (xy 47.606585 -356.973426) (xy 47.656185 -356.947925)
			(xy 47.708969 -356.929918) (xy 47.763812 -356.919788) (xy 47.819546 -356.917751) (xy 47.874983 -356.923851)
			(xy 47.92894 -356.937957) (xy 47.980269 -356.959769) (xy 48.027875 -356.988823) (xy 48.070743 -357.024498)
			(xy 48.10796 -357.066035) (xy 48.138733 -357.112548) (xy 48.162405 -357.163045) (xy 48.178473 -357.216452)
			(xy 48.186593 -357.271628) (xy 48.187102 -357.299514) (xy 48.186593 -357.3274) (xy 48.178473 -357.382576)
			(xy 48.162405 -357.435983) (xy 48.138733 -357.48648) (xy 48.10796 -357.532993) (xy 48.070743 -357.57453)
			(xy 48.027875 -357.610205) (xy 47.980269 -357.639259) (xy 47.92894 -357.661071) (xy 47.874983 -357.675177)
			(xy 47.819546 -357.681277) (xy 47.763812 -357.67924) (xy 47.708969 -357.66911) (xy 47.656185 -357.651103)
			(xy 47.606585 -357.625602) (xy 47.561227 -357.593151) (xy 47.521078 -357.554442) (xy 47.486992 -357.510299)
			(xy 47.459696 -357.461664) (xy 47.439773 -357.409573) (xy 47.427647 -357.355136) (xy 47.423576 -357.299514)
			(xy 44.443447 -357.299514) (xy 44.438717 -357.304972) (xy 44.397519 -357.340663) (xy 44.351661 -357.370127)
			(xy 44.302077 -357.392766) (xy 44.249776 -357.408118) (xy 44.195822 -357.41587) (xy 44.168568 -357.416354)
			(xy 44.141318 -357.415852) (xy 44.087373 -357.408092) (xy 44.035082 -357.392736) (xy 43.985507 -357.370094)
			(xy 43.939659 -357.340629) (xy 43.898471 -357.304939) (xy 43.86278 -357.263752) (xy 43.833313 -357.217905)
			(xy 43.810669 -357.168331) (xy 43.795311 -357.11604) (xy 43.787549 -357.062096) (xy 43.78706 -357.034846)
			(xy 43.787536 -357.007272) (xy 43.795484 -356.952698) (xy 43.811205 -356.899838) (xy 43.834373 -356.849791)
			(xy 43.864505 -356.803602) (xy 43.900973 -356.762231) (xy 43.92168 -356.744016) (xy 43.932533 -356.734071)
			(xy 43.948609 -356.709435) (xy 43.957 -356.681239) (xy 43.957009 -356.651821) (xy 43.948635 -356.623619)
			(xy 43.932572 -356.598973) (xy 43.92168 -356.589076) (xy 43.90095 -356.570885) (xy 43.864482 -356.529512)
			(xy 43.834353 -356.483317) (xy 43.81119 -356.433265) (xy 43.795478 -356.3804) (xy 43.787543 -356.325822)
			(xy 43.78706 -356.298246) (xy 43.787663 -356.268495) (xy 43.796938 -356.209719) (xy 43.81521 -356.15309)
			(xy 43.842036 -356.099976) (xy 43.858942 -356.075488) (xy 43.866861 -356.063559) (xy 43.87646 -356.036601)
			(xy 43.878193 -356.008037) (xy 43.871925 -355.980115) (xy 43.85815 -355.955033) (xy 43.83795 -355.934763)
			(xy 43.825668 -355.927406) (xy 43.804606 -355.915307) (xy 43.765515 -355.886475) (xy 43.7305 -355.852809)
			(xy 43.700154 -355.814881) (xy 43.687238 -355.79431) (xy 43.679349 -355.782061) (xy 43.657869 -355.762388)
			(xy 43.631706 -355.749586) (xy 43.602992 -355.744698) (xy 43.574067 -355.748121) (xy 43.560492 -355.753416)
			(xy 43.53728 -355.762901) (xy 43.488948 -355.776254) (xy 43.439259 -355.782984) (xy 43.414188 -355.783388)
			(xy 43.389119 -355.782955) (xy 43.339436 -355.776209) (xy 43.291102 -355.76288) (xy 43.267884 -355.753416)
			(xy 43.254305 -355.748162) (xy 43.225397 -355.744783) (xy 43.196708 -355.749685) (xy 43.170562 -355.762471)
			(xy 43.149078 -355.782106) (xy 43.141138 -355.79431) (xy 43.126569 -355.817441) (xy 43.091726 -355.859562)
			(xy 43.051103 -355.896141) (xy 43.005572 -355.926392) (xy 42.95611 -355.949668) (xy 42.903779 -355.965468)
			(xy 42.8497 -355.973454) (xy 42.795036 -355.973454) (xy 42.740957 -355.965468) (xy 42.688626 -355.949668)
			(xy 42.639164 -355.926392) (xy 42.593633 -355.896141) (xy 42.55301 -355.859562) (xy 42.518167 -355.817441)
			(xy 42.503598 -355.79431) (xy 42.495652 -355.782102) (xy 42.474188 -355.76243) (xy 42.44804 -355.749622)
			(xy 42.41934 -355.744723) (xy 42.390425 -355.748131) (xy 42.376852 -355.753416) (xy 42.353645 -355.762913)
			(xy 42.305311 -355.776261) (xy 42.25562 -355.782986) (xy 42.230548 -355.783388) (xy 42.202657 -355.782956)
			(xy 42.147496 -355.774649) (xy 42.09419 -355.758212) (xy 42.04393 -355.734014) (xy 41.997837 -355.702594)
			(xy 41.956943 -355.664655) (xy 41.922161 -355.621044) (xy 41.894268 -355.572736) (xy 41.873886 -355.52081)
			(xy 41.861472 -355.466427) (xy 41.857303 -355.4108) (xy 34.902394 -355.4108) (xy 34.902394 -356.80523)
			(xy 37.03396 -356.80523) (xy 37.038031 -356.749608) (xy 37.050157 -356.695171) (xy 37.07008 -356.64308)
			(xy 37.097376 -356.594445) (xy 37.131462 -356.550302) (xy 37.171611 -356.511593) (xy 37.216969 -356.479142)
			(xy 37.266569 -356.453641) (xy 37.319353 -356.435634) (xy 37.374196 -356.425504) (xy 37.42993 -356.423467)
			(xy 37.485367 -356.429567) (xy 37.539324 -356.443673) (xy 37.590653 -356.465485) (xy 37.60879 -356.476554)
			(xy 38.399718 -356.476554) (xy 38.403789 -356.420932) (xy 38.415915 -356.366495) (xy 38.435838 -356.314404)
			(xy 38.463134 -356.265769) (xy 38.49722 -356.221626) (xy 38.537369 -356.182917) (xy 38.582727 -356.150466)
			(xy 38.632327 -356.124965) (xy 38.685111 -356.106958) (xy 38.739954 -356.096828) (xy 38.795688 -356.094791)
			(xy 38.851125 -356.100891) (xy 38.905082 -356.114997) (xy 38.956411 -356.136809) (xy 39.004017 -356.165863)
			(xy 39.046885 -356.201538) (xy 39.084102 -356.243075) (xy 39.114875 -356.289588) (xy 39.138547 -356.340085)
			(xy 39.154615 -356.393492) (xy 39.162735 -356.448668) (xy 39.163244 -356.476554) (xy 39.162735 -356.50444)
			(xy 39.154615 -356.559616) (xy 39.138547 -356.613023) (xy 39.114875 -356.66352) (xy 39.084102 -356.710033)
			(xy 39.046885 -356.75157) (xy 39.004017 -356.787245) (xy 38.956411 -356.816299) (xy 38.905082 -356.838111)
			(xy 38.851125 -356.852217) (xy 38.795688 -356.858317) (xy 38.739954 -356.85628) (xy 38.685111 -356.84615)
			(xy 38.632327 -356.828143) (xy 38.582727 -356.802642) (xy 38.537369 -356.770191) (xy 38.49722 -356.731482)
			(xy 38.463134 -356.687339) (xy 38.435838 -356.638704) (xy 38.415915 -356.586613) (xy 38.403789 -356.532176)
			(xy 38.399718 -356.476554) (xy 37.60879 -356.476554) (xy 37.638259 -356.494539) (xy 37.681127 -356.530214)
			(xy 37.718344 -356.571751) (xy 37.749117 -356.618264) (xy 37.772789 -356.668761) (xy 37.788857 -356.722168)
			(xy 37.796977 -356.777344) (xy 37.797486 -356.80523) (xy 37.796977 -356.833116) (xy 37.788857 -356.888292)
			(xy 37.772789 -356.941699) (xy 37.749117 -356.992196) (xy 37.718344 -357.038709) (xy 37.681127 -357.080246)
			(xy 37.638259 -357.115921) (xy 37.590653 -357.144975) (xy 37.539324 -357.166787) (xy 37.485367 -357.180893)
			(xy 37.42993 -357.186993) (xy 37.374196 -357.184956) (xy 37.319353 -357.174826) (xy 37.266569 -357.156819)
			(xy 37.216969 -357.131318) (xy 37.171611 -357.098867) (xy 37.131462 -357.060158) (xy 37.097376 -357.016015)
			(xy 37.07008 -356.96738) (xy 37.050157 -356.915289) (xy 37.038031 -356.860852) (xy 37.03396 -356.80523)
			(xy 34.902394 -356.80523) (xy 34.902394 -357.98506) (xy 39.206424 -357.98506) (xy 39.206805 -357.95972)
			(xy 39.21352 -357.909488) (xy 39.226827 -357.860586) (xy 39.246491 -357.813877) (xy 39.272166 -357.770183)
			(xy 39.3034 -357.730272) (xy 39.321232 -357.712264) (xy 39.330672 -357.702529) (xy 39.344468 -357.679196)
			(xy 39.351619 -357.653049) (xy 39.351618 -357.625942) (xy 39.344464 -357.599795) (xy 39.330666 -357.576463)
			(xy 39.321232 -357.566722) (xy 39.30342 -357.548696) (xy 39.27219 -357.508788) (xy 39.246518 -357.465096)
			(xy 39.226857 -357.41839) (xy 39.213553 -357.369493) (xy 39.20684 -357.319264) (xy 39.206424 -357.293926)
			(xy 39.20691 -357.266675) (xy 39.214666 -357.212727) (xy 39.230021 -357.160432) (xy 39.252663 -357.110855)
			(xy 39.282129 -357.065005) (xy 39.31782 -357.023814) (xy 39.359011 -356.988123) (xy 39.404861 -356.958657)
			(xy 39.454438 -356.936015) (xy 39.506733 -356.92066) (xy 39.560681 -356.912904) (xy 39.615183 -356.912904)
			(xy 39.669131 -356.92066) (xy 39.721426 -356.936015) (xy 39.771003 -356.958657) (xy 39.816853 -356.988123)
			(xy 39.858044 -357.023814) (xy 39.893735 -357.065005) (xy 39.923201 -357.110855) (xy 39.945843 -357.160432)
			(xy 39.961198 -357.212727) (xy 39.968954 -357.266675) (xy 39.9691 -357.274876) (xy 40.83177 -357.274876)
			(xy 40.832255 -357.247625) (xy 40.840015 -357.193679) (xy 40.855372 -357.141385) (xy 40.878014 -357.091809)
			(xy 40.907481 -357.04596) (xy 40.943172 -357.004771) (xy 40.984362 -356.96908) (xy 41.030211 -356.939613)
			(xy 41.079787 -356.916971) (xy 41.132081 -356.901614) (xy 41.186027 -356.893855) (xy 41.213278 -356.893368)
			(xy 41.240528 -356.893899) (xy 41.294472 -356.901652) (xy 41.346765 -356.917003) (xy 41.39634 -356.939639)
			(xy 41.44219 -356.969101) (xy 41.483379 -357.004788) (xy 41.519071 -357.045974) (xy 41.548538 -357.091819)
			(xy 41.571181 -357.141392) (xy 41.586539 -357.193683) (xy 41.594298 -357.247626) (xy 41.594786 -357.274876)
			(xy 41.594544 -357.293543) (xy 41.590858 -357.330695) (xy 41.58742 -357.349044) (xy 41.585129 -357.363318)
			(xy 41.587649 -357.3921) (xy 41.598137 -357.419022) (xy 41.615752 -357.441924) (xy 41.63908 -357.458969)
			(xy 41.666252 -357.468792) (xy 41.680638 -357.470202) (xy 41.70929 -357.472578) (xy 41.765453 -357.484869)
			(xy 41.819137 -357.505447) (xy 41.869127 -357.533844) (xy 41.914291 -357.569419) (xy 41.953607 -357.611366)
			(xy 41.986186 -357.658737) (xy 42.01129 -357.710459) (xy 42.028351 -357.765361) (xy 42.036983 -357.822202)
			(xy 42.037508 -357.850948) (xy 42.037067 -357.8782) (xy 42.029304 -357.93215) (xy 42.013943 -357.984445)
			(xy 41.991296 -358.034023) (xy 41.963993 -358.0765) (xy 48.879506 -358.0765) (xy 48.879919 -358.051161)
			(xy 48.886628 -358.00093) (xy 48.899929 -357.95203) (xy 48.919587 -357.905321) (xy 48.945256 -357.861625)
			(xy 48.976485 -357.821713) (xy 48.994314 -357.803704) (xy 49.003707 -357.79393) (xy 49.017495 -357.770605)
			(xy 49.024645 -357.74447) (xy 49.024651 -357.717375) (xy 49.017513 -357.691237) (xy 49.003736 -357.667906)
			(xy 48.994314 -357.658162) (xy 48.97647 -357.640167) (xy 48.945243 -357.600252) (xy 48.919576 -357.556553)
			(xy 48.899921 -357.509842) (xy 48.886624 -357.460938) (xy 48.879918 -357.410705) (xy 48.879506 -357.385366)
			(xy 48.879992 -357.358115) (xy 48.887748 -357.304167) (xy 48.903103 -357.251872) (xy 48.925745 -357.202295)
			(xy 48.955211 -357.156445) (xy 48.990902 -357.115254) (xy 49.032093 -357.079563) (xy 49.077943 -357.050097)
			(xy 49.12752 -357.027455) (xy 49.179815 -357.0121) (xy 49.233763 -357.004344) (xy 49.288265 -357.004344)
			(xy 49.342213 -357.0121) (xy 49.394508 -357.027455) (xy 49.444085 -357.050097) (xy 49.489935 -357.079563)
			(xy 49.531126 -357.115254) (xy 49.566817 -357.156445) (xy 49.596283 -357.202295) (xy 49.618925 -357.251872)
			(xy 49.63428 -357.304167) (xy 49.642036 -357.358115) (xy 49.642522 -357.385366) (xy 49.642079 -357.410704)
			(xy 49.635374 -357.460933) (xy 49.622079 -357.509833) (xy 49.602426 -357.556542) (xy 49.576763 -357.600238)
			(xy 49.54554 -357.640151) (xy 49.527714 -357.658162) (xy 49.518299 -357.667899) (xy 49.504594 -357.691253)
			(xy 49.497496 -357.717384) (xy 49.497502 -357.744462) (xy 49.504612 -357.77059) (xy 49.518328 -357.793937)
			(xy 49.527714 -357.803704) (xy 49.545547 -357.82171) (xy 49.576774 -357.861623) (xy 49.602441 -357.905319)
			(xy 49.622098 -357.952029) (xy 49.635398 -358.00093) (xy 49.635935 -358.00495) (xy 49.911272 -358.00495)
			(xy 49.911272 -357.95045) (xy 49.919027 -357.896506) (xy 49.93438 -357.844214) (xy 49.957018 -357.794639)
			(xy 49.986481 -357.74879) (xy 50.022168 -357.7076) (xy 50.063353 -357.671908) (xy 50.109199 -357.64244)
			(xy 50.158771 -357.619796) (xy 50.211061 -357.604437) (xy 50.265004 -357.596675) (xy 50.292254 -357.596186)
			(xy 50.32106 -357.596711) (xy 50.378016 -357.605388) (xy 50.433023 -357.62252) (xy 50.484832 -357.647721)
			(xy 50.532268 -357.680417) (xy 50.574256 -357.719867) (xy 50.609841 -357.765176) (xy 50.624486 -357.789988)
			(xy 50.707798 -357.7971) (xy 50.730404 -357.772208) (xy 50.740446 -357.761125) (xy 50.754329 -357.734658)
			(xy 50.759967 -357.705307) (xy 50.756878 -357.67558) (xy 50.745326 -357.648016) (xy 50.726298 -357.624968)
			(xy 50.714148 -357.616252) (xy 50.69202 -357.601012) (xy 50.651853 -357.565328) (xy 50.617087 -357.524363)
			(xy 50.588411 -357.478927) (xy 50.566391 -357.429918) (xy 50.551463 -357.378305) (xy 50.543921 -357.325108)
			(xy 50.54346 -357.298244) (xy 50.543946 -357.270993) (xy 50.551702 -357.217045) (xy 50.567057 -357.16475)
			(xy 50.589699 -357.115173) (xy 50.619165 -357.069323) (xy 50.654856 -357.028132) (xy 50.696047 -356.992441)
			(xy 50.741897 -356.962975) (xy 50.791474 -356.940333) (xy 50.843769 -356.924978) (xy 50.897717 -356.917222)
			(xy 50.952219 -356.917222) (xy 51.006167 -356.924978) (xy 51.058462 -356.940333) (xy 51.108039 -356.962975)
			(xy 51.153889 -356.992441) (xy 51.19508 -357.028132) (xy 51.230771 -357.069323) (xy 51.260237 -357.115173)
			(xy 51.282879 -357.16475) (xy 51.298234 -357.217045) (xy 51.30599 -357.270993) (xy 51.306476 -357.298244)
			(xy 51.305909 -357.327899) (xy 51.296725 -357.386495) (xy 51.278585 -357.442963) (xy 51.251926 -357.495945)
			(xy 51.217391 -357.544164) (xy 51.197002 -357.565706) (xy 51.186943 -357.576775) (xy 51.17306 -357.603246)
			(xy 51.167424 -357.632601) (xy 51.170516 -357.662332) (xy 51.182073 -357.689898) (xy 51.201106 -357.712946)
			(xy 51.213258 -357.721662) (xy 51.235394 -357.736891) (xy 51.275561 -357.772577) (xy 51.310325 -357.813544)
			(xy 51.339 -357.858982) (xy 51.361019 -357.907993) (xy 51.375946 -357.959607) (xy 51.383486 -358.012805)
			(xy 51.383946 -358.03967) (xy 51.383394 -358.066919) (xy 51.375643 -358.120862) (xy 51.360293 -358.173153)
			(xy 51.337658 -358.222728) (xy 51.308199 -358.268576) (xy 51.272514 -358.309766) (xy 51.231331 -358.345458)
			(xy 51.185487 -358.374926) (xy 51.135917 -358.397569) (xy 51.083629 -358.412928) (xy 51.029687 -358.420689)
			(xy 51.002438 -358.421178) (xy 50.97328 -358.420631) (xy 50.915643 -358.411762) (xy 50.860027 -358.394223)
			(xy 50.807728 -358.368424) (xy 50.759965 -358.334966) (xy 50.717851 -358.294628) (xy 50.69967 -358.271826)
			(xy 50.690711 -358.260963) (xy 50.668153 -358.244136) (xy 50.64186 -358.234099) (xy 50.613827 -358.231613)
			(xy 50.586179 -358.236866) (xy 50.561011 -358.24946) (xy 50.550318 -358.258618) (xy 50.529074 -358.27741)
			(xy 50.482094 -358.309185) (xy 50.430927 -358.333651) (xy 50.376701 -358.350272) (xy 50.320612 -358.358678)
			(xy 50.292254 -358.359202) (xy 50.265004 -358.358725) (xy 50.211061 -358.350963) (xy 50.158771 -358.335604)
			(xy 50.109199 -358.31296) (xy 50.063353 -358.283492) (xy 50.022168 -358.2478) (xy 49.986481 -358.20661)
			(xy 49.957018 -358.160761) (xy 49.93438 -358.111186) (xy 49.919027 -358.058894) (xy 49.911272 -358.00495)
			(xy 49.635935 -358.00495) (xy 49.642108 -358.051161) (xy 49.642522 -358.0765) (xy 49.642036 -358.103751)
			(xy 49.63428 -358.157699) (xy 49.618925 -358.209994) (xy 49.596283 -358.259571) (xy 49.566817 -358.305421)
			(xy 49.531126 -358.346612) (xy 49.489935 -358.382303) (xy 49.444085 -358.411769) (xy 49.394508 -358.434411)
			(xy 49.342213 -358.449766) (xy 49.288265 -358.457522) (xy 49.233763 -358.457522) (xy 49.179815 -358.449766)
			(xy 49.12752 -358.434411) (xy 49.077943 -358.411769) (xy 49.032093 -358.382303) (xy 48.990902 -358.346612)
			(xy 48.955211 -358.305421) (xy 48.925745 -358.259571) (xy 48.903103 -358.209994) (xy 48.887748 -358.157699)
			(xy 48.879992 -358.103751) (xy 48.879506 -358.0765) (xy 41.963993 -358.0765) (xy 41.961825 -358.079873)
			(xy 41.926129 -358.121063) (xy 41.884934 -358.156753) (xy 41.839081 -358.186219) (xy 41.7895 -358.208859)
			(xy 41.737203 -358.224214) (xy 41.683252 -358.23197) (xy 41.656 -358.232456) (xy 41.628751 -358.231922)
			(xy 41.574807 -358.224167) (xy 41.522516 -358.208814) (xy 41.472942 -358.186177) (xy 41.427094 -358.156715)
			(xy 41.385905 -358.121029) (xy 41.350214 -358.079844) (xy 41.320746 -358.034) (xy 41.298102 -357.984429)
			(xy 41.282743 -357.93214) (xy 41.274981 -357.878197) (xy 41.274492 -357.850948) (xy 41.27473 -357.832281)
			(xy 41.278424 -357.79513) (xy 41.281858 -357.77678) (xy 41.284144 -357.762505) (xy 41.28163 -357.733721)
			(xy 41.271145 -357.706797) (xy 41.25353 -357.683894) (xy 41.2302 -357.666849) (xy 41.203027 -357.65703)
			(xy 41.18864 -357.655622) (xy 41.159985 -357.653254) (xy 41.103817 -357.64097) (xy 41.050129 -357.620398)
			(xy 41.000134 -357.592003) (xy 40.954967 -357.556428) (xy 40.915648 -357.514478) (xy 40.88307 -357.467103)
			(xy 40.857969 -357.415376) (xy 40.840913 -357.360469) (xy 40.83229 -357.303624) (xy 40.83177 -357.274876)
			(xy 39.9691 -357.274876) (xy 39.96944 -357.293926) (xy 39.969031 -357.319265) (xy 39.962318 -357.369495)
			(xy 39.949016 -357.418395) (xy 39.929357 -357.465104) (xy 39.903688 -357.508799) (xy 39.87246 -357.548712)
			(xy 39.854632 -357.566722) (xy 39.845256 -357.576494) (xy 39.831545 -357.599837) (xy 39.82444 -357.625959)
			(xy 39.824439 -357.653031) (xy 39.831541 -357.679154) (xy 39.84525 -357.702498) (xy 39.854632 -357.712264)
			(xy 39.872449 -357.730285) (xy 39.903676 -357.770195) (xy 39.929346 -357.813888) (xy 39.949006 -357.860595)
			(xy 39.962309 -357.909493) (xy 39.969023 -357.959722) (xy 39.969319 -357.977694) (xy 40.221914 -357.977694)
			(xy 40.225985 -357.922072) (xy 40.238111 -357.867635) (xy 40.258034 -357.815544) (xy 40.28533 -357.766909)
			(xy 40.319416 -357.722766) (xy 40.359565 -357.684057) (xy 40.404923 -357.651606) (xy 40.454523 -357.626105)
			(xy 40.507307 -357.608098) (xy 40.56215 -357.597968) (xy 40.617884 -357.595931) (xy 40.673321 -357.602031)
			(xy 40.727278 -357.616137) (xy 40.778607 -357.637949) (xy 40.826213 -357.667003) (xy 40.869081 -357.702678)
			(xy 40.906298 -357.744215) (xy 40.937071 -357.790728) (xy 40.960743 -357.841225) (xy 40.976811 -357.894632)
			(xy 40.984931 -357.949808) (xy 40.98544 -357.977694) (xy 40.984931 -358.00558) (xy 40.976811 -358.060756)
			(xy 40.960743 -358.114163) (xy 40.937071 -358.16466) (xy 40.906298 -358.211173) (xy 40.869081 -358.25271)
			(xy 40.826213 -358.288385) (xy 40.778607 -358.317439) (xy 40.727278 -358.339251) (xy 40.673321 -358.353357)
			(xy 40.617884 -358.359457) (xy 40.56215 -358.35742) (xy 40.507307 -358.34729) (xy 40.454523 -358.329283)
			(xy 40.404923 -358.303782) (xy 40.359565 -358.271331) (xy 40.319416 -358.232622) (xy 40.28533 -358.188479)
			(xy 40.258034 -358.139844) (xy 40.238111 -358.087753) (xy 40.225985 -358.033316) (xy 40.221914 -357.977694)
			(xy 39.969319 -357.977694) (xy 39.96944 -357.98506) (xy 39.968954 -358.012311) (xy 39.961198 -358.066259)
			(xy 39.945843 -358.118554) (xy 39.923201 -358.168131) (xy 39.893735 -358.213981) (xy 39.858044 -358.255172)
			(xy 39.816853 -358.290863) (xy 39.771003 -358.320329) (xy 39.721426 -358.342971) (xy 39.669131 -358.358326)
			(xy 39.615183 -358.366082) (xy 39.560681 -358.366082) (xy 39.506733 -358.358326) (xy 39.454438 -358.342971)
			(xy 39.404861 -358.320329) (xy 39.359011 -358.290863) (xy 39.31782 -358.255172) (xy 39.282129 -358.213981)
			(xy 39.252663 -358.168131) (xy 39.230021 -358.118554) (xy 39.214666 -358.066259) (xy 39.20691 -358.012311)
			(xy 39.206424 -357.98506) (xy 34.902394 -357.98506) (xy 34.902394 -361.049316) (xy 38.985952 -361.049316)
			(xy 38.986493 -361.022067) (xy 38.994246 -360.968123) (xy 39.009597 -360.915832) (xy 39.032234 -360.866258)
			(xy 39.061695 -360.820409) (xy 39.09738 -360.77922) (xy 39.138564 -360.743528) (xy 39.184409 -360.714061)
			(xy 39.23398 -360.691417) (xy 39.286269 -360.676058) (xy 39.340211 -360.668297) (xy 39.36746 -360.667808)
			(xy 39.394829 -360.668296) (xy 39.449008 -360.676108) (xy 39.501511 -360.691592) (xy 39.551258 -360.714429)
			(xy 39.597226 -360.744149) (xy 39.618158 -360.761788) (xy 39.629486 -360.771024) (xy 39.656043 -360.7832)
			(xy 39.68496 -360.787373) (xy 39.713877 -360.7832) (xy 39.740434 -360.771024) (xy 39.751762 -360.761788)
			(xy 39.772696 -360.744151) (xy 39.818668 -360.71444) (xy 39.868416 -360.691603) (xy 39.920916 -360.676112)
			(xy 39.975091 -360.668283) (xy 40.00246 -360.667808) (xy 40.031376 -360.668352) (xy 40.088546 -360.677075)
			(xy 40.143745 -360.694328) (xy 40.195706 -360.719715) (xy 40.243241 -360.752654) (xy 40.285259 -360.792391)
			(xy 40.30345 -360.814874) (xy 40.313347 -360.826679) (xy 40.338671 -360.844198) (xy 40.368064 -360.853374)
			(xy 40.398856 -360.853374) (xy 40.428249 -360.844198) (xy 40.453573 -360.826679) (xy 40.46347 -360.814874)
			(xy 40.481671 -360.792399) (xy 40.52369 -360.752665) (xy 40.571223 -360.719726) (xy 40.623182 -360.694336)
			(xy 40.678377 -360.677077) (xy 40.735545 -360.668345) (xy 40.76446 -360.667808) (xy 40.791713 -360.668293)
			(xy 40.845664 -360.676045) (xy 40.897962 -360.691396) (xy 40.947543 -360.714035) (xy 40.993397 -360.743501)
			(xy 41.034591 -360.779192) (xy 41.070285 -360.820384) (xy 41.099753 -360.866236) (xy 41.122395 -360.915815)
			(xy 41.13775 -360.968113) (xy 41.145506 -361.022063) (xy 41.145968 -361.049316) (xy 41.145407 -361.078446)
			(xy 41.136539 -361.136027) (xy 41.119011 -361.191589) (xy 41.093232 -361.243835) (xy 41.059802 -361.29155)
			(xy 41.04005 -361.312968) (xy 41.031213 -361.322807) (xy 41.018431 -361.345945) (xy 41.012034 -361.371593)
			(xy 41.012456 -361.398024) (xy 41.019666 -361.423456) (xy 41.033179 -361.446175) (xy 41.042336 -361.455716)
			(xy 41.063488 -361.477374) (xy 41.089422 -361.512612) (xy 44.706032 -361.512612) (xy 44.706601 -361.483444)
			(xy 44.715499 -361.425789) (xy 44.733074 -361.370162) (xy 44.758916 -361.317861) (xy 44.792423 -361.270106)
			(xy 44.832811 -361.228011) (xy 44.855638 -361.209844) (xy 44.866037 -361.201446) (xy 44.882331 -361.180263)
			(xy 44.892574 -361.155579) (xy 44.896065 -361.129083) (xy 44.892565 -361.102588) (xy 44.882314 -361.077908)
			(xy 44.866013 -361.05673) (xy 44.855638 -361.0483) (xy 44.832794 -361.03015) (xy 44.792392 -360.988061)
			(xy 44.758878 -360.940306) (xy 44.733034 -360.888) (xy 44.715466 -360.832365) (xy 44.706583 -360.774703)
			(xy 44.706032 -360.745532) (xy 44.706485 -360.718278) (xy 44.714239 -360.664325) (xy 44.729593 -360.612024)
			(xy 44.752235 -360.562442) (xy 44.781703 -360.516586) (xy 44.817398 -360.475392) (xy 44.858593 -360.439698)
			(xy 44.904449 -360.410231) (xy 44.954032 -360.38759) (xy 45.006333 -360.372237) (xy 45.060286 -360.364485)
			(xy 45.08754 -360.364024) (xy 45.116456 -360.364576) (xy 45.173626 -360.373297) (xy 45.228824 -360.390547)
			(xy 45.280786 -360.415933) (xy 45.328321 -360.448871) (xy 45.370339 -360.488607) (xy 45.38853 -360.51109)
			(xy 45.398427 -360.522895) (xy 45.423751 -360.540414) (xy 45.453144 -360.54959) (xy 45.483936 -360.54959)
			(xy 45.513329 -360.540414) (xy 45.538653 -360.522895) (xy 45.54855 -360.51109) (xy 45.566767 -360.488628)
			(xy 45.608781 -360.448892) (xy 45.656311 -360.415951) (xy 45.708267 -360.390559) (xy 45.76346 -360.373298)
			(xy 45.820626 -360.364563) (xy 45.84954 -360.364024) (xy 45.878086 -360.364584) (xy 45.934539 -360.373094)
			(xy 45.989094 -360.389919) (xy 46.040535 -360.414683) (xy 46.064424 -360.430318) (xy 46.075556 -360.4374)
			(xy 46.100412 -360.446212) (xy 46.126699 -360.448341) (xy 46.152649 -360.443643) (xy 46.176521 -360.432435)
			(xy 46.196711 -360.415469) (xy 46.204632 -360.404918) (xy 46.22004 -360.383903) (xy 46.255641 -360.345851)
			(xy 46.296087 -360.312995) (xy 46.340626 -360.285946) (xy 46.38843 -360.265206) (xy 46.438611 -360.251161)
			(xy 46.490235 -360.244072) (xy 46.51629 -360.243628) (xy 46.545207 -360.244143) (xy 46.602379 -360.252871)
			(xy 46.657578 -360.270129) (xy 46.70954 -360.295521) (xy 46.757074 -360.328466) (xy 46.79909 -360.368208)
			(xy 46.81728 -360.390694) (xy 46.827177 -360.402499) (xy 46.852501 -360.420018) (xy 46.881894 -360.429194)
			(xy 46.912686 -360.429194) (xy 46.942079 -360.420018) (xy 46.967403 -360.402499) (xy 46.9773 -360.390694)
			(xy 46.995489 -360.368209) (xy 47.03751 -360.328474) (xy 47.085045 -360.295536) (xy 47.137007 -360.270148)
			(xy 47.192204 -360.252892) (xy 47.249374 -360.244163) (xy 47.27829 -360.243628) (xy 47.305544 -360.244065)
			(xy 47.359498 -360.251821) (xy 47.411799 -360.267178) (xy 47.461381 -360.289822) (xy 47.507236 -360.319292)
			(xy 47.54843 -360.354989) (xy 47.584123 -360.396185) (xy 47.613591 -360.442042) (xy 47.636231 -360.491626)
			(xy 47.651584 -360.543927) (xy 47.659337 -360.597882) (xy 47.659798 -360.625136) (xy 47.659322 -360.651178)
			(xy 47.652244 -360.702778) (xy 47.638212 -360.752936) (xy 47.617485 -360.800718) (xy 47.59045 -360.845235)
			(xy 47.557609 -360.88566) (xy 47.538894 -360.903774) (xy 47.528968 -360.91375) (xy 47.514501 -360.937875)
			(xy 47.507156 -360.965029) (xy 47.507487 -360.993157) (xy 47.515471 -361.020131) (xy 47.530501 -361.043909)
			(xy 47.540672 -361.053634) (xy 47.56026 -361.07179) (xy 47.59465 -361.112652) (xy 47.623006 -361.157912)
			(xy 47.644772 -361.206684) (xy 47.659523 -361.258015) (xy 47.666971 -361.310902) (xy 47.667418 -361.337606)
			(xy 47.66692 -361.365376) (xy 47.658866 -361.420328) (xy 47.64293 -361.473533) (xy 47.619447 -361.523864)
			(xy 47.588915 -361.570258) (xy 47.551979 -361.611735) (xy 47.53102 -361.62996) (xy 47.520368 -361.639481)
			(xy 47.504384 -361.663145) (xy 47.495592 -361.690314) (xy 47.494682 -361.718856) (xy 47.501726 -361.74653)
			(xy 47.516171 -361.771164) (xy 47.526194 -361.781344) (xy 47.544559 -361.799414) (xy 47.576728 -361.839658)
			(xy 47.603195 -361.883862) (xy 47.623477 -361.931223) (xy 47.637207 -361.980882) (xy 47.644135 -362.031935)
			(xy 47.644558 -362.057696) (xy 47.6441 -362.085067) (xy 47.636282 -362.139246) (xy 47.620791 -362.19175)
			(xy 47.597948 -362.241497) (xy 47.568221 -362.287463) (xy 47.550578 -362.308394) (xy 47.541347 -362.319725)
			(xy 47.529172 -362.346282) (xy 47.524999 -362.375197) (xy 47.52917 -362.404112) (xy 47.541343 -362.43067)
			(xy 47.550578 -362.441998) (xy 47.568215 -362.462934) (xy 47.597939 -362.508901) (xy 47.620784 -362.558647)
			(xy 47.636281 -362.611149) (xy 47.64411 -362.665327) (xy 47.64411 -362.720067) (xy 47.636282 -362.774245)
			(xy 47.620787 -362.826747) (xy 47.597942 -362.876493) (xy 47.568218 -362.922461) (xy 47.550578 -362.943394)
			(xy 47.541347 -362.954725) (xy 47.529172 -362.981282) (xy 47.524999 -363.010197) (xy 47.52917 -363.039112)
			(xy 47.541343 -363.06567) (xy 47.550578 -363.076998) (xy 47.568215 -363.097934) (xy 47.597939 -363.143901)
			(xy 47.620784 -363.193647) (xy 47.636281 -363.246149) (xy 47.63987 -363.270984) (xy 48.72126 -363.270984)
			(xy 48.72126 -363.186288) (xy 48.729311 -363.101974) (xy 48.74534 -363.018808) (xy 48.769201 -362.937541)
			(xy 48.80068 -362.858911) (xy 48.839491 -362.78363) (xy 48.885281 -362.712378) (xy 48.937637 -362.645802)
			(xy 48.996085 -362.584504) (xy 49.060095 -362.529039) (xy 49.129087 -362.47991) (xy 49.202437 -362.437561)
			(xy 49.27948 -362.402377) (xy 49.359519 -362.374675) (xy 49.441828 -362.354707) (xy 49.525663 -362.342654)
			(xy 49.610264 -362.338624) (xy 49.694865 -362.342654) (xy 49.7787 -362.354707) (xy 49.861009 -362.374675)
			(xy 49.941048 -362.402377) (xy 50.018091 -362.437561) (xy 50.091441 -362.47991) (xy 50.160433 -362.529039)
			(xy 50.224443 -362.584504) (xy 50.282891 -362.645802) (xy 50.335247 -362.712378) (xy 50.381037 -362.78363)
			(xy 50.419848 -362.858911) (xy 50.451327 -362.937541) (xy 50.475188 -363.018808) (xy 50.491217 -363.101974)
			(xy 50.499268 -363.186288) (xy 50.499772 -363.228636) (xy 51.245773 -363.228636) (xy 51.249809 -363.145189)
			(xy 51.261881 -363.062521) (xy 51.281874 -362.981404) (xy 51.309603 -362.902595) (xy 51.344809 -362.82683)
			(xy 51.387163 -362.754817) (xy 51.436269 -362.687228) (xy 51.49167 -362.624694) (xy 51.552847 -362.567799)
			(xy 51.61923 -362.517073) (xy 51.690198 -362.472992) (xy 51.76509 -362.435966) (xy 51.843206 -362.40634)
			(xy 51.923816 -362.384392) (xy 52.006168 -362.370327) (xy 52.089494 -362.364275) (xy 52.173014 -362.366294)
			(xy 52.25595 -362.376364) (xy 52.337526 -362.394392) (xy 52.416982 -362.420209) (xy 52.493575 -362.453574)
			(xy 52.566591 -362.494175) (xy 52.635347 -362.541634) (xy 52.699201 -362.595507) (xy 52.757558 -362.655292)
			(xy 52.809873 -362.720429) (xy 52.855656 -362.790312) (xy 52.894481 -362.864287) (xy 52.925986 -362.941664)
			(xy 52.949875 -363.021721) (xy 52.965926 -363.103709) (xy 52.973989 -363.186864) (xy 52.974494 -363.228636)
			(xy 52.973989 -363.270408) (xy 52.965926 -363.353563) (xy 52.949875 -363.435551) (xy 52.925986 -363.515608)
			(xy 52.894481 -363.592985) (xy 52.855656 -363.66696) (xy 52.809873 -363.736843) (xy 52.757558 -363.80198)
			(xy 52.699201 -363.861765) (xy 52.635347 -363.915638) (xy 52.566591 -363.963097) (xy 52.493575 -364.003698)
			(xy 52.416982 -364.037063) (xy 52.337526 -364.06288) (xy 52.25595 -364.080908) (xy 52.173014 -364.090978)
			(xy 52.089494 -364.092997) (xy 52.006168 -364.086945) (xy 51.923816 -364.07288) (xy 51.843206 -364.050932)
			(xy 51.76509 -364.021306) (xy 51.690198 -363.98428) (xy 51.61923 -363.940199) (xy 51.552847 -363.889473)
			(xy 51.49167 -363.832578) (xy 51.436269 -363.770044) (xy 51.387163 -363.702455) (xy 51.344809 -363.630442)
			(xy 51.309603 -363.554677) (xy 51.281874 -363.475868) (xy 51.261881 -363.394751) (xy 51.249809 -363.312083)
			(xy 51.245773 -363.228636) (xy 50.499772 -363.228636) (xy 50.499268 -363.270984) (xy 50.491217 -363.355298)
			(xy 50.475188 -363.438464) (xy 50.451327 -363.519731) (xy 50.419848 -363.598361) (xy 50.381037 -363.673642)
			(xy 50.335247 -363.744894) (xy 50.282891 -363.81147) (xy 50.224443 -363.872768) (xy 50.160433 -363.928233)
			(xy 50.091441 -363.977362) (xy 50.018091 -364.019711) (xy 49.941048 -364.054895) (xy 49.861009 -364.082597)
			(xy 49.7787 -364.102565) (xy 49.694865 -364.114618) (xy 49.610264 -364.118649) (xy 49.525663 -364.114618)
			(xy 49.441828 -364.102565) (xy 49.359519 -364.082597) (xy 49.27948 -364.054895) (xy 49.202437 -364.019711)
			(xy 49.129087 -363.977362) (xy 49.060095 -363.928233) (xy 48.996085 -363.872768) (xy 48.937637 -363.81147)
			(xy 48.885281 -363.744894) (xy 48.839491 -363.673642) (xy 48.80068 -363.598361) (xy 48.769201 -363.519731)
			(xy 48.74534 -363.438464) (xy 48.729311 -363.355298) (xy 48.72126 -363.270984) (xy 47.63987 -363.270984)
			(xy 47.64411 -363.300327) (xy 47.64411 -363.355067) (xy 47.636282 -363.409245) (xy 47.620787 -363.461747)
			(xy 47.597942 -363.511493) (xy 47.568218 -363.557461) (xy 47.550578 -363.578394) (xy 47.541347 -363.589725)
			(xy 47.529172 -363.616282) (xy 47.524999 -363.645197) (xy 47.52917 -363.674112) (xy 47.541343 -363.70067)
			(xy 47.550578 -363.711998) (xy 47.568226 -363.732923) (xy 47.597937 -363.778897) (xy 47.620772 -363.828647)
			(xy 47.636261 -363.881149) (xy 47.644086 -363.935326) (xy 47.644558 -363.962696) (xy 47.644141 -363.989951)
			(xy 47.636383 -364.043906) (xy 47.621025 -364.096208) (xy 47.598379 -364.145791) (xy 47.568907 -364.191647)
			(xy 47.533208 -364.232841) (xy 47.49201 -364.268535) (xy 47.446151 -364.298001) (xy 47.396565 -364.320641)
			(xy 47.344261 -364.335993) (xy 47.290305 -364.343744) (xy 47.26305 -364.344204) (xy 47.234133 -364.343686)
			(xy 47.17696 -364.334962) (xy 47.121759 -364.317706) (xy 47.069797 -364.292315) (xy 47.022263 -364.259369)
			(xy 46.980249 -364.219625) (xy 46.96206 -364.197138) (xy 46.952163 -364.185333) (xy 46.926839 -364.167814)
			(xy 46.897446 -364.158638) (xy 46.866654 -364.158638) (xy 46.837261 -364.167814) (xy 46.811937 -364.185333)
			(xy 46.80204 -364.197138) (xy 46.783836 -364.21961) (xy 46.741818 -364.259344) (xy 46.694285 -364.292284)
			(xy 46.642327 -364.317674) (xy 46.587132 -364.334933) (xy 46.529965 -364.343666) (xy 46.50105 -364.344204)
			(xy 46.473798 -364.343698) (xy 46.419849 -364.335948) (xy 46.367551 -364.320598) (xy 46.317971 -364.297961)
			(xy 46.272117 -364.268498) (xy 46.230924 -364.232808) (xy 46.19523 -364.191619) (xy 46.165761 -364.145769)
			(xy 46.143118 -364.096192) (xy 46.127762 -364.043896) (xy 46.120005 -363.989948) (xy 46.119542 -363.962696)
			(xy 46.119995 -363.935325) (xy 46.127815 -363.881145) (xy 46.143306 -363.828642) (xy 46.166151 -363.778895)
			(xy 46.195879 -363.732929) (xy 46.213522 -363.711998) (xy 46.222761 -363.700673) (xy 46.234935 -363.674114)
			(xy 46.239106 -363.645197) (xy 46.234933 -363.61628) (xy 46.222758 -363.589722) (xy 46.213522 -363.578394)
			(xy 46.195878 -363.557464) (xy 46.166153 -363.511496) (xy 46.143309 -363.461749) (xy 46.127813 -363.409247)
			(xy 46.119985 -363.355068) (xy 46.119985 -363.300326) (xy 46.127814 -363.246148) (xy 46.143311 -363.193645)
			(xy 46.166156 -363.143899) (xy 46.195881 -363.097931) (xy 46.213522 -363.076998) (xy 46.222761 -363.065673)
			(xy 46.234935 -363.039114) (xy 46.239106 -363.010197) (xy 46.234933 -362.98128) (xy 46.222758 -362.954722)
			(xy 46.213522 -362.943394) (xy 46.195878 -362.922464) (xy 46.166153 -362.876496) (xy 46.143309 -362.826749)
			(xy 46.127813 -362.774247) (xy 46.119985 -362.720068) (xy 46.119985 -362.665326) (xy 46.127814 -362.611148)
			(xy 46.143311 -362.558645) (xy 46.166156 -362.508899) (xy 46.195881 -362.462931) (xy 46.213522 -362.441998)
			(xy 46.222761 -362.430673) (xy 46.234935 -362.404114) (xy 46.239106 -362.375197) (xy 46.234933 -362.34628)
			(xy 46.222758 -362.319722) (xy 46.213522 -362.308394) (xy 46.19587 -362.287472) (xy 46.166159 -362.241497)
			(xy 46.143326 -362.191747) (xy 46.127838 -362.139244) (xy 46.120014 -362.085066) (xy 46.119542 -362.057696)
			(xy 46.119779 -362.038641) (xy 46.123595 -362.000723) (xy 46.127162 -361.982004) (xy 46.129464 -361.968526)
			(xy 46.127624 -361.941254) (xy 46.118615 -361.915448) (xy 46.103081 -361.892958) (xy 46.082137 -361.875395)
			(xy 46.057284 -361.864018) (xy 46.030303 -361.859643) (xy 46.003128 -361.862584) (xy 45.990256 -361.867196)
			(xy 45.967794 -361.875742) (xy 45.921251 -361.887724) (xy 45.87357 -361.893759) (xy 45.84954 -361.89412)
			(xy 45.820623 -361.893603) (xy 45.76345 -361.884878) (xy 45.70825 -361.867622) (xy 45.656288 -361.84223)
			(xy 45.608754 -361.809285) (xy 45.566739 -361.769541) (xy 45.54855 -361.747054) (xy 45.538653 -361.735249)
			(xy 45.513329 -361.71773) (xy 45.483936 -361.708554) (xy 45.453144 -361.708554) (xy 45.423751 -361.71773)
			(xy 45.398427 -361.735249) (xy 45.38853 -361.747054) (xy 45.370336 -361.769534) (xy 45.328315 -361.809267)
			(xy 45.28078 -361.842205) (xy 45.22882 -361.867593) (xy 45.173624 -361.884851) (xy 45.116456 -361.893583)
			(xy 45.08754 -361.89412) (xy 45.060289 -361.893608) (xy 45.00634 -361.885856) (xy 44.954044 -361.870506)
			(xy 44.904465 -361.847869) (xy 44.858612 -361.818406) (xy 44.817419 -361.782718) (xy 44.781725 -361.74153)
			(xy 44.752256 -361.695681) (xy 44.729612 -361.646105) (xy 44.714255 -361.593811) (xy 44.706496 -361.539863)
			(xy 44.706032 -361.512612) (xy 41.089422 -361.512612) (xy 41.09937 -361.526129) (xy 41.127101 -361.579939)
			(xy 41.145985 -361.637453) (xy 41.155547 -361.697228) (xy 41.156128 -361.727496) (xy 41.155677 -361.754867)
			(xy 41.147858 -361.809047) (xy 41.132367 -361.861551) (xy 41.109521 -361.911298) (xy 41.079792 -361.957264)
			(xy 41.062148 -361.978194) (xy 41.052919 -361.989526) (xy 41.040748 -362.016083) (xy 41.036577 -362.044997)
			(xy 41.040746 -362.073911) (xy 41.052916 -362.100469) (xy 41.062148 -362.111798) (xy 41.079786 -362.132733)
			(xy 41.109513 -362.1787) (xy 41.13236 -362.228446) (xy 41.147857 -362.280948) (xy 41.155687 -362.335126)
			(xy 41.155687 -362.389868) (xy 41.147859 -362.444046) (xy 41.132362 -362.496549) (xy 41.109516 -362.546295)
			(xy 41.079789 -362.592262) (xy 41.062148 -362.613194) (xy 41.052919 -362.624526) (xy 41.040748 -362.651083)
			(xy 41.036577 -362.679997) (xy 41.040746 -362.708911) (xy 41.052916 -362.735469) (xy 41.062148 -362.746798)
			(xy 41.079792 -362.767727) (xy 41.109504 -362.8137) (xy 41.13234 -362.863448) (xy 41.14783 -362.91595)
			(xy 41.155656 -362.970126) (xy 41.156128 -362.997496) (xy 41.155634 -363.026414) (xy 41.146904 -363.083588)
			(xy 41.129643 -363.138788) (xy 41.104247 -363.19075) (xy 41.071298 -363.238283) (xy 41.031551 -363.280298)
			(xy 41.009062 -363.298486) (xy 40.997256 -363.308385) (xy 40.97973 -363.333706) (xy 40.970549 -363.3631)
			(xy 40.970548 -363.393895) (xy 40.979728 -363.42329) (xy 40.997253 -363.448611) (xy 41.009062 -363.458506)
			(xy 41.02984 -363.475265) (xy 41.066968 -363.513618) (xy 41.098388 -363.556773) (xy 41.123486 -363.603885)
			(xy 41.141771 -363.654037) (xy 41.152887 -363.706247) (xy 41.156617 -363.759498) (xy 41.152888 -363.812748)
			(xy 41.141773 -363.864959) (xy 41.123488 -363.91511) (xy 41.098391 -363.962223) (xy 41.066972 -364.005378)
			(xy 41.029844 -364.043732) (xy 41.009062 -364.060486) (xy 40.997256 -364.070385) (xy 40.97973 -364.095706)
			(xy 40.970549 -364.1251) (xy 40.970548 -364.155895) (xy 40.979728 -364.18529) (xy 40.997253 -364.210611)
			(xy 41.009062 -364.220506) (xy 41.03154 -364.238703) (xy 41.071278 -364.280721) (xy 41.104218 -364.328254)
			(xy 41.129608 -364.380214) (xy 41.146865 -364.435411) (xy 41.155593 -364.49258) (xy 41.156128 -364.521496)
			(xy 41.155566 -364.550626) (xy 41.149178 -364.592108) (xy 55.39308 -364.592108) (xy 55.397151 -364.536486)
			(xy 55.409277 -364.482049) (xy 55.4292 -364.429958) (xy 55.456496 -364.381323) (xy 55.490582 -364.33718)
			(xy 55.530731 -364.298471) (xy 55.576089 -364.26602) (xy 55.625689 -364.240519) (xy 55.678473 -364.222512)
			(xy 55.733316 -364.212382) (xy 55.78905 -364.210345) (xy 55.844487 -364.216445) (xy 55.898444 -364.230551)
			(xy 55.949773 -364.252363) (xy 55.997379 -364.281417) (xy 56.040247 -364.317092) (xy 56.077464 -364.358629)
			(xy 56.108237 -364.405142) (xy 56.131909 -364.455639) (xy 56.147977 -364.509046) (xy 56.156097 -364.564222)
			(xy 56.156606 -364.592108) (xy 56.156097 -364.619994) (xy 56.147977 -364.67517) (xy 56.131909 -364.728577)
			(xy 56.108237 -364.779074) (xy 56.077464 -364.825587) (xy 56.040247 -364.867124) (xy 55.997379 -364.902799)
			(xy 55.949773 -364.931853) (xy 55.898444 -364.953665) (xy 55.844487 -364.967771) (xy 55.78905 -364.973871)
			(xy 55.733316 -364.971834) (xy 55.678473 -364.961704) (xy 55.625689 -364.943697) (xy 55.576089 -364.918196)
			(xy 55.530731 -364.885745) (xy 55.490582 -364.847036) (xy 55.456496 -364.802893) (xy 55.4292 -364.754258)
			(xy 55.409277 -364.702167) (xy 55.397151 -364.64773) (xy 55.39308 -364.592108) (xy 41.149178 -364.592108)
			(xy 41.146699 -364.608208) (xy 41.129172 -364.66377) (xy 41.103393 -364.716016) (xy 41.069963 -364.763731)
			(xy 41.05021 -364.785148) (xy 41.039828 -364.796775) (xy 41.026037 -364.824712) (xy 41.021295 -364.855504)
			(xy 41.02604 -364.886296) (xy 41.039833 -364.914232) (xy 41.05021 -364.925864) (xy 41.069921 -364.947315)
			(xy 41.10333 -364.995035) (xy 41.129104 -365.047275) (xy 41.146646 -365.102823) (xy 41.15555 -365.16039)
			(xy 41.156128 -365.189516) (xy 41.155637 -365.216767) (xy 41.147879 -365.270713) (xy 41.132523 -365.323007)
			(xy 41.109881 -365.372583) (xy 41.080415 -365.418432) (xy 41.044724 -365.459622) (xy 41.003535 -365.495313)
			(xy 40.957686 -365.524779) (xy 40.90811 -365.547421) (xy 40.855817 -365.562778) (xy 40.801871 -365.570537)
			(xy 40.77462 -365.571024) (xy 40.745702 -365.57052) (xy 40.688529 -365.561792) (xy 40.633329 -365.544533)
			(xy 40.581366 -365.519139) (xy 40.533833 -365.486192) (xy 40.491818 -365.446446) (xy 40.47363 -365.423958)
			(xy 40.463733 -365.412153) (xy 40.438409 -365.394634) (xy 40.409016 -365.385458) (xy 40.378224 -365.385458)
			(xy 40.348831 -365.394634) (xy 40.323507 -365.412153) (xy 40.31361 -365.423958) (xy 40.295403 -365.446428)
			(xy 40.253388 -365.486166) (xy 40.205856 -365.519108) (xy 40.153898 -365.544499) (xy 40.098703 -365.561757)
			(xy 40.041535 -365.570488) (xy 40.01262 -365.571024) (xy 39.985249 -365.570565) (xy 39.931069 -365.562748)
			(xy 39.878565 -365.547258) (xy 39.828818 -365.524415) (xy 39.782853 -365.494687) (xy 39.761922 -365.477044)
			(xy 39.750594 -365.467808) (xy 39.724037 -365.455632) (xy 39.69512 -365.451459) (xy 39.666203 -365.455632)
			(xy 39.639646 -365.467808) (xy 39.628318 -365.477044) (xy 39.607396 -365.494695) (xy 39.56142 -365.524404)
			(xy 39.51167 -365.547237) (xy 39.459167 -365.562725) (xy 39.40499 -365.570551) (xy 39.37762 -365.571024)
			(xy 39.350368 -365.570526) (xy 39.29642 -365.562772) (xy 39.244123 -365.54742) (xy 39.194544 -365.524781)
			(xy 39.148692 -365.495316) (xy 39.107499 -365.459626) (xy 39.071805 -365.418437) (xy 39.042337 -365.372587)
			(xy 39.019693 -365.32301) (xy 39.004335 -365.270716) (xy 38.996576 -365.216768) (xy 38.996112 -365.189516)
			(xy 38.996698 -365.160387) (xy 39.005561 -365.102807) (xy 39.023083 -365.047246) (xy 39.048857 -364.994999)
			(xy 39.082281 -364.947283) (xy 39.10203 -364.925864) (xy 39.112397 -364.914226) (xy 39.126184 -364.886292)
			(xy 39.130927 -364.855504) (xy 39.126186 -364.824716) (xy 39.112402 -364.796781) (xy 39.10203 -364.785148)
			(xy 39.082267 -364.763743) (xy 39.048868 -364.71601) (xy 39.023104 -364.663758) (xy 39.005574 -364.6082)
			(xy 38.996683 -364.550625) (xy 38.996112 -364.521496) (xy 38.996623 -364.492579) (xy 39.005353 -364.435407)
			(xy 39.022612 -364.380208) (xy 39.048005 -364.328246) (xy 39.08095 -364.280713) (xy 39.120692 -364.238696)
			(xy 39.143178 -364.220506) (xy 39.154988 -364.210613) (xy 39.172507 -364.185289) (xy 39.181683 -364.155894)
			(xy 39.181682 -364.125101) (xy 39.172505 -364.095707) (xy 39.154984 -364.070383) (xy 39.143178 -364.060486)
			(xy 39.12239 -364.043738) (xy 39.085258 -364.005385) (xy 39.053835 -363.96223) (xy 39.028735 -363.915116)
			(xy 39.010448 -363.864963) (xy 38.999331 -363.81275) (xy 38.995601 -363.759498) (xy 38.999331 -363.706245)
			(xy 39.010449 -363.654032) (xy 39.028737 -363.60388) (xy 39.053838 -363.556766) (xy 39.085261 -363.513611)
			(xy 39.122394 -363.475259) (xy 39.143178 -363.458506) (xy 39.154988 -363.448613) (xy 39.172507 -363.423289)
			(xy 39.181683 -363.393894) (xy 39.181682 -363.363101) (xy 39.172505 -363.333707) (xy 39.154984 -363.308383)
			(xy 39.143178 -363.298486) (xy 39.120683 -363.280308) (xy 39.08095 -363.238285) (xy 39.048013 -363.190747)
			(xy 39.022626 -363.138784) (xy 39.005372 -363.083584) (xy 38.996646 -363.026413) (xy 38.996112 -362.997496)
			(xy 38.996573 -362.970126) (xy 39.004391 -362.915946) (xy 39.019882 -362.863443) (xy 39.042725 -362.813696)
			(xy 39.07245 -362.767729) (xy 39.090092 -362.746798) (xy 39.099333 -362.735474) (xy 39.111511 -362.708915)
			(xy 39.115683 -362.679997) (xy 39.11151 -362.651079) (xy 39.09933 -362.624521) (xy 39.090092 -362.613194)
			(xy 39.072449 -362.592264) (xy 39.042727 -362.546295) (xy 39.019884 -362.496548) (xy 39.004389 -362.444046)
			(xy 38.996562 -362.389867) (xy 38.996562 -362.335127) (xy 39.004391 -362.280948) (xy 39.019886 -362.228447)
			(xy 39.04273 -362.1787) (xy 39.072452 -362.132731) (xy 39.090092 -362.111798) (xy 39.099333 -362.100474)
			(xy 39.111511 -362.073915) (xy 39.115683 -362.044997) (xy 39.11151 -362.016079) (xy 39.09933 -361.989521)
			(xy 39.090092 -361.978194) (xy 39.072435 -361.957276) (xy 39.042726 -361.911299) (xy 39.019894 -361.861548)
			(xy 39.004407 -361.809044) (xy 38.996584 -361.754866) (xy 38.996112 -361.727496) (xy 38.996686 -361.698366)
			(xy 39.005552 -361.640786) (xy 39.023077 -361.585225) (xy 39.048853 -361.532978) (xy 39.08228 -361.485263)
			(xy 39.10203 -361.463844) (xy 39.110857 -361.453996) (xy 39.123643 -361.430861) (xy 39.130042 -361.405215)
			(xy 39.129623 -361.378785) (xy 39.122414 -361.353354) (xy 39.108901 -361.330636) (xy 39.099744 -361.321096)
			(xy 39.078595 -361.299436) (xy 39.042713 -361.250681) (xy 39.014981 -361.196872) (xy 38.996097 -361.139358)
			(xy 38.986534 -361.079583) (xy 38.985952 -361.049316) (xy 34.902394 -361.049316) (xy 34.902394 -365.851948)
			(xy 41.654982 -365.851948) (xy 41.659053 -365.796326) (xy 41.671179 -365.741889) (xy 41.691102 -365.689798)
			(xy 41.718398 -365.641163) (xy 41.752484 -365.59702) (xy 41.792633 -365.558311) (xy 41.837991 -365.52586)
			(xy 41.887591 -365.500359) (xy 41.940375 -365.482352) (xy 41.995218 -365.472222) (xy 42.050952 -365.470185)
			(xy 42.106389 -365.476285) (xy 42.160346 -365.490391) (xy 42.211675 -365.512203) (xy 42.259281 -365.541257)
			(xy 42.302149 -365.576932) (xy 42.330083 -365.608108) (xy 55.39308 -365.608108) (xy 55.397151 -365.552486)
			(xy 55.409277 -365.498049) (xy 55.4292 -365.445958) (xy 55.456496 -365.397323) (xy 55.490582 -365.35318)
			(xy 55.530731 -365.314471) (xy 55.576089 -365.28202) (xy 55.625689 -365.256519) (xy 55.678473 -365.238512)
			(xy 55.733316 -365.228382) (xy 55.78905 -365.226345) (xy 55.844487 -365.232445) (xy 55.898444 -365.246551)
			(xy 55.949773 -365.268363) (xy 55.997379 -365.297417) (xy 56.040247 -365.333092) (xy 56.077464 -365.374629)
			(xy 56.108237 -365.421142) (xy 56.131909 -365.471639) (xy 56.147977 -365.525046) (xy 56.156097 -365.580222)
			(xy 56.156606 -365.608108) (xy 56.156097 -365.635994) (xy 56.147977 -365.69117) (xy 56.131909 -365.744577)
			(xy 56.108237 -365.795074) (xy 56.077464 -365.841587) (xy 56.040247 -365.883124) (xy 55.997379 -365.918799)
			(xy 55.949773 -365.947853) (xy 55.898444 -365.969665) (xy 55.844487 -365.983771) (xy 55.78905 -365.989871)
			(xy 55.733316 -365.987834) (xy 55.678473 -365.977704) (xy 55.625689 -365.959697) (xy 55.576089 -365.934196)
			(xy 55.530731 -365.901745) (xy 55.490582 -365.863036) (xy 55.456496 -365.818893) (xy 55.4292 -365.770258)
			(xy 55.409277 -365.718167) (xy 55.397151 -365.66373) (xy 55.39308 -365.608108) (xy 42.330083 -365.608108)
			(xy 42.339366 -365.618469) (xy 42.370139 -365.664982) (xy 42.393811 -365.715479) (xy 42.409879 -365.768886)
			(xy 42.417999 -365.824062) (xy 42.418508 -365.851948) (xy 42.417999 -365.879834) (xy 42.409879 -365.93501)
			(xy 42.393811 -365.988417) (xy 42.370139 -366.038914) (xy 42.339366 -366.085427) (xy 42.302149 -366.126964)
			(xy 42.259281 -366.162639) (xy 42.211675 -366.191693) (xy 42.160346 -366.213505) (xy 42.106389 -366.227611)
			(xy 42.050952 -366.233711) (xy 41.995218 -366.231674) (xy 41.940375 -366.221544) (xy 41.887591 -366.203537)
			(xy 41.837991 -366.178036) (xy 41.792633 -366.145585) (xy 41.752484 -366.106876) (xy 41.718398 -366.062733)
			(xy 41.691102 -366.014098) (xy 41.671179 -365.962007) (xy 41.659053 -365.90757) (xy 41.654982 -365.851948)
			(xy 34.902394 -365.851948) (xy 34.902394 -365.859822) (xy 36.05022 -367.007648) (xy 55.41391 -367.007648)
		)
		(stroke
			(width 0)
			(type solid)
		)
		(fill yes)
		(layer "In13.Cu")
		(net "GND")
	)
	(gr_poly
		(pts
			(xy 313.817254 -65.842388) (xy 313.831089 -65.84193) (xy 313.857745 -65.83451) (xy 313.881429 -65.820203)
			(xy 313.9004 -65.80006) (xy 313.913263 -65.775562) (xy 313.919074 -65.74851) (xy 313.917405 -65.72089)
			(xy 313.908379 -65.694734) (xy 313.892659 -65.671964) (xy 313.882278 -65.66281) (xy 313.861251 -65.644572)
			(xy 313.824189 -65.603047) (xy 313.793548 -65.55658) (xy 313.769979 -65.506157) (xy 313.75398 -65.452846)
			(xy 313.745892 -65.397778) (xy 313.745372 -65.369948) (xy 313.745858 -65.342697) (xy 313.753614 -65.288749)
			(xy 313.768969 -65.236454) (xy 313.791611 -65.186877) (xy 313.821077 -65.141027) (xy 313.856768 -65.099836)
			(xy 313.897959 -65.064145) (xy 313.943809 -65.034679) (xy 313.993386 -65.012037) (xy 314.045681 -64.996682)
			(xy 314.099629 -64.988926) (xy 314.154131 -64.988926) (xy 314.208079 -64.996682) (xy 314.260374 -65.012037)
			(xy 314.309951 -65.034679) (xy 314.332067 -65.048892) (xy 316.214758 -65.048892) (xy 316.218829 -64.99327)
			(xy 316.230955 -64.938833) (xy 316.250878 -64.886742) (xy 316.278174 -64.838107) (xy 316.31226 -64.793964)
			(xy 316.352409 -64.755255) (xy 316.397767 -64.722804) (xy 316.447367 -64.697303) (xy 316.500151 -64.679296)
			(xy 316.554994 -64.669166) (xy 316.610728 -64.667129) (xy 316.666165 -64.673229) (xy 316.720122 -64.687335)
			(xy 316.771451 -64.709147) (xy 316.819057 -64.738201) (xy 316.861925 -64.773876) (xy 316.899142 -64.815413)
			(xy 316.929915 -64.861926) (xy 316.953587 -64.912423) (xy 316.969655 -64.96583) (xy 316.977775 -65.021006)
			(xy 316.978284 -65.048892) (xy 316.977775 -65.076778) (xy 316.969655 -65.131954) (xy 316.953587 -65.185361)
			(xy 316.929915 -65.235858) (xy 316.899142 -65.282371) (xy 316.861925 -65.323908) (xy 316.819057 -65.359583)
			(xy 316.771451 -65.388637) (xy 316.720122 -65.410449) (xy 316.666165 -65.424555) (xy 316.610728 -65.430655)
			(xy 316.554994 -65.428618) (xy 316.500151 -65.418488) (xy 316.447367 -65.400481) (xy 316.397767 -65.37498)
			(xy 316.352409 -65.342529) (xy 316.31226 -65.30382) (xy 316.278174 -65.259677) (xy 316.250878 -65.211042)
			(xy 316.230955 -65.158951) (xy 316.218829 -65.104514) (xy 316.214758 -65.048892) (xy 314.332067 -65.048892)
			(xy 314.355801 -65.064145) (xy 314.396992 -65.099836) (xy 314.432683 -65.141027) (xy 314.462149 -65.186877)
			(xy 314.484791 -65.236454) (xy 314.500146 -65.288749) (xy 314.507902 -65.342697) (xy 314.508388 -65.369948)
			(xy 314.507887 -65.39778) (xy 314.499808 -65.452853) (xy 314.483812 -65.506168) (xy 314.46024 -65.556594)
			(xy 314.429591 -65.603059) (xy 314.392517 -65.644579) (xy 314.371482 -65.66281) (xy 314.361168 -65.672025)
			(xy 314.34548 -65.694788) (xy 314.336475 -65.720926) (xy 314.334814 -65.748522) (xy 314.340619 -65.775552)
			(xy 314.353464 -65.800032) (xy 314.372407 -65.820168) (xy 314.396058 -65.834483) (xy 314.422683 -65.841926)
			(xy 314.436506 -65.842388) (xy 325.908416 -65.842388) (xy 328.415396 -63.335408) (xy 328.415396 -61.560202)
			(xy 328.414819 -61.544507) (xy 328.405305 -61.514593) (xy 328.387169 -61.48897) (xy 328.362121 -61.470051)
			(xy 328.332516 -61.459615) (xy 328.316844 -61.458602) (xy 328.290131 -61.457364) (xy 328.237423 -61.448339)
			(xy 328.186491 -61.432043) (xy 328.138333 -61.408795) (xy 328.093893 -61.37905) (xy 328.054042 -61.343393)
			(xy 328.019559 -61.30252) (xy 327.991121 -61.257233) (xy 327.969285 -61.208419) (xy 327.954479 -61.157034)
			(xy 327.946992 -61.104086) (xy 327.946512 -61.077348) (xy 327.946995 -61.049879) (xy 327.954885 -60.995511)
			(xy 327.970494 -60.942837) (xy 327.9935 -60.892948) (xy 328.023425 -60.846876) (xy 328.059652 -60.805575)
			(xy 328.101429 -60.769899) (xy 328.147893 -60.740586) (xy 328.198083 -60.718243) (xy 328.224388 -60.710318)
			(xy 328.237778 -60.706066) (xy 328.261694 -60.691346) (xy 328.280687 -60.67066) (xy 328.293317 -60.645577)
			(xy 328.298625 -60.618) (xy 328.296209 -60.590021) (xy 328.291698 -60.576714) (xy 328.280348 -60.544287)
			(xy 328.268076 -60.476696) (xy 328.267314 -60.442348) (xy 328.267774 -60.415093) (xy 328.275526 -60.361139)
			(xy 328.290878 -60.308836) (xy 328.313518 -60.259251) (xy 328.342985 -60.213394) (xy 328.378679 -60.172197)
			(xy 328.419873 -60.1365) (xy 328.465729 -60.10703) (xy 328.515312 -60.084387) (xy 328.567613 -60.069031)
			(xy 328.621568 -60.061276) (xy 328.648822 -60.06084) (xy 328.675368 -60.061293) (xy 328.727948 -60.068647)
			(xy 328.778999 -60.083222) (xy 328.827535 -60.104739) (xy 328.872617 -60.132779) (xy 328.913375 -60.166802)
			(xy 328.949018 -60.20615) (xy 328.97886 -60.250061) (xy 328.99096 -60.273692) (xy 328.99748 -60.285863)
			(xy 329.015879 -60.306436) (xy 329.039114 -60.321331) (xy 329.06549 -60.329459) (xy 329.09308 -60.330226)
			(xy 329.119867 -60.323578) (xy 329.143895 -60.309999) (xy 329.154028 -60.300616) (xy 332.398624 -57.05602)
			(xy 332.38694 -57.025286) (xy 332.376987 -56.997108) (xy 332.366258 -56.938324) (xy 332.365604 -56.908446)
			(xy 332.366084 -56.882455) (xy 332.374209 -56.831111) (xy 332.390268 -56.781671) (xy 332.413863 -56.735353)
			(xy 332.444415 -56.693296) (xy 332.48117 -56.656537) (xy 332.523224 -56.625981) (xy 332.56954 -56.602381)
			(xy 332.618978 -56.586317) (xy 332.670321 -56.578186) (xy 332.696312 -56.577738) (xy 332.72619 -56.578382)
			(xy 332.784973 -56.589122) (xy 332.813152 -56.599074) (xy 332.843886 -56.610758) (xy 333.122016 -56.332628)
			(xy 333.122016 -56.256174) (xy 333.121573 -56.242523) (xy 333.114331 -56.2162) (xy 333.100372 -56.192737)
			(xy 333.080694 -56.173812) (xy 333.056704 -56.160779) (xy 333.030118 -56.15457) (xy 333.002837 -56.155629)
			(xy 332.976812 -56.163879) (xy 332.953904 -56.178732) (xy 332.94447 -56.18861) (xy 332.925494 -56.209068)
			(xy 332.881934 -56.243932) (xy 332.833135 -56.270981) (xy 332.780484 -56.289446) (xy 332.725479 -56.298801)
			(xy 332.697582 -56.299354) (xy 332.671592 -56.298843) (xy 332.620253 -56.290709) (xy 332.570818 -56.274644)
			(xy 332.524504 -56.251044) (xy 332.482453 -56.22049) (xy 332.445698 -56.183734) (xy 332.415146 -56.14168)
			(xy 332.391549 -56.095366) (xy 332.375487 -56.04593) (xy 332.367356 -55.99459) (xy 332.367356 -55.94261)
			(xy 332.375487 -55.89127) (xy 332.391549 -55.841834) (xy 332.415146 -55.79552) (xy 332.445698 -55.753466)
			(xy 332.482453 -55.71671) (xy 332.524504 -55.686156) (xy 332.570818 -55.662556) (xy 332.620253 -55.646491)
			(xy 332.671592 -55.638357) (xy 332.697582 -55.637938) (xy 332.725475 -55.638523) (xy 332.780468 -55.647898)
			(xy 332.833107 -55.666369) (xy 332.881901 -55.69341) (xy 332.925465 -55.728256) (xy 332.94447 -55.748682)
			(xy 332.953871 -55.758597) (xy 332.976781 -55.77347) (xy 333.002814 -55.781734) (xy 333.030107 -55.782798)
			(xy 333.056705 -55.776585) (xy 333.080702 -55.763541) (xy 333.100381 -55.744599) (xy 333.114331 -55.721117)
			(xy 333.121554 -55.694775) (xy 333.122016 -55.681118) (xy 333.122016 -54.613048) (xy 333.178912 -54.556152)
			(xy 333.180182 -54.537102) (xy 333.182278 -54.512463) (xy 333.192861 -54.464161) (xy 333.210517 -54.417973)
			(xy 333.234853 -54.374929) (xy 333.265326 -54.335987) (xy 333.301257 -54.302016) (xy 333.341845 -54.273773)
			(xy 333.386185 -54.251887) (xy 333.43329 -54.236846) (xy 333.482109 -54.228986) (xy 333.506826 -54.228238)
			(xy 333.51978 -54.215284) (xy 333.51978 -52.016406) (xy 333.760064 -51.776122) (xy 333.760064 -51.231292)
			(xy 334.527906 -50.46345) (xy 334.527906 -49.933352) (xy 334.527463 -49.919624) (xy 334.52016 -49.893159)
			(xy 334.506068 -49.869597) (xy 334.486206 -49.850642) (xy 334.462011 -49.837666) (xy 334.435233 -49.831608)
			(xy 334.407809 -49.832905) (xy 334.381722 -49.841464) (xy 334.35886 -49.856665) (xy 334.349598 -49.866804)
			(xy 334.333813 -49.884422) (xy 334.298075 -49.915412) (xy 334.258289 -49.940998) (xy 334.215265 -49.960659)
			(xy 334.169881 -49.973993) (xy 334.12306 -49.980729) (xy 334.099408 -49.981104) (xy 334.073419 -49.980621)
			(xy 334.02208 -49.972491) (xy 333.972645 -49.95643) (xy 333.926331 -49.932833) (xy 333.884279 -49.902281)
			(xy 333.847524 -49.865527) (xy 333.816971 -49.823476) (xy 333.793373 -49.777163) (xy 333.777311 -49.727728)
			(xy 333.769179 -49.676389) (xy 333.769179 -49.624411) (xy 333.777311 -49.573072) (xy 333.793373 -49.523637)
			(xy 333.816971 -49.477324) (xy 333.847524 -49.435273) (xy 333.884279 -49.398519) (xy 333.926331 -49.367967)
			(xy 333.972645 -49.34437) (xy 334.02208 -49.328309) (xy 334.073419 -49.320179) (xy 334.099408 -49.319688)
			(xy 334.123058 -49.320091) (xy 334.169877 -49.326825) (xy 334.215261 -49.340155) (xy 334.258285 -49.359809)
			(xy 334.298074 -49.385387) (xy 334.333816 -49.416369) (xy 334.349598 -49.433988) (xy 334.358927 -49.44405)
			(xy 334.381775 -49.459225) (xy 334.407839 -49.467767) (xy 334.435237 -49.469059) (xy 334.461989 -49.463007)
			(xy 334.486163 -49.450049) (xy 334.506013 -49.43112) (xy 334.520104 -49.407589) (xy 334.52742 -49.381154)
			(xy 334.527906 -49.36744) (xy 334.527906 -48.226218) (xy 334.242156 -47.940468) (xy 333.840328 -47.940468)
			(xy 333.838804 -47.989744) (xy 333.837606 -48.015229) (xy 333.828339 -48.065397) (xy 333.811474 -48.113546)
			(xy 333.787413 -48.158532) (xy 333.756726 -48.199288) (xy 333.720143 -48.234846) (xy 333.678531 -48.264362)
			(xy 333.632878 -48.287134) (xy 333.58427 -48.302623) (xy 333.533858 -48.310461) (xy 333.482842 -48.310461)
			(xy 333.43243 -48.302623) (xy 333.383822 -48.287134) (xy 333.338169 -48.264362) (xy 333.296557 -48.234846)
			(xy 333.259974 -48.199288) (xy 333.229287 -48.158532) (xy 333.205226 -48.113546) (xy 333.188361 -48.065397)
			(xy 333.179094 -48.015229) (xy 333.177896 -47.989744) (xy 333.176372 -47.940468) (xy 332.735936 -47.940468)
			(xy 332.719172 -47.957232) (xy 332.709895 -47.967118) (xy 332.696455 -47.990651) (xy 332.689675 -48.016891)
			(xy 332.690034 -48.043989) (xy 332.697505 -48.07004) (xy 332.711563 -48.093209) (xy 332.731219 -48.111867)
			(xy 332.755089 -48.1247) (xy 332.768194 -48.128174) (xy 332.79213 -48.134199) (xy 332.838018 -48.152379)
			(xy 332.880695 -48.177175) (xy 332.919213 -48.208038) (xy 332.952718 -48.244281) (xy 332.980466 -48.285101)
			(xy 333.001841 -48.32959) (xy 333.016368 -48.376761) (xy 333.023724 -48.425567) (xy 333.024226 -48.450246)
			(xy 333.023713 -48.476231) (xy 333.015577 -48.527561) (xy 332.999512 -48.576987) (xy 332.975914 -48.623291)
			(xy 332.945364 -48.665335) (xy 332.908613 -48.702082) (xy 332.866567 -48.732629) (xy 332.820261 -48.756223)
			(xy 332.770834 -48.772283) (xy 332.719503 -48.780415) (xy 332.693518 -48.780954) (xy 332.668833 -48.780504)
			(xy 332.620009 -48.773177) (xy 332.572819 -48.758666) (xy 332.528312 -48.737297) (xy 332.487481 -48.709544)
			(xy 332.451233 -48.676025) (xy 332.420375 -48.637486) (xy 332.395594 -48.594785) (xy 332.377442 -48.548872)
			(xy 332.371446 -48.524922) (xy 332.367982 -48.511814) (xy 332.355152 -48.487942) (xy 332.336495 -48.468284)
			(xy 332.313325 -48.454226) (xy 332.287272 -48.446757) (xy 332.260173 -48.446403) (xy 332.233934 -48.453189)
			(xy 332.210405 -48.466637) (xy 332.200504 -48.4759) (xy 332.12405 -48.552354) (xy 332.113366 -48.563852)
			(xy 332.098942 -48.59171) (xy 332.09363 -48.622627) (xy 332.097929 -48.653702) (xy 332.111435 -48.682016)
			(xy 332.121764 -48.693832) (xy 332.138519 -48.712317) (xy 332.166841 -48.753387) (xy 332.188668 -48.798248)
			(xy 332.203503 -48.845881) (xy 332.21101 -48.895202) (xy 332.211426 -48.920146) (xy 332.210913 -48.946131)
			(xy 332.202777 -48.997461) (xy 332.186712 -49.046887) (xy 332.163114 -49.093191) (xy 332.132564 -49.135235)
			(xy 332.095813 -49.171982) (xy 332.053767 -49.202529) (xy 332.007461 -49.226123) (xy 331.958034 -49.242183)
			(xy 331.906703 -49.250315) (xy 331.880718 -49.250854) (xy 331.850234 -49.250178) (xy 331.790291 -49.239055)
			(xy 331.761592 -49.228756) (xy 331.748274 -49.224105) (xy 331.720192 -49.221533) (xy 331.692477 -49.226734)
			(xy 331.667238 -49.239312) (xy 331.646399 -49.25831) (xy 331.631546 -49.282281) (xy 331.623811 -49.309399)
			(xy 331.623416 -49.323498) (xy 331.623416 -49.416033) (xy 332.36332 -49.416033) (xy 332.36332 -49.364059)
			(xy 332.37145 -49.312724) (xy 332.387511 -49.263294) (xy 332.411107 -49.216984) (xy 332.441657 -49.174936)
			(xy 332.478408 -49.138185) (xy 332.520456 -49.107635) (xy 332.566766 -49.084039) (xy 332.616196 -49.067978)
			(xy 332.667531 -49.059848) (xy 332.719505 -49.059848) (xy 332.77084 -49.067978) (xy 332.82027 -49.084039)
			(xy 332.86658 -49.107635) (xy 332.908628 -49.138185) (xy 332.945379 -49.174936) (xy 332.975929 -49.216984)
			(xy 332.999525 -49.263294) (xy 333.015586 -49.312724) (xy 333.023716 -49.364059) (xy 333.024226 -49.390046)
			(xy 333.023716 -49.416033) (xy 333.015586 -49.467368) (xy 332.999525 -49.516798) (xy 332.975929 -49.563108)
			(xy 332.945379 -49.605156) (xy 332.908628 -49.641907) (xy 332.86658 -49.672457) (xy 332.82027 -49.696053)
			(xy 332.77084 -49.712114) (xy 332.719505 -49.720244) (xy 332.667531 -49.720244) (xy 332.616196 -49.712114)
			(xy 332.566766 -49.696053) (xy 332.520456 -49.672457) (xy 332.478408 -49.641907) (xy 332.441657 -49.605156)
			(xy 332.411107 -49.563108) (xy 332.387511 -49.516798) (xy 332.37145 -49.467368) (xy 332.36332 -49.416033)
			(xy 331.623416 -49.416033) (xy 331.623416 -49.456594) (xy 331.623871 -49.470694) (xy 331.631583 -49.497819)
			(xy 331.64642 -49.521799) (xy 331.667251 -49.540807) (xy 331.692487 -49.553392) (xy 331.720203 -49.558594)
			(xy 331.748285 -49.556016) (xy 331.761592 -49.551336) (xy 331.790289 -49.541031) (xy 331.850234 -49.529915)
			(xy 331.880718 -49.529238) (xy 331.906701 -49.529749) (xy 331.958026 -49.537881) (xy 332.007447 -49.553941)
			(xy 332.053747 -49.577535) (xy 332.095787 -49.608081) (xy 332.132531 -49.644827) (xy 332.163075 -49.686868)
			(xy 332.186666 -49.73317) (xy 332.202723 -49.782592) (xy 332.210852 -49.833917) (xy 332.210852 -49.885883)
			(xy 332.202723 -49.937208) (xy 332.186666 -49.98663) (xy 332.163075 -50.032932) (xy 332.132531 -50.074973)
			(xy 332.095787 -50.111719) (xy 332.053747 -50.142265) (xy 332.007447 -50.165859) (xy 331.958026 -50.181919)
			(xy 331.906701 -50.190051) (xy 331.880718 -50.190654) (xy 331.850234 -50.189978) (xy 331.790291 -50.178855)
			(xy 331.761592 -50.168556) (xy 331.748274 -50.163905) (xy 331.720192 -50.161333) (xy 331.692477 -50.166534)
			(xy 331.667238 -50.179112) (xy 331.646399 -50.19811) (xy 331.631546 -50.222081) (xy 331.623811 -50.249199)
			(xy 331.623416 -50.263298) (xy 331.623416 -50.355833) (xy 332.36332 -50.355833) (xy 332.36332 -50.303859)
			(xy 332.37145 -50.252524) (xy 332.387511 -50.203094) (xy 332.411107 -50.156784) (xy 332.441657 -50.114736)
			(xy 332.478408 -50.077985) (xy 332.520456 -50.047435) (xy 332.566766 -50.023839) (xy 332.616196 -50.007778)
			(xy 332.667531 -49.999648) (xy 332.719505 -49.999648) (xy 332.77084 -50.007778) (xy 332.82027 -50.023839)
			(xy 332.86658 -50.047435) (xy 332.908628 -50.077985) (xy 332.945379 -50.114736) (xy 332.975929 -50.156784)
			(xy 332.999525 -50.203094) (xy 333.015586 -50.252524) (xy 333.023716 -50.303859) (xy 333.024226 -50.329846)
			(xy 333.023716 -50.355833) (xy 333.015586 -50.407168) (xy 332.999525 -50.456598) (xy 332.975929 -50.502908)
			(xy 332.945379 -50.544956) (xy 332.908628 -50.581707) (xy 332.86658 -50.612257) (xy 332.82027 -50.635853)
			(xy 332.77084 -50.651914) (xy 332.719505 -50.660044) (xy 332.667531 -50.660044) (xy 332.616196 -50.651914)
			(xy 332.566766 -50.635853) (xy 332.520456 -50.612257) (xy 332.478408 -50.581707) (xy 332.441657 -50.544956)
			(xy 332.411107 -50.502908) (xy 332.387511 -50.456598) (xy 332.37145 -50.407168) (xy 332.36332 -50.355833)
			(xy 331.623416 -50.355833) (xy 331.623416 -50.396394) (xy 331.623871 -50.410494) (xy 331.631583 -50.437619)
			(xy 331.64642 -50.461599) (xy 331.667251 -50.480607) (xy 331.692487 -50.493192) (xy 331.720203 -50.498394)
			(xy 331.748285 -50.495816) (xy 331.761592 -50.491136) (xy 331.790289 -50.480831) (xy 331.850234 -50.469715)
			(xy 331.880718 -50.469038) (xy 331.906701 -50.469549) (xy 331.958026 -50.477681) (xy 332.007447 -50.493741)
			(xy 332.053747 -50.517335) (xy 332.095787 -50.547881) (xy 332.132531 -50.584627) (xy 332.163075 -50.626668)
			(xy 332.186666 -50.67297) (xy 332.202723 -50.722392) (xy 332.210852 -50.773717) (xy 332.210852 -50.825683)
			(xy 332.210844 -50.825733) (xy 333.177644 -50.825733) (xy 333.177644 -50.773759) (xy 333.185774 -50.722424)
			(xy 333.201835 -50.672994) (xy 333.225431 -50.626684) (xy 333.255981 -50.584636) (xy 333.292732 -50.547885)
			(xy 333.33478 -50.517335) (xy 333.38109 -50.493739) (xy 333.43052 -50.477678) (xy 333.481855 -50.469548)
			(xy 333.533829 -50.469548) (xy 333.585164 -50.477678) (xy 333.634594 -50.493739) (xy 333.680904 -50.517335)
			(xy 333.722952 -50.547885) (xy 333.759703 -50.584636) (xy 333.790253 -50.626684) (xy 333.813849 -50.672994)
			(xy 333.82991 -50.722424) (xy 333.83804 -50.773759) (xy 333.83855 -50.799746) (xy 333.83804 -50.825733)
			(xy 333.82991 -50.877068) (xy 333.813849 -50.926498) (xy 333.790253 -50.972808) (xy 333.759703 -51.014856)
			(xy 333.722952 -51.051607) (xy 333.680904 -51.082157) (xy 333.634594 -51.105753) (xy 333.585164 -51.121814)
			(xy 333.533829 -51.129944) (xy 333.481855 -51.129944) (xy 333.43052 -51.121814) (xy 333.38109 -51.105753)
			(xy 333.33478 -51.082157) (xy 333.292732 -51.051607) (xy 333.255981 -51.014856) (xy 333.225431 -50.972808)
			(xy 333.201835 -50.926498) (xy 333.185774 -50.877068) (xy 333.177644 -50.825733) (xy 332.210844 -50.825733)
			(xy 332.202723 -50.877008) (xy 332.186666 -50.92643) (xy 332.163075 -50.972732) (xy 332.132531 -51.014773)
			(xy 332.095787 -51.051519) (xy 332.053747 -51.082065) (xy 332.007447 -51.105659) (xy 331.958026 -51.121719)
			(xy 331.906701 -51.129851) (xy 331.880718 -51.130454) (xy 331.856806 -51.130013) (xy 331.809485 -51.123091)
			(xy 331.763652 -51.109432) (xy 331.720262 -51.08932) (xy 331.680217 -51.063174) (xy 331.662024 -51.04765)
			(xy 331.62621 -51.016154) (xy 331.395832 -51.246532) (xy 331.396086 -51.267614) (xy 331.396086 -51.269646)
			(xy 331.395573 -51.29563) (xy 331.387437 -51.346958) (xy 331.371371 -51.396381) (xy 331.347773 -51.442682)
			(xy 331.317222 -51.484722) (xy 331.280471 -51.521466) (xy 331.238424 -51.552008) (xy 331.192118 -51.575597)
			(xy 331.142692 -51.591652) (xy 331.091362 -51.599778) (xy 331.065378 -51.600354) (xy 331.063346 -51.600354)
			(xy 331.042264 -51.6001) (xy 330.876831 -51.765533) (xy 331.549758 -51.765533) (xy 331.549758 -51.713559)
			(xy 331.557888 -51.662224) (xy 331.573949 -51.612794) (xy 331.597545 -51.566484) (xy 331.628095 -51.524436)
			(xy 331.664846 -51.487685) (xy 331.706894 -51.457135) (xy 331.753204 -51.433539) (xy 331.802634 -51.417478)
			(xy 331.853969 -51.409348) (xy 331.905943 -51.409348) (xy 331.957278 -51.417478) (xy 332.006708 -51.433539)
			(xy 332.053018 -51.457135) (xy 332.095066 -51.487685) (xy 332.131817 -51.524436) (xy 332.162367 -51.566484)
			(xy 332.185963 -51.612794) (xy 332.202024 -51.662224) (xy 332.210154 -51.713559) (xy 332.210664 -51.739546)
			(xy 332.210154 -51.765533) (xy 332.202024 -51.816868) (xy 332.185963 -51.866298) (xy 332.162367 -51.912608)
			(xy 332.131817 -51.954656) (xy 332.095066 -51.991407) (xy 332.053018 -52.021957) (xy 332.006708 -52.045553)
			(xy 331.957278 -52.061614) (xy 331.905943 -52.069744) (xy 331.853969 -52.069744) (xy 331.802634 -52.061614)
			(xy 331.753204 -52.045553) (xy 331.706894 -52.021957) (xy 331.664846 -51.991407) (xy 331.628095 -51.954656)
			(xy 331.597545 -51.912608) (xy 331.573949 -51.866298) (xy 331.557888 -51.816868) (xy 331.549758 -51.765533)
			(xy 330.876831 -51.765533) (xy 330.406931 -52.235433) (xy 330.737466 -52.235433) (xy 330.737466 -52.183459)
			(xy 330.745596 -52.132124) (xy 330.761657 -52.082694) (xy 330.785253 -52.036384) (xy 330.815803 -51.994336)
			(xy 330.852554 -51.957585) (xy 330.894602 -51.927035) (xy 330.940912 -51.903439) (xy 330.990342 -51.887378)
			(xy 331.041677 -51.879248) (xy 331.093651 -51.879248) (xy 331.144986 -51.887378) (xy 331.194416 -51.903439)
			(xy 331.240726 -51.927035) (xy 331.282774 -51.957585) (xy 331.319525 -51.994336) (xy 331.350075 -52.036384)
			(xy 331.373671 -52.082694) (xy 331.389732 -52.132124) (xy 331.397862 -52.183459) (xy 331.398372 -52.209446)
			(xy 331.397862 -52.235433) (xy 331.389732 -52.286768) (xy 331.373671 -52.336198) (xy 331.350075 -52.382508)
			(xy 331.319525 -52.424556) (xy 331.282774 -52.461307) (xy 331.240726 -52.491857) (xy 331.194416 -52.515453)
			(xy 331.144986 -52.531514) (xy 331.093651 -52.539644) (xy 331.041677 -52.539644) (xy 330.990342 -52.531514)
			(xy 330.940912 -52.515453) (xy 330.894602 -52.491857) (xy 330.852554 -52.461307) (xy 330.815803 -52.424556)
			(xy 330.785253 -52.382508) (xy 330.761657 -52.336198) (xy 330.745596 -52.286768) (xy 330.737466 -52.235433)
			(xy 330.406931 -52.235433) (xy 330.378816 -52.263548) (xy 330.312776 -52.263548) (xy 330.312776 -52.35194)
			(xy 330.348844 -52.362862) (xy 330.373923 -52.371052) (xy 330.421299 -52.39426) (xy 330.464395 -52.424687)
			(xy 330.50212 -52.461563) (xy 330.53352 -52.503956) (xy 330.557799 -52.550792) (xy 330.574343 -52.600885)
			(xy 330.582734 -52.652969) (xy 330.583286 -52.679346) (xy 330.582776 -52.705333) (xy 330.574646 -52.756668)
			(xy 330.558585 -52.806098) (xy 330.534989 -52.852408) (xy 330.504439 -52.894456) (xy 330.467688 -52.931207)
			(xy 330.42564 -52.961757) (xy 330.37933 -52.985353) (xy 330.3299 -53.001414) (xy 330.278565 -53.009544)
			(xy 330.226591 -53.009544) (xy 330.175256 -53.001414) (xy 330.125826 -52.985353) (xy 330.079516 -52.961757)
			(xy 330.037468 -52.931207) (xy 330.000717 -52.894456) (xy 329.970167 -52.852408) (xy 329.946571 -52.806098)
			(xy 329.93051 -52.756668) (xy 329.92238 -52.705333) (xy 329.92187 -52.679346) (xy 329.922397 -52.652423)
			(xy 329.931123 -52.59929) (xy 329.94835 -52.548275) (xy 329.973624 -52.50073) (xy 330.006273 -52.457913)
			(xy 330.025502 -52.439062) (xy 330.036149 -52.428231) (xy 330.051114 -52.401821) (xy 330.057662 -52.372181)
			(xy 330.055215 -52.341925) (xy 330.043989 -52.313723) (xy 330.024975 -52.290061) (xy 329.99985 -52.273028)
			(xy 329.97083 -52.264126) (xy 329.955652 -52.263548) (xy 329.766168 -52.263548) (xy 329.755754 -52.300378)
			(xy 329.748386 -52.324435) (xy 329.727388 -52.370155) (xy 329.699708 -52.412167) (xy 329.665985 -52.449502)
			(xy 329.626996 -52.4813) (xy 329.583641 -52.506825) (xy 329.53692 -52.525491) (xy 329.487912 -52.536865)
			(xy 329.437746 -52.540686) (xy 329.38758 -52.536865) (xy 329.338572 -52.525491) (xy 329.291851 -52.506825)
			(xy 329.248496 -52.4813) (xy 329.209507 -52.449502) (xy 329.175784 -52.412167) (xy 329.148104 -52.370155)
			(xy 329.127106 -52.324435) (xy 329.119738 -52.300378) (xy 329.109324 -52.263548) (xy 328.958194 -52.263548)
			(xy 328.95413 -52.31003) (xy 328.951408 -52.335743) (xy 328.938997 -52.385934) (xy 328.918925 -52.433582)
			(xy 328.891681 -52.477526) (xy 328.85793 -52.516693) (xy 328.818493 -52.55013) (xy 328.774334 -52.577021)
			(xy 328.726527 -52.596711) (xy 328.676238 -52.608721) (xy 328.624692 -52.612757) (xy 328.573146 -52.608721)
			(xy 328.522857 -52.596711) (xy 328.47505 -52.577021) (xy 328.430891 -52.55013) (xy 328.391454 -52.516693)
			(xy 328.357703 -52.477526) (xy 328.330459 -52.433582) (xy 328.310387 -52.385934) (xy 328.297976 -52.335743)
			(xy 328.295254 -52.31003) (xy 328.29119 -52.263548) (xy 322.453 -52.263548) (xy 320.2432 -50.053748)
			(xy 312.83021 -50.053748) (xy 312.815089 -50.054287) (xy 312.786169 -50.063129) (xy 312.761117 -50.080067)
			(xy 312.742137 -50.103611) (xy 312.730901 -50.131687) (xy 312.729118 -50.146712) (xy 312.726225 -50.174951)
			(xy 312.713146 -50.230186) (xy 312.692027 -50.282874) (xy 312.663333 -50.331851) (xy 312.627698 -50.376035)
			(xy 312.58591 -50.41445) (xy 312.538889 -50.446249) (xy 312.487676 -50.470729) (xy 312.433401 -50.487349)
			(xy 312.377262 -50.495743) (xy 312.34888 -50.496216) (xy 312.321629 -50.495729) (xy 312.267683 -50.48797)
			(xy 312.215391 -50.472613) (xy 312.165815 -50.449971) (xy 312.119967 -50.420504) (xy 312.078778 -50.384813)
			(xy 312.043088 -50.343623) (xy 312.013623 -50.297774) (xy 311.990982 -50.248198) (xy 311.975627 -50.195905)
			(xy 311.96787 -50.141959) (xy 311.967372 -50.114708) (xy 311.967372 -50.053748) (xy 311.882282 -50.053748)
			(xy 311.517284 -50.418746) (xy 311.507632 -50.428144) (xy 311.497899 -50.437632) (xy 311.483408 -50.460615)
			(xy 311.475503 -50.48661) (xy 311.474748 -50.51377) (xy 311.481194 -50.540165) (xy 311.494385 -50.563918)
			(xy 311.503568 -50.57394) (xy 311.523914 -50.595474) (xy 311.558371 -50.643661) (xy 311.584968 -50.696594)
			(xy 311.603065 -50.753002) (xy 311.612228 -50.811528) (xy 311.612788 -50.841148) (xy 311.612302 -50.868399)
			(xy 311.604546 -50.922347) (xy 311.589191 -50.974642) (xy 311.566549 -51.024219) (xy 311.537083 -51.070069)
			(xy 311.501392 -51.11126) (xy 311.460201 -51.146951) (xy 311.414351 -51.176417) (xy 311.364774 -51.199059)
			(xy 311.312479 -51.214414) (xy 311.258531 -51.22217) (xy 311.204029 -51.22217) (xy 311.150081 -51.214414)
			(xy 311.097786 -51.199059) (xy 311.048209 -51.176417) (xy 311.002359 -51.146951) (xy 310.961168 -51.11126)
			(xy 310.925477 -51.070069) (xy 310.896011 -51.024219) (xy 310.873369 -50.974642) (xy 310.858014 -50.922347)
			(xy 310.850258 -50.868399) (xy 310.849772 -50.841148) (xy 310.850371 -50.809921) (xy 310.860508 -50.748296)
			(xy 310.880566 -50.689152) (xy 310.89473 -50.661316) (xy 310.901288 -50.647862) (xy 310.907084 -50.618513)
			(xy 310.904133 -50.588743) (xy 310.892689 -50.561103) (xy 310.873731 -50.537961) (xy 310.848885 -50.521299)
			(xy 310.820278 -50.512546) (xy 310.805322 -50.511964) (xy 310.024018 -50.511964) (xy 309.186834 -51.349148)
			(xy 311.662062 -51.349148) (xy 311.666133 -51.293526) (xy 311.678259 -51.239089) (xy 311.698182 -51.186998)
			(xy 311.725478 -51.138363) (xy 311.759564 -51.09422) (xy 311.799713 -51.055511) (xy 311.845071 -51.02306)
			(xy 311.894671 -50.997559) (xy 311.947455 -50.979552) (xy 312.002298 -50.969422) (xy 312.058032 -50.967385)
			(xy 312.113469 -50.973485) (xy 312.167426 -50.987591) (xy 312.218755 -51.009403) (xy 312.266361 -51.038457)
			(xy 312.309229 -51.074132) (xy 312.346446 -51.115669) (xy 312.377219 -51.162182) (xy 312.400891 -51.212679)
			(xy 312.416959 -51.266086) (xy 312.422458 -51.303451) (xy 312.872605 -51.303451) (xy 312.872605 -51.248949)
			(xy 312.880362 -51.195003) (xy 312.895717 -51.14271) (xy 312.918359 -51.093134) (xy 312.947826 -51.047286)
			(xy 312.983518 -51.006098) (xy 313.024708 -50.970409) (xy 313.070559 -50.940946) (xy 313.120136 -50.918308)
			(xy 313.172431 -50.902956) (xy 313.226377 -50.895203) (xy 313.253628 -50.894742) (xy 313.280555 -50.895198)
			(xy 313.333873 -50.902786) (xy 313.385595 -50.917794) (xy 313.434693 -50.939924) (xy 313.480193 -50.968736)
			(xy 313.521191 -51.003657) (xy 313.539378 -51.02352) (xy 313.549172 -51.033844) (xy 313.57317 -51.049114)
			(xy 313.600447 -51.057178) (xy 313.62889 -51.057412) (xy 313.656296 -51.049797) (xy 313.680541 -51.034923)
			(xy 313.699748 -51.013942) (xy 313.70651 -51.001422) (xy 313.718721 -50.977944) (xy 313.748622 -50.934281)
			(xy 313.784268 -50.895167) (xy 313.824975 -50.861353) (xy 313.869964 -50.833488) (xy 313.918372 -50.812105)
			(xy 313.969269 -50.797615) (xy 314.02168 -50.790295) (xy 314.04814 -50.78984) (xy 314.075393 -50.790233)
			(xy 314.129343 -50.797995) (xy 314.18164 -50.813355) (xy 314.231218 -50.836002) (xy 314.277069 -50.865473)
			(xy 314.31826 -50.901169) (xy 314.353951 -50.942363) (xy 314.383418 -50.988217) (xy 314.406059 -51.037798)
			(xy 314.421414 -51.090096) (xy 314.42917 -51.144047) (xy 314.42917 -51.145948) (xy 318.038478 -51.145948)
			(xy 318.042549 -51.090326) (xy 318.054675 -51.035889) (xy 318.074598 -50.983798) (xy 318.101894 -50.935163)
			(xy 318.13598 -50.89102) (xy 318.176129 -50.852311) (xy 318.221487 -50.81986) (xy 318.271087 -50.794359)
			(xy 318.323871 -50.776352) (xy 318.378714 -50.766222) (xy 318.434448 -50.764185) (xy 318.489885 -50.770285)
			(xy 318.543842 -50.784391) (xy 318.595171 -50.806203) (xy 318.642777 -50.835257) (xy 318.685645 -50.870932)
			(xy 318.722862 -50.912469) (xy 318.753635 -50.958982) (xy 318.777307 -51.009479) (xy 318.793375 -51.062886)
			(xy 318.801495 -51.118062) (xy 318.802004 -51.145948) (xy 318.801495 -51.173834) (xy 318.793375 -51.22901)
			(xy 318.777307 -51.282417) (xy 318.753635 -51.332914) (xy 318.722862 -51.379427) (xy 318.685645 -51.420964)
			(xy 318.642777 -51.456639) (xy 318.595171 -51.485693) (xy 318.543842 -51.507505) (xy 318.489885 -51.521611)
			(xy 318.434448 -51.527711) (xy 318.378714 -51.525674) (xy 318.323871 -51.515544) (xy 318.271087 -51.497537)
			(xy 318.221487 -51.472036) (xy 318.176129 -51.439585) (xy 318.13598 -51.400876) (xy 318.101894 -51.356733)
			(xy 318.074598 -51.308098) (xy 318.054675 -51.256007) (xy 318.042549 -51.20157) (xy 318.038478 -51.145948)
			(xy 314.42917 -51.145948) (xy 314.42917 -51.198553) (xy 314.421414 -51.252504) (xy 314.406059 -51.304802)
			(xy 314.383418 -51.354383) (xy 314.353951 -51.400237) (xy 314.31826 -51.441431) (xy 314.277069 -51.477127)
			(xy 314.231218 -51.506598) (xy 314.18164 -51.529245) (xy 314.129343 -51.544605) (xy 314.075393 -51.552367)
			(xy 314.04814 -51.552856) (xy 314.021214 -51.552354) (xy 313.967899 -51.544775) (xy 313.916178 -51.529777)
			(xy 313.867079 -51.507655) (xy 313.821578 -51.478852) (xy 313.780578 -51.443937) (xy 313.76239 -51.424078)
			(xy 313.75263 -51.413719) (xy 313.728624 -51.39845) (xy 313.701339 -51.390389) (xy 313.672888 -51.390161)
			(xy 313.645477 -51.397782) (xy 313.621228 -51.412663) (xy 313.60202 -51.433652) (xy 313.595258 -51.446176)
			(xy 313.58307 -51.469667) (xy 313.553167 -51.513331) (xy 313.517518 -51.552444) (xy 313.476806 -51.586257)
			(xy 313.431814 -51.614122) (xy 313.383403 -51.635502) (xy 313.332503 -51.649989) (xy 313.280089 -51.657305)
			(xy 313.253628 -51.657758) (xy 313.226377 -51.657197) (xy 313.172431 -51.649444) (xy 313.120136 -51.634092)
			(xy 313.070559 -51.611454) (xy 313.024708 -51.581991) (xy 312.983518 -51.546302) (xy 312.947826 -51.505114)
			(xy 312.918359 -51.459266) (xy 312.895717 -51.40969) (xy 312.880362 -51.357397) (xy 312.872605 -51.303451)
			(xy 312.422458 -51.303451) (xy 312.425079 -51.321262) (xy 312.425588 -51.349148) (xy 312.425079 -51.377034)
			(xy 312.416959 -51.43221) (xy 312.400891 -51.485617) (xy 312.377219 -51.536114) (xy 312.346446 -51.582627)
			(xy 312.309229 -51.624164) (xy 312.266361 -51.659839) (xy 312.218755 -51.688893) (xy 312.167426 -51.710705)
			(xy 312.113469 -51.724811) (xy 312.058032 -51.730911) (xy 312.002298 -51.728874) (xy 311.947455 -51.718744)
			(xy 311.894671 -51.700737) (xy 311.845071 -51.675236) (xy 311.799713 -51.642785) (xy 311.759564 -51.604076)
			(xy 311.725478 -51.559933) (xy 311.698182 -51.511298) (xy 311.678259 -51.459207) (xy 311.666133 -51.40477)
			(xy 311.662062 -51.349148) (xy 309.186834 -51.349148) (xy 308.980332 -51.55565) (xy 308.969982 -51.566768)
			(xy 308.955745 -51.593583) (xy 308.950027 -51.623399) (xy 308.953332 -51.653578) (xy 308.96537 -51.681449)
			(xy 308.985073 -51.704546) (xy 308.997604 -51.71313) (xy 309.02046 -51.728209) (xy 309.062002 -51.76388)
			(xy 309.098013 -51.805128) (xy 309.127752 -51.851104) (xy 309.150607 -51.900861) (xy 309.166108 -51.953377)
			(xy 309.173935 -52.00757) (xy 309.174388 -52.034948) (xy 309.173898 -52.062196) (xy 309.166136 -52.116138)
			(xy 309.150777 -52.168426) (xy 309.128133 -52.217995) (xy 309.098665 -52.263838) (xy 309.076903 -52.288948)
			(xy 310.442862 -52.288948) (xy 310.446933 -52.233326) (xy 310.459059 -52.178889) (xy 310.478982 -52.126798)
			(xy 310.506278 -52.078163) (xy 310.540364 -52.03402) (xy 310.580513 -51.995311) (xy 310.625871 -51.96286)
			(xy 310.675471 -51.937359) (xy 310.728255 -51.919352) (xy 310.783098 -51.909222) (xy 310.838832 -51.907185)
			(xy 310.894269 -51.913285) (xy 310.948226 -51.927391) (xy 310.999555 -51.949203) (xy 311.047161 -51.978257)
			(xy 311.090029 -52.013932) (xy 311.127246 -52.055469) (xy 311.158019 -52.101982) (xy 311.181691 -52.152479)
			(xy 311.197759 -52.205886) (xy 311.205879 -52.261062) (xy 311.205924 -52.263548) (xy 313.710318 -52.263548)
			(xy 313.714389 -52.207926) (xy 313.726515 -52.153489) (xy 313.746438 -52.101398) (xy 313.773734 -52.052763)
			(xy 313.80782 -52.00862) (xy 313.847969 -51.969911) (xy 313.893327 -51.93746) (xy 313.942927 -51.911959)
			(xy 313.995711 -51.893952) (xy 314.050554 -51.883822) (xy 314.106288 -51.881785) (xy 314.161725 -51.887885)
			(xy 314.215682 -51.901991) (xy 314.267011 -51.923803) (xy 314.314617 -51.952857) (xy 314.357485 -51.988532)
			(xy 314.394702 -52.030069) (xy 314.425475 -52.076582) (xy 314.449147 -52.127079) (xy 314.465215 -52.180486)
			(xy 314.473335 -52.235662) (xy 314.473844 -52.263548) (xy 314.473335 -52.291434) (xy 314.465215 -52.34661)
			(xy 314.449147 -52.400017) (xy 314.425475 -52.450514) (xy 314.394702 -52.497027) (xy 314.357485 -52.538564)
			(xy 314.314617 -52.574239) (xy 314.267011 -52.603293) (xy 314.215682 -52.625105) (xy 314.161725 -52.639211)
			(xy 314.106288 -52.645311) (xy 314.050554 -52.643274) (xy 313.995711 -52.633144) (xy 313.942927 -52.615137)
			(xy 313.893327 -52.589636) (xy 313.847969 -52.557185) (xy 313.80782 -52.518476) (xy 313.773734 -52.474333)
			(xy 313.746438 -52.425698) (xy 313.726515 -52.373607) (xy 313.714389 -52.31917) (xy 313.710318 -52.263548)
			(xy 311.205924 -52.263548) (xy 311.206388 -52.288948) (xy 311.205879 -52.316834) (xy 311.197759 -52.37201)
			(xy 311.181691 -52.425417) (xy 311.158019 -52.475914) (xy 311.127246 -52.522427) (xy 311.090029 -52.563964)
			(xy 311.047161 -52.599639) (xy 310.999555 -52.628693) (xy 310.948226 -52.650505) (xy 310.894269 -52.664611)
			(xy 310.838832 -52.670711) (xy 310.783098 -52.668674) (xy 310.728255 -52.658544) (xy 310.675471 -52.640537)
			(xy 310.625871 -52.615036) (xy 310.580513 -52.582585) (xy 310.540364 -52.543876) (xy 310.506278 -52.499733)
			(xy 310.478982 -52.451098) (xy 310.459059 -52.399007) (xy 310.446933 -52.34457) (xy 310.442862 -52.288948)
			(xy 309.076903 -52.288948) (xy 309.062973 -52.305021) (xy 309.021784 -52.340706) (xy 308.975936 -52.370165)
			(xy 308.926362 -52.392801) (xy 308.874071 -52.408151) (xy 308.820129 -52.415903) (xy 308.79288 -52.416456)
			(xy 308.765504 -52.415982) (xy 308.711314 -52.408149) (xy 308.658802 -52.392646) (xy 308.609047 -52.369794)
			(xy 308.563072 -52.34006) (xy 308.521821 -52.304057) (xy 308.486143 -52.262525) (xy 308.471062 -52.239672)
			(xy 308.46243 -52.227195) (xy 308.439326 -52.207554) (xy 308.411477 -52.195556) (xy 308.381333 -52.192255)
			(xy 308.351547 -52.197942) (xy 308.32474 -52.212117) (xy 308.313582 -52.2224) (xy 307.055774 -53.480208)
			(xy 310.305702 -53.480208) (xy 310.309773 -53.424586) (xy 310.321899 -53.370149) (xy 310.341822 -53.318058)
			(xy 310.369118 -53.269423) (xy 310.403204 -53.22528) (xy 310.443353 -53.186571) (xy 310.488711 -53.15412)
			(xy 310.538311 -53.128619) (xy 310.591095 -53.110612) (xy 310.645938 -53.100482) (xy 310.701672 -53.098445)
			(xy 310.757109 -53.104545) (xy 310.811066 -53.118651) (xy 310.862395 -53.140463) (xy 310.910001 -53.169517)
			(xy 310.952869 -53.205192) (xy 310.990086 -53.246729) (xy 311.020859 -53.293242) (xy 311.026347 -53.304948)
			(xy 312.474862 -53.304948) (xy 312.478933 -53.249326) (xy 312.491059 -53.194889) (xy 312.510982 -53.142798)
			(xy 312.538278 -53.094163) (xy 312.572364 -53.05002) (xy 312.612513 -53.011311) (xy 312.657871 -52.97886)
			(xy 312.707471 -52.953359) (xy 312.760255 -52.935352) (xy 312.815098 -52.925222) (xy 312.870832 -52.923185)
			(xy 312.926269 -52.929285) (xy 312.980226 -52.943391) (xy 313.031555 -52.965203) (xy 313.079161 -52.994257)
			(xy 313.122029 -53.029932) (xy 313.159246 -53.071469) (xy 313.190019 -53.117982) (xy 313.213691 -53.168479)
			(xy 313.229759 -53.221886) (xy 313.230769 -53.228748) (xy 313.712604 -53.228748) (xy 313.716675 -53.173126)
			(xy 313.728801 -53.118689) (xy 313.748724 -53.066598) (xy 313.77602 -53.017963) (xy 313.810106 -52.97382)
			(xy 313.850255 -52.935111) (xy 313.895613 -52.90266) (xy 313.945213 -52.877159) (xy 313.997997 -52.859152)
			(xy 314.05284 -52.849022) (xy 314.108574 -52.846985) (xy 314.164011 -52.853085) (xy 314.217968 -52.867191)
			(xy 314.269297 -52.889003) (xy 314.316903 -52.918057) (xy 314.359771 -52.953732) (xy 314.396988 -52.995269)
			(xy 314.427761 -53.041782) (xy 314.451433 -53.092279) (xy 314.467501 -53.145686) (xy 314.475621 -53.200862)
			(xy 314.47613 -53.228748) (xy 314.476102 -53.230272) (xy 318.543684 -53.230272) (xy 318.547755 -53.17465)
			(xy 318.559881 -53.120213) (xy 318.579804 -53.068122) (xy 318.6071 -53.019487) (xy 318.641186 -52.975344)
			(xy 318.681335 -52.936635) (xy 318.726693 -52.904184) (xy 318.776293 -52.878683) (xy 318.829077 -52.860676)
			(xy 318.88392 -52.850546) (xy 318.939654 -52.848509) (xy 318.995091 -52.854609) (xy 319.049048 -52.868715)
			(xy 319.100377 -52.890527) (xy 319.147983 -52.919581) (xy 319.190851 -52.955256) (xy 319.228068 -52.996793)
			(xy 319.258841 -53.043306) (xy 319.282513 -53.093803) (xy 319.298581 -53.14721) (xy 319.306701 -53.202386)
			(xy 319.30721 -53.230272) (xy 319.306701 -53.258158) (xy 319.301834 -53.291232) (xy 319.582544 -53.291232)
			(xy 319.586615 -53.23561) (xy 319.598741 -53.181173) (xy 319.618664 -53.129082) (xy 319.64596 -53.080447)
			(xy 319.680046 -53.036304) (xy 319.720195 -52.997595) (xy 319.765553 -52.965144) (xy 319.815153 -52.939643)
			(xy 319.867937 -52.921636) (xy 319.92278 -52.911506) (xy 319.978514 -52.909469) (xy 320.033951 -52.915569)
			(xy 320.087908 -52.929675) (xy 320.139237 -52.951487) (xy 320.172116 -52.971553) (xy 320.981546 -52.971553)
			(xy 320.981546 -52.917047) (xy 320.989302 -52.863097) (xy 321.004658 -52.8108) (xy 321.027299 -52.76122)
			(xy 321.056766 -52.715367) (xy 321.092458 -52.674174) (xy 321.133649 -52.638479) (xy 321.179501 -52.60901)
			(xy 321.229079 -52.586365) (xy 321.281376 -52.571007) (xy 321.335325 -52.563247) (xy 321.362578 -52.56276)
			(xy 321.389817 -52.563238) (xy 321.44374 -52.571004) (xy 321.496008 -52.586367) (xy 321.545557 -52.609013)
			(xy 321.591377 -52.638482) (xy 321.61226 -52.655978) (xy 321.624074 -52.665373) (xy 321.651661 -52.677572)
			(xy 321.681606 -52.681197) (xy 321.711307 -52.675936) (xy 321.738184 -52.662244) (xy 321.74942 -52.652168)
			(xy 321.770884 -52.632219) (xy 321.818785 -52.598471) (xy 321.871281 -52.57244) (xy 321.927138 -52.554735)
			(xy 321.985044 -52.545773) (xy 322.014342 -52.545234) (xy 322.041594 -52.545639) (xy 322.095543 -52.553401)
			(xy 322.147839 -52.568761) (xy 322.197416 -52.591407) (xy 322.243266 -52.620878) (xy 322.284456 -52.656574)
			(xy 322.320147 -52.697767) (xy 322.349613 -52.743621) (xy 322.372253 -52.793201) (xy 322.387608 -52.845498)
			(xy 322.395364 -52.899448) (xy 322.395364 -52.953952) (xy 322.387608 -53.007902) (xy 322.372253 -53.060199)
			(xy 322.349613 -53.109779) (xy 322.320147 -53.155633) (xy 322.284456 -53.196826) (xy 322.243266 -53.232522)
			(xy 322.235307 -53.237638) (xy 323.65264 -53.237638) (xy 323.656711 -53.182016) (xy 323.668837 -53.127579)
			(xy 323.68876 -53.075488) (xy 323.716056 -53.026853) (xy 323.750142 -52.98271) (xy 323.790291 -52.944001)
			(xy 323.835649 -52.91155) (xy 323.885249 -52.886049) (xy 323.938033 -52.868042) (xy 323.992876 -52.857912)
			(xy 324.04861 -52.855875) (xy 324.104047 -52.861975) (xy 324.158004 -52.876081) (xy 324.209333 -52.897893)
			(xy 324.256939 -52.926947) (xy 324.299807 -52.962622) (xy 324.337024 -53.004159) (xy 324.367797 -53.050672)
			(xy 324.391469 -53.101169) (xy 324.407537 -53.154576) (xy 324.410577 -53.175233) (xy 329.107548 -53.175233)
			(xy 329.107548 -53.123259) (xy 329.115678 -53.071924) (xy 329.131739 -53.022494) (xy 329.155335 -52.976184)
			(xy 329.185885 -52.934136) (xy 329.222636 -52.897385) (xy 329.264684 -52.866835) (xy 329.310994 -52.843239)
			(xy 329.360424 -52.827178) (xy 329.411759 -52.819048) (xy 329.463733 -52.819048) (xy 329.515068 -52.827178)
			(xy 329.564498 -52.843239) (xy 329.610808 -52.866835) (xy 329.652856 -52.897385) (xy 329.689607 -52.934136)
			(xy 329.720157 -52.976184) (xy 329.743753 -53.022494) (xy 329.759814 -53.071924) (xy 329.767944 -53.123259)
			(xy 329.768454 -53.149246) (xy 329.767944 -53.175233) (xy 330.73899 -53.175233) (xy 330.73899 -53.123259)
			(xy 330.74712 -53.071924) (xy 330.763181 -53.022494) (xy 330.786777 -52.976184) (xy 330.817327 -52.934136)
			(xy 330.854078 -52.897385) (xy 330.896126 -52.866835) (xy 330.942436 -52.843239) (xy 330.991866 -52.827178)
			(xy 331.043201 -52.819048) (xy 331.095175 -52.819048) (xy 331.14651 -52.827178) (xy 331.19594 -52.843239)
			(xy 331.24225 -52.866835) (xy 331.284298 -52.897385) (xy 331.321049 -52.934136) (xy 331.351599 -52.976184)
			(xy 331.375195 -53.022494) (xy 331.391256 -53.071924) (xy 331.399386 -53.123259) (xy 331.399896 -53.149246)
			(xy 331.399386 -53.175233) (xy 332.36713 -53.175233) (xy 332.36713 -53.123259) (xy 332.37526 -53.071924)
			(xy 332.391321 -53.022494) (xy 332.414917 -52.976184) (xy 332.445467 -52.934136) (xy 332.482218 -52.897385)
			(xy 332.524266 -52.866835) (xy 332.570576 -52.843239) (xy 332.620006 -52.827178) (xy 332.671341 -52.819048)
			(xy 332.723315 -52.819048) (xy 332.77465 -52.827178) (xy 332.82408 -52.843239) (xy 332.87039 -52.866835)
			(xy 332.912438 -52.897385) (xy 332.949189 -52.934136) (xy 332.979739 -52.976184) (xy 333.003335 -53.022494)
			(xy 333.019396 -53.071924) (xy 333.027526 -53.123259) (xy 333.028036 -53.149246) (xy 333.027526 -53.175233)
			(xy 333.019396 -53.226568) (xy 333.003335 -53.275998) (xy 332.979739 -53.322308) (xy 332.949189 -53.364356)
			(xy 332.912438 -53.401107) (xy 332.87039 -53.431657) (xy 332.82408 -53.455253) (xy 332.77465 -53.471314)
			(xy 332.723315 -53.479444) (xy 332.671341 -53.479444) (xy 332.620006 -53.471314) (xy 332.570576 -53.455253)
			(xy 332.524266 -53.431657) (xy 332.482218 -53.401107) (xy 332.445467 -53.364356) (xy 332.414917 -53.322308)
			(xy 332.391321 -53.275998) (xy 332.37526 -53.226568) (xy 332.36713 -53.175233) (xy 331.399386 -53.175233)
			(xy 331.391256 -53.226568) (xy 331.375195 -53.275998) (xy 331.351599 -53.322308) (xy 331.321049 -53.364356)
			(xy 331.284298 -53.401107) (xy 331.24225 -53.431657) (xy 331.19594 -53.455253) (xy 331.14651 -53.471314)
			(xy 331.095175 -53.479444) (xy 331.043201 -53.479444) (xy 330.991866 -53.471314) (xy 330.942436 -53.455253)
			(xy 330.896126 -53.431657) (xy 330.854078 -53.401107) (xy 330.817327 -53.364356) (xy 330.786777 -53.322308)
			(xy 330.763181 -53.275998) (xy 330.74712 -53.226568) (xy 330.73899 -53.175233) (xy 329.767944 -53.175233)
			(xy 329.759814 -53.226568) (xy 329.743753 -53.275998) (xy 329.720157 -53.322308) (xy 329.689607 -53.364356)
			(xy 329.652856 -53.401107) (xy 329.610808 -53.431657) (xy 329.564498 -53.455253) (xy 329.515068 -53.471314)
			(xy 329.463733 -53.479444) (xy 329.411759 -53.479444) (xy 329.360424 -53.471314) (xy 329.310994 -53.455253)
			(xy 329.264684 -53.431657) (xy 329.222636 -53.401107) (xy 329.185885 -53.364356) (xy 329.155335 -53.322308)
			(xy 329.131739 -53.275998) (xy 329.115678 -53.226568) (xy 329.107548 -53.175233) (xy 324.410577 -53.175233)
			(xy 324.415657 -53.209752) (xy 324.416166 -53.237638) (xy 324.415657 -53.265524) (xy 324.407537 -53.3207)
			(xy 324.391469 -53.374107) (xy 324.367797 -53.424604) (xy 324.337024 -53.471117) (xy 324.299807 -53.512654)
			(xy 324.256939 -53.548329) (xy 324.209333 -53.577383) (xy 324.158004 -53.599195) (xy 324.104047 -53.613301)
			(xy 324.04861 -53.619401) (xy 323.992876 -53.617364) (xy 323.938033 -53.607234) (xy 323.885249 -53.589227)
			(xy 323.835649 -53.563726) (xy 323.790291 -53.531275) (xy 323.750142 -53.492566) (xy 323.716056 -53.448423)
			(xy 323.68876 -53.399788) (xy 323.668837 -53.347697) (xy 323.656711 -53.29326) (xy 323.65264 -53.237638)
			(xy 322.235307 -53.237638) (xy 322.197416 -53.261993) (xy 322.147839 -53.284639) (xy 322.095543 -53.299999)
			(xy 322.041594 -53.307761) (xy 322.014342 -53.30825) (xy 321.987103 -53.307758) (xy 321.933181 -53.299995)
			(xy 321.880914 -53.284635) (xy 321.831365 -53.261992) (xy 321.785543 -53.232526) (xy 321.76466 -53.215032)
			(xy 321.752906 -53.205556) (xy 321.725297 -53.193366) (xy 321.695333 -53.189755) (xy 321.665619 -53.195038)
			(xy 321.638735 -53.208754) (xy 321.6275 -53.218842) (xy 321.60603 -53.238784) (xy 321.55813 -53.272532)
			(xy 321.505636 -53.298565) (xy 321.44978 -53.316272) (xy 321.391875 -53.325236) (xy 321.362578 -53.325776)
			(xy 321.335325 -53.325353) (xy 321.281376 -53.317593) (xy 321.229079 -53.302235) (xy 321.179501 -53.27959)
			(xy 321.133649 -53.250121) (xy 321.092458 -53.214426) (xy 321.056766 -53.173233) (xy 321.027299 -53.12738)
			(xy 321.004658 -53.0778) (xy 320.989302 -53.025503) (xy 320.981546 -52.971553) (xy 320.172116 -52.971553)
			(xy 320.186843 -52.980541) (xy 320.229711 -53.016216) (xy 320.266928 -53.057753) (xy 320.297701 -53.104266)
			(xy 320.321373 -53.154763) (xy 320.337441 -53.20817) (xy 320.345561 -53.263346) (xy 320.34607 -53.291232)
			(xy 320.345561 -53.319118) (xy 320.337441 -53.374294) (xy 320.321373 -53.427701) (xy 320.297701 -53.478198)
			(xy 320.266928 -53.524711) (xy 320.229711 -53.566248) (xy 320.186843 -53.601923) (xy 320.139237 -53.630977)
			(xy 320.105924 -53.645133) (xy 328.296272 -53.645133) (xy 328.296272 -53.593159) (xy 328.304402 -53.541824)
			(xy 328.320463 -53.492394) (xy 328.344059 -53.446084) (xy 328.374609 -53.404036) (xy 328.41136 -53.367285)
			(xy 328.453408 -53.336735) (xy 328.499718 -53.313139) (xy 328.549148 -53.297078) (xy 328.600483 -53.288948)
			(xy 328.652457 -53.288948) (xy 328.703792 -53.297078) (xy 328.753222 -53.313139) (xy 328.799532 -53.336735)
			(xy 328.84158 -53.367285) (xy 328.878331 -53.404036) (xy 328.908881 -53.446084) (xy 328.932477 -53.492394)
			(xy 328.948538 -53.541824) (xy 328.956668 -53.593159) (xy 328.957178 -53.619146) (xy 328.956668 -53.645133)
			(xy 329.92238 -53.645133) (xy 329.92238 -53.593159) (xy 329.93051 -53.541824) (xy 329.946571 -53.492394)
			(xy 329.970167 -53.446084) (xy 330.000717 -53.404036) (xy 330.037468 -53.367285) (xy 330.079516 -53.336735)
			(xy 330.125826 -53.313139) (xy 330.175256 -53.297078) (xy 330.226591 -53.288948) (xy 330.278565 -53.288948)
			(xy 330.3299 -53.297078) (xy 330.37933 -53.313139) (xy 330.42564 -53.336735) (xy 330.467688 -53.367285)
			(xy 330.504439 -53.404036) (xy 330.534989 -53.446084) (xy 330.558585 -53.492394) (xy 330.574646 -53.541824)
			(xy 330.582776 -53.593159) (xy 330.583286 -53.619146) (xy 330.582776 -53.645133) (xy 330.574646 -53.696468)
			(xy 330.558585 -53.745898) (xy 330.534989 -53.792208) (xy 330.504439 -53.834256) (xy 330.467688 -53.871007)
			(xy 330.42564 -53.901557) (xy 330.37933 -53.925153) (xy 330.3299 -53.941214) (xy 330.278565 -53.949344)
			(xy 330.226591 -53.949344) (xy 330.175256 -53.941214) (xy 330.125826 -53.925153) (xy 330.079516 -53.901557)
			(xy 330.037468 -53.871007) (xy 330.000717 -53.834256) (xy 329.970167 -53.792208) (xy 329.946571 -53.745898)
			(xy 329.93051 -53.696468) (xy 329.92238 -53.645133) (xy 328.956668 -53.645133) (xy 328.948538 -53.696468)
			(xy 328.932477 -53.745898) (xy 328.908881 -53.792208) (xy 328.878331 -53.834256) (xy 328.84158 -53.871007)
			(xy 328.799532 -53.901557) (xy 328.753222 -53.925153) (xy 328.703792 -53.941214) (xy 328.652457 -53.949344)
			(xy 328.600483 -53.949344) (xy 328.549148 -53.941214) (xy 328.499718 -53.925153) (xy 328.453408 -53.901557)
			(xy 328.41136 -53.871007) (xy 328.374609 -53.834256) (xy 328.344059 -53.792208) (xy 328.320463 -53.745898)
			(xy 328.304402 -53.696468) (xy 328.296272 -53.645133) (xy 320.105924 -53.645133) (xy 320.087908 -53.652789)
			(xy 320.033951 -53.666895) (xy 319.978514 -53.672995) (xy 319.92278 -53.670958) (xy 319.867937 -53.660828)
			(xy 319.815153 -53.642821) (xy 319.765553 -53.61732) (xy 319.720195 -53.584869) (xy 319.680046 -53.54616)
			(xy 319.64596 -53.502017) (xy 319.618664 -53.453382) (xy 319.598741 -53.401291) (xy 319.586615 -53.346854)
			(xy 319.582544 -53.291232) (xy 319.301834 -53.291232) (xy 319.298581 -53.313334) (xy 319.282513 -53.366741)
			(xy 319.258841 -53.417238) (xy 319.228068 -53.463751) (xy 319.190851 -53.505288) (xy 319.147983 -53.540963)
			(xy 319.100377 -53.570017) (xy 319.049048 -53.591829) (xy 318.995091 -53.605935) (xy 318.939654 -53.612035)
			(xy 318.88392 -53.609998) (xy 318.829077 -53.599868) (xy 318.776293 -53.581861) (xy 318.726693 -53.55636)
			(xy 318.681335 -53.523909) (xy 318.641186 -53.4852) (xy 318.6071 -53.441057) (xy 318.579804 -53.392422)
			(xy 318.559881 -53.340331) (xy 318.547755 -53.285894) (xy 318.543684 -53.230272) (xy 314.476102 -53.230272)
			(xy 314.475621 -53.256634) (xy 314.467501 -53.31181) (xy 314.451433 -53.365217) (xy 314.427761 -53.415714)
			(xy 314.396988 -53.462227) (xy 314.359771 -53.503764) (xy 314.316903 -53.539439) (xy 314.269297 -53.568493)
			(xy 314.217968 -53.590305) (xy 314.164011 -53.604411) (xy 314.108574 -53.610511) (xy 314.05284 -53.608474)
			(xy 313.997997 -53.598344) (xy 313.945213 -53.580337) (xy 313.895613 -53.554836) (xy 313.850255 -53.522385)
			(xy 313.810106 -53.483676) (xy 313.77602 -53.439533) (xy 313.748724 -53.390898) (xy 313.728801 -53.338807)
			(xy 313.716675 -53.28437) (xy 313.712604 -53.228748) (xy 313.230769 -53.228748) (xy 313.237879 -53.277062)
			(xy 313.238388 -53.304948) (xy 313.237879 -53.332834) (xy 313.229759 -53.38801) (xy 313.213691 -53.441417)
			(xy 313.190019 -53.491914) (xy 313.159246 -53.538427) (xy 313.122029 -53.579964) (xy 313.079161 -53.615639)
			(xy 313.031555 -53.644693) (xy 312.980226 -53.666505) (xy 312.926269 -53.680611) (xy 312.870832 -53.686711)
			(xy 312.815098 -53.684674) (xy 312.760255 -53.674544) (xy 312.707471 -53.656537) (xy 312.657871 -53.631036)
			(xy 312.612513 -53.598585) (xy 312.572364 -53.559876) (xy 312.538278 -53.515733) (xy 312.510982 -53.467098)
			(xy 312.491059 -53.415007) (xy 312.478933 -53.36057) (xy 312.474862 -53.304948) (xy 311.026347 -53.304948)
			(xy 311.044531 -53.343739) (xy 311.060599 -53.397146) (xy 311.068719 -53.452322) (xy 311.069228 -53.480208)
			(xy 311.068719 -53.508094) (xy 311.060599 -53.56327) (xy 311.044531 -53.616677) (xy 311.020859 -53.667174)
			(xy 310.990086 -53.713687) (xy 310.952869 -53.755224) (xy 310.910001 -53.790899) (xy 310.862395 -53.819953)
			(xy 310.811066 -53.841765) (xy 310.757109 -53.855871) (xy 310.701672 -53.861971) (xy 310.645938 -53.859934)
			(xy 310.591095 -53.849804) (xy 310.538311 -53.831797) (xy 310.488711 -53.806296) (xy 310.443353 -53.773845)
			(xy 310.403204 -53.735136) (xy 310.369118 -53.690993) (xy 310.341822 -53.642358) (xy 310.321899 -53.590267)
			(xy 310.309773 -53.53583) (xy 310.305702 -53.480208) (xy 307.055774 -53.480208) (xy 306.354734 -54.181248)
			(xy 309.259222 -54.181248) (xy 309.263293 -54.125626) (xy 309.275419 -54.071189) (xy 309.295342 -54.019098)
			(xy 309.322638 -53.970463) (xy 309.356724 -53.92632) (xy 309.396873 -53.887611) (xy 309.442231 -53.85516)
			(xy 309.491831 -53.829659) (xy 309.544615 -53.811652) (xy 309.599458 -53.801522) (xy 309.655192 -53.799485)
			(xy 309.710629 -53.805585) (xy 309.764586 -53.819691) (xy 309.815915 -53.841503) (xy 309.863521 -53.870557)
			(xy 309.906389 -53.906232) (xy 309.943606 -53.947769) (xy 309.974379 -53.994282) (xy 309.998051 -54.044779)
			(xy 310.014119 -54.098186) (xy 310.022239 -54.153362) (xy 310.022748 -54.181248) (xy 310.022239 -54.209134)
			(xy 310.014119 -54.26431) (xy 309.998051 -54.317717) (xy 309.974379 -54.368214) (xy 309.943606 -54.414727)
			(xy 309.906389 -54.456264) (xy 309.863521 -54.491939) (xy 309.815915 -54.520993) (xy 309.79812 -54.528555)
			(xy 312.999043 -54.528555) (xy 312.999043 -54.474045) (xy 313.006801 -54.420091) (xy 313.022158 -54.36779)
			(xy 313.044803 -54.318207) (xy 313.074274 -54.272351) (xy 313.109971 -54.231157) (xy 313.151167 -54.195462)
			(xy 313.197024 -54.165993) (xy 313.246609 -54.143351) (xy 313.29891 -54.127996) (xy 313.352865 -54.120242)
			(xy 313.38012 -54.11978) (xy 313.412271 -54.120429) (xy 313.475661 -54.131231) (xy 313.536335 -54.152526)
			(xy 313.564778 -54.167532) (xy 313.578231 -54.17444) (xy 313.60781 -54.180693) (xy 313.637922 -54.178008)
			(xy 313.665927 -54.16662) (xy 313.689369 -54.147529) (xy 313.70619 -54.122409) (xy 313.711082 -54.108096)
			(xy 313.719404 -54.082369) (xy 313.74233 -54.033397) (xy 313.771938 -53.988152) (xy 313.807635 -53.947538)
			(xy 313.848708 -53.912369) (xy 313.894333 -53.883349) (xy 313.943597 -53.86106) (xy 313.995514 -53.845946)
			(xy 314.049044 -53.838311) (xy 314.07608 -53.83784) (xy 314.103337 -53.838206) (xy 314.157297 -53.845961)
			(xy 314.209604 -53.861317) (xy 314.259193 -53.883962) (xy 314.305054 -53.913433) (xy 314.346255 -53.949131)
			(xy 314.381955 -53.99033) (xy 314.411429 -54.036189) (xy 314.434076 -54.085777) (xy 314.449435 -54.138083)
			(xy 314.457193 -54.192043) (xy 314.457193 -54.246557) (xy 314.449435 -54.300517) (xy 314.434076 -54.352823)
			(xy 314.411429 -54.402411) (xy 314.381955 -54.44827) (xy 314.346255 -54.489469) (xy 314.305054 -54.525167)
			(xy 314.259193 -54.554638) (xy 314.209604 -54.577283) (xy 314.157297 -54.592639) (xy 314.103337 -54.600394)
			(xy 314.07608 -54.600856) (xy 314.043929 -54.600203) (xy 313.98054 -54.589401) (xy 313.919865 -54.568109)
			(xy 313.891422 -54.553104) (xy 313.877953 -54.546234) (xy 313.848383 -54.539988) (xy 313.818281 -54.542672)
			(xy 313.790283 -54.554052) (xy 313.766843 -54.57313) (xy 313.750016 -54.598234) (xy 313.745118 -54.61254)
			(xy 313.736818 -54.638274) (xy 313.713888 -54.687245) (xy 313.684276 -54.73249) (xy 313.648575 -54.773102)
			(xy 313.6075 -54.80827) (xy 313.561873 -54.837289) (xy 313.512607 -54.859578) (xy 313.460688 -54.87469)
			(xy 313.407157 -54.882325) (xy 313.38012 -54.882796) (xy 313.352865 -54.882358) (xy 313.29891 -54.874604)
			(xy 313.246609 -54.859249) (xy 313.197024 -54.836607) (xy 313.151167 -54.807138) (xy 313.109971 -54.771443)
			(xy 313.074274 -54.730249) (xy 313.044803 -54.684393) (xy 313.022158 -54.63481) (xy 313.006801 -54.582509)
			(xy 312.999043 -54.528555) (xy 309.79812 -54.528555) (xy 309.764586 -54.542805) (xy 309.710629 -54.556911)
			(xy 309.655192 -54.563011) (xy 309.599458 -54.560974) (xy 309.544615 -54.550844) (xy 309.491831 -54.532837)
			(xy 309.442231 -54.507336) (xy 309.396873 -54.474885) (xy 309.356724 -54.436176) (xy 309.322638 -54.392033)
			(xy 309.295342 -54.343398) (xy 309.275419 -54.291307) (xy 309.263293 -54.23687) (xy 309.259222 -54.181248)
			(xy 306.354734 -54.181248) (xy 305.550824 -54.985158) (xy 305.53516 -55.00029) (xy 305.500453 -55.026603)
			(xy 305.462491 -55.047952) (xy 305.442366 -55.056278) (xy 305.43246 -55.060088) (xy 305.1556 -55.336948)
			(xy 310.442862 -55.336948) (xy 310.446933 -55.281326) (xy 310.459059 -55.226889) (xy 310.478982 -55.174798)
			(xy 310.506278 -55.126163) (xy 310.540364 -55.08202) (xy 310.580513 -55.043311) (xy 310.625871 -55.01086)
			(xy 310.675471 -54.985359) (xy 310.728255 -54.967352) (xy 310.783098 -54.957222) (xy 310.838832 -54.955185)
			(xy 310.894269 -54.961285) (xy 310.948226 -54.975391) (xy 310.999555 -54.997203) (xy 311.047161 -55.026257)
			(xy 311.090029 -55.061932) (xy 311.127246 -55.103469) (xy 311.158019 -55.149982) (xy 311.181691 -55.200479)
			(xy 311.197759 -55.253886) (xy 311.205879 -55.309062) (xy 311.206388 -55.336948) (xy 312.474862 -55.336948)
			(xy 312.478933 -55.281326) (xy 312.491059 -55.226889) (xy 312.510982 -55.174798) (xy 312.538278 -55.126163)
			(xy 312.572364 -55.08202) (xy 312.612513 -55.043311) (xy 312.657871 -55.01086) (xy 312.707471 -54.985359)
			(xy 312.760255 -54.967352) (xy 312.815098 -54.957222) (xy 312.870832 -54.955185) (xy 312.926269 -54.961285)
			(xy 312.980226 -54.975391) (xy 313.031555 -54.997203) (xy 313.079161 -55.026257) (xy 313.122029 -55.061932)
			(xy 313.159246 -55.103469) (xy 313.190019 -55.149982) (xy 313.213691 -55.200479) (xy 313.224182 -55.235348)
			(xy 313.710318 -55.235348) (xy 313.714389 -55.179726) (xy 313.726515 -55.125289) (xy 313.746438 -55.073198)
			(xy 313.773734 -55.024563) (xy 313.80782 -54.98042) (xy 313.847969 -54.941711) (xy 313.893327 -54.90926)
			(xy 313.942927 -54.883759) (xy 313.995711 -54.865752) (xy 314.050554 -54.855622) (xy 314.106288 -54.853585)
			(xy 314.161725 -54.859685) (xy 314.215682 -54.873791) (xy 314.267011 -54.895603) (xy 314.314617 -54.924657)
			(xy 314.357485 -54.960332) (xy 314.394702 -55.001869) (xy 314.425475 -55.048382) (xy 314.449147 -55.098879)
			(xy 314.465215 -55.152286) (xy 314.473335 -55.207462) (xy 314.473844 -55.235348) (xy 314.473335 -55.263234)
			(xy 314.465215 -55.31841) (xy 314.449147 -55.371817) (xy 314.425475 -55.422314) (xy 314.394702 -55.468827)
			(xy 314.357485 -55.510364) (xy 314.314617 -55.546039) (xy 314.267011 -55.575093) (xy 314.215682 -55.596905)
			(xy 314.161725 -55.611011) (xy 314.106288 -55.617111) (xy 314.050554 -55.615074) (xy 313.995711 -55.604944)
			(xy 313.942927 -55.586937) (xy 313.893327 -55.561436) (xy 313.847969 -55.528985) (xy 313.80782 -55.490276)
			(xy 313.773734 -55.446133) (xy 313.746438 -55.397498) (xy 313.726515 -55.345407) (xy 313.714389 -55.29097)
			(xy 313.710318 -55.235348) (xy 313.224182 -55.235348) (xy 313.229759 -55.253886) (xy 313.237879 -55.309062)
			(xy 313.238388 -55.336948) (xy 313.237879 -55.364834) (xy 313.229759 -55.42001) (xy 313.213691 -55.473417)
			(xy 313.190019 -55.523914) (xy 313.159246 -55.570427) (xy 313.122029 -55.611964) (xy 313.079161 -55.647639)
			(xy 313.031555 -55.676693) (xy 312.980226 -55.698505) (xy 312.926269 -55.712611) (xy 312.870832 -55.718711)
			(xy 312.815098 -55.716674) (xy 312.760255 -55.706544) (xy 312.707471 -55.688537) (xy 312.657871 -55.663036)
			(xy 312.612513 -55.630585) (xy 312.572364 -55.591876) (xy 312.538278 -55.547733) (xy 312.510982 -55.499098)
			(xy 312.491059 -55.447007) (xy 312.478933 -55.39257) (xy 312.474862 -55.336948) (xy 311.206388 -55.336948)
			(xy 311.205879 -55.364834) (xy 311.197759 -55.42001) (xy 311.181691 -55.473417) (xy 311.158019 -55.523914)
			(xy 311.127246 -55.570427) (xy 311.090029 -55.611964) (xy 311.047161 -55.647639) (xy 310.999555 -55.676693)
			(xy 310.948226 -55.698505) (xy 310.894269 -55.712611) (xy 310.838832 -55.718711) (xy 310.783098 -55.716674)
			(xy 310.728255 -55.706544) (xy 310.675471 -55.688537) (xy 310.625871 -55.663036) (xy 310.580513 -55.630585)
			(xy 310.540364 -55.591876) (xy 310.506278 -55.547733) (xy 310.478982 -55.499098) (xy 310.459059 -55.447007)
			(xy 310.446933 -55.39257) (xy 310.442862 -55.336948) (xy 305.1556 -55.336948) (xy 304.188601 -56.303947)
			(xy 313.720526 -56.303947) (xy 313.720526 -56.249453) (xy 313.728281 -56.195514) (xy 313.743633 -56.143227)
			(xy 313.76627 -56.093658) (xy 313.795731 -56.047814) (xy 313.831416 -56.00663) (xy 313.872598 -55.970943)
			(xy 313.91844 -55.94148) (xy 313.968009 -55.91884) (xy 314.020294 -55.903485) (xy 314.074233 -55.895728)
			(xy 314.10148 -55.89524) (xy 314.128508 -55.895727) (xy 314.182022 -55.903366) (xy 314.233919 -55.918493)
			(xy 314.283156 -55.940804) (xy 314.306204 -55.95493) (xy 314.314233 -55.959532) (xy 314.332358 -55.963198)
			(xy 314.350606 -55.9602) (xy 314.366606 -55.950927) (xy 314.372752 -55.944008) (xy 314.379945 -55.935428)
			(xy 314.395064 -55.918908) (xy 314.402978 -55.910988) (xy 315.830966 -54.483) (xy 315.851852 -54.46269)
			(xy 315.898035 -54.427177) (xy 315.948462 -54.398001) (xy 316.002269 -54.375664) (xy 316.058532 -54.360548)
			(xy 316.116289 -54.352913) (xy 316.145418 -54.352444) (xy 317.80353 -54.352444) (xy 318.171322 -53.984906)
			(xy 318.192221 -53.964623) (xy 318.238421 -53.929164) (xy 318.288855 -53.900038) (xy 318.342659 -53.877746)
			(xy 318.398913 -53.862667) (xy 318.456654 -53.855062) (xy 318.485774 -53.854604) (xy 322.231258 -53.854604)
			(xy 322.260379 -53.855034) (xy 322.318123 -53.862637) (xy 322.374379 -53.877717) (xy 322.428183 -53.900016)
			(xy 322.478613 -53.929152) (xy 322.524806 -53.964627) (xy 322.54571 -53.984906) (xy 322.833238 -54.27218)
			(xy 322.844123 -54.282359) (xy 322.870386 -54.296419) (xy 322.899588 -54.302312) (xy 322.929249 -54.299539)
			(xy 322.956852 -54.288334) (xy 322.980054 -54.269649) (xy 322.996886 -54.245069) (xy 323.001894 -54.231032)
			(xy 323.010462 -54.205636) (xy 323.033662 -54.157323) (xy 323.063394 -54.112731) (xy 323.099072 -54.072737)
			(xy 323.139994 -54.038128) (xy 323.185355 -54.009584) (xy 323.234264 -53.987667) (xy 323.285758 -53.972808)
			(xy 323.338825 -53.965299) (xy 323.365622 -53.96484) (xy 323.392878 -53.965235) (xy 323.446834 -53.972996)
			(xy 323.499136 -53.988357) (xy 323.548719 -54.011006) (xy 323.58043 -54.031388) (xy 325.399156 -54.031388)
			(xy 325.403132 -53.977062) (xy 325.414975 -53.923893) (xy 325.434434 -53.873016) (xy 325.461094 -53.825514)
			(xy 325.494385 -53.7824) (xy 325.533599 -53.744593) (xy 325.577901 -53.712898) (xy 325.626344 -53.687992)
			(xy 325.677898 -53.670404) (xy 325.731464 -53.66051) (xy 325.785899 -53.65852) (xy 325.840044 -53.664478)
			(xy 325.892744 -53.678256) (xy 325.942877 -53.69956) (xy 325.989373 -53.727936) (xy 326.031243 -53.76278)
			(xy 326.067592 -53.803349) (xy 326.097648 -53.848778) (xy 326.120769 -53.898099) (xy 326.136462 -53.950261)
			(xy 326.144393 -54.004152) (xy 326.14489 -54.031388) (xy 326.144393 -54.058624) (xy 326.136462 -54.112515)
			(xy 326.135704 -54.115033) (xy 329.107548 -54.115033) (xy 329.107548 -54.063059) (xy 329.115678 -54.011724)
			(xy 329.131739 -53.962294) (xy 329.155335 -53.915984) (xy 329.185885 -53.873936) (xy 329.222636 -53.837185)
			(xy 329.264684 -53.806635) (xy 329.310994 -53.783039) (xy 329.360424 -53.766978) (xy 329.411759 -53.758848)
			(xy 329.463733 -53.758848) (xy 329.515068 -53.766978) (xy 329.564498 -53.783039) (xy 329.610808 -53.806635)
			(xy 329.652856 -53.837185) (xy 329.689607 -53.873936) (xy 329.720157 -53.915984) (xy 329.743753 -53.962294)
			(xy 329.759814 -54.011724) (xy 329.767944 -54.063059) (xy 329.768454 -54.089046) (xy 329.767944 -54.115033)
			(xy 330.73772 -54.115033) (xy 330.73772 -54.063059) (xy 330.74585 -54.011724) (xy 330.761911 -53.962294)
			(xy 330.785507 -53.915984) (xy 330.816057 -53.873936) (xy 330.852808 -53.837185) (xy 330.894856 -53.806635)
			(xy 330.941166 -53.783039) (xy 330.990596 -53.766978) (xy 331.041931 -53.758848) (xy 331.093905 -53.758848)
			(xy 331.14524 -53.766978) (xy 331.19467 -53.783039) (xy 331.24098 -53.806635) (xy 331.283028 -53.837185)
			(xy 331.319779 -53.873936) (xy 331.350329 -53.915984) (xy 331.373925 -53.962294) (xy 331.389986 -54.011724)
			(xy 331.398116 -54.063059) (xy 331.398626 -54.089046) (xy 331.398116 -54.115033) (xy 331.389986 -54.166368)
			(xy 331.373925 -54.215798) (xy 331.350329 -54.262108) (xy 331.319779 -54.304156) (xy 331.283028 -54.340907)
			(xy 331.24098 -54.371457) (xy 331.19467 -54.395053) (xy 331.14524 -54.411114) (xy 331.093905 -54.419244)
			(xy 331.041931 -54.419244) (xy 330.990596 -54.411114) (xy 330.941166 -54.395053) (xy 330.894856 -54.371457)
			(xy 330.852808 -54.340907) (xy 330.816057 -54.304156) (xy 330.785507 -54.262108) (xy 330.761911 -54.215798)
			(xy 330.74585 -54.166368) (xy 330.73772 -54.115033) (xy 329.767944 -54.115033) (xy 329.759814 -54.166368)
			(xy 329.743753 -54.215798) (xy 329.720157 -54.262108) (xy 329.689607 -54.304156) (xy 329.652856 -54.340907)
			(xy 329.610808 -54.371457) (xy 329.564498 -54.395053) (xy 329.515068 -54.411114) (xy 329.463733 -54.419244)
			(xy 329.411759 -54.419244) (xy 329.360424 -54.411114) (xy 329.310994 -54.395053) (xy 329.264684 -54.371457)
			(xy 329.222636 -54.340907) (xy 329.185885 -54.304156) (xy 329.155335 -54.262108) (xy 329.131739 -54.215798)
			(xy 329.115678 -54.166368) (xy 329.107548 -54.115033) (xy 326.135704 -54.115033) (xy 326.120769 -54.164677)
			(xy 326.097648 -54.213998) (xy 326.067592 -54.259427) (xy 326.031243 -54.299996) (xy 325.989373 -54.33484)
			(xy 325.942877 -54.363216) (xy 325.892744 -54.38452) (xy 325.840044 -54.398298) (xy 325.785899 -54.404256)
			(xy 325.731464 -54.402266) (xy 325.677898 -54.392372) (xy 325.626344 -54.374784) (xy 325.577901 -54.349878)
			(xy 325.533599 -54.318183) (xy 325.494385 -54.280376) (xy 325.461094 -54.237262) (xy 325.434434 -54.18976)
			(xy 325.414975 -54.138883) (xy 325.403132 -54.085714) (xy 325.399156 -54.031388) (xy 323.58043 -54.031388)
			(xy 323.594575 -54.04048) (xy 323.635768 -54.076181) (xy 323.671462 -54.117382) (xy 323.700928 -54.163242)
			(xy 323.723567 -54.21283) (xy 323.738919 -54.265135) (xy 323.74667 -54.319092) (xy 323.74713 -54.346348)
			(xy 323.746658 -54.373149) (xy 323.739174 -54.426224) (xy 323.724333 -54.47773) (xy 323.702427 -54.52665)
			(xy 323.673887 -54.572021) (xy 323.662968 -54.584933) (xy 328.29678 -54.584933) (xy 328.29678 -54.532959)
			(xy 328.30491 -54.481624) (xy 328.320971 -54.432194) (xy 328.344567 -54.385884) (xy 328.375117 -54.343836)
			(xy 328.411868 -54.307085) (xy 328.453916 -54.276535) (xy 328.500226 -54.252939) (xy 328.549656 -54.236878)
			(xy 328.600991 -54.228748) (xy 328.652965 -54.228748) (xy 328.7043 -54.236878) (xy 328.75373 -54.252939)
			(xy 328.80004 -54.276535) (xy 328.842088 -54.307085) (xy 328.878839 -54.343836) (xy 328.909389 -54.385884)
			(xy 328.932985 -54.432194) (xy 328.949046 -54.481624) (xy 328.957176 -54.532959) (xy 328.957686 -54.558946)
			(xy 328.957176 -54.584933) (xy 329.92238 -54.584933) (xy 329.92238 -54.532959) (xy 329.93051 -54.481624)
			(xy 329.946571 -54.432194) (xy 329.970167 -54.385884) (xy 330.000717 -54.343836) (xy 330.037468 -54.307085)
			(xy 330.079516 -54.276535) (xy 330.125826 -54.252939) (xy 330.175256 -54.236878) (xy 330.226591 -54.228748)
			(xy 330.278565 -54.228748) (xy 330.3299 -54.236878) (xy 330.37933 -54.252939) (xy 330.42564 -54.276535)
			(xy 330.467688 -54.307085) (xy 330.504439 -54.343836) (xy 330.534989 -54.385884) (xy 330.558585 -54.432194)
			(xy 330.574646 -54.481624) (xy 330.582776 -54.532959) (xy 330.583286 -54.558946) (xy 330.582776 -54.584933)
			(xy 331.55306 -54.584933) (xy 331.55306 -54.532959) (xy 331.56119 -54.481624) (xy 331.577251 -54.432194)
			(xy 331.600847 -54.385884) (xy 331.631397 -54.343836) (xy 331.668148 -54.307085) (xy 331.710196 -54.276535)
			(xy 331.756506 -54.252939) (xy 331.805936 -54.236878) (xy 331.857271 -54.228748) (xy 331.909245 -54.228748)
			(xy 331.96058 -54.236878) (xy 332.01001 -54.252939) (xy 332.05632 -54.276535) (xy 332.098368 -54.307085)
			(xy 332.135119 -54.343836) (xy 332.165669 -54.385884) (xy 332.189265 -54.432194) (xy 332.205326 -54.481624)
			(xy 332.213456 -54.532959) (xy 332.213966 -54.558946) (xy 332.213456 -54.584933) (xy 332.205326 -54.636268)
			(xy 332.189265 -54.685698) (xy 332.165669 -54.732008) (xy 332.135119 -54.774056) (xy 332.098368 -54.810807)
			(xy 332.05632 -54.841357) (xy 332.01001 -54.864953) (xy 331.96058 -54.881014) (xy 331.909245 -54.889144)
			(xy 331.857271 -54.889144) (xy 331.805936 -54.881014) (xy 331.756506 -54.864953) (xy 331.710196 -54.841357)
			(xy 331.668148 -54.810807) (xy 331.631397 -54.774056) (xy 331.600847 -54.732008) (xy 331.577251 -54.685698)
			(xy 331.56119 -54.636268) (xy 331.55306 -54.584933) (xy 330.582776 -54.584933) (xy 330.574646 -54.636268)
			(xy 330.558585 -54.685698) (xy 330.534989 -54.732008) (xy 330.504439 -54.774056) (xy 330.467688 -54.810807)
			(xy 330.42564 -54.841357) (xy 330.37933 -54.864953) (xy 330.3299 -54.881014) (xy 330.278565 -54.889144)
			(xy 330.226591 -54.889144) (xy 330.175256 -54.881014) (xy 330.125826 -54.864953) (xy 330.079516 -54.841357)
			(xy 330.037468 -54.810807) (xy 330.000717 -54.774056) (xy 329.970167 -54.732008) (xy 329.946571 -54.685698)
			(xy 329.93051 -54.636268) (xy 329.92238 -54.584933) (xy 328.957176 -54.584933) (xy 328.949046 -54.636268)
			(xy 328.932985 -54.685698) (xy 328.909389 -54.732008) (xy 328.878839 -54.774056) (xy 328.842088 -54.810807)
			(xy 328.80004 -54.841357) (xy 328.75373 -54.864953) (xy 328.7043 -54.881014) (xy 328.652965 -54.889144)
			(xy 328.600991 -54.889144) (xy 328.549656 -54.881014) (xy 328.500226 -54.864953) (xy 328.453916 -54.841357)
			(xy 328.411868 -54.810807) (xy 328.375117 -54.774056) (xy 328.344567 -54.732008) (xy 328.320971 -54.685698)
			(xy 328.30491 -54.636268) (xy 328.29678 -54.584933) (xy 323.662968 -54.584933) (xy 323.639276 -54.612949)
			(xy 323.599275 -54.648628) (xy 323.554673 -54.678356) (xy 323.506349 -54.701545) (xy 323.480938 -54.710076)
			(xy 323.466894 -54.71509) (xy 323.442274 -54.731889) (xy 323.423557 -54.755084) (xy 323.412339 -54.782697)
			(xy 323.409574 -54.812373) (xy 323.4155 -54.841582) (xy 323.429611 -54.867835) (xy 323.43979 -54.878732)
			(xy 323.615778 -55.054833) (xy 329.107548 -55.054833) (xy 329.107548 -55.002859) (xy 329.115678 -54.951524)
			(xy 329.131739 -54.902094) (xy 329.155335 -54.855784) (xy 329.185885 -54.813736) (xy 329.222636 -54.776985)
			(xy 329.264684 -54.746435) (xy 329.310994 -54.722839) (xy 329.360424 -54.706778) (xy 329.411759 -54.698648)
			(xy 329.463733 -54.698648) (xy 329.515068 -54.706778) (xy 329.564498 -54.722839) (xy 329.610808 -54.746435)
			(xy 329.652856 -54.776985) (xy 329.689607 -54.813736) (xy 329.720157 -54.855784) (xy 329.743753 -54.902094)
			(xy 329.759814 -54.951524) (xy 329.767944 -55.002859) (xy 329.768454 -55.028846) (xy 329.767944 -55.054833)
			(xy 330.73772 -55.054833) (xy 330.73772 -55.002859) (xy 330.74585 -54.951524) (xy 330.761911 -54.902094)
			(xy 330.785507 -54.855784) (xy 330.816057 -54.813736) (xy 330.852808 -54.776985) (xy 330.894856 -54.746435)
			(xy 330.941166 -54.722839) (xy 330.990596 -54.706778) (xy 331.041931 -54.698648) (xy 331.093905 -54.698648)
			(xy 331.14524 -54.706778) (xy 331.19467 -54.722839) (xy 331.24098 -54.746435) (xy 331.283028 -54.776985)
			(xy 331.319779 -54.813736) (xy 331.350329 -54.855784) (xy 331.373925 -54.902094) (xy 331.389986 -54.951524)
			(xy 331.398116 -55.002859) (xy 331.398626 -55.028846) (xy 331.398116 -55.054833) (xy 331.389986 -55.106168)
			(xy 331.373925 -55.155598) (xy 331.350329 -55.201908) (xy 331.319779 -55.243956) (xy 331.283028 -55.280707)
			(xy 331.24098 -55.311257) (xy 331.19467 -55.334853) (xy 331.14524 -55.350914) (xy 331.093905 -55.359044)
			(xy 331.041931 -55.359044) (xy 330.990596 -55.350914) (xy 330.941166 -55.334853) (xy 330.894856 -55.311257)
			(xy 330.852808 -55.280707) (xy 330.816057 -55.243956) (xy 330.785507 -55.201908) (xy 330.761911 -55.155598)
			(xy 330.74585 -55.106168) (xy 330.73772 -55.054833) (xy 329.767944 -55.054833) (xy 329.759814 -55.106168)
			(xy 329.743753 -55.155598) (xy 329.720157 -55.201908) (xy 329.689607 -55.243956) (xy 329.652856 -55.280707)
			(xy 329.610808 -55.311257) (xy 329.564498 -55.334853) (xy 329.515068 -55.350914) (xy 329.463733 -55.359044)
			(xy 329.411759 -55.359044) (xy 329.360424 -55.350914) (xy 329.310994 -55.334853) (xy 329.264684 -55.311257)
			(xy 329.222636 -55.280707) (xy 329.185885 -55.243956) (xy 329.155335 -55.201908) (xy 329.131739 -55.155598)
			(xy 329.115678 -55.106168) (xy 329.107548 -55.054833) (xy 323.615778 -55.054833) (xy 323.837046 -55.276242)
			(xy 323.85733 -55.29714) (xy 323.892791 -55.34334) (xy 323.921917 -55.393773) (xy 323.94421 -55.447578)
			(xy 323.959287 -55.503833) (xy 323.96204 -55.524733) (xy 328.29678 -55.524733) (xy 328.29678 -55.472759)
			(xy 328.30491 -55.421424) (xy 328.320971 -55.371994) (xy 328.344567 -55.325684) (xy 328.375117 -55.283636)
			(xy 328.411868 -55.246885) (xy 328.453916 -55.216335) (xy 328.500226 -55.192739) (xy 328.549656 -55.176678)
			(xy 328.600991 -55.168548) (xy 328.652965 -55.168548) (xy 328.7043 -55.176678) (xy 328.75373 -55.192739)
			(xy 328.80004 -55.216335) (xy 328.842088 -55.246885) (xy 328.878839 -55.283636) (xy 328.909389 -55.325684)
			(xy 328.932985 -55.371994) (xy 328.949046 -55.421424) (xy 328.957176 -55.472759) (xy 328.957686 -55.498746)
			(xy 328.957176 -55.524733) (xy 329.925682 -55.524733) (xy 329.925682 -55.472759) (xy 329.933812 -55.421424)
			(xy 329.949873 -55.371994) (xy 329.973469 -55.325684) (xy 330.004019 -55.283636) (xy 330.04077 -55.246885)
			(xy 330.082818 -55.216335) (xy 330.129128 -55.192739) (xy 330.178558 -55.176678) (xy 330.229893 -55.168548)
			(xy 330.281867 -55.168548) (xy 330.333202 -55.176678) (xy 330.382632 -55.192739) (xy 330.428942 -55.216335)
			(xy 330.47099 -55.246885) (xy 330.507741 -55.283636) (xy 330.538291 -55.325684) (xy 330.561887 -55.371994)
			(xy 330.577948 -55.421424) (xy 330.586078 -55.472759) (xy 330.586588 -55.498746) (xy 330.586078 -55.524733)
			(xy 331.55179 -55.524733) (xy 331.55179 -55.472759) (xy 331.55992 -55.421424) (xy 331.575981 -55.371994)
			(xy 331.599577 -55.325684) (xy 331.630127 -55.283636) (xy 331.666878 -55.246885) (xy 331.708926 -55.216335)
			(xy 331.755236 -55.192739) (xy 331.804666 -55.176678) (xy 331.856001 -55.168548) (xy 331.907975 -55.168548)
			(xy 331.95931 -55.176678) (xy 332.00874 -55.192739) (xy 332.05505 -55.216335) (xy 332.097098 -55.246885)
			(xy 332.133849 -55.283636) (xy 332.164399 -55.325684) (xy 332.187995 -55.371994) (xy 332.204056 -55.421424)
			(xy 332.212186 -55.472759) (xy 332.212696 -55.498746) (xy 332.212186 -55.524733) (xy 332.204056 -55.576068)
			(xy 332.187995 -55.625498) (xy 332.164399 -55.671808) (xy 332.133849 -55.713856) (xy 332.097098 -55.750607)
			(xy 332.05505 -55.781157) (xy 332.00874 -55.804753) (xy 331.95931 -55.820814) (xy 331.907975 -55.828944)
			(xy 331.856001 -55.828944) (xy 331.804666 -55.820814) (xy 331.755236 -55.804753) (xy 331.708926 -55.781157)
			(xy 331.666878 -55.750607) (xy 331.630127 -55.713856) (xy 331.599577 -55.671808) (xy 331.575981 -55.625498)
			(xy 331.55992 -55.576068) (xy 331.55179 -55.524733) (xy 330.586078 -55.524733) (xy 330.577948 -55.576068)
			(xy 330.561887 -55.625498) (xy 330.538291 -55.671808) (xy 330.507741 -55.713856) (xy 330.47099 -55.750607)
			(xy 330.428942 -55.781157) (xy 330.382632 -55.804753) (xy 330.333202 -55.820814) (xy 330.281867 -55.828944)
			(xy 330.229893 -55.828944) (xy 330.178558 -55.820814) (xy 330.129128 -55.804753) (xy 330.082818 -55.781157)
			(xy 330.04077 -55.750607) (xy 330.004019 -55.713856) (xy 329.973469 -55.671808) (xy 329.949873 -55.625498)
			(xy 329.933812 -55.576068) (xy 329.925682 -55.524733) (xy 328.957176 -55.524733) (xy 328.949046 -55.576068)
			(xy 328.932985 -55.625498) (xy 328.909389 -55.671808) (xy 328.878839 -55.713856) (xy 328.842088 -55.750607)
			(xy 328.80004 -55.781157) (xy 328.75373 -55.804753) (xy 328.7043 -55.820814) (xy 328.652965 -55.828944)
			(xy 328.600991 -55.828944) (xy 328.549656 -55.820814) (xy 328.500226 -55.804753) (xy 328.453916 -55.781157)
			(xy 328.411868 -55.750607) (xy 328.375117 -55.713856) (xy 328.344567 -55.671808) (xy 328.320971 -55.625498)
			(xy 328.30491 -55.576068) (xy 328.29678 -55.524733) (xy 323.96204 -55.524733) (xy 323.966892 -55.561574)
			(xy 323.967348 -55.590694) (xy 323.967348 -56.259247) (xy 324.429922 -56.259247) (xy 324.429922 -56.204753)
			(xy 324.437677 -56.150813) (xy 324.45303 -56.098526) (xy 324.475667 -56.048955) (xy 324.505128 -56.003111)
			(xy 324.540813 -55.961926) (xy 324.581997 -55.926239) (xy 324.62784 -55.896776) (xy 324.677409 -55.874136)
			(xy 324.729695 -55.858781) (xy 324.783635 -55.851023) (xy 324.810882 -55.850536) (xy 324.837526 -55.850931)
			(xy 324.890297 -55.858332) (xy 324.941523 -55.873006) (xy 324.990209 -55.894668) (xy 325.035405 -55.922896)
			(xy 325.076233 -55.957141) (xy 325.111896 -55.996734) (xy 325.1417 -56.040907) (xy 325.153782 -56.064658)
			(xy 325.160263 -56.077086) (xy 325.178944 -56.097974) (xy 325.2026 -56.112998) (xy 325.229449 -56.121025)
			(xy 325.257469 -56.121452) (xy 325.28455 -56.114247) (xy 325.308652 -56.099951) (xy 325.327961 -56.079642)
			(xy 325.334884 -56.067452) (xy 325.347306 -56.044674) (xy 325.377425 -56.002428) (xy 325.412991 -55.964652)
			(xy 325.453347 -55.932045) (xy 325.497749 -55.905206) (xy 325.545379 -55.884632) (xy 325.595357 -55.870701)
			(xy 325.646762 -55.863672) (xy 325.672704 -55.863236) (xy 325.699958 -55.863634) (xy 325.753912 -55.871392)
			(xy 325.806212 -55.886749) (xy 325.855794 -55.909393) (xy 325.90165 -55.938863) (xy 325.942844 -55.974559)
			(xy 325.960238 -55.994633) (xy 330.73899 -55.994633) (xy 330.73899 -55.942659) (xy 330.74712 -55.891324)
			(xy 330.763181 -55.841894) (xy 330.786777 -55.795584) (xy 330.817327 -55.753536) (xy 330.854078 -55.716785)
			(xy 330.896126 -55.686235) (xy 330.942436 -55.662639) (xy 330.991866 -55.646578) (xy 331.043201 -55.638448)
			(xy 331.095175 -55.638448) (xy 331.14651 -55.646578) (xy 331.19594 -55.662639) (xy 331.24225 -55.686235)
			(xy 331.284298 -55.716785) (xy 331.321049 -55.753536) (xy 331.351599 -55.795584) (xy 331.375195 -55.841894)
			(xy 331.391256 -55.891324) (xy 331.399386 -55.942659) (xy 331.399896 -55.968646) (xy 331.399386 -55.994633)
			(xy 331.391256 -56.045968) (xy 331.375195 -56.095398) (xy 331.351599 -56.141708) (xy 331.321049 -56.183756)
			(xy 331.284298 -56.220507) (xy 331.24225 -56.251057) (xy 331.19594 -56.274653) (xy 331.14651 -56.290714)
			(xy 331.095175 -56.298844) (xy 331.043201 -56.298844) (xy 330.991866 -56.290714) (xy 330.942436 -56.274653)
			(xy 330.896126 -56.251057) (xy 330.854078 -56.220507) (xy 330.817327 -56.183756) (xy 330.786777 -56.141708)
			(xy 330.763181 -56.095398) (xy 330.74712 -56.045968) (xy 330.73899 -55.994633) (xy 325.960238 -55.994633)
			(xy 325.978539 -56.015754) (xy 326.008009 -56.061609) (xy 326.030652 -56.111192) (xy 326.046009 -56.163492)
			(xy 326.053766 -56.217446) (xy 326.053766 -56.271954) (xy 326.046009 -56.325908) (xy 326.030652 -56.378208)
			(xy 326.008009 -56.427791) (xy 326.001097 -56.438546) (xy 328.29627 -56.438546) (xy 328.29678 -56.412559)
			(xy 328.30491 -56.361224) (xy 328.320971 -56.311794) (xy 328.344567 -56.265484) (xy 328.375117 -56.223436)
			(xy 328.411868 -56.186685) (xy 328.453916 -56.156135) (xy 328.500226 -56.132539) (xy 328.549656 -56.116478)
			(xy 328.600991 -56.108348) (xy 328.652965 -56.108348) (xy 328.7043 -56.116478) (xy 328.75373 -56.132539)
			(xy 328.80004 -56.156135) (xy 328.842088 -56.186685) (xy 328.878839 -56.223436) (xy 328.909389 -56.265484)
			(xy 328.932985 -56.311794) (xy 328.949046 -56.361224) (xy 328.957176 -56.412559) (xy 328.957686 -56.438546)
			(xy 328.957164 -56.464533) (xy 329.925682 -56.464533) (xy 329.925682 -56.412559) (xy 329.933812 -56.361224)
			(xy 329.949873 -56.311794) (xy 329.973469 -56.265484) (xy 330.004019 -56.223436) (xy 330.04077 -56.186685)
			(xy 330.082818 -56.156135) (xy 330.129128 -56.132539) (xy 330.178558 -56.116478) (xy 330.229893 -56.108348)
			(xy 330.281867 -56.108348) (xy 330.333202 -56.116478) (xy 330.382632 -56.132539) (xy 330.428942 -56.156135)
			(xy 330.47099 -56.186685) (xy 330.507741 -56.223436) (xy 330.538291 -56.265484) (xy 330.561887 -56.311794)
			(xy 330.577948 -56.361224) (xy 330.586078 -56.412559) (xy 330.586588 -56.438546) (xy 330.586078 -56.464533)
			(xy 331.55179 -56.464533) (xy 331.55179 -56.412559) (xy 331.55992 -56.361224) (xy 331.575981 -56.311794)
			(xy 331.599577 -56.265484) (xy 331.630127 -56.223436) (xy 331.666878 -56.186685) (xy 331.708926 -56.156135)
			(xy 331.755236 -56.132539) (xy 331.804666 -56.116478) (xy 331.856001 -56.108348) (xy 331.907975 -56.108348)
			(xy 331.95931 -56.116478) (xy 332.00874 -56.132539) (xy 332.05505 -56.156135) (xy 332.097098 -56.186685)
			(xy 332.133849 -56.223436) (xy 332.164399 -56.265484) (xy 332.187995 -56.311794) (xy 332.204056 -56.361224)
			(xy 332.212186 -56.412559) (xy 332.212696 -56.438546) (xy 332.212186 -56.464533) (xy 332.204056 -56.515868)
			(xy 332.187995 -56.565298) (xy 332.164399 -56.611608) (xy 332.133849 -56.653656) (xy 332.097098 -56.690407)
			(xy 332.05505 -56.720957) (xy 332.00874 -56.744553) (xy 331.95931 -56.760614) (xy 331.907975 -56.768744)
			(xy 331.856001 -56.768744) (xy 331.804666 -56.760614) (xy 331.755236 -56.744553) (xy 331.708926 -56.720957)
			(xy 331.666878 -56.690407) (xy 331.630127 -56.653656) (xy 331.599577 -56.611608) (xy 331.575981 -56.565298)
			(xy 331.55992 -56.515868) (xy 331.55179 -56.464533) (xy 330.586078 -56.464533) (xy 330.577948 -56.515868)
			(xy 330.561887 -56.565298) (xy 330.538291 -56.611608) (xy 330.507741 -56.653656) (xy 330.47099 -56.690407)
			(xy 330.428942 -56.720957) (xy 330.382632 -56.744553) (xy 330.333202 -56.760614) (xy 330.281867 -56.768744)
			(xy 330.229893 -56.768744) (xy 330.178558 -56.760614) (xy 330.129128 -56.744553) (xy 330.082818 -56.720957)
			(xy 330.04077 -56.690407) (xy 330.004019 -56.653656) (xy 329.973469 -56.611608) (xy 329.949873 -56.565298)
			(xy 329.933812 -56.515868) (xy 329.925682 -56.464533) (xy 328.957164 -56.464533) (xy 328.957163 -56.464558)
			(xy 328.949019 -56.515939) (xy 328.932938 -56.565415) (xy 328.909317 -56.611767) (xy 328.89444 -56.63311)
			(xy 328.886365 -56.645004) (xy 328.876535 -56.672005) (xy 328.874637 -56.700676) (xy 328.880823 -56.728737)
			(xy 328.894599 -56.753953) (xy 328.91487 -56.774318) (xy 328.927206 -56.7817) (xy 328.940166 -56.789099)
			(xy 328.964841 -56.80589) (xy 328.976482 -56.815228) (xy 328.98715 -56.823424) (xy 329.011664 -56.834477)
			(xy 329.038215 -56.838745) (xy 329.064958 -56.835932) (xy 329.090039 -56.826232) (xy 329.111717 -56.81032)
			(xy 329.128488 -56.7893) (xy 329.134216 -56.777128) (xy 329.145652 -56.752138) (xy 329.175512 -56.706005)
			(xy 329.212585 -56.665441) (xy 329.255853 -56.631562) (xy 329.304125 -56.6053) (xy 329.356073 -56.587377)
			(xy 329.410269 -56.578286) (xy 329.437746 -56.577738) (xy 329.463734 -56.578159) (xy 329.51507 -56.586297)
			(xy 329.564502 -56.602364) (xy 329.610811 -56.625965) (xy 329.652859 -56.65652) (xy 329.68961 -56.693276)
			(xy 329.720159 -56.735328) (xy 329.743754 -56.781641) (xy 329.759814 -56.831074) (xy 329.767945 -56.882412)
			(xy 329.767945 -56.934389) (xy 329.759814 -56.985726) (xy 329.743754 -57.035159) (xy 329.720159 -57.081472)
			(xy 329.68961 -57.123524) (xy 329.652859 -57.16028) (xy 329.610811 -57.190835) (xy 329.564502 -57.214436)
			(xy 329.51507 -57.230503) (xy 329.463734 -57.238641) (xy 329.437746 -57.239154) (xy 329.409315 -57.238528)
			(xy 329.353297 -57.228764) (xy 329.299767 -57.209583) (xy 329.250295 -57.181549) (xy 329.227942 -57.16397)
			(xy 329.217253 -57.155803) (xy 329.192745 -57.144748) (xy 329.1662 -57.140477) (xy 329.139461 -57.143286)
			(xy 329.114383 -57.15298) (xy 329.092706 -57.168886) (xy 329.075936 -57.189901) (xy 329.070208 -57.20207)
			(xy 329.058831 -57.227089) (xy 329.028963 -57.273225) (xy 329.013367 -57.290285) (xy 330.162201 -57.290285)
			(xy 330.162201 -57.238315) (xy 330.170331 -57.186985) (xy 330.186389 -57.137558) (xy 330.209981 -57.091252)
			(xy 330.240525 -57.049206) (xy 330.277271 -57.012455) (xy 330.319313 -56.981905) (xy 330.365616 -56.958306)
			(xy 330.41504 -56.942241) (xy 330.466369 -56.934105) (xy 330.492354 -56.933592) (xy 330.521285 -56.9342)
			(xy 330.57826 -56.944288) (xy 330.605638 -56.953658) (xy 330.620221 -56.958355) (xy 330.650803 -56.959863)
			(xy 330.680464 -56.952261) (xy 330.70655 -56.936228) (xy 330.726729 -56.913199) (xy 330.739195 -56.885232)
			(xy 330.741528 -56.870092) (xy 330.745155 -56.843594) (xy 330.759806 -56.792162) (xy 330.782546 -56.743759)
			(xy 330.81278 -56.699648) (xy 330.849721 -56.660979) (xy 330.892406 -56.628761) (xy 330.939719 -56.603835)
			(xy 330.990429 -56.58685) (xy 331.043211 -56.578249) (xy 331.06995 -56.577738) (xy 331.095945 -56.578126)
			(xy 331.147297 -56.586252) (xy 331.196745 -56.602312) (xy 331.243072 -56.62591) (xy 331.285136 -56.656466)
			(xy 331.321902 -56.693226) (xy 331.352464 -56.735285) (xy 331.376069 -56.781608) (xy 331.392137 -56.831054)
			(xy 331.400271 -56.882405) (xy 331.400271 -56.934395) (xy 331.392137 -56.985746) (xy 331.376069 -57.035192)
			(xy 331.352464 -57.081515) (xy 331.321902 -57.123574) (xy 331.285136 -57.160334) (xy 331.243072 -57.19089)
			(xy 331.196745 -57.214488) (xy 331.147297 -57.230548) (xy 331.095945 -57.238674) (xy 331.06995 -57.239154)
			(xy 331.041019 -57.238547) (xy 330.984044 -57.228459) (xy 330.956666 -57.219088) (xy 330.942091 -57.214357)
			(xy 330.911501 -57.212846) (xy 330.881833 -57.22045) (xy 330.855742 -57.236491) (xy 330.835563 -57.259531)
			(xy 330.823103 -57.287509) (xy 330.820776 -57.302654) (xy 330.817182 -57.329156) (xy 330.802524 -57.380589)
			(xy 330.779778 -57.428991) (xy 330.749539 -57.473101) (xy 330.712594 -57.511769) (xy 330.669906 -57.543986)
			(xy 330.62259 -57.568911) (xy 330.571878 -57.585896) (xy 330.519094 -57.594497) (xy 330.492354 -57.595008)
			(xy 330.466369 -57.594495) (xy 330.41504 -57.586359) (xy 330.365616 -57.570294) (xy 330.319313 -57.546695)
			(xy 330.277271 -57.516145) (xy 330.240525 -57.479394) (xy 330.209981 -57.437348) (xy 330.186389 -57.391042)
			(xy 330.170331 -57.341615) (xy 330.162201 -57.290285) (xy 329.013367 -57.290285) (xy 328.99188 -57.313789)
			(xy 328.948602 -57.347665) (xy 328.90032 -57.373922) (xy 328.848362 -57.391838) (xy 328.794158 -57.400918)
			(xy 328.766678 -57.40146) (xy 328.740686 -57.401045) (xy 328.689342 -57.392909) (xy 328.639903 -57.376841)
			(xy 328.593586 -57.353236) (xy 328.551533 -57.322676) (xy 328.514778 -57.285914) (xy 328.484227 -57.243854)
			(xy 328.460632 -57.197532) (xy 328.444575 -57.14809) (xy 328.43645 -57.096744) (xy 328.43597 -57.070752)
			(xy 328.436482 -57.04474) (xy 328.444628 -56.993357) (xy 328.460711 -56.943881) (xy 328.484336 -56.89753)
			(xy 328.499216 -56.876188) (xy 328.507274 -56.864285) (xy 328.517096 -56.837288) (xy 328.518992 -56.808621)
			(xy 328.512809 -56.780566) (xy 328.49904 -56.755352) (xy 328.47878 -56.734984) (xy 328.46645 -56.727598)
			(xy 328.4447 -56.71498) (xy 328.404938 -56.684205) (xy 328.370294 -56.647765) (xy 328.341568 -56.606499)
			(xy 328.31942 -56.561359) (xy 328.304363 -56.513386) (xy 328.296743 -56.463686) (xy 328.29627 -56.438546)
			(xy 326.001097 -56.438546) (xy 325.978539 -56.473646) (xy 325.942844 -56.514841) (xy 325.90165 -56.550537)
			(xy 325.855794 -56.580007) (xy 325.806212 -56.602651) (xy 325.753912 -56.618008) (xy 325.699958 -56.625766)
			(xy 325.672704 -56.626252) (xy 325.646062 -56.625793) (xy 325.593294 -56.618403) (xy 325.542068 -56.603739)
			(xy 325.493383 -56.582087) (xy 325.448186 -56.553868) (xy 325.407357 -56.519632) (xy 325.371693 -56.480045)
			(xy 325.341886 -56.435878) (xy 325.329804 -56.41213) (xy 325.323194 -56.399777) (xy 325.304534 -56.3789)
			(xy 325.280902 -56.363881) (xy 325.254078 -56.35585) (xy 325.22608 -56.355413) (xy 325.199018 -56.362602)
			(xy 325.174929 -56.376875) (xy 325.155625 -56.397159) (xy 325.148702 -56.409336) (xy 325.136285 -56.432117)
			(xy 325.106166 -56.474364) (xy 325.0706 -56.51214) (xy 325.030243 -56.544748) (xy 324.98584 -56.571586)
			(xy 324.938209 -56.592159) (xy 324.88823 -56.606089) (xy 324.836824 -56.613117) (xy 324.810882 -56.613552)
			(xy 324.783635 -56.612977) (xy 324.729695 -56.605219) (xy 324.677409 -56.589864) (xy 324.62784 -56.567224)
			(xy 324.581997 -56.537761) (xy 324.540813 -56.502074) (xy 324.505128 -56.460889) (xy 324.475667 -56.415045)
			(xy 324.45303 -56.365474) (xy 324.437677 -56.313187) (xy 324.429922 -56.259247) (xy 323.967348 -56.259247)
			(xy 323.967348 -56.729376) (xy 323.966879 -56.758496) (xy 323.959286 -56.816239) (xy 323.944214 -56.872494)
			(xy 323.921922 -56.926299) (xy 323.892792 -56.97673) (xy 323.857323 -57.022923) (xy 323.837046 -57.043828)
			(xy 323.556884 -57.32399) (xy 324.143876 -57.32399) (xy 324.147947 -57.268368) (xy 324.160073 -57.213931)
			(xy 324.179996 -57.16184) (xy 324.207292 -57.113205) (xy 324.241378 -57.069062) (xy 324.281527 -57.030353)
			(xy 324.326885 -56.997902) (xy 324.376485 -56.972401) (xy 324.429269 -56.954394) (xy 324.484112 -56.944264)
			(xy 324.539846 -56.942227) (xy 324.595283 -56.948327) (xy 324.64924 -56.962433) (xy 324.700569 -56.984245)
			(xy 324.748175 -57.013299) (xy 324.791043 -57.048974) (xy 324.82826 -57.090511) (xy 324.859033 -57.137024)
			(xy 324.882705 -57.187521) (xy 324.898773 -57.240928) (xy 324.906893 -57.296104) (xy 324.907402 -57.32399)
			(xy 324.906893 -57.351876) (xy 324.898773 -57.407052) (xy 324.882705 -57.460459) (xy 324.872379 -57.482486)
			(xy 325.421 -57.482486) (xy 325.424976 -57.42816) (xy 325.436819 -57.374991) (xy 325.456278 -57.324114)
			(xy 325.482938 -57.276612) (xy 325.516229 -57.233498) (xy 325.555443 -57.195691) (xy 325.599745 -57.163996)
			(xy 325.648188 -57.13909) (xy 325.699742 -57.121502) (xy 325.753308 -57.111608) (xy 325.807743 -57.109618)
			(xy 325.861888 -57.115576) (xy 325.914588 -57.129354) (xy 325.964721 -57.150658) (xy 326.011217 -57.179034)
			(xy 326.053087 -57.213878) (xy 326.089436 -57.254447) (xy 326.119492 -57.299876) (xy 326.142613 -57.349197)
			(xy 326.158306 -57.401359) (xy 326.166237 -57.45525) (xy 326.166734 -57.482486) (xy 326.166237 -57.509722)
			(xy 326.158306 -57.563613) (xy 326.142613 -57.615775) (xy 326.119492 -57.665096) (xy 326.089436 -57.710525)
			(xy 326.053087 -57.751094) (xy 326.011217 -57.785938) (xy 325.964721 -57.814314) (xy 325.914588 -57.835618)
			(xy 325.861888 -57.849396) (xy 325.807743 -57.855354) (xy 325.753308 -57.853364) (xy 325.699742 -57.84347)
			(xy 325.648188 -57.825882) (xy 325.599745 -57.800976) (xy 325.555443 -57.769281) (xy 325.516229 -57.731474)
			(xy 325.482938 -57.68836) (xy 325.456278 -57.640858) (xy 325.436819 -57.589981) (xy 325.424976 -57.536812)
			(xy 325.421 -57.482486) (xy 324.872379 -57.482486) (xy 324.859033 -57.510956) (xy 324.82826 -57.557469)
			(xy 324.791043 -57.599006) (xy 324.748175 -57.634681) (xy 324.700569 -57.663735) (xy 324.64924 -57.685547)
			(xy 324.595283 -57.699653) (xy 324.539846 -57.705753) (xy 324.484112 -57.703716) (xy 324.429269 -57.693586)
			(xy 324.376485 -57.675579) (xy 324.326885 -57.650078) (xy 324.281527 -57.617627) (xy 324.241378 -57.578918)
			(xy 324.207292 -57.534775) (xy 324.179996 -57.48614) (xy 324.160073 -57.434049) (xy 324.147947 -57.379612)
			(xy 324.143876 -57.32399) (xy 323.556884 -57.32399) (xy 322.389754 -58.49112) (xy 325.86498 -58.49112)
			(xy 325.869051 -58.435498) (xy 325.881177 -58.381061) (xy 325.9011 -58.32897) (xy 325.928396 -58.280335)
			(xy 325.962482 -58.236192) (xy 326.002631 -58.197483) (xy 326.047989 -58.165032) (xy 326.097589 -58.139531)
			(xy 326.150373 -58.121524) (xy 326.205216 -58.111394) (xy 326.26095 -58.109357) (xy 326.316387 -58.115457)
			(xy 326.370344 -58.129563) (xy 326.421673 -58.151375) (xy 326.469279 -58.180429) (xy 326.512147 -58.216104)
			(xy 326.549364 -58.257641) (xy 326.580137 -58.304154) (xy 326.603809 -58.354651) (xy 326.619877 -58.408058)
			(xy 326.627997 -58.463234) (xy 326.628506 -58.49112) (xy 326.627997 -58.519006) (xy 326.619877 -58.574182)
			(xy 326.603809 -58.627589) (xy 326.580137 -58.678086) (xy 326.549364 -58.724599) (xy 326.512147 -58.766136)
			(xy 326.469279 -58.801811) (xy 326.421673 -58.830865) (xy 326.370344 -58.852677) (xy 326.316387 -58.866783)
			(xy 326.26095 -58.872883) (xy 326.205216 -58.870846) (xy 326.150373 -58.860716) (xy 326.097589 -58.842709)
			(xy 326.047989 -58.817208) (xy 326.002631 -58.784757) (xy 325.962482 -58.746048) (xy 325.928396 -58.701905)
			(xy 325.9011 -58.65327) (xy 325.881177 -58.601179) (xy 325.869051 -58.546742) (xy 325.86498 -58.49112)
			(xy 322.389754 -58.49112) (xy 322.283074 -58.5978) (xy 322.26217 -58.61809) (xy 322.215991 -58.653606)
			(xy 322.165568 -58.682784) (xy 322.111765 -58.705125) (xy 322.055504 -58.720245) (xy 321.99775 -58.727884)
			(xy 321.968622 -58.728356) (xy 321.939491 -58.727877) (xy 321.881728 -58.720272) (xy 321.825452 -58.70519)
			(xy 321.771628 -58.682889) (xy 321.721176 -58.65375) (xy 321.674962 -58.618273) (xy 321.633775 -58.577065)
			(xy 321.598322 -58.530832) (xy 321.56921 -58.480365) (xy 321.546936 -58.42653) (xy 321.531883 -58.370246)
			(xy 321.524308 -58.312479) (xy 321.523868 -58.283348) (xy 321.524284 -58.254226) (xy 321.531886 -58.196481)
			(xy 321.546968 -58.140224) (xy 321.56927 -58.08642) (xy 321.59841 -58.03599) (xy 321.633888 -57.989799)
			(xy 321.65417 -57.968896) (xy 321.858894 -57.763918) (xy 321.868548 -57.753484) (xy 321.882297 -57.728621)
			(xy 321.888666 -57.700933) (xy 321.887163 -57.672562) (xy 321.877904 -57.645703) (xy 321.861605 -57.622432)
			(xy 321.839527 -57.604551) (xy 321.826636 -57.598564) (xy 321.804456 -57.588802) (xy 321.762542 -57.564476)
			(xy 321.74307 -57.55005) (xy 321.730864 -57.541298) (xy 321.702739 -57.53079) (xy 321.672774 -57.528904)
			(xy 321.643553 -57.535801) (xy 321.617594 -57.550887) (xy 321.597136 -57.572862) (xy 321.583941 -57.599832)
			(xy 321.581018 -57.614566) (xy 321.576312 -57.641109) (xy 321.560411 -57.692615) (xy 321.537415 -57.741369)
			(xy 321.507784 -57.7864) (xy 321.472107 -57.826809) (xy 321.431096 -57.861792) (xy 321.385567 -57.890652)
			(xy 321.336428 -57.912813) (xy 321.284658 -57.927834) (xy 321.231289 -57.935415) (xy 321.204336 -57.935876)
			(xy 321.177079 -57.93548) (xy 321.12312 -57.927726) (xy 321.070813 -57.912372) (xy 321.021224 -57.889729)
			(xy 320.975363 -57.86026) (xy 320.934162 -57.824563) (xy 320.898462 -57.783366) (xy 320.868988 -57.737507)
			(xy 320.846341 -57.687921) (xy 320.830982 -57.635615) (xy 320.823223 -57.581657) (xy 320.823223 -57.527143)
			(xy 320.830982 -57.473185) (xy 320.846341 -57.420879) (xy 320.868988 -57.371293) (xy 320.898462 -57.325434)
			(xy 320.934162 -57.284237) (xy 320.975363 -57.24854) (xy 321.021224 -57.219071) (xy 321.070813 -57.196428)
			(xy 321.12312 -57.181074) (xy 321.177079 -57.17332) (xy 321.204336 -57.17286) (xy 321.229268 -57.173258)
			(xy 321.278708 -57.179744) (xy 321.326883 -57.192613) (xy 321.372971 -57.211648) (xy 321.416188 -57.236522)
			(xy 321.436238 -57.251346) (xy 321.448436 -57.26011) (xy 321.476564 -57.270617) (xy 321.506531 -57.272503)
			(xy 321.535754 -57.265604) (xy 321.561714 -57.250516) (xy 321.582173 -57.228538) (xy 321.595367 -57.201566)
			(xy 321.59829 -57.18683) (xy 321.602986 -57.160285) (xy 321.618888 -57.108778) (xy 321.641884 -57.060024)
			(xy 321.671517 -57.014993) (xy 321.707195 -56.974584) (xy 321.748207 -56.939601) (xy 321.793737 -56.910741)
			(xy 321.842878 -56.888581) (xy 321.894649 -56.873561) (xy 321.948019 -56.86598) (xy 321.974972 -56.86552)
			(xy 322.002923 -56.865997) (xy 322.058228 -56.874139) (xy 322.111753 -56.890267) (xy 322.16235 -56.914036)
			(xy 322.208935 -56.944936) (xy 322.25051 -56.982305) (xy 322.286185 -57.025343) (xy 322.315195 -57.073128)
			(xy 322.326508 -57.098692) (xy 322.332426 -57.111633) (xy 322.350298 -57.133766) (xy 322.373584 -57.150107)
			(xy 322.400475 -57.159386) (xy 322.428883 -57.160884) (xy 322.456602 -57.154483) (xy 322.481477 -57.140681)
			(xy 322.491862 -57.13095) (xy 323.07784 -56.545226) (xy 323.07784 -56.424576) (xy 323.020182 -56.424576)
			(xy 323.013578 -56.426354) (xy 322.989153 -56.43254) (xy 322.939203 -56.439159) (xy 322.91401 -56.439562)
			(xy 322.886755 -56.439135) (xy 322.832801 -56.431378) (xy 322.780499 -56.416021) (xy 322.730916 -56.393377)
			(xy 322.685061 -56.363905) (xy 322.643867 -56.328208) (xy 322.608173 -56.28701) (xy 322.578706 -56.241152)
			(xy 322.556066 -56.191567) (xy 322.540714 -56.139264) (xy 322.532962 -56.085309) (xy 322.532502 -56.058054)
			(xy 322.532966 -56.031658) (xy 322.540238 -55.97937) (xy 322.55465 -55.928584) (xy 322.575927 -55.88027)
			(xy 322.603664 -55.835351) (xy 322.637328 -55.794687) (xy 322.676279 -55.759052) (xy 322.719771 -55.729129)
			(xy 322.766973 -55.705489) (xy 322.791836 -55.696612) (xy 322.805656 -55.69137) (xy 322.829783 -55.674325)
			(xy 322.848022 -55.651088) (xy 322.85885 -55.623603) (xy 322.86136 -55.59417) (xy 322.855341 -55.565249)
			(xy 322.841299 -55.53926) (xy 322.831206 -55.528464) (xy 322.047108 -54.744112) (xy 318.669924 -54.744112)
			(xy 318.302132 -55.111904) (xy 318.281247 -55.132215) (xy 318.235064 -55.167729) (xy 318.184637 -55.196904)
			(xy 318.13083 -55.219241) (xy 318.074566 -55.234356) (xy 318.067062 -55.235348) (xy 320.895978 -55.235348)
			(xy 320.900049 -55.179726) (xy 320.912175 -55.125289) (xy 320.932098 -55.073198) (xy 320.959394 -55.024563)
			(xy 320.99348 -54.98042) (xy 321.033629 -54.941711) (xy 321.078987 -54.90926) (xy 321.128587 -54.883759)
			(xy 321.181371 -54.865752) (xy 321.236214 -54.855622) (xy 321.291948 -54.853585) (xy 321.347385 -54.859685)
			(xy 321.401342 -54.873791) (xy 321.452671 -54.895603) (xy 321.500277 -54.924657) (xy 321.543145 -54.960332)
			(xy 321.580362 -55.001869) (xy 321.611135 -55.048382) (xy 321.634807 -55.098879) (xy 321.650875 -55.152286)
			(xy 321.658995 -55.207462) (xy 321.659504 -55.235348) (xy 321.658995 -55.263234) (xy 321.650875 -55.31841)
			(xy 321.634807 -55.371817) (xy 321.611135 -55.422314) (xy 321.580362 -55.468827) (xy 321.543145 -55.510364)
			(xy 321.500277 -55.546039) (xy 321.452671 -55.575093) (xy 321.401342 -55.596905) (xy 321.347385 -55.611011)
			(xy 321.291948 -55.617111) (xy 321.236214 -55.615074) (xy 321.181371 -55.604944) (xy 321.128587 -55.586937)
			(xy 321.078987 -55.561436) (xy 321.033629 -55.528985) (xy 320.99348 -55.490276) (xy 320.959394 -55.446133)
			(xy 320.932098 -55.397498) (xy 320.912175 -55.345407) (xy 320.900049 -55.29097) (xy 320.895978 -55.235348)
			(xy 318.067062 -55.235348) (xy 318.016809 -55.241991) (xy 317.98768 -55.24246) (xy 316.329568 -55.24246)
			(xy 315.32046 -56.251348) (xy 318.792604 -56.251348) (xy 318.796675 -56.195726) (xy 318.808801 -56.141289)
			(xy 318.828724 -56.089198) (xy 318.85602 -56.040563) (xy 318.890106 -55.99642) (xy 318.930255 -55.957711)
			(xy 318.975613 -55.92526) (xy 319.025213 -55.899759) (xy 319.077997 -55.881752) (xy 319.13284 -55.871622)
			(xy 319.188574 -55.869585) (xy 319.244011 -55.875685) (xy 319.297968 -55.889791) (xy 319.349297 -55.911603)
			(xy 319.396903 -55.940657) (xy 319.439771 -55.976332) (xy 319.476988 -56.017869) (xy 319.503574 -56.058054)
			(xy 321.515992 -56.058054) (xy 321.520063 -56.002432) (xy 321.532189 -55.947995) (xy 321.552112 -55.895904)
			(xy 321.579408 -55.847269) (xy 321.613494 -55.803126) (xy 321.653643 -55.764417) (xy 321.699001 -55.731966)
			(xy 321.748601 -55.706465) (xy 321.801385 -55.688458) (xy 321.856228 -55.678328) (xy 321.911962 -55.676291)
			(xy 321.967399 -55.682391) (xy 322.021356 -55.696497) (xy 322.072685 -55.718309) (xy 322.120291 -55.747363)
			(xy 322.163159 -55.783038) (xy 322.200376 -55.824575) (xy 322.231149 -55.871088) (xy 322.254821 -55.921585)
			(xy 322.270889 -55.974992) (xy 322.279009 -56.030168) (xy 322.279518 -56.058054) (xy 322.279009 -56.08594)
			(xy 322.270889 -56.141116) (xy 322.254821 -56.194523) (xy 322.231149 -56.24502) (xy 322.200376 -56.291533)
			(xy 322.163159 -56.33307) (xy 322.120291 -56.368745) (xy 322.072685 -56.397799) (xy 322.021356 -56.419611)
			(xy 321.967399 -56.433717) (xy 321.911962 -56.439817) (xy 321.856228 -56.43778) (xy 321.801385 -56.42765)
			(xy 321.748601 -56.409643) (xy 321.699001 -56.384142) (xy 321.653643 -56.351691) (xy 321.613494 -56.312982)
			(xy 321.579408 -56.268839) (xy 321.552112 -56.220204) (xy 321.532189 -56.168113) (xy 321.520063 -56.113676)
			(xy 321.515992 -56.058054) (xy 319.503574 -56.058054) (xy 319.507761 -56.064382) (xy 319.531433 -56.114879)
			(xy 319.547501 -56.168286) (xy 319.555621 -56.223462) (xy 319.55613 -56.251348) (xy 319.555621 -56.279234)
			(xy 319.547501 -56.33441) (xy 319.531433 -56.387817) (xy 319.507761 -56.438314) (xy 319.476988 -56.484827)
			(xy 319.439771 -56.526364) (xy 319.396903 -56.562039) (xy 319.349297 -56.591093) (xy 319.297968 -56.612905)
			(xy 319.244011 -56.627011) (xy 319.188574 -56.633111) (xy 319.13284 -56.631074) (xy 319.077997 -56.620944)
			(xy 319.025213 -56.602937) (xy 318.975613 -56.577436) (xy 318.930255 -56.544985) (xy 318.890106 -56.506276)
			(xy 318.85602 -56.462133) (xy 318.828724 -56.413498) (xy 318.808801 -56.361407) (xy 318.796675 -56.30697)
			(xy 318.792604 -56.251348) (xy 315.32046 -56.251348) (xy 315.162184 -56.40959) (xy 315.162184 -56.911748)
			(xy 315.161665 -56.942135) (xy 315.15339 -57.002342) (xy 315.136994 -57.060861) (xy 315.112782 -57.116603)
			(xy 315.081205 -57.168528) (xy 315.042852 -57.215671) (xy 314.998437 -57.257152) (xy 314.948787 -57.292198)
			(xy 314.894827 -57.320158) (xy 314.837563 -57.34051) (xy 314.778061 -57.352874) (xy 314.71743 -57.357022)
			(xy 314.656799 -57.352874) (xy 314.597297 -57.34051) (xy 314.540033 -57.320158) (xy 314.486073 -57.292198)
			(xy 314.436423 -57.257152) (xy 314.392008 -57.215671) (xy 314.353655 -57.168528) (xy 314.322078 -57.116603)
			(xy 314.297866 -57.060861) (xy 314.28147 -57.002342) (xy 314.273195 -56.942135) (xy 314.272676 -56.911748)
			(xy 314.272676 -56.754776) (xy 314.272225 -56.740206) (xy 314.264019 -56.712245) (xy 314.248253 -56.687738)
			(xy 314.226209 -56.66868) (xy 314.199681 -56.656621) (xy 314.170828 -56.652541) (xy 314.156344 -56.654192)
			(xy 314.142705 -56.656067) (xy 314.115247 -56.658103) (xy 314.10148 -56.658256) (xy 314.074233 -56.657672)
			(xy 314.020294 -56.649915) (xy 313.968009 -56.63456) (xy 313.91844 -56.61192) (xy 313.872598 -56.582457)
			(xy 313.831416 -56.54677) (xy 313.795731 -56.505586) (xy 313.76627 -56.459742) (xy 313.743633 -56.410173)
			(xy 313.728281 -56.357886) (xy 313.720526 -56.303947) (xy 304.188601 -56.303947) (xy 303.40808 -57.084468)
			(xy 306.109622 -57.084468) (xy 306.113693 -57.028846) (xy 306.125819 -56.974409) (xy 306.145742 -56.922318)
			(xy 306.173038 -56.873683) (xy 306.207124 -56.82954) (xy 306.247273 -56.790831) (xy 306.292631 -56.75838)
			(xy 306.342231 -56.732879) (xy 306.395015 -56.714872) (xy 306.449858 -56.704742) (xy 306.505592 -56.702705)
			(xy 306.561029 -56.708805) (xy 306.614986 -56.722911) (xy 306.666315 -56.744723) (xy 306.713921 -56.773777)
			(xy 306.756789 -56.809452) (xy 306.794006 -56.850989) (xy 306.824779 -56.897502) (xy 306.848451 -56.947999)
			(xy 306.86047 -56.987948) (xy 306.979318 -56.987948) (xy 306.983389 -56.932326) (xy 306.995515 -56.877889)
			(xy 307.015438 -56.825798) (xy 307.042734 -56.777163) (xy 307.07682 -56.73302) (xy 307.116969 -56.694311)
			(xy 307.162327 -56.66186) (xy 307.211927 -56.636359) (xy 307.264711 -56.618352) (xy 307.319554 -56.608222)
			(xy 307.375288 -56.606185) (xy 307.430725 -56.612285) (xy 307.484682 -56.626391) (xy 307.536011 -56.648203)
			(xy 307.583617 -56.677257) (xy 307.626485 -56.712932) (xy 307.663702 -56.754469) (xy 307.694475 -56.800982)
			(xy 307.718147 -56.851479) (xy 307.734215 -56.904886) (xy 307.742335 -56.960062) (xy 307.742844 -56.987948)
			(xy 307.742335 -57.015834) (xy 307.734215 -57.07101) (xy 307.726345 -57.097168) (xy 307.857142 -57.097168)
			(xy 307.861213 -57.041546) (xy 307.873339 -56.987109) (xy 307.893262 -56.935018) (xy 307.920558 -56.886383)
			(xy 307.954644 -56.84224) (xy 307.994793 -56.803531) (xy 308.040151 -56.77108) (xy 308.089751 -56.745579)
			(xy 308.142535 -56.727572) (xy 308.197378 -56.717442) (xy 308.253112 -56.715405) (xy 308.308549 -56.721505)
			(xy 308.362506 -56.735611) (xy 308.413835 -56.757423) (xy 308.461441 -56.786477) (xy 308.504309 -56.822152)
			(xy 308.541526 -56.863689) (xy 308.572299 -56.910202) (xy 308.595971 -56.960699) (xy 308.612039 -57.014106)
			(xy 308.620159 -57.069282) (xy 308.620668 -57.097168) (xy 308.620159 -57.125054) (xy 308.612039 -57.18023)
			(xy 308.595971 -57.233637) (xy 308.572299 -57.284134) (xy 308.541526 -57.330647) (xy 308.504309 -57.372184)
			(xy 308.461441 -57.407859) (xy 308.413835 -57.436913) (xy 308.362506 -57.458725) (xy 308.308549 -57.472831)
			(xy 308.253112 -57.478931) (xy 308.197378 -57.476894) (xy 308.142535 -57.466764) (xy 308.089751 -57.448757)
			(xy 308.040151 -57.423256) (xy 307.994793 -57.390805) (xy 307.954644 -57.352096) (xy 307.920558 -57.307953)
			(xy 307.893262 -57.259318) (xy 307.873339 -57.207227) (xy 307.861213 -57.15279) (xy 307.857142 -57.097168)
			(xy 307.726345 -57.097168) (xy 307.718147 -57.124417) (xy 307.694475 -57.174914) (xy 307.663702 -57.221427)
			(xy 307.626485 -57.262964) (xy 307.583617 -57.298639) (xy 307.536011 -57.327693) (xy 307.484682 -57.349505)
			(xy 307.430725 -57.363611) (xy 307.375288 -57.369711) (xy 307.319554 -57.367674) (xy 307.264711 -57.357544)
			(xy 307.211927 -57.339537) (xy 307.162327 -57.314036) (xy 307.116969 -57.281585) (xy 307.07682 -57.242876)
			(xy 307.042734 -57.198733) (xy 307.015438 -57.150098) (xy 306.995515 -57.098007) (xy 306.983389 -57.04357)
			(xy 306.979318 -56.987948) (xy 306.86047 -56.987948) (xy 306.864519 -57.001406) (xy 306.872639 -57.056582)
			(xy 306.873148 -57.084468) (xy 306.872639 -57.112354) (xy 306.864519 -57.16753) (xy 306.848451 -57.220937)
			(xy 306.824779 -57.271434) (xy 306.794006 -57.317947) (xy 306.756789 -57.359484) (xy 306.713921 -57.395159)
			(xy 306.666315 -57.424213) (xy 306.614986 -57.446025) (xy 306.561029 -57.460131) (xy 306.505592 -57.466231)
			(xy 306.449858 -57.464194) (xy 306.395015 -57.454064) (xy 306.342231 -57.436057) (xy 306.292631 -57.410556)
			(xy 306.247273 -57.378105) (xy 306.207124 -57.339396) (xy 306.173038 -57.295253) (xy 306.145742 -57.246618)
			(xy 306.125819 -57.194527) (xy 306.113693 -57.14009) (xy 306.109622 -57.084468) (xy 303.40808 -57.084468)
			(xy 302.1076 -58.384948) (xy 302.1076 -58.511948) (xy 315.777372 -58.511948) (xy 315.777904 -58.482773)
			(xy 315.786796 -58.425106) (xy 315.804364 -58.369464) (xy 315.830199 -58.317146) (xy 315.863699 -58.269371)
			(xy 315.904082 -58.227254) (xy 315.950407 -58.191777) (xy 316.001594 -58.163766) (xy 316.028832 -58.1533)
			(xy 316.041333 -58.148371) (xy 316.063314 -58.132924) (xy 316.080507 -58.11228) (xy 316.091722 -58.087867)
			(xy 316.096185 -58.061374) (xy 316.093586 -58.034635) (xy 316.084105 -58.009497) (xy 316.076584 -57.99836)
			(xy 316.059604 -57.973869) (xy 316.032677 -57.920707) (xy 316.014341 -57.864006) (xy 316.00504 -57.805144)
			(xy 316.004448 -57.775348) (xy 316.004844 -57.749463) (xy 316.011856 -57.698171) (xy 316.025743 -57.6483)
			(xy 316.04625 -57.600765) (xy 316.072999 -57.556443) (xy 316.1055 -57.516147) (xy 316.143154 -57.480619)
			(xy 316.16396 -57.465214) (xy 316.175273 -57.456483) (xy 316.193025 -57.434108) (xy 316.20388 -57.407691)
			(xy 316.206988 -57.3793) (xy 316.202106 -57.351159) (xy 316.189616 -57.325474) (xy 316.170497 -57.304257)
			(xy 316.158626 -57.296304) (xy 316.135433 -57.28131) (xy 316.093281 -57.245626) (xy 316.056715 -57.204237)
			(xy 316.0265 -57.158007) (xy 316.003268 -57.107903) (xy 315.987504 -57.054973) (xy 315.979538 -57.000322)
			(xy 315.979048 -56.972708) (xy 315.979534 -56.945457) (xy 315.98729 -56.891509) (xy 316.002645 -56.839214)
			(xy 316.025287 -56.789637) (xy 316.054753 -56.743787) (xy 316.090444 -56.702596) (xy 316.131635 -56.666905)
			(xy 316.177485 -56.637439) (xy 316.227062 -56.614797) (xy 316.279357 -56.599442) (xy 316.333305 -56.591686)
			(xy 316.387807 -56.591686) (xy 316.441755 -56.599442) (xy 316.49405 -56.614797) (xy 316.543627 -56.637439)
			(xy 316.589477 -56.666905) (xy 316.630668 -56.702596) (xy 316.666359 -56.743787) (xy 316.695825 -56.789637)
			(xy 316.718467 -56.839214) (xy 316.733822 -56.891509) (xy 316.741578 -56.945457) (xy 316.742064 -56.972708)
			(xy 316.74163 -56.998591) (xy 316.734625 -57.049882) (xy 316.720744 -57.099752) (xy 316.700243 -57.147286)
			(xy 316.673499 -57.191609) (xy 316.641004 -57.231906) (xy 316.603355 -57.267435) (xy 316.582552 -57.282842)
			(xy 316.571181 -57.291504) (xy 316.553426 -57.313894) (xy 316.542573 -57.340327) (xy 316.539472 -57.368733)
			(xy 316.544365 -57.396886) (xy 316.55687 -57.422579) (xy 316.576007 -57.443799) (xy 316.587886 -57.451752)
			(xy 316.611061 -57.466772) (xy 316.653214 -57.502451) (xy 316.68978 -57.543836) (xy 316.719997 -57.590062)
			(xy 316.743232 -57.640162) (xy 316.759 -57.693088) (xy 316.766971 -57.747735) (xy 316.767464 -57.775348)
			(xy 316.766905 -57.804521) (xy 316.758015 -57.862187) (xy 316.740449 -57.917826) (xy 316.714617 -57.970143)
			(xy 316.681121 -58.017917) (xy 316.640742 -58.060035) (xy 316.594422 -58.095514) (xy 316.54324 -58.123528)
			(xy 316.516004 -58.133996) (xy 316.503509 -58.138942) (xy 316.481525 -58.154383) (xy 316.464329 -58.175023)
			(xy 316.45311 -58.199434) (xy 316.448646 -58.225926) (xy 316.451246 -58.252665) (xy 316.460729 -58.2778)
			(xy 316.468252 -58.288936) (xy 316.485235 -58.313425) (xy 316.51216 -58.366588) (xy 316.530495 -58.42329)
			(xy 316.539795 -58.482152) (xy 316.540388 -58.511948) (xy 316.539902 -58.539199) (xy 316.532965 -58.587449)
			(xy 317.992786 -58.587449) (xy 317.992786 -58.532951) (xy 318.000541 -58.479008) (xy 318.015894 -58.426718)
			(xy 318.038531 -58.377144) (xy 318.067993 -58.331297) (xy 318.10368 -58.290108) (xy 318.144864 -58.254417)
			(xy 318.190709 -58.224951) (xy 318.24028 -58.202308) (xy 318.292569 -58.186949) (xy 318.346511 -58.179188)
			(xy 318.37376 -58.1787) (xy 318.403128 -58.179226) (xy 318.461174 -58.188197) (xy 318.517152 -58.20598)
			(xy 318.543686 -58.218578) (xy 318.556591 -58.224561) (xy 318.584552 -58.229747) (xy 318.612858 -58.227016)
			(xy 318.639312 -58.216579) (xy 318.661858 -58.199247) (xy 318.678745 -58.176367) (xy 318.684148 -58.163206)
			(xy 318.69479 -58.136236) (xy 318.722961 -58.085567) (xy 318.758475 -58.039743) (xy 318.800515 -57.999821)
			(xy 318.848111 -57.966721) (xy 318.900168 -57.941203) (xy 318.955486 -57.923857) (xy 319.012793 -57.915081)
			(xy 319.04178 -57.91454) (xy 319.069037 -57.914906) (xy 319.122997 -57.922661) (xy 319.175304 -57.938017)
			(xy 319.224893 -57.960662) (xy 319.270754 -57.990133) (xy 319.311955 -58.025831) (xy 319.347655 -58.06703)
			(xy 319.377129 -58.112889) (xy 319.399776 -58.162477) (xy 319.415135 -58.214783) (xy 319.422893 -58.268743)
			(xy 319.422893 -58.323257) (xy 319.415135 -58.377217) (xy 319.399776 -58.429523) (xy 319.377129 -58.479111)
			(xy 319.347655 -58.52497) (xy 319.311955 -58.566169) (xy 319.270754 -58.601867) (xy 319.224893 -58.631338)
			(xy 319.175304 -58.653983) (xy 319.122997 -58.669339) (xy 319.069037 -58.677094) (xy 319.04178 -58.677556)
			(xy 319.012411 -58.677047) (xy 318.954365 -58.668068) (xy 318.898387 -58.650279) (xy 318.871854 -58.637678)
			(xy 318.85892 -58.631766) (xy 318.830973 -58.626576) (xy 318.802678 -58.629298) (xy 318.776233 -58.639721)
			(xy 318.75369 -58.657035) (xy 318.736799 -58.679898) (xy 318.731392 -58.69305) (xy 318.720831 -58.720053)
			(xy 318.692646 -58.770723) (xy 318.65712 -58.816546) (xy 318.615068 -58.856465) (xy 318.567461 -58.889561)
			(xy 318.515393 -58.915073) (xy 318.460065 -58.932412) (xy 318.402751 -58.941179) (xy 318.37376 -58.941716)
			(xy 318.346511 -58.941212) (xy 318.292569 -58.933451) (xy 318.24028 -58.918092) (xy 318.190709 -58.895449)
			(xy 318.144864 -58.865983) (xy 318.10368 -58.830292) (xy 318.067993 -58.789103) (xy 318.038531 -58.743256)
			(xy 318.015894 -58.693682) (xy 318.000541 -58.641392) (xy 317.992786 -58.587449) (xy 316.532965 -58.587449)
			(xy 316.532146 -58.593147) (xy 316.516791 -58.645442) (xy 316.494149 -58.695019) (xy 316.464683 -58.740869)
			(xy 316.428992 -58.78206) (xy 316.387801 -58.817751) (xy 316.341951 -58.847217) (xy 316.292374 -58.869859)
			(xy 316.240079 -58.885214) (xy 316.186131 -58.89297) (xy 316.131629 -58.89297) (xy 316.077681 -58.885214)
			(xy 316.025386 -58.869859) (xy 315.975809 -58.847217) (xy 315.929959 -58.817751) (xy 315.888768 -58.78206)
			(xy 315.853077 -58.740869) (xy 315.823611 -58.695019) (xy 315.800969 -58.645442) (xy 315.785614 -58.593147)
			(xy 315.777858 -58.539199) (xy 315.777372 -58.511948) (xy 302.1076 -58.511948) (xy 302.1076 -59.446668)
			(xy 315.993778 -59.446668) (xy 315.997849 -59.391046) (xy 316.009975 -59.336609) (xy 316.029898 -59.284518)
			(xy 316.057194 -59.235883) (xy 316.09128 -59.19174) (xy 316.131429 -59.153031) (xy 316.176787 -59.12058)
			(xy 316.226387 -59.095079) (xy 316.279171 -59.077072) (xy 316.334014 -59.066942) (xy 316.389748 -59.064905)
			(xy 316.445185 -59.071005) (xy 316.499142 -59.085111) (xy 316.550471 -59.106923) (xy 316.598077 -59.135977)
			(xy 316.640945 -59.171652) (xy 316.678162 -59.213189) (xy 316.708935 -59.259702) (xy 316.732607 -59.310199)
			(xy 316.748675 -59.363606) (xy 316.749909 -59.371992) (xy 326.755504 -59.371992) (xy 326.759575 -59.31637)
			(xy 326.771701 -59.261933) (xy 326.791624 -59.209842) (xy 326.81892 -59.161207) (xy 326.853006 -59.117064)
			(xy 326.893155 -59.078355) (xy 326.938513 -59.045904) (xy 326.988113 -59.020403) (xy 327.040897 -59.002396)
			(xy 327.09574 -58.992266) (xy 327.151474 -58.990229) (xy 327.206911 -58.996329) (xy 327.260868 -59.010435)
			(xy 327.312197 -59.032247) (xy 327.359803 -59.061301) (xy 327.402671 -59.096976) (xy 327.439888 -59.138513)
			(xy 327.470661 -59.185026) (xy 327.494333 -59.235523) (xy 327.510401 -59.28893) (xy 327.518521 -59.344106)
			(xy 327.51903 -59.371992) (xy 327.518521 -59.399878) (xy 327.510401 -59.455054) (xy 327.494333 -59.508461)
			(xy 327.470661 -59.558958) (xy 327.439888 -59.605471) (xy 327.402671 -59.647008) (xy 327.359803 -59.682683)
			(xy 327.312197 -59.711737) (xy 327.260868 -59.733549) (xy 327.206911 -59.747655) (xy 327.151474 -59.753755)
			(xy 327.09574 -59.751718) (xy 327.040897 -59.741588) (xy 326.988113 -59.723581) (xy 326.938513 -59.69808)
			(xy 326.893155 -59.665629) (xy 326.853006 -59.62692) (xy 326.81892 -59.582777) (xy 326.791624 -59.534142)
			(xy 326.771701 -59.482051) (xy 326.759575 -59.427614) (xy 326.755504 -59.371992) (xy 316.749909 -59.371992)
			(xy 316.756795 -59.418782) (xy 316.757304 -59.446668) (xy 316.756795 -59.474554) (xy 316.748675 -59.52973)
			(xy 316.732607 -59.583137) (xy 316.708935 -59.633634) (xy 316.678162 -59.680147) (xy 316.640945 -59.721684)
			(xy 316.598077 -59.757359) (xy 316.550471 -59.786413) (xy 316.499142 -59.808225) (xy 316.445185 -59.822331)
			(xy 316.389748 -59.828431) (xy 316.334014 -59.826394) (xy 316.279171 -59.816264) (xy 316.226387 -59.798257)
			(xy 316.176787 -59.772756) (xy 316.131429 -59.740305) (xy 316.09128 -59.701596) (xy 316.057194 -59.657453)
			(xy 316.029898 -59.608818) (xy 316.009975 -59.556727) (xy 315.997849 -59.50229) (xy 315.993778 -59.446668)
			(xy 302.1076 -59.446668) (xy 302.1076 -59.847988) (xy 318.098422 -59.847988) (xy 318.102493 -59.792366)
			(xy 318.114619 -59.737929) (xy 318.134542 -59.685838) (xy 318.161838 -59.637203) (xy 318.195924 -59.59306)
			(xy 318.236073 -59.554351) (xy 318.281431 -59.5219) (xy 318.331031 -59.496399) (xy 318.383815 -59.478392)
			(xy 318.438658 -59.468262) (xy 318.494392 -59.466225) (xy 318.549829 -59.472325) (xy 318.603786 -59.486431)
			(xy 318.655115 -59.508243) (xy 318.702721 -59.537297) (xy 318.745589 -59.572972) (xy 318.782806 -59.614509)
			(xy 318.813579 -59.661022) (xy 318.837251 -59.711519) (xy 318.853319 -59.764926) (xy 318.861439 -59.820102)
			(xy 318.861948 -59.847988) (xy 318.861439 -59.875874) (xy 318.853319 -59.93105) (xy 318.837251 -59.984457)
			(xy 318.813579 -60.034954) (xy 318.782806 -60.081467) (xy 318.745589 -60.123004) (xy 318.702721 -60.158679)
			(xy 318.655115 -60.187733) (xy 318.603786 -60.209545) (xy 318.549829 -60.223651) (xy 318.494392 -60.229751)
			(xy 318.438658 -60.227714) (xy 318.383815 -60.217584) (xy 318.331031 -60.199577) (xy 318.281431 -60.174076)
			(xy 318.236073 -60.141625) (xy 318.195924 -60.102916) (xy 318.161838 -60.058773) (xy 318.134542 -60.010138)
			(xy 318.114619 -59.958047) (xy 318.102493 -59.90361) (xy 318.098422 -59.847988) (xy 302.1076 -59.847988)
			(xy 302.1076 -60.315348) (xy 315.998604 -60.315348) (xy 316.002675 -60.259726) (xy 316.014801 -60.205289)
			(xy 316.034724 -60.153198) (xy 316.06202 -60.104563) (xy 316.096106 -60.06042) (xy 316.136255 -60.021711)
			(xy 316.181613 -59.98926) (xy 316.231213 -59.963759) (xy 316.283997 -59.945752) (xy 316.33884 -59.935622)
			(xy 316.394574 -59.933585) (xy 316.450011 -59.939685) (xy 316.503968 -59.953791) (xy 316.555297 -59.975603)
			(xy 316.602903 -60.004657) (xy 316.645771 -60.040332) (xy 316.682988 -60.081869) (xy 316.713761 -60.128382)
			(xy 316.737433 -60.178879) (xy 316.753501 -60.232286) (xy 316.761621 -60.287462) (xy 316.76213 -60.315348)
			(xy 316.761621 -60.343234) (xy 316.753501 -60.39841) (xy 316.737433 -60.451817) (xy 316.713761 -60.502314)
			(xy 316.682988 -60.548827) (xy 316.645771 -60.590364) (xy 316.602903 -60.626039) (xy 316.555297 -60.655093)
			(xy 316.503968 -60.676905) (xy 316.450011 -60.691011) (xy 316.394574 -60.697111) (xy 316.33884 -60.695074)
			(xy 316.283997 -60.684944) (xy 316.231213 -60.666937) (xy 316.181613 -60.641436) (xy 316.136255 -60.608985)
			(xy 316.096106 -60.570276) (xy 316.06202 -60.526133) (xy 316.034724 -60.477498) (xy 316.014801 -60.425407)
			(xy 316.002675 -60.37097) (xy 315.998604 -60.315348) (xy 302.1076 -60.315348) (xy 302.1076 -61.130688)
			(xy 303.107342 -61.130688) (xy 303.111413 -61.075066) (xy 303.123539 -61.020629) (xy 303.143462 -60.968538)
			(xy 303.170758 -60.919903) (xy 303.204844 -60.87576) (xy 303.244993 -60.837051) (xy 303.290351 -60.8046)
			(xy 303.339951 -60.779099) (xy 303.392735 -60.761092) (xy 303.447578 -60.750962) (xy 303.503312 -60.748925)
			(xy 303.558749 -60.755025) (xy 303.612706 -60.769131) (xy 303.638679 -60.780168) (xy 324.311262 -60.780168)
			(xy 324.315333 -60.724546) (xy 324.327459 -60.670109) (xy 324.347382 -60.618018) (xy 324.374678 -60.569383)
			(xy 324.408764 -60.52524) (xy 324.448913 -60.486531) (xy 324.494271 -60.45408) (xy 324.543871 -60.428579)
			(xy 324.596655 -60.410572) (xy 324.651498 -60.400442) (xy 324.707232 -60.398405) (xy 324.762669 -60.404505)
			(xy 324.816626 -60.418611) (xy 324.867955 -60.440423) (xy 324.915561 -60.469477) (xy 324.958429 -60.505152)
			(xy 324.995646 -60.546689) (xy 325.026419 -60.593202) (xy 325.050091 -60.643699) (xy 325.066159 -60.697106)
			(xy 325.074279 -60.752282) (xy 325.074788 -60.780168) (xy 325.074279 -60.808054) (xy 325.066159 -60.86323)
			(xy 325.050091 -60.916637) (xy 325.026419 -60.967134) (xy 324.995646 -61.013647) (xy 324.958429 -61.055184)
			(xy 324.936069 -61.073792) (xy 326.93178 -61.073792) (xy 326.935851 -61.01817) (xy 326.947977 -60.963733)
			(xy 326.9679 -60.911642) (xy 326.995196 -60.863007) (xy 327.029282 -60.818864) (xy 327.069431 -60.780155)
			(xy 327.114789 -60.747704) (xy 327.164389 -60.722203) (xy 327.217173 -60.704196) (xy 327.272016 -60.694066)
			(xy 327.32775 -60.692029) (xy 327.383187 -60.698129) (xy 327.437144 -60.712235) (xy 327.488473 -60.734047)
			(xy 327.536079 -60.763101) (xy 327.578947 -60.798776) (xy 327.616164 -60.840313) (xy 327.646937 -60.886826)
			(xy 327.670609 -60.937323) (xy 327.686677 -60.99073) (xy 327.694797 -61.045906) (xy 327.695306 -61.073792)
			(xy 327.694797 -61.101678) (xy 327.686677 -61.156854) (xy 327.670609 -61.210261) (xy 327.646937 -61.260758)
			(xy 327.616164 -61.307271) (xy 327.578947 -61.348808) (xy 327.536079 -61.384483) (xy 327.488473 -61.413537)
			(xy 327.437144 -61.435349) (xy 327.383187 -61.449455) (xy 327.32775 -61.455555) (xy 327.272016 -61.453518)
			(xy 327.217173 -61.443388) (xy 327.164389 -61.425381) (xy 327.114789 -61.39988) (xy 327.069431 -61.367429)
			(xy 327.029282 -61.32872) (xy 326.995196 -61.284577) (xy 326.9679 -61.235942) (xy 326.947977 -61.183851)
			(xy 326.935851 -61.129414) (xy 326.93178 -61.073792) (xy 324.936069 -61.073792) (xy 324.915561 -61.090859)
			(xy 324.867955 -61.119913) (xy 324.816626 -61.141725) (xy 324.762669 -61.155831) (xy 324.707232 -61.161931)
			(xy 324.651498 -61.159894) (xy 324.596655 -61.149764) (xy 324.543871 -61.131757) (xy 324.494271 -61.106256)
			(xy 324.448913 -61.073805) (xy 324.408764 -61.035096) (xy 324.374678 -60.990953) (xy 324.347382 -60.942318)
			(xy 324.327459 -60.890227) (xy 324.315333 -60.83579) (xy 324.311262 -60.780168) (xy 303.638679 -60.780168)
			(xy 303.664035 -60.790943) (xy 303.711641 -60.819997) (xy 303.754509 -60.855672) (xy 303.791726 -60.897209)
			(xy 303.822499 -60.943722) (xy 303.846171 -60.994219) (xy 303.862239 -61.047626) (xy 303.870359 -61.102802)
			(xy 303.870868 -61.130688) (xy 303.870359 -61.158574) (xy 303.862239 -61.21375) (xy 303.846171 -61.267157)
			(xy 303.822499 -61.317654) (xy 303.813439 -61.331348) (xy 315.998604 -61.331348) (xy 316.002675 -61.275726)
			(xy 316.014801 -61.221289) (xy 316.034724 -61.169198) (xy 316.06202 -61.120563) (xy 316.096106 -61.07642)
			(xy 316.136255 -61.037711) (xy 316.181613 -61.00526) (xy 316.231213 -60.979759) (xy 316.283997 -60.961752)
			(xy 316.33884 -60.951622) (xy 316.394574 -60.949585) (xy 316.450011 -60.955685) (xy 316.503968 -60.969791)
			(xy 316.555297 -60.991603) (xy 316.602903 -61.020657) (xy 316.645771 -61.056332) (xy 316.682988 -61.097869)
			(xy 316.713761 -61.144382) (xy 316.737433 -61.194879) (xy 316.753501 -61.248286) (xy 316.759744 -61.290708)
			(xy 318.227962 -61.290708) (xy 318.232033 -61.235086) (xy 318.244159 -61.180649) (xy 318.264082 -61.128558)
			(xy 318.291378 -61.079923) (xy 318.325464 -61.03578) (xy 318.365613 -60.997071) (xy 318.410971 -60.96462)
			(xy 318.460571 -60.939119) (xy 318.513355 -60.921112) (xy 318.568198 -60.910982) (xy 318.623932 -60.908945)
			(xy 318.679369 -60.915045) (xy 318.733326 -60.929151) (xy 318.784655 -60.950963) (xy 318.832261 -60.980017)
			(xy 318.875129 -61.015692) (xy 318.912346 -61.057229) (xy 318.943119 -61.103742) (xy 318.966791 -61.154239)
			(xy 318.982859 -61.207646) (xy 318.990979 -61.262822) (xy 318.991488 -61.290708) (xy 318.990979 -61.318594)
			(xy 318.982859 -61.37377) (xy 318.966791 -61.427177) (xy 318.943119 -61.477674) (xy 318.912346 -61.524187)
			(xy 318.875129 -61.565724) (xy 318.832261 -61.601399) (xy 318.784655 -61.630453) (xy 318.733326 -61.652265)
			(xy 318.679369 -61.666371) (xy 318.623932 -61.672471) (xy 318.568198 -61.670434) (xy 318.513355 -61.660304)
			(xy 318.460571 -61.642297) (xy 318.410971 -61.616796) (xy 318.365613 -61.584345) (xy 318.325464 -61.545636)
			(xy 318.291378 -61.501493) (xy 318.264082 -61.452858) (xy 318.244159 -61.400767) (xy 318.232033 -61.34633)
			(xy 318.227962 -61.290708) (xy 316.759744 -61.290708) (xy 316.761621 -61.303462) (xy 316.76213 -61.331348)
			(xy 316.761621 -61.359234) (xy 316.753501 -61.41441) (xy 316.737433 -61.467817) (xy 316.713761 -61.518314)
			(xy 316.682988 -61.564827) (xy 316.645771 -61.606364) (xy 316.602903 -61.642039) (xy 316.555297 -61.671093)
			(xy 316.503968 -61.692905) (xy 316.450011 -61.707011) (xy 316.394574 -61.713111) (xy 316.33884 -61.711074)
			(xy 316.283997 -61.700944) (xy 316.231213 -61.682937) (xy 316.181613 -61.657436) (xy 316.136255 -61.624985)
			(xy 316.096106 -61.586276) (xy 316.06202 -61.542133) (xy 316.034724 -61.493498) (xy 316.014801 -61.441407)
			(xy 316.002675 -61.38697) (xy 315.998604 -61.331348) (xy 303.813439 -61.331348) (xy 303.791726 -61.364167)
			(xy 303.754509 -61.405704) (xy 303.711641 -61.441379) (xy 303.664035 -61.470433) (xy 303.612706 -61.492245)
			(xy 303.558749 -61.506351) (xy 303.503312 -61.512451) (xy 303.447578 -61.510414) (xy 303.392735 -61.500284)
			(xy 303.339951 -61.482277) (xy 303.290351 -61.456776) (xy 303.244993 -61.424325) (xy 303.204844 -61.385616)
			(xy 303.170758 -61.341473) (xy 303.143462 -61.292838) (xy 303.123539 -61.240747) (xy 303.111413 -61.18631)
			(xy 303.107342 -61.130688) (xy 302.1076 -61.130688) (xy 302.1076 -62.775592) (xy 306.251862 -62.775592)
			(xy 306.255933 -62.71997) (xy 306.268059 -62.665533) (xy 306.287982 -62.613442) (xy 306.315278 -62.564807)
			(xy 306.349364 -62.520664) (xy 306.389513 -62.481955) (xy 306.434871 -62.449504) (xy 306.484471 -62.424003)
			(xy 306.537255 -62.405996) (xy 306.592098 -62.395866) (xy 306.647832 -62.393829) (xy 306.703269 -62.399929)
			(xy 306.757226 -62.414035) (xy 306.808555 -62.435847) (xy 306.856161 -62.464901) (xy 306.899029 -62.500576)
			(xy 306.936246 -62.542113) (xy 306.967019 -62.588626) (xy 306.990691 -62.639123) (xy 307.006759 -62.69253)
			(xy 307.014879 -62.747706) (xy 307.015388 -62.775592) (xy 307.014879 -62.803478) (xy 307.006759 -62.858654)
			(xy 306.990691 -62.912061) (xy 306.967019 -62.962558) (xy 306.936246 -63.009071) (xy 306.899029 -63.050608)
			(xy 306.856161 -63.086283) (xy 306.808555 -63.115337) (xy 306.757226 -63.137149) (xy 306.703269 -63.151255)
			(xy 306.647832 -63.157355) (xy 306.592098 -63.155318) (xy 306.537255 -63.145188) (xy 306.484471 -63.127181)
			(xy 306.434871 -63.10168) (xy 306.389513 -63.069229) (xy 306.349364 -63.03052) (xy 306.315278 -62.986377)
			(xy 306.287982 -62.937742) (xy 306.268059 -62.885651) (xy 306.255933 -62.831214) (xy 306.251862 -62.775592)
			(xy 302.1076 -62.775592) (xy 302.1076 -63.464948) (xy 308.919372 -63.464948) (xy 308.919886 -63.437123)
			(xy 308.927944 -63.38206) (xy 308.943924 -63.328754) (xy 308.967488 -63.278339) (xy 308.998133 -63.231887)
			(xy 309.035208 -63.190387) (xy 309.077925 -63.154719) (xy 309.125375 -63.125644) (xy 309.176549 -63.103779)
			(xy 309.23036 -63.089589) (xy 309.257954 -63.08598) (xy 309.271668 -63.083921) (xy 309.297357 -63.073518)
			(xy 309.319295 -63.05658) (xy 309.335861 -63.034359) (xy 309.34583 -63.008498) (xy 309.348465 -62.980908)
			(xy 309.343571 -62.953627) (xy 309.337964 -62.940946) (xy 309.326088 -62.915017) (xy 309.309331 -62.860506)
			(xy 309.300881 -62.804107) (xy 309.300372 -62.775592) (xy 309.300923 -62.747171) (xy 309.309338 -62.690956)
			(xy 309.326009 -62.636614) (xy 309.350566 -62.585352) (xy 309.382466 -62.538305) (xy 309.420999 -62.496519)
			(xy 309.465312 -62.460919) (xy 309.489602 -62.446154) (xy 309.502482 -62.438073) (xy 309.523103 -62.415744)
			(xy 309.536249 -62.388342) (xy 309.540762 -62.358285) (xy 309.536241 -62.328229) (xy 309.523085 -62.30083)
			(xy 309.502458 -62.278508) (xy 309.489602 -62.270386) (xy 309.465304 -62.255635) (xy 309.421007 -62.220018)
			(xy 309.382484 -62.178223) (xy 309.350588 -62.131175) (xy 309.326025 -62.079915) (xy 309.309339 -62.025579)
			(xy 309.300899 -61.969368) (xy 309.300372 -61.940948) (xy 309.300858 -61.913697) (xy 309.308614 -61.859749)
			(xy 309.323969 -61.807454) (xy 309.346611 -61.757877) (xy 309.376077 -61.712027) (xy 309.411768 -61.670836)
			(xy 309.452959 -61.635145) (xy 309.498809 -61.605679) (xy 309.548386 -61.583037) (xy 309.600681 -61.567682)
			(xy 309.654629 -61.559926) (xy 309.709131 -61.559926) (xy 309.763079 -61.567682) (xy 309.815374 -61.583037)
			(xy 309.864951 -61.605679) (xy 309.910801 -61.635145) (xy 309.951992 -61.670836) (xy 309.987683 -61.712027)
			(xy 310.017149 -61.757877) (xy 310.039791 -61.807454) (xy 310.055146 -61.859749) (xy 310.062902 -61.913697)
			(xy 310.063388 -61.940948) (xy 310.062888 -61.969371) (xy 310.054467 -62.025589) (xy 310.043805 -62.060328)
			(xy 312.545982 -62.060328) (xy 312.550053 -62.004706) (xy 312.562179 -61.950269) (xy 312.582102 -61.898178)
			(xy 312.609398 -61.849543) (xy 312.643484 -61.8054) (xy 312.683633 -61.766691) (xy 312.728991 -61.73424)
			(xy 312.778591 -61.708739) (xy 312.831375 -61.690732) (xy 312.886218 -61.680602) (xy 312.941952 -61.678565)
			(xy 312.997389 -61.684665) (xy 313.051346 -61.698771) (xy 313.102675 -61.720583) (xy 313.150281 -61.749637)
			(xy 313.193149 -61.785312) (xy 313.230366 -61.826849) (xy 313.261139 -61.873362) (xy 313.284811 -61.923859)
			(xy 313.300879 -61.977266) (xy 313.308999 -62.032442) (xy 313.309508 -62.060328) (xy 314.704982 -62.060328)
			(xy 314.709053 -62.004706) (xy 314.721179 -61.950269) (xy 314.741102 -61.898178) (xy 314.768398 -61.849543)
			(xy 314.802484 -61.8054) (xy 314.842633 -61.766691) (xy 314.887991 -61.73424) (xy 314.937591 -61.708739)
			(xy 314.990375 -61.690732) (xy 315.045218 -61.680602) (xy 315.100952 -61.678565) (xy 315.156389 -61.684665)
			(xy 315.210346 -61.698771) (xy 315.261675 -61.720583) (xy 315.309281 -61.749637) (xy 315.352149 -61.785312)
			(xy 315.389366 -61.826849) (xy 315.420139 -61.873362) (xy 315.443811 -61.923859) (xy 315.459879 -61.977266)
			(xy 315.467999 -62.032442) (xy 315.468508 -62.060328) (xy 315.467999 -62.088214) (xy 315.459879 -62.14339)
			(xy 315.457358 -62.151768) (xy 321.363592 -62.151768) (xy 321.367663 -62.096146) (xy 321.379789 -62.041709)
			(xy 321.399712 -61.989618) (xy 321.427008 -61.940983) (xy 321.461094 -61.89684) (xy 321.501243 -61.858131)
			(xy 321.546601 -61.82568) (xy 321.596201 -61.800179) (xy 321.648985 -61.782172) (xy 321.703828 -61.772042)
			(xy 321.759562 -61.770005) (xy 321.814999 -61.776105) (xy 321.868956 -61.790211) (xy 321.920285 -61.812023)
			(xy 321.967891 -61.841077) (xy 322.010759 -61.876752) (xy 322.047976 -61.918289) (xy 322.078749 -61.964802)
			(xy 322.102421 -62.015299) (xy 322.118489 -62.068706) (xy 322.126609 -62.123882) (xy 322.127118 -62.151768)
			(xy 322.126609 -62.179654) (xy 322.118489 -62.23483) (xy 322.102421 -62.288237) (xy 322.078749 -62.338734)
			(xy 322.047976 -62.385247) (xy 322.010759 -62.426784) (xy 321.967891 -62.462459) (xy 321.920285 -62.491513)
			(xy 321.868956 -62.513325) (xy 321.814999 -62.527431) (xy 321.759562 -62.533531) (xy 321.703828 -62.531494)
			(xy 321.648985 -62.521364) (xy 321.596201 -62.503357) (xy 321.546601 -62.477856) (xy 321.501243 -62.445405)
			(xy 321.461094 -62.406696) (xy 321.427008 -62.362553) (xy 321.399712 -62.313918) (xy 321.379789 -62.261827)
			(xy 321.367663 -62.20739) (xy 321.363592 -62.151768) (xy 315.457358 -62.151768) (xy 315.443811 -62.196797)
			(xy 315.420139 -62.247294) (xy 315.389366 -62.293807) (xy 315.352149 -62.335344) (xy 315.309281 -62.371019)
			(xy 315.261675 -62.400073) (xy 315.210346 -62.421885) (xy 315.156389 -62.435991) (xy 315.100952 -62.442091)
			(xy 315.045218 -62.440054) (xy 314.990375 -62.429924) (xy 314.937591 -62.411917) (xy 314.887991 -62.386416)
			(xy 314.842633 -62.353965) (xy 314.802484 -62.315256) (xy 314.768398 -62.271113) (xy 314.741102 -62.222478)
			(xy 314.721179 -62.170387) (xy 314.709053 -62.11595) (xy 314.704982 -62.060328) (xy 313.309508 -62.060328)
			(xy 313.308999 -62.088214) (xy 313.300879 -62.14339) (xy 313.284811 -62.196797) (xy 313.261139 -62.247294)
			(xy 313.230366 -62.293807) (xy 313.193149 -62.335344) (xy 313.150281 -62.371019) (xy 313.102675 -62.400073)
			(xy 313.051346 -62.421885) (xy 312.997389 -62.435991) (xy 312.941952 -62.442091) (xy 312.886218 -62.440054)
			(xy 312.831375 -62.429924) (xy 312.778591 -62.411917) (xy 312.728991 -62.386416) (xy 312.683633 -62.353965)
			(xy 312.643484 -62.315256) (xy 312.609398 -62.271113) (xy 312.582102 -62.222478) (xy 312.562179 -62.170387)
			(xy 312.550053 -62.11595) (xy 312.545982 -62.060328) (xy 310.043805 -62.060328) (xy 310.037788 -62.079933)
			(xy 310.013222 -62.131197) (xy 309.981315 -62.178243) (xy 309.942773 -62.220027) (xy 309.898452 -62.255623)
			(xy 309.874158 -62.270386) (xy 309.861328 -62.278544) (xy 309.8407 -62.300852) (xy 309.827543 -62.32824)
			(xy 309.823021 -62.358285) (xy 309.827534 -62.388332) (xy 309.840682 -62.415723) (xy 309.861304 -62.438037)
			(xy 309.874158 -62.446154) (xy 309.89842 -62.460961) (xy 309.942719 -62.496568) (xy 309.981246 -62.538353)
			(xy 310.013146 -62.585391) (xy 310.037715 -62.636642) (xy 310.044821 -62.659768) (xy 318.121282 -62.659768)
			(xy 318.125353 -62.604146) (xy 318.137479 -62.549709) (xy 318.157402 -62.497618) (xy 318.184698 -62.448983)
			(xy 318.218784 -62.40484) (xy 318.258933 -62.366131) (xy 318.304291 -62.33368) (xy 318.353891 -62.308179)
			(xy 318.406675 -62.290172) (xy 318.461518 -62.280042) (xy 318.517252 -62.278005) (xy 318.572689 -62.284105)
			(xy 318.626646 -62.298211) (xy 318.677975 -62.320023) (xy 318.725581 -62.349077) (xy 318.768449 -62.384752)
			(xy 318.805666 -62.426289) (xy 318.836439 -62.472802) (xy 318.860111 -62.523299) (xy 318.876179 -62.576706)
			(xy 318.884299 -62.631882) (xy 318.884808 -62.659768) (xy 318.884299 -62.687654) (xy 318.876179 -62.74283)
			(xy 318.860111 -62.796237) (xy 318.836439 -62.846734) (xy 318.805666 -62.893247) (xy 318.768449 -62.934784)
			(xy 318.725581 -62.970459) (xy 318.677975 -62.999513) (xy 318.626646 -63.021325) (xy 318.572689 -63.035431)
			(xy 318.517252 -63.041531) (xy 318.461518 -63.039494) (xy 318.406675 -63.029364) (xy 318.353891 -63.011357)
			(xy 318.304291 -62.985856) (xy 318.258933 -62.953405) (xy 318.218784 -62.914696) (xy 318.184698 -62.870553)
			(xy 318.157402 -62.821918) (xy 318.137479 -62.769827) (xy 318.125353 -62.71539) (xy 318.121282 -62.659768)
			(xy 310.044821 -62.659768) (xy 310.054408 -62.69097) (xy 310.062857 -62.747174) (xy 310.063388 -62.775592)
			(xy 310.062858 -62.803416) (xy 310.054797 -62.858476) (xy 310.038814 -62.911778) (xy 310.01525 -62.96219)
			(xy 309.984606 -63.008639) (xy 309.947533 -63.050139) (xy 309.91617 -63.076328) (xy 312.545982 -63.076328)
			(xy 312.550053 -63.020706) (xy 312.562179 -62.966269) (xy 312.582102 -62.914178) (xy 312.609398 -62.865543)
			(xy 312.643484 -62.8214) (xy 312.683633 -62.782691) (xy 312.728991 -62.75024) (xy 312.778591 -62.724739)
			(xy 312.831375 -62.706732) (xy 312.886218 -62.696602) (xy 312.941952 -62.694565) (xy 312.997389 -62.700665)
			(xy 313.051346 -62.714771) (xy 313.102675 -62.736583) (xy 313.150281 -62.765637) (xy 313.193149 -62.801312)
			(xy 313.230366 -62.842849) (xy 313.261139 -62.889362) (xy 313.284811 -62.939859) (xy 313.300879 -62.993266)
			(xy 313.308999 -63.048442) (xy 313.309508 -63.076328) (xy 314.704982 -63.076328) (xy 314.709053 -63.020706)
			(xy 314.721179 -62.966269) (xy 314.741102 -62.914178) (xy 314.768398 -62.865543) (xy 314.802484 -62.8214)
			(xy 314.842633 -62.782691) (xy 314.887991 -62.75024) (xy 314.937591 -62.724739) (xy 314.990375 -62.706732)
			(xy 315.045218 -62.696602) (xy 315.100952 -62.694565) (xy 315.156389 -62.700665) (xy 315.210346 -62.714771)
			(xy 315.261675 -62.736583) (xy 315.309281 -62.765637) (xy 315.352149 -62.801312) (xy 315.389366 -62.842849)
			(xy 315.420139 -62.889362) (xy 315.443811 -62.939859) (xy 315.459879 -62.993266) (xy 315.467999 -63.048442)
			(xy 315.468508 -63.076328) (xy 315.467999 -63.104214) (xy 315.461524 -63.14821) (xy 316.324994 -63.14821)
			(xy 316.329065 -63.092588) (xy 316.341191 -63.038151) (xy 316.361114 -62.98606) (xy 316.38841 -62.937425)
			(xy 316.422496 -62.893282) (xy 316.462645 -62.854573) (xy 316.508003 -62.822122) (xy 316.557603 -62.796621)
			(xy 316.610387 -62.778614) (xy 316.66523 -62.768484) (xy 316.720964 -62.766447) (xy 316.776401 -62.772547)
			(xy 316.830358 -62.786653) (xy 316.881687 -62.808465) (xy 316.929293 -62.837519) (xy 316.972161 -62.873194)
			(xy 317.009378 -62.914731) (xy 317.040151 -62.961244) (xy 317.063823 -63.011741) (xy 317.079891 -63.065148)
			(xy 317.088011 -63.120324) (xy 317.08852 -63.14821) (xy 317.088011 -63.176096) (xy 317.079891 -63.231272)
			(xy 317.063823 -63.284679) (xy 317.040151 -63.335176) (xy 317.009378 -63.381689) (xy 316.972161 -63.423226)
			(xy 316.929293 -63.458901) (xy 316.881687 -63.487955) (xy 316.864101 -63.495428) (xy 320.944492 -63.495428)
			(xy 320.948563 -63.439806) (xy 320.960689 -63.385369) (xy 320.980612 -63.333278) (xy 321.007908 -63.284643)
			(xy 321.041994 -63.2405) (xy 321.082143 -63.201791) (xy 321.127501 -63.16934) (xy 321.177101 -63.143839)
			(xy 321.229885 -63.125832) (xy 321.284728 -63.115702) (xy 321.340462 -63.113665) (xy 321.395899 -63.119765)
			(xy 321.449856 -63.133871) (xy 321.501185 -63.155683) (xy 321.548791 -63.184737) (xy 321.591659 -63.220412)
			(xy 321.628876 -63.261949) (xy 321.659649 -63.308462) (xy 321.683321 -63.358959) (xy 321.699389 -63.412366)
			(xy 321.707509 -63.467542) (xy 321.708018 -63.495428) (xy 321.707509 -63.523314) (xy 321.699389 -63.57849)
			(xy 321.683321 -63.631897) (xy 321.659649 -63.682394) (xy 321.628876 -63.728907) (xy 321.591659 -63.770444)
			(xy 321.548791 -63.806119) (xy 321.501185 -63.835173) (xy 321.449856 -63.856985) (xy 321.395899 -63.871091)
			(xy 321.340462 -63.877191) (xy 321.284728 -63.875154) (xy 321.229885 -63.865024) (xy 321.177101 -63.847017)
			(xy 321.127501 -63.821516) (xy 321.082143 -63.789065) (xy 321.041994 -63.750356) (xy 321.007908 -63.706213)
			(xy 320.980612 -63.657578) (xy 320.960689 -63.605487) (xy 320.948563 -63.55105) (xy 320.944492 -63.495428)
			(xy 316.864101 -63.495428) (xy 316.830358 -63.509767) (xy 316.776401 -63.523873) (xy 316.720964 -63.529973)
			(xy 316.66523 -63.527936) (xy 316.610387 -63.517806) (xy 316.557603 -63.499799) (xy 316.508003 -63.474298)
			(xy 316.462645 -63.441847) (xy 316.422496 -63.403138) (xy 316.38841 -63.358995) (xy 316.361114 -63.31036)
			(xy 316.341191 -63.258269) (xy 316.329065 -63.203832) (xy 316.324994 -63.14821) (xy 315.461524 -63.14821)
			(xy 315.459879 -63.15939) (xy 315.443811 -63.212797) (xy 315.420139 -63.263294) (xy 315.389366 -63.309807)
			(xy 315.352149 -63.351344) (xy 315.309281 -63.387019) (xy 315.261675 -63.416073) (xy 315.210346 -63.437885)
			(xy 315.156389 -63.451991) (xy 315.100952 -63.458091) (xy 315.045218 -63.456054) (xy 314.990375 -63.445924)
			(xy 314.937591 -63.427917) (xy 314.887991 -63.402416) (xy 314.842633 -63.369965) (xy 314.802484 -63.331256)
			(xy 314.768398 -63.287113) (xy 314.741102 -63.238478) (xy 314.721179 -63.186387) (xy 314.709053 -63.13195)
			(xy 314.704982 -63.076328) (xy 313.309508 -63.076328) (xy 313.308999 -63.104214) (xy 313.300879 -63.15939)
			(xy 313.284811 -63.212797) (xy 313.261139 -63.263294) (xy 313.230366 -63.309807) (xy 313.193149 -63.351344)
			(xy 313.150281 -63.387019) (xy 313.102675 -63.416073) (xy 313.051346 -63.437885) (xy 312.997389 -63.451991)
			(xy 312.941952 -63.458091) (xy 312.886218 -63.456054) (xy 312.831375 -63.445924) (xy 312.778591 -63.427917)
			(xy 312.728991 -63.402416) (xy 312.683633 -63.369965) (xy 312.643484 -63.331256) (xy 312.609398 -63.287113)
			(xy 312.582102 -63.238478) (xy 312.562179 -63.186387) (xy 312.550053 -63.13195) (xy 312.545982 -63.076328)
			(xy 309.91617 -63.076328) (xy 309.90482 -63.085806) (xy 309.857374 -63.114883) (xy 309.806205 -63.136752)
			(xy 309.752399 -63.150947) (xy 309.724806 -63.15456) (xy 309.711087 -63.156603) (xy 309.685387 -63.166999)
			(xy 309.66344 -63.183936) (xy 309.64687 -63.206161) (xy 309.636901 -63.23203) (xy 309.634273 -63.259628)
			(xy 309.63918 -63.286913) (xy 309.644796 -63.299594) (xy 309.65665 -63.325532) (xy 309.673416 -63.380039)
			(xy 309.681875 -63.436434) (xy 309.682388 -63.464948) (xy 309.681902 -63.492199) (xy 309.674146 -63.546147)
			(xy 309.658791 -63.598442) (xy 309.636149 -63.648019) (xy 309.606683 -63.693869) (xy 309.570992 -63.73506)
			(xy 309.529801 -63.770751) (xy 309.483951 -63.800217) (xy 309.434374 -63.822859) (xy 309.382079 -63.838214)
			(xy 309.328131 -63.84597) (xy 309.273629 -63.84597) (xy 309.219681 -63.838214) (xy 309.167386 -63.822859)
			(xy 309.117809 -63.800217) (xy 309.071959 -63.770751) (xy 309.030768 -63.73506) (xy 308.995077 -63.693869)
			(xy 308.965611 -63.648019) (xy 308.942969 -63.598442) (xy 308.927614 -63.546147) (xy 308.919858 -63.492199)
			(xy 308.919372 -63.464948) (xy 302.1076 -63.464948) (xy 302.1076 -64.127147) (xy 303.585926 -64.127147)
			(xy 303.585926 -64.072653) (xy 303.593681 -64.018714) (xy 303.609033 -63.966427) (xy 303.63167 -63.916858)
			(xy 303.661131 -63.871014) (xy 303.696816 -63.82983) (xy 303.737998 -63.794143) (xy 303.78384 -63.76468)
			(xy 303.833409 -63.74204) (xy 303.885694 -63.726685) (xy 303.939633 -63.718928) (xy 303.96688 -63.71844)
			(xy 303.995797 -63.718958) (xy 304.052969 -63.727685) (xy 304.108169 -63.744942) (xy 304.160131 -63.770333)
			(xy 304.207664 -63.803278) (xy 304.24968 -63.84302) (xy 304.26787 -63.865506) (xy 304.277767 -63.877311)
			(xy 304.303091 -63.89483) (xy 304.332484 -63.904006) (xy 304.363276 -63.904006) (xy 304.392669 -63.89483)
			(xy 304.417993 -63.877311) (xy 304.42789 -63.865506) (xy 304.446088 -63.843029) (xy 304.488106 -63.803293)
			(xy 304.53564 -63.770353) (xy 304.5876 -63.744963) (xy 304.642796 -63.727706) (xy 304.699964 -63.718976)
			(xy 304.72888 -63.71844) (xy 304.756137 -63.718806) (xy 304.810097 -63.726561) (xy 304.862404 -63.741917)
			(xy 304.911993 -63.764562) (xy 304.957854 -63.794033) (xy 304.999055 -63.829731) (xy 305.034755 -63.87093)
			(xy 305.064229 -63.916789) (xy 305.086876 -63.966377) (xy 305.102235 -64.018683) (xy 305.105154 -64.038988)
			(xy 318.757298 -64.038988) (xy 318.761369 -63.983366) (xy 318.773495 -63.928929) (xy 318.793418 -63.876838)
			(xy 318.820714 -63.828203) (xy 318.8548 -63.78406) (xy 318.894949 -63.745351) (xy 318.940307 -63.7129)
			(xy 318.989907 -63.687399) (xy 319.042691 -63.669392) (xy 319.097534 -63.659262) (xy 319.153268 -63.657225)
			(xy 319.208705 -63.663325) (xy 319.262662 -63.677431) (xy 319.313991 -63.699243) (xy 319.361597 -63.728297)
			(xy 319.404465 -63.763972) (xy 319.441682 -63.805509) (xy 319.472455 -63.852022) (xy 319.496127 -63.902519)
			(xy 319.512195 -63.955926) (xy 319.520315 -64.011102) (xy 319.520824 -64.038988) (xy 319.520315 -64.066874)
			(xy 319.512195 -64.12205) (xy 319.496127 -64.175457) (xy 319.472455 -64.225954) (xy 319.441682 -64.272467)
			(xy 319.414815 -64.302453) (xy 324.698563 -64.302453) (xy 324.698563 -64.247947) (xy 324.706321 -64.193996)
			(xy 324.721677 -64.141698) (xy 324.74432 -64.092118) (xy 324.773789 -64.046265) (xy 324.809483 -64.005073)
			(xy 324.850677 -63.96938) (xy 324.89653 -63.939913) (xy 324.946111 -63.917272) (xy 324.99841 -63.901918)
			(xy 325.052361 -63.894162) (xy 325.079614 -63.8937) (xy 325.108205 -63.894233) (xy 325.164746 -63.902768)
			(xy 325.219375 -63.91966) (xy 325.270865 -63.944528) (xy 325.294752 -63.960248) (xy 325.307244 -63.968192)
			(xy 325.335418 -63.977232) (xy 325.365002 -63.977815) (xy 325.39351 -63.969892) (xy 325.418551 -63.954128)
			(xy 325.438021 -63.931847) (xy 325.444612 -63.918592) (xy 325.455469 -63.895672) (xy 325.482403 -63.852697)
			(xy 325.514806 -63.81368) (xy 325.552103 -63.779312) (xy 325.572628 -63.764414) (xy 325.583496 -63.756324)
			(xy 325.600754 -63.735448) (xy 325.611927 -63.710772) (xy 325.616229 -63.684029) (xy 325.61336 -63.657095)
			(xy 325.60352 -63.631858) (xy 325.5874 -63.610091) (xy 325.56613 -63.593319) (xy 325.553832 -63.58763)
			(xy 325.528289 -63.576337) (xy 325.480571 -63.547317) (xy 325.437594 -63.51165) (xy 325.400276 -63.470098)
			(xy 325.369416 -63.423548) (xy 325.345673 -63.372997) (xy 325.329555 -63.319524) (xy 325.321404 -63.264273)
			(xy 325.320914 -63.236348) (xy 325.3214 -63.209097) (xy 325.329156 -63.155149) (xy 325.344511 -63.102854)
			(xy 325.367153 -63.053277) (xy 325.396619 -63.007427) (xy 325.43231 -62.966236) (xy 325.473501 -62.930545)
			(xy 325.519351 -62.901079) (xy 325.568928 -62.878437) (xy 325.621223 -62.863082) (xy 325.675171 -62.855326)
			(xy 325.729673 -62.855326) (xy 325.783621 -62.863082) (xy 325.835916 -62.878437) (xy 325.840976 -62.880748)
			(xy 327.352404 -62.880748) (xy 327.356475 -62.825126) (xy 327.368601 -62.770689) (xy 327.388524 -62.718598)
			(xy 327.41582 -62.669963) (xy 327.449906 -62.62582) (xy 327.490055 -62.587111) (xy 327.535413 -62.55466)
			(xy 327.585013 -62.529159) (xy 327.637797 -62.511152) (xy 327.69264 -62.501022) (xy 327.748374 -62.498985)
			(xy 327.803811 -62.505085) (xy 327.857768 -62.519191) (xy 327.909097 -62.541003) (xy 327.956703 -62.570057)
			(xy 327.999571 -62.605732) (xy 328.036788 -62.647269) (xy 328.067561 -62.693782) (xy 328.091233 -62.744279)
			(xy 328.107301 -62.797686) (xy 328.115421 -62.852862) (xy 328.11593 -62.880748) (xy 328.115421 -62.908634)
			(xy 328.107301 -62.96381) (xy 328.091233 -63.017217) (xy 328.067561 -63.067714) (xy 328.036788 -63.114227)
			(xy 327.999571 -63.155764) (xy 327.956703 -63.191439) (xy 327.909097 -63.220493) (xy 327.857768 -63.242305)
			(xy 327.803811 -63.256411) (xy 327.748374 -63.262511) (xy 327.69264 -63.260474) (xy 327.637797 -63.250344)
			(xy 327.585013 -63.232337) (xy 327.535413 -63.206836) (xy 327.490055 -63.174385) (xy 327.449906 -63.135676)
			(xy 327.41582 -63.091533) (xy 327.388524 -63.042898) (xy 327.368601 -62.990807) (xy 327.356475 -62.93637)
			(xy 327.352404 -62.880748) (xy 325.840976 -62.880748) (xy 325.885493 -62.901079) (xy 325.931343 -62.930545)
			(xy 325.972534 -62.966236) (xy 326.008225 -63.007427) (xy 326.037691 -63.053277) (xy 326.060333 -63.102854)
			(xy 326.075688 -63.155149) (xy 326.083444 -63.209097) (xy 326.08393 -63.236348) (xy 326.083479 -63.262481)
			(xy 326.079388 -63.292228) (xy 326.188322 -63.292228) (xy 326.192393 -63.236606) (xy 326.204519 -63.182169)
			(xy 326.224442 -63.130078) (xy 326.251738 -63.081443) (xy 326.285824 -63.0373) (xy 326.325973 -62.998591)
			(xy 326.371331 -62.96614) (xy 326.420931 -62.940639) (xy 326.473715 -62.922632) (xy 326.528558 -62.912502)
			(xy 326.584292 -62.910465) (xy 326.639729 -62.916565) (xy 326.693686 -62.930671) (xy 326.745015 -62.952483)
			(xy 326.792621 -62.981537) (xy 326.835489 -63.017212) (xy 326.872706 -63.058749) (xy 326.903479 -63.105262)
			(xy 326.927151 -63.155759) (xy 326.943219 -63.209166) (xy 326.951339 -63.264342) (xy 326.951848 -63.292228)
			(xy 326.951339 -63.320114) (xy 326.943219 -63.37529) (xy 326.927151 -63.428697) (xy 326.903479 -63.479194)
			(xy 326.872706 -63.525707) (xy 326.835489 -63.567244) (xy 326.792621 -63.602919) (xy 326.745015 -63.631973)
			(xy 326.693686 -63.653785) (xy 326.639729 -63.667891) (xy 326.584292 -63.673991) (xy 326.528558 -63.671954)
			(xy 326.473715 -63.661824) (xy 326.420931 -63.643817) (xy 326.371331 -63.618316) (xy 326.325973 -63.585865)
			(xy 326.285824 -63.547156) (xy 326.251738 -63.503013) (xy 326.224442 -63.454378) (xy 326.204519 -63.402287)
			(xy 326.192393 -63.34785) (xy 326.188322 -63.292228) (xy 326.079388 -63.292228) (xy 326.076358 -63.314258)
			(xy 326.062227 -63.364577) (xy 326.041353 -63.412492) (xy 326.014127 -63.457106) (xy 325.98106 -63.49758)
			(xy 325.942772 -63.533157) (xy 325.921624 -63.548514) (xy 325.910842 -63.556706) (xy 325.893594 -63.577564)
			(xy 325.882426 -63.602218) (xy 325.878119 -63.628939) (xy 325.880976 -63.655853) (xy 325.890797 -63.681074)
			(xy 325.906893 -63.702834) (xy 325.928135 -63.719606) (xy 325.94042 -63.725298) (xy 325.965956 -63.736664)
			(xy 326.013728 -63.76568) (xy 326.056756 -63.801354) (xy 326.094119 -63.842923) (xy 326.125019 -63.889498)
			(xy 326.148794 -63.940083) (xy 326.164936 -63.993594) (xy 326.173099 -64.048888) (xy 326.173592 -64.076834)
			(xy 326.173592 -64.940434) (xy 326.173107 -64.967703) (xy 326.165342 -65.021685) (xy 326.149974 -65.074013)
			(xy 326.127316 -65.123621) (xy 326.097829 -65.1695) (xy 326.062114 -65.210717) (xy 326.020897 -65.246431)
			(xy 325.975017 -65.275918) (xy 325.925409 -65.298575) (xy 325.873081 -65.313943) (xy 325.819099 -65.321708)
			(xy 325.79183 -65.322196) (xy 325.75978 -65.321509) (xy 325.69658 -65.310792) (xy 325.6661 -65.30086)
			(xy 325.65338 -65.296925) (xy 325.626837 -65.294976) (xy 325.600694 -65.299959) (xy 325.57673 -65.311536)
			(xy 325.556577 -65.328918) (xy 325.541607 -65.350923) (xy 325.536814 -65.363344) (xy 325.527796 -65.387932)
			(xy 325.503939 -65.434556) (xy 325.473928 -65.477478) (xy 325.438327 -65.51589) (xy 325.397804 -65.549069)
			(xy 325.353124 -65.576393) (xy 325.305125 -65.597346) (xy 325.25471 -65.611535) (xy 325.202829 -65.618693)
			(xy 325.176642 -65.619122) (xy 325.149388 -65.618634) (xy 325.095435 -65.610882) (xy 325.043134 -65.59553)
			(xy 324.99355 -65.572891) (xy 324.947693 -65.543425) (xy 324.906497 -65.507732) (xy 324.8708 -65.46654)
			(xy 324.84133 -65.420687) (xy 324.818685 -65.371106) (xy 324.803327 -65.318806) (xy 324.795569 -65.264854)
			(xy 324.795569 -65.210346) (xy 324.803327 -65.156394) (xy 324.818685 -65.104094) (xy 324.84133 -65.054513)
			(xy 324.8708 -65.00866) (xy 324.906497 -64.967468) (xy 324.947693 -64.931775) (xy 324.99355 -64.902309)
			(xy 325.043134 -64.87967) (xy 325.095435 -64.864318) (xy 325.149388 -64.856566) (xy 325.176642 -64.856106)
			(xy 325.203022 -64.85656) (xy 325.25528 -64.863819) (xy 325.280782 -64.870584) (xy 325.293802 -64.873898)
			(xy 325.320662 -64.874207) (xy 325.346673 -64.867505) (xy 325.370038 -64.854253) (xy 325.38914 -64.835369)
			(xy 325.402659 -64.812157) (xy 325.40966 -64.786225) (xy 325.410068 -64.772794) (xy 325.410068 -64.700658)
			(xy 325.409568 -64.685663) (xy 325.400821 -64.656975) (xy 325.384123 -64.632061) (xy 325.360912 -64.613068)
			(xy 325.333186 -64.601631) (xy 325.303335 -64.598735) (xy 325.273928 -64.60463) (xy 325.260462 -64.61125)
			(xy 325.232491 -64.625567) (xy 325.17302 -64.645845) (xy 325.111031 -64.656099) (xy 325.079614 -64.656716)
			(xy 325.052361 -64.656238) (xy 324.99841 -64.648482) (xy 324.946111 -64.633128) (xy 324.89653 -64.610487)
			(xy 324.850677 -64.58102) (xy 324.809483 -64.545327) (xy 324.773789 -64.504135) (xy 324.74432 -64.458282)
			(xy 324.721677 -64.408702) (xy 324.706321 -64.356404) (xy 324.698563 -64.302453) (xy 319.414815 -64.302453)
			(xy 319.404465 -64.314004) (xy 319.361597 -64.349679) (xy 319.313991 -64.378733) (xy 319.262662 -64.400545)
			(xy 319.208705 -64.414651) (xy 319.153268 -64.420751) (xy 319.097534 -64.418714) (xy 319.042691 -64.408584)
			(xy 318.989907 -64.390577) (xy 318.940307 -64.365076) (xy 318.894949 -64.332625) (xy 318.8548 -64.293916)
			(xy 318.820714 -64.249773) (xy 318.793418 -64.201138) (xy 318.773495 -64.149047) (xy 318.761369 -64.09461)
			(xy 318.757298 -64.038988) (xy 305.105154 -64.038988) (xy 305.109993 -64.072643) (xy 305.109993 -64.127157)
			(xy 305.102235 -64.181117) (xy 305.086876 -64.233423) (xy 305.064229 -64.283011) (xy 305.034755 -64.32887)
			(xy 304.999055 -64.370069) (xy 304.957854 -64.405767) (xy 304.911993 -64.435238) (xy 304.862404 -64.457883)
			(xy 304.810097 -64.473239) (xy 304.756137 -64.480994) (xy 304.72888 -64.481456) (xy 304.699964 -64.480897)
			(xy 304.642794 -64.472178) (xy 304.587596 -64.45493) (xy 304.535633 -64.429546) (xy 304.488099 -64.396609)
			(xy 304.446081 -64.356873) (xy 304.42789 -64.33439) (xy 304.417993 -64.322585) (xy 304.392669 -64.305066)
			(xy 304.363276 -64.29589) (xy 304.332484 -64.29589) (xy 304.303091 -64.305066) (xy 304.277767 -64.322585)
			(xy 304.26787 -64.33439) (xy 304.249693 -64.356886) (xy 304.207671 -64.396621) (xy 304.160133 -64.429559)
			(xy 304.108169 -64.454945) (xy 304.052969 -64.472198) (xy 303.995797 -64.480923) (xy 303.96688 -64.481456)
			(xy 303.939633 -64.480872) (xy 303.885694 -64.473115) (xy 303.833409 -64.45776) (xy 303.78384 -64.43512)
			(xy 303.737998 -64.405657) (xy 303.696816 -64.36997) (xy 303.661131 -64.328786) (xy 303.63167 -64.282942)
			(xy 303.609033 -64.233373) (xy 303.593681 -64.181086) (xy 303.585926 -64.127147) (xy 302.1076 -64.127147)
			(xy 302.1076 -64.785748) (xy 303.16424 -65.842388)
		)
		(stroke
			(width 0)
			(type solid)
		)
		(fill yes)
		(layer "In13.Cu")
		(net "P3V3_AUX")
	)
	(gr_poly
		(pts
			(xy 42.009822 -440.610752) (xy 42.024717 -440.610245) (xy 42.053246 -440.60167) (xy 42.078086 -440.585228)
			(xy 42.097125 -440.562316) (xy 42.108743 -440.534886) (xy 42.11195 -440.505269) (xy 42.106474 -440.475987)
			(xy 42.092781 -440.449532) (xy 42.08272 -440.43854) (xy 42.062757 -440.417086) (xy 42.028988 -440.369192)
			(xy 42.002943 -440.316695) (xy 41.985237 -440.260833) (xy 41.976284 -440.202919) (xy 41.975786 -440.173618)
			(xy 41.976272 -440.146367) (xy 41.984028 -440.092419) (xy 41.999383 -440.040124) (xy 42.022025 -439.990547)
			(xy 42.051491 -439.944697) (xy 42.087182 -439.903506) (xy 42.128373 -439.867815) (xy 42.174223 -439.838349)
			(xy 42.2238 -439.815707) (xy 42.276095 -439.800352) (xy 42.330043 -439.792596) (xy 42.384545 -439.792596)
			(xy 42.438493 -439.800352) (xy 42.490788 -439.815707) (xy 42.540365 -439.838349) (xy 42.586215 -439.867815)
			(xy 42.627406 -439.903506) (xy 42.663097 -439.944697) (xy 42.692563 -439.990547) (xy 42.715205 -440.040124)
			(xy 42.73056 -440.092419) (xy 42.738316 -440.146367) (xy 42.738802 -440.173618) (xy 42.738266 -440.202916)
			(xy 42.729308 -440.260825) (xy 42.711606 -440.316684) (xy 42.685574 -440.369181) (xy 42.651825 -440.417083)
			(xy 42.631868 -440.43854) (xy 42.62189 -440.449594) (xy 42.608236 -440.476042) (xy 42.602781 -440.505302)
			(xy 42.605989 -440.534893) (xy 42.617588 -440.562305) (xy 42.636594 -440.585211) (xy 42.661394 -440.60167)
			(xy 42.689884 -440.610284) (xy 42.704766 -440.610752) (xy 52.850034 -440.610752) (xy 54.883812 -438.576974)
			(xy 54.883812 -432.576224) (xy 54.005226 -431.697638) (xy 52.647342 -431.697638) (xy 52.632465 -431.698149)
			(xy 52.603972 -431.706721) (xy 52.579163 -431.723149) (xy 52.560149 -431.746035) (xy 52.548546 -431.773434)
			(xy 52.54534 -431.803015) (xy 52.550805 -431.832264) (xy 52.557172 -431.84572) (xy 52.570457 -431.872868)
			(xy 52.58924 -431.930314) (xy 52.598749 -431.989999) (xy 52.599336 -432.020218) (xy 52.59885 -432.047469)
			(xy 52.591094 -432.101417) (xy 52.575739 -432.153712) (xy 52.553097 -432.203289) (xy 52.523631 -432.249139)
			(xy 52.48794 -432.29033) (xy 52.446749 -432.326021) (xy 52.400899 -432.355487) (xy 52.351322 -432.378129)
			(xy 52.299027 -432.393484) (xy 52.245079 -432.40124) (xy 52.190577 -432.40124) (xy 52.136629 -432.393484)
			(xy 52.084334 -432.378129) (xy 52.034757 -432.355487) (xy 51.988907 -432.326021) (xy 51.947716 -432.29033)
			(xy 51.912025 -432.249139) (xy 51.882559 -432.203289) (xy 51.859917 -432.153712) (xy 51.844562 -432.101417)
			(xy 51.836806 -432.047469) (xy 51.83632 -432.020218) (xy 51.836874 -431.989996) (xy 51.846373 -431.930305)
			(xy 51.865183 -431.872863) (xy 51.878484 -431.84572) (xy 51.884833 -431.832261) (xy 51.890256 -431.803015)
			(xy 51.88703 -431.773446) (xy 51.875428 -431.746057) (xy 51.856433 -431.723167) (xy 51.831653 -431.706715)
			(xy 51.803185 -431.698092) (xy 51.788314 -431.697638) (xy 35.8521 -431.697638) (xy 33.81883 -429.664368)
			(xy 33.81883 -402.246338) (xy 36.613846 -399.451322) (xy 36.603178 -399.421096) (xy 36.592868 -399.390167)
			(xy 36.581764 -399.325929) (xy 36.58108 -399.293334) (xy 36.58163 -399.264289) (xy 36.590448 -399.206872)
			(xy 36.607871 -399.151457) (xy 36.633495 -399.099324) (xy 36.666729 -399.05168) (xy 36.706802 -399.009625)
			(xy 36.752789 -398.974134) (xy 36.77793 -398.959578) (xy 36.79119 -398.951609) (xy 36.812524 -398.929223)
			(xy 36.8262 -398.901489) (xy 36.830971 -398.870936) (xy 36.826401 -398.840353) (xy 36.820094 -398.826228)
			(xy 36.807989 -398.800093) (xy 36.790896 -398.745091) (xy 36.782248 -398.688148) (xy 36.78174 -398.65935)
			(xy 36.782229 -398.632095) (xy 36.78999 -398.578139) (xy 36.805347 -398.525836) (xy 36.827987 -398.476249)
			(xy 36.857451 -398.430387) (xy 36.893139 -398.389182) (xy 36.934325 -398.353472) (xy 36.980171 -398.323984)
			(xy 37.029746 -398.301317) (xy 37.082041 -398.285933) (xy 37.135993 -398.278144) (xy 37.163248 -398.277588)
			(xy 38.026848 -398.277588) (xy 38.05411 -398.278055) (xy 38.108079 -398.285824) (xy 38.160391 -398.301197)
			(xy 38.209982 -398.323861) (xy 38.223802 -398.332749) (xy 47.218606 -398.332749) (xy 47.218606 -398.278251)
			(xy 47.226362 -398.224307) (xy 47.241716 -398.172016) (xy 47.264356 -398.122443) (xy 47.29382 -398.076596)
			(xy 47.329509 -398.035409) (xy 47.370696 -397.99972) (xy 47.416543 -397.970256) (xy 47.466116 -397.947616)
			(xy 47.518407 -397.932262) (xy 47.572351 -397.924506) (xy 47.5996 -397.92402) (xy 47.614652 -397.924192)
			(xy 47.644659 -397.926606) (xy 47.659544 -397.928846) (xy 47.673899 -397.930627) (xy 47.70258 -397.926951)
			(xy 47.729077 -397.915378) (xy 47.751265 -397.896837) (xy 47.76736 -397.872816) (xy 47.776071 -397.845245)
			(xy 47.776892 -397.830802) (xy 47.778042 -397.803997) (xy 47.786888 -397.751081) (xy 47.803056 -397.699925)
			(xy 47.826229 -397.651537) (xy 47.855949 -397.60687) (xy 47.89163 -397.566805) (xy 47.932571 -397.532132)
			(xy 47.977963 -397.503532) (xy 48.026912 -397.481571) (xy 48.078455 -397.466681) (xy 48.131575 -397.459154)
			(xy 48.1584 -397.458692) (xy 48.185651 -397.459178) (xy 48.239599 -397.466934) (xy 48.291894 -397.482289)
			(xy 48.341471 -397.504931) (xy 48.387321 -397.534397) (xy 48.428512 -397.570088) (xy 48.464203 -397.611279)
			(xy 48.493669 -397.657129) (xy 48.516311 -397.706706) (xy 48.531666 -397.759001) (xy 48.539422 -397.812949)
			(xy 48.539422 -397.867451) (xy 48.531666 -397.921399) (xy 48.516311 -397.973694) (xy 48.493669 -398.023271)
			(xy 48.464203 -398.069121) (xy 48.428512 -398.110312) (xy 48.387321 -398.146003) (xy 48.341471 -398.175469)
			(xy 48.291894 -398.198111) (xy 48.239599 -398.213466) (xy 48.185651 -398.221222) (xy 48.1584 -398.221708)
			(xy 48.143348 -398.221535) (xy 48.113341 -398.219122) (xy 48.098456 -398.216882) (xy 48.084096 -398.215171)
			(xy 48.055429 -398.218844) (xy 48.028942 -398.230408) (xy 48.006759 -398.248934) (xy 47.990661 -398.272937)
			(xy 47.981938 -398.30049) (xy 47.981108 -398.314926) (xy 47.979983 -398.341732) (xy 47.971134 -398.394649)
			(xy 47.954962 -398.445806) (xy 47.931786 -398.494194) (xy 47.902063 -398.53886) (xy 47.866379 -398.578924)
			(xy 47.825437 -398.613598) (xy 47.780043 -398.642196) (xy 47.731091 -398.664157) (xy 47.679547 -398.679048)
			(xy 47.626426 -398.686574) (xy 47.5996 -398.687036) (xy 47.572351 -398.686494) (xy 47.518407 -398.678738)
			(xy 47.466116 -398.663384) (xy 47.416543 -398.640744) (xy 47.370696 -398.61128) (xy 47.329509 -398.575591)
			(xy 47.29382 -398.534404) (xy 47.264356 -398.488557) (xy 47.241716 -398.438984) (xy 47.226362 -398.386693)
			(xy 47.218606 -398.332749) (xy 38.223802 -398.332749) (xy 38.255842 -398.353354) (xy 38.297036 -398.389075)
			(xy 38.332725 -398.430297) (xy 38.362182 -398.47618) (xy 38.384807 -398.525788) (xy 38.400139 -398.578113)
			(xy 38.407866 -398.632087) (xy 38.408356 -398.65935) (xy 38.406832 -398.695672) (xy 38.405951 -398.709779)
			(xy 38.411081 -398.737563) (xy 38.423627 -398.762879) (xy 38.442628 -398.78379) (xy 38.46663 -398.798695)
			(xy 38.493797 -398.806455) (xy 38.507924 -398.806924) (xy 40.204644 -398.806924) (xy 40.228019 -398.792261)
			(xy 40.278095 -398.769089) (xy 40.330986 -398.753368) (xy 40.385589 -398.745424) (xy 40.440767 -398.745424)
			(xy 40.49537 -398.753368) (xy 40.548261 -398.769089) (xy 40.598337 -398.792261) (xy 40.621712 -398.806924)
			(xy 42.102278 -398.806924) (xy 42.104056 -398.757902) (xy 42.105508 -398.731315) (xy 42.114864 -398.678899)
			(xy 42.131415 -398.628293) (xy 42.154838 -398.580477) (xy 42.184679 -398.536381) (xy 42.220359 -398.49686)
			(xy 42.261185 -398.462681) (xy 42.306365 -398.434509) (xy 42.355023 -398.412889) (xy 42.406213 -398.398241)
			(xy 42.458942 -398.39085) (xy 42.485564 -398.390364) (xy 43.349164 -398.390364) (xy 43.375787 -398.390824)
			(xy 43.428517 -398.398219) (xy 43.479707 -398.41287) (xy 43.528365 -398.434493) (xy 43.573545 -398.462669)
			(xy 43.614371 -398.49685) (xy 43.650051 -398.536373) (xy 43.679891 -398.580471) (xy 43.703314 -398.628289)
			(xy 43.719864 -398.678897) (xy 43.72922 -398.731315) (xy 43.730672 -398.757902) (xy 43.73245 -398.806924)
			(xy 48.380904 -398.806924) (xy 48.83277 -398.355058) (xy 48.83277 -395.916404) (xy 48.799242 -395.904212)
			(xy 48.773785 -395.894471) (xy 48.72594 -395.868366) (xy 48.682633 -395.835273) (xy 48.644877 -395.795964)
			(xy 48.613555 -395.75136) (xy 48.589399 -395.702501) (xy 48.572974 -395.650532) (xy 48.564663 -395.596665)
			(xy 48.564661 -395.542162) (xy 48.572967 -395.488295) (xy 48.589389 -395.436324) (xy 48.613541 -395.387464)
			(xy 48.64486 -395.342857) (xy 48.682613 -395.303545) (xy 48.725917 -395.270449) (xy 48.773761 -395.24434)
			(xy 48.799242 -395.234668) (xy 48.83277 -395.222476) (xy 48.83277 -387.458204) (xy 48.004222 -386.629656)
			(xy 40.51173 -386.629656) (xy 40.489257 -386.646602) (xy 40.440316 -386.674395) (xy 40.387819 -386.69469)
			(xy 40.33291 -386.707047) (xy 40.27678 -386.711196) (xy 40.22065 -386.707047) (xy 40.165741 -386.69469)
			(xy 40.113244 -386.674395) (xy 40.064303 -386.646602) (xy 40.04183 -386.629656) (xy 39.498524 -386.629656)
			(xy 39.476051 -386.646602) (xy 39.42711 -386.674395) (xy 39.374613 -386.69469) (xy 39.319704 -386.707047)
			(xy 39.263574 -386.711196) (xy 39.207444 -386.707047) (xy 39.152535 -386.69469) (xy 39.100038 -386.674395)
			(xy 39.051097 -386.646602) (xy 39.028624 -386.629656) (xy 36.328858 -386.629656) (xy 34.170112 -384.47091)
			(xy 34.170112 -382.056386) (xy 33.747964 -381.633984) (xy 33.724799 -381.610084) (xy 33.684279 -381.55728)
			(xy 33.651001 -381.499636) (xy 33.625535 -381.43814) (xy 33.608318 -381.373846) (xy 33.599643 -381.307854)
			(xy 33.59912 -381.274574) (xy 33.59912 -354.227384) (xy 33.599665 -354.194106) (xy 33.60835 -354.128119)
			(xy 33.625572 -354.063829) (xy 33.651034 -354.002336) (xy 33.684301 -353.94469) (xy 33.724805 -353.891878)
			(xy 33.747964 -353.867974) (xy 34.170112 -353.445572) (xy 34.170112 -334.73263) (xy 40.74795 -328.154792)
			(xy 40.758143 -328.143812) (xy 40.772219 -328.117383) (xy 40.778026 -328.088007) (xy 40.775065 -328.05821)
			(xy 40.76359 -328.030552) (xy 40.744588 -328.007409) (xy 40.719691 -327.990772) (xy 40.69104 -327.982069)
			(xy 40.676068 -327.981564) (xy 39.74338 -327.981564) (xy 39.701104 -327.981076) (xy 39.616913 -327.973274)
			(xy 39.5338 -327.957738) (xy 39.452476 -327.934599) (xy 39.373634 -327.904055) (xy 39.297946 -327.866367)
			(xy 39.226058 -327.821857) (xy 39.158584 -327.770903) (xy 39.0961 -327.71394) (xy 39.039137 -327.651456)
			(xy 38.988183 -327.583982) (xy 38.943673 -327.512094) (xy 38.905985 -327.436406) (xy 38.875441 -327.357564)
			(xy 38.852302 -327.27624) (xy 38.836766 -327.193127) (xy 38.828964 -327.108936) (xy 38.828964 -327.024384)
			(xy 38.836766 -326.940193) (xy 38.852302 -326.85708) (xy 38.875441 -326.775756) (xy 38.905985 -326.696914)
			(xy 38.943673 -326.621226) (xy 38.988183 -326.549338) (xy 39.039137 -326.481864) (xy 39.0961 -326.41938)
			(xy 39.158584 -326.362417) (xy 39.226058 -326.311463) (xy 39.297946 -326.266953) (xy 39.373634 -326.229265)
			(xy 39.452476 -326.198721) (xy 39.5338 -326.175582) (xy 39.616913 -326.160046) (xy 39.701104 -326.152244)
			(xy 39.74338 -326.151748) (xy 40.98798 -326.151748) (xy 41.030385 -326.152222) (xy 41.114833 -326.160063)
			(xy 41.198192 -326.175687) (xy 41.279747 -326.198961) (xy 41.358797 -326.229685) (xy 41.434663 -326.267595)
			(xy 41.506695 -326.312365) (xy 41.574272 -326.363612) (xy 41.636815 -326.420894) (xy 41.693786 -326.48372)
			(xy 41.744697 -326.55155) (xy 41.78911 -326.623803) (xy 41.826643 -326.699856) (xy 41.856975 -326.779057)
			(xy 41.868852 -326.819768) (xy 41.873478 -326.834197) (xy 41.889848 -326.859676) (xy 41.912966 -326.879239)
			(xy 41.940802 -326.891169) (xy 41.970912 -326.894417) (xy 42.000652 -326.8887) (xy 42.027411 -326.874519)
			(xy 42.038524 -326.864218) (xy 45.248322 -323.65442) (xy 45.230467 -323.630736) (xy 45.20207 -323.578667)
			(xy 45.182709 -323.522607) (xy 45.172921 -323.464111) (xy 45.172376 -323.434456) (xy 45.172928 -323.406475)
			(xy 45.181689 -323.351202) (xy 45.198987 -323.29798) (xy 45.224397 -323.248118) (xy 45.257294 -323.202845)
			(xy 45.296867 -323.163275) (xy 45.342142 -323.130382) (xy 45.392006 -323.104976) (xy 45.445229 -323.087682)
			(xy 45.500503 -323.078926) (xy 45.528484 -323.078348) (xy 45.553138 -323.078787) (xy 45.601969 -323.085632)
			(xy 45.649388 -323.099151) (xy 45.694487 -323.119086) (xy 45.715682 -323.131688) (xy 45.749972 -323.15277)
			(xy 45.970698 -322.932044) (xy 48.56099 -322.932044) (xy 48.563276 -322.883784) (xy 48.564928 -322.858219)
			(xy 48.574646 -322.807921) (xy 48.591465 -322.759532) (xy 48.615039 -322.71405) (xy 48.644882 -322.672411)
			(xy 48.662336 -322.65366) (xy 48.672744 -322.642094) (xy 48.686625 -322.614263) (xy 48.69147 -322.583543)
			(xy 48.686831 -322.552791) (xy 48.673139 -322.524868) (xy 48.662844 -322.513198) (xy 48.644673 -322.49325)
			(xy 48.613948 -322.448896) (xy 48.590267 -322.400414) (xy 48.574172 -322.348914) (xy 48.566032 -322.295574)
			(xy 48.565562 -322.268596) (xy 48.56606 -322.241947) (xy 48.574003 -322.189243) (xy 48.589713 -322.138313)
			(xy 48.612839 -322.090292) (xy 48.642863 -322.046255) (xy 48.679115 -322.007184) (xy 48.720786 -321.973953)
			(xy 48.766944 -321.947304) (xy 48.816558 -321.927832) (xy 48.86852 -321.915972) (xy 48.92167 -321.911989)
			(xy 48.97482 -321.915972) (xy 49.026782 -321.927832) (xy 49.076396 -321.947304) (xy 49.122554 -321.973953)
			(xy 49.164225 -322.007184) (xy 49.200477 -322.046255) (xy 49.230501 -322.090292) (xy 49.253627 -322.138313)
			(xy 49.269337 -322.189243) (xy 49.27728 -322.241947) (xy 49.277778 -322.268596) (xy 49.277281 -322.295896)
			(xy 49.268943 -322.349855) (xy 49.25246 -322.401907) (xy 49.228221 -322.450832) (xy 49.196794 -322.49548)
			(xy 49.17821 -322.515484) (xy 49.167798 -322.527053) (xy 49.153909 -322.554889) (xy 49.149051 -322.585616)
			(xy 49.153677 -322.616379) (xy 49.167357 -322.644319) (xy 49.177702 -322.655946) (xy 49.194741 -322.674643)
			(xy 49.22391 -322.715972) (xy 49.246941 -322.76101) (xy 49.263369 -322.808853) (xy 49.272866 -322.858539)
			(xy 49.274476 -322.883784) (xy 49.276762 -322.932044) (xy 52.03317 -322.932044) (xy 52.037742 -322.886324)
			(xy 52.040904 -322.86005) (xy 52.05399 -322.808776) (xy 52.074508 -322.759997) (xy 52.102007 -322.714785)
			(xy 52.135884 -322.674132) (xy 52.155344 -322.6562) (xy 52.165392 -322.646643) (xy 52.180384 -322.623328)
			(xy 52.188537 -322.596835) (xy 52.189245 -322.569125) (xy 52.182458 -322.54225) (xy 52.168677 -322.5182)
			(xy 52.159154 -322.508118) (xy 52.139504 -322.487908) (xy 52.106192 -322.442439) (xy 52.080451 -322.392295)
			(xy 52.06292 -322.338724) (xy 52.054038 -322.283063) (xy 52.05349 -322.25488) (xy 52.053988 -322.228231)
			(xy 52.061931 -322.175527) (xy 52.077641 -322.124597) (xy 52.100767 -322.076576) (xy 52.130791 -322.032539)
			(xy 52.167043 -321.993468) (xy 52.208714 -321.960237) (xy 52.254872 -321.933588) (xy 52.304486 -321.914116)
			(xy 52.356448 -321.902256) (xy 52.409598 -321.898273) (xy 52.462748 -321.902256) (xy 52.51471 -321.914116)
			(xy 52.564324 -321.933588) (xy 52.610482 -321.960237) (xy 52.652153 -321.993468) (xy 52.688405 -322.032539)
			(xy 52.718429 -322.076576) (xy 52.741555 -322.124597) (xy 52.757265 -322.175527) (xy 52.765208 -322.228231)
			(xy 52.765706 -322.25488) (xy 52.765276 -322.279937) (xy 52.758248 -322.329556) (xy 52.744343 -322.377702)
			(xy 52.723835 -322.423427) (xy 52.697126 -322.465831) (xy 52.664744 -322.504077) (xy 52.646326 -322.521072)
			(xy 52.636268 -322.530626) (xy 52.621258 -322.553941) (xy 52.613093 -322.58044) (xy 52.612379 -322.60816)
			(xy 52.619168 -322.635045) (xy 52.632956 -322.659102) (xy 52.642516 -322.669154) (xy 52.659696 -322.686722)
			(xy 52.689554 -322.725746) (xy 52.713765 -322.768505) (xy 52.731867 -322.814186) (xy 52.743517 -322.861922)
			(xy 52.746402 -322.886324) (xy 52.750974 -322.932044) (xy 56.9468 -322.932044) (xy 60.12434 -319.75425)
			(xy 60.12434 -319.453006) (xy 60.124635 -319.419947) (xy 60.129086 -319.353979) (xy 60.13323 -319.32118)
			(xy 60.133738 -319.317878) (xy 60.133738 -319.131188) (xy 59.540902 -318.538352) (xy 59.020964 -318.538352)
			(xy 59.020964 -318.589406) (xy 59.020964 -318.59093) (xy 59.020478 -318.618181) (xy 59.012722 -318.672129)
			(xy 58.997367 -318.724424) (xy 58.974725 -318.774001) (xy 58.945259 -318.819851) (xy 58.909568 -318.861042)
			(xy 58.868377 -318.896733) (xy 58.822527 -318.926199) (xy 58.77295 -318.948841) (xy 58.720655 -318.964196)
			(xy 58.666707 -318.971952) (xy 58.612205 -318.971952) (xy 58.558257 -318.964196) (xy 58.505962 -318.948841)
			(xy 58.456385 -318.926199) (xy 58.410535 -318.896733) (xy 58.369344 -318.861042) (xy 58.333653 -318.819851)
			(xy 58.304187 -318.774001) (xy 58.281545 -318.724424) (xy 58.26619 -318.672129) (xy 58.258434 -318.618181)
			(xy 58.257948 -318.59093) (xy 58.257948 -318.538352) (xy 56.795924 -318.538352) (xy 56.780743 -318.538911)
			(xy 56.751724 -318.547839) (xy 56.726617 -318.564912) (xy 56.707647 -318.588618) (xy 56.696492 -318.616856)
			(xy 56.694142 -318.647127) (xy 56.700805 -318.676748) (xy 56.707786 -318.690244) (xy 56.722466 -318.717327)
			(xy 56.743309 -318.775292) (xy 56.75389 -318.835975) (xy 56.754522 -318.866774) (xy 56.754024 -318.893423)
			(xy 56.746081 -318.946127) (xy 56.730371 -318.997057) (xy 56.707245 -319.045078) (xy 56.677221 -319.089115)
			(xy 56.640969 -319.128186) (xy 56.599298 -319.161417) (xy 56.55314 -319.188066) (xy 56.503526 -319.207538)
			(xy 56.451564 -319.219398) (xy 56.398414 -319.223382) (xy 56.345264 -319.219398) (xy 56.293302 -319.207538)
			(xy 56.243688 -319.188066) (xy 56.19753 -319.161417) (xy 56.155859 -319.128186) (xy 56.119607 -319.089115)
			(xy 56.089583 -319.045078) (xy 56.066457 -318.997057) (xy 56.050747 -318.946127) (xy 56.042804 -318.893423)
			(xy 56.042306 -318.866774) (xy 56.042929 -318.835972) (xy 56.05348 -318.775279) (xy 56.074331 -318.717313)
			(xy 56.089042 -318.690244) (xy 56.096062 -318.676785) (xy 56.102665 -318.647174) (xy 56.100277 -318.61693)
			(xy 56.089109 -318.588722) (xy 56.070146 -318.56504) (xy 56.045063 -318.547974) (xy 56.016072 -318.539031)
			(xy 56.000904 -318.538352) (xy 49.252124 -318.538352) (xy 49.236943 -318.538911) (xy 49.207924 -318.547839)
			(xy 49.182817 -318.564912) (xy 49.163847 -318.588618) (xy 49.152692 -318.616856) (xy 49.150342 -318.647127)
			(xy 49.157005 -318.676748) (xy 49.163986 -318.690244) (xy 49.178666 -318.717327) (xy 49.199509 -318.775292)
			(xy 49.21009 -318.835975) (xy 49.210722 -318.866774) (xy 49.210224 -318.893423) (xy 49.202281 -318.946127)
			(xy 49.186571 -318.997057) (xy 49.163445 -319.045078) (xy 49.133421 -319.089115) (xy 49.097169 -319.128186)
			(xy 49.055498 -319.161417) (xy 49.00934 -319.188066) (xy 48.959726 -319.207538) (xy 48.907764 -319.219398)
			(xy 48.854614 -319.223382) (xy 48.801464 -319.219398) (xy 48.749502 -319.207538) (xy 48.699888 -319.188066)
			(xy 48.65373 -319.161417) (xy 48.612059 -319.128186) (xy 48.575807 -319.089115) (xy 48.545783 -319.045078)
			(xy 48.522657 -318.997057) (xy 48.506947 -318.946127) (xy 48.499004 -318.893423) (xy 48.498506 -318.866774)
			(xy 48.499129 -318.835972) (xy 48.50968 -318.775279) (xy 48.530531 -318.717313) (xy 48.545242 -318.690244)
			(xy 48.552262 -318.676785) (xy 48.558865 -318.647174) (xy 48.556477 -318.61693) (xy 48.545309 -318.588722)
			(xy 48.526346 -318.56504) (xy 48.501263 -318.547974) (xy 48.472272 -318.539031) (xy 48.457104 -318.538352)
			(xy 43.978068 -318.538352) (xy 43.964415 -318.538795) (xy 43.938086 -318.546039) (xy 43.914619 -318.560001)
			(xy 43.89569 -318.579682) (xy 43.882652 -318.603675) (xy 43.876439 -318.630266) (xy 43.877494 -318.657552)
			(xy 43.885741 -318.683584) (xy 43.900591 -318.706499) (xy 43.910504 -318.715898) (xy 43.929037 -318.732874)
			(xy 43.96162 -318.771142) (xy 43.988498 -318.81361) (xy 44.009138 -318.859436) (xy 44.023131 -318.907708)
			(xy 44.030197 -318.957468) (xy 44.030646 -318.982598) (xy 44.030148 -319.009247) (xy 44.022205 -319.061951)
			(xy 44.006495 -319.112881) (xy 43.983369 -319.160902) (xy 43.953345 -319.204939) (xy 43.917093 -319.24401)
			(xy 43.875422 -319.277241) (xy 43.829264 -319.30389) (xy 43.77965 -319.323362) (xy 43.727688 -319.335222)
			(xy 43.674538 -319.339206) (xy 43.621388 -319.335222) (xy 43.569426 -319.323362) (xy 43.519812 -319.30389)
			(xy 43.473654 -319.277241) (xy 43.431983 -319.24401) (xy 43.395731 -319.204939) (xy 43.365707 -319.160902)
			(xy 43.342581 -319.112881) (xy 43.326871 -319.061951) (xy 43.318928 -319.009247) (xy 43.31843 -318.982598)
			(xy 43.318862 -318.957468) (xy 43.32593 -318.907707) (xy 43.339925 -318.859434) (xy 43.36057 -318.813609)
			(xy 43.387453 -318.771143) (xy 43.420041 -318.732878) (xy 43.438572 -318.715898) (xy 43.448483 -318.706498)
			(xy 43.463348 -318.683594) (xy 43.471607 -318.657568) (xy 43.472667 -318.630283) (xy 43.466453 -318.603695)
			(xy 43.45341 -318.579706) (xy 43.434472 -318.560036) (xy 43.410995 -318.546093) (xy 43.384661 -318.538875)
			(xy 43.371008 -318.538352) (xy 41.708324 -318.538352) (xy 41.693143 -318.538911) (xy 41.664124 -318.547839)
			(xy 41.639017 -318.564912) (xy 41.620047 -318.588618) (xy 41.608892 -318.616856) (xy 41.606542 -318.647127)
			(xy 41.613205 -318.676748) (xy 41.620186 -318.690244) (xy 41.634866 -318.717327) (xy 41.655709 -318.775292)
			(xy 41.66629 -318.835975) (xy 41.666922 -318.866774) (xy 41.666424 -318.893423) (xy 41.658481 -318.946127)
			(xy 41.642771 -318.997057) (xy 41.619645 -319.045078) (xy 41.589621 -319.089115) (xy 41.553369 -319.128186)
			(xy 41.511698 -319.161417) (xy 41.46554 -319.188066) (xy 41.415926 -319.207538) (xy 41.363964 -319.219398)
			(xy 41.310814 -319.223382) (xy 41.257664 -319.219398) (xy 41.205702 -319.207538) (xy 41.156088 -319.188066)
			(xy 41.10993 -319.161417) (xy 41.068259 -319.128186) (xy 41.032007 -319.089115) (xy 41.001983 -319.045078)
			(xy 40.978857 -318.997057) (xy 40.963147 -318.946127) (xy 40.955204 -318.893423) (xy 40.954706 -318.866774)
			(xy 40.955329 -318.835972) (xy 40.96588 -318.775279) (xy 40.986731 -318.717313) (xy 41.001442 -318.690244)
			(xy 41.008462 -318.676785) (xy 41.015065 -318.647174) (xy 41.012677 -318.61693) (xy 41.001509 -318.588722)
			(xy 40.982546 -318.56504) (xy 40.957463 -318.547974) (xy 40.928472 -318.539031) (xy 40.913304 -318.538352)
			(xy 40.728138 -318.538352) (xy 40.725852 -318.538606) (xy 40.712672 -318.539709) (xy 40.686246 -318.540851)
			(xy 40.67302 -318.540892) (xy 40.63365 -318.540892) (xy 40.620424 -318.540858) (xy 40.593997 -318.539715)
			(xy 40.580818 -318.538606) (xy 40.578532 -318.538352) (xy 36.859972 -318.538352) (xy 36.845903 -318.538796)
			(xy 36.81883 -318.546467) (xy 36.794886 -318.561245) (xy 36.775891 -318.582005) (xy 36.763294 -318.607165)
			(xy 36.758053 -318.634811) (xy 36.760567 -318.662836) (xy 36.770644 -318.689108) (xy 36.778692 -318.700658)
			(xy 36.795353 -318.723918) (xy 36.821826 -318.774637) (xy 36.839861 -318.828933) (xy 36.848994 -318.885412)
			(xy 36.849558 -318.914018) (xy 36.84906 -318.940667) (xy 36.841117 -318.993371) (xy 36.825407 -319.044301)
			(xy 36.802281 -319.092322) (xy 36.772257 -319.136359) (xy 36.736005 -319.17543) (xy 36.694334 -319.208661)
			(xy 36.648176 -319.23531) (xy 36.598562 -319.254782) (xy 36.5466 -319.266642) (xy 36.49345 -319.270626)
			(xy 36.4403 -319.266642) (xy 36.388338 -319.254782) (xy 36.338724 -319.23531) (xy 36.292566 -319.208661)
			(xy 36.250895 -319.17543) (xy 36.214643 -319.136359) (xy 36.184619 -319.092322) (xy 36.161493 -319.044301)
			(xy 36.145783 -318.993371) (xy 36.13784 -318.940667) (xy 36.137342 -318.914018) (xy 36.137889 -318.885409)
			(xy 36.146998 -318.828922) (xy 36.165034 -318.774622) (xy 36.19153 -318.723909) (xy 36.208208 -318.700658)
			(xy 36.216258 -318.689119) (xy 36.226293 -318.662844) (xy 36.228778 -318.634829) (xy 36.223526 -318.607198)
			(xy 36.210934 -318.582049) (xy 36.191958 -318.561289) (xy 36.168039 -318.546494) (xy 36.14099 -318.538787)
			(xy 36.126928 -318.538352) (xy 34.164524 -318.538352) (xy 34.149343 -318.538911) (xy 34.120324 -318.547839)
			(xy 34.095217 -318.564912) (xy 34.076247 -318.588618) (xy 34.065092 -318.616856) (xy 34.062742 -318.647127)
			(xy 34.069405 -318.676748) (xy 34.076386 -318.690244) (xy 34.091066 -318.717327) (xy 34.111909 -318.775292)
			(xy 34.12249 -318.835975) (xy 34.123122 -318.866774) (xy 34.122624 -318.893423) (xy 34.114681 -318.946127)
			(xy 34.098971 -318.997057) (xy 34.075845 -319.045078) (xy 34.045821 -319.089115) (xy 34.009569 -319.128186)
			(xy 33.967898 -319.161417) (xy 33.92174 -319.188066) (xy 33.872126 -319.207538) (xy 33.820164 -319.219398)
			(xy 33.767014 -319.223382) (xy 33.713864 -319.219398) (xy 33.661902 -319.207538) (xy 33.612288 -319.188066)
			(xy 33.56613 -319.161417) (xy 33.524459 -319.128186) (xy 33.488207 -319.089115) (xy 33.458183 -319.045078)
			(xy 33.435057 -318.997057) (xy 33.419347 -318.946127) (xy 33.411404 -318.893423) (xy 33.410906 -318.866774)
			(xy 33.411529 -318.835972) (xy 33.42208 -318.775279) (xy 33.442931 -318.717313) (xy 33.457642 -318.690244)
			(xy 33.464662 -318.676785) (xy 33.471265 -318.647174) (xy 33.468877 -318.61693) (xy 33.457709 -318.588722)
			(xy 33.438746 -318.56504) (xy 33.413663 -318.547974) (xy 33.384672 -318.539031) (xy 33.369504 -318.538352)
			(xy 29.461206 -318.538352) (xy 29.447336 -318.538821) (xy 29.42062 -318.546292) (xy 29.396905 -318.560683)
			(xy 29.377943 -318.58093) (xy 29.365136 -318.605537) (xy 29.35943 -318.632684) (xy 29.35986 -318.646556)
			(xy 29.360622 -318.669416) (xy 29.360124 -318.696065) (xy 29.352181 -318.748769) (xy 29.336471 -318.799699)
			(xy 29.313345 -318.84772) (xy 29.283321 -318.891757) (xy 29.247069 -318.930828) (xy 29.205398 -318.964059)
			(xy 29.15924 -318.990708) (xy 29.109626 -319.01018) (xy 29.057664 -319.02204) (xy 29.004514 -319.026024)
			(xy 28.951364 -319.02204) (xy 28.899402 -319.01018) (xy 28.849788 -318.990708) (xy 28.80363 -318.964059)
			(xy 28.761959 -318.930828) (xy 28.725707 -318.891757) (xy 28.695683 -318.84772) (xy 28.672557 -318.799699)
			(xy 28.656847 -318.748769) (xy 28.648904 -318.696065) (xy 28.648406 -318.669416) (xy 28.649168 -318.646556)
			(xy 28.649595 -318.632691) (xy 28.643871 -318.605561) (xy 28.631055 -318.580973) (xy 28.612095 -318.560742)
			(xy 28.588388 -318.546361) (xy 28.561686 -318.538892) (xy 28.547822 -318.538352) (xy 26.620724 -318.538352)
			(xy 26.605543 -318.538911) (xy 26.576524 -318.547839) (xy 26.551417 -318.564912) (xy 26.532447 -318.588618)
			(xy 26.521292 -318.616856) (xy 26.518942 -318.647127) (xy 26.525605 -318.676748) (xy 26.532586 -318.690244)
			(xy 26.547266 -318.717327) (xy 26.568109 -318.775292) (xy 26.57869 -318.835975) (xy 26.579322 -318.866774)
			(xy 26.578824 -318.893423) (xy 26.570881 -318.946127) (xy 26.555171 -318.997057) (xy 26.532045 -319.045078)
			(xy 26.502021 -319.089115) (xy 26.465769 -319.128186) (xy 26.424098 -319.161417) (xy 26.37794 -319.188066)
			(xy 26.328326 -319.207538) (xy 26.276364 -319.219398) (xy 26.223214 -319.223382) (xy 26.170064 -319.219398)
			(xy 26.118102 -319.207538) (xy 26.068488 -319.188066) (xy 26.02233 -319.161417) (xy 25.980659 -319.128186)
			(xy 25.944407 -319.089115) (xy 25.914383 -319.045078) (xy 25.891257 -318.997057) (xy 25.875547 -318.946127)
			(xy 25.867604 -318.893423) (xy 25.867106 -318.866774) (xy 25.867729 -318.835972) (xy 25.87828 -318.775279)
			(xy 25.899131 -318.717313) (xy 25.913842 -318.690244) (xy 25.920862 -318.676785) (xy 25.927465 -318.647174)
			(xy 25.925077 -318.61693) (xy 25.913909 -318.588722) (xy 25.894946 -318.56504) (xy 25.869863 -318.547974)
			(xy 25.840872 -318.539031) (xy 25.825704 -318.538352) (xy 21.777706 -318.538352) (xy 21.776944 -318.58839)
			(xy 21.776052 -318.614766) (xy 21.767447 -318.666833) (xy 21.751252 -318.717061) (xy 21.727823 -318.764349)
			(xy 21.697672 -318.807662) (xy 21.66146 -318.846051) (xy 21.61998 -318.878677) (xy 21.574139 -318.904824)
			(xy 21.524942 -318.923921) (xy 21.473465 -318.935549) (xy 21.420836 -318.939453) (xy 21.368207 -318.935549)
			(xy 21.31673 -318.923921) (xy 21.267533 -318.904824) (xy 21.221692 -318.878677) (xy 21.180212 -318.846051)
			(xy 21.144 -318.807662) (xy 21.113849 -318.764349) (xy 21.09042 -318.717061) (xy 21.074225 -318.666833)
			(xy 21.06562 -318.614766) (xy 21.064728 -318.58839) (xy 21.063966 -318.538352) (xy 19.076924 -318.538352)
			(xy 19.061743 -318.538911) (xy 19.032724 -318.547839) (xy 19.007617 -318.564912) (xy 18.988647 -318.588618)
			(xy 18.977492 -318.616856) (xy 18.975142 -318.647127) (xy 18.981805 -318.676748) (xy 18.988786 -318.690244)
			(xy 19.003466 -318.717327) (xy 19.024309 -318.775292) (xy 19.03489 -318.835975) (xy 19.035522 -318.866774)
			(xy 19.035024 -318.893423) (xy 19.027081 -318.946127) (xy 19.011371 -318.997057) (xy 18.988245 -319.045078)
			(xy 18.958221 -319.089115) (xy 18.921969 -319.128186) (xy 18.880298 -319.161417) (xy 18.83414 -319.188066)
			(xy 18.784526 -319.207538) (xy 18.732564 -319.219398) (xy 18.679414 -319.223382) (xy 18.626264 -319.219398)
			(xy 18.574302 -319.207538) (xy 18.524688 -319.188066) (xy 18.47853 -319.161417) (xy 18.436859 -319.128186)
			(xy 18.400607 -319.089115) (xy 18.370583 -319.045078) (xy 18.347457 -318.997057) (xy 18.331747 -318.946127)
			(xy 18.323804 -318.893423) (xy 18.323306 -318.866774) (xy 18.323929 -318.835972) (xy 18.33448 -318.775279)
			(xy 18.355331 -318.717313) (xy 18.370042 -318.690244) (xy 18.377062 -318.676785) (xy 18.383665 -318.647174)
			(xy 18.381277 -318.61693) (xy 18.370109 -318.588722) (xy 18.351146 -318.56504) (xy 18.326063 -318.547974)
			(xy 18.297072 -318.539031) (xy 18.281904 -318.538352) (xy 13.769848 -318.538352) (xy 13.759688 -318.57569)
			(xy 13.751914 -318.601844) (xy 13.729521 -318.651596) (xy 13.699805 -318.697352) (xy 13.663461 -318.738044)
			(xy 13.621338 -318.772719) (xy 13.574421 -318.800567) (xy 13.523807 -318.820937) (xy 13.47068 -318.833353)
			(xy 13.41628 -318.837524) (xy 13.36188 -318.833353) (xy 13.308753 -318.820937) (xy 13.258139 -318.800567)
			(xy 13.211222 -318.772719) (xy 13.169099 -318.738044) (xy 13.132755 -318.697352) (xy 13.103039 -318.651596)
			(xy 13.080646 -318.601844) (xy 13.072872 -318.57569) (xy 13.062712 -318.538352) (xy 11.5062 -318.538352)
			(xy 11.409426 -318.635126) (xy 11.432286 -318.669924) (xy 11.446324 -318.691916) (xy 11.468515 -318.739133)
			(xy 11.483593 -318.789079) (xy 11.491238 -318.840688) (xy 11.491722 -318.866774) (xy 11.491221 -318.893821)
			(xy 11.483044 -318.947292) (xy 11.466874 -318.998912) (xy 11.443084 -319.047493) (xy 11.41222 -319.091917)
			(xy 11.374993 -319.131162) (xy 11.332259 -319.164326) (xy 11.285 -319.190646) (xy 11.25982 -319.20053)
			(xy 11.2268 -319.212722) (xy 11.2268 -319.37071) (xy 11.25982 -319.382902) (xy 11.284992 -319.392807)
			(xy 11.332251 -319.419123) (xy 11.344466 -319.428601) (xy 16.456396 -319.428601) (xy 16.456396 -319.375303)
			(xy 16.464339 -319.322599) (xy 16.480049 -319.271669) (xy 16.503175 -319.223648) (xy 16.533199 -319.179611)
			(xy 16.569451 -319.14054) (xy 16.611122 -319.107309) (xy 16.65728 -319.08066) (xy 16.706894 -319.061188)
			(xy 16.758856 -319.049328) (xy 16.812006 -319.045345) (xy 16.865156 -319.049328) (xy 16.917118 -319.061188)
			(xy 16.966732 -319.08066) (xy 17.01289 -319.107309) (xy 17.054561 -319.14054) (xy 17.090813 -319.179611)
			(xy 17.120837 -319.223648) (xy 17.143963 -319.271669) (xy 17.159673 -319.322599) (xy 17.167616 -319.375303)
			(xy 17.168114 -319.401952) (xy 17.167616 -319.428601) (xy 17.159673 -319.481305) (xy 17.143963 -319.532235)
			(xy 17.120837 -319.580256) (xy 17.090813 -319.624293) (xy 17.054561 -319.663364) (xy 17.01289 -319.696595)
			(xy 16.966732 -319.723244) (xy 16.917118 -319.742716) (xy 16.914529 -319.743307) (xy 18.323804 -319.743307)
			(xy 18.323804 -319.690009) (xy 18.331747 -319.637305) (xy 18.347457 -319.586375) (xy 18.370583 -319.538354)
			(xy 18.400607 -319.494317) (xy 18.436859 -319.455246) (xy 18.47853 -319.422015) (xy 18.524688 -319.395366)
			(xy 18.574302 -319.375894) (xy 18.626264 -319.364034) (xy 18.679414 -319.360051) (xy 18.732564 -319.364034)
			(xy 18.763947 -319.371197) (xy 23.990036 -319.371197) (xy 23.990036 -319.317899) (xy 23.997979 -319.265195)
			(xy 24.013689 -319.214265) (xy 24.036815 -319.166244) (xy 24.066839 -319.122207) (xy 24.103091 -319.083136)
			(xy 24.144762 -319.049905) (xy 24.19092 -319.023256) (xy 24.240534 -319.003784) (xy 24.292496 -318.991924)
			(xy 24.345646 -318.987941) (xy 24.398796 -318.991924) (xy 24.450758 -319.003784) (xy 24.500372 -319.023256)
			(xy 24.54653 -319.049905) (xy 24.588201 -319.083136) (xy 24.624453 -319.122207) (xy 24.654477 -319.166244)
			(xy 24.677603 -319.214265) (xy 24.693313 -319.265195) (xy 24.701256 -319.317899) (xy 24.701493 -319.330557)
			(xy 31.499038 -319.330557) (xy 31.499038 -319.277259) (xy 31.506981 -319.224555) (xy 31.522691 -319.173625)
			(xy 31.545817 -319.125604) (xy 31.575841 -319.081567) (xy 31.612093 -319.042496) (xy 31.653764 -319.009265)
			(xy 31.699922 -318.982616) (xy 31.749536 -318.963144) (xy 31.801498 -318.951284) (xy 31.854648 -318.947301)
			(xy 31.907798 -318.951284) (xy 31.95976 -318.963144) (xy 32.009374 -318.982616) (xy 32.055532 -319.009265)
			(xy 32.097203 -319.042496) (xy 32.133455 -319.081567) (xy 32.163479 -319.125604) (xy 32.186605 -319.173625)
			(xy 32.202315 -319.224555) (xy 32.210258 -319.277259) (xy 32.210756 -319.303908) (xy 32.210258 -319.330557)
			(xy 32.209033 -319.338685) (xy 39.04868 -319.338685) (xy 39.04868 -319.285387) (xy 39.056623 -319.232683)
			(xy 39.072333 -319.181753) (xy 39.095459 -319.133732) (xy 39.125483 -319.089695) (xy 39.161735 -319.050624)
			(xy 39.203406 -319.017393) (xy 39.249564 -318.990744) (xy 39.299178 -318.971272) (xy 39.35114 -318.959412)
			(xy 39.40429 -318.955429) (xy 39.45744 -318.959412) (xy 39.509402 -318.971272) (xy 39.559016 -318.990744)
			(xy 39.605174 -319.017393) (xy 39.646845 -319.050624) (xy 39.683097 -319.089695) (xy 39.713121 -319.133732)
			(xy 39.736247 -319.181753) (xy 39.751957 -319.232683) (xy 39.7599 -319.285387) (xy 39.760398 -319.312036)
			(xy 39.7599 -319.338685) (xy 39.751957 -319.391389) (xy 39.736247 -319.442319) (xy 39.713121 -319.49034)
			(xy 39.683097 -319.534377) (xy 39.646845 -319.573448) (xy 39.605174 -319.606679) (xy 39.559016 -319.633328)
			(xy 39.509402 -319.6528) (xy 39.45744 -319.66466) (xy 39.40429 -319.668644) (xy 39.35114 -319.66466)
			(xy 39.299178 -319.6528) (xy 39.249564 -319.633328) (xy 39.203406 -319.606679) (xy 39.161735 -319.573448)
			(xy 39.125483 -319.534377) (xy 39.095459 -319.49034) (xy 39.072333 -319.442319) (xy 39.056623 -319.391389)
			(xy 39.04868 -319.338685) (xy 32.209033 -319.338685) (xy 32.202315 -319.383261) (xy 32.186605 -319.434191)
			(xy 32.163479 -319.482212) (xy 32.133455 -319.526249) (xy 32.097203 -319.56532) (xy 32.055532 -319.598551)
			(xy 32.009374 -319.6252) (xy 31.95976 -319.644672) (xy 31.907798 -319.656532) (xy 31.854648 -319.660516)
			(xy 31.801498 -319.656532) (xy 31.749536 -319.644672) (xy 31.699922 -319.6252) (xy 31.653764 -319.598551)
			(xy 31.612093 -319.56532) (xy 31.575841 -319.526249) (xy 31.545817 -319.482212) (xy 31.522691 -319.434191)
			(xy 31.506981 -319.383261) (xy 31.499038 -319.330557) (xy 24.701493 -319.330557) (xy 24.701754 -319.344548)
			(xy 24.701256 -319.371197) (xy 24.693313 -319.423901) (xy 24.677603 -319.474831) (xy 24.654477 -319.522852)
			(xy 24.624453 -319.566889) (xy 24.588201 -319.60596) (xy 24.54653 -319.639191) (xy 24.500372 -319.66584)
			(xy 24.450758 -319.685312) (xy 24.398796 -319.697172) (xy 24.345646 -319.701156) (xy 24.292496 -319.697172)
			(xy 24.240534 -319.685312) (xy 24.19092 -319.66584) (xy 24.144762 -319.639191) (xy 24.103091 -319.60596)
			(xy 24.066839 -319.566889) (xy 24.036815 -319.522852) (xy 24.013689 -319.474831) (xy 23.997979 -319.423901)
			(xy 23.990036 -319.371197) (xy 18.763947 -319.371197) (xy 18.784526 -319.375894) (xy 18.83414 -319.395366)
			(xy 18.880298 -319.422015) (xy 18.921969 -319.455246) (xy 18.958221 -319.494317) (xy 18.988245 -319.538354)
			(xy 19.011371 -319.586375) (xy 19.027081 -319.637305) (xy 19.035024 -319.690009) (xy 19.035522 -319.716658)
			(xy 19.035024 -319.743307) (xy 25.867604 -319.743307) (xy 25.867604 -319.690009) (xy 25.875547 -319.637305)
			(xy 25.891257 -319.586375) (xy 25.914383 -319.538354) (xy 25.944407 -319.494317) (xy 25.980659 -319.455246)
			(xy 26.02233 -319.422015) (xy 26.068488 -319.395366) (xy 26.118102 -319.375894) (xy 26.170064 -319.364034)
			(xy 26.223214 -319.360051) (xy 26.276364 -319.364034) (xy 26.328326 -319.375894) (xy 26.37794 -319.395366)
			(xy 26.424098 -319.422015) (xy 26.465769 -319.455246) (xy 26.502021 -319.494317) (xy 26.532045 -319.538354)
			(xy 26.555171 -319.586375) (xy 26.570881 -319.637305) (xy 26.578824 -319.690009) (xy 26.579322 -319.716658)
			(xy 26.578824 -319.743307) (xy 33.411404 -319.743307) (xy 33.411404 -319.690009) (xy 33.419347 -319.637305)
			(xy 33.435057 -319.586375) (xy 33.458183 -319.538354) (xy 33.488207 -319.494317) (xy 33.524459 -319.455246)
			(xy 33.56613 -319.422015) (xy 33.612288 -319.395366) (xy 33.661902 -319.375894) (xy 33.713864 -319.364034)
			(xy 33.767014 -319.360051) (xy 33.820164 -319.364034) (xy 33.872126 -319.375894) (xy 33.92174 -319.395366)
			(xy 33.967898 -319.422015) (xy 34.009569 -319.455246) (xy 34.045821 -319.494317) (xy 34.075845 -319.538354)
			(xy 34.098971 -319.586375) (xy 34.114681 -319.637305) (xy 34.122624 -319.690009) (xy 34.123122 -319.716658)
			(xy 34.122624 -319.743307) (xy 40.955204 -319.743307) (xy 40.955204 -319.690009) (xy 40.963147 -319.637305)
			(xy 40.978857 -319.586375) (xy 41.001983 -319.538354) (xy 41.032007 -319.494317) (xy 41.068259 -319.455246)
			(xy 41.10993 -319.422015) (xy 41.156088 -319.395366) (xy 41.205702 -319.375894) (xy 41.257664 -319.364034)
			(xy 41.310814 -319.360051) (xy 41.363964 -319.364034) (xy 41.415926 -319.375894) (xy 41.46554 -319.395366)
			(xy 41.511698 -319.422015) (xy 41.553369 -319.455246) (xy 41.589621 -319.494317) (xy 41.619645 -319.538354)
			(xy 41.642771 -319.586375) (xy 41.658481 -319.637305) (xy 41.666424 -319.690009) (xy 41.666922 -319.716658)
			(xy 41.666424 -319.743307) (xy 41.660912 -319.779883) (xy 46.614832 -319.779883) (xy 46.614832 -319.726585)
			(xy 46.622775 -319.673881) (xy 46.638485 -319.622951) (xy 46.661611 -319.57493) (xy 46.691635 -319.530893)
			(xy 46.727887 -319.491822) (xy 46.769558 -319.458591) (xy 46.815716 -319.431942) (xy 46.86533 -319.41247)
			(xy 46.917292 -319.40061) (xy 46.970442 -319.396627) (xy 47.023592 -319.40061) (xy 47.075554 -319.41247)
			(xy 47.125168 -319.431942) (xy 47.171326 -319.458591) (xy 47.212997 -319.491822) (xy 47.249249 -319.530893)
			(xy 47.279273 -319.57493) (xy 47.302399 -319.622951) (xy 47.318109 -319.673881) (xy 47.326052 -319.726585)
			(xy 47.326364 -319.743307) (xy 48.499004 -319.743307) (xy 48.499004 -319.690009) (xy 48.506947 -319.637305)
			(xy 48.522657 -319.586375) (xy 48.545783 -319.538354) (xy 48.575807 -319.494317) (xy 48.612059 -319.455246)
			(xy 48.65373 -319.422015) (xy 48.699888 -319.395366) (xy 48.749502 -319.375894) (xy 48.801464 -319.364034)
			(xy 48.854614 -319.360051) (xy 48.907764 -319.364034) (xy 48.959726 -319.375894) (xy 49.00934 -319.395366)
			(xy 49.055498 -319.422015) (xy 49.097169 -319.455246) (xy 49.133421 -319.494317) (xy 49.159964 -319.533249)
			(xy 50.747412 -319.533249) (xy 50.747412 -319.479951) (xy 50.755355 -319.427247) (xy 50.771065 -319.376317)
			(xy 50.794191 -319.328296) (xy 50.824215 -319.284259) (xy 50.860467 -319.245188) (xy 50.902138 -319.211957)
			(xy 50.948296 -319.185308) (xy 50.99791 -319.165836) (xy 51.049872 -319.153976) (xy 51.103022 -319.149993)
			(xy 51.156172 -319.153976) (xy 51.208134 -319.165836) (xy 51.257748 -319.185308) (xy 51.303906 -319.211957)
			(xy 51.345577 -319.245188) (xy 51.381829 -319.284259) (xy 51.411853 -319.328296) (xy 51.434979 -319.376317)
			(xy 51.450689 -319.427247) (xy 51.458632 -319.479951) (xy 51.45913 -319.5066) (xy 51.458632 -319.533249)
			(xy 51.450689 -319.585953) (xy 51.434979 -319.636883) (xy 51.411853 -319.684904) (xy 51.381829 -319.728941)
			(xy 51.37227 -319.739243) (xy 54.209686 -319.739243) (xy 54.209686 -319.685945) (xy 54.217629 -319.633241)
			(xy 54.233339 -319.582311) (xy 54.256465 -319.53429) (xy 54.286489 -319.490253) (xy 54.322741 -319.451182)
			(xy 54.364412 -319.417951) (xy 54.41057 -319.391302) (xy 54.460184 -319.37183) (xy 54.512146 -319.35997)
			(xy 54.565296 -319.355987) (xy 54.618446 -319.35997) (xy 54.670408 -319.37183) (xy 54.720022 -319.391302)
			(xy 54.76618 -319.417951) (xy 54.807851 -319.451182) (xy 54.844103 -319.490253) (xy 54.874127 -319.53429)
			(xy 54.897253 -319.582311) (xy 54.912963 -319.633241) (xy 54.920906 -319.685945) (xy 54.921404 -319.712594)
			(xy 54.920906 -319.739243) (xy 54.912963 -319.791947) (xy 54.897253 -319.842877) (xy 54.874127 -319.890898)
			(xy 54.844103 -319.934935) (xy 54.807851 -319.974006) (xy 54.76618 -320.007237) (xy 54.720022 -320.033886)
			(xy 54.670408 -320.053358) (xy 54.618446 -320.065218) (xy 54.565296 -320.069202) (xy 54.512146 -320.065218)
			(xy 54.460184 -320.053358) (xy 54.41057 -320.033886) (xy 54.364412 -320.007237) (xy 54.322741 -319.974006)
			(xy 54.286489 -319.934935) (xy 54.256465 -319.890898) (xy 54.233339 -319.842877) (xy 54.217629 -319.791947)
			(xy 54.209686 -319.739243) (xy 51.37227 -319.739243) (xy 51.345577 -319.768012) (xy 51.303906 -319.801243)
			(xy 51.257748 -319.827892) (xy 51.208134 -319.847364) (xy 51.156172 -319.859224) (xy 51.103022 -319.863208)
			(xy 51.049872 -319.859224) (xy 50.99791 -319.847364) (xy 50.948296 -319.827892) (xy 50.902138 -319.801243)
			(xy 50.860467 -319.768012) (xy 50.824215 -319.728941) (xy 50.794191 -319.684904) (xy 50.771065 -319.636883)
			(xy 50.755355 -319.585953) (xy 50.747412 -319.533249) (xy 49.159964 -319.533249) (xy 49.163445 -319.538354)
			(xy 49.186571 -319.586375) (xy 49.202281 -319.637305) (xy 49.210224 -319.690009) (xy 49.210722 -319.716658)
			(xy 49.210224 -319.743307) (xy 49.202281 -319.796011) (xy 49.186571 -319.846941) (xy 49.163445 -319.894962)
			(xy 49.133421 -319.938999) (xy 49.097169 -319.97807) (xy 49.055498 -320.011301) (xy 49.00934 -320.03795)
			(xy 48.959726 -320.057422) (xy 48.907764 -320.069282) (xy 48.854614 -320.073266) (xy 48.801464 -320.069282)
			(xy 48.749502 -320.057422) (xy 48.699888 -320.03795) (xy 48.65373 -320.011301) (xy 48.612059 -319.97807)
			(xy 48.575807 -319.938999) (xy 48.545783 -319.894962) (xy 48.522657 -319.846941) (xy 48.506947 -319.796011)
			(xy 48.499004 -319.743307) (xy 47.326364 -319.743307) (xy 47.32655 -319.753234) (xy 47.326052 -319.779883)
			(xy 47.318109 -319.832587) (xy 47.302399 -319.883517) (xy 47.279273 -319.931538) (xy 47.249249 -319.975575)
			(xy 47.212997 -320.014646) (xy 47.171326 -320.047877) (xy 47.125168 -320.074526) (xy 47.075554 -320.093998)
			(xy 47.023592 -320.105858) (xy 46.970442 -320.109842) (xy 46.917292 -320.105858) (xy 46.86533 -320.093998)
			(xy 46.815716 -320.074526) (xy 46.769558 -320.047877) (xy 46.727887 -320.014646) (xy 46.691635 -319.975575)
			(xy 46.661611 -319.931538) (xy 46.638485 -319.883517) (xy 46.622775 -319.832587) (xy 46.614832 -319.779883)
			(xy 41.660912 -319.779883) (xy 41.658481 -319.796011) (xy 41.642771 -319.846941) (xy 41.619645 -319.894962)
			(xy 41.589621 -319.938999) (xy 41.553369 -319.97807) (xy 41.511698 -320.011301) (xy 41.46554 -320.03795)
			(xy 41.415926 -320.057422) (xy 41.363964 -320.069282) (xy 41.310814 -320.073266) (xy 41.257664 -320.069282)
			(xy 41.205702 -320.057422) (xy 41.156088 -320.03795) (xy 41.10993 -320.011301) (xy 41.068259 -319.97807)
			(xy 41.032007 -319.938999) (xy 41.001983 -319.894962) (xy 40.978857 -319.846941) (xy 40.963147 -319.796011)
			(xy 40.955204 -319.743307) (xy 34.122624 -319.743307) (xy 34.114681 -319.796011) (xy 34.098971 -319.846941)
			(xy 34.075845 -319.894962) (xy 34.045821 -319.938999) (xy 34.009569 -319.97807) (xy 33.967898 -320.011301)
			(xy 33.92174 -320.03795) (xy 33.872126 -320.057422) (xy 33.820164 -320.069282) (xy 33.767014 -320.073266)
			(xy 33.713864 -320.069282) (xy 33.661902 -320.057422) (xy 33.612288 -320.03795) (xy 33.56613 -320.011301)
			(xy 33.524459 -319.97807) (xy 33.488207 -319.938999) (xy 33.458183 -319.894962) (xy 33.435057 -319.846941)
			(xy 33.419347 -319.796011) (xy 33.411404 -319.743307) (xy 26.578824 -319.743307) (xy 26.570881 -319.796011)
			(xy 26.555171 -319.846941) (xy 26.532045 -319.894962) (xy 26.502021 -319.938999) (xy 26.465769 -319.97807)
			(xy 26.424098 -320.011301) (xy 26.37794 -320.03795) (xy 26.328326 -320.057422) (xy 26.276364 -320.069282)
			(xy 26.223214 -320.073266) (xy 26.170064 -320.069282) (xy 26.118102 -320.057422) (xy 26.068488 -320.03795)
			(xy 26.02233 -320.011301) (xy 25.980659 -319.97807) (xy 25.944407 -319.938999) (xy 25.914383 -319.894962)
			(xy 25.891257 -319.846941) (xy 25.875547 -319.796011) (xy 25.867604 -319.743307) (xy 19.035024 -319.743307)
			(xy 19.027081 -319.796011) (xy 19.011371 -319.846941) (xy 18.988245 -319.894962) (xy 18.958221 -319.938999)
			(xy 18.921969 -319.97807) (xy 18.880298 -320.011301) (xy 18.83414 -320.03795) (xy 18.784526 -320.057422)
			(xy 18.732564 -320.069282) (xy 18.679414 -320.073266) (xy 18.626264 -320.069282) (xy 18.574302 -320.057422)
			(xy 18.524688 -320.03795) (xy 18.47853 -320.011301) (xy 18.436859 -319.97807) (xy 18.400607 -319.938999)
			(xy 18.370583 -319.894962) (xy 18.347457 -319.846941) (xy 18.331747 -319.796011) (xy 18.323804 -319.743307)
			(xy 16.914529 -319.743307) (xy 16.865156 -319.754576) (xy 16.812006 -319.75856) (xy 16.758856 -319.754576)
			(xy 16.706894 -319.742716) (xy 16.65728 -319.723244) (xy 16.611122 -319.696595) (xy 16.569451 -319.663364)
			(xy 16.533199 -319.624293) (xy 16.503175 -319.580256) (xy 16.480049 -319.532235) (xy 16.464339 -319.481305)
			(xy 16.456396 -319.428601) (xy 11.344466 -319.428601) (xy 11.374987 -319.452284) (xy 11.412216 -319.491526)
			(xy 11.443082 -319.535947) (xy 11.466875 -319.584525) (xy 11.483048 -319.636143) (xy 11.491228 -319.689613)
			(xy 11.491229 -319.743705) (xy 11.483048 -319.797175) (xy 11.466875 -319.848793) (xy 11.443083 -319.897372)
			(xy 11.412217 -319.941793) (xy 11.374988 -319.981035) (xy 11.332252 -320.014196) (xy 11.284993 -320.040513)
			(xy 11.25982 -320.050414) (xy 11.2268 -320.062606) (xy 11.2268 -320.165) (xy 55.436936 -320.165)
			(xy 55.44092 -320.111838) (xy 55.452784 -320.059864) (xy 55.472262 -320.010239) (xy 55.498919 -319.964071)
			(xy 55.53216 -319.922393) (xy 55.571242 -319.886135) (xy 55.615291 -319.856107) (xy 55.663324 -319.83298)
			(xy 55.714268 -319.817271) (xy 55.766985 -319.80933) (xy 55.79364 -319.80886) (xy 55.820407 -319.809353)
			(xy 55.873341 -319.817344) (xy 55.924482 -319.833171) (xy 55.972677 -319.856477) (xy 56.016839 -319.886736)
			(xy 56.055973 -319.923265) (xy 56.089196 -319.965243) (xy 56.11576 -320.011721) (xy 56.135065 -320.061653)
			(xy 56.146677 -320.113912) (xy 56.148986 -320.140584) (xy 56.150362 -320.153815) (xy 56.159003 -320.178962)
			(xy 56.173845 -320.201025) (xy 56.193881 -320.218505) (xy 56.217753 -320.230218) (xy 56.243839 -320.235369)
			(xy 56.270371 -320.233607) (xy 56.283098 -320.229738) (xy 56.311079 -320.220784) (xy 56.36904 -320.211211)
			(xy 56.398414 -320.210688) (xy 56.425062 -320.211195) (xy 56.477763 -320.21914) (xy 56.528692 -320.234851)
			(xy 56.57671 -320.257977) (xy 56.620745 -320.288001) (xy 56.659813 -320.324253) (xy 56.693043 -320.365923)
			(xy 56.71969 -320.412079) (xy 56.739161 -320.461692) (xy 56.751021 -320.513652) (xy 56.755004 -320.5668)
			(xy 56.751021 -320.619948) (xy 56.739161 -320.671908) (xy 56.71969 -320.721521) (xy 56.693043 -320.767677)
			(xy 56.659813 -320.809347) (xy 56.620745 -320.845599) (xy 56.57671 -320.875623) (xy 56.528692 -320.898749)
			(xy 56.477763 -320.91446) (xy 56.425062 -320.922405) (xy 56.398414 -320.922904) (xy 56.371644 -320.922487)
			(xy 56.318705 -320.914488) (xy 56.267561 -320.898653) (xy 56.219364 -320.875339) (xy 56.1752 -320.845071)
			(xy 56.136067 -320.808533) (xy 56.102845 -320.766547) (xy 56.076284 -320.720061) (xy 56.056982 -320.670121)
			(xy 56.045375 -320.617855) (xy 56.043068 -320.59118) (xy 56.041703 -320.577945) (xy 56.033071 -320.552789)
			(xy 56.018231 -320.530718) (xy 55.998192 -320.513232) (xy 55.974314 -320.501519) (xy 55.94822 -320.496375)
			(xy 55.921684 -320.498149) (xy 55.908956 -320.502026) (xy 55.880971 -320.510966) (xy 55.823013 -320.520548)
			(xy 55.79364 -320.521076) (xy 55.766985 -320.52067) (xy 55.714268 -320.512729) (xy 55.663324 -320.49702)
			(xy 55.615291 -320.473893) (xy 55.571242 -320.443865) (xy 55.53216 -320.407607) (xy 55.498919 -320.365929)
			(xy 55.472262 -320.319761) (xy 55.452784 -320.270136) (xy 55.44092 -320.218162) (xy 55.436936 -320.165)
			(xy 11.2268 -320.165) (xy 11.2268 -320.220848) (xy 11.25982 -320.23304) (xy 11.284992 -320.242945)
			(xy 11.33225 -320.269262) (xy 11.374985 -320.302424) (xy 11.412213 -320.341666) (xy 11.443078 -320.386087)
			(xy 11.466871 -320.434666) (xy 11.483043 -320.486283) (xy 11.491224 -320.539753) (xy 11.491224 -320.593445)
			(xy 14.223736 -320.593445) (xy 14.223736 -320.540147) (xy 14.231679 -320.487443) (xy 14.247389 -320.436513)
			(xy 14.270515 -320.388492) (xy 14.300539 -320.344455) (xy 14.336791 -320.305384) (xy 14.378462 -320.272153)
			(xy 14.42462 -320.245504) (xy 14.474234 -320.226032) (xy 14.526196 -320.214172) (xy 14.579346 -320.210189)
			(xy 14.632496 -320.214172) (xy 14.684458 -320.226032) (xy 14.734072 -320.245504) (xy 14.78023 -320.272153)
			(xy 14.821901 -320.305384) (xy 14.858153 -320.344455) (xy 14.888177 -320.388492) (xy 14.911303 -320.436513)
			(xy 14.927013 -320.487443) (xy 14.934956 -320.540147) (xy 14.935454 -320.566796) (xy 14.934956 -320.593445)
			(xy 18.323804 -320.593445) (xy 18.323804 -320.540147) (xy 18.331747 -320.487443) (xy 18.347457 -320.436513)
			(xy 18.370583 -320.388492) (xy 18.400607 -320.344455) (xy 18.436859 -320.305384) (xy 18.47853 -320.272153)
			(xy 18.524688 -320.245504) (xy 18.574302 -320.226032) (xy 18.626264 -320.214172) (xy 18.679414 -320.210189)
			(xy 18.732564 -320.214172) (xy 18.784526 -320.226032) (xy 18.83414 -320.245504) (xy 18.880298 -320.272153)
			(xy 18.921969 -320.305384) (xy 18.958221 -320.344455) (xy 18.988245 -320.388492) (xy 19.011371 -320.436513)
			(xy 19.027081 -320.487443) (xy 19.035024 -320.540147) (xy 19.035522 -320.566796) (xy 19.035024 -320.593445)
			(xy 21.767536 -320.593445) (xy 21.767536 -320.540147) (xy 21.775479 -320.487443) (xy 21.791189 -320.436513)
			(xy 21.814315 -320.388492) (xy 21.844339 -320.344455) (xy 21.880591 -320.305384) (xy 21.922262 -320.272153)
			(xy 21.96842 -320.245504) (xy 22.018034 -320.226032) (xy 22.069996 -320.214172) (xy 22.123146 -320.210189)
			(xy 22.176296 -320.214172) (xy 22.228258 -320.226032) (xy 22.277872 -320.245504) (xy 22.32403 -320.272153)
			(xy 22.365701 -320.305384) (xy 22.401953 -320.344455) (xy 22.431977 -320.388492) (xy 22.455103 -320.436513)
			(xy 22.470813 -320.487443) (xy 22.478756 -320.540147) (xy 22.479254 -320.566796) (xy 22.478756 -320.593445)
			(xy 25.867604 -320.593445) (xy 25.867604 -320.540147) (xy 25.875547 -320.487443) (xy 25.891257 -320.436513)
			(xy 25.914383 -320.388492) (xy 25.944407 -320.344455) (xy 25.980659 -320.305384) (xy 26.02233 -320.272153)
			(xy 26.068488 -320.245504) (xy 26.118102 -320.226032) (xy 26.170064 -320.214172) (xy 26.223214 -320.210189)
			(xy 26.276364 -320.214172) (xy 26.328326 -320.226032) (xy 26.37794 -320.245504) (xy 26.424098 -320.272153)
			(xy 26.465769 -320.305384) (xy 26.502021 -320.344455) (xy 26.532045 -320.388492) (xy 26.555171 -320.436513)
			(xy 26.570881 -320.487443) (xy 26.578824 -320.540147) (xy 26.579322 -320.566796) (xy 26.578824 -320.593445)
			(xy 29.311336 -320.593445) (xy 29.311336 -320.540147) (xy 29.319279 -320.487443) (xy 29.334989 -320.436513)
			(xy 29.358115 -320.388492) (xy 29.388139 -320.344455) (xy 29.424391 -320.305384) (xy 29.466062 -320.272153)
			(xy 29.51222 -320.245504) (xy 29.561834 -320.226032) (xy 29.613796 -320.214172) (xy 29.666946 -320.210189)
			(xy 29.720096 -320.214172) (xy 29.772058 -320.226032) (xy 29.821672 -320.245504) (xy 29.86783 -320.272153)
			(xy 29.909501 -320.305384) (xy 29.945753 -320.344455) (xy 29.975777 -320.388492) (xy 29.998903 -320.436513)
			(xy 30.014613 -320.487443) (xy 30.022556 -320.540147) (xy 30.023054 -320.566796) (xy 30.022556 -320.593445)
			(xy 33.411404 -320.593445) (xy 33.411404 -320.540147) (xy 33.419347 -320.487443) (xy 33.435057 -320.436513)
			(xy 33.458183 -320.388492) (xy 33.488207 -320.344455) (xy 33.524459 -320.305384) (xy 33.56613 -320.272153)
			(xy 33.612288 -320.245504) (xy 33.661902 -320.226032) (xy 33.713864 -320.214172) (xy 33.767014 -320.210189)
			(xy 33.820164 -320.214172) (xy 33.872126 -320.226032) (xy 33.92174 -320.245504) (xy 33.967898 -320.272153)
			(xy 34.009569 -320.305384) (xy 34.045821 -320.344455) (xy 34.075845 -320.388492) (xy 34.098971 -320.436513)
			(xy 34.114681 -320.487443) (xy 34.122624 -320.540147) (xy 34.123122 -320.566796) (xy 34.122624 -320.593445)
			(xy 36.855136 -320.593445) (xy 36.855136 -320.540147) (xy 36.863079 -320.487443) (xy 36.878789 -320.436513)
			(xy 36.901915 -320.388492) (xy 36.931939 -320.344455) (xy 36.968191 -320.305384) (xy 37.009862 -320.272153)
			(xy 37.05602 -320.245504) (xy 37.105634 -320.226032) (xy 37.157596 -320.214172) (xy 37.210746 -320.210189)
			(xy 37.263896 -320.214172) (xy 37.315858 -320.226032) (xy 37.365472 -320.245504) (xy 37.41163 -320.272153)
			(xy 37.453301 -320.305384) (xy 37.489553 -320.344455) (xy 37.519577 -320.388492) (xy 37.542703 -320.436513)
			(xy 37.558413 -320.487443) (xy 37.566356 -320.540147) (xy 37.566854 -320.566796) (xy 37.566356 -320.593445)
			(xy 40.955204 -320.593445) (xy 40.955204 -320.540147) (xy 40.963147 -320.487443) (xy 40.978857 -320.436513)
			(xy 41.001983 -320.388492) (xy 41.032007 -320.344455) (xy 41.068259 -320.305384) (xy 41.10993 -320.272153)
			(xy 41.156088 -320.245504) (xy 41.205702 -320.226032) (xy 41.257664 -320.214172) (xy 41.310814 -320.210189)
			(xy 41.363964 -320.214172) (xy 41.415926 -320.226032) (xy 41.46554 -320.245504) (xy 41.511698 -320.272153)
			(xy 41.553369 -320.305384) (xy 41.589621 -320.344455) (xy 41.619645 -320.388492) (xy 41.642771 -320.436513)
			(xy 41.658481 -320.487443) (xy 41.666424 -320.540147) (xy 41.666922 -320.566796) (xy 41.666424 -320.593445)
			(xy 44.398936 -320.593445) (xy 44.398936 -320.540147) (xy 44.406879 -320.487443) (xy 44.422589 -320.436513)
			(xy 44.445715 -320.388492) (xy 44.475739 -320.344455) (xy 44.511991 -320.305384) (xy 44.553662 -320.272153)
			(xy 44.59982 -320.245504) (xy 44.649434 -320.226032) (xy 44.701396 -320.214172) (xy 44.754546 -320.210189)
			(xy 44.807696 -320.214172) (xy 44.859658 -320.226032) (xy 44.909272 -320.245504) (xy 44.95543 -320.272153)
			(xy 44.997101 -320.305384) (xy 45.033353 -320.344455) (xy 45.063377 -320.388492) (xy 45.086503 -320.436513)
			(xy 45.102213 -320.487443) (xy 45.110156 -320.540147) (xy 45.110654 -320.566796) (xy 45.110156 -320.593445)
			(xy 48.499004 -320.593445) (xy 48.499004 -320.540147) (xy 48.506947 -320.487443) (xy 48.522657 -320.436513)
			(xy 48.545783 -320.388492) (xy 48.575807 -320.344455) (xy 48.612059 -320.305384) (xy 48.65373 -320.272153)
			(xy 48.699888 -320.245504) (xy 48.749502 -320.226032) (xy 48.801464 -320.214172) (xy 48.854614 -320.210189)
			(xy 48.907764 -320.214172) (xy 48.959726 -320.226032) (xy 49.00934 -320.245504) (xy 49.055498 -320.272153)
			(xy 49.097169 -320.305384) (xy 49.133421 -320.344455) (xy 49.163445 -320.388492) (xy 49.186571 -320.436513)
			(xy 49.202281 -320.487443) (xy 49.210224 -320.540147) (xy 49.210722 -320.566796) (xy 49.210224 -320.593445)
			(xy 51.942736 -320.593445) (xy 51.942736 -320.540147) (xy 51.950679 -320.487443) (xy 51.966389 -320.436513)
			(xy 51.989515 -320.388492) (xy 52.019539 -320.344455) (xy 52.055791 -320.305384) (xy 52.097462 -320.272153)
			(xy 52.14362 -320.245504) (xy 52.193234 -320.226032) (xy 52.245196 -320.214172) (xy 52.298346 -320.210189)
			(xy 52.351496 -320.214172) (xy 52.403458 -320.226032) (xy 52.453072 -320.245504) (xy 52.49923 -320.272153)
			(xy 52.540901 -320.305384) (xy 52.577153 -320.344455) (xy 52.607177 -320.388492) (xy 52.630303 -320.436513)
			(xy 52.646013 -320.487443) (xy 52.653956 -320.540147) (xy 52.654454 -320.566796) (xy 52.653956 -320.593445)
			(xy 52.646013 -320.646149) (xy 52.630303 -320.697079) (xy 52.607177 -320.7451) (xy 52.577153 -320.789137)
			(xy 52.540901 -320.828208) (xy 52.49923 -320.861439) (xy 52.453072 -320.888088) (xy 52.403458 -320.90756)
			(xy 52.351496 -320.91942) (xy 52.298346 -320.923404) (xy 52.245196 -320.91942) (xy 52.193234 -320.90756)
			(xy 52.14362 -320.888088) (xy 52.097462 -320.861439) (xy 52.055791 -320.828208) (xy 52.019539 -320.789137)
			(xy 51.989515 -320.7451) (xy 51.966389 -320.697079) (xy 51.950679 -320.646149) (xy 51.942736 -320.593445)
			(xy 49.210224 -320.593445) (xy 49.202281 -320.646149) (xy 49.186571 -320.697079) (xy 49.163445 -320.7451)
			(xy 49.133421 -320.789137) (xy 49.097169 -320.828208) (xy 49.055498 -320.861439) (xy 49.00934 -320.888088)
			(xy 48.959726 -320.90756) (xy 48.907764 -320.91942) (xy 48.854614 -320.923404) (xy 48.801464 -320.91942)
			(xy 48.749502 -320.90756) (xy 48.699888 -320.888088) (xy 48.65373 -320.861439) (xy 48.612059 -320.828208)
			(xy 48.575807 -320.789137) (xy 48.545783 -320.7451) (xy 48.522657 -320.697079) (xy 48.506947 -320.646149)
			(xy 48.499004 -320.593445) (xy 45.110156 -320.593445) (xy 45.102213 -320.646149) (xy 45.086503 -320.697079)
			(xy 45.063377 -320.7451) (xy 45.033353 -320.789137) (xy 44.997101 -320.828208) (xy 44.95543 -320.861439)
			(xy 44.909272 -320.888088) (xy 44.859658 -320.90756) (xy 44.807696 -320.91942) (xy 44.754546 -320.923404)
			(xy 44.701396 -320.91942) (xy 44.649434 -320.90756) (xy 44.59982 -320.888088) (xy 44.553662 -320.861439)
			(xy 44.511991 -320.828208) (xy 44.475739 -320.789137) (xy 44.445715 -320.7451) (xy 44.422589 -320.697079)
			(xy 44.406879 -320.646149) (xy 44.398936 -320.593445) (xy 41.666424 -320.593445) (xy 41.658481 -320.646149)
			(xy 41.642771 -320.697079) (xy 41.619645 -320.7451) (xy 41.589621 -320.789137) (xy 41.553369 -320.828208)
			(xy 41.511698 -320.861439) (xy 41.46554 -320.888088) (xy 41.415926 -320.90756) (xy 41.363964 -320.91942)
			(xy 41.310814 -320.923404) (xy 41.257664 -320.91942) (xy 41.205702 -320.90756) (xy 41.156088 -320.888088)
			(xy 41.10993 -320.861439) (xy 41.068259 -320.828208) (xy 41.032007 -320.789137) (xy 41.001983 -320.7451)
			(xy 40.978857 -320.697079) (xy 40.963147 -320.646149) (xy 40.955204 -320.593445) (xy 37.566356 -320.593445)
			(xy 37.558413 -320.646149) (xy 37.542703 -320.697079) (xy 37.519577 -320.7451) (xy 37.489553 -320.789137)
			(xy 37.453301 -320.828208) (xy 37.41163 -320.861439) (xy 37.365472 -320.888088) (xy 37.315858 -320.90756)
			(xy 37.263896 -320.91942) (xy 37.210746 -320.923404) (xy 37.157596 -320.91942) (xy 37.105634 -320.90756)
			(xy 37.05602 -320.888088) (xy 37.009862 -320.861439) (xy 36.968191 -320.828208) (xy 36.931939 -320.789137)
			(xy 36.901915 -320.7451) (xy 36.878789 -320.697079) (xy 36.863079 -320.646149) (xy 36.855136 -320.593445)
			(xy 34.122624 -320.593445) (xy 34.114681 -320.646149) (xy 34.098971 -320.697079) (xy 34.075845 -320.7451)
			(xy 34.045821 -320.789137) (xy 34.009569 -320.828208) (xy 33.967898 -320.861439) (xy 33.92174 -320.888088)
			(xy 33.872126 -320.90756) (xy 33.820164 -320.91942) (xy 33.767014 -320.923404) (xy 33.713864 -320.91942)
			(xy 33.661902 -320.90756) (xy 33.612288 -320.888088) (xy 33.56613 -320.861439) (xy 33.524459 -320.828208)
			(xy 33.488207 -320.789137) (xy 33.458183 -320.7451) (xy 33.435057 -320.697079) (xy 33.419347 -320.646149)
			(xy 33.411404 -320.593445) (xy 30.022556 -320.593445) (xy 30.014613 -320.646149) (xy 29.998903 -320.697079)
			(xy 29.975777 -320.7451) (xy 29.945753 -320.789137) (xy 29.909501 -320.828208) (xy 29.86783 -320.861439)
			(xy 29.821672 -320.888088) (xy 29.772058 -320.90756) (xy 29.720096 -320.91942) (xy 29.666946 -320.923404)
			(xy 29.613796 -320.91942) (xy 29.561834 -320.90756) (xy 29.51222 -320.888088) (xy 29.466062 -320.861439)
			(xy 29.424391 -320.828208) (xy 29.388139 -320.789137) (xy 29.358115 -320.7451) (xy 29.334989 -320.697079)
			(xy 29.319279 -320.646149) (xy 29.311336 -320.593445) (xy 26.578824 -320.593445) (xy 26.570881 -320.646149)
			(xy 26.555171 -320.697079) (xy 26.532045 -320.7451) (xy 26.502021 -320.789137) (xy 26.465769 -320.828208)
			(xy 26.424098 -320.861439) (xy 26.37794 -320.888088) (xy 26.328326 -320.90756) (xy 26.276364 -320.91942)
			(xy 26.223214 -320.923404) (xy 26.170064 -320.91942) (xy 26.118102 -320.90756) (xy 26.068488 -320.888088)
			(xy 26.02233 -320.861439) (xy 25.980659 -320.828208) (xy 25.944407 -320.789137) (xy 25.914383 -320.7451)
			(xy 25.891257 -320.697079) (xy 25.875547 -320.646149) (xy 25.867604 -320.593445) (xy 22.478756 -320.593445)
			(xy 22.470813 -320.646149) (xy 22.455103 -320.697079) (xy 22.431977 -320.7451) (xy 22.401953 -320.789137)
			(xy 22.365701 -320.828208) (xy 22.32403 -320.861439) (xy 22.277872 -320.888088) (xy 22.228258 -320.90756)
			(xy 22.176296 -320.91942) (xy 22.123146 -320.923404) (xy 22.069996 -320.91942) (xy 22.018034 -320.90756)
			(xy 21.96842 -320.888088) (xy 21.922262 -320.861439) (xy 21.880591 -320.828208) (xy 21.844339 -320.789137)
			(xy 21.814315 -320.7451) (xy 21.791189 -320.697079) (xy 21.775479 -320.646149) (xy 21.767536 -320.593445)
			(xy 19.035024 -320.593445) (xy 19.027081 -320.646149) (xy 19.011371 -320.697079) (xy 18.988245 -320.7451)
			(xy 18.958221 -320.789137) (xy 18.921969 -320.828208) (xy 18.880298 -320.861439) (xy 18.83414 -320.888088)
			(xy 18.784526 -320.90756) (xy 18.732564 -320.91942) (xy 18.679414 -320.923404) (xy 18.626264 -320.91942)
			(xy 18.574302 -320.90756) (xy 18.524688 -320.888088) (xy 18.47853 -320.861439) (xy 18.436859 -320.828208)
			(xy 18.400607 -320.789137) (xy 18.370583 -320.7451) (xy 18.347457 -320.697079) (xy 18.331747 -320.646149)
			(xy 18.323804 -320.593445) (xy 14.934956 -320.593445) (xy 14.927013 -320.646149) (xy 14.911303 -320.697079)
			(xy 14.888177 -320.7451) (xy 14.858153 -320.789137) (xy 14.821901 -320.828208) (xy 14.78023 -320.861439)
			(xy 14.734072 -320.888088) (xy 14.684458 -320.90756) (xy 14.632496 -320.91942) (xy 14.579346 -320.923404)
			(xy 14.526196 -320.91942) (xy 14.474234 -320.90756) (xy 14.42462 -320.888088) (xy 14.378462 -320.861439)
			(xy 14.336791 -320.828208) (xy 14.300539 -320.789137) (xy 14.270515 -320.7451) (xy 14.247389 -320.697079)
			(xy 14.231679 -320.646149) (xy 14.223736 -320.593445) (xy 11.491224 -320.593445) (xy 11.491224 -320.593844)
			(xy 11.483044 -320.647314) (xy 11.466872 -320.698932) (xy 11.44308 -320.74751) (xy 11.412215 -320.791932)
			(xy 11.374987 -320.831175) (xy 11.332252 -320.864336) (xy 11.284994 -320.890654) (xy 11.25982 -320.900552)
			(xy 11.2268 -320.912744) (xy 11.2268 -321.070732) (xy 11.25982 -321.082924) (xy 11.284993 -321.092829)
			(xy 11.332254 -321.119147) (xy 11.37499 -321.152309) (xy 11.412221 -321.191552) (xy 11.443088 -321.235975)
			(xy 11.466883 -321.284555) (xy 11.483057 -321.336174) (xy 11.491238 -321.389646) (xy 11.491239 -321.443329)
			(xy 14.223736 -321.443329) (xy 14.223736 -321.390031) (xy 14.231679 -321.337327) (xy 14.247389 -321.286397)
			(xy 14.270515 -321.238376) (xy 14.300539 -321.194339) (xy 14.336791 -321.155268) (xy 14.378462 -321.122037)
			(xy 14.42462 -321.095388) (xy 14.474234 -321.075916) (xy 14.526196 -321.064056) (xy 14.579346 -321.060073)
			(xy 14.632496 -321.064056) (xy 14.684458 -321.075916) (xy 14.734072 -321.095388) (xy 14.78023 -321.122037)
			(xy 14.821901 -321.155268) (xy 14.858153 -321.194339) (xy 14.888177 -321.238376) (xy 14.911303 -321.286397)
			(xy 14.927013 -321.337327) (xy 14.934956 -321.390031) (xy 14.935454 -321.41668) (xy 14.934956 -321.443329)
			(xy 18.323804 -321.443329) (xy 18.323804 -321.390031) (xy 18.331747 -321.337327) (xy 18.347457 -321.286397)
			(xy 18.370583 -321.238376) (xy 18.400607 -321.194339) (xy 18.436859 -321.155268) (xy 18.47853 -321.122037)
			(xy 18.524688 -321.095388) (xy 18.574302 -321.075916) (xy 18.626264 -321.064056) (xy 18.679414 -321.060073)
			(xy 18.732564 -321.064056) (xy 18.784526 -321.075916) (xy 18.83414 -321.095388) (xy 18.880298 -321.122037)
			(xy 18.921969 -321.155268) (xy 18.958221 -321.194339) (xy 18.988245 -321.238376) (xy 19.011371 -321.286397)
			(xy 19.027081 -321.337327) (xy 19.035024 -321.390031) (xy 19.035522 -321.41668) (xy 19.035024 -321.443329)
			(xy 21.767536 -321.443329) (xy 21.767536 -321.390031) (xy 21.775479 -321.337327) (xy 21.791189 -321.286397)
			(xy 21.814315 -321.238376) (xy 21.844339 -321.194339) (xy 21.880591 -321.155268) (xy 21.922262 -321.122037)
			(xy 21.96842 -321.095388) (xy 22.018034 -321.075916) (xy 22.069996 -321.064056) (xy 22.123146 -321.060073)
			(xy 22.176296 -321.064056) (xy 22.228258 -321.075916) (xy 22.277872 -321.095388) (xy 22.32403 -321.122037)
			(xy 22.365701 -321.155268) (xy 22.401953 -321.194339) (xy 22.431977 -321.238376) (xy 22.455103 -321.286397)
			(xy 22.470813 -321.337327) (xy 22.478756 -321.390031) (xy 22.479254 -321.41668) (xy 22.478756 -321.443329)
			(xy 25.867604 -321.443329) (xy 25.867604 -321.390031) (xy 25.875547 -321.337327) (xy 25.891257 -321.286397)
			(xy 25.914383 -321.238376) (xy 25.944407 -321.194339) (xy 25.980659 -321.155268) (xy 26.02233 -321.122037)
			(xy 26.068488 -321.095388) (xy 26.118102 -321.075916) (xy 26.170064 -321.064056) (xy 26.223214 -321.060073)
			(xy 26.276364 -321.064056) (xy 26.328326 -321.075916) (xy 26.37794 -321.095388) (xy 26.424098 -321.122037)
			(xy 26.465769 -321.155268) (xy 26.502021 -321.194339) (xy 26.532045 -321.238376) (xy 26.555171 -321.286397)
			(xy 26.570881 -321.337327) (xy 26.578824 -321.390031) (xy 26.579322 -321.41668) (xy 26.578824 -321.443329)
			(xy 29.311336 -321.443329) (xy 29.311336 -321.390031) (xy 29.319279 -321.337327) (xy 29.334989 -321.286397)
			(xy 29.358115 -321.238376) (xy 29.388139 -321.194339) (xy 29.424391 -321.155268) (xy 29.466062 -321.122037)
			(xy 29.51222 -321.095388) (xy 29.561834 -321.075916) (xy 29.613796 -321.064056) (xy 29.666946 -321.060073)
			(xy 29.720096 -321.064056) (xy 29.772058 -321.075916) (xy 29.821672 -321.095388) (xy 29.86783 -321.122037)
			(xy 29.909501 -321.155268) (xy 29.945753 -321.194339) (xy 29.975777 -321.238376) (xy 29.998903 -321.286397)
			(xy 30.014613 -321.337327) (xy 30.022556 -321.390031) (xy 30.023054 -321.41668) (xy 30.022556 -321.443329)
			(xy 33.411404 -321.443329) (xy 33.411404 -321.390031) (xy 33.419347 -321.337327) (xy 33.435057 -321.286397)
			(xy 33.458183 -321.238376) (xy 33.488207 -321.194339) (xy 33.524459 -321.155268) (xy 33.56613 -321.122037)
			(xy 33.612288 -321.095388) (xy 33.661902 -321.075916) (xy 33.713864 -321.064056) (xy 33.767014 -321.060073)
			(xy 33.820164 -321.064056) (xy 33.872126 -321.075916) (xy 33.92174 -321.095388) (xy 33.967898 -321.122037)
			(xy 34.009569 -321.155268) (xy 34.045821 -321.194339) (xy 34.075845 -321.238376) (xy 34.098971 -321.286397)
			(xy 34.114681 -321.337327) (xy 34.122624 -321.390031) (xy 34.123122 -321.41668) (xy 34.122624 -321.443329)
			(xy 36.855136 -321.443329) (xy 36.855136 -321.390031) (xy 36.863079 -321.337327) (xy 36.878789 -321.286397)
			(xy 36.901915 -321.238376) (xy 36.931939 -321.194339) (xy 36.968191 -321.155268) (xy 37.009862 -321.122037)
			(xy 37.05602 -321.095388) (xy 37.105634 -321.075916) (xy 37.157596 -321.064056) (xy 37.210746 -321.060073)
			(xy 37.263896 -321.064056) (xy 37.315858 -321.075916) (xy 37.365472 -321.095388) (xy 37.41163 -321.122037)
			(xy 37.453301 -321.155268) (xy 37.489553 -321.194339) (xy 37.519577 -321.238376) (xy 37.542703 -321.286397)
			(xy 37.558413 -321.337327) (xy 37.566356 -321.390031) (xy 37.566854 -321.41668) (xy 37.566356 -321.443329)
			(xy 40.955204 -321.443329) (xy 40.955204 -321.390031) (xy 40.963147 -321.337327) (xy 40.978857 -321.286397)
			(xy 41.001983 -321.238376) (xy 41.032007 -321.194339) (xy 41.068259 -321.155268) (xy 41.10993 -321.122037)
			(xy 41.156088 -321.095388) (xy 41.205702 -321.075916) (xy 41.257664 -321.064056) (xy 41.310814 -321.060073)
			(xy 41.363964 -321.064056) (xy 41.415926 -321.075916) (xy 41.46554 -321.095388) (xy 41.511698 -321.122037)
			(xy 41.553369 -321.155268) (xy 41.589621 -321.194339) (xy 41.619645 -321.238376) (xy 41.642771 -321.286397)
			(xy 41.658481 -321.337327) (xy 41.666424 -321.390031) (xy 41.666922 -321.41668) (xy 41.666424 -321.443329)
			(xy 44.398936 -321.443329) (xy 44.398936 -321.390031) (xy 44.406879 -321.337327) (xy 44.422589 -321.286397)
			(xy 44.445715 -321.238376) (xy 44.475739 -321.194339) (xy 44.511991 -321.155268) (xy 44.553662 -321.122037)
			(xy 44.59982 -321.095388) (xy 44.649434 -321.075916) (xy 44.701396 -321.064056) (xy 44.754546 -321.060073)
			(xy 44.807696 -321.064056) (xy 44.859658 -321.075916) (xy 44.909272 -321.095388) (xy 44.95543 -321.122037)
			(xy 44.997101 -321.155268) (xy 45.033353 -321.194339) (xy 45.063377 -321.238376) (xy 45.086503 -321.286397)
			(xy 45.102213 -321.337327) (xy 45.110156 -321.390031) (xy 45.110654 -321.41668) (xy 45.110156 -321.443329)
			(xy 48.499004 -321.443329) (xy 48.499004 -321.390031) (xy 48.506947 -321.337327) (xy 48.522657 -321.286397)
			(xy 48.545783 -321.238376) (xy 48.575807 -321.194339) (xy 48.612059 -321.155268) (xy 48.65373 -321.122037)
			(xy 48.699888 -321.095388) (xy 48.749502 -321.075916) (xy 48.801464 -321.064056) (xy 48.854614 -321.060073)
			(xy 48.907764 -321.064056) (xy 48.959726 -321.075916) (xy 49.00934 -321.095388) (xy 49.055498 -321.122037)
			(xy 49.097169 -321.155268) (xy 49.133421 -321.194339) (xy 49.163445 -321.238376) (xy 49.186571 -321.286397)
			(xy 49.202281 -321.337327) (xy 49.210224 -321.390031) (xy 49.210722 -321.41668) (xy 49.210224 -321.443329)
			(xy 51.942736 -321.443329) (xy 51.942736 -321.390031) (xy 51.950679 -321.337327) (xy 51.966389 -321.286397)
			(xy 51.989515 -321.238376) (xy 52.019539 -321.194339) (xy 52.055791 -321.155268) (xy 52.097462 -321.122037)
			(xy 52.14362 -321.095388) (xy 52.193234 -321.075916) (xy 52.245196 -321.064056) (xy 52.298346 -321.060073)
			(xy 52.351496 -321.064056) (xy 52.403458 -321.075916) (xy 52.453072 -321.095388) (xy 52.49923 -321.122037)
			(xy 52.540901 -321.155268) (xy 52.577153 -321.194339) (xy 52.607177 -321.238376) (xy 52.630303 -321.286397)
			(xy 52.646013 -321.337327) (xy 52.653956 -321.390031) (xy 52.654454 -321.41668) (xy 52.653956 -321.443329)
			(xy 56.042804 -321.443329) (xy 56.042804 -321.390031) (xy 56.050747 -321.337327) (xy 56.066457 -321.286397)
			(xy 56.089583 -321.238376) (xy 56.119607 -321.194339) (xy 56.155859 -321.155268) (xy 56.19753 -321.122037)
			(xy 56.243688 -321.095388) (xy 56.293302 -321.075916) (xy 56.345264 -321.064056) (xy 56.398414 -321.060073)
			(xy 56.451564 -321.064056) (xy 56.503526 -321.075916) (xy 56.55314 -321.095388) (xy 56.599298 -321.122037)
			(xy 56.640969 -321.155268) (xy 56.677221 -321.194339) (xy 56.707245 -321.238376) (xy 56.730371 -321.286397)
			(xy 56.746081 -321.337327) (xy 56.754024 -321.390031) (xy 56.754522 -321.41668) (xy 56.754024 -321.443329)
			(xy 56.746081 -321.496033) (xy 56.730371 -321.546963) (xy 56.707245 -321.594984) (xy 56.677221 -321.639021)
			(xy 56.640969 -321.678092) (xy 56.599298 -321.711323) (xy 56.55314 -321.737972) (xy 56.503526 -321.757444)
			(xy 56.451564 -321.769304) (xy 56.398414 -321.773288) (xy 56.345264 -321.769304) (xy 56.293302 -321.757444)
			(xy 56.243688 -321.737972) (xy 56.19753 -321.711323) (xy 56.155859 -321.678092) (xy 56.119607 -321.639021)
			(xy 56.089583 -321.594984) (xy 56.066457 -321.546963) (xy 56.050747 -321.496033) (xy 56.042804 -321.443329)
			(xy 52.653956 -321.443329) (xy 52.646013 -321.496033) (xy 52.630303 -321.546963) (xy 52.607177 -321.594984)
			(xy 52.577153 -321.639021) (xy 52.540901 -321.678092) (xy 52.49923 -321.711323) (xy 52.453072 -321.737972)
			(xy 52.403458 -321.757444) (xy 52.351496 -321.769304) (xy 52.298346 -321.773288) (xy 52.245196 -321.769304)
			(xy 52.193234 -321.757444) (xy 52.14362 -321.737972) (xy 52.097462 -321.711323) (xy 52.055791 -321.678092)
			(xy 52.019539 -321.639021) (xy 51.989515 -321.594984) (xy 51.966389 -321.546963) (xy 51.950679 -321.496033)
			(xy 51.942736 -321.443329) (xy 49.210224 -321.443329) (xy 49.202281 -321.496033) (xy 49.186571 -321.546963)
			(xy 49.163445 -321.594984) (xy 49.133421 -321.639021) (xy 49.097169 -321.678092) (xy 49.055498 -321.711323)
			(xy 49.00934 -321.737972) (xy 48.959726 -321.757444) (xy 48.907764 -321.769304) (xy 48.854614 -321.773288)
			(xy 48.801464 -321.769304) (xy 48.749502 -321.757444) (xy 48.699888 -321.737972) (xy 48.65373 -321.711323)
			(xy 48.612059 -321.678092) (xy 48.575807 -321.639021) (xy 48.545783 -321.594984) (xy 48.522657 -321.546963)
			(xy 48.506947 -321.496033) (xy 48.499004 -321.443329) (xy 45.110156 -321.443329) (xy 45.102213 -321.496033)
			(xy 45.086503 -321.546963) (xy 45.063377 -321.594984) (xy 45.033353 -321.639021) (xy 44.997101 -321.678092)
			(xy 44.95543 -321.711323) (xy 44.909272 -321.737972) (xy 44.859658 -321.757444) (xy 44.807696 -321.769304)
			(xy 44.754546 -321.773288) (xy 44.701396 -321.769304) (xy 44.649434 -321.757444) (xy 44.59982 -321.737972)
			(xy 44.553662 -321.711323) (xy 44.511991 -321.678092) (xy 44.475739 -321.639021) (xy 44.445715 -321.594984)
			(xy 44.422589 -321.546963) (xy 44.406879 -321.496033) (xy 44.398936 -321.443329) (xy 41.666424 -321.443329)
			(xy 41.658481 -321.496033) (xy 41.642771 -321.546963) (xy 41.619645 -321.594984) (xy 41.589621 -321.639021)
			(xy 41.553369 -321.678092) (xy 41.511698 -321.711323) (xy 41.46554 -321.737972) (xy 41.415926 -321.757444)
			(xy 41.363964 -321.769304) (xy 41.310814 -321.773288) (xy 41.257664 -321.769304) (xy 41.205702 -321.757444)
			(xy 41.156088 -321.737972) (xy 41.10993 -321.711323) (xy 41.068259 -321.678092) (xy 41.032007 -321.639021)
			(xy 41.001983 -321.594984) (xy 40.978857 -321.546963) (xy 40.963147 -321.496033) (xy 40.955204 -321.443329)
			(xy 37.566356 -321.443329) (xy 37.558413 -321.496033) (xy 37.542703 -321.546963) (xy 37.519577 -321.594984)
			(xy 37.489553 -321.639021) (xy 37.453301 -321.678092) (xy 37.41163 -321.711323) (xy 37.365472 -321.737972)
			(xy 37.315858 -321.757444) (xy 37.263896 -321.769304) (xy 37.210746 -321.773288) (xy 37.157596 -321.769304)
			(xy 37.105634 -321.757444) (xy 37.05602 -321.737972) (xy 37.009862 -321.711323) (xy 36.968191 -321.678092)
			(xy 36.931939 -321.639021) (xy 36.901915 -321.594984) (xy 36.878789 -321.546963) (xy 36.863079 -321.496033)
			(xy 36.855136 -321.443329) (xy 34.122624 -321.443329) (xy 34.114681 -321.496033) (xy 34.098971 -321.546963)
			(xy 34.075845 -321.594984) (xy 34.045821 -321.639021) (xy 34.009569 -321.678092) (xy 33.967898 -321.711323)
			(xy 33.92174 -321.737972) (xy 33.872126 -321.757444) (xy 33.820164 -321.769304) (xy 33.767014 -321.773288)
			(xy 33.713864 -321.769304) (xy 33.661902 -321.757444) (xy 33.612288 -321.737972) (xy 33.56613 -321.711323)
			(xy 33.524459 -321.678092) (xy 33.488207 -321.639021) (xy 33.458183 -321.594984) (xy 33.435057 -321.546963)
			(xy 33.419347 -321.496033) (xy 33.411404 -321.443329) (xy 30.022556 -321.443329) (xy 30.014613 -321.496033)
			(xy 29.998903 -321.546963) (xy 29.975777 -321.594984) (xy 29.945753 -321.639021) (xy 29.909501 -321.678092)
			(xy 29.86783 -321.711323) (xy 29.821672 -321.737972) (xy 29.772058 -321.757444) (xy 29.720096 -321.769304)
			(xy 29.666946 -321.773288) (xy 29.613796 -321.769304) (xy 29.561834 -321.757444) (xy 29.51222 -321.737972)
			(xy 29.466062 -321.711323) (xy 29.424391 -321.678092) (xy 29.388139 -321.639021) (xy 29.358115 -321.594984)
			(xy 29.334989 -321.546963) (xy 29.319279 -321.496033) (xy 29.311336 -321.443329) (xy 26.578824 -321.443329)
			(xy 26.570881 -321.496033) (xy 26.555171 -321.546963) (xy 26.532045 -321.594984) (xy 26.502021 -321.639021)
			(xy 26.465769 -321.678092) (xy 26.424098 -321.711323) (xy 26.37794 -321.737972) (xy 26.328326 -321.757444)
			(xy 26.276364 -321.769304) (xy 26.223214 -321.773288) (xy 26.170064 -321.769304) (xy 26.118102 -321.757444)
			(xy 26.068488 -321.737972) (xy 26.02233 -321.711323) (xy 25.980659 -321.678092) (xy 25.944407 -321.639021)
			(xy 25.914383 -321.594984) (xy 25.891257 -321.546963) (xy 25.875547 -321.496033) (xy 25.867604 -321.443329)
			(xy 22.478756 -321.443329) (xy 22.470813 -321.496033) (xy 22.455103 -321.546963) (xy 22.431977 -321.594984)
			(xy 22.401953 -321.639021) (xy 22.365701 -321.678092) (xy 22.32403 -321.711323) (xy 22.277872 -321.737972)
			(xy 22.228258 -321.757444) (xy 22.176296 -321.769304) (xy 22.123146 -321.773288) (xy 22.069996 -321.769304)
			(xy 22.018034 -321.757444) (xy 21.96842 -321.737972) (xy 21.922262 -321.711323) (xy 21.880591 -321.678092)
			(xy 21.844339 -321.639021) (xy 21.814315 -321.594984) (xy 21.791189 -321.546963) (xy 21.775479 -321.496033)
			(xy 21.767536 -321.443329) (xy 19.035024 -321.443329) (xy 19.027081 -321.496033) (xy 19.011371 -321.546963)
			(xy 18.988245 -321.594984) (xy 18.958221 -321.639021) (xy 18.921969 -321.678092) (xy 18.880298 -321.711323)
			(xy 18.83414 -321.737972) (xy 18.784526 -321.757444) (xy 18.732564 -321.769304) (xy 18.679414 -321.773288)
			(xy 18.626264 -321.769304) (xy 18.574302 -321.757444) (xy 18.524688 -321.737972) (xy 18.47853 -321.711323)
			(xy 18.436859 -321.678092) (xy 18.400607 -321.639021) (xy 18.370583 -321.594984) (xy 18.347457 -321.546963)
			(xy 18.331747 -321.496033) (xy 18.323804 -321.443329) (xy 14.934956 -321.443329) (xy 14.927013 -321.496033)
			(xy 14.911303 -321.546963) (xy 14.888177 -321.594984) (xy 14.858153 -321.639021) (xy 14.821901 -321.678092)
			(xy 14.78023 -321.711323) (xy 14.734072 -321.737972) (xy 14.684458 -321.757444) (xy 14.632496 -321.769304)
			(xy 14.579346 -321.773288) (xy 14.526196 -321.769304) (xy 14.474234 -321.757444) (xy 14.42462 -321.737972)
			(xy 14.378462 -321.711323) (xy 14.336791 -321.678092) (xy 14.300539 -321.639021) (xy 14.270515 -321.594984)
			(xy 14.247389 -321.546963) (xy 14.231679 -321.496033) (xy 14.223736 -321.443329) (xy 11.491239 -321.443329)
			(xy 11.491239 -321.44374) (xy 11.48306 -321.497212) (xy 11.466888 -321.548832) (xy 11.443095 -321.597413)
			(xy 11.41223 -321.641837) (xy 11.375001 -321.681082) (xy 11.332265 -321.714246) (xy 11.285006 -321.740565)
			(xy 11.25982 -321.750436) (xy 11.2268 -321.762628) (xy 11.2268 -322.424044) (xy 11.7348 -322.932044)
			(xy 16.067532 -322.932044) (xy 16.569948 -323.43446) (xy 19.060644 -323.43446) (xy 19.064627 -323.381306)
			(xy 19.076489 -323.329339) (xy 19.095963 -323.27972) (xy 19.122614 -323.233559) (xy 19.155849 -323.191885)
			(xy 19.194923 -323.155629) (xy 19.238964 -323.125603) (xy 19.286989 -323.102476) (xy 19.337924 -323.086765)
			(xy 19.390632 -323.078821) (xy 19.417284 -323.078348) (xy 19.443692 -323.078855) (xy 19.495928 -323.086653)
			(xy 19.54644 -323.10208) (xy 19.594119 -323.124798) (xy 19.637921 -323.15431) (xy 19.676883 -323.189966)
			(xy 19.69389 -323.210174) (xy 19.703827 -323.221567) (xy 19.72888 -323.238458) (xy 19.757776 -323.247289)
			(xy 19.787992 -323.247289) (xy 19.816888 -323.238458) (xy 19.841941 -323.221567) (xy 19.851878 -323.210174)
			(xy 19.868882 -323.189962) (xy 19.907844 -323.154302) (xy 19.951645 -323.124786) (xy 19.999325 -323.102064)
			(xy 20.049837 -323.086632) (xy 20.102075 -323.078829) (xy 20.128484 -323.078348) (xy 20.155133 -323.078854)
			(xy 20.207835 -323.086798) (xy 20.258765 -323.102508) (xy 20.306784 -323.125634) (xy 20.35082 -323.155658)
			(xy 20.38989 -323.191909) (xy 20.42312 -323.233579) (xy 20.449769 -323.279737) (xy 20.469241 -323.32935)
			(xy 20.481101 -323.381311) (xy 20.485084 -323.43446) (xy 20.485081 -323.4345) (xy 22.540448 -323.4345)
			(xy 22.544432 -323.381345) (xy 22.556293 -323.329378) (xy 22.575766 -323.279759) (xy 22.602417 -323.233596)
			(xy 22.635651 -323.191921) (xy 22.674724 -323.155664) (xy 22.718765 -323.125636) (xy 22.766789 -323.102507)
			(xy 22.817724 -323.086794) (xy 22.870432 -323.078847) (xy 22.897084 -323.078348) (xy 22.923492 -323.078855)
			(xy 22.975728 -323.086653) (xy 23.02624 -323.10208) (xy 23.073919 -323.124798) (xy 23.117721 -323.15431)
			(xy 23.156683 -323.189966) (xy 23.17369 -323.210174) (xy 23.183627 -323.221567) (xy 23.20868 -323.238458)
			(xy 23.237576 -323.247289) (xy 23.267792 -323.247289) (xy 23.296688 -323.238458) (xy 23.321741 -323.221567)
			(xy 23.331678 -323.210174) (xy 23.348682 -323.189962) (xy 23.387644 -323.154302) (xy 23.431445 -323.124786)
			(xy 23.479125 -323.102064) (xy 23.529637 -323.086632) (xy 23.581875 -323.078829) (xy 23.608284 -323.078348)
			(xy 23.634933 -323.078908) (xy 23.687635 -323.086849) (xy 23.738565 -323.102557) (xy 23.786585 -323.12568)
			(xy 23.830622 -323.155703) (xy 23.869692 -323.191953) (xy 23.902923 -323.233622) (xy 23.929573 -323.279778)
			(xy 23.949045 -323.329391) (xy 23.960905 -323.381352) (xy 23.964888 -323.4345) (xy 26.604448 -323.4345)
			(xy 26.608432 -323.381345) (xy 26.620293 -323.329378) (xy 26.639766 -323.279759) (xy 26.666417 -323.233596)
			(xy 26.699651 -323.191921) (xy 26.738724 -323.155664) (xy 26.782765 -323.125636) (xy 26.830789 -323.102507)
			(xy 26.881724 -323.086794) (xy 26.934432 -323.078847) (xy 26.961084 -323.078348) (xy 26.987492 -323.078855)
			(xy 27.039728 -323.086653) (xy 27.09024 -323.10208) (xy 27.137919 -323.124798) (xy 27.181721 -323.15431)
			(xy 27.220683 -323.189966) (xy 27.23769 -323.210174) (xy 27.247627 -323.221567) (xy 27.27268 -323.238458)
			(xy 27.301576 -323.247289) (xy 27.331792 -323.247289) (xy 27.360688 -323.238458) (xy 27.385741 -323.221567)
			(xy 27.395678 -323.210174) (xy 27.412682 -323.189962) (xy 27.451644 -323.154302) (xy 27.495445 -323.124786)
			(xy 27.543125 -323.102064) (xy 27.593637 -323.086632) (xy 27.645875 -323.078829) (xy 27.672284 -323.078348)
			(xy 27.698933 -323.078908) (xy 27.751635 -323.086849) (xy 27.802565 -323.102557) (xy 27.850585 -323.12568)
			(xy 27.894622 -323.155703) (xy 27.933692 -323.191953) (xy 27.966923 -323.233622) (xy 27.993573 -323.279778)
			(xy 28.013045 -323.329391) (xy 28.024905 -323.381352) (xy 28.028888 -323.4345) (xy 30.084248 -323.4345)
			(xy 30.088232 -323.381345) (xy 30.100093 -323.329378) (xy 30.119566 -323.279759) (xy 30.146217 -323.233596)
			(xy 30.179451 -323.191921) (xy 30.218524 -323.155664) (xy 30.262565 -323.125636) (xy 30.310589 -323.102507)
			(xy 30.361524 -323.086794) (xy 30.414232 -323.078847) (xy 30.440884 -323.078348) (xy 30.467292 -323.078855)
			(xy 30.519528 -323.086653) (xy 30.57004 -323.10208) (xy 30.617719 -323.124798) (xy 30.661521 -323.15431)
			(xy 30.700483 -323.189966) (xy 30.71749 -323.210174) (xy 30.727427 -323.221567) (xy 30.75248 -323.238458)
			(xy 30.781376 -323.247289) (xy 30.811592 -323.247289) (xy 30.840488 -323.238458) (xy 30.865541 -323.221567)
			(xy 30.875478 -323.210174) (xy 30.892482 -323.189962) (xy 30.931444 -323.154302) (xy 30.975245 -323.124786)
			(xy 31.022925 -323.102064) (xy 31.073437 -323.086632) (xy 31.125675 -323.078829) (xy 31.152084 -323.078348)
			(xy 31.178733 -323.078908) (xy 31.231435 -323.086849) (xy 31.282365 -323.102557) (xy 31.330385 -323.12568)
			(xy 31.374422 -323.155703) (xy 31.413492 -323.191953) (xy 31.446723 -323.233622) (xy 31.473373 -323.279778)
			(xy 31.492845 -323.329391) (xy 31.504705 -323.381352) (xy 31.508688 -323.4345) (xy 34.148248 -323.4345)
			(xy 34.152232 -323.381345) (xy 34.164093 -323.329378) (xy 34.183566 -323.279759) (xy 34.210217 -323.233596)
			(xy 34.243451 -323.191921) (xy 34.282524 -323.155664) (xy 34.326565 -323.125636) (xy 34.374589 -323.102507)
			(xy 34.425524 -323.086794) (xy 34.478232 -323.078847) (xy 34.504884 -323.078348) (xy 34.531292 -323.078855)
			(xy 34.583528 -323.086653) (xy 34.63404 -323.10208) (xy 34.681719 -323.124798) (xy 34.725521 -323.15431)
			(xy 34.764483 -323.189966) (xy 34.78149 -323.210174) (xy 34.791427 -323.221567) (xy 34.81648 -323.238458)
			(xy 34.845376 -323.247289) (xy 34.875592 -323.247289) (xy 34.904488 -323.238458) (xy 34.929541 -323.221567)
			(xy 34.939478 -323.210174) (xy 34.956482 -323.189962) (xy 34.995444 -323.154302) (xy 35.039245 -323.124786)
			(xy 35.086925 -323.102064) (xy 35.137437 -323.086632) (xy 35.189675 -323.078829) (xy 35.216084 -323.078348)
			(xy 35.242733 -323.078908) (xy 35.295435 -323.086849) (xy 35.346365 -323.102557) (xy 35.394385 -323.12568)
			(xy 35.438422 -323.155703) (xy 35.477492 -323.191953) (xy 35.510723 -323.233622) (xy 35.537373 -323.279778)
			(xy 35.556845 -323.329391) (xy 35.568705 -323.381352) (xy 35.572688 -323.4345) (xy 37.628048 -323.4345)
			(xy 37.632032 -323.381345) (xy 37.643893 -323.329378) (xy 37.663366 -323.279759) (xy 37.690017 -323.233596)
			(xy 37.723251 -323.191921) (xy 37.762324 -323.155664) (xy 37.806365 -323.125636) (xy 37.854389 -323.102507)
			(xy 37.905324 -323.086794) (xy 37.958032 -323.078847) (xy 37.984684 -323.078348) (xy 38.011092 -323.078855)
			(xy 38.063328 -323.086653) (xy 38.11384 -323.10208) (xy 38.161519 -323.124798) (xy 38.205321 -323.15431)
			(xy 38.244283 -323.189966) (xy 38.26129 -323.210174) (xy 38.271227 -323.221567) (xy 38.29628 -323.238458)
			(xy 38.325176 -323.247289) (xy 38.355392 -323.247289) (xy 38.384288 -323.238458) (xy 38.409341 -323.221567)
			(xy 38.419278 -323.210174) (xy 38.436282 -323.189962) (xy 38.475244 -323.154302) (xy 38.519045 -323.124786)
			(xy 38.566725 -323.102064) (xy 38.617237 -323.086632) (xy 38.669475 -323.078829) (xy 38.695884 -323.078348)
			(xy 38.722533 -323.078908) (xy 38.775235 -323.086849) (xy 38.826165 -323.102557) (xy 38.874185 -323.12568)
			(xy 38.918222 -323.155703) (xy 38.957292 -323.191953) (xy 38.990523 -323.233622) (xy 39.017173 -323.279778)
			(xy 39.036645 -323.329391) (xy 39.048505 -323.381352) (xy 39.052488 -323.4345) (xy 41.692048 -323.4345)
			(xy 41.696032 -323.381345) (xy 41.707893 -323.329378) (xy 41.727366 -323.279759) (xy 41.754017 -323.233596)
			(xy 41.787251 -323.191921) (xy 41.826324 -323.155664) (xy 41.870365 -323.125636) (xy 41.918389 -323.102507)
			(xy 41.969324 -323.086794) (xy 42.022032 -323.078847) (xy 42.048684 -323.078348) (xy 42.075092 -323.078855)
			(xy 42.127328 -323.086653) (xy 42.17784 -323.10208) (xy 42.225519 -323.124798) (xy 42.269321 -323.15431)
			(xy 42.308283 -323.189966) (xy 42.32529 -323.210174) (xy 42.335227 -323.221567) (xy 42.36028 -323.238458)
			(xy 42.389176 -323.247289) (xy 42.419392 -323.247289) (xy 42.448288 -323.238458) (xy 42.473341 -323.221567)
			(xy 42.483278 -323.210174) (xy 42.500282 -323.189962) (xy 42.539244 -323.154302) (xy 42.583045 -323.124786)
			(xy 42.630725 -323.102064) (xy 42.681237 -323.086632) (xy 42.733475 -323.078829) (xy 42.759884 -323.078348)
			(xy 42.786533 -323.078908) (xy 42.839235 -323.086849) (xy 42.890165 -323.102557) (xy 42.938185 -323.12568)
			(xy 42.982222 -323.155703) (xy 43.021292 -323.191953) (xy 43.054523 -323.233622) (xy 43.081173 -323.279778)
			(xy 43.100645 -323.329391) (xy 43.112505 -323.381352) (xy 43.116488 -323.4345) (xy 43.112505 -323.487648)
			(xy 43.100645 -323.539609) (xy 43.081173 -323.589222) (xy 43.054523 -323.635378) (xy 43.021292 -323.677047)
			(xy 42.982222 -323.713297) (xy 42.938185 -323.74332) (xy 42.890165 -323.766443) (xy 42.839235 -323.782151)
			(xy 42.786533 -323.790092) (xy 42.759884 -323.790564) (xy 42.733474 -323.790112) (xy 42.681234 -323.782307)
			(xy 42.630719 -323.766871) (xy 42.583039 -323.744143) (xy 42.53924 -323.71462) (xy 42.500282 -323.678952)
			(xy 42.483278 -323.658738) (xy 42.473341 -323.647345) (xy 42.448288 -323.630454) (xy 42.419392 -323.621623)
			(xy 42.389176 -323.621623) (xy 42.36028 -323.630454) (xy 42.335227 -323.647345) (xy 42.32529 -323.658738)
			(xy 42.308306 -323.678968) (xy 42.26934 -323.714626) (xy 42.225535 -323.744139) (xy 42.177851 -323.766859)
			(xy 42.127335 -323.782287) (xy 42.075094 -323.790086) (xy 42.048684 -323.790564) (xy 42.022032 -323.790153)
			(xy 41.969324 -323.782206) (xy 41.918389 -323.766493) (xy 41.870365 -323.743364) (xy 41.826324 -323.713336)
			(xy 41.787251 -323.677079) (xy 41.754017 -323.635404) (xy 41.727366 -323.589241) (xy 41.707893 -323.539622)
			(xy 41.696032 -323.487655) (xy 41.692048 -323.4345) (xy 39.052488 -323.4345) (xy 39.048505 -323.487648)
			(xy 39.036645 -323.539609) (xy 39.017173 -323.589222) (xy 38.990523 -323.635378) (xy 38.957292 -323.677047)
			(xy 38.918222 -323.713297) (xy 38.874185 -323.74332) (xy 38.826165 -323.766443) (xy 38.775235 -323.782151)
			(xy 38.722533 -323.790092) (xy 38.695884 -323.790564) (xy 38.669474 -323.790112) (xy 38.617234 -323.782307)
			(xy 38.566719 -323.766871) (xy 38.519039 -323.744143) (xy 38.47524 -323.71462) (xy 38.436282 -323.678952)
			(xy 38.419278 -323.658738) (xy 38.409341 -323.647345) (xy 38.384288 -323.630454) (xy 38.355392 -323.621623)
			(xy 38.325176 -323.621623) (xy 38.29628 -323.630454) (xy 38.271227 -323.647345) (xy 38.26129 -323.658738)
			(xy 38.244306 -323.678968) (xy 38.20534 -323.714626) (xy 38.161535 -323.744139) (xy 38.113851 -323.766859)
			(xy 38.063335 -323.782287) (xy 38.011094 -323.790086) (xy 37.984684 -323.790564) (xy 37.958032 -323.790153)
			(xy 37.905324 -323.782206) (xy 37.854389 -323.766493) (xy 37.806365 -323.743364) (xy 37.762324 -323.713336)
			(xy 37.723251 -323.677079) (xy 37.690017 -323.635404) (xy 37.663366 -323.589241) (xy 37.643893 -323.539622)
			(xy 37.632032 -323.487655) (xy 37.628048 -323.4345) (xy 35.572688 -323.4345) (xy 35.568705 -323.487648)
			(xy 35.556845 -323.539609) (xy 35.537373 -323.589222) (xy 35.510723 -323.635378) (xy 35.477492 -323.677047)
			(xy 35.438422 -323.713297) (xy 35.394385 -323.74332) (xy 35.346365 -323.766443) (xy 35.295435 -323.782151)
			(xy 35.242733 -323.790092) (xy 35.216084 -323.790564) (xy 35.189674 -323.790112) (xy 35.137434 -323.782307)
			(xy 35.086919 -323.766871) (xy 35.039239 -323.744143) (xy 34.99544 -323.71462) (xy 34.956482 -323.678952)
			(xy 34.939478 -323.658738) (xy 34.929541 -323.647345) (xy 34.904488 -323.630454) (xy 34.875592 -323.621623)
			(xy 34.845376 -323.621623) (xy 34.81648 -323.630454) (xy 34.791427 -323.647345) (xy 34.78149 -323.658738)
			(xy 34.764506 -323.678968) (xy 34.72554 -323.714626) (xy 34.681735 -323.744139) (xy 34.634051 -323.766859)
			(xy 34.583535 -323.782287) (xy 34.531294 -323.790086) (xy 34.504884 -323.790564) (xy 34.478232 -323.790153)
			(xy 34.425524 -323.782206) (xy 34.374589 -323.766493) (xy 34.326565 -323.743364) (xy 34.282524 -323.713336)
			(xy 34.243451 -323.677079) (xy 34.210217 -323.635404) (xy 34.183566 -323.589241) (xy 34.164093 -323.539622)
			(xy 34.152232 -323.487655) (xy 34.148248 -323.4345) (xy 31.508688 -323.4345) (xy 31.504705 -323.487648)
			(xy 31.492845 -323.539609) (xy 31.473373 -323.589222) (xy 31.446723 -323.635378) (xy 31.413492 -323.677047)
			(xy 31.374422 -323.713297) (xy 31.330385 -323.74332) (xy 31.282365 -323.766443) (xy 31.231435 -323.782151)
			(xy 31.178733 -323.790092) (xy 31.152084 -323.790564) (xy 31.125674 -323.790112) (xy 31.073434 -323.782307)
			(xy 31.022919 -323.766871) (xy 30.975239 -323.744143) (xy 30.93144 -323.71462) (xy 30.892482 -323.678952)
			(xy 30.875478 -323.658738) (xy 30.865541 -323.647345) (xy 30.840488 -323.630454) (xy 30.811592 -323.621623)
			(xy 30.781376 -323.621623) (xy 30.75248 -323.630454) (xy 30.727427 -323.647345) (xy 30.71749 -323.658738)
			(xy 30.700506 -323.678968) (xy 30.66154 -323.714626) (xy 30.617735 -323.744139) (xy 30.570051 -323.766859)
			(xy 30.519535 -323.782287) (xy 30.467294 -323.790086) (xy 30.440884 -323.790564) (xy 30.414232 -323.790153)
			(xy 30.361524 -323.782206) (xy 30.310589 -323.766493) (xy 30.262565 -323.743364) (xy 30.218524 -323.713336)
			(xy 30.179451 -323.677079) (xy 30.146217 -323.635404) (xy 30.119566 -323.589241) (xy 30.100093 -323.539622)
			(xy 30.088232 -323.487655) (xy 30.084248 -323.4345) (xy 28.028888 -323.4345) (xy 28.024905 -323.487648)
			(xy 28.013045 -323.539609) (xy 27.993573 -323.589222) (xy 27.966923 -323.635378) (xy 27.933692 -323.677047)
			(xy 27.894622 -323.713297) (xy 27.850585 -323.74332) (xy 27.802565 -323.766443) (xy 27.751635 -323.782151)
			(xy 27.698933 -323.790092) (xy 27.672284 -323.790564) (xy 27.645874 -323.790112) (xy 27.593634 -323.782307)
			(xy 27.543119 -323.766871) (xy 27.495439 -323.744143) (xy 27.45164 -323.71462) (xy 27.412682 -323.678952)
			(xy 27.395678 -323.658738) (xy 27.385741 -323.647345) (xy 27.360688 -323.630454) (xy 27.331792 -323.621623)
			(xy 27.301576 -323.621623) (xy 27.27268 -323.630454) (xy 27.247627 -323.647345) (xy 27.23769 -323.658738)
			(xy 27.220706 -323.678968) (xy 27.18174 -323.714626) (xy 27.137935 -323.744139) (xy 27.090251 -323.766859)
			(xy 27.039735 -323.782287) (xy 26.987494 -323.790086) (xy 26.961084 -323.790564) (xy 26.934432 -323.790153)
			(xy 26.881724 -323.782206) (xy 26.830789 -323.766493) (xy 26.782765 -323.743364) (xy 26.738724 -323.713336)
			(xy 26.699651 -323.677079) (xy 26.666417 -323.635404) (xy 26.639766 -323.589241) (xy 26.620293 -323.539622)
			(xy 26.608432 -323.487655) (xy 26.604448 -323.4345) (xy 23.964888 -323.4345) (xy 23.960905 -323.487648)
			(xy 23.949045 -323.539609) (xy 23.929573 -323.589222) (xy 23.902923 -323.635378) (xy 23.869692 -323.677047)
			(xy 23.830622 -323.713297) (xy 23.786585 -323.74332) (xy 23.738565 -323.766443) (xy 23.687635 -323.782151)
			(xy 23.634933 -323.790092) (xy 23.608284 -323.790564) (xy 23.581874 -323.790112) (xy 23.529634 -323.782307)
			(xy 23.479119 -323.766871) (xy 23.431439 -323.744143) (xy 23.38764 -323.71462) (xy 23.348682 -323.678952)
			(xy 23.331678 -323.658738) (xy 23.321741 -323.647345) (xy 23.296688 -323.630454) (xy 23.267792 -323.621623)
			(xy 23.237576 -323.621623) (xy 23.20868 -323.630454) (xy 23.183627 -323.647345) (xy 23.17369 -323.658738)
			(xy 23.156706 -323.678968) (xy 23.11774 -323.714626) (xy 23.073935 -323.744139) (xy 23.026251 -323.766859)
			(xy 22.975735 -323.782287) (xy 22.923494 -323.790086) (xy 22.897084 -323.790564) (xy 22.870432 -323.790153)
			(xy 22.817724 -323.782206) (xy 22.766789 -323.766493) (xy 22.718765 -323.743364) (xy 22.674724 -323.713336)
			(xy 22.635651 -323.677079) (xy 22.602417 -323.635404) (xy 22.575766 -323.589241) (xy 22.556293 -323.539622)
			(xy 22.544432 -323.487655) (xy 22.540448 -323.4345) (xy 20.485081 -323.4345) (xy 20.481101 -323.487609)
			(xy 20.469241 -323.53957) (xy 20.449769 -323.589183) (xy 20.42312 -323.635341) (xy 20.38989 -323.677011)
			(xy 20.35082 -323.713262) (xy 20.306784 -323.743286) (xy 20.258765 -323.766412) (xy 20.207835 -323.782122)
			(xy 20.155133 -323.790066) (xy 20.128484 -323.790564) (xy 20.102074 -323.790112) (xy 20.049834 -323.782307)
			(xy 19.999319 -323.766871) (xy 19.951639 -323.744143) (xy 19.90784 -323.71462) (xy 19.868882 -323.678952)
			(xy 19.851878 -323.658738) (xy 19.841941 -323.647345) (xy 19.816888 -323.630454) (xy 19.787992 -323.621623)
			(xy 19.757776 -323.621623) (xy 19.72888 -323.630454) (xy 19.703827 -323.647345) (xy 19.69389 -323.658738)
			(xy 19.676906 -323.678968) (xy 19.63794 -323.714626) (xy 19.594135 -323.744139) (xy 19.546451 -323.766859)
			(xy 19.495935 -323.782287) (xy 19.443694 -323.790086) (xy 19.417284 -323.790564) (xy 19.390632 -323.790099)
			(xy 19.337924 -323.782155) (xy 19.286989 -323.766444) (xy 19.238964 -323.743317) (xy 19.194923 -323.713291)
			(xy 19.155849 -323.677035) (xy 19.122614 -323.635361) (xy 19.095963 -323.5892) (xy 19.076489 -323.539581)
			(xy 19.064627 -323.487614) (xy 19.060644 -323.43446) (xy 16.569948 -323.43446) (xy 20.244424 -327.108936)
			(xy 23.741356 -327.108936) (xy 23.741356 -327.024384) (xy 23.749158 -326.940192) (xy 23.764694 -326.857079)
			(xy 23.787833 -326.775754) (xy 23.818377 -326.696911) (xy 23.856066 -326.621222) (xy 23.900577 -326.549334)
			(xy 23.951531 -326.481859) (xy 24.008494 -326.419374) (xy 24.070979 -326.362411) (xy 24.138454 -326.311457)
			(xy 24.210342 -326.266946) (xy 24.286031 -326.229257) (xy 24.364874 -326.198713) (xy 24.446199 -326.175574)
			(xy 24.529312 -326.160038) (xy 24.613504 -326.152236) (xy 24.65578 -326.151748) (xy 25.90038 -326.151748)
			(xy 25.942656 -326.152244) (xy 26.026847 -326.160046) (xy 26.10996 -326.175582) (xy 26.191284 -326.198721)
			(xy 26.270126 -326.229265) (xy 26.345814 -326.266953) (xy 26.417702 -326.311463) (xy 26.485176 -326.362417)
			(xy 26.54766 -326.41938) (xy 26.604623 -326.481864) (xy 26.655577 -326.549338) (xy 26.700087 -326.621226)
			(xy 26.737775 -326.696914) (xy 26.768319 -326.775756) (xy 26.791458 -326.85708) (xy 26.806994 -326.940193)
			(xy 26.814796 -327.024384) (xy 26.814796 -327.108936) (xy 31.285156 -327.108936) (xy 31.285156 -327.024384)
			(xy 31.292958 -326.940192) (xy 31.308494 -326.857079) (xy 31.331633 -326.775754) (xy 31.362177 -326.696911)
			(xy 31.399866 -326.621222) (xy 31.444377 -326.549334) (xy 31.495331 -326.481859) (xy 31.552294 -326.419374)
			(xy 31.614779 -326.362411) (xy 31.682254 -326.311457) (xy 31.754142 -326.266946) (xy 31.829831 -326.229257)
			(xy 31.908674 -326.198713) (xy 31.989999 -326.175574) (xy 32.073112 -326.160038) (xy 32.157304 -326.152236)
			(xy 32.19958 -326.151748) (xy 33.44418 -326.151748) (xy 33.486456 -326.152244) (xy 33.570647 -326.160046)
			(xy 33.65376 -326.175582) (xy 33.735084 -326.198721) (xy 33.813926 -326.229265) (xy 33.889614 -326.266953)
			(xy 33.961502 -326.311463) (xy 34.028976 -326.362417) (xy 34.09146 -326.41938) (xy 34.148423 -326.481864)
			(xy 34.199377 -326.549338) (xy 34.243887 -326.621226) (xy 34.281575 -326.696914) (xy 34.312119 -326.775756)
			(xy 34.335258 -326.85708) (xy 34.350794 -326.940193) (xy 34.358596 -327.024384) (xy 34.358596 -327.108936)
			(xy 34.350794 -327.193127) (xy 34.335258 -327.27624) (xy 34.312119 -327.357564) (xy 34.281575 -327.436406)
			(xy 34.243887 -327.512094) (xy 34.199377 -327.583982) (xy 34.148423 -327.651456) (xy 34.09146 -327.71394)
			(xy 34.028976 -327.770903) (xy 33.961502 -327.821857) (xy 33.889614 -327.866367) (xy 33.813926 -327.904055)
			(xy 33.735084 -327.934599) (xy 33.65376 -327.957738) (xy 33.570647 -327.973274) (xy 33.486456 -327.981076)
			(xy 33.44418 -327.981564) (xy 32.19958 -327.981564) (xy 32.157304 -327.981084) (xy 32.073112 -327.973282)
			(xy 31.989999 -327.957746) (xy 31.908674 -327.934607) (xy 31.829831 -327.904063) (xy 31.754142 -327.866374)
			(xy 31.682254 -327.821863) (xy 31.614779 -327.770909) (xy 31.552294 -327.713946) (xy 31.495331 -327.651461)
			(xy 31.444377 -327.583986) (xy 31.399866 -327.512098) (xy 31.362177 -327.436409) (xy 31.331633 -327.357566)
			(xy 31.308494 -327.276241) (xy 31.292958 -327.193128) (xy 31.285156 -327.108936) (xy 26.814796 -327.108936)
			(xy 26.806994 -327.193127) (xy 26.791458 -327.27624) (xy 26.768319 -327.357564) (xy 26.737775 -327.436406)
			(xy 26.700087 -327.512094) (xy 26.655577 -327.583982) (xy 26.604623 -327.651456) (xy 26.54766 -327.71394)
			(xy 26.485176 -327.770903) (xy 26.417702 -327.821857) (xy 26.345814 -327.866367) (xy 26.270126 -327.904055)
			(xy 26.191284 -327.934599) (xy 26.10996 -327.957738) (xy 26.026847 -327.973274) (xy 25.942656 -327.981076)
			(xy 25.90038 -327.981564) (xy 24.65578 -327.981564) (xy 24.613504 -327.981084) (xy 24.529312 -327.973282)
			(xy 24.446199 -327.957746) (xy 24.364874 -327.934607) (xy 24.286031 -327.904063) (xy 24.210342 -327.866374)
			(xy 24.138454 -327.821863) (xy 24.070979 -327.770909) (xy 24.008494 -327.713946) (xy 23.951531 -327.651461)
			(xy 23.900577 -327.583986) (xy 23.856066 -327.512098) (xy 23.818377 -327.436409) (xy 23.787833 -327.357566)
			(xy 23.764694 -327.276241) (xy 23.749158 -327.193128) (xy 23.741356 -327.108936) (xy 20.244424 -327.108936)
			(xy 23.599902 -330.464414) (xy 27.265376 -330.464414) (xy 27.905964 -331.105002) (xy 27.905964 -331.152246)
			(xy 27.909012 -331.160628) (xy 27.919554 -331.191971) (xy 27.930924 -331.257107) (xy 27.931618 -331.290168)
			(xy 27.930938 -331.32323) (xy 27.919569 -331.388369) (xy 27.909012 -331.419708) (xy 27.905964 -331.42809)
			(xy 27.905964 -331.914246) (xy 27.909012 -331.922628) (xy 27.919554 -331.953971) (xy 27.930924 -332.019107)
			(xy 27.931618 -332.052168) (xy 27.930938 -332.08523) (xy 27.919569 -332.150369) (xy 27.909012 -332.181708)
			(xy 27.905964 -332.19009) (xy 27.905964 -332.676246) (xy 27.909012 -332.684628) (xy 27.919554 -332.715971)
			(xy 27.930924 -332.781107) (xy 27.931618 -332.814168) (xy 27.930938 -332.84723) (xy 27.919569 -332.912369)
			(xy 27.909012 -332.943708) (xy 27.905964 -332.95209) (xy 27.905964 -333.438246) (xy 27.909012 -333.446628)
			(xy 27.919554 -333.477971) (xy 27.930924 -333.543107) (xy 27.931618 -333.576168) (xy 27.930938 -333.60923)
			(xy 27.919569 -333.674369) (xy 27.909012 -333.705708) (xy 27.905964 -333.71409) (xy 27.905964 -334.073246)
			(xy 27.909012 -334.081628) (xy 27.919554 -334.112971) (xy 27.930924 -334.178107) (xy 27.931618 -334.211168)
			(xy 27.930938 -334.24423) (xy 27.919569 -334.309369) (xy 27.909012 -334.340708) (xy 27.905964 -334.34909)
			(xy 27.905964 -334.708246) (xy 27.909012 -334.716628) (xy 27.919554 -334.747971) (xy 27.930924 -334.813107)
			(xy 27.931618 -334.846168) (xy 27.930938 -334.87923) (xy 27.919569 -334.944369) (xy 27.909012 -334.975708)
			(xy 27.905964 -334.98409) (xy 27.905964 -336.464148) (xy 30.154372 -336.464148) (xy 30.1549 -336.436897)
			(xy 30.16265 -336.38295) (xy 30.177999 -336.330654) (xy 30.200634 -336.281076) (xy 30.230095 -336.235223)
			(xy 30.265782 -336.19403) (xy 30.306969 -336.158336) (xy 30.352816 -336.128867) (xy 30.40239 -336.106223)
			(xy 30.454683 -336.090864) (xy 30.508629 -336.083105) (xy 30.53588 -336.08264) (xy 30.564797 -336.083158)
			(xy 30.621969 -336.091885) (xy 30.677169 -336.109142) (xy 30.729131 -336.134533) (xy 30.776664 -336.167478)
			(xy 30.81868 -336.20722) (xy 30.83687 -336.229706) (xy 30.846767 -336.241511) (xy 30.872091 -336.25903)
			(xy 30.901484 -336.268206) (xy 30.932276 -336.268206) (xy 30.961669 -336.25903) (xy 30.986993 -336.241511)
			(xy 30.99689 -336.229706) (xy 31.015088 -336.207229) (xy 31.057106 -336.167493) (xy 31.10464 -336.134553)
			(xy 31.1566 -336.109163) (xy 31.211796 -336.091906) (xy 31.268964 -336.083176) (xy 31.29788 -336.08264)
			(xy 31.325137 -336.083006) (xy 31.379097 -336.090761) (xy 31.431404 -336.106117) (xy 31.480993 -336.128762)
			(xy 31.526854 -336.158233) (xy 31.568055 -336.193931) (xy 31.603755 -336.23513) (xy 31.633229 -336.280989)
			(xy 31.655876 -336.330577) (xy 31.671235 -336.382883) (xy 31.678993 -336.436843) (xy 31.678993 -336.491357)
			(xy 31.671235 -336.545317) (xy 31.655876 -336.597623) (xy 31.633229 -336.647211) (xy 31.603755 -336.69307)
			(xy 31.568055 -336.734269) (xy 31.526854 -336.769967) (xy 31.480993 -336.799438) (xy 31.431404 -336.822083)
			(xy 31.379097 -336.837439) (xy 31.325137 -336.845194) (xy 31.29788 -336.845656) (xy 31.268964 -336.845097)
			(xy 31.211794 -336.836378) (xy 31.156596 -336.81913) (xy 31.104633 -336.793746) (xy 31.057099 -336.760809)
			(xy 31.015081 -336.721073) (xy 30.99689 -336.69859) (xy 30.986993 -336.686785) (xy 30.961669 -336.669266)
			(xy 30.932276 -336.66009) (xy 30.901484 -336.66009) (xy 30.872091 -336.669266) (xy 30.846767 -336.686785)
			(xy 30.83687 -336.69859) (xy 30.822123 -336.716897) (xy 30.788887 -336.750143) (xy 30.770576 -336.764884)
			(xy 30.760254 -336.77351) (xy 30.744108 -336.795011) (xy 30.734128 -336.819979) (xy 30.731005 -336.846685)
			(xy 30.734955 -336.873282) (xy 30.745704 -336.897928) (xy 30.762509 -336.918919) (xy 30.773116 -336.92719)
			(xy 30.796892 -336.945278) (xy 30.839015 -336.987638) (xy 30.874019 -337.036048) (xy 30.901048 -337.089322)
			(xy 30.919442 -337.146159) (xy 30.928749 -337.205168) (xy 30.929326 -337.235038) (xy 30.92884 -337.262289)
			(xy 30.921084 -337.316237) (xy 30.905729 -337.368532) (xy 30.883087 -337.418109) (xy 30.853621 -337.463959)
			(xy 30.81793 -337.50515) (xy 30.776739 -337.540841) (xy 30.730889 -337.570307) (xy 30.681312 -337.592949)
			(xy 30.629017 -337.608304) (xy 30.575069 -337.61606) (xy 30.520567 -337.61606) (xy 30.466619 -337.608304)
			(xy 30.414324 -337.592949) (xy 30.364747 -337.570307) (xy 30.318897 -337.540841) (xy 30.277706 -337.50515)
			(xy 30.242015 -337.463959) (xy 30.212549 -337.418109) (xy 30.189907 -337.368532) (xy 30.174552 -337.316237)
			(xy 30.166796 -337.262289) (xy 30.16631 -337.235038) (xy 30.16686 -337.206154) (xy 30.175578 -337.149048)
			(xy 30.192803 -337.093908) (xy 30.218143 -337.041995) (xy 30.251019 -336.994495) (xy 30.29068 -336.952493)
			(xy 30.313122 -336.934302) (xy 30.323459 -336.925693) (xy 30.339605 -336.904188) (xy 30.349584 -336.879216)
			(xy 30.352706 -336.852506) (xy 30.348753 -336.825906) (xy 30.338 -336.801258) (xy 30.321191 -336.780267)
			(xy 30.310582 -336.771996) (xy 30.286799 -336.753917) (xy 30.244676 -336.711554) (xy 30.209673 -336.663143)
			(xy 30.182645 -336.609867) (xy 30.164253 -336.553029) (xy 30.154948 -336.494018) (xy 30.154372 -336.464148)
			(xy 27.905964 -336.464148) (xy 27.905964 -340.293452) (xy 24.22779 -343.971626) (xy 24.22779 -385.802378)
			(xy 28.134562 -385.802378) (xy 28.138633 -385.746756) (xy 28.150759 -385.692319) (xy 28.170682 -385.640228)
			(xy 28.197978 -385.591593) (xy 28.232064 -385.54745) (xy 28.272213 -385.508741) (xy 28.317571 -385.47629)
			(xy 28.367171 -385.450789) (xy 28.419955 -385.432782) (xy 28.474798 -385.422652) (xy 28.530532 -385.420615)
			(xy 28.585969 -385.426715) (xy 28.639926 -385.440821) (xy 28.691255 -385.462633) (xy 28.738861 -385.491687)
			(xy 28.781729 -385.527362) (xy 28.818946 -385.568899) (xy 28.849719 -385.615412) (xy 28.873391 -385.665909)
			(xy 28.889459 -385.719316) (xy 28.897579 -385.774492) (xy 28.898088 -385.802378) (xy 28.897579 -385.830264)
			(xy 28.889459 -385.88544) (xy 28.873391 -385.938847) (xy 28.849719 -385.989344) (xy 28.818946 -386.035857)
			(xy 28.781729 -386.077394) (xy 28.738861 -386.113069) (xy 28.691255 -386.142123) (xy 28.639926 -386.163935)
			(xy 28.585969 -386.178041) (xy 28.530532 -386.184141) (xy 28.474798 -386.182104) (xy 28.419955 -386.171974)
			(xy 28.367171 -386.153967) (xy 28.317571 -386.128466) (xy 28.272213 -386.096015) (xy 28.232064 -386.057306)
			(xy 28.197978 -386.013163) (xy 28.170682 -385.964528) (xy 28.150759 -385.912437) (xy 28.138633 -385.858)
			(xy 28.134562 -385.802378) (xy 24.22779 -385.802378) (xy 24.22779 -387.608826) (xy 24.833578 -387.608826)
			(xy 24.837649 -387.553204) (xy 24.849775 -387.498767) (xy 24.869698 -387.446676) (xy 24.896994 -387.398041)
			(xy 24.93108 -387.353898) (xy 24.971229 -387.315189) (xy 25.016587 -387.282738) (xy 25.066187 -387.257237)
			(xy 25.118971 -387.23923) (xy 25.173814 -387.2291) (xy 25.229548 -387.227063) (xy 25.284985 -387.233163)
			(xy 25.337439 -387.246876) (xy 28.256228 -387.246876) (xy 28.260299 -387.191254) (xy 28.272425 -387.136817)
			(xy 28.292348 -387.084726) (xy 28.319644 -387.036091) (xy 28.35373 -386.991948) (xy 28.393879 -386.953239)
			(xy 28.439237 -386.920788) (xy 28.488837 -386.895287) (xy 28.541621 -386.87728) (xy 28.596464 -386.86715)
			(xy 28.652198 -386.865113) (xy 28.707635 -386.871213) (xy 28.761592 -386.885319) (xy 28.812921 -386.907131)
			(xy 28.860527 -386.936185) (xy 28.903395 -386.97186) (xy 28.940612 -387.013397) (xy 28.971385 -387.05991)
			(xy 28.995057 -387.110407) (xy 29.011125 -387.163814) (xy 29.019245 -387.21899) (xy 29.019754 -387.246876)
			(xy 29.019245 -387.274762) (xy 29.011125 -387.329938) (xy 28.995057 -387.383345) (xy 28.971385 -387.433842)
			(xy 28.940612 -387.480355) (xy 28.903395 -387.521892) (xy 28.860527 -387.557567) (xy 28.812921 -387.586621)
			(xy 28.761592 -387.608433) (xy 28.707635 -387.622539) (xy 28.652198 -387.628639) (xy 28.596464 -387.626602)
			(xy 28.541621 -387.616472) (xy 28.488837 -387.598465) (xy 28.439237 -387.572964) (xy 28.393879 -387.540513)
			(xy 28.35373 -387.501804) (xy 28.319644 -387.457661) (xy 28.292348 -387.409026) (xy 28.272425 -387.356935)
			(xy 28.260299 -387.302498) (xy 28.256228 -387.246876) (xy 25.337439 -387.246876) (xy 25.338942 -387.247269)
			(xy 25.390271 -387.269081) (xy 25.437877 -387.298135) (xy 25.480745 -387.33381) (xy 25.517962 -387.375347)
			(xy 25.548735 -387.42186) (xy 25.572407 -387.472357) (xy 25.588475 -387.525764) (xy 25.596595 -387.58094)
			(xy 25.597104 -387.608826) (xy 25.596595 -387.636712) (xy 25.588475 -387.691888) (xy 25.572407 -387.745295)
			(xy 25.548735 -387.795792) (xy 25.517962 -387.842305) (xy 25.480745 -387.883842) (xy 25.437877 -387.919517)
			(xy 25.390271 -387.948571) (xy 25.338942 -387.970383) (xy 25.284985 -387.984489) (xy 25.229548 -387.990589)
			(xy 25.173814 -387.988552) (xy 25.118971 -387.978422) (xy 25.066187 -387.960415) (xy 25.016587 -387.934914)
			(xy 24.971229 -387.902463) (xy 24.93108 -387.863754) (xy 24.896994 -387.819611) (xy 24.869698 -387.770976)
			(xy 24.849775 -387.718885) (xy 24.837649 -387.664448) (xy 24.833578 -387.608826) (xy 24.22779 -387.608826)
			(xy 24.22779 -390.294876) (xy 28.256228 -390.294876) (xy 28.260299 -390.239254) (xy 28.272425 -390.184817)
			(xy 28.292348 -390.132726) (xy 28.319644 -390.084091) (xy 28.35373 -390.039948) (xy 28.393879 -390.001239)
			(xy 28.439237 -389.968788) (xy 28.488837 -389.943287) (xy 28.541621 -389.92528) (xy 28.596464 -389.91515)
			(xy 28.652198 -389.913113) (xy 28.707635 -389.919213) (xy 28.761592 -389.933319) (xy 28.812921 -389.955131)
			(xy 28.860527 -389.984185) (xy 28.903395 -390.01986) (xy 28.940612 -390.061397) (xy 28.970895 -390.10717)
			(xy 31.968946 -390.10717) (xy 31.973017 -390.051548) (xy 31.985143 -389.997111) (xy 32.005066 -389.94502)
			(xy 32.032362 -389.896385) (xy 32.066448 -389.852242) (xy 32.106597 -389.813533) (xy 32.151955 -389.781082)
			(xy 32.201555 -389.755581) (xy 32.254339 -389.737574) (xy 32.309182 -389.727444) (xy 32.364916 -389.725407)
			(xy 32.420353 -389.731507) (xy 32.47431 -389.745613) (xy 32.525639 -389.767425) (xy 32.573245 -389.796479)
			(xy 32.616113 -389.832154) (xy 32.65333 -389.873691) (xy 32.684103 -389.920204) (xy 32.707775 -389.970701)
			(xy 32.718801 -390.007348) (xy 46.835312 -390.007348) (xy 46.839383 -389.951726) (xy 46.851509 -389.897289)
			(xy 46.871432 -389.845198) (xy 46.898728 -389.796563) (xy 46.932814 -389.75242) (xy 46.972963 -389.713711)
			(xy 47.018321 -389.68126) (xy 47.067921 -389.655759) (xy 47.120705 -389.637752) (xy 47.175548 -389.627622)
			(xy 47.231282 -389.625585) (xy 47.286719 -389.631685) (xy 47.340676 -389.645791) (xy 47.392005 -389.667603)
			(xy 47.439611 -389.696657) (xy 47.482479 -389.732332) (xy 47.519696 -389.773869) (xy 47.550469 -389.820382)
			(xy 47.574141 -389.870879) (xy 47.590209 -389.924286) (xy 47.598329 -389.979462) (xy 47.598838 -390.007348)
			(xy 47.598329 -390.035234) (xy 47.590209 -390.09041) (xy 47.574141 -390.143817) (xy 47.550469 -390.194314)
			(xy 47.519696 -390.240827) (xy 47.482479 -390.282364) (xy 47.439611 -390.318039) (xy 47.392005 -390.347093)
			(xy 47.340676 -390.368905) (xy 47.286719 -390.383011) (xy 47.231282 -390.389111) (xy 47.175548 -390.387074)
			(xy 47.120705 -390.376944) (xy 47.067921 -390.358937) (xy 47.018321 -390.333436) (xy 46.972963 -390.300985)
			(xy 46.932814 -390.262276) (xy 46.898728 -390.218133) (xy 46.871432 -390.169498) (xy 46.851509 -390.117407)
			(xy 46.839383 -390.06297) (xy 46.835312 -390.007348) (xy 32.718801 -390.007348) (xy 32.723843 -390.024108)
			(xy 32.731963 -390.079284) (xy 32.732472 -390.10717) (xy 32.731963 -390.135056) (xy 32.723843 -390.190232)
			(xy 32.707775 -390.243639) (xy 32.684103 -390.294136) (xy 32.65333 -390.340649) (xy 32.616113 -390.382186)
			(xy 32.573245 -390.417861) (xy 32.525639 -390.446915) (xy 32.47431 -390.468727) (xy 32.420353 -390.482833)
			(xy 32.364916 -390.488933) (xy 32.309182 -390.486896) (xy 32.254339 -390.476766) (xy 32.201555 -390.458759)
			(xy 32.151955 -390.433258) (xy 32.106597 -390.400807) (xy 32.066448 -390.362098) (xy 32.032362 -390.317955)
			(xy 32.005066 -390.26932) (xy 31.985143 -390.217229) (xy 31.973017 -390.162792) (xy 31.968946 -390.10717)
			(xy 28.970895 -390.10717) (xy 28.971385 -390.10791) (xy 28.995057 -390.158407) (xy 29.011125 -390.211814)
			(xy 29.019245 -390.26699) (xy 29.019754 -390.294876) (xy 29.019245 -390.322762) (xy 29.011125 -390.377938)
			(xy 28.995057 -390.431345) (xy 28.971385 -390.481842) (xy 28.940612 -390.528355) (xy 28.903395 -390.569892)
			(xy 28.860527 -390.605567) (xy 28.812921 -390.634621) (xy 28.761592 -390.656433) (xy 28.707635 -390.670539)
			(xy 28.652198 -390.676639) (xy 28.596464 -390.674602) (xy 28.541621 -390.664472) (xy 28.488837 -390.646465)
			(xy 28.439237 -390.620964) (xy 28.393879 -390.588513) (xy 28.35373 -390.549804) (xy 28.319644 -390.505661)
			(xy 28.292348 -390.457026) (xy 28.272425 -390.404935) (xy 28.260299 -390.350498) (xy 28.256228 -390.294876)
			(xy 24.22779 -390.294876) (xy 24.22779 -391.310876) (xy 28.256228 -391.310876) (xy 28.260299 -391.255254)
			(xy 28.272425 -391.200817) (xy 28.292348 -391.148726) (xy 28.319644 -391.100091) (xy 28.35373 -391.055948)
			(xy 28.393879 -391.017239) (xy 28.439237 -390.984788) (xy 28.488837 -390.959287) (xy 28.541621 -390.94128)
			(xy 28.596464 -390.93115) (xy 28.652198 -390.929113) (xy 28.707635 -390.935213) (xy 28.761592 -390.949319)
			(xy 28.812921 -390.971131) (xy 28.860527 -391.000185) (xy 28.903395 -391.03586) (xy 28.940612 -391.077397)
			(xy 28.971385 -391.12391) (xy 28.995057 -391.174407) (xy 29.011125 -391.227814) (xy 29.019245 -391.28299)
			(xy 29.019754 -391.310876) (xy 29.019245 -391.338762) (xy 29.011125 -391.393938) (xy 28.995057 -391.447345)
			(xy 28.971385 -391.497842) (xy 28.940612 -391.544355) (xy 28.903395 -391.585892) (xy 28.860527 -391.621567)
			(xy 28.836885 -391.635996) (xy 31.968946 -391.635996) (xy 31.973017 -391.580374) (xy 31.985143 -391.525937)
			(xy 32.005066 -391.473846) (xy 32.032362 -391.425211) (xy 32.066448 -391.381068) (xy 32.106597 -391.342359)
			(xy 32.151955 -391.309908) (xy 32.201555 -391.284407) (xy 32.254339 -391.2664) (xy 32.309182 -391.25627)
			(xy 32.364916 -391.254233) (xy 32.420353 -391.260333) (xy 32.47431 -391.274439) (xy 32.525639 -391.296251)
			(xy 32.573245 -391.325305) (xy 32.616113 -391.36098) (xy 32.65333 -391.402517) (xy 32.654373 -391.404094)
			(xy 38.548816 -391.404094) (xy 38.552887 -391.348472) (xy 38.565013 -391.294035) (xy 38.584936 -391.241944)
			(xy 38.612232 -391.193309) (xy 38.646318 -391.149166) (xy 38.686467 -391.110457) (xy 38.731825 -391.078006)
			(xy 38.781425 -391.052505) (xy 38.834209 -391.034498) (xy 38.889052 -391.024368) (xy 38.944786 -391.022331)
			(xy 39.000223 -391.028431) (xy 39.05418 -391.042537) (xy 39.105509 -391.064349) (xy 39.153115 -391.093403)
			(xy 39.195983 -391.129078) (xy 39.2332 -391.170615) (xy 39.263973 -391.217128) (xy 39.287645 -391.267625)
			(xy 39.303713 -391.321032) (xy 39.311833 -391.376208) (xy 39.311864 -391.377932) (xy 40.593516 -391.377932)
			(xy 40.597587 -391.32231) (xy 40.609713 -391.267873) (xy 40.629636 -391.215782) (xy 40.656932 -391.167147)
			(xy 40.691018 -391.123004) (xy 40.731167 -391.084295) (xy 40.776525 -391.051844) (xy 40.826125 -391.026343)
			(xy 40.878909 -391.008336) (xy 40.933752 -390.998206) (xy 40.989486 -390.996169) (xy 41.044923 -391.002269)
			(xy 41.09888 -391.016375) (xy 41.150209 -391.038187) (xy 41.197815 -391.067241) (xy 41.224733 -391.089642)
			(xy 46.835312 -391.089642) (xy 46.839383 -391.03402) (xy 46.851509 -390.979583) (xy 46.871432 -390.927492)
			(xy 46.898728 -390.878857) (xy 46.932814 -390.834714) (xy 46.972963 -390.796005) (xy 47.018321 -390.763554)
			(xy 47.067921 -390.738053) (xy 47.120705 -390.720046) (xy 47.175548 -390.709916) (xy 47.231282 -390.707879)
			(xy 47.286719 -390.713979) (xy 47.340676 -390.728085) (xy 47.392005 -390.749897) (xy 47.439611 -390.778951)
			(xy 47.482479 -390.814626) (xy 47.519696 -390.856163) (xy 47.550469 -390.902676) (xy 47.574141 -390.953173)
			(xy 47.590209 -391.00658) (xy 47.598329 -391.061756) (xy 47.598838 -391.089642) (xy 47.598329 -391.117528)
			(xy 47.590209 -391.172704) (xy 47.574141 -391.226111) (xy 47.550469 -391.276608) (xy 47.519696 -391.323121)
			(xy 47.482479 -391.364658) (xy 47.439611 -391.400333) (xy 47.392005 -391.429387) (xy 47.340676 -391.451199)
			(xy 47.286719 -391.465305) (xy 47.231282 -391.471405) (xy 47.175548 -391.469368) (xy 47.120705 -391.459238)
			(xy 47.067921 -391.441231) (xy 47.018321 -391.41573) (xy 46.972963 -391.383279) (xy 46.932814 -391.34457)
			(xy 46.898728 -391.300427) (xy 46.871432 -391.251792) (xy 46.851509 -391.199701) (xy 46.839383 -391.145264)
			(xy 46.835312 -391.089642) (xy 41.224733 -391.089642) (xy 41.240683 -391.102916) (xy 41.2779 -391.144453)
			(xy 41.308673 -391.190966) (xy 41.332345 -391.241463) (xy 41.348413 -391.29487) (xy 41.356533 -391.350046)
			(xy 41.357042 -391.377932) (xy 41.356533 -391.405818) (xy 41.348413 -391.460994) (xy 41.332345 -391.514401)
			(xy 41.308673 -391.564898) (xy 41.2779 -391.611411) (xy 41.240683 -391.652948) (xy 41.197815 -391.688623)
			(xy 41.150209 -391.717677) (xy 41.09888 -391.739489) (xy 41.044923 -391.753595) (xy 40.989486 -391.759695)
			(xy 40.933752 -391.757658) (xy 40.878909 -391.747528) (xy 40.826125 -391.729521) (xy 40.776525 -391.70402)
			(xy 40.731167 -391.671569) (xy 40.691018 -391.63286) (xy 40.656932 -391.588717) (xy 40.629636 -391.540082)
			(xy 40.609713 -391.487991) (xy 40.597587 -391.433554) (xy 40.593516 -391.377932) (xy 39.311864 -391.377932)
			(xy 39.312342 -391.404094) (xy 39.311833 -391.43198) (xy 39.303713 -391.487156) (xy 39.287645 -391.540563)
			(xy 39.263973 -391.59106) (xy 39.2332 -391.637573) (xy 39.195983 -391.67911) (xy 39.153115 -391.714785)
			(xy 39.105509 -391.743839) (xy 39.05418 -391.765651) (xy 39.000223 -391.779757) (xy 38.944786 -391.785857)
			(xy 38.889052 -391.78382) (xy 38.834209 -391.77369) (xy 38.781425 -391.755683) (xy 38.731825 -391.730182)
			(xy 38.686467 -391.697731) (xy 38.646318 -391.659022) (xy 38.612232 -391.614879) (xy 38.584936 -391.566244)
			(xy 38.565013 -391.514153) (xy 38.552887 -391.459716) (xy 38.548816 -391.404094) (xy 32.654373 -391.404094)
			(xy 32.684103 -391.44903) (xy 32.707775 -391.499527) (xy 32.723843 -391.552934) (xy 32.731963 -391.60811)
			(xy 32.732472 -391.635996) (xy 32.731963 -391.663882) (xy 32.723843 -391.719058) (xy 32.707775 -391.772465)
			(xy 32.684103 -391.822962) (xy 32.65333 -391.869475) (xy 32.616113 -391.911012) (xy 32.573245 -391.946687)
			(xy 32.525639 -391.975741) (xy 32.47431 -391.997553) (xy 32.420353 -392.011659) (xy 32.364916 -392.017759)
			(xy 32.309182 -392.015722) (xy 32.254339 -392.005592) (xy 32.201555 -391.987585) (xy 32.151955 -391.962084)
			(xy 32.106597 -391.929633) (xy 32.066448 -391.890924) (xy 32.032362 -391.846781) (xy 32.005066 -391.798146)
			(xy 31.985143 -391.746055) (xy 31.973017 -391.691618) (xy 31.968946 -391.635996) (xy 28.836885 -391.635996)
			(xy 28.812921 -391.650621) (xy 28.761592 -391.672433) (xy 28.707635 -391.686539) (xy 28.652198 -391.692639)
			(xy 28.596464 -391.690602) (xy 28.541621 -391.680472) (xy 28.488837 -391.662465) (xy 28.439237 -391.636964)
			(xy 28.393879 -391.604513) (xy 28.35373 -391.565804) (xy 28.319644 -391.521661) (xy 28.292348 -391.473026)
			(xy 28.272425 -391.420935) (xy 28.260299 -391.366498) (xy 28.256228 -391.310876) (xy 24.22779 -391.310876)
			(xy 24.22779 -392.326876) (xy 28.256228 -392.326876) (xy 28.260299 -392.271254) (xy 28.272425 -392.216817)
			(xy 28.292348 -392.164726) (xy 28.319644 -392.116091) (xy 28.35373 -392.071948) (xy 28.393879 -392.033239)
			(xy 28.439237 -392.000788) (xy 28.488837 -391.975287) (xy 28.541621 -391.95728) (xy 28.596464 -391.94715)
			(xy 28.652198 -391.945113) (xy 28.707635 -391.951213) (xy 28.761592 -391.965319) (xy 28.812921 -391.987131)
			(xy 28.860527 -392.016185) (xy 28.903395 -392.05186) (xy 28.940612 -392.093397) (xy 28.971385 -392.13991)
			(xy 28.991756 -392.183366) (xy 46.835312 -392.183366) (xy 46.839383 -392.127744) (xy 46.851509 -392.073307)
			(xy 46.871432 -392.021216) (xy 46.898728 -391.972581) (xy 46.932814 -391.928438) (xy 46.972963 -391.889729)
			(xy 47.018321 -391.857278) (xy 47.067921 -391.831777) (xy 47.120705 -391.81377) (xy 47.175548 -391.80364)
			(xy 47.231282 -391.801603) (xy 47.286719 -391.807703) (xy 47.340676 -391.821809) (xy 47.392005 -391.843621)
			(xy 47.439611 -391.872675) (xy 47.482479 -391.90835) (xy 47.519696 -391.949887) (xy 47.550469 -391.9964)
			(xy 47.574141 -392.046897) (xy 47.590209 -392.100304) (xy 47.598329 -392.15548) (xy 47.598838 -392.183366)
			(xy 47.598329 -392.211252) (xy 47.590209 -392.266428) (xy 47.574141 -392.319835) (xy 47.550469 -392.370332)
			(xy 47.519696 -392.416845) (xy 47.482479 -392.458382) (xy 47.439611 -392.494057) (xy 47.392005 -392.523111)
			(xy 47.340676 -392.544923) (xy 47.286719 -392.559029) (xy 47.231282 -392.565129) (xy 47.175548 -392.563092)
			(xy 47.120705 -392.552962) (xy 47.067921 -392.534955) (xy 47.018321 -392.509454) (xy 46.972963 -392.477003)
			(xy 46.932814 -392.438294) (xy 46.898728 -392.394151) (xy 46.871432 -392.345516) (xy 46.851509 -392.293425)
			(xy 46.839383 -392.238988) (xy 46.835312 -392.183366) (xy 28.991756 -392.183366) (xy 28.995057 -392.190407)
			(xy 29.011125 -392.243814) (xy 29.019245 -392.29899) (xy 29.019754 -392.326876) (xy 29.019245 -392.354762)
			(xy 29.011125 -392.409938) (xy 28.995057 -392.463345) (xy 28.971385 -392.513842) (xy 28.940612 -392.560355)
			(xy 28.903395 -392.601892) (xy 28.860527 -392.637567) (xy 28.812921 -392.666621) (xy 28.761592 -392.688433)
			(xy 28.707635 -392.702539) (xy 28.652198 -392.708639) (xy 28.596464 -392.706602) (xy 28.541621 -392.696472)
			(xy 28.488837 -392.678465) (xy 28.439237 -392.652964) (xy 28.393879 -392.620513) (xy 28.35373 -392.581804)
			(xy 28.319644 -392.537661) (xy 28.292348 -392.489026) (xy 28.272425 -392.436935) (xy 28.260299 -392.382498)
			(xy 28.256228 -392.326876) (xy 24.22779 -392.326876) (xy 24.22779 -393.342876) (xy 28.256228 -393.342876)
			(xy 28.260299 -393.287254) (xy 28.272425 -393.232817) (xy 28.292348 -393.180726) (xy 28.319644 -393.132091)
			(xy 28.35373 -393.087948) (xy 28.393879 -393.049239) (xy 28.439237 -393.016788) (xy 28.488837 -392.991287)
			(xy 28.541621 -392.97328) (xy 28.596464 -392.96315) (xy 28.652198 -392.961113) (xy 28.707635 -392.967213)
			(xy 28.761592 -392.981319) (xy 28.812921 -393.003131) (xy 28.860527 -393.032185) (xy 28.903395 -393.06786)
			(xy 28.940612 -393.109397) (xy 28.971385 -393.15591) (xy 28.980564 -393.17549) (xy 31.968946 -393.17549)
			(xy 31.973017 -393.119868) (xy 31.985143 -393.065431) (xy 32.005066 -393.01334) (xy 32.032362 -392.964705)
			(xy 32.066448 -392.920562) (xy 32.106597 -392.881853) (xy 32.151955 -392.849402) (xy 32.201555 -392.823901)
			(xy 32.254339 -392.805894) (xy 32.309182 -392.795764) (xy 32.364916 -392.793727) (xy 32.420353 -392.799827)
			(xy 32.47431 -392.813933) (xy 32.525639 -392.835745) (xy 32.573245 -392.864799) (xy 32.616113 -392.900474)
			(xy 32.65333 -392.942011) (xy 32.684103 -392.988524) (xy 32.707775 -393.039021) (xy 32.723843 -393.092428)
			(xy 32.731963 -393.147604) (xy 32.732472 -393.17549) (xy 32.731963 -393.203376) (xy 32.723843 -393.258552)
			(xy 32.707775 -393.311959) (xy 32.684103 -393.362456) (xy 32.65333 -393.408969) (xy 32.616113 -393.450506)
			(xy 32.611761 -393.454128) (xy 38.515034 -393.454128) (xy 38.519105 -393.398506) (xy 38.531231 -393.344069)
			(xy 38.551154 -393.291978) (xy 38.57845 -393.243343) (xy 38.612536 -393.1992) (xy 38.652685 -393.160491)
			(xy 38.698043 -393.12804) (xy 38.747643 -393.102539) (xy 38.800427 -393.084532) (xy 38.85527 -393.074402)
			(xy 38.911004 -393.072365) (xy 38.966441 -393.078465) (xy 39.020398 -393.092571) (xy 39.071727 -393.114383)
			(xy 39.119333 -393.143437) (xy 39.162201 -393.179112) (xy 39.199418 -393.220649) (xy 39.230191 -393.267162)
			(xy 39.253863 -393.317659) (xy 39.269931 -393.371066) (xy 39.278051 -393.426242) (xy 39.27856 -393.454128)
			(xy 39.27837 -393.464542) (xy 40.606978 -393.464542) (xy 40.611049 -393.40892) (xy 40.623175 -393.354483)
			(xy 40.643098 -393.302392) (xy 40.670394 -393.253757) (xy 40.70448 -393.209614) (xy 40.744629 -393.170905)
			(xy 40.789987 -393.138454) (xy 40.839587 -393.112953) (xy 40.892371 -393.094946) (xy 40.947214 -393.084816)
			(xy 41.002948 -393.082779) (xy 41.058385 -393.088879) (xy 41.112342 -393.102985) (xy 41.163671 -393.124797)
			(xy 41.211277 -393.153851) (xy 41.254145 -393.189526) (xy 41.291362 -393.231063) (xy 41.322135 -393.277576)
			(xy 41.340006 -393.315698) (xy 46.835312 -393.315698) (xy 46.839383 -393.260076) (xy 46.851509 -393.205639)
			(xy 46.871432 -393.153548) (xy 46.898728 -393.104913) (xy 46.932814 -393.06077) (xy 46.972963 -393.022061)
			(xy 47.018321 -392.98961) (xy 47.067921 -392.964109) (xy 47.120705 -392.946102) (xy 47.175548 -392.935972)
			(xy 47.231282 -392.933935) (xy 47.286719 -392.940035) (xy 47.340676 -392.954141) (xy 47.392005 -392.975953)
			(xy 47.439611 -393.005007) (xy 47.482479 -393.040682) (xy 47.519696 -393.082219) (xy 47.550469 -393.128732)
			(xy 47.574141 -393.179229) (xy 47.590209 -393.232636) (xy 47.598329 -393.287812) (xy 47.598838 -393.315698)
			(xy 47.598329 -393.343584) (xy 47.590209 -393.39876) (xy 47.574141 -393.452167) (xy 47.550469 -393.502664)
			(xy 47.519696 -393.549177) (xy 47.482479 -393.590714) (xy 47.439611 -393.626389) (xy 47.392005 -393.655443)
			(xy 47.340676 -393.677255) (xy 47.286719 -393.691361) (xy 47.231282 -393.697461) (xy 47.175548 -393.695424)
			(xy 47.120705 -393.685294) (xy 47.067921 -393.667287) (xy 47.018321 -393.641786) (xy 46.972963 -393.609335)
			(xy 46.932814 -393.570626) (xy 46.898728 -393.526483) (xy 46.871432 -393.477848) (xy 46.851509 -393.425757)
			(xy 46.839383 -393.37132) (xy 46.835312 -393.315698) (xy 41.340006 -393.315698) (xy 41.345807 -393.328073)
			(xy 41.361875 -393.38148) (xy 41.369995 -393.436656) (xy 41.370504 -393.464542) (xy 41.369995 -393.492428)
			(xy 41.361875 -393.547604) (xy 41.345807 -393.601011) (xy 41.322135 -393.651508) (xy 41.291362 -393.698021)
			(xy 41.254145 -393.739558) (xy 41.211277 -393.775233) (xy 41.163671 -393.804287) (xy 41.112342 -393.826099)
			(xy 41.058385 -393.840205) (xy 41.002948 -393.846305) (xy 40.947214 -393.844268) (xy 40.892371 -393.834138)
			(xy 40.839587 -393.816131) (xy 40.789987 -393.79063) (xy 40.744629 -393.758179) (xy 40.70448 -393.71947)
			(xy 40.670394 -393.675327) (xy 40.643098 -393.626692) (xy 40.623175 -393.574601) (xy 40.611049 -393.520164)
			(xy 40.606978 -393.464542) (xy 39.27837 -393.464542) (xy 39.278051 -393.482014) (xy 39.269931 -393.53719)
			(xy 39.253863 -393.590597) (xy 39.230191 -393.641094) (xy 39.199418 -393.687607) (xy 39.162201 -393.729144)
			(xy 39.119333 -393.764819) (xy 39.071727 -393.793873) (xy 39.020398 -393.815685) (xy 38.966441 -393.829791)
			(xy 38.911004 -393.835891) (xy 38.85527 -393.833854) (xy 38.800427 -393.823724) (xy 38.747643 -393.805717)
			(xy 38.698043 -393.780216) (xy 38.652685 -393.747765) (xy 38.612536 -393.709056) (xy 38.57845 -393.664913)
			(xy 38.551154 -393.616278) (xy 38.531231 -393.564187) (xy 38.519105 -393.50975) (xy 38.515034 -393.454128)
			(xy 32.611761 -393.454128) (xy 32.573245 -393.486181) (xy 32.525639 -393.515235) (xy 32.47431 -393.537047)
			(xy 32.420353 -393.551153) (xy 32.364916 -393.557253) (xy 32.309182 -393.555216) (xy 32.254339 -393.545086)
			(xy 32.201555 -393.527079) (xy 32.151955 -393.501578) (xy 32.106597 -393.469127) (xy 32.066448 -393.430418)
			(xy 32.032362 -393.386275) (xy 32.005066 -393.33764) (xy 31.985143 -393.285549) (xy 31.973017 -393.231112)
			(xy 31.968946 -393.17549) (xy 28.980564 -393.17549) (xy 28.995057 -393.206407) (xy 29.011125 -393.259814)
			(xy 29.019245 -393.31499) (xy 29.019754 -393.342876) (xy 29.019245 -393.370762) (xy 29.011125 -393.425938)
			(xy 28.995057 -393.479345) (xy 28.971385 -393.529842) (xy 28.940612 -393.576355) (xy 28.903395 -393.617892)
			(xy 28.860527 -393.653567) (xy 28.812921 -393.682621) (xy 28.761592 -393.704433) (xy 28.707635 -393.718539)
			(xy 28.652198 -393.724639) (xy 28.596464 -393.722602) (xy 28.541621 -393.712472) (xy 28.488837 -393.694465)
			(xy 28.439237 -393.668964) (xy 28.393879 -393.636513) (xy 28.35373 -393.597804) (xy 28.319644 -393.553661)
			(xy 28.292348 -393.505026) (xy 28.272425 -393.452935) (xy 28.260299 -393.398498) (xy 28.256228 -393.342876)
			(xy 24.22779 -393.342876) (xy 24.22779 -394.43025) (xy 46.835312 -394.43025) (xy 46.839383 -394.374628)
			(xy 46.851509 -394.320191) (xy 46.871432 -394.2681) (xy 46.898728 -394.219465) (xy 46.932814 -394.175322)
			(xy 46.972963 -394.136613) (xy 47.018321 -394.104162) (xy 47.067921 -394.078661) (xy 47.120705 -394.060654)
			(xy 47.175548 -394.050524) (xy 47.231282 -394.048487) (xy 47.286719 -394.054587) (xy 47.340676 -394.068693)
			(xy 47.392005 -394.090505) (xy 47.439611 -394.119559) (xy 47.482479 -394.155234) (xy 47.519696 -394.196771)
			(xy 47.550469 -394.243284) (xy 47.574141 -394.293781) (xy 47.590209 -394.347188) (xy 47.598329 -394.402364)
			(xy 47.598838 -394.43025) (xy 47.598329 -394.458136) (xy 47.590209 -394.513312) (xy 47.574141 -394.566719)
			(xy 47.550469 -394.617216) (xy 47.519696 -394.663729) (xy 47.482479 -394.705266) (xy 47.439611 -394.740941)
			(xy 47.392005 -394.769995) (xy 47.340676 -394.791807) (xy 47.286719 -394.805913) (xy 47.231282 -394.812013)
			(xy 47.175548 -394.809976) (xy 47.120705 -394.799846) (xy 47.067921 -394.781839) (xy 47.018321 -394.756338)
			(xy 46.972963 -394.723887) (xy 46.932814 -394.685178) (xy 46.898728 -394.641035) (xy 46.871432 -394.5924)
			(xy 46.851509 -394.540309) (xy 46.839383 -394.485872) (xy 46.835312 -394.43025) (xy 24.22779 -394.43025)
			(xy 24.22779 -395.70025) (xy 46.835312 -395.70025) (xy 46.839383 -395.644628) (xy 46.851509 -395.590191)
			(xy 46.871432 -395.5381) (xy 46.898728 -395.489465) (xy 46.932814 -395.445322) (xy 46.972963 -395.406613)
			(xy 47.018321 -395.374162) (xy 47.067921 -395.348661) (xy 47.120705 -395.330654) (xy 47.175548 -395.320524)
			(xy 47.231282 -395.318487) (xy 47.286719 -395.324587) (xy 47.340676 -395.338693) (xy 47.392005 -395.360505)
			(xy 47.439611 -395.389559) (xy 47.482479 -395.425234) (xy 47.519696 -395.466771) (xy 47.550469 -395.513284)
			(xy 47.574141 -395.563781) (xy 47.590209 -395.617188) (xy 47.598329 -395.672364) (xy 47.598838 -395.70025)
			(xy 47.598329 -395.728136) (xy 47.590209 -395.783312) (xy 47.574141 -395.836719) (xy 47.550469 -395.887216)
			(xy 47.519696 -395.933729) (xy 47.482479 -395.975266) (xy 47.439611 -396.010941) (xy 47.392005 -396.039995)
			(xy 47.340676 -396.061807) (xy 47.286719 -396.075913) (xy 47.231282 -396.082013) (xy 47.175548 -396.079976)
			(xy 47.120705 -396.069846) (xy 47.067921 -396.051839) (xy 47.018321 -396.026338) (xy 46.972963 -395.993887)
			(xy 46.932814 -395.955178) (xy 46.898728 -395.911035) (xy 46.871432 -395.8624) (xy 46.851509 -395.810309)
			(xy 46.839383 -395.755872) (xy 46.835312 -395.70025) (xy 24.22779 -395.70025) (xy 24.22779 -396.974314)
			(xy 24.78151 -397.528034) (xy 24.792491 -397.538269) (xy 24.818947 -397.55242) (xy 24.848373 -397.558279)
			(xy 24.878232 -397.55534) (xy 24.905951 -397.543857) (xy 24.929141 -397.524819) (xy 24.945803 -397.499868)
			(xy 24.954502 -397.471154) (xy 24.954992 -397.456152) (xy 24.954992 -396.742412) (xy 24.955444 -396.715016)
			(xy 24.963244 -396.660784) (xy 24.978727 -396.608227) (xy 25.001576 -396.558428) (xy 25.031318 -396.512414)
			(xy 25.048972 -396.49146) (xy 25.058106 -396.48011) (xy 25.070188 -396.453614) (xy 25.074324 -396.424789)
			(xy 25.070181 -396.395964) (xy 25.058094 -396.369471) (xy 25.048972 -396.35811) (xy 25.031331 -396.337178)
			(xy 25.001605 -396.291211) (xy 24.978763 -396.241465) (xy 24.963272 -396.188962) (xy 24.955453 -396.134782)
			(xy 24.954992 -396.107412) (xy 24.955478 -396.080161) (xy 24.963234 -396.026213) (xy 24.978589 -395.973918)
			(xy 25.001231 -395.924341) (xy 25.030697 -395.878491) (xy 25.066388 -395.8373) (xy 25.107579 -395.801609)
			(xy 25.153429 -395.772143) (xy 25.203006 -395.749501) (xy 25.255301 -395.734146) (xy 25.309249 -395.72639)
			(xy 25.363751 -395.72639) (xy 25.417699 -395.734146) (xy 25.469994 -395.749501) (xy 25.519571 -395.772143)
			(xy 25.565421 -395.801609) (xy 25.606612 -395.8373) (xy 25.642303 -395.878491) (xy 25.671769 -395.924341)
			(xy 25.694411 -395.973918) (xy 25.709766 -396.026213) (xy 25.717522 -396.080161) (xy 25.718008 -396.107412)
			(xy 25.717535 -396.134782) (xy 25.70971 -396.188959) (xy 25.694222 -396.241462) (xy 25.671389 -396.291212)
			(xy 25.64168 -396.337189) (xy 25.624028 -396.35811) (xy 25.614793 -396.36941) (xy 25.604929 -396.390876)
			(xy 28.256228 -396.390876) (xy 28.260299 -396.335254) (xy 28.272425 -396.280817) (xy 28.292348 -396.228726)
			(xy 28.319644 -396.180091) (xy 28.35373 -396.135948) (xy 28.393879 -396.097239) (xy 28.439237 -396.064788)
			(xy 28.488837 -396.039287) (xy 28.541621 -396.02128) (xy 28.596464 -396.01115) (xy 28.652198 -396.009113)
			(xy 28.707635 -396.015213) (xy 28.761592 -396.029319) (xy 28.812921 -396.051131) (xy 28.860527 -396.080185)
			(xy 28.903395 -396.11586) (xy 28.940612 -396.157397) (xy 28.971385 -396.20391) (xy 28.995057 -396.254407)
			(xy 29.001115 -396.274544) (xy 35.204398 -396.274544) (xy 35.208469 -396.218922) (xy 35.220595 -396.164485)
			(xy 35.240518 -396.112394) (xy 35.267814 -396.063759) (xy 35.3019 -396.019616) (xy 35.342049 -395.980907)
			(xy 35.387407 -395.948456) (xy 35.437007 -395.922955) (xy 35.489791 -395.904948) (xy 35.544634 -395.894818)
			(xy 35.600368 -395.892781) (xy 35.655805 -395.898881) (xy 35.709762 -395.912987) (xy 35.761091 -395.934799)
			(xy 35.808697 -395.963853) (xy 35.851565 -395.999528) (xy 35.888782 -396.041065) (xy 35.919555 -396.087578)
			(xy 35.943227 -396.138075) (xy 35.959295 -396.191482) (xy 35.967415 -396.246658) (xy 35.967924 -396.274544)
			(xy 35.967415 -396.30243) (xy 35.959295 -396.357606) (xy 35.943227 -396.411013) (xy 35.919555 -396.46151)
			(xy 35.888782 -396.508023) (xy 35.851565 -396.54956) (xy 35.808697 -396.585235) (xy 35.761091 -396.614289)
			(xy 35.709762 -396.636101) (xy 35.655805 -396.650207) (xy 35.600368 -396.656307) (xy 35.544634 -396.65427)
			(xy 35.489791 -396.64414) (xy 35.437007 -396.626133) (xy 35.387407 -396.600632) (xy 35.342049 -396.568181)
			(xy 35.3019 -396.529472) (xy 35.267814 -396.485329) (xy 35.240518 -396.436694) (xy 35.220595 -396.384603)
			(xy 35.208469 -396.330166) (xy 35.204398 -396.274544) (xy 29.001115 -396.274544) (xy 29.011125 -396.307814)
			(xy 29.019245 -396.36299) (xy 29.019754 -396.390876) (xy 29.019245 -396.418762) (xy 29.011125 -396.473938)
			(xy 28.995057 -396.527345) (xy 28.971385 -396.577842) (xy 28.940612 -396.624355) (xy 28.903395 -396.665892)
			(xy 28.860527 -396.701567) (xy 28.812921 -396.730621) (xy 28.761592 -396.752433) (xy 28.707635 -396.766539)
			(xy 28.652198 -396.772639) (xy 28.596464 -396.770602) (xy 28.541621 -396.760472) (xy 28.488837 -396.742465)
			(xy 28.439237 -396.716964) (xy 28.393879 -396.684513) (xy 28.35373 -396.645804) (xy 28.319644 -396.601661)
			(xy 28.292348 -396.553026) (xy 28.272425 -396.500935) (xy 28.260299 -396.446498) (xy 28.256228 -396.390876)
			(xy 25.604929 -396.390876) (xy 25.602612 -396.395917) (xy 25.598436 -396.424789) (xy 25.602606 -396.453661)
			(xy 25.61478 -396.480171) (xy 25.624028 -396.49146) (xy 25.641673 -396.512419) (xy 25.671402 -396.55844)
			(xy 25.694246 -396.608238) (xy 25.709736 -396.660791) (xy 25.717553 -396.715018) (xy 25.718008 -396.742412)
			(xy 25.718008 -397.406876) (xy 28.256228 -397.406876) (xy 28.260299 -397.351254) (xy 28.272425 -397.296817)
			(xy 28.292348 -397.244726) (xy 28.319644 -397.196091) (xy 28.35373 -397.151948) (xy 28.393879 -397.113239)
			(xy 28.439237 -397.080788) (xy 28.488837 -397.055287) (xy 28.541621 -397.03728) (xy 28.596464 -397.02715)
			(xy 28.652198 -397.025113) (xy 28.707635 -397.031213) (xy 28.751345 -397.04264) (xy 32.554162 -397.04264)
			(xy 32.558233 -396.987018) (xy 32.570359 -396.932581) (xy 32.590282 -396.88049) (xy 32.617578 -396.831855)
			(xy 32.651664 -396.787712) (xy 32.691813 -396.749003) (xy 32.737171 -396.716552) (xy 32.786771 -396.691051)
			(xy 32.839555 -396.673044) (xy 32.894398 -396.662914) (xy 32.950132 -396.660877) (xy 33.005569 -396.666977)
			(xy 33.059526 -396.681083) (xy 33.110855 -396.702895) (xy 33.158461 -396.731949) (xy 33.201329 -396.767624)
			(xy 33.238546 -396.809161) (xy 33.269319 -396.855674) (xy 33.292991 -396.906171) (xy 33.309059 -396.959578)
			(xy 33.317179 -397.014754) (xy 33.317688 -397.04264) (xy 33.317179 -397.070526) (xy 33.309059 -397.125702)
			(xy 33.292991 -397.179109) (xy 33.269319 -397.229606) (xy 33.238546 -397.276119) (xy 33.201329 -397.317656)
			(xy 33.158461 -397.353331) (xy 33.110855 -397.382385) (xy 33.059526 -397.404197) (xy 33.005569 -397.418303)
			(xy 32.950132 -397.424403) (xy 32.894398 -397.422366) (xy 32.839555 -397.412236) (xy 32.786771 -397.394229)
			(xy 32.737171 -397.368728) (xy 32.691813 -397.336277) (xy 32.651664 -397.297568) (xy 32.617578 -397.253425)
			(xy 32.590282 -397.20479) (xy 32.570359 -397.152699) (xy 32.558233 -397.098262) (xy 32.554162 -397.04264)
			(xy 28.751345 -397.04264) (xy 28.761592 -397.045319) (xy 28.812921 -397.067131) (xy 28.860527 -397.096185)
			(xy 28.903395 -397.13186) (xy 28.940612 -397.173397) (xy 28.971385 -397.21991) (xy 28.995057 -397.270407)
			(xy 29.011125 -397.323814) (xy 29.019245 -397.37899) (xy 29.019754 -397.406876) (xy 29.019245 -397.434762)
			(xy 29.011125 -397.489938) (xy 28.995057 -397.543345) (xy 28.971385 -397.593842) (xy 28.940612 -397.640355)
			(xy 28.903395 -397.681892) (xy 28.860527 -397.717567) (xy 28.812921 -397.746621) (xy 28.761592 -397.768433)
			(xy 28.707635 -397.782539) (xy 28.652198 -397.788639) (xy 28.596464 -397.786602) (xy 28.541621 -397.776472)
			(xy 28.488837 -397.758465) (xy 28.439237 -397.732964) (xy 28.393879 -397.700513) (xy 28.35373 -397.661804)
			(xy 28.319644 -397.617661) (xy 28.292348 -397.569026) (xy 28.272425 -397.516935) (xy 28.260299 -397.462498)
			(xy 28.256228 -397.406876) (xy 25.718008 -397.406876) (xy 25.718008 -397.606012) (xy 25.717537 -397.633912)
			(xy 25.709438 -397.689121) (xy 25.693386 -397.742562) (xy 25.669722 -397.793095) (xy 25.638952 -397.839644)
			(xy 25.620726 -397.860774) (xy 25.611327 -397.871974) (xy 25.598778 -397.898369) (xy 25.594214 -397.927236)
			(xy 25.598006 -397.956215) (xy 25.609846 -397.982936) (xy 25.618948 -397.994378) (xy 25.635949 -398.015141)
			(xy 25.664567 -398.060535) (xy 25.68654 -398.109493) (xy 25.701433 -398.161048) (xy 25.708954 -398.214181)
			(xy 25.709372 -398.241012) (xy 25.708994 -398.265498) (xy 25.70272 -398.314067) (xy 25.690278 -398.361432)
			(xy 25.681432 -398.384268) (xy 25.668732 -398.415256) (xy 26.537158 -399.283682) (xy 26.537158 -400.050508)
			(xy 26.835354 -400.050508) (xy 26.85796 -400.051016) (xy 26.868751 -400.051175) (xy 26.888919 -400.043549)
			(xy 26.904205 -400.028341) (xy 26.911935 -400.008212) (xy 26.911808 -399.997422) (xy 26.911046 -399.974816)
			(xy 26.911532 -399.947565) (xy 26.919288 -399.893617) (xy 26.934643 -399.841322) (xy 26.957285 -399.791745)
			(xy 26.986751 -399.745895) (xy 27.022442 -399.704704) (xy 27.063633 -399.669013) (xy 27.109483 -399.639547)
			(xy 27.15906 -399.616905) (xy 27.211355 -399.60155) (xy 27.265303 -399.593794) (xy 27.319805 -399.593794)
			(xy 27.373753 -399.60155) (xy 27.426048 -399.616905) (xy 27.475625 -399.639547) (xy 27.521475 -399.669013)
			(xy 27.562666 -399.704704) (xy 27.598357 -399.745895) (xy 27.627823 -399.791745) (xy 27.650465 -399.841322)
			(xy 27.66582 -399.893617) (xy 27.673576 -399.947565) (xy 27.674062 -399.974816) (xy 27.673522 -400.003791)
			(xy 27.664757 -400.061075) (xy 27.64743 -400.116375) (xy 27.62194 -400.168418) (xy 27.588873 -400.216009)
			(xy 27.54899 -400.258052) (xy 27.503208 -400.29358) (xy 27.452579 -400.321777) (xy 27.39827 -400.341994)
			(xy 27.341527 -400.353765) (xy 27.31262 -400.355816) (xy 27.297754 -400.357123) (xy 27.269688 -400.367226)
			(xy 27.245729 -400.384995) (xy 27.227915 -400.408921) (xy 27.21776 -400.436968) (xy 27.216354 -400.451828)
			(xy 27.214308 -400.480747) (xy 27.20257 -400.537517) (xy 27.182377 -400.591858) (xy 27.154194 -400.642518)
			(xy 27.118671 -400.688331) (xy 27.076625 -400.728241) (xy 27.029024 -400.761329) (xy 26.976964 -400.786834)
			(xy 26.921645 -400.804169) (xy 26.86434 -400.812933) (xy 26.835354 -400.813524) (xy 26.537158 -400.813524)
			(xy 26.537158 -402.067776) (xy 26.564844 -402.082) (xy 26.589491 -402.095158) (xy 26.634985 -402.127587)
			(xy 26.675263 -402.166306) (xy 26.709462 -402.210486) (xy 26.736851 -402.259181) (xy 26.756844 -402.311351)
			(xy 26.769014 -402.365879) (xy 26.773099 -402.421599) (xy 26.769014 -402.477319) (xy 26.756845 -402.531847)
			(xy 26.736852 -402.584017) (xy 26.709463 -402.632713) (xy 26.675264 -402.676893) (xy 26.634987 -402.715612)
			(xy 26.589492 -402.748041) (xy 26.564844 -402.761196) (xy 26.537158 -402.77542) (xy 26.537158 -403.3139)
			(xy 26.57729 -403.322536) (xy 26.605327 -403.329131) (xy 26.659154 -403.349618) (xy 26.709291 -403.377962)
			(xy 26.754599 -403.413518) (xy 26.794049 -403.455481) (xy 26.826744 -403.502895) (xy 26.851942 -403.554685)
			(xy 26.86907 -403.609673) (xy 26.87774 -403.666611) (xy 26.87828 -403.695408) (xy 29.285184 -403.695408)
			(xy 29.285709 -403.665612) (xy 29.294975 -403.606745) (xy 29.313282 -403.550035) (xy 29.340184 -403.496861)
			(xy 29.375028 -403.448517) (xy 29.416966 -403.40618) (xy 29.440632 -403.388068) (xy 29.45135 -403.379674)
			(xy 29.468218 -403.358317) (xy 29.478842 -403.333261) (xy 29.482467 -403.306288) (xy 29.478836 -403.279316)
			(xy 29.468206 -403.254263) (xy 29.451333 -403.232909) (xy 29.440632 -403.224492) (xy 29.416983 -403.206363)
			(xy 29.375061 -403.164021) (xy 29.340229 -403.115677) (xy 29.313334 -403.062507) (xy 29.29503 -403.005804)
			(xy 29.285761 -402.946944) (xy 29.285184 -402.917152) (xy 29.28567 -402.889901) (xy 29.293426 -402.835953)
			(xy 29.308781 -402.783658) (xy 29.331423 -402.734081) (xy 29.360889 -402.688231) (xy 29.39658 -402.64704)
			(xy 29.437771 -402.611349) (xy 29.483621 -402.581883) (xy 29.533198 -402.559241) (xy 29.585493 -402.543886)
			(xy 29.639441 -402.53613) (xy 29.693943 -402.53613) (xy 29.747891 -402.543886) (xy 29.800186 -402.559241)
			(xy 29.849763 -402.581883) (xy 29.895613 -402.611349) (xy 29.936804 -402.64704) (xy 29.972495 -402.688231)
			(xy 30.001961 -402.734081) (xy 30.024603 -402.783658) (xy 30.039958 -402.835953) (xy 30.047714 -402.889901)
			(xy 30.0482 -402.917152) (xy 30.047651 -402.946947) (xy 30.038392 -403.005814) (xy 30.02009 -403.062524)
			(xy 29.993192 -403.115698) (xy 29.958351 -403.164041) (xy 29.916416 -403.206379) (xy 29.892752 -403.224492)
			(xy 29.882075 -403.232933) (xy 29.86521 -403.254281) (xy 29.854585 -403.279326) (xy 29.850956 -403.306288)
			(xy 29.854579 -403.333251) (xy 29.865198 -403.358299) (xy 29.882058 -403.37965) (xy 29.892752 -403.388068)
			(xy 29.916426 -403.406166) (xy 29.958348 -403.448514) (xy 29.993177 -403.496864) (xy 30.020068 -403.55004)
			(xy 30.038366 -403.606749) (xy 30.047628 -403.665614) (xy 30.0482 -403.695408) (xy 30.047714 -403.722659)
			(xy 30.039958 -403.776607) (xy 30.024603 -403.828902) (xy 30.001961 -403.878479) (xy 29.972495 -403.924329)
			(xy 29.936804 -403.96552) (xy 29.895613 -404.001211) (xy 29.849763 -404.030677) (xy 29.800186 -404.053319)
			(xy 29.747891 -404.068674) (xy 29.693943 -404.07643) (xy 29.639441 -404.07643) (xy 29.585493 -404.068674)
			(xy 29.533198 -404.053319) (xy 29.483621 -404.030677) (xy 29.437771 -404.001211) (xy 29.39658 -403.96552)
			(xy 29.360889 -403.924329) (xy 29.331423 -403.878479) (xy 29.308781 -403.828902) (xy 29.293426 -403.776607)
			(xy 29.28567 -403.722659) (xy 29.285184 -403.695408) (xy 26.87828 -403.695408) (xy 26.877768 -403.723676)
			(xy 26.869427 -403.779594) (xy 26.852928 -403.833669) (xy 26.828634 -403.884719) (xy 26.797074 -403.931627)
			(xy 26.758941 -403.973367) (xy 26.73731 -403.991572) (xy 26.726001 -404.001503) (xy 26.709249 -404.026487)
			(xy 26.700494 -404.055267) (xy 26.700497 -404.085348) (xy 26.709255 -404.114126) (xy 26.726011 -404.139109)
			(xy 26.73731 -404.149052) (xy 26.758931 -404.16727) (xy 26.797076 -404.208999) (xy 26.828643 -404.255902)
			(xy 26.85294 -404.306951) (xy 26.869434 -404.361028) (xy 26.877763 -404.416948) (xy 26.87828 -404.445216)
			(xy 26.877753 -404.474013) (xy 26.86909 -404.530951) (xy 26.851965 -404.58594) (xy 26.826766 -404.637728)
			(xy 26.794067 -404.685139) (xy 26.75461 -404.727094) (xy 26.709294 -404.762639) (xy 26.659148 -404.790966)
			(xy 26.605313 -404.811431) (xy 26.57729 -404.818088) (xy 26.537158 -404.826724) (xy 26.537158 -406.037288)
			(xy 29.284674 -406.037288) (xy 29.288745 -405.981666) (xy 29.300871 -405.927229) (xy 29.320794 -405.875138)
			(xy 29.34809 -405.826503) (xy 29.382176 -405.78236) (xy 29.422325 -405.743651) (xy 29.467683 -405.7112)
			(xy 29.517283 -405.685699) (xy 29.570067 -405.667692) (xy 29.62491 -405.657562) (xy 29.680644 -405.655525)
			(xy 29.736081 -405.661625) (xy 29.790038 -405.675731) (xy 29.841367 -405.697543) (xy 29.888973 -405.726597)
			(xy 29.889337 -405.7269) (xy 30.918402 -405.7269) (xy 30.922473 -405.671278) (xy 30.934599 -405.616841)
			(xy 30.954522 -405.56475) (xy 30.981818 -405.516115) (xy 31.015904 -405.471972) (xy 31.056053 -405.433263)
			(xy 31.101411 -405.400812) (xy 31.151011 -405.375311) (xy 31.203795 -405.357304) (xy 31.258638 -405.347174)
			(xy 31.314372 -405.345137) (xy 31.369809 -405.351237) (xy 31.423766 -405.365343) (xy 31.475095 -405.387155)
			(xy 31.522701 -405.416209) (xy 31.565569 -405.451884) (xy 31.602786 -405.493421) (xy 31.633559 -405.539934)
			(xy 31.657231 -405.590431) (xy 31.673299 -405.643838) (xy 31.681419 -405.699014) (xy 31.681928 -405.7269)
			(xy 31.681419 -405.754786) (xy 31.673299 -405.809962) (xy 31.657231 -405.863369) (xy 31.633559 -405.913866)
			(xy 31.602786 -405.960379) (xy 31.565569 -406.001916) (xy 31.522701 -406.037591) (xy 31.475095 -406.066645)
			(xy 31.423766 -406.088457) (xy 31.369809 -406.102563) (xy 31.314372 -406.108663) (xy 31.258638 -406.106626)
			(xy 31.203795 -406.096496) (xy 31.151011 -406.078489) (xy 31.101411 -406.052988) (xy 31.056053 -406.020537)
			(xy 31.015904 -405.981828) (xy 30.981818 -405.937685) (xy 30.954522 -405.88905) (xy 30.934599 -405.836959)
			(xy 30.922473 -405.782522) (xy 30.918402 -405.7269) (xy 29.889337 -405.7269) (xy 29.931841 -405.762272)
			(xy 29.969058 -405.803809) (xy 29.999831 -405.850322) (xy 30.023503 -405.900819) (xy 30.039571 -405.954226)
			(xy 30.047691 -406.009402) (xy 30.0482 -406.037288) (xy 30.047691 -406.065174) (xy 30.039571 -406.12035)
			(xy 30.023503 -406.173757) (xy 29.999831 -406.224254) (xy 29.969058 -406.270767) (xy 29.931841 -406.312304)
			(xy 29.888973 -406.347979) (xy 29.841367 -406.377033) (xy 29.790038 -406.398845) (xy 29.736081 -406.412951)
			(xy 29.680644 -406.419051) (xy 29.62491 -406.417014) (xy 29.570067 -406.406884) (xy 29.517283 -406.388877)
			(xy 29.467683 -406.363376) (xy 29.422325 -406.330925) (xy 29.382176 -406.292216) (xy 29.34809 -406.248073)
			(xy 29.320794 -406.199438) (xy 29.300871 -406.147347) (xy 29.288745 -406.09291) (xy 29.284674 -406.037288)
			(xy 26.537158 -406.037288) (xy 26.537158 -406.955752) (xy 26.57729 -406.964388) (xy 26.603862 -406.9706)
			(xy 26.655017 -406.989595) (xy 26.702945 -407.015686) (xy 26.746665 -407.048339) (xy 26.785288 -407.086888)
			(xy 26.818023 -407.130547) (xy 26.844205 -407.178425) (xy 26.863297 -407.229544) (xy 26.874911 -407.282862)
			(xy 26.87881 -407.337292) (xy 26.874913 -407.391721) (xy 26.863302 -407.44504) (xy 26.844212 -407.49616)
			(xy 26.818033 -407.544039) (xy 26.785299 -407.587699) (xy 26.746678 -407.62625) (xy 26.702959 -407.658905)
			(xy 26.655033 -407.684998) (xy 26.603878 -407.703996) (xy 26.57729 -407.710132) (xy 26.537158 -407.718768)
			(xy 26.537158 -407.7208) (xy 27.608782 -407.7208) (xy 27.612853 -407.665178) (xy 27.624979 -407.610741)
			(xy 27.644902 -407.55865) (xy 27.672198 -407.510015) (xy 27.706284 -407.465872) (xy 27.746433 -407.427163)
			(xy 27.791791 -407.394712) (xy 27.841391 -407.369211) (xy 27.894175 -407.351204) (xy 27.949018 -407.341074)
			(xy 28.004752 -407.339037) (xy 28.060189 -407.345137) (xy 28.114146 -407.359243) (xy 28.165475 -407.381055)
			(xy 28.213081 -407.410109) (xy 28.255949 -407.445784) (xy 28.293166 -407.487321) (xy 28.323939 -407.533834)
			(xy 28.347611 -407.584331) (xy 28.363679 -407.637738) (xy 28.371799 -407.692914) (xy 28.372308 -407.7208)
			(xy 28.371799 -407.748686) (xy 28.363679 -407.803862) (xy 28.347611 -407.857269) (xy 28.323939 -407.907766)
			(xy 28.293166 -407.954279) (xy 28.255949 -407.995816) (xy 28.213081 -408.031491) (xy 28.165475 -408.060545)
			(xy 28.114146 -408.082357) (xy 28.060189 -408.096463) (xy 28.004752 -408.102563) (xy 27.949018 -408.100526)
			(xy 27.894175 -408.090396) (xy 27.841391 -408.072389) (xy 27.791791 -408.046888) (xy 27.746433 -408.014437)
			(xy 27.706284 -407.975728) (xy 27.672198 -407.931585) (xy 27.644902 -407.88295) (xy 27.624979 -407.830859)
			(xy 27.612853 -407.776422) (xy 27.608782 -407.7208) (xy 26.537158 -407.7208) (xy 26.537158 -410.784548)
			(xy 29.284674 -410.784548) (xy 29.288745 -410.728926) (xy 29.300871 -410.674489) (xy 29.320794 -410.622398)
			(xy 29.34809 -410.573763) (xy 29.382176 -410.52962) (xy 29.422325 -410.490911) (xy 29.467683 -410.45846)
			(xy 29.517283 -410.432959) (xy 29.570067 -410.414952) (xy 29.62491 -410.404822) (xy 29.680644 -410.402785)
			(xy 29.736081 -410.408885) (xy 29.790038 -410.422991) (xy 29.841367 -410.444803) (xy 29.888973 -410.473857)
			(xy 29.931841 -410.509532) (xy 29.969058 -410.551069) (xy 29.999831 -410.597582) (xy 30.023503 -410.648079)
			(xy 30.039571 -410.701486) (xy 30.047691 -410.756662) (xy 30.0482 -410.784548) (xy 30.047691 -410.812434)
			(xy 30.039571 -410.86761) (xy 30.023503 -410.921017) (xy 29.999831 -410.971514) (xy 29.969058 -411.018027)
			(xy 29.931841 -411.059564) (xy 29.888973 -411.095239) (xy 29.841367 -411.124293) (xy 29.790038 -411.146105)
			(xy 29.736081 -411.160211) (xy 29.680644 -411.166311) (xy 29.62491 -411.164274) (xy 29.570067 -411.154144)
			(xy 29.517283 -411.136137) (xy 29.467683 -411.110636) (xy 29.422325 -411.078185) (xy 29.382176 -411.039476)
			(xy 29.34809 -410.995333) (xy 29.320794 -410.946698) (xy 29.300871 -410.894607) (xy 29.288745 -410.84017)
			(xy 29.284674 -410.784548) (xy 26.537158 -410.784548) (xy 26.537158 -411.703012) (xy 26.57729 -411.711648)
			(xy 26.603858 -411.71786) (xy 26.655005 -411.736854) (xy 26.702924 -411.762942) (xy 26.746637 -411.795591)
			(xy 26.785252 -411.834136) (xy 26.817981 -411.877789) (xy 26.844157 -411.92566) (xy 26.863244 -411.976773)
			(xy 26.874855 -412.030083) (xy 26.878751 -412.084504) (xy 26.87875 -412.08452) (xy 29.970982 -412.08452)
			(xy 29.975053 -412.028898) (xy 29.987179 -411.974461) (xy 30.007102 -411.92237) (xy 30.034398 -411.873735)
			(xy 30.068484 -411.829592) (xy 30.108633 -411.790883) (xy 30.153991 -411.758432) (xy 30.203591 -411.732931)
			(xy 30.256375 -411.714924) (xy 30.311218 -411.704794) (xy 30.366952 -411.702757) (xy 30.422389 -411.708857)
			(xy 30.476346 -411.722963) (xy 30.527675 -411.744775) (xy 30.575281 -411.773829) (xy 30.618149 -411.809504)
			(xy 30.655366 -411.851041) (xy 30.686139 -411.897554) (xy 30.709811 -411.948051) (xy 30.725879 -412.001458)
			(xy 30.733999 -412.056634) (xy 30.734508 -412.08452) (xy 30.733999 -412.112406) (xy 30.725879 -412.167582)
			(xy 30.709811 -412.220989) (xy 30.686139 -412.271486) (xy 30.655366 -412.317999) (xy 30.618149 -412.359536)
			(xy 30.575281 -412.395211) (xy 30.527675 -412.424265) (xy 30.476346 -412.446077) (xy 30.422389 -412.460183)
			(xy 30.366952 -412.466283) (xy 30.311218 -412.464246) (xy 30.256375 -412.454116) (xy 30.203591 -412.436109)
			(xy 30.153991 -412.410608) (xy 30.108633 -412.378157) (xy 30.068484 -412.339448) (xy 30.034398 -412.295305)
			(xy 30.007102 -412.24667) (xy 29.987179 -412.194579) (xy 29.975053 -412.140142) (xy 29.970982 -412.08452)
			(xy 26.87875 -412.08452) (xy 26.874854 -412.138925) (xy 26.863242 -412.192235) (xy 26.844153 -412.243347)
			(xy 26.817976 -412.291218) (xy 26.785246 -412.33487) (xy 26.74663 -412.373414) (xy 26.702917 -412.406063)
			(xy 26.654997 -412.43215) (xy 26.603849 -412.451143) (xy 26.57729 -412.457392) (xy 26.537158 -412.466028)
			(xy 26.537158 -413.131254) (xy 26.580592 -413.137604) (xy 26.607429 -413.142029) (xy 26.659576 -413.157486)
			(xy 26.709 -413.180194) (xy 26.754696 -413.209691) (xy 26.795741 -413.24538) (xy 26.8313 -413.286536)
			(xy 26.860653 -413.332326) (xy 26.883205 -413.38182) (xy 26.898498 -413.434016) (xy 26.906224 -413.487855)
			(xy 26.906224 -413.542245) (xy 26.898499 -413.596084) (xy 26.883205 -413.648279) (xy 26.860653 -413.697774)
			(xy 26.8313 -413.743563) (xy 26.795741 -413.78472) (xy 26.754697 -413.820408) (xy 26.709 -413.849906)
			(xy 26.659577 -413.872613) (xy 26.60743 -413.888071) (xy 26.580592 -413.892492) (xy 26.537158 -413.898842)
			(xy 26.537158 -414.24225) (xy 26.579576 -414.249362) (xy 26.606007 -414.254178) (xy 26.65727 -414.270256)
			(xy 26.705769 -414.293368) (xy 26.750547 -414.323055) (xy 26.790717 -414.358731) (xy 26.825484 -414.399689)
			(xy 26.854161 -414.44512) (xy 26.876181 -414.494125) (xy 26.891108 -414.545734) (xy 26.898647 -414.598928)
			(xy 26.899108 -414.62579) (xy 26.898587 -414.654092) (xy 26.89021 -414.710073) (xy 26.873653 -414.764202)
			(xy 26.849281 -414.81529) (xy 26.817628 -414.862217) (xy 26.779388 -414.903952) (xy 26.735401 -414.939578)
			(xy 26.686634 -414.968314) (xy 26.634155 -414.989529) (xy 26.606754 -414.99663) (xy 26.592784 -415.000186)
			(xy 26.537158 -415.055812) (xy 26.537158 -415.366962) (xy 29.284674 -415.366962) (xy 29.288745 -415.31134)
			(xy 29.300871 -415.256903) (xy 29.320794 -415.204812) (xy 29.34809 -415.156177) (xy 29.382176 -415.112034)
			(xy 29.422325 -415.073325) (xy 29.467683 -415.040874) (xy 29.517283 -415.015373) (xy 29.570067 -414.997366)
			(xy 29.62491 -414.987236) (xy 29.680644 -414.985199) (xy 29.736081 -414.991299) (xy 29.790038 -415.005405)
			(xy 29.841367 -415.027217) (xy 29.888973 -415.056271) (xy 29.931841 -415.091946) (xy 29.969058 -415.133483)
			(xy 29.999831 -415.179996) (xy 30.023503 -415.230493) (xy 30.039571 -415.2839) (xy 30.047691 -415.339076)
			(xy 30.0482 -415.366962) (xy 30.047691 -415.394848) (xy 30.039571 -415.450024) (xy 30.023503 -415.503431)
			(xy 29.999831 -415.553928) (xy 29.969058 -415.600441) (xy 29.931841 -415.641978) (xy 29.888973 -415.677653)
			(xy 29.841367 -415.706707) (xy 29.790038 -415.728519) (xy 29.736081 -415.742625) (xy 29.680644 -415.748725)
			(xy 29.62491 -415.746688) (xy 29.570067 -415.736558) (xy 29.517283 -415.718551) (xy 29.467683 -415.69305)
			(xy 29.422325 -415.660599) (xy 29.382176 -415.62189) (xy 29.34809 -415.577747) (xy 29.320794 -415.529112)
			(xy 29.300871 -415.477021) (xy 29.288745 -415.422584) (xy 29.284674 -415.366962) (xy 26.537158 -415.366962)
			(xy 26.537158 -415.63544) (xy 26.57729 -415.644076) (xy 26.605325 -415.650672) (xy 26.65915 -415.671159)
			(xy 26.709284 -415.699504) (xy 26.754588 -415.735061) (xy 26.794034 -415.777024) (xy 26.826724 -415.824439)
			(xy 26.851917 -415.876228) (xy 26.86904 -415.931216) (xy 26.877703 -415.988152) (xy 26.87828 -416.016948)
			(xy 26.877808 -416.044379) (xy 26.869959 -416.098677) (xy 26.854413 -416.151292) (xy 26.831493 -416.201137)
			(xy 26.801671 -416.247186) (xy 26.765561 -416.28849) (xy 26.723908 -416.324196) (xy 26.700988 -416.339274)
			(xy 26.688877 -416.347489) (xy 26.669593 -416.369484) (xy 26.657348 -416.39605) (xy 26.653152 -416.424999)
			(xy 26.657348 -416.453949) (xy 26.669592 -416.480515) (xy 26.688876 -416.502511) (xy 26.700988 -416.510724)
			(xy 26.723896 -416.525819) (xy 26.765537 -416.561533) (xy 26.801639 -416.602838) (xy 26.83146 -416.648884)
			(xy 26.854385 -416.698723) (xy 26.869944 -416.751329) (xy 26.877814 -416.805621) (xy 26.87828 -416.83305)
			(xy 26.877757 -416.86185) (xy 26.869103 -416.918795) (xy 26.851984 -416.973792) (xy 26.826789 -417.025589)
			(xy 26.794092 -417.073008) (xy 26.754636 -417.114971) (xy 26.709318 -417.150523) (xy 26.659169 -417.178857)
			(xy 26.605329 -417.199327) (xy 26.57729 -417.205922) (xy 26.537158 -417.214558) (xy 26.537158 -424.271948)
			(xy 31.925512 -424.271948) (xy 31.929583 -424.216326) (xy 31.941709 -424.161889) (xy 31.961632 -424.109798)
			(xy 31.988928 -424.061163) (xy 32.023014 -424.01702) (xy 32.063163 -423.978311) (xy 32.108521 -423.94586)
			(xy 32.158121 -423.920359) (xy 32.210905 -423.902352) (xy 32.265748 -423.892222) (xy 32.321482 -423.890185)
			(xy 32.376919 -423.896285) (xy 32.430876 -423.910391) (xy 32.482205 -423.932203) (xy 32.529811 -423.961257)
			(xy 32.572679 -423.996932) (xy 32.609896 -424.038469) (xy 32.640669 -424.084982) (xy 32.664341 -424.135479)
			(xy 32.680409 -424.188886) (xy 32.688529 -424.244062) (xy 32.689038 -424.271948) (xy 32.688529 -424.299834)
			(xy 32.680409 -424.35501) (xy 32.664341 -424.408417) (xy 32.640669 -424.458914) (xy 32.609896 -424.505427)
			(xy 32.572679 -424.546964) (xy 32.529811 -424.582639) (xy 32.482205 -424.611693) (xy 32.430876 -424.633505)
			(xy 32.376919 -424.647611) (xy 32.321482 -424.653711) (xy 32.265748 -424.651674) (xy 32.210905 -424.641544)
			(xy 32.158121 -424.623537) (xy 32.108521 -424.598036) (xy 32.063163 -424.565585) (xy 32.023014 -424.526876)
			(xy 31.988928 -424.482733) (xy 31.961632 -424.434098) (xy 31.941709 -424.382007) (xy 31.929583 -424.32757)
			(xy 31.925512 -424.271948) (xy 26.537158 -424.271948) (xy 26.537158 -425.287948) (xy 32.179512 -425.287948)
			(xy 32.183583 -425.232326) (xy 32.195709 -425.177889) (xy 32.215632 -425.125798) (xy 32.242928 -425.077163)
			(xy 32.277014 -425.03302) (xy 32.317163 -424.994311) (xy 32.362521 -424.96186) (xy 32.412121 -424.936359)
			(xy 32.464905 -424.918352) (xy 32.519748 -424.908222) (xy 32.575482 -424.906185) (xy 32.630919 -424.912285)
			(xy 32.684876 -424.926391) (xy 32.736205 -424.948203) (xy 32.783811 -424.977257) (xy 32.826679 -425.012932)
			(xy 32.863896 -425.054469) (xy 32.894669 -425.100982) (xy 32.918341 -425.151479) (xy 32.934409 -425.204886)
			(xy 32.942529 -425.260062) (xy 32.943038 -425.287948) (xy 32.942529 -425.315834) (xy 32.934409 -425.37101)
			(xy 32.918341 -425.424417) (xy 32.894669 -425.474914) (xy 32.863896 -425.521427) (xy 32.826679 -425.562964)
			(xy 32.783811 -425.598639) (xy 32.736205 -425.627693) (xy 32.684876 -425.649505) (xy 32.630919 -425.663611)
			(xy 32.575482 -425.669711) (xy 32.519748 -425.667674) (xy 32.464905 -425.657544) (xy 32.412121 -425.639537)
			(xy 32.362521 -425.614036) (xy 32.317163 -425.581585) (xy 32.277014 -425.542876) (xy 32.242928 -425.498733)
			(xy 32.215632 -425.450098) (xy 32.195709 -425.398007) (xy 32.183583 -425.34357) (xy 32.179512 -425.287948)
			(xy 26.537158 -425.287948) (xy 26.537158 -426.792898) (xy 29.391862 -426.792898) (xy 29.395933 -426.737276)
			(xy 29.408059 -426.682839) (xy 29.427982 -426.630748) (xy 29.455278 -426.582113) (xy 29.489364 -426.53797)
			(xy 29.529513 -426.499261) (xy 29.574871 -426.46681) (xy 29.624471 -426.441309) (xy 29.677255 -426.423302)
			(xy 29.732098 -426.413172) (xy 29.787832 -426.411135) (xy 29.843269 -426.417235) (xy 29.897226 -426.431341)
			(xy 29.948555 -426.453153) (xy 29.996161 -426.482207) (xy 30.039029 -426.517882) (xy 30.076246 -426.559419)
			(xy 30.107019 -426.605932) (xy 30.130691 -426.656429) (xy 30.146759 -426.709836) (xy 30.154879 -426.765012)
			(xy 30.155388 -426.792898) (xy 30.154879 -426.820784) (xy 30.146759 -426.87596) (xy 30.130691 -426.929367)
			(xy 30.107019 -426.979864) (xy 30.076246 -427.026377) (xy 30.039029 -427.067914) (xy 29.996161 -427.103589)
			(xy 29.948555 -427.132643) (xy 29.897226 -427.154455) (xy 29.843269 -427.168561) (xy 29.787832 -427.174661)
			(xy 29.732098 -427.172624) (xy 29.677255 -427.162494) (xy 29.624471 -427.144487) (xy 29.574871 -427.118986)
			(xy 29.529513 -427.086535) (xy 29.489364 -427.047826) (xy 29.455278 -427.003683) (xy 29.427982 -426.955048)
			(xy 29.408059 -426.902957) (xy 29.395933 -426.84852) (xy 29.391862 -426.792898) (xy 26.537158 -426.792898)
			(xy 26.537158 -427.188884) (xy 31.315912 -427.188884) (xy 31.319983 -427.133262) (xy 31.332109 -427.078825)
			(xy 31.352032 -427.026734) (xy 31.379328 -426.978099) (xy 31.413414 -426.933956) (xy 31.453563 -426.895247)
			(xy 31.498921 -426.862796) (xy 31.548521 -426.837295) (xy 31.601305 -426.819288) (xy 31.656148 -426.809158)
			(xy 31.711882 -426.807121) (xy 31.767319 -426.813221) (xy 31.821276 -426.827327) (xy 31.872605 -426.849139)
			(xy 31.920211 -426.878193) (xy 31.963079 -426.913868) (xy 32.000296 -426.955405) (xy 32.031069 -427.001918)
			(xy 32.054741 -427.052415) (xy 32.070809 -427.105822) (xy 32.078929 -427.160998) (xy 32.079438 -427.188884)
			(xy 32.078929 -427.21677) (xy 32.070809 -427.271946) (xy 32.054741 -427.325353) (xy 32.031069 -427.37585)
			(xy 32.000296 -427.422363) (xy 31.963079 -427.4639) (xy 31.920211 -427.499575) (xy 31.872605 -427.528629)
			(xy 31.821276 -427.550441) (xy 31.767319 -427.564547) (xy 31.711882 -427.570647) (xy 31.656148 -427.56861)
			(xy 31.601305 -427.55848) (xy 31.548521 -427.540473) (xy 31.498921 -427.514972) (xy 31.453563 -427.482521)
			(xy 31.413414 -427.443812) (xy 31.379328 -427.399669) (xy 31.352032 -427.351034) (xy 31.332109 -427.298943)
			(xy 31.319983 -427.244506) (xy 31.315912 -427.188884) (xy 26.537158 -427.188884) (xy 26.537158 -428.843948)
			(xy 31.925512 -428.843948) (xy 31.929583 -428.788326) (xy 31.941709 -428.733889) (xy 31.961632 -428.681798)
			(xy 31.988928 -428.633163) (xy 32.023014 -428.58902) (xy 32.063163 -428.550311) (xy 32.108521 -428.51786)
			(xy 32.158121 -428.492359) (xy 32.210905 -428.474352) (xy 32.265748 -428.464222) (xy 32.321482 -428.462185)
			(xy 32.376919 -428.468285) (xy 32.430876 -428.482391) (xy 32.482205 -428.504203) (xy 32.529811 -428.533257)
			(xy 32.572679 -428.568932) (xy 32.609896 -428.610469) (xy 32.640669 -428.656982) (xy 32.664341 -428.707479)
			(xy 32.680409 -428.760886) (xy 32.688529 -428.816062) (xy 32.689038 -428.843948) (xy 32.688529 -428.871834)
			(xy 32.680409 -428.92701) (xy 32.664341 -428.980417) (xy 32.640669 -429.030914) (xy 32.609896 -429.077427)
			(xy 32.572679 -429.118964) (xy 32.529811 -429.154639) (xy 32.482205 -429.183693) (xy 32.430876 -429.205505)
			(xy 32.376919 -429.219611) (xy 32.321482 -429.225711) (xy 32.265748 -429.223674) (xy 32.210905 -429.213544)
			(xy 32.158121 -429.195537) (xy 32.108521 -429.170036) (xy 32.063163 -429.137585) (xy 32.023014 -429.098876)
			(xy 31.988928 -429.054733) (xy 31.961632 -429.006098) (xy 31.941709 -428.954007) (xy 31.929583 -428.89957)
			(xy 31.925512 -428.843948) (xy 26.537158 -428.843948) (xy 26.537158 -429.859948) (xy 31.925512 -429.859948)
			(xy 31.929583 -429.804326) (xy 31.941709 -429.749889) (xy 31.961632 -429.697798) (xy 31.988928 -429.649163)
			(xy 32.023014 -429.60502) (xy 32.063163 -429.566311) (xy 32.108521 -429.53386) (xy 32.158121 -429.508359)
			(xy 32.210905 -429.490352) (xy 32.265748 -429.480222) (xy 32.321482 -429.478185) (xy 32.376919 -429.484285)
			(xy 32.430876 -429.498391) (xy 32.482205 -429.520203) (xy 32.529811 -429.549257) (xy 32.572679 -429.584932)
			(xy 32.609896 -429.626469) (xy 32.640669 -429.672982) (xy 32.664341 -429.723479) (xy 32.680409 -429.776886)
			(xy 32.688529 -429.832062) (xy 32.689038 -429.859948) (xy 32.688529 -429.887834) (xy 32.680409 -429.94301)
			(xy 32.664341 -429.996417) (xy 32.640669 -430.046914) (xy 32.609896 -430.093427) (xy 32.572679 -430.134964)
			(xy 32.529811 -430.170639) (xy 32.482205 -430.199693) (xy 32.430876 -430.221505) (xy 32.376919 -430.235611)
			(xy 32.321482 -430.241711) (xy 32.265748 -430.239674) (xy 32.210905 -430.229544) (xy 32.158121 -430.211537)
			(xy 32.108521 -430.186036) (xy 32.063163 -430.153585) (xy 32.023014 -430.114876) (xy 31.988928 -430.070733)
			(xy 31.961632 -430.022098) (xy 31.941709 -429.970007) (xy 31.929583 -429.91557) (xy 31.925512 -429.859948)
			(xy 26.537158 -429.859948) (xy 26.537158 -431.510948) (xy 29.537912 -431.510948) (xy 29.541983 -431.455326)
			(xy 29.554109 -431.400889) (xy 29.574032 -431.348798) (xy 29.601328 -431.300163) (xy 29.635414 -431.25602)
			(xy 29.675563 -431.217311) (xy 29.720921 -431.18486) (xy 29.770521 -431.159359) (xy 29.823305 -431.141352)
			(xy 29.878148 -431.131222) (xy 29.933882 -431.129185) (xy 29.989319 -431.135285) (xy 30.043276 -431.149391)
			(xy 30.094605 -431.171203) (xy 30.142211 -431.200257) (xy 30.185079 -431.235932) (xy 30.222296 -431.277469)
			(xy 30.253069 -431.323982) (xy 30.276741 -431.374479) (xy 30.292809 -431.427886) (xy 30.300929 -431.483062)
			(xy 30.301438 -431.510948) (xy 30.300929 -431.538834) (xy 30.292809 -431.59401) (xy 30.276741 -431.647417)
			(xy 30.253069 -431.697914) (xy 30.222296 -431.744427) (xy 30.185079 -431.785964) (xy 30.142211 -431.821639)
			(xy 30.094605 -431.850693) (xy 30.043276 -431.872505) (xy 29.989319 -431.886611) (xy 29.940816 -431.891948)
			(xy 31.925512 -431.891948) (xy 31.929583 -431.836326) (xy 31.941709 -431.781889) (xy 31.961632 -431.729798)
			(xy 31.988928 -431.681163) (xy 32.023014 -431.63702) (xy 32.063163 -431.598311) (xy 32.108521 -431.56586)
			(xy 32.158121 -431.540359) (xy 32.210905 -431.522352) (xy 32.265748 -431.512222) (xy 32.321482 -431.510185)
			(xy 32.376919 -431.516285) (xy 32.430876 -431.530391) (xy 32.482205 -431.552203) (xy 32.529811 -431.581257)
			(xy 32.572679 -431.616932) (xy 32.609896 -431.658469) (xy 32.640669 -431.704982) (xy 32.664341 -431.755479)
			(xy 32.680409 -431.808886) (xy 32.688529 -431.864062) (xy 32.689038 -431.891948) (xy 32.688529 -431.919834)
			(xy 32.680409 -431.97501) (xy 32.664341 -432.028417) (xy 32.640669 -432.078914) (xy 32.609896 -432.125427)
			(xy 32.572679 -432.166964) (xy 32.529811 -432.202639) (xy 32.482205 -432.231693) (xy 32.430876 -432.253505)
			(xy 32.376919 -432.267611) (xy 32.321482 -432.273711) (xy 32.265748 -432.271674) (xy 32.210905 -432.261544)
			(xy 32.158121 -432.243537) (xy 32.108521 -432.218036) (xy 32.063163 -432.185585) (xy 32.023014 -432.146876)
			(xy 31.988928 -432.102733) (xy 31.961632 -432.054098) (xy 31.941709 -432.002007) (xy 31.929583 -431.94757)
			(xy 31.925512 -431.891948) (xy 29.940816 -431.891948) (xy 29.933882 -431.892711) (xy 29.878148 -431.890674)
			(xy 29.823305 -431.880544) (xy 29.770521 -431.862537) (xy 29.720921 -431.837036) (xy 29.675563 -431.804585)
			(xy 29.635414 -431.765876) (xy 29.601328 -431.721733) (xy 29.574032 -431.673098) (xy 29.554109 -431.621007)
			(xy 29.541983 -431.56657) (xy 29.537912 -431.510948) (xy 26.537158 -431.510948) (xy 26.537158 -432.434053)
			(xy 36.411861 -432.434053) (xy 36.411861 -432.379547) (xy 36.419619 -432.325595) (xy 36.434975 -432.273297)
			(xy 36.457619 -432.223717) (xy 36.487088 -432.177863) (xy 36.522782 -432.136671) (xy 36.563976 -432.100978)
			(xy 36.609831 -432.071511) (xy 36.659412 -432.04887) (xy 36.711711 -432.033515) (xy 36.765663 -432.02576)
			(xy 36.792916 -432.025298) (xy 36.821831 -432.025877) (xy 36.878999 -432.034594) (xy 36.934197 -432.05184)
			(xy 36.986159 -432.07722) (xy 37.033694 -432.110153) (xy 37.075714 -432.149883) (xy 37.093906 -432.172364)
			(xy 37.102655 -432.182765) (xy 37.124399 -432.199044) (xy 37.149669 -432.209006) (xy 37.176672 -432.211943)
			(xy 37.203493 -432.207648) (xy 37.228228 -432.196424) (xy 37.249123 -432.179069) (xy 37.264696 -432.156813)
			(xy 37.269674 -432.14417) (xy 37.280062 -432.116809) (xy 37.308009 -432.065389) (xy 37.343477 -432.018838)
			(xy 37.385636 -431.978248) (xy 37.433498 -431.944568) (xy 37.48594 -431.91859) (xy 37.541732 -431.900921)
			(xy 37.599568 -431.891977) (xy 37.62883 -431.89144) (xy 37.656083 -431.891832) (xy 37.710035 -431.899593)
			(xy 37.762332 -431.914953) (xy 37.811912 -431.937598) (xy 37.857764 -431.967069) (xy 37.898956 -432.002765)
			(xy 37.934649 -432.04396) (xy 37.964116 -432.089814) (xy 37.986758 -432.139396) (xy 38.002113 -432.191695)
			(xy 38.00987 -432.245647) (xy 38.00987 -432.300153) (xy 38.002113 -432.354105) (xy 37.986758 -432.406404)
			(xy 37.964116 -432.455986) (xy 37.934649 -432.50184) (xy 37.898956 -432.543035) (xy 37.857764 -432.578731)
			(xy 37.811912 -432.608202) (xy 37.762332 -432.630847) (xy 37.710035 -432.646207) (xy 37.656222 -432.653948)
			(xy 52.524912 -432.653948) (xy 52.528983 -432.598326) (xy 52.541109 -432.543889) (xy 52.561032 -432.491798)
			(xy 52.588328 -432.443163) (xy 52.622414 -432.39902) (xy 52.662563 -432.360311) (xy 52.707921 -432.32786)
			(xy 52.757521 -432.302359) (xy 52.810305 -432.284352) (xy 52.865148 -432.274222) (xy 52.920882 -432.272185)
			(xy 52.976319 -432.278285) (xy 53.030276 -432.292391) (xy 53.081605 -432.314203) (xy 53.129211 -432.343257)
			(xy 53.172079 -432.378932) (xy 53.209296 -432.420469) (xy 53.240069 -432.466982) (xy 53.263741 -432.517479)
			(xy 53.279809 -432.570886) (xy 53.287929 -432.626062) (xy 53.288438 -432.653948) (xy 53.287929 -432.681834)
			(xy 53.279809 -432.73701) (xy 53.263741 -432.790417) (xy 53.240069 -432.840914) (xy 53.209296 -432.887427)
			(xy 53.172079 -432.928964) (xy 53.129211 -432.964639) (xy 53.081605 -432.993693) (xy 53.030276 -433.015505)
			(xy 52.976319 -433.029611) (xy 52.920882 -433.035711) (xy 52.865148 -433.033674) (xy 52.810305 -433.023544)
			(xy 52.757521 -433.005537) (xy 52.707921 -432.980036) (xy 52.662563 -432.947585) (xy 52.622414 -432.908876)
			(xy 52.588328 -432.864733) (xy 52.561032 -432.816098) (xy 52.541109 -432.764007) (xy 52.528983 -432.70957)
			(xy 52.524912 -432.653948) (xy 37.656222 -432.653948) (xy 37.656083 -432.653968) (xy 37.62883 -432.654456)
			(xy 37.599913 -432.653933) (xy 37.542741 -432.645207) (xy 37.487542 -432.627951) (xy 37.43558 -432.602561)
			(xy 37.388046 -432.569617) (xy 37.34603 -432.529876) (xy 37.32784 -432.50739) (xy 37.319171 -432.496915)
			(xy 37.297413 -432.480624) (xy 37.272124 -432.470658) (xy 37.245102 -432.467724) (xy 37.218264 -432.472031)
			(xy 37.193516 -432.483271) (xy 37.172615 -432.500649) (xy 37.157045 -432.522929) (xy 37.152072 -432.535584)
			(xy 37.141705 -432.562954) (xy 37.113758 -432.614377) (xy 37.078289 -432.660931) (xy 37.036127 -432.701523)
			(xy 36.988262 -432.735202) (xy 36.935816 -432.761178) (xy 36.880019 -432.778843) (xy 36.822179 -432.787781)
			(xy 36.792916 -432.788314) (xy 36.765663 -432.78784) (xy 36.711711 -432.780085) (xy 36.659412 -432.76473)
			(xy 36.609831 -432.742089) (xy 36.563976 -432.712622) (xy 36.522782 -432.676929) (xy 36.487088 -432.635737)
			(xy 36.457619 -432.589883) (xy 36.434975 -432.540303) (xy 36.419619 -432.488005) (xy 36.411861 -432.434053)
			(xy 26.537158 -432.434053) (xy 26.537158 -432.907948) (xy 31.925512 -432.907948) (xy 31.929583 -432.852326)
			(xy 31.941709 -432.797889) (xy 31.961632 -432.745798) (xy 31.988928 -432.697163) (xy 32.023014 -432.65302)
			(xy 32.063163 -432.614311) (xy 32.108521 -432.58186) (xy 32.158121 -432.556359) (xy 32.210905 -432.538352)
			(xy 32.265748 -432.528222) (xy 32.321482 -432.526185) (xy 32.376919 -432.532285) (xy 32.430876 -432.546391)
			(xy 32.482205 -432.568203) (xy 32.529811 -432.597257) (xy 32.572679 -432.632932) (xy 32.609896 -432.674469)
			(xy 32.640669 -432.720982) (xy 32.664341 -432.771479) (xy 32.680409 -432.824886) (xy 32.688529 -432.880062)
			(xy 32.689038 -432.907948) (xy 32.688529 -432.935834) (xy 32.680409 -432.99101) (xy 32.664341 -433.044417)
			(xy 32.640669 -433.094914) (xy 32.609896 -433.141427) (xy 32.572679 -433.182964) (xy 32.529811 -433.218639)
			(xy 32.482205 -433.247693) (xy 32.430876 -433.269505) (xy 32.376919 -433.283611) (xy 32.321482 -433.289711)
			(xy 32.265748 -433.287674) (xy 32.210905 -433.277544) (xy 32.158121 -433.259537) (xy 32.108521 -433.234036)
			(xy 32.063163 -433.201585) (xy 32.023014 -433.162876) (xy 31.988928 -433.118733) (xy 31.961632 -433.070098)
			(xy 31.941709 -433.018007) (xy 31.929583 -432.96357) (xy 31.925512 -432.907948) (xy 26.537158 -432.907948)
			(xy 26.537158 -433.923948) (xy 31.925512 -433.923948) (xy 31.929583 -433.868326) (xy 31.941709 -433.813889)
			(xy 31.961632 -433.761798) (xy 31.988928 -433.713163) (xy 32.023014 -433.66902) (xy 32.063163 -433.630311)
			(xy 32.108521 -433.59786) (xy 32.158121 -433.572359) (xy 32.210905 -433.554352) (xy 32.265748 -433.544222)
			(xy 32.321482 -433.542185) (xy 32.376919 -433.548285) (xy 32.430876 -433.562391) (xy 32.482205 -433.584203)
			(xy 32.529811 -433.613257) (xy 32.572679 -433.648932) (xy 32.609896 -433.690469) (xy 32.640669 -433.736982)
			(xy 32.664341 -433.787479) (xy 32.680409 -433.840886) (xy 32.688529 -433.896062) (xy 32.689038 -433.923948)
			(xy 32.688529 -433.951834) (xy 32.686278 -433.967128) (xy 38.937944 -433.967128) (xy 38.942015 -433.911506)
			(xy 38.954141 -433.857069) (xy 38.974064 -433.804978) (xy 39.00136 -433.756343) (xy 39.035446 -433.7122)
			(xy 39.075595 -433.673491) (xy 39.120953 -433.64104) (xy 39.170553 -433.615539) (xy 39.223337 -433.597532)
			(xy 39.27818 -433.587402) (xy 39.333914 -433.585365) (xy 39.389351 -433.591465) (xy 39.443308 -433.605571)
			(xy 39.494637 -433.627383) (xy 39.542243 -433.656437) (xy 39.585111 -433.692112) (xy 39.622328 -433.733649)
			(xy 39.653101 -433.780162) (xy 39.676773 -433.830659) (xy 39.678858 -433.837588) (xy 40.590722 -433.837588)
			(xy 40.594793 -433.781966) (xy 40.606919 -433.727529) (xy 40.626842 -433.675438) (xy 40.654138 -433.626803)
			(xy 40.688224 -433.58266) (xy 40.728373 -433.543951) (xy 40.773731 -433.5115) (xy 40.823331 -433.485999)
			(xy 40.876115 -433.467992) (xy 40.930958 -433.457862) (xy 40.986692 -433.455825) (xy 41.042129 -433.461925)
			(xy 41.096086 -433.476031) (xy 41.147415 -433.497843) (xy 41.195021 -433.526897) (xy 41.237889 -433.562572)
			(xy 41.275106 -433.604109) (xy 41.305879 -433.650622) (xy 41.329551 -433.701119) (xy 41.344321 -433.750212)
			(xy 41.916348 -433.750212) (xy 41.920419 -433.69459) (xy 41.932545 -433.640153) (xy 41.952468 -433.588062)
			(xy 41.979764 -433.539427) (xy 42.01385 -433.495284) (xy 42.053999 -433.456575) (xy 42.099357 -433.424124)
			(xy 42.148957 -433.398623) (xy 42.201741 -433.380616) (xy 42.256584 -433.370486) (xy 42.312318 -433.368449)
			(xy 42.367755 -433.374549) (xy 42.421712 -433.388655) (xy 42.473041 -433.410467) (xy 42.520647 -433.439521)
			(xy 42.563515 -433.475196) (xy 42.600732 -433.516733) (xy 42.631505 -433.563246) (xy 42.655177 -433.613743)
			(xy 42.671245 -433.66715) (xy 42.679365 -433.722326) (xy 42.679874 -433.750212) (xy 42.679365 -433.778098)
			(xy 42.671245 -433.833274) (xy 42.655177 -433.886681) (xy 42.631505 -433.937178) (xy 42.600732 -433.983691)
			(xy 42.563515 -434.025228) (xy 42.520647 -434.060903) (xy 42.473041 -434.089957) (xy 42.472191 -434.090318)
			(xy 49.404522 -434.090318) (xy 49.408593 -434.034696) (xy 49.420719 -433.980259) (xy 49.440642 -433.928168)
			(xy 49.467938 -433.879533) (xy 49.502024 -433.83539) (xy 49.542173 -433.796681) (xy 49.587531 -433.76423)
			(xy 49.637131 -433.738729) (xy 49.689915 -433.720722) (xy 49.744758 -433.710592) (xy 49.800492 -433.708555)
			(xy 49.855929 -433.714655) (xy 49.909886 -433.728761) (xy 49.961215 -433.750573) (xy 50.008821 -433.779627)
			(xy 50.051689 -433.815302) (xy 50.088906 -433.856839) (xy 50.119679 -433.903352) (xy 50.143351 -433.953849)
			(xy 50.159419 -434.007256) (xy 50.167539 -434.062432) (xy 50.168048 -434.090318) (xy 50.167539 -434.118204)
			(xy 50.159419 -434.17338) (xy 50.143351 -434.226787) (xy 50.119679 -434.277284) (xy 50.088906 -434.323797)
			(xy 50.051689 -434.365334) (xy 50.008821 -434.401009) (xy 49.961215 -434.430063) (xy 49.909886 -434.451875)
			(xy 49.855929 -434.465981) (xy 49.800492 -434.472081) (xy 49.744758 -434.470044) (xy 49.689915 -434.459914)
			(xy 49.637131 -434.441907) (xy 49.587531 -434.416406) (xy 49.542173 -434.383955) (xy 49.502024 -434.345246)
			(xy 49.467938 -434.301103) (xy 49.440642 -434.252468) (xy 49.420719 -434.200377) (xy 49.408593 -434.14594)
			(xy 49.404522 -434.090318) (xy 42.472191 -434.090318) (xy 42.421712 -434.111769) (xy 42.367755 -434.125875)
			(xy 42.312318 -434.131975) (xy 42.256584 -434.129938) (xy 42.201741 -434.119808) (xy 42.148957 -434.101801)
			(xy 42.099357 -434.0763) (xy 42.053999 -434.043849) (xy 42.01385 -434.00514) (xy 41.979764 -433.960997)
			(xy 41.952468 -433.912362) (xy 41.932545 -433.860271) (xy 41.920419 -433.805834) (xy 41.916348 -433.750212)
			(xy 41.344321 -433.750212) (xy 41.345619 -433.754526) (xy 41.353739 -433.809702) (xy 41.354248 -433.837588)
			(xy 41.353739 -433.865474) (xy 41.345619 -433.92065) (xy 41.329551 -433.974057) (xy 41.305879 -434.024554)
			(xy 41.275106 -434.071067) (xy 41.237889 -434.112604) (xy 41.195021 -434.148279) (xy 41.147415 -434.177333)
			(xy 41.096086 -434.199145) (xy 41.042129 -434.213251) (xy 40.986692 -434.219351) (xy 40.930958 -434.217314)
			(xy 40.876115 -434.207184) (xy 40.823331 -434.189177) (xy 40.773731 -434.163676) (xy 40.728373 -434.131225)
			(xy 40.688224 -434.092516) (xy 40.654138 -434.048373) (xy 40.626842 -433.999738) (xy 40.606919 -433.947647)
			(xy 40.594793 -433.89321) (xy 40.590722 -433.837588) (xy 39.678858 -433.837588) (xy 39.692841 -433.884066)
			(xy 39.700961 -433.939242) (xy 39.70147 -433.967128) (xy 39.700961 -433.995014) (xy 39.692841 -434.05019)
			(xy 39.676773 -434.103597) (xy 39.653101 -434.154094) (xy 39.622328 -434.200607) (xy 39.585111 -434.242144)
			(xy 39.542243 -434.277819) (xy 39.494637 -434.306873) (xy 39.443308 -434.328685) (xy 39.389351 -434.342791)
			(xy 39.333914 -434.348891) (xy 39.27818 -434.346854) (xy 39.223337 -434.336724) (xy 39.170553 -434.318717)
			(xy 39.120953 -434.293216) (xy 39.075595 -434.260765) (xy 39.035446 -434.222056) (xy 39.00136 -434.177913)
			(xy 38.974064 -434.129278) (xy 38.954141 -434.077187) (xy 38.942015 -434.02275) (xy 38.937944 -433.967128)
			(xy 32.686278 -433.967128) (xy 32.680409 -434.00701) (xy 32.664341 -434.060417) (xy 32.640669 -434.110914)
			(xy 32.609896 -434.157427) (xy 32.572679 -434.198964) (xy 32.529811 -434.234639) (xy 32.482205 -434.263693)
			(xy 32.430876 -434.285505) (xy 32.376919 -434.299611) (xy 32.321482 -434.305711) (xy 32.265748 -434.303674)
			(xy 32.210905 -434.293544) (xy 32.158121 -434.275537) (xy 32.108521 -434.250036) (xy 32.063163 -434.217585)
			(xy 32.023014 -434.178876) (xy 31.988928 -434.134733) (xy 31.961632 -434.086098) (xy 31.941709 -434.034007)
			(xy 31.929583 -433.97957) (xy 31.925512 -433.923948) (xy 26.537158 -433.923948) (xy 26.537158 -435.233318)
			(xy 39.024812 -435.233318) (xy 39.028883 -435.177696) (xy 39.041009 -435.123259) (xy 39.060932 -435.071168)
			(xy 39.088228 -435.022533) (xy 39.122314 -434.97839) (xy 39.162463 -434.939681) (xy 39.207821 -434.90723)
			(xy 39.257421 -434.881729) (xy 39.310205 -434.863722) (xy 39.365048 -434.853592) (xy 39.420782 -434.851555)
			(xy 39.427716 -434.852318) (xy 41.507662 -434.852318) (xy 41.511733 -434.796696) (xy 41.523859 -434.742259)
			(xy 41.543782 -434.690168) (xy 41.571078 -434.641533) (xy 41.605164 -434.59739) (xy 41.645313 -434.558681)
			(xy 41.690671 -434.52623) (xy 41.740271 -434.500729) (xy 41.793055 -434.482722) (xy 41.847898 -434.472592)
			(xy 41.903632 -434.470555) (xy 41.959069 -434.476655) (xy 42.013026 -434.490761) (xy 42.064355 -434.512573)
			(xy 42.111961 -434.541627) (xy 42.154829 -434.577302) (xy 42.192046 -434.618839) (xy 42.222819 -434.665352)
			(xy 42.246491 -434.715849) (xy 42.256141 -434.747924) (xy 48.744122 -434.747924) (xy 48.748193 -434.692302)
			(xy 48.760319 -434.637865) (xy 48.780242 -434.585774) (xy 48.807538 -434.537139) (xy 48.841624 -434.492996)
			(xy 48.881773 -434.454287) (xy 48.927131 -434.421836) (xy 48.976731 -434.396335) (xy 49.029515 -434.378328)
			(xy 49.084358 -434.368198) (xy 49.140092 -434.366161) (xy 49.195529 -434.372261) (xy 49.249486 -434.386367)
			(xy 49.300815 -434.408179) (xy 49.348421 -434.437233) (xy 49.391289 -434.472908) (xy 49.428506 -434.514445)
			(xy 49.459279 -434.560958) (xy 49.482951 -434.611455) (xy 49.499019 -434.664862) (xy 49.507139 -434.720038)
			(xy 49.507648 -434.747924) (xy 49.507139 -434.77581) (xy 49.499019 -434.830986) (xy 49.482951 -434.884393)
			(xy 49.459279 -434.93489) (xy 49.428506 -434.981403) (xy 49.391289 -435.02294) (xy 49.348421 -435.058615)
			(xy 49.300815 -435.087669) (xy 49.249486 -435.109481) (xy 49.195529 -435.123587) (xy 49.140092 -435.129687)
			(xy 49.084358 -435.12765) (xy 49.029515 -435.11752) (xy 48.976731 -435.099513) (xy 48.927131 -435.074012)
			(xy 48.881773 -435.041561) (xy 48.841624 -435.002852) (xy 48.807538 -434.958709) (xy 48.780242 -434.910074)
			(xy 48.760319 -434.857983) (xy 48.748193 -434.803546) (xy 48.744122 -434.747924) (xy 42.256141 -434.747924)
			(xy 42.262559 -434.769256) (xy 42.270679 -434.824432) (xy 42.271188 -434.852318) (xy 42.270679 -434.880204)
			(xy 42.262559 -434.93538) (xy 42.246491 -434.988787) (xy 42.222819 -435.039284) (xy 42.192046 -435.085797)
			(xy 42.154829 -435.127334) (xy 42.111961 -435.163009) (xy 42.064355 -435.192063) (xy 42.013026 -435.213875)
			(xy 41.959069 -435.227981) (xy 41.903632 -435.234081) (xy 41.847898 -435.232044) (xy 41.793055 -435.221914)
			(xy 41.740271 -435.203907) (xy 41.690671 -435.178406) (xy 41.645313 -435.145955) (xy 41.605164 -435.107246)
			(xy 41.571078 -435.063103) (xy 41.543782 -435.014468) (xy 41.523859 -434.962377) (xy 41.511733 -434.90794)
			(xy 41.507662 -434.852318) (xy 39.427716 -434.852318) (xy 39.476219 -434.857655) (xy 39.530176 -434.871761)
			(xy 39.581505 -434.893573) (xy 39.629111 -434.922627) (xy 39.671979 -434.958302) (xy 39.709196 -434.999839)
			(xy 39.739969 -435.046352) (xy 39.763641 -435.096849) (xy 39.779709 -435.150256) (xy 39.787829 -435.205432)
			(xy 39.788338 -435.233318) (xy 39.787829 -435.261204) (xy 39.779709 -435.31638) (xy 39.763641 -435.369787)
			(xy 39.739969 -435.420284) (xy 39.709196 -435.466797) (xy 39.690809 -435.487318) (xy 49.297842 -435.487318)
			(xy 49.301913 -435.431696) (xy 49.314039 -435.377259) (xy 49.333962 -435.325168) (xy 49.361258 -435.276533)
			(xy 49.395344 -435.23239) (xy 49.435493 -435.193681) (xy 49.480851 -435.16123) (xy 49.530451 -435.135729)
			(xy 49.583235 -435.117722) (xy 49.638078 -435.107592) (xy 49.693812 -435.105555) (xy 49.749249 -435.111655)
			(xy 49.803206 -435.125761) (xy 49.854535 -435.147573) (xy 49.902141 -435.176627) (xy 49.945009 -435.212302)
			(xy 49.951322 -435.219348) (xy 54.004462 -435.219348) (xy 54.008533 -435.163726) (xy 54.020659 -435.109289)
			(xy 54.040582 -435.057198) (xy 54.067878 -435.008563) (xy 54.101964 -434.96442) (xy 54.142113 -434.925711)
			(xy 54.187471 -434.89326) (xy 54.237071 -434.867759) (xy 54.289855 -434.849752) (xy 54.344698 -434.839622)
			(xy 54.400432 -434.837585) (xy 54.455869 -434.843685) (xy 54.509826 -434.857791) (xy 54.561155 -434.879603)
			(xy 54.608761 -434.908657) (xy 54.651629 -434.944332) (xy 54.688846 -434.985869) (xy 54.719619 -435.032382)
			(xy 54.743291 -435.082879) (xy 54.759359 -435.136286) (xy 54.767479 -435.191462) (xy 54.767988 -435.219348)
			(xy 54.767479 -435.247234) (xy 54.759359 -435.30241) (xy 54.743291 -435.355817) (xy 54.719619 -435.406314)
			(xy 54.688846 -435.452827) (xy 54.651629 -435.494364) (xy 54.608761 -435.530039) (xy 54.561155 -435.559093)
			(xy 54.509826 -435.580905) (xy 54.455869 -435.595011) (xy 54.400432 -435.601111) (xy 54.344698 -435.599074)
			(xy 54.289855 -435.588944) (xy 54.237071 -435.570937) (xy 54.187471 -435.545436) (xy 54.142113 -435.512985)
			(xy 54.101964 -435.474276) (xy 54.067878 -435.430133) (xy 54.040582 -435.381498) (xy 54.020659 -435.329407)
			(xy 54.008533 -435.27497) (xy 54.004462 -435.219348) (xy 49.951322 -435.219348) (xy 49.982226 -435.253839)
			(xy 50.012999 -435.300352) (xy 50.036671 -435.350849) (xy 50.052739 -435.404256) (xy 50.060859 -435.459432)
			(xy 50.061368 -435.487318) (xy 50.060859 -435.515204) (xy 50.052739 -435.57038) (xy 50.036671 -435.623787)
			(xy 50.012999 -435.674284) (xy 49.982226 -435.720797) (xy 49.945009 -435.762334) (xy 49.902141 -435.798009)
			(xy 49.854535 -435.827063) (xy 49.803206 -435.848875) (xy 49.749249 -435.862981) (xy 49.693812 -435.869081)
			(xy 49.638078 -435.867044) (xy 49.583235 -435.856914) (xy 49.530451 -435.838907) (xy 49.480851 -435.813406)
			(xy 49.435493 -435.780955) (xy 49.395344 -435.742246) (xy 49.361258 -435.698103) (xy 49.333962 -435.649468)
			(xy 49.314039 -435.597377) (xy 49.301913 -435.54294) (xy 49.297842 -435.487318) (xy 39.690809 -435.487318)
			(xy 39.671979 -435.508334) (xy 39.629111 -435.544009) (xy 39.581505 -435.573063) (xy 39.530176 -435.594875)
			(xy 39.476219 -435.608981) (xy 39.420782 -435.615081) (xy 39.365048 -435.613044) (xy 39.310205 -435.602914)
			(xy 39.257421 -435.584907) (xy 39.207821 -435.559406) (xy 39.162463 -435.526955) (xy 39.122314 -435.488246)
			(xy 39.088228 -435.444103) (xy 39.060932 -435.395468) (xy 39.041009 -435.343377) (xy 39.028883 -435.28894)
			(xy 39.024812 -435.233318) (xy 26.537158 -435.233318) (xy 26.537158 -436.268368) (xy 34.79495 -436.268368)
			(xy 34.799021 -436.212746) (xy 34.811147 -436.158309) (xy 34.83107 -436.106218) (xy 34.858366 -436.057583)
			(xy 34.892452 -436.01344) (xy 34.932601 -435.974731) (xy 34.977959 -435.94228) (xy 35.027559 -435.916779)
			(xy 35.080343 -435.898772) (xy 35.135186 -435.888642) (xy 35.19092 -435.886605) (xy 35.246357 -435.892705)
			(xy 35.300314 -435.906811) (xy 35.351643 -435.928623) (xy 35.399249 -435.957677) (xy 35.442117 -435.993352)
			(xy 35.479334 -436.034889) (xy 35.510107 -436.081402) (xy 35.533779 -436.131899) (xy 35.549847 -436.185306)
			(xy 35.557967 -436.240482) (xy 35.558337 -436.260748) (xy 36.326062 -436.260748) (xy 36.330133 -436.205126)
			(xy 36.342259 -436.150689) (xy 36.362182 -436.098598) (xy 36.389478 -436.049963) (xy 36.423564 -436.00582)
			(xy 36.463713 -435.967111) (xy 36.509071 -435.93466) (xy 36.558671 -435.909159) (xy 36.611455 -435.891152)
			(xy 36.666298 -435.881022) (xy 36.722032 -435.878985) (xy 36.777469 -435.885085) (xy 36.831426 -435.899191)
			(xy 36.882755 -435.921003) (xy 36.930361 -435.950057) (xy 36.973229 -435.985732) (xy 37.010446 -436.027269)
			(xy 37.041219 -436.073782) (xy 37.063972 -436.122318) (xy 41.035222 -436.122318) (xy 41.039293 -436.066696)
			(xy 41.051419 -436.012259) (xy 41.071342 -435.960168) (xy 41.098638 -435.911533) (xy 41.132724 -435.86739)
			(xy 41.172873 -435.828681) (xy 41.218231 -435.79623) (xy 41.267831 -435.770729) (xy 41.320615 -435.752722)
			(xy 41.375458 -435.742592) (xy 41.431192 -435.740555) (xy 41.486629 -435.746655) (xy 41.540586 -435.760761)
			(xy 41.591915 -435.782573) (xy 41.639521 -435.811627) (xy 41.682389 -435.847302) (xy 41.719606 -435.888839)
			(xy 41.750379 -435.935352) (xy 41.774051 -435.985849) (xy 41.790119 -436.039256) (xy 41.798239 -436.094432)
			(xy 41.798748 -436.122318) (xy 41.798239 -436.150204) (xy 41.790119 -436.20538) (xy 41.774051 -436.258787)
			(xy 41.750379 -436.309284) (xy 41.719606 -436.355797) (xy 41.682389 -436.397334) (xy 41.639521 -436.433009)
			(xy 41.591915 -436.462063) (xy 41.540586 -436.483875) (xy 41.486629 -436.497981) (xy 41.431192 -436.504081)
			(xy 41.375458 -436.502044) (xy 41.320615 -436.491914) (xy 41.267831 -436.473907) (xy 41.218231 -436.448406)
			(xy 41.172873 -436.415955) (xy 41.132724 -436.377246) (xy 41.098638 -436.333103) (xy 41.071342 -436.284468)
			(xy 41.051419 -436.232377) (xy 41.039293 -436.17794) (xy 41.035222 -436.122318) (xy 37.063972 -436.122318)
			(xy 37.064891 -436.124279) (xy 37.080959 -436.177686) (xy 37.089079 -436.232862) (xy 37.089588 -436.260748)
			(xy 37.089079 -436.288634) (xy 37.080959 -436.34381) (xy 37.064891 -436.397217) (xy 37.041219 -436.447714)
			(xy 37.010446 -436.494227) (xy 36.973229 -436.535764) (xy 36.930361 -436.571439) (xy 36.882755 -436.600493)
			(xy 36.831426 -436.622305) (xy 36.777469 -436.636411) (xy 36.722032 -436.642511) (xy 36.666298 -436.640474)
			(xy 36.611455 -436.630344) (xy 36.558671 -436.612337) (xy 36.509071 -436.586836) (xy 36.463713 -436.554385)
			(xy 36.423564 -436.515676) (xy 36.389478 -436.471533) (xy 36.362182 -436.422898) (xy 36.342259 -436.370807)
			(xy 36.330133 -436.31637) (xy 36.326062 -436.260748) (xy 35.558337 -436.260748) (xy 35.558476 -436.268368)
			(xy 35.557967 -436.296254) (xy 35.549847 -436.35143) (xy 35.533779 -436.404837) (xy 35.510107 -436.455334)
			(xy 35.479334 -436.501847) (xy 35.442117 -436.543384) (xy 35.399249 -436.579059) (xy 35.351643 -436.608113)
			(xy 35.300314 -436.629925) (xy 35.246357 -436.644031) (xy 35.19092 -436.650131) (xy 35.135186 -436.648094)
			(xy 35.080343 -436.637964) (xy 35.027559 -436.619957) (xy 34.977959 -436.594456) (xy 34.932601 -436.562005)
			(xy 34.892452 -436.523296) (xy 34.858366 -436.479153) (xy 34.83107 -436.430518) (xy 34.811147 -436.378427)
			(xy 34.799021 -436.32399) (xy 34.79495 -436.268368) (xy 26.537158 -436.268368) (xy 26.537158 -436.692548)
			(xy 31.550862 -436.692548) (xy 31.554933 -436.636926) (xy 31.567059 -436.582489) (xy 31.586982 -436.530398)
			(xy 31.614278 -436.481763) (xy 31.648364 -436.43762) (xy 31.688513 -436.398911) (xy 31.733871 -436.36646)
			(xy 31.783471 -436.340959) (xy 31.836255 -436.322952) (xy 31.891098 -436.312822) (xy 31.946832 -436.310785)
			(xy 32.002269 -436.316885) (xy 32.056226 -436.330991) (xy 32.107555 -436.352803) (xy 32.155161 -436.381857)
			(xy 32.198029 -436.417532) (xy 32.235246 -436.459069) (xy 32.266019 -436.505582) (xy 32.289691 -436.556079)
			(xy 32.305759 -436.609486) (xy 32.313879 -436.664662) (xy 32.314388 -436.692548) (xy 32.313879 -436.720434)
			(xy 32.305759 -436.77561) (xy 32.289691 -436.829017) (xy 32.266019 -436.879514) (xy 32.235246 -436.926027)
			(xy 32.198029 -436.967564) (xy 32.155161 -437.003239) (xy 32.107555 -437.032293) (xy 32.056226 -437.054105)
			(xy 32.002269 -437.068211) (xy 31.946832 -437.074311) (xy 31.891098 -437.072274) (xy 31.836255 -437.062144)
			(xy 31.783471 -437.044137) (xy 31.733871 -437.018636) (xy 31.688513 -436.986185) (xy 31.648364 -436.947476)
			(xy 31.614278 -436.903333) (xy 31.586982 -436.854698) (xy 31.567059 -436.802607) (xy 31.554933 -436.74817)
			(xy 31.550862 -436.692548) (xy 26.537158 -436.692548) (xy 26.537158 -437.187594) (xy 41.949876 -437.187594)
			(xy 41.953947 -437.131972) (xy 41.966073 -437.077535) (xy 41.985996 -437.025444) (xy 42.013292 -436.976809)
			(xy 42.047378 -436.932666) (xy 42.087527 -436.893957) (xy 42.132885 -436.861506) (xy 42.182485 -436.836005)
			(xy 42.235269 -436.817998) (xy 42.290112 -436.807868) (xy 42.345846 -436.805831) (xy 42.401283 -436.811931)
			(xy 42.45524 -436.826037) (xy 42.506569 -436.847849) (xy 42.554175 -436.876903) (xy 42.597043 -436.912578)
			(xy 42.63426 -436.954115) (xy 42.665033 -437.000628) (xy 42.688705 -437.051125) (xy 42.704773 -437.104532)
			(xy 42.712893 -437.159708) (xy 42.713402 -437.187594) (xy 42.713295 -437.193436) (xy 43.55033 -437.193436)
			(xy 43.554401 -437.137814) (xy 43.566527 -437.083377) (xy 43.58645 -437.031286) (xy 43.613746 -436.982651)
			(xy 43.647832 -436.938508) (xy 43.687981 -436.899799) (xy 43.733339 -436.867348) (xy 43.782939 -436.841847)
			(xy 43.835723 -436.82384) (xy 43.890566 -436.81371) (xy 43.9463 -436.811673) (xy 44.001737 -436.817773)
			(xy 44.055694 -436.831879) (xy 44.107023 -436.853691) (xy 44.154629 -436.882745) (xy 44.197497 -436.91842)
			(xy 44.234714 -436.959957) (xy 44.265487 -437.00647) (xy 44.283834 -437.045608) (xy 44.86605 -437.045608)
			(xy 44.870121 -436.989986) (xy 44.882247 -436.935549) (xy 44.90217 -436.883458) (xy 44.929466 -436.834823)
			(xy 44.963552 -436.79068) (xy 45.003701 -436.751971) (xy 45.049059 -436.71952) (xy 45.098659 -436.694019)
			(xy 45.151443 -436.676012) (xy 45.206286 -436.665882) (xy 45.26202 -436.663845) (xy 45.317457 -436.669945)
			(xy 45.371414 -436.684051) (xy 45.422743 -436.705863) (xy 45.470349 -436.734917) (xy 45.513217 -436.770592)
			(xy 45.550434 -436.812129) (xy 45.581207 -436.858642) (xy 45.604879 -436.909139) (xy 45.620947 -436.962546)
			(xy 45.628125 -437.011318) (xy 46.30877 -437.011318) (xy 46.312841 -436.955696) (xy 46.324967 -436.901259)
			(xy 46.34489 -436.849168) (xy 46.372186 -436.800533) (xy 46.406272 -436.75639) (xy 46.446421 -436.717681)
			(xy 46.491779 -436.68523) (xy 46.541379 -436.659729) (xy 46.594163 -436.641722) (xy 46.649006 -436.631592)
			(xy 46.70474 -436.629555) (xy 46.760177 -436.635655) (xy 46.814134 -436.649761) (xy 46.865463 -436.671573)
			(xy 46.913069 -436.700627) (xy 46.955937 -436.736302) (xy 46.993154 -436.777839) (xy 47.023927 -436.824352)
			(xy 47.047599 -436.874849) (xy 47.063667 -436.928256) (xy 47.068041 -436.957978) (xy 53.639718 -436.957978)
			(xy 53.643789 -436.902356) (xy 53.655915 -436.847919) (xy 53.675838 -436.795828) (xy 53.703134 -436.747193)
			(xy 53.73722 -436.70305) (xy 53.777369 -436.664341) (xy 53.822727 -436.63189) (xy 53.872327 -436.606389)
			(xy 53.925111 -436.588382) (xy 53.979954 -436.578252) (xy 54.035688 -436.576215) (xy 54.091125 -436.582315)
			(xy 54.145082 -436.596421) (xy 54.196411 -436.618233) (xy 54.244017 -436.647287) (xy 54.286885 -436.682962)
			(xy 54.324102 -436.724499) (xy 54.354875 -436.771012) (xy 54.378547 -436.821509) (xy 54.394615 -436.874916)
			(xy 54.402735 -436.930092) (xy 54.403244 -436.957978) (xy 54.402735 -436.985864) (xy 54.394615 -437.04104)
			(xy 54.378547 -437.094447) (xy 54.354875 -437.144944) (xy 54.324102 -437.191457) (xy 54.286885 -437.232994)
			(xy 54.244017 -437.268669) (xy 54.196411 -437.297723) (xy 54.145082 -437.319535) (xy 54.091125 -437.333641)
			(xy 54.035688 -437.339741) (xy 53.979954 -437.337704) (xy 53.925111 -437.327574) (xy 53.872327 -437.309567)
			(xy 53.822727 -437.284066) (xy 53.777369 -437.251615) (xy 53.73722 -437.212906) (xy 53.703134 -437.168763)
			(xy 53.675838 -437.120128) (xy 53.655915 -437.068037) (xy 53.643789 -437.0136) (xy 53.639718 -436.957978)
			(xy 47.068041 -436.957978) (xy 47.071787 -436.983432) (xy 47.072296 -437.011318) (xy 47.071787 -437.039204)
			(xy 47.063667 -437.09438) (xy 47.047599 -437.147787) (xy 47.023927 -437.198284) (xy 46.993154 -437.244797)
			(xy 46.955937 -437.286334) (xy 46.913069 -437.322009) (xy 46.865463 -437.351063) (xy 46.814134 -437.372875)
			(xy 46.760177 -437.386981) (xy 46.70474 -437.393081) (xy 46.649006 -437.391044) (xy 46.594163 -437.380914)
			(xy 46.541379 -437.362907) (xy 46.491779 -437.337406) (xy 46.446421 -437.304955) (xy 46.406272 -437.266246)
			(xy 46.372186 -437.222103) (xy 46.34489 -437.173468) (xy 46.324967 -437.121377) (xy 46.312841 -437.06694)
			(xy 46.30877 -437.011318) (xy 45.628125 -437.011318) (xy 45.629067 -437.017722) (xy 45.629576 -437.045608)
			(xy 45.629067 -437.073494) (xy 45.620947 -437.12867) (xy 45.604879 -437.182077) (xy 45.581207 -437.232574)
			(xy 45.550434 -437.279087) (xy 45.513217 -437.320624) (xy 45.470349 -437.356299) (xy 45.422743 -437.385353)
			(xy 45.371414 -437.407165) (xy 45.317457 -437.421271) (xy 45.26202 -437.427371) (xy 45.206286 -437.425334)
			(xy 45.151443 -437.415204) (xy 45.098659 -437.397197) (xy 45.049059 -437.371696) (xy 45.003701 -437.339245)
			(xy 44.963552 -437.300536) (xy 44.929466 -437.256393) (xy 44.90217 -437.207758) (xy 44.882247 -437.155667)
			(xy 44.870121 -437.10123) (xy 44.86605 -437.045608) (xy 44.283834 -437.045608) (xy 44.289159 -437.056967)
			(xy 44.305227 -437.110374) (xy 44.313347 -437.16555) (xy 44.313856 -437.193436) (xy 44.313347 -437.221322)
			(xy 44.305227 -437.276498) (xy 44.289159 -437.329905) (xy 44.265487 -437.380402) (xy 44.234714 -437.426915)
			(xy 44.224748 -437.438038) (xy 49.514504 -437.438038) (xy 49.518575 -437.382416) (xy 49.530701 -437.327979)
			(xy 49.550624 -437.275888) (xy 49.57792 -437.227253) (xy 49.612006 -437.18311) (xy 49.652155 -437.144401)
			(xy 49.697513 -437.11195) (xy 49.747113 -437.086449) (xy 49.799897 -437.068442) (xy 49.85474 -437.058312)
			(xy 49.910474 -437.056275) (xy 49.965911 -437.062375) (xy 50.019868 -437.076481) (xy 50.071197 -437.098293)
			(xy 50.118803 -437.127347) (xy 50.161671 -437.163022) (xy 50.198888 -437.204559) (xy 50.229661 -437.251072)
			(xy 50.253333 -437.301569) (xy 50.269401 -437.354976) (xy 50.277521 -437.410152) (xy 50.27803 -437.438038)
			(xy 50.277521 -437.465924) (xy 50.269401 -437.5211) (xy 50.253333 -437.574507) (xy 50.229661 -437.625004)
			(xy 50.198888 -437.671517) (xy 50.161671 -437.713054) (xy 50.118803 -437.748729) (xy 50.071197 -437.777783)
			(xy 50.019868 -437.799595) (xy 49.965911 -437.813701) (xy 49.910474 -437.819801) (xy 49.85474 -437.817764)
			(xy 49.799897 -437.807634) (xy 49.747113 -437.789627) (xy 49.697513 -437.764126) (xy 49.652155 -437.731675)
			(xy 49.612006 -437.692966) (xy 49.57792 -437.648823) (xy 49.550624 -437.600188) (xy 49.530701 -437.548097)
			(xy 49.518575 -437.49366) (xy 49.514504 -437.438038) (xy 44.224748 -437.438038) (xy 44.197497 -437.468452)
			(xy 44.154629 -437.504127) (xy 44.107023 -437.533181) (xy 44.055694 -437.554993) (xy 44.001737 -437.569099)
			(xy 43.9463 -437.575199) (xy 43.890566 -437.573162) (xy 43.835723 -437.563032) (xy 43.782939 -437.545025)
			(xy 43.733339 -437.519524) (xy 43.687981 -437.487073) (xy 43.647832 -437.448364) (xy 43.613746 -437.404221)
			(xy 43.58645 -437.355586) (xy 43.566527 -437.303495) (xy 43.554401 -437.249058) (xy 43.55033 -437.193436)
			(xy 42.713295 -437.193436) (xy 42.712893 -437.21548) (xy 42.704773 -437.270656) (xy 42.688705 -437.324063)
			(xy 42.665033 -437.37456) (xy 42.63426 -437.421073) (xy 42.597043 -437.46261) (xy 42.554175 -437.498285)
			(xy 42.506569 -437.527339) (xy 42.45524 -437.549151) (xy 42.401283 -437.563257) (xy 42.345846 -437.569357)
			(xy 42.290112 -437.56732) (xy 42.235269 -437.55719) (xy 42.182485 -437.539183) (xy 42.132885 -437.513682)
			(xy 42.087527 -437.481231) (xy 42.047378 -437.442522) (xy 42.013292 -437.398379) (xy 41.985996 -437.349744)
			(xy 41.966073 -437.297653) (xy 41.953947 -437.243216) (xy 41.949876 -437.187594) (xy 26.537158 -437.187594)
			(xy 26.537158 -437.585612) (xy 33.79546 -437.585612) (xy 33.799531 -437.52999) (xy 33.811657 -437.475553)
			(xy 33.83158 -437.423462) (xy 33.858876 -437.374827) (xy 33.892962 -437.330684) (xy 33.933111 -437.291975)
			(xy 33.978469 -437.259524) (xy 34.028069 -437.234023) (xy 34.080853 -437.216016) (xy 34.135696 -437.205886)
			(xy 34.19143 -437.203849) (xy 34.246867 -437.209949) (xy 34.300824 -437.224055) (xy 34.352153 -437.245867)
			(xy 34.399759 -437.274921) (xy 34.442627 -437.310596) (xy 34.479844 -437.352133) (xy 34.510617 -437.398646)
			(xy 34.534289 -437.449143) (xy 34.550357 -437.50255) (xy 34.558477 -437.557726) (xy 34.558986 -437.585612)
			(xy 34.558477 -437.613498) (xy 34.550357 -437.668674) (xy 34.538361 -437.708548) (xy 39.013382 -437.708548)
			(xy 39.017453 -437.652926) (xy 39.029579 -437.598489) (xy 39.049502 -437.546398) (xy 39.076798 -437.497763)
			(xy 39.110884 -437.45362) (xy 39.151033 -437.414911) (xy 39.196391 -437.38246) (xy 39.245991 -437.356959)
			(xy 39.298775 -437.338952) (xy 39.353618 -437.328822) (xy 39.409352 -437.326785) (xy 39.464789 -437.332885)
			(xy 39.518746 -437.346991) (xy 39.570075 -437.368803) (xy 39.617681 -437.397857) (xy 39.660549 -437.433532)
			(xy 39.697766 -437.475069) (xy 39.728539 -437.521582) (xy 39.752211 -437.572079) (xy 39.768279 -437.625486)
			(xy 39.776399 -437.680662) (xy 39.776908 -437.708548) (xy 39.776399 -437.736434) (xy 39.768279 -437.79161)
			(xy 39.752211 -437.845017) (xy 39.728539 -437.895514) (xy 39.697766 -437.942027) (xy 39.660549 -437.983564)
			(xy 39.617681 -438.019239) (xy 39.570075 -438.048293) (xy 39.518746 -438.070105) (xy 39.464789 -438.084211)
			(xy 39.409352 -438.090311) (xy 39.353618 -438.088274) (xy 39.298775 -438.078144) (xy 39.245991 -438.060137)
			(xy 39.196391 -438.034636) (xy 39.151033 -438.002185) (xy 39.110884 -437.963476) (xy 39.076798 -437.919333)
			(xy 39.049502 -437.870698) (xy 39.029579 -437.818607) (xy 39.017453 -437.76417) (xy 39.013382 -437.708548)
			(xy 34.538361 -437.708548) (xy 34.534289 -437.722081) (xy 34.510617 -437.772578) (xy 34.479844 -437.819091)
			(xy 34.442627 -437.860628) (xy 34.399759 -437.896303) (xy 34.352153 -437.925357) (xy 34.300824 -437.947169)
			(xy 34.246867 -437.961275) (xy 34.19143 -437.967375) (xy 34.135696 -437.965338) (xy 34.080853 -437.955208)
			(xy 34.028069 -437.937201) (xy 33.978469 -437.9117) (xy 33.933111 -437.879249) (xy 33.892962 -437.84054)
			(xy 33.858876 -437.796397) (xy 33.83158 -437.747762) (xy 33.811657 -437.695671) (xy 33.799531 -437.641234)
			(xy 33.79546 -437.585612) (xy 26.537158 -437.585612) (xy 26.537158 -438.561988) (xy 29.444186 -438.561988)
			(xy 29.448257 -438.506366) (xy 29.460383 -438.451929) (xy 29.480306 -438.399838) (xy 29.507602 -438.351203)
			(xy 29.541688 -438.30706) (xy 29.581837 -438.268351) (xy 29.627195 -438.2359) (xy 29.676795 -438.210399)
			(xy 29.729579 -438.192392) (xy 29.784422 -438.182262) (xy 29.840156 -438.180225) (xy 29.895593 -438.186325)
			(xy 29.94955 -438.200431) (xy 30.000879 -438.222243) (xy 30.048485 -438.251297) (xy 30.091353 -438.286972)
			(xy 30.12857 -438.328509) (xy 30.159343 -438.375022) (xy 30.183015 -438.425519) (xy 30.199083 -438.478926)
			(xy 30.207203 -438.534102) (xy 30.20748 -438.549288) (xy 34.63239 -438.549288) (xy 34.636461 -438.493666)
			(xy 34.648587 -438.439229) (xy 34.66851 -438.387138) (xy 34.695806 -438.338503) (xy 34.729892 -438.29436)
			(xy 34.770041 -438.255651) (xy 34.815399 -438.2232) (xy 34.864999 -438.197699) (xy 34.917783 -438.179692)
			(xy 34.972626 -438.169562) (xy 35.02836 -438.167525) (xy 35.083797 -438.173625) (xy 35.137754 -438.187731)
			(xy 35.189083 -438.209543) (xy 35.236689 -438.238597) (xy 35.279557 -438.274272) (xy 35.316774 -438.315809)
			(xy 35.347547 -438.362322) (xy 35.371219 -438.412819) (xy 35.387287 -438.466226) (xy 35.395407 -438.521402)
			(xy 35.395661 -438.535318) (xy 42.74134 -438.535318) (xy 42.745411 -438.479696) (xy 42.757537 -438.425259)
			(xy 42.77746 -438.373168) (xy 42.804756 -438.324533) (xy 42.838842 -438.28039) (xy 42.878991 -438.241681)
			(xy 42.924349 -438.20923) (xy 42.973949 -438.183729) (xy 43.026733 -438.165722) (xy 43.081576 -438.155592)
			(xy 43.13731 -438.153555) (xy 43.192747 -438.159655) (xy 43.246704 -438.173761) (xy 43.298033 -438.195573)
			(xy 43.345639 -438.224627) (xy 43.388507 -438.260302) (xy 43.425724 -438.301839) (xy 43.456497 -438.348352)
			(xy 43.480169 -438.398849) (xy 43.496237 -438.452256) (xy 43.504357 -438.507432) (xy 43.504866 -438.535318)
			(xy 44.887386 -438.535318) (xy 44.891457 -438.479696) (xy 44.903583 -438.425259) (xy 44.923506 -438.373168)
			(xy 44.950802 -438.324533) (xy 44.984888 -438.28039) (xy 45.025037 -438.241681) (xy 45.070395 -438.20923)
			(xy 45.119995 -438.183729) (xy 45.172779 -438.165722) (xy 45.227622 -438.155592) (xy 45.283356 -438.153555)
			(xy 45.338793 -438.159655) (xy 45.391247 -438.173368) (xy 47.571658 -438.173368) (xy 47.575729 -438.117746)
			(xy 47.587855 -438.063309) (xy 47.607778 -438.011218) (xy 47.635074 -437.962583) (xy 47.66916 -437.91844)
			(xy 47.709309 -437.879731) (xy 47.754667 -437.84728) (xy 47.804267 -437.821779) (xy 47.857051 -437.803772)
			(xy 47.911894 -437.793642) (xy 47.967628 -437.791605) (xy 48.023065 -437.797705) (xy 48.077022 -437.811811)
			(xy 48.128351 -437.833623) (xy 48.175957 -437.862677) (xy 48.218825 -437.898352) (xy 48.256042 -437.939889)
			(xy 48.286815 -437.986402) (xy 48.310487 -438.036899) (xy 48.326555 -438.090306) (xy 48.334675 -438.145482)
			(xy 48.335184 -438.173368) (xy 48.334675 -438.201254) (xy 48.326555 -438.25643) (xy 48.310487 -438.309837)
			(xy 48.286815 -438.360334) (xy 48.256042 -438.406847) (xy 48.218825 -438.448384) (xy 48.175957 -438.484059)
			(xy 48.128351 -438.513113) (xy 48.127501 -438.513474) (xy 50.176682 -438.513474) (xy 50.180753 -438.457852)
			(xy 50.192879 -438.403415) (xy 50.212802 -438.351324) (xy 50.240098 -438.302689) (xy 50.274184 -438.258546)
			(xy 50.314333 -438.219837) (xy 50.359691 -438.187386) (xy 50.409291 -438.161885) (xy 50.462075 -438.143878)
			(xy 50.516918 -438.133748) (xy 50.572652 -438.131711) (xy 50.628089 -438.137811) (xy 50.682046 -438.151917)
			(xy 50.733375 -438.173729) (xy 50.780981 -438.202783) (xy 50.823849 -438.238458) (xy 50.861066 -438.279995)
			(xy 50.891839 -438.326508) (xy 50.915511 -438.377005) (xy 50.931579 -438.430412) (xy 50.939699 -438.485588)
			(xy 50.940208 -438.513474) (xy 50.939699 -438.54136) (xy 50.931579 -438.596536) (xy 50.915511 -438.649943)
			(xy 50.891839 -438.70044) (xy 50.861066 -438.746953) (xy 50.823849 -438.78849) (xy 50.780981 -438.824165)
			(xy 50.733375 -438.853219) (xy 50.682046 -438.875031) (xy 50.628089 -438.889137) (xy 50.572652 -438.895237)
			(xy 50.516918 -438.8932) (xy 50.462075 -438.88307) (xy 50.409291 -438.865063) (xy 50.359691 -438.839562)
			(xy 50.314333 -438.807111) (xy 50.274184 -438.768402) (xy 50.240098 -438.724259) (xy 50.212802 -438.675624)
			(xy 50.192879 -438.623533) (xy 50.180753 -438.569096) (xy 50.176682 -438.513474) (xy 48.127501 -438.513474)
			(xy 48.077022 -438.534925) (xy 48.023065 -438.549031) (xy 47.967628 -438.555131) (xy 47.911894 -438.553094)
			(xy 47.857051 -438.542964) (xy 47.804267 -438.524957) (xy 47.754667 -438.499456) (xy 47.709309 -438.467005)
			(xy 47.66916 -438.428296) (xy 47.635074 -438.384153) (xy 47.607778 -438.335518) (xy 47.587855 -438.283427)
			(xy 47.575729 -438.22899) (xy 47.571658 -438.173368) (xy 45.391247 -438.173368) (xy 45.39275 -438.173761)
			(xy 45.444079 -438.195573) (xy 45.491685 -438.224627) (xy 45.534553 -438.260302) (xy 45.57177 -438.301839)
			(xy 45.602543 -438.348352) (xy 45.626215 -438.398849) (xy 45.642283 -438.452256) (xy 45.650403 -438.507432)
			(xy 45.650912 -438.535318) (xy 45.650403 -438.563204) (xy 45.642283 -438.61838) (xy 45.626215 -438.671787)
			(xy 45.602543 -438.722284) (xy 45.57177 -438.768797) (xy 45.534553 -438.810334) (xy 45.491685 -438.846009)
			(xy 45.444079 -438.875063) (xy 45.39275 -438.896875) (xy 45.338793 -438.910981) (xy 45.283356 -438.917081)
			(xy 45.227622 -438.915044) (xy 45.172779 -438.904914) (xy 45.119995 -438.886907) (xy 45.070395 -438.861406)
			(xy 45.025037 -438.828955) (xy 44.984888 -438.790246) (xy 44.950802 -438.746103) (xy 44.923506 -438.697468)
			(xy 44.903583 -438.645377) (xy 44.891457 -438.59094) (xy 44.887386 -438.535318) (xy 43.504866 -438.535318)
			(xy 43.504357 -438.563204) (xy 43.496237 -438.61838) (xy 43.480169 -438.671787) (xy 43.456497 -438.722284)
			(xy 43.425724 -438.768797) (xy 43.388507 -438.810334) (xy 43.345639 -438.846009) (xy 43.298033 -438.875063)
			(xy 43.246704 -438.896875) (xy 43.192747 -438.910981) (xy 43.13731 -438.917081) (xy 43.081576 -438.915044)
			(xy 43.026733 -438.904914) (xy 42.973949 -438.886907) (xy 42.924349 -438.861406) (xy 42.878991 -438.828955)
			(xy 42.838842 -438.790246) (xy 42.804756 -438.746103) (xy 42.77746 -438.697468) (xy 42.757537 -438.645377)
			(xy 42.745411 -438.59094) (xy 42.74134 -438.535318) (xy 35.395661 -438.535318) (xy 35.395916 -438.549288)
			(xy 35.395407 -438.577174) (xy 35.387287 -438.63235) (xy 35.371219 -438.685757) (xy 35.347547 -438.736254)
			(xy 35.316774 -438.782767) (xy 35.279557 -438.824304) (xy 35.236689 -438.859979) (xy 35.189083 -438.889033)
			(xy 35.137754 -438.910845) (xy 35.083797 -438.924951) (xy 35.02836 -438.931051) (xy 34.972626 -438.929014)
			(xy 34.917783 -438.918884) (xy 34.864999 -438.900877) (xy 34.815399 -438.875376) (xy 34.770041 -438.842925)
			(xy 34.729892 -438.804216) (xy 34.695806 -438.760073) (xy 34.66851 -438.711438) (xy 34.648587 -438.659347)
			(xy 34.636461 -438.60491) (xy 34.63239 -438.549288) (xy 30.20748 -438.549288) (xy 30.207712 -438.561988)
			(xy 30.207203 -438.589874) (xy 30.199083 -438.64505) (xy 30.183015 -438.698457) (xy 30.159343 -438.748954)
			(xy 30.12857 -438.795467) (xy 30.091353 -438.837004) (xy 30.048485 -438.872679) (xy 30.000879 -438.901733)
			(xy 29.94955 -438.923545) (xy 29.895593 -438.937651) (xy 29.840156 -438.943751) (xy 29.784422 -438.941714)
			(xy 29.729579 -438.931584) (xy 29.676795 -438.913577) (xy 29.627195 -438.888076) (xy 29.581837 -438.855625)
			(xy 29.541688 -438.816916) (xy 29.507602 -438.772773) (xy 29.480306 -438.724138) (xy 29.460383 -438.672047)
			(xy 29.448257 -438.61761) (xy 29.444186 -438.561988) (xy 26.537158 -438.561988) (xy 26.537158 -439.129424)
			(xy 26.934922 -439.527188) (xy 29.400752 -439.527188) (xy 29.404823 -439.471566) (xy 29.416949 -439.417129)
			(xy 29.436872 -439.365038) (xy 29.464168 -439.316403) (xy 29.498254 -439.27226) (xy 29.538403 -439.233551)
			(xy 29.583761 -439.2011) (xy 29.633361 -439.175599) (xy 29.686145 -439.157592) (xy 29.740988 -439.147462)
			(xy 29.796722 -439.145425) (xy 29.852159 -439.151525) (xy 29.856034 -439.152538) (xy 48.520348 -439.152538)
			(xy 48.524419 -439.096916) (xy 48.536545 -439.042479) (xy 48.556468 -438.990388) (xy 48.583764 -438.941753)
			(xy 48.61785 -438.89761) (xy 48.657999 -438.858901) (xy 48.703357 -438.82645) (xy 48.752957 -438.800949)
			(xy 48.805741 -438.782942) (xy 48.860584 -438.772812) (xy 48.916318 -438.770775) (xy 48.971755 -438.776875)
			(xy 49.025712 -438.790981) (xy 49.077041 -438.812793) (xy 49.124647 -438.841847) (xy 49.167515 -438.877522)
			(xy 49.204732 -438.919059) (xy 49.235505 -438.965572) (xy 49.259177 -439.016069) (xy 49.275245 -439.069476)
			(xy 49.283365 -439.124652) (xy 49.283874 -439.152538) (xy 49.283365 -439.180424) (xy 49.275245 -439.2356)
			(xy 49.259177 -439.289007) (xy 49.235505 -439.339504) (xy 49.204732 -439.386017) (xy 49.167515 -439.427554)
			(xy 49.124647 -439.463229) (xy 49.077041 -439.492283) (xy 49.025712 -439.514095) (xy 48.971755 -439.528201)
			(xy 48.916318 -439.534301) (xy 48.860584 -439.532264) (xy 48.805741 -439.522134) (xy 48.752957 -439.504127)
			(xy 48.703357 -439.478626) (xy 48.657999 -439.446175) (xy 48.61785 -439.407466) (xy 48.583764 -439.363323)
			(xy 48.556468 -439.314688) (xy 48.536545 -439.262597) (xy 48.524419 -439.20816) (xy 48.520348 -439.152538)
			(xy 29.856034 -439.152538) (xy 29.906116 -439.165631) (xy 29.957445 -439.187443) (xy 30.005051 -439.216497)
			(xy 30.047919 -439.252172) (xy 30.085136 -439.293709) (xy 30.115909 -439.340222) (xy 30.139581 -439.390719)
			(xy 30.155649 -439.444126) (xy 30.163769 -439.499302) (xy 30.164278 -439.527188) (xy 30.163769 -439.555074)
			(xy 30.155649 -439.61025) (xy 30.139581 -439.663657) (xy 30.115909 -439.714154) (xy 30.085136 -439.760667)
			(xy 30.072211 -439.775092) (xy 34.944302 -439.775092) (xy 34.948373 -439.71947) (xy 34.960499 -439.665033)
			(xy 34.980422 -439.612942) (xy 35.007718 -439.564307) (xy 35.041804 -439.520164) (xy 35.081953 -439.481455)
			(xy 35.127311 -439.449004) (xy 35.176911 -439.423503) (xy 35.229695 -439.405496) (xy 35.284538 -439.395366)
			(xy 35.340272 -439.393329) (xy 35.395709 -439.399429) (xy 35.449666 -439.413535) (xy 35.500995 -439.435347)
			(xy 35.548601 -439.464401) (xy 35.591469 -439.500076) (xy 35.628686 -439.541613) (xy 35.659459 -439.588126)
			(xy 35.683131 -439.638623) (xy 35.699199 -439.69203) (xy 35.707319 -439.747206) (xy 35.707828 -439.775092)
			(xy 35.707319 -439.802978) (xy 35.699199 -439.858154) (xy 35.683131 -439.911561) (xy 35.659459 -439.962058)
			(xy 35.628686 -440.008571) (xy 35.591469 -440.050108) (xy 35.548601 -440.085783) (xy 35.500995 -440.114837)
			(xy 35.449666 -440.136649) (xy 35.395709 -440.150755) (xy 35.340272 -440.156855) (xy 35.284538 -440.154818)
			(xy 35.229695 -440.144688) (xy 35.176911 -440.126681) (xy 35.127311 -440.10118) (xy 35.081953 -440.068729)
			(xy 35.041804 -440.03002) (xy 35.007718 -439.985877) (xy 34.980422 -439.937242) (xy 34.960499 -439.885151)
			(xy 34.948373 -439.830714) (xy 34.944302 -439.775092) (xy 30.072211 -439.775092) (xy 30.047919 -439.802204)
			(xy 30.005051 -439.837879) (xy 29.957445 -439.866933) (xy 29.906116 -439.888745) (xy 29.852159 -439.902851)
			(xy 29.796722 -439.908951) (xy 29.740988 -439.906914) (xy 29.686145 -439.896784) (xy 29.633361 -439.878777)
			(xy 29.583761 -439.853276) (xy 29.538403 -439.820825) (xy 29.498254 -439.782116) (xy 29.464168 -439.737973)
			(xy 29.436872 -439.689338) (xy 29.416949 -439.637247) (xy 29.404823 -439.58281) (xy 29.400752 -439.527188)
			(xy 26.934922 -439.527188) (xy 28.018486 -440.610752)
		)
		(stroke
			(width 0)
			(type solid)
		)
		(fill yes)
		(layer "In13.Cu")
		(net "P3V3_AUX")
	)
	(gr_poly
		(pts
			(xy 432.700684 -185.270648) (xy 432.699033 -185.257885) (xy 432.697253 -185.232209) (xy 432.697128 -185.21934)
			(xy 432.697614 -185.192071) (xy 432.705376 -185.138087) (xy 432.720741 -185.085757) (xy 432.743398 -185.036147)
			(xy 432.772884 -184.990266) (xy 432.808599 -184.949049) (xy 432.849816 -184.913334) (xy 432.895697 -184.883848)
			(xy 432.945307 -184.861191) (xy 432.997637 -184.845826) (xy 433.051621 -184.838064) (xy 433.106159 -184.838064)
			(xy 433.160143 -184.845826) (xy 433.212473 -184.861191) (xy 433.262083 -184.883848) (xy 433.307964 -184.913334)
			(xy 433.349181 -184.949049) (xy 433.384896 -184.990266) (xy 433.414382 -185.036147) (xy 433.437039 -185.085757)
			(xy 433.452404 -185.138087) (xy 433.460166 -185.192071) (xy 433.460652 -185.21934) (xy 433.460518 -185.232208)
			(xy 433.458738 -185.257884) (xy 433.457096 -185.270648) (xy 434.77688 -185.270648) (xy 434.79114 -185.270173)
			(xy 434.818551 -185.262295) (xy 434.842716 -185.247147) (xy 434.861753 -185.22591) (xy 434.874178 -185.200238)
			(xy 434.879022 -185.172132) (xy 434.875909 -185.143782) (xy 434.87086 -185.13044) (xy 434.85946 -185.105009)
			(xy 434.843393 -185.051645) (xy 434.835284 -184.996507) (xy 434.834792 -184.968642) (xy 434.834792 -184.968388)
			(xy 434.835278 -184.941137) (xy 434.843034 -184.887189) (xy 434.858389 -184.834894) (xy 434.881031 -184.785317)
			(xy 434.910497 -184.739467) (xy 434.946188 -184.698276) (xy 434.987379 -184.662585) (xy 435.033229 -184.633119)
			(xy 435.082806 -184.610477) (xy 435.135101 -184.595122) (xy 435.189049 -184.587366) (xy 435.243551 -184.587366)
			(xy 435.297499 -184.595122) (xy 435.349794 -184.610477) (xy 435.399371 -184.633119) (xy 435.445221 -184.662585)
			(xy 435.486412 -184.698276) (xy 435.522103 -184.739467) (xy 435.551569 -184.785317) (xy 435.574211 -184.834894)
			(xy 435.589566 -184.887189) (xy 435.597322 -184.941137) (xy 435.597808 -184.968388) (xy 435.597808 -184.968642)
			(xy 435.59728 -184.996504) (xy 435.589147 -185.051631) (xy 435.573104 -185.104996) (xy 435.56174 -185.13044)
			(xy 435.556772 -185.143803) (xy 435.553661 -185.17213) (xy 435.558502 -185.200213) (xy 435.570917 -185.225863)
			(xy 435.589938 -185.247083) (xy 435.614083 -185.262219) (xy 435.641471 -185.27009) (xy 435.65572 -185.270648)
			(xy 447.46164 -185.270648) (xy 449.09994 -183.632348) (xy 449.09994 -174.71898) (xy 449.072508 -174.712376)
			(xy 449.044423 -174.705817) (xy 448.990495 -174.685382) (xy 448.940258 -174.657059) (xy 448.89486 -174.621494)
			(xy 448.855334 -174.579498) (xy 448.822582 -174.53203) (xy 448.797352 -174.480171) (xy 448.780218 -174.425104)
			(xy 448.771572 -174.368086) (xy 448.77101 -174.33925) (xy 448.771531 -174.310548) (xy 448.780135 -174.253791)
			(xy 448.797142 -174.198963) (xy 448.822167 -174.1473) (xy 448.854647 -174.099967) (xy 448.893848 -174.058031)
			(xy 448.938888 -174.02244) (xy 448.988749 -173.993994) (xy 449.042309 -173.973336) (xy 449.070222 -173.966632)
			(xy 449.09994 -173.959266) (xy 449.09994 -159.274256) (xy 455.60488 -152.769316) (xy 455.60488 -128.630934)
			(xy 446.063116 -119.08917) (xy 446.052134 -119.078996) (xy 446.025713 -119.064953) (xy 445.996356 -119.059169)
			(xy 445.966583 -119.062139) (xy 445.938947 -119.073609) (xy 445.915821 -119.092595) (xy 445.899188 -119.117467)
			(xy 445.890476 -119.146092) (xy 445.889888 -119.161052) (xy 445.889888 -126.31293) (xy 445.88933 -126.341904)
			(xy 445.880225 -126.399132) (xy 445.862274 -126.45423) (xy 445.83592 -126.505839) (xy 445.801814 -126.552687)
			(xy 445.781684 -126.573534) (xy 443.694566 -128.660652) (xy 443.673717 -128.680779) (xy 443.626868 -128.714883)
			(xy 443.575259 -128.741236) (xy 443.520163 -128.759188) (xy 443.462935 -128.768297) (xy 443.433962 -128.768856)
			(xy 439.209434 -128.768856) (xy 434.087524 -133.890512) (xy 434.066675 -133.910639) (xy 434.019826 -133.944746)
			(xy 433.968218 -133.971102) (xy 433.913121 -133.98906) (xy 433.855894 -133.998176) (xy 433.82692 -133.998716)
			(xy 432.64201 -133.998716) (xy 432.635914 -134.00024) (xy 432.613353 -134.005473) (xy 432.567378 -134.011078)
			(xy 432.54422 -134.011416) (xy 432.517037 -134.010937) (xy 432.463221 -134.003222) (xy 432.411045 -133.987945)
			(xy 432.361566 -133.965417) (xy 432.315786 -133.936092) (xy 432.274633 -133.900566) (xy 432.238939 -133.859558)
			(xy 432.209429 -133.813898) (xy 432.1867 -133.764511) (xy 432.171211 -133.712397) (xy 432.163277 -133.658613)
			(xy 432.162712 -133.631432) (xy 432.162712 -133.6294) (xy 432.163245 -133.600163) (xy 432.172182 -133.542375)
			(xy 432.180492 -133.514338) (xy 432.182524 -133.508496) (xy 432.186512 -133.493741) (xy 432.186441 -133.463191)
			(xy 432.177346 -133.434025) (xy 432.160038 -133.40885) (xy 432.136064 -133.389913) (xy 432.107564 -133.378907)
			(xy 432.092354 -133.377432) (xy 431.324004 -133.377432) (xy 431.194718 -133.506972) (xy 431.081688 -133.620002)
			(xy 431.081688 -135.545068) (xy 431.227736 -135.545068) (xy 431.231807 -135.489446) (xy 431.243933 -135.435009)
			(xy 431.263856 -135.382918) (xy 431.291152 -135.334283) (xy 431.325238 -135.29014) (xy 431.365387 -135.251431)
			(xy 431.410745 -135.21898) (xy 431.460345 -135.193479) (xy 431.513129 -135.175472) (xy 431.567972 -135.165342)
			(xy 431.623706 -135.163305) (xy 431.679143 -135.169405) (xy 431.7331 -135.183511) (xy 431.784429 -135.205323)
			(xy 431.832035 -135.234377) (xy 431.874903 -135.270052) (xy 431.91212 -135.311589) (xy 431.942893 -135.358102)
			(xy 431.966565 -135.408599) (xy 431.982633 -135.462006) (xy 431.990753 -135.517182) (xy 431.991262 -135.545068)
			(xy 431.990753 -135.572954) (xy 431.982633 -135.62813) (xy 431.966565 -135.681537) (xy 431.942893 -135.732034)
			(xy 431.91212 -135.778547) (xy 431.874903 -135.820084) (xy 431.832035 -135.855759) (xy 431.784429 -135.884813)
			(xy 431.7331 -135.906625) (xy 431.679143 -135.920731) (xy 431.623706 -135.926831) (xy 431.567972 -135.924794)
			(xy 431.513129 -135.914664) (xy 431.460345 -135.896657) (xy 431.410745 -135.871156) (xy 431.365387 -135.838705)
			(xy 431.325238 -135.799996) (xy 431.291152 -135.755853) (xy 431.263856 -135.707218) (xy 431.243933 -135.655127)
			(xy 431.231807 -135.60069) (xy 431.227736 -135.545068) (xy 431.081688 -135.545068) (xy 431.081688 -137.542778)
			(xy 431.333146 -137.542778) (xy 431.337217 -137.487156) (xy 431.349343 -137.432719) (xy 431.369266 -137.380628)
			(xy 431.396562 -137.331993) (xy 431.430648 -137.28785) (xy 431.470797 -137.249141) (xy 431.516155 -137.21669)
			(xy 431.565755 -137.191189) (xy 431.618539 -137.173182) (xy 431.673382 -137.163052) (xy 431.729116 -137.161015)
			(xy 431.784553 -137.167115) (xy 431.83851 -137.181221) (xy 431.889839 -137.203033) (xy 431.937445 -137.232087)
			(xy 431.980313 -137.267762) (xy 432.01753 -137.309299) (xy 432.048303 -137.355812) (xy 432.071975 -137.406309)
			(xy 432.088043 -137.459716) (xy 432.096163 -137.514892) (xy 432.096672 -137.542778) (xy 432.096163 -137.570664)
			(xy 432.088043 -137.62584) (xy 432.071975 -137.679247) (xy 432.048303 -137.729744) (xy 432.01753 -137.776257)
			(xy 431.980313 -137.817794) (xy 431.937445 -137.853469) (xy 431.889839 -137.882523) (xy 431.83851 -137.904335)
			(xy 431.784553 -137.918441) (xy 431.729116 -137.924541) (xy 431.673382 -137.922504) (xy 431.618539 -137.912374)
			(xy 431.565755 -137.894367) (xy 431.516155 -137.868866) (xy 431.470797 -137.836415) (xy 431.430648 -137.797706)
			(xy 431.396562 -137.753563) (xy 431.369266 -137.704928) (xy 431.349343 -137.652837) (xy 431.337217 -137.5984)
			(xy 431.333146 -137.542778) (xy 431.081688 -137.542778) (xy 431.081688 -140.15593) (xy 431.764694 -140.838936)
			(xy 431.789068 -140.853692) (xy 431.833544 -140.889301) (xy 431.872231 -140.931128) (xy 431.904266 -140.978244)
			(xy 431.928939 -141.0296) (xy 431.945699 -141.084053) (xy 431.954175 -141.140395) (xy 431.954686 -141.168882)
			(xy 431.954224 -141.196135) (xy 431.946469 -141.250087) (xy 431.931114 -141.302386) (xy 431.908472 -141.351967)
			(xy 431.879005 -141.39782) (xy 431.843311 -141.439013) (xy 431.802117 -141.474707) (xy 431.756263 -141.504174)
			(xy 431.706682 -141.526816) (xy 431.654383 -141.54217) (xy 431.600431 -141.549924) (xy 431.573178 -141.55039)
			(xy 431.545114 -141.549897) (xy 431.48959 -141.54168) (xy 431.43587 -141.525412) (xy 431.385116 -141.501443)
			(xy 431.338425 -141.470293) (xy 431.296804 -141.432635) (xy 431.261154 -141.389281) (xy 431.24628 -141.365478)
			(xy 431.242978 -141.360144) (xy 430.452276 -140.569188) (xy 430.432151 -140.548338) (xy 430.398051 -140.501487)
			(xy 430.3717 -140.449879) (xy 430.353748 -140.394783) (xy 430.344638 -140.337557) (xy 430.344072 -140.308584)
			(xy 430.344072 -133.467348) (xy 430.344631 -133.438375) (xy 430.353739 -133.381147) (xy 430.371691 -133.32605)
			(xy 430.398045 -133.274442) (xy 430.43215 -133.227594) (xy 430.452276 -133.206744) (xy 430.910746 -132.748274)
			(xy 430.931625 -132.728195) (xy 430.978484 -132.694145) (xy 431.030092 -132.667844) (xy 431.085179 -132.649939)
			(xy 431.142388 -132.640871) (xy 431.17135 -132.640324) (xy 431.200052 -132.640324) (xy 431.248058 -132.5753)
			(xy 431.24247 -132.55244) (xy 431.237462 -132.530364) (xy 431.232113 -132.485413) (xy 431.231802 -132.462778)
			(xy 431.231802 -132.459984) (xy 431.232479 -132.432864) (xy 431.240559 -132.379222) (xy 431.256157 -132.327265)
			(xy 431.278957 -132.278041) (xy 431.3085 -132.232543) (xy 431.34419 -132.19169) (xy 431.385308 -132.156303)
			(xy 431.431023 -132.127098) (xy 431.480414 -132.104663) (xy 431.532485 -132.089451) (xy 431.586186 -132.081768)
			(xy 431.61331 -132.08127) (xy 431.640561 -132.081756) (xy 431.694509 -132.089514) (xy 431.746804 -132.10487)
			(xy 431.796381 -132.127511) (xy 431.842232 -132.156977) (xy 431.883423 -132.192669) (xy 431.919115 -132.233858)
			(xy 431.948583 -132.279708) (xy 431.971226 -132.329285) (xy 431.986583 -132.381579) (xy 431.994343 -132.435527)
			(xy 431.994818 -132.462778) (xy 431.994818 -132.463032) (xy 431.994657 -132.478984) (xy 431.991987 -132.510777)
			(xy 431.989484 -132.526532) (xy 431.988287 -132.540242) (xy 431.992395 -132.567443) (xy 432.003602 -132.592566)
			(xy 432.021096 -132.613796) (xy 432.043614 -132.629599) (xy 432.069528 -132.638831) (xy 432.08321 -132.640324)
			(xy 433.228496 -132.640324) (xy 434.167788 -131.701032) (xy 434.24094 -131.627626) (xy 434.251027 -131.616835)
			(xy 434.26507 -131.590863) (xy 434.271111 -131.561962) (xy 434.268647 -131.532539) (xy 434.257882 -131.505046)
			(xy 434.239714 -131.481772) (xy 434.215656 -131.464655) (xy 434.201824 -131.459478) (xy 434.175129 -131.451821)
			(xy 434.124127 -131.429847) (xy 434.076851 -131.40071) (xy 434.034297 -131.365028) (xy 433.997367 -131.323553)
			(xy 433.966839 -131.277163) (xy 433.943359 -131.226836) (xy 433.927424 -131.173638) (xy 433.919369 -131.118691)
			(xy 433.918868 -131.090924) (xy 433.918868 -131.090416) (xy 433.919235 -131.066885) (xy 433.925061 -131.020186)
			(xy 433.936589 -130.974558) (xy 433.944776 -130.952494) (xy 433.949098 -130.938358) (xy 433.950294 -130.908834)
			(xy 433.942999 -130.880202) (xy 433.927821 -130.85485) (xy 433.906027 -130.834898) (xy 433.879439 -130.822009)
			(xy 433.850275 -130.817262) (xy 433.835556 -130.818636) (xy 433.816837 -130.822206) (xy 433.778919 -130.826028)
			(xy 433.759864 -130.826256) (xy 433.732613 -130.825768) (xy 433.678667 -130.818007) (xy 433.626374 -130.80265)
			(xy 433.576798 -130.780007) (xy 433.530949 -130.750541) (xy 433.489759 -130.71485) (xy 433.454067 -130.673661)
			(xy 433.424599 -130.627813) (xy 433.401955 -130.578238) (xy 433.386595 -130.525945) (xy 433.378833 -130.471999)
			(xy 433.378356 -130.444748) (xy 433.378535 -130.427185) (xy 433.381717 -130.392205) (xy 433.384706 -130.374898)
			(xy 433.386908 -130.360179) (xy 433.383669 -130.330608) (xy 433.37205 -130.303223) (xy 433.353036 -130.280346)
			(xy 433.328237 -130.263915) (xy 433.299757 -130.255323) (xy 433.284884 -130.254756) (xy 432.168808 -130.254756)
			(xy 432.153394 -130.255277) (xy 432.123964 -130.264449) (xy 432.098613 -130.281987) (xy 432.079655 -130.306294)
			(xy 432.068817 -130.335153) (xy 432.067462 -130.350514) (xy 432.06532 -130.379359) (xy 432.053421 -130.435962)
			(xy 432.033114 -130.490119) (xy 432.004863 -130.540589) (xy 431.969316 -130.586216) (xy 431.927289 -130.625954)
			(xy 431.879743 -130.658891) (xy 431.827771 -130.684272) (xy 431.772561 -130.701517) (xy 431.715382 -130.710228)
			(xy 431.686462 -130.710686) (xy 431.659213 -130.710197) (xy 431.605271 -130.702436) (xy 431.552982 -130.687077)
			(xy 431.503411 -130.664434) (xy 431.457567 -130.634966) (xy 431.416383 -130.599274) (xy 431.380698 -130.558085)
			(xy 431.351237 -130.512236) (xy 431.328602 -130.462662) (xy 431.313251 -130.410371) (xy 431.305499 -130.356427)
			(xy 431.304954 -130.329178) (xy 431.305428 -130.301785) (xy 431.31326 -130.247563) (xy 431.328762 -130.195016)
			(xy 431.339752 -130.16992) (xy 431.3453 -130.156504) (xy 431.349417 -130.127781) (xy 431.345289 -130.099059)
			(xy 431.333249 -130.072658) (xy 431.314269 -130.050709) (xy 431.289882 -130.034985) (xy 431.262057 -130.026755)
			(xy 431.24755 -130.026156) (xy 429.952658 -130.026156) (xy 429.938143 -130.026705) (xy 429.910302 -130.034937)
			(xy 429.885901 -130.050669) (xy 429.86691 -130.072629) (xy 429.854863 -130.099044) (xy 429.850733 -130.127782)
			(xy 429.854853 -130.156521) (xy 429.860456 -130.16992) (xy 429.871452 -130.195013) (xy 429.886948 -130.247561)
			(xy 429.894771 -130.301785) (xy 429.895254 -130.329178) (xy 429.894768 -130.356429) (xy 429.887012 -130.410377)
			(xy 429.871657 -130.462672) (xy 429.849015 -130.512249) (xy 429.819549 -130.558099) (xy 429.783858 -130.59929)
			(xy 429.742667 -130.634981) (xy 429.696817 -130.664447) (xy 429.64724 -130.687089) (xy 429.594945 -130.702444)
			(xy 429.540997 -130.7102) (xy 429.486495 -130.7102) (xy 429.432547 -130.702444) (xy 429.380252 -130.687089)
			(xy 429.330675 -130.664447) (xy 429.284825 -130.634981) (xy 429.243634 -130.59929) (xy 429.207943 -130.558099)
			(xy 429.178477 -130.512249) (xy 429.155835 -130.462672) (xy 429.14048 -130.410377) (xy 429.132724 -130.356429)
			(xy 429.132238 -130.329178) (xy 429.132712 -130.301785) (xy 429.140544 -130.247563) (xy 429.156045 -130.195016)
			(xy 429.167036 -130.16992) (xy 429.172584 -130.156505) (xy 429.176703 -130.127783) (xy 429.172575 -130.099062)
			(xy 429.160534 -130.072662) (xy 429.141554 -130.050715) (xy 429.117166 -130.034993) (xy 429.089341 -130.026767)
			(xy 429.074834 -130.026156) (xy 425.919392 -130.026156) (xy 425.90544 -130.026581) (xy 425.878575 -130.03412)
			(xy 425.85476 -130.04866) (xy 425.835778 -130.069111) (xy 425.82305 -130.093942) (xy 425.81753 -130.121293)
			(xy 425.819631 -130.149117) (xy 425.829195 -130.175329) (xy 425.845507 -130.197967) (xy 425.856146 -130.207004)
			(xy 425.878207 -130.225215) (xy 425.917147 -130.267117) (xy 425.9494 -130.314361) (xy 425.974243 -130.365887)
			(xy 425.99112 -130.420544) (xy 425.999653 -130.477107) (xy 426.000164 -130.505708) (xy 425.999678 -130.532959)
			(xy 425.991922 -130.586907) (xy 425.976567 -130.639202) (xy 425.953925 -130.688779) (xy 425.927114 -130.730498)
			(xy 427.27829 -130.730498) (xy 427.282361 -130.674876) (xy 427.294487 -130.620439) (xy 427.31441 -130.568348)
			(xy 427.341706 -130.519713) (xy 427.375792 -130.47557) (xy 427.415941 -130.436861) (xy 427.461299 -130.40441)
			(xy 427.510899 -130.378909) (xy 427.563683 -130.360902) (xy 427.618526 -130.350772) (xy 427.67426 -130.348735)
			(xy 427.729697 -130.354835) (xy 427.783654 -130.368941) (xy 427.834983 -130.390753) (xy 427.882589 -130.419807)
			(xy 427.925457 -130.455482) (xy 427.962674 -130.497019) (xy 427.993447 -130.543532) (xy 428.017119 -130.594029)
			(xy 428.033187 -130.647436) (xy 428.041307 -130.702612) (xy 428.041816 -130.730498) (xy 428.041307 -130.758384)
			(xy 428.033187 -130.81356) (xy 428.017119 -130.866967) (xy 427.993447 -130.917464) (xy 427.962674 -130.963977)
			(xy 427.925457 -131.005514) (xy 427.882589 -131.041189) (xy 427.834983 -131.070243) (xy 427.783654 -131.092055)
			(xy 427.729697 -131.106161) (xy 427.67426 -131.112261) (xy 427.618526 -131.110224) (xy 427.563683 -131.100094)
			(xy 427.510899 -131.082087) (xy 427.461299 -131.056586) (xy 427.415941 -131.024135) (xy 427.375792 -130.985426)
			(xy 427.341706 -130.941283) (xy 427.31441 -130.892648) (xy 427.294487 -130.840557) (xy 427.282361 -130.78612)
			(xy 427.27829 -130.730498) (xy 425.927114 -130.730498) (xy 425.924459 -130.734629) (xy 425.888768 -130.77582)
			(xy 425.847577 -130.811511) (xy 425.801727 -130.840977) (xy 425.75215 -130.863619) (xy 425.699855 -130.878974)
			(xy 425.645907 -130.88673) (xy 425.591405 -130.88673) (xy 425.537457 -130.878974) (xy 425.485162 -130.863619)
			(xy 425.435585 -130.840977) (xy 425.389735 -130.811511) (xy 425.348544 -130.77582) (xy 425.312853 -130.734629)
			(xy 425.283387 -130.688779) (xy 425.260745 -130.639202) (xy 425.24539 -130.586907) (xy 425.237634 -130.532959)
			(xy 425.237148 -130.505708) (xy 425.237631 -130.478248) (xy 425.245513 -130.423896) (xy 425.261099 -130.371234)
			(xy 425.28407 -130.321348) (xy 425.31395 -130.275267) (xy 425.350124 -130.233942) (xy 425.391844 -130.198227)
			(xy 425.438252 -130.168856) (xy 425.488388 -130.146437) (xy 425.541219 -130.131432) (xy 425.568364 -130.127248)
			(xy 425.61256 -130.121406) (xy 425.61256 -130.026156) (xy 425.379134 -130.026156) (xy 424.886628 -130.518662)
			(xy 424.763692 -130.641344) (xy 424.757088 -130.647948) (xy 424.655742 -130.749294) (xy 424.51147 -130.749294)
			(xy 424.503088 -130.749548) (xy 415.410142 -130.749548) (xy 414.61055 -131.54914) (xy 420.687752 -131.54914)
			(xy 420.691823 -131.493518) (xy 420.703949 -131.439081) (xy 420.723872 -131.38699) (xy 420.751168 -131.338355)
			(xy 420.785254 -131.294212) (xy 420.825403 -131.255503) (xy 420.870761 -131.223052) (xy 420.920361 -131.197551)
			(xy 420.973145 -131.179544) (xy 421.027988 -131.169414) (xy 421.083722 -131.167377) (xy 421.139159 -131.173477)
			(xy 421.193116 -131.187583) (xy 421.244445 -131.209395) (xy 421.292051 -131.238449) (xy 421.334919 -131.274124)
			(xy 421.372136 -131.315661) (xy 421.402909 -131.362174) (xy 421.426581 -131.412671) (xy 421.442649 -131.466078)
			(xy 421.450769 -131.521254) (xy 421.451278 -131.54914) (xy 421.450769 -131.577026) (xy 421.447509 -131.599178)
			(xy 428.565054 -131.599178) (xy 428.569125 -131.543556) (xy 428.581251 -131.489119) (xy 428.601174 -131.437028)
			(xy 428.62847 -131.388393) (xy 428.662556 -131.34425) (xy 428.702705 -131.305541) (xy 428.748063 -131.27309)
			(xy 428.797663 -131.247589) (xy 428.850447 -131.229582) (xy 428.90529 -131.219452) (xy 428.961024 -131.217415)
			(xy 429.016461 -131.223515) (xy 429.070418 -131.237621) (xy 429.121747 -131.259433) (xy 429.169353 -131.288487)
			(xy 429.212221 -131.324162) (xy 429.249438 -131.365699) (xy 429.280211 -131.412212) (xy 429.303883 -131.462709)
			(xy 429.319951 -131.516116) (xy 429.328071 -131.571292) (xy 429.32858 -131.599178) (xy 431.856386 -131.599178)
			(xy 431.860457 -131.543556) (xy 431.872583 -131.489119) (xy 431.892506 -131.437028) (xy 431.919802 -131.388393)
			(xy 431.953888 -131.34425) (xy 431.994037 -131.305541) (xy 432.039395 -131.27309) (xy 432.088995 -131.247589)
			(xy 432.141779 -131.229582) (xy 432.196622 -131.219452) (xy 432.252356 -131.217415) (xy 432.307793 -131.223515)
			(xy 432.36175 -131.237621) (xy 432.413079 -131.259433) (xy 432.460685 -131.288487) (xy 432.503553 -131.324162)
			(xy 432.54077 -131.365699) (xy 432.571543 -131.412212) (xy 432.595215 -131.462709) (xy 432.611283 -131.516116)
			(xy 432.619403 -131.571292) (xy 432.619912 -131.599178) (xy 432.619403 -131.627064) (xy 432.611283 -131.68224)
			(xy 432.595215 -131.735647) (xy 432.571543 -131.786144) (xy 432.54077 -131.832657) (xy 432.503553 -131.874194)
			(xy 432.460685 -131.909869) (xy 432.413079 -131.938923) (xy 432.36175 -131.960735) (xy 432.307793 -131.974841)
			(xy 432.252356 -131.980941) (xy 432.196622 -131.978904) (xy 432.141779 -131.968774) (xy 432.088995 -131.950767)
			(xy 432.039395 -131.925266) (xy 431.994037 -131.892815) (xy 431.953888 -131.854106) (xy 431.919802 -131.809963)
			(xy 431.892506 -131.761328) (xy 431.872583 -131.709237) (xy 431.860457 -131.6548) (xy 431.856386 -131.599178)
			(xy 429.32858 -131.599178) (xy 429.328071 -131.627064) (xy 429.319951 -131.68224) (xy 429.303883 -131.735647)
			(xy 429.280211 -131.786144) (xy 429.249438 -131.832657) (xy 429.212221 -131.874194) (xy 429.169353 -131.909869)
			(xy 429.121747 -131.938923) (xy 429.070418 -131.960735) (xy 429.016461 -131.974841) (xy 428.961024 -131.980941)
			(xy 428.90529 -131.978904) (xy 428.850447 -131.968774) (xy 428.797663 -131.950767) (xy 428.748063 -131.925266)
			(xy 428.702705 -131.892815) (xy 428.662556 -131.854106) (xy 428.62847 -131.809963) (xy 428.601174 -131.761328)
			(xy 428.581251 -131.709237) (xy 428.569125 -131.6548) (xy 428.565054 -131.599178) (xy 421.447509 -131.599178)
			(xy 421.442649 -131.632202) (xy 421.426581 -131.685609) (xy 421.402909 -131.736106) (xy 421.372136 -131.782619)
			(xy 421.334919 -131.824156) (xy 421.292051 -131.859831) (xy 421.244445 -131.888885) (xy 421.193116 -131.910697)
			(xy 421.139159 -131.924803) (xy 421.083722 -131.930903) (xy 421.027988 -131.928866) (xy 420.973145 -131.918736)
			(xy 420.920361 -131.900729) (xy 420.870761 -131.875228) (xy 420.825403 -131.842777) (xy 420.785254 -131.804068)
			(xy 420.751168 -131.759925) (xy 420.723872 -131.71129) (xy 420.703949 -131.659199) (xy 420.691823 -131.604762)
			(xy 420.687752 -131.54914) (xy 414.61055 -131.54914) (xy 413.211772 -132.947918) (xy 422.728642 -132.947918)
			(xy 422.732713 -132.892296) (xy 422.744839 -132.837859) (xy 422.764762 -132.785768) (xy 422.792058 -132.737133)
			(xy 422.826144 -132.69299) (xy 422.866293 -132.654281) (xy 422.911651 -132.62183) (xy 422.961251 -132.596329)
			(xy 423.014035 -132.578322) (xy 423.068878 -132.568192) (xy 423.124612 -132.566155) (xy 423.180049 -132.572255)
			(xy 423.234006 -132.586361) (xy 423.285335 -132.608173) (xy 423.332941 -132.637227) (xy 423.375809 -132.672902)
			(xy 423.413026 -132.714439) (xy 423.443799 -132.760952) (xy 423.467471 -132.811449) (xy 423.483539 -132.864856)
			(xy 423.491659 -132.920032) (xy 423.492168 -132.947918) (xy 423.491659 -132.975804) (xy 423.483539 -133.03098)
			(xy 423.471466 -133.071108) (xy 425.474382 -133.071108) (xy 425.478453 -133.015486) (xy 425.490579 -132.961049)
			(xy 425.510502 -132.908958) (xy 425.537798 -132.860323) (xy 425.571884 -132.81618) (xy 425.612033 -132.777471)
			(xy 425.657391 -132.74502) (xy 425.706991 -132.719519) (xy 425.759775 -132.701512) (xy 425.814618 -132.691382)
			(xy 425.870352 -132.689345) (xy 425.925789 -132.695445) (xy 425.979746 -132.709551) (xy 426.031075 -132.731363)
			(xy 426.078681 -132.760417) (xy 426.121549 -132.796092) (xy 426.158766 -132.837629) (xy 426.189539 -132.884142)
			(xy 426.213211 -132.934639) (xy 426.229279 -132.988046) (xy 426.237399 -133.043222) (xy 426.237908 -133.071108)
			(xy 426.237399 -133.098994) (xy 426.229279 -133.15417) (xy 426.213211 -133.207577) (xy 426.189539 -133.258074)
			(xy 426.158766 -133.304587) (xy 426.121549 -133.346124) (xy 426.078681 -133.381799) (xy 426.031075 -133.410853)
			(xy 425.979746 -133.432665) (xy 425.925789 -133.446771) (xy 425.870352 -133.452871) (xy 425.814618 -133.450834)
			(xy 425.759775 -133.440704) (xy 425.706991 -133.422697) (xy 425.657391 -133.397196) (xy 425.612033 -133.364745)
			(xy 425.571884 -133.326036) (xy 425.537798 -133.281893) (xy 425.510502 -133.233258) (xy 425.490579 -133.181167)
			(xy 425.478453 -133.12673) (xy 425.474382 -133.071108) (xy 423.471466 -133.071108) (xy 423.467471 -133.084387)
			(xy 423.443799 -133.134884) (xy 423.413026 -133.181397) (xy 423.375809 -133.222934) (xy 423.332941 -133.258609)
			(xy 423.285335 -133.287663) (xy 423.234006 -133.309475) (xy 423.180049 -133.323581) (xy 423.124612 -133.329681)
			(xy 423.068878 -133.327644) (xy 423.014035 -133.317514) (xy 422.961251 -133.299507) (xy 422.911651 -133.274006)
			(xy 422.866293 -133.241555) (xy 422.826144 -133.202846) (xy 422.792058 -133.158703) (xy 422.764762 -133.110068)
			(xy 422.744839 -133.057977) (xy 422.732713 -133.00354) (xy 422.728642 -132.947918) (xy 413.211772 -132.947918)
			(xy 412.680912 -133.478778) (xy 429.131728 -133.478778) (xy 429.135799 -133.423156) (xy 429.147925 -133.368719)
			(xy 429.167848 -133.316628) (xy 429.195144 -133.267993) (xy 429.22923 -133.22385) (xy 429.269379 -133.185141)
			(xy 429.314737 -133.15269) (xy 429.364337 -133.127189) (xy 429.417121 -133.109182) (xy 429.471964 -133.099052)
			(xy 429.527698 -133.097015) (xy 429.583135 -133.103115) (xy 429.637092 -133.117221) (xy 429.688421 -133.139033)
			(xy 429.736027 -133.168087) (xy 429.778895 -133.203762) (xy 429.816112 -133.245299) (xy 429.846885 -133.291812)
			(xy 429.870557 -133.342309) (xy 429.886625 -133.395716) (xy 429.894745 -133.450892) (xy 429.895254 -133.478778)
			(xy 429.894745 -133.506664) (xy 429.886625 -133.56184) (xy 429.870557 -133.615247) (xy 429.846885 -133.665744)
			(xy 429.816112 -133.712257) (xy 429.778895 -133.753794) (xy 429.736027 -133.789469) (xy 429.688421 -133.818523)
			(xy 429.637092 -133.840335) (xy 429.583135 -133.854441) (xy 429.527698 -133.860541) (xy 429.471964 -133.858504)
			(xy 429.417121 -133.848374) (xy 429.364337 -133.830367) (xy 429.314737 -133.804866) (xy 429.269379 -133.772415)
			(xy 429.22923 -133.733706) (xy 429.195144 -133.689563) (xy 429.167848 -133.640928) (xy 429.147925 -133.588837)
			(xy 429.135799 -133.5344) (xy 429.131728 -133.478778) (xy 412.680912 -133.478778) (xy 411.411928 -134.747762)
			(xy 429.158398 -134.747762) (xy 429.162469 -134.69214) (xy 429.174595 -134.637703) (xy 429.194518 -134.585612)
			(xy 429.221814 -134.536977) (xy 429.2559 -134.492834) (xy 429.296049 -134.454125) (xy 429.341407 -134.421674)
			(xy 429.391007 -134.396173) (xy 429.443791 -134.378166) (xy 429.498634 -134.368036) (xy 429.554368 -134.365999)
			(xy 429.609805 -134.372099) (xy 429.663762 -134.386205) (xy 429.715091 -134.408017) (xy 429.762697 -134.437071)
			(xy 429.805565 -134.472746) (xy 429.842782 -134.514283) (xy 429.873555 -134.560796) (xy 429.897227 -134.611293)
			(xy 429.913295 -134.6647) (xy 429.921415 -134.719876) (xy 429.921924 -134.747762) (xy 429.921415 -134.775648)
			(xy 429.913295 -134.830824) (xy 429.897227 -134.884231) (xy 429.873555 -134.934728) (xy 429.842782 -134.981241)
			(xy 429.805565 -135.022778) (xy 429.762697 -135.058453) (xy 429.715091 -135.087507) (xy 429.663762 -135.109319)
			(xy 429.609805 -135.123425) (xy 429.554368 -135.129525) (xy 429.498634 -135.127488) (xy 429.443791 -135.117358)
			(xy 429.391007 -135.099351) (xy 429.341407 -135.07385) (xy 429.296049 -135.041399) (xy 429.2559 -135.00269)
			(xy 429.221814 -134.958547) (xy 429.194518 -134.909912) (xy 429.174595 -134.857821) (xy 429.162469 -134.803384)
			(xy 429.158398 -134.747762) (xy 411.411928 -134.747762) (xy 411.017212 -135.142478) (xy 419.188136 -135.142478)
			(xy 419.192207 -135.086856) (xy 419.204333 -135.032419) (xy 419.224256 -134.980328) (xy 419.251552 -134.931693)
			(xy 419.285638 -134.88755) (xy 419.325787 -134.848841) (xy 419.371145 -134.81639) (xy 419.420745 -134.790889)
			(xy 419.473529 -134.772882) (xy 419.528372 -134.762752) (xy 419.584106 -134.760715) (xy 419.639543 -134.766815)
			(xy 419.6935 -134.780921) (xy 419.744829 -134.802733) (xy 419.792435 -134.831787) (xy 419.835303 -134.867462)
			(xy 419.87252 -134.908999) (xy 419.903293 -134.955512) (xy 419.926965 -135.006009) (xy 419.943033 -135.059416)
			(xy 419.951153 -135.114592) (xy 419.951662 -135.142478) (xy 419.951597 -135.146034) (xy 421.320214 -135.146034)
			(xy 421.3207 -135.118783) (xy 421.328456 -135.064835) (xy 421.343811 -135.01254) (xy 421.366453 -134.962963)
			(xy 421.395919 -134.917113) (xy 421.43161 -134.875922) (xy 421.472801 -134.840231) (xy 421.518651 -134.810765)
			(xy 421.568228 -134.788123) (xy 421.620523 -134.772768) (xy 421.674471 -134.765012) (xy 421.728973 -134.765012)
			(xy 421.782921 -134.772768) (xy 421.835216 -134.788123) (xy 421.884793 -134.810765) (xy 421.930643 -134.840231)
			(xy 421.971834 -134.875922) (xy 422.007525 -134.917113) (xy 422.036991 -134.962963) (xy 422.059633 -135.01254)
			(xy 422.074988 -135.064835) (xy 422.082744 -135.118783) (xy 422.08323 -135.146034) (xy 422.08286 -135.171249)
			(xy 422.076256 -135.221245) (xy 422.063114 -135.269932) (xy 422.053766 -135.293354) (xy 422.048903 -135.306273)
			(xy 422.045481 -135.333649) (xy 422.049519 -135.360942) (xy 422.060722 -135.386154) (xy 422.07827 -135.407444)
			(xy 422.100882 -135.423252) (xy 422.126902 -135.432425) (xy 422.140634 -135.433816) (xy 422.169256 -135.436256)
			(xy 422.225356 -135.448603) (xy 422.278972 -135.469218) (xy 422.328892 -135.497637) (xy 422.373988 -135.533217)
			(xy 422.413242 -135.575154) (xy 422.445767 -135.622501) (xy 422.470828 -135.674189) (xy 422.487858 -135.729048)
			(xy 422.496474 -135.785841) (xy 422.496996 -135.814562) (xy 422.496421 -135.844475) (xy 422.487063 -135.903565)
			(xy 422.468587 -135.960466) (xy 422.441447 -136.013782) (xy 422.424352 -136.038336) (xy 422.417 -136.049244)
			(xy 422.407492 -136.073757) (xy 422.404562 -136.099886) (xy 422.408405 -136.125896) (xy 422.418765 -136.150062)
			(xy 422.434956 -136.170778) (xy 422.44518 -136.179052) (xy 422.468223 -136.197173) (xy 422.508955 -136.239328)
			(xy 422.542755 -136.287221) (xy 422.568827 -136.339723) (xy 422.586555 -136.395597) (xy 422.595522 -136.453526)
			(xy 422.596056 -136.482836) (xy 422.59557 -136.510087) (xy 422.587814 -136.564035) (xy 422.572459 -136.61633)
			(xy 422.549817 -136.665907) (xy 422.520351 -136.711757) (xy 422.48466 -136.752948) (xy 422.443469 -136.788639)
			(xy 422.397619 -136.818105) (xy 422.348042 -136.840747) (xy 422.295747 -136.856102) (xy 422.241799 -136.863858)
			(xy 422.187297 -136.863858) (xy 422.133349 -136.856102) (xy 422.081054 -136.840747) (xy 422.031477 -136.818105)
			(xy 421.985627 -136.788639) (xy 421.944436 -136.752948) (xy 421.908745 -136.711757) (xy 421.879279 -136.665907)
			(xy 421.856637 -136.61633) (xy 421.841282 -136.564035) (xy 421.833526 -136.510087) (xy 421.83304 -136.482836)
			(xy 421.833608 -136.452923) (xy 421.842966 -136.393832) (xy 421.861444 -136.33693) (xy 421.888587 -136.283615)
			(xy 421.905684 -136.259062) (xy 421.913053 -136.248163) (xy 421.922569 -136.223647) (xy 421.925501 -136.197514)
			(xy 421.921655 -136.171499) (xy 421.911287 -136.147331) (xy 421.895086 -136.126617) (xy 421.884856 -136.118346)
			(xy 421.861799 -136.100243) (xy 421.82107 -136.058082) (xy 421.787274 -136.010185) (xy 421.761205 -135.95768)
			(xy 421.74348 -135.901803) (xy 421.734514 -135.843872) (xy 421.73398 -135.814562) (xy 421.734348 -135.789347)
			(xy 421.740953 -135.739351) (xy 421.754095 -135.690663) (xy 421.763444 -135.667242) (xy 421.768303 -135.654323)
			(xy 421.771724 -135.626947) (xy 421.767685 -135.599656) (xy 421.756483 -135.574444) (xy 421.738935 -135.553155)
			(xy 421.716326 -135.537346) (xy 421.690307 -135.528172) (xy 421.676576 -135.52678) (xy 421.647954 -135.524335)
			(xy 421.591854 -135.51199) (xy 421.538238 -135.491375) (xy 421.488318 -135.462958) (xy 421.443221 -135.427378)
			(xy 421.403967 -135.385441) (xy 421.371442 -135.338094) (xy 421.346381 -135.286407) (xy 421.329351 -135.231548)
			(xy 421.320736 -135.174755) (xy 421.320214 -135.146034) (xy 419.951597 -135.146034) (xy 419.951153 -135.170364)
			(xy 419.943033 -135.22554) (xy 419.926965 -135.278947) (xy 419.903293 -135.329444) (xy 419.87252 -135.375957)
			(xy 419.835303 -135.417494) (xy 419.792435 -135.453169) (xy 419.744829 -135.482223) (xy 419.6935 -135.504035)
			(xy 419.639543 -135.518141) (xy 419.584106 -135.524241) (xy 419.528372 -135.522204) (xy 419.473529 -135.512074)
			(xy 419.420745 -135.494067) (xy 419.371145 -135.468566) (xy 419.325787 -135.436115) (xy 419.285638 -135.397406)
			(xy 419.251552 -135.353263) (xy 419.224256 -135.304628) (xy 419.204333 -135.252537) (xy 419.192207 -135.1981)
			(xy 419.188136 -135.142478) (xy 411.017212 -135.142478) (xy 410.18968 -135.97001) (xy 410.18968 -137.130028)
			(xy 428.753016 -137.130028) (xy 428.753463 -137.103293) (xy 428.760925 -137.050348) (xy 428.775708 -136.998963)
			(xy 428.797521 -136.950146) (xy 428.825937 -136.904853) (xy 428.860399 -136.863971) (xy 428.880016 -136.845802)
			(xy 428.890822 -136.835406) (xy 428.906368 -136.809781) (xy 428.913789 -136.780743) (xy 428.912443 -136.750802)
			(xy 428.902446 -136.722547) (xy 428.893986 -136.710166) (xy 428.876517 -136.68545) (xy 428.848814 -136.631639)
			(xy 428.829949 -136.574132) (xy 428.820397 -136.514367) (xy 428.819818 -136.484106) (xy 428.82029 -136.455888)
			(xy 428.828576 -136.400063) (xy 428.844998 -136.34607) (xy 428.869197 -136.295085) (xy 428.900645 -136.248223)
			(xy 428.938655 -136.206507) (xy 428.982397 -136.170847) (xy 429.030917 -136.142022) (xy 429.083154 -136.120661)
			(xy 429.137969 -136.107232) (xy 429.16602 -136.104122) (xy 429.180402 -136.102296) (xy 429.207356 -136.091662)
			(xy 429.230235 -136.073881) (xy 429.247195 -136.050386) (xy 429.256869 -136.023073) (xy 429.258478 -135.994141)
			(xy 429.255682 -135.979916) (xy 429.250944 -135.958447) (xy 429.245847 -135.914777) (xy 429.245522 -135.892794)
			(xy 429.246008 -135.865543) (xy 429.253764 -135.811595) (xy 429.269119 -135.7593) (xy 429.291761 -135.709723)
			(xy 429.321227 -135.663873) (xy 429.356918 -135.622682) (xy 429.398109 -135.586991) (xy 429.443959 -135.557525)
			(xy 429.493536 -135.534883) (xy 429.545831 -135.519528) (xy 429.599779 -135.511772) (xy 429.654281 -135.511772)
			(xy 429.708229 -135.519528) (xy 429.760524 -135.534883) (xy 429.810101 -135.557525) (xy 429.855951 -135.586991)
			(xy 429.897142 -135.622682) (xy 429.932833 -135.663873) (xy 429.962299 -135.709723) (xy 429.984941 -135.7593)
			(xy 430.000296 -135.811595) (xy 430.008052 -135.865543) (xy 430.008538 -135.892794) (xy 430.008015 -135.92101)
			(xy 429.999731 -135.97683) (xy 429.983312 -136.030819) (xy 429.959117 -136.081801) (xy 429.927675 -136.128661)
			(xy 429.889671 -136.170376) (xy 429.845935 -136.206037) (xy 429.797423 -136.234864) (xy 429.745192 -136.256229)
			(xy 429.690384 -136.269664) (xy 429.662336 -136.272778) (xy 429.64796 -136.274645) (xy 429.621005 -136.285266)
			(xy 429.598123 -136.303038) (xy 429.58116 -136.326525) (xy 429.571485 -136.353834) (xy 429.569877 -136.382761)
			(xy 429.572674 -136.396984) (xy 429.577413 -136.418453) (xy 429.582509 -136.462123) (xy 429.582834 -136.484106)
			(xy 429.582359 -136.51084) (xy 429.574905 -136.563785) (xy 429.560129 -136.61517) (xy 429.538321 -136.663988)
			(xy 429.509909 -136.709281) (xy 429.47545 -136.750163) (xy 429.455834 -136.768332) (xy 429.444998 -136.778702)
			(xy 429.429448 -136.804333) (xy 429.422029 -136.83338) (xy 429.423384 -136.863329) (xy 429.433395 -136.891588)
			(xy 429.441864 -136.903968) (xy 429.459298 -136.928708) (xy 429.487011 -136.982509) (xy 429.505885 -137.04001)
			(xy 429.515448 -137.099769) (xy 429.516032 -137.130028) (xy 429.515546 -137.157279) (xy 429.50779 -137.211227)
			(xy 429.492435 -137.263522) (xy 429.469793 -137.313099) (xy 429.440327 -137.358949) (xy 429.404636 -137.40014)
			(xy 429.363445 -137.435831) (xy 429.317595 -137.465297) (xy 429.268018 -137.487939) (xy 429.215723 -137.503294)
			(xy 429.161775 -137.51105) (xy 429.107273 -137.51105) (xy 429.053325 -137.503294) (xy 429.00103 -137.487939)
			(xy 428.951453 -137.465297) (xy 428.905603 -137.435831) (xy 428.864412 -137.40014) (xy 428.828721 -137.358949)
			(xy 428.799255 -137.313099) (xy 428.776613 -137.263522) (xy 428.761258 -137.211227) (xy 428.753502 -137.157279)
			(xy 428.753016 -137.130028) (xy 410.18968 -137.130028) (xy 410.18968 -137.724388) (xy 421.191942 -137.724388)
			(xy 421.196013 -137.668766) (xy 421.208139 -137.614329) (xy 421.228062 -137.562238) (xy 421.255358 -137.513603)
			(xy 421.289444 -137.46946) (xy 421.329593 -137.430751) (xy 421.374951 -137.3983) (xy 421.424551 -137.372799)
			(xy 421.477335 -137.354792) (xy 421.532178 -137.344662) (xy 421.587912 -137.342625) (xy 421.643349 -137.348725)
			(xy 421.697306 -137.362831) (xy 421.748635 -137.384643) (xy 421.796241 -137.413697) (xy 421.839109 -137.449372)
			(xy 421.876326 -137.490909) (xy 421.907099 -137.537422) (xy 421.930771 -137.587919) (xy 421.946839 -137.641326)
			(xy 421.954959 -137.696502) (xy 421.955468 -137.724388) (xy 421.954959 -137.752274) (xy 421.946839 -137.80745)
			(xy 421.930771 -137.860857) (xy 421.907099 -137.911354) (xy 421.876326 -137.957867) (xy 421.839109 -137.999404)
			(xy 421.796241 -138.035079) (xy 421.748635 -138.064133) (xy 421.697306 -138.085945) (xy 421.643349 -138.100051)
			(xy 421.587912 -138.106151) (xy 421.532178 -138.104114) (xy 421.477335 -138.093984) (xy 421.424551 -138.075977)
			(xy 421.374951 -138.050476) (xy 421.329593 -138.018025) (xy 421.289444 -137.979316) (xy 421.255358 -137.935173)
			(xy 421.228062 -137.886538) (xy 421.208139 -137.834447) (xy 421.196013 -137.78001) (xy 421.191942 -137.724388)
			(xy 410.18968 -137.724388) (xy 410.18968 -138.143996) (xy 428.762158 -138.143996) (xy 428.766229 -138.088374)
			(xy 428.778355 -138.033937) (xy 428.798278 -137.981846) (xy 428.825574 -137.933211) (xy 428.85966 -137.889068)
			(xy 428.899809 -137.850359) (xy 428.945167 -137.817908) (xy 428.994767 -137.792407) (xy 429.047551 -137.7744)
			(xy 429.102394 -137.76427) (xy 429.158128 -137.762233) (xy 429.213565 -137.768333) (xy 429.267522 -137.782439)
			(xy 429.318851 -137.804251) (xy 429.366457 -137.833305) (xy 429.409325 -137.86898) (xy 429.446542 -137.910517)
			(xy 429.477315 -137.95703) (xy 429.500987 -138.007527) (xy 429.517055 -138.060934) (xy 429.525175 -138.11611)
			(xy 429.525684 -138.143996) (xy 429.525175 -138.171882) (xy 429.517055 -138.227058) (xy 429.500987 -138.280465)
			(xy 429.477315 -138.330962) (xy 429.446542 -138.377475) (xy 429.409325 -138.419012) (xy 429.366457 -138.454687)
			(xy 429.318851 -138.483741) (xy 429.267522 -138.505553) (xy 429.213565 -138.519659) (xy 429.158128 -138.525759)
			(xy 429.102394 -138.523722) (xy 429.047551 -138.513592) (xy 428.994767 -138.495585) (xy 428.945167 -138.470084)
			(xy 428.899809 -138.437633) (xy 428.85966 -138.398924) (xy 428.825574 -138.354781) (xy 428.798278 -138.306146)
			(xy 428.778355 -138.254055) (xy 428.766229 -138.199618) (xy 428.762158 -138.143996) (xy 410.18968 -138.143996)
			(xy 410.18968 -138.575288) (xy 419.00043 -138.575288) (xy 419.004501 -138.519666) (xy 419.016627 -138.465229)
			(xy 419.03655 -138.413138) (xy 419.063846 -138.364503) (xy 419.097932 -138.32036) (xy 419.138081 -138.281651)
			(xy 419.183439 -138.2492) (xy 419.233039 -138.223699) (xy 419.285823 -138.205692) (xy 419.340666 -138.195562)
			(xy 419.3964 -138.193525) (xy 419.451837 -138.199625) (xy 419.505794 -138.213731) (xy 419.557123 -138.235543)
			(xy 419.604729 -138.264597) (xy 419.647597 -138.300272) (xy 419.684814 -138.341809) (xy 419.715587 -138.388322)
			(xy 419.739259 -138.438819) (xy 419.755327 -138.492226) (xy 419.763447 -138.547402) (xy 419.763956 -138.575288)
			(xy 419.763447 -138.603174) (xy 419.755327 -138.65835) (xy 419.739259 -138.711757) (xy 419.715587 -138.762254)
			(xy 419.684814 -138.808767) (xy 419.647597 -138.850304) (xy 419.604729 -138.885979) (xy 419.557123 -138.915033)
			(xy 419.505794 -138.936845) (xy 419.451837 -138.950951) (xy 419.3964 -138.957051) (xy 419.340666 -138.955014)
			(xy 419.285823 -138.944884) (xy 419.233039 -138.926877) (xy 419.183439 -138.901376) (xy 419.138081 -138.868925)
			(xy 419.097932 -138.830216) (xy 419.063846 -138.786073) (xy 419.03655 -138.737438) (xy 419.016627 -138.685347)
			(xy 419.004501 -138.63091) (xy 419.00043 -138.575288) (xy 410.18968 -138.575288) (xy 410.18968 -139.48664)
			(xy 417.582602 -139.48664) (xy 417.586673 -139.431018) (xy 417.598799 -139.376581) (xy 417.618722 -139.32449)
			(xy 417.646018 -139.275855) (xy 417.680104 -139.231712) (xy 417.720253 -139.193003) (xy 417.765611 -139.160552)
			(xy 417.815211 -139.135051) (xy 417.867995 -139.117044) (xy 417.922838 -139.106914) (xy 417.978572 -139.104877)
			(xy 418.034009 -139.110977) (xy 418.087966 -139.125083) (xy 418.139295 -139.146895) (xy 418.186901 -139.175949)
			(xy 418.229769 -139.211624) (xy 418.266986 -139.253161) (xy 418.297759 -139.299674) (xy 418.321431 -139.350171)
			(xy 418.337499 -139.403578) (xy 418.345619 -139.458754) (xy 418.346128 -139.48664) (xy 418.345619 -139.514526)
			(xy 418.343667 -139.527788) (xy 419.538402 -139.527788) (xy 419.542473 -139.472166) (xy 419.554599 -139.417729)
			(xy 419.574522 -139.365638) (xy 419.601818 -139.317003) (xy 419.635904 -139.27286) (xy 419.676053 -139.234151)
			(xy 419.721411 -139.2017) (xy 419.771011 -139.176199) (xy 419.823795 -139.158192) (xy 419.878638 -139.148062)
			(xy 419.934372 -139.146025) (xy 419.989809 -139.152125) (xy 420.043766 -139.166231) (xy 420.095095 -139.188043)
			(xy 420.142701 -139.217097) (xy 420.185569 -139.252772) (xy 420.222786 -139.294309) (xy 420.253559 -139.340822)
			(xy 420.277231 -139.391319) (xy 420.293299 -139.444726) (xy 420.301419 -139.499902) (xy 420.301928 -139.527788)
			(xy 420.301419 -139.555674) (xy 420.293299 -139.61085) (xy 420.277231 -139.664257) (xy 420.261428 -139.697968)
			(xy 423.5229 -139.697968) (xy 423.526971 -139.642346) (xy 423.539097 -139.587909) (xy 423.55902 -139.535818)
			(xy 423.586316 -139.487183) (xy 423.620402 -139.44304) (xy 423.660551 -139.404331) (xy 423.705909 -139.37188)
			(xy 423.755509 -139.346379) (xy 423.808293 -139.328372) (xy 423.863136 -139.318242) (xy 423.91887 -139.316205)
			(xy 423.974307 -139.322305) (xy 424.028264 -139.336411) (xy 424.079593 -139.358223) (xy 424.127199 -139.387277)
			(xy 424.170067 -139.422952) (xy 424.207284 -139.464489) (xy 424.238057 -139.511002) (xy 424.261729 -139.561499)
			(xy 424.277797 -139.614906) (xy 424.285917 -139.670082) (xy 424.286426 -139.697968) (xy 424.285917 -139.725854)
			(xy 424.277797 -139.78103) (xy 424.261729 -139.834437) (xy 424.238057 -139.884934) (xy 424.207284 -139.931447)
			(xy 424.170067 -139.972984) (xy 424.127199 -140.008659) (xy 424.079593 -140.037713) (xy 424.028264 -140.059525)
			(xy 423.974307 -140.073631) (xy 423.91887 -140.079731) (xy 423.863136 -140.077694) (xy 423.808293 -140.067564)
			(xy 423.755509 -140.049557) (xy 423.705909 -140.024056) (xy 423.660551 -139.991605) (xy 423.620402 -139.952896)
			(xy 423.586316 -139.908753) (xy 423.55902 -139.860118) (xy 423.539097 -139.808027) (xy 423.526971 -139.75359)
			(xy 423.5229 -139.697968) (xy 420.261428 -139.697968) (xy 420.253559 -139.714754) (xy 420.222786 -139.761267)
			(xy 420.185569 -139.802804) (xy 420.142701 -139.838479) (xy 420.095095 -139.867533) (xy 420.043766 -139.889345)
			(xy 419.989809 -139.903451) (xy 419.934372 -139.909551) (xy 419.878638 -139.907514) (xy 419.823795 -139.897384)
			(xy 419.771011 -139.879377) (xy 419.721411 -139.853876) (xy 419.676053 -139.821425) (xy 419.635904 -139.782716)
			(xy 419.601818 -139.738573) (xy 419.574522 -139.689938) (xy 419.554599 -139.637847) (xy 419.542473 -139.58341)
			(xy 419.538402 -139.527788) (xy 418.343667 -139.527788) (xy 418.337499 -139.569702) (xy 418.321431 -139.623109)
			(xy 418.297759 -139.673606) (xy 418.266986 -139.720119) (xy 418.229769 -139.761656) (xy 418.186901 -139.797331)
			(xy 418.139295 -139.826385) (xy 418.087966 -139.848197) (xy 418.034009 -139.862303) (xy 417.978572 -139.868403)
			(xy 417.922838 -139.866366) (xy 417.867995 -139.856236) (xy 417.815211 -139.838229) (xy 417.765611 -139.812728)
			(xy 417.720253 -139.780277) (xy 417.680104 -139.741568) (xy 417.646018 -139.697425) (xy 417.618722 -139.64879)
			(xy 417.598799 -139.596699) (xy 417.586673 -139.542262) (xy 417.582602 -139.48664) (xy 410.18968 -139.48664)
			(xy 410.18968 -140.264388) (xy 426.322996 -140.264388) (xy 426.327067 -140.208766) (xy 426.339193 -140.154329)
			(xy 426.359116 -140.102238) (xy 426.386412 -140.053603) (xy 426.420498 -140.00946) (xy 426.460647 -139.970751)
			(xy 426.506005 -139.9383) (xy 426.555605 -139.912799) (xy 426.608389 -139.894792) (xy 426.663232 -139.884662)
			(xy 426.718966 -139.882625) (xy 426.774403 -139.888725) (xy 426.82836 -139.902831) (xy 426.879689 -139.924643)
			(xy 426.927295 -139.953697) (xy 426.970163 -139.989372) (xy 427.00738 -140.030909) (xy 427.038153 -140.077422)
			(xy 427.061825 -140.127919) (xy 427.077893 -140.181326) (xy 427.086013 -140.236502) (xy 427.086522 -140.264388)
			(xy 427.086013 -140.292274) (xy 427.077893 -140.34745) (xy 427.061825 -140.400857) (xy 427.038153 -140.451354)
			(xy 427.00738 -140.497867) (xy 426.970163 -140.539404) (xy 426.927295 -140.575079) (xy 426.879689 -140.604133)
			(xy 426.82836 -140.625945) (xy 426.774403 -140.640051) (xy 426.718966 -140.646151) (xy 426.663232 -140.644114)
			(xy 426.608389 -140.633984) (xy 426.555605 -140.615977) (xy 426.506005 -140.590476) (xy 426.460647 -140.558025)
			(xy 426.420498 -140.519316) (xy 426.386412 -140.475173) (xy 426.359116 -140.426538) (xy 426.339193 -140.374447)
			(xy 426.327067 -140.32001) (xy 426.322996 -140.264388) (xy 410.18968 -140.264388) (xy 410.18968 -142.35684)
			(xy 416.831526 -142.35684) (xy 416.92068 -142.267686) (xy 416.923982 -142.262352) (xy 416.938874 -142.238564)
			(xy 416.974537 -142.19523) (xy 417.016162 -142.157587) (xy 417.06285 -142.126446) (xy 417.113596 -142.102478)
			(xy 417.167306 -142.0862) (xy 417.222819 -142.077963) (xy 417.25088 -142.07744) (xy 417.278133 -142.077902)
			(xy 417.332083 -142.085657) (xy 417.384381 -142.101012) (xy 417.43396 -142.123654) (xy 417.479812 -142.153122)
			(xy 417.521003 -142.188816) (xy 417.556695 -142.23001) (xy 417.58616 -142.275864) (xy 417.608798 -142.325446)
			(xy 417.624149 -142.377744) (xy 417.6319 -142.431695) (xy 417.632388 -142.458948) (xy 417.631894 -142.487012)
			(xy 417.623673 -142.542533) (xy 417.607402 -142.59625) (xy 417.583431 -142.647001) (xy 417.55228 -142.693689)
			(xy 417.514621 -142.735306) (xy 417.471267 -142.770953) (xy 417.447476 -142.785846) (xy 417.442142 -142.789148)
			(xy 417.350194 -142.881096) (xy 417.244784 -142.986252) (xy 417.232846 -142.997682) (xy 417.230306 -143.000222)
			(xy 417.220487 -143.00965) (xy 417.205801 -143.032557) (xy 417.197689 -143.058531) (xy 417.196728 -143.085725)
			(xy 417.202986 -143.112206) (xy 417.216019 -143.136093) (xy 417.234901 -143.155687) (xy 417.258288 -143.169596)
			(xy 417.284519 -143.176831) (xy 417.298124 -143.17726) (xy 420.759382 -143.17726) (xy 422.41851 -141.518132)
			(xy 422.427984 -141.507987) (xy 422.441594 -141.483808) (xy 422.448204 -141.456861) (xy 422.447326 -141.429128)
			(xy 422.439025 -141.402653) (xy 422.423913 -141.379383) (xy 422.403102 -141.361033) (xy 422.390824 -141.354556)
			(xy 422.364374 -141.343682) (xy 422.314803 -141.315168) (xy 422.270042 -141.279575) (xy 422.231094 -141.237702)
			(xy 422.198831 -141.190485) (xy 422.173975 -141.138983) (xy 422.157082 -141.084347) (xy 422.148532 -141.027803)
			(xy 422.148 -140.99921) (xy 422.148463 -140.971957) (xy 422.156219 -140.918005) (xy 422.171574 -140.865707)
			(xy 422.194216 -140.816126) (xy 422.223684 -140.770272) (xy 422.259377 -140.729079) (xy 422.30057 -140.693385)
			(xy 422.346424 -140.663917) (xy 422.396005 -140.641274) (xy 422.448303 -140.625919) (xy 422.502255 -140.618163)
			(xy 422.529508 -140.617702) (xy 422.555886 -140.618148) (xy 422.608141 -140.625413) (xy 422.658897 -140.639803)
			(xy 422.707189 -140.661044) (xy 422.752096 -140.688732) (xy 422.792763 -140.722339) (xy 422.828416 -140.761225)
			(xy 422.858376 -140.80465) (xy 422.87063 -140.828014) (xy 422.877332 -140.840373) (xy 422.896307 -140.861101)
			(xy 422.920221 -140.875863) (xy 422.947257 -140.883535) (xy 422.975359 -140.883535) (xy 423.002395 -140.875863)
			(xy 423.026309 -140.861101) (xy 423.045284 -140.840373) (xy 423.051986 -140.828014) (xy 423.064229 -140.804645)
			(xy 423.094187 -140.761219) (xy 423.12984 -140.722332) (xy 423.170509 -140.688727) (xy 423.215419 -140.661044)
			(xy 423.263714 -140.63981) (xy 423.314473 -140.62543) (xy 423.366729 -140.618179) (xy 423.393108 -140.617702)
			(xy 423.420844 -140.618207) (xy 423.475729 -140.626252) (xy 423.528872 -140.642158) (xy 423.579153 -140.665588)
			(xy 423.625513 -140.69605) (xy 423.666975 -140.732902) (xy 423.702666 -140.775367) (xy 423.731833 -140.822552)
			(xy 423.753864 -140.873462) (xy 423.768293 -140.927024) (xy 423.772076 -140.954506) (xy 423.7736 -140.968222)
			(xy 423.775422 -140.996875) (xy 423.771472 -141.054151) (xy 423.758986 -141.110189) (xy 423.738246 -141.163724)
			(xy 423.709719 -141.213547) (xy 423.67405 -141.258534) (xy 423.632043 -141.29767) (xy 423.584647 -141.33007)
			(xy 423.532932 -141.355004) (xy 423.478066 -141.371909) (xy 423.44975 -141.376654) (xy 423.406316 -141.383258)
			(xy 423.406316 -141.415008) (xy 426.048422 -141.415008) (xy 426.052493 -141.359386) (xy 426.064619 -141.304949)
			(xy 426.084542 -141.252858) (xy 426.111838 -141.204223) (xy 426.145924 -141.16008) (xy 426.186073 -141.121371)
			(xy 426.231431 -141.08892) (xy 426.281031 -141.063419) (xy 426.333815 -141.045412) (xy 426.388658 -141.035282)
			(xy 426.444392 -141.033245) (xy 426.499829 -141.039345) (xy 426.553786 -141.053451) (xy 426.605115 -141.075263)
			(xy 426.652721 -141.104317) (xy 426.695589 -141.139992) (xy 426.732806 -141.181529) (xy 426.763579 -141.228042)
			(xy 426.787251 -141.278539) (xy 426.803319 -141.331946) (xy 426.811439 -141.387122) (xy 426.811948 -141.415008)
			(xy 426.811439 -141.442894) (xy 426.803319 -141.49807) (xy 426.787251 -141.551477) (xy 426.763579 -141.601974)
			(xy 426.732806 -141.648487) (xy 426.695589 -141.690024) (xy 426.652721 -141.725699) (xy 426.605115 -141.754753)
			(xy 426.553786 -141.776565) (xy 426.499829 -141.790671) (xy 426.444392 -141.796771) (xy 426.388658 -141.794734)
			(xy 426.333815 -141.784604) (xy 426.281031 -141.766597) (xy 426.231431 -141.741096) (xy 426.186073 -141.708645)
			(xy 426.145924 -141.669936) (xy 426.111838 -141.625793) (xy 426.084542 -141.577158) (xy 426.064619 -141.525067)
			(xy 426.052493 -141.47063) (xy 426.048422 -141.415008) (xy 423.406316 -141.415008) (xy 423.406316 -141.683994)
			(xy 423.405725 -141.708996) (xy 423.395931 -141.758033) (xy 423.376759 -141.804216) (xy 423.348945 -141.845772)
			(xy 423.33164 -141.863826) (xy 421.302434 -143.893032) (xy 421.292256 -143.903999) (xy 421.278196 -143.930393)
			(xy 421.272383 -143.959728) (xy 421.275315 -143.989489) (xy 421.286742 -144.017125) (xy 421.305684 -144.040267)
			(xy 421.330517 -144.056931) (xy 421.359111 -144.065688) (xy 421.374062 -144.06626) (xy 421.73525 -144.06626)
			(xy 422.082468 -143.719296) (xy 422.10441 -143.698039) (xy 422.153085 -143.661122) (xy 422.206352 -143.631209)
			(xy 422.26321 -143.608862) (xy 422.29278 -143.601186) (xy 422.318425 -143.595392) (xy 422.370632 -143.589154)
			(xy 422.39692 -143.58874) (xy 426.4406 -143.58874) (xy 426.46689 -143.589126) (xy 426.519099 -143.595369)
			(xy 426.54474 -143.601186) (xy 426.574316 -143.608846) (xy 426.631181 -143.631181) (xy 426.68445 -143.661097)
			(xy 426.733118 -143.698029) (xy 426.755052 -143.719296) (xy 426.824679 -143.788892) (xy 427.194218 -143.788892)
			(xy 427.194673 -143.762513) (xy 427.201927 -143.710255) (xy 427.21631 -143.659495) (xy 427.237546 -143.6112)
			(xy 427.265233 -143.566289) (xy 427.298841 -143.525621) (xy 427.33773 -143.489969) (xy 427.381159 -143.460013)
			(xy 427.40453 -143.44777) (xy 427.416899 -143.441083) (xy 427.437636 -143.422108) (xy 427.452403 -143.398191)
			(xy 427.460078 -143.371151) (xy 427.460077 -143.343042) (xy 427.4524 -143.316003) (xy 427.437631 -143.292087)
			(xy 427.416893 -143.273113) (xy 427.40453 -143.266414) (xy 427.38114 -143.254209) (xy 427.337718 -143.224239)
			(xy 427.298835 -143.188577) (xy 427.265232 -143.147902) (xy 427.237548 -143.102988) (xy 427.216311 -143.054691)
			(xy 427.201924 -143.00393) (xy 427.194662 -142.951672) (xy 427.194218 -142.925292) (xy 427.194704 -142.898041)
			(xy 427.20246 -142.844093) (xy 427.217815 -142.791798) (xy 427.240457 -142.742221) (xy 427.269923 -142.696371)
			(xy 427.305614 -142.65518) (xy 427.346805 -142.619489) (xy 427.392655 -142.590023) (xy 427.442232 -142.567381)
			(xy 427.494527 -142.552026) (xy 427.548475 -142.54427) (xy 427.602977 -142.54427) (xy 427.656925 -142.552026)
			(xy 427.70922 -142.567381) (xy 427.758797 -142.590023) (xy 427.804647 -142.619489) (xy 427.845838 -142.65518)
			(xy 427.881529 -142.696371) (xy 427.910995 -142.742221) (xy 427.933637 -142.791798) (xy 427.948992 -142.844093)
			(xy 427.956748 -142.898041) (xy 427.957234 -142.925292) (xy 427.956737 -142.95167) (xy 427.949487 -143.003924)
			(xy 427.935108 -143.054682) (xy 427.913877 -143.102976) (xy 427.886196 -143.147886) (xy 427.852595 -143.188555)
			(xy 427.813712 -143.224209) (xy 427.770289 -143.254169) (xy 427.746922 -143.266414) (xy 427.734572 -143.273128)
			(xy 427.713846 -143.292103) (xy 427.699087 -143.316014) (xy 427.691415 -143.343047) (xy 427.691415 -143.371146)
			(xy 427.699084 -143.398179) (xy 427.713841 -143.422092) (xy 427.734566 -143.441068) (xy 427.746922 -143.44777)
			(xy 427.770294 -143.460009) (xy 427.813717 -143.489972) (xy 427.852602 -143.525628) (xy 427.886208 -143.566298)
			(xy 427.913894 -143.611207) (xy 427.935135 -143.6595) (xy 427.949524 -143.710258) (xy 427.956788 -143.762513)
			(xy 427.957234 -143.788892) (xy 427.956748 -143.816143) (xy 427.948992 -143.870091) (xy 427.933637 -143.922386)
			(xy 427.910995 -143.971963) (xy 427.881529 -144.017813) (xy 427.845838 -144.059004) (xy 427.804647 -144.094695)
			(xy 427.758797 -144.124161) (xy 427.70922 -144.146803) (xy 427.656925 -144.162158) (xy 427.602977 -144.169914)
			(xy 427.548475 -144.169914) (xy 427.494527 -144.162158) (xy 427.442232 -144.146803) (xy 427.392655 -144.124161)
			(xy 427.346805 -144.094695) (xy 427.305614 -144.059004) (xy 427.269923 -144.017813) (xy 427.240457 -143.971963)
			(xy 427.217815 -143.922386) (xy 427.20246 -143.870091) (xy 427.194704 -143.816143) (xy 427.194218 -143.788892)
			(xy 426.824679 -143.788892) (xy 427.31817 -144.28216) (xy 430.32045 -144.28216) (xy 432.655472 -141.947138)
			(xy 432.655472 -140.361162) (xy 432.325272 -140.030708) (xy 432.304012 -140.008768) (xy 432.267089 -139.960094)
			(xy 432.237169 -139.906829) (xy 432.214814 -139.849973) (xy 432.207162 -139.820396) (xy 432.201369 -139.794751)
			(xy 432.195135 -139.742544) (xy 432.194716 -139.716256) (xy 432.195195 -139.687122) (xy 432.202806 -139.629354)
			(xy 432.217892 -139.573073) (xy 432.240195 -139.519243) (xy 432.269333 -139.468784) (xy 432.304807 -139.422561)
			(xy 432.346012 -139.381362) (xy 432.392241 -139.345895) (xy 432.442704 -139.316765) (xy 432.496538 -139.29447)
			(xy 432.552821 -139.279393) (xy 432.61059 -139.271791) (xy 432.639724 -139.271248) (xy 432.666014 -139.271636)
			(xy 432.718222 -139.277881) (xy 432.743864 -139.283694) (xy 432.773439 -139.291356) (xy 432.830302 -139.313693)
			(xy 432.883569 -139.343612) (xy 432.932234 -139.380545) (xy 432.954176 -139.401804) (xy 433.414932 -139.86256)
			(xy 433.436188 -139.884502) (xy 433.473104 -139.933178) (xy 433.503016 -139.986445) (xy 433.525362 -140.043303)
			(xy 433.533042 -140.072872) (xy 433.538837 -140.098517) (xy 433.545074 -140.150724) (xy 433.545488 -140.177012)
			(xy 433.545488 -141.423136) (xy 433.54601 -141.438115) (xy 433.554688 -141.466788) (xy 433.571315 -141.491707)
			(xy 433.594459 -141.510727) (xy 433.622128 -141.522209) (xy 433.651939 -141.525166) (xy 433.681325 -141.519342)
			(xy 433.707754 -141.505239) (xy 433.718716 -141.495018) (xy 433.813712 -141.400022) (xy 433.813712 -139.610338)
			(xy 433.81324 -139.596694) (xy 433.80595 -139.570396) (xy 433.791959 -139.546965) (xy 433.772267 -139.528072)
			(xy 433.748276 -139.515065) (xy 433.721699 -139.508871) (xy 433.708048 -139.508992) (xy 433.69992 -139.5095)
			(xy 433.695094 -139.510008) (xy 433.665884 -139.511024) (xy 433.639595 -139.510622) (xy 433.587388 -139.504378)
			(xy 433.561744 -139.498578) (xy 433.532169 -139.490916) (xy 433.475306 -139.468578) (xy 433.42204 -139.43866)
			(xy 433.373376 -139.401725) (xy 433.351432 -139.380468) (xy 432.478688 -138.507724) (xy 432.457431 -138.485782)
			(xy 432.420516 -138.437106) (xy 432.390604 -138.383838) (xy 432.368259 -138.326981) (xy 432.360578 -138.297412)
			(xy 432.354784 -138.271767) (xy 432.348548 -138.21956) (xy 432.348132 -138.193272) (xy 432.348132 -136.02716)
			(xy 432.348515 -136.000869) (xy 432.35475 -135.948659) (xy 432.360578 -135.92302) (xy 432.36824 -135.893446)
			(xy 432.390579 -135.836583) (xy 432.420498 -135.783317) (xy 432.457432 -135.734652) (xy 432.478688 -135.712708)
			(xy 432.726592 -135.464804) (xy 432.748532 -135.443543) (xy 432.797204 -135.406617) (xy 432.850469 -135.376695)
			(xy 432.907325 -135.354339) (xy 432.936904 -135.346694) (xy 432.962486 -135.340909) (xy 433.014565 -135.334665)
			(xy 433.04079 -135.334248) (xy 433.048664 -135.334502) (xy 433.078295 -135.335486) (xy 433.136917 -135.344332)
			(xy 433.193848 -135.360873) (xy 433.248083 -135.384819) (xy 433.298663 -135.415745) (xy 433.321968 -135.43407)
			(xy 433.321968 -135.434324) (xy 433.329334 -135.440166) (xy 433.359306 -135.450326) (xy 433.391564 -135.443722)
			(xy 433.407561 -135.439817) (xy 433.436067 -135.423369) (xy 433.447444 -135.411464) (xy 433.465638 -135.391663)
			(xy 433.506629 -135.356861) (xy 433.552101 -135.328159) (xy 433.601152 -135.306124) (xy 433.652811 -135.291194)
			(xy 433.706053 -135.283665) (xy 433.73294 -135.283194) (xy 433.760189 -135.283683) (xy 433.793865 -135.288528)
			(xy 435.509922 -135.288528) (xy 435.513993 -135.232906) (xy 435.526119 -135.178469) (xy 435.546042 -135.126378)
			(xy 435.573338 -135.077743) (xy 435.607424 -135.0336) (xy 435.647573 -134.994891) (xy 435.692931 -134.96244)
			(xy 435.742531 -134.936939) (xy 435.795315 -134.918932) (xy 435.850158 -134.908802) (xy 435.905892 -134.906765)
			(xy 435.961329 -134.912865) (xy 436.015286 -134.926971) (xy 436.066615 -134.948783) (xy 436.114221 -134.977837)
			(xy 436.157089 -135.013512) (xy 436.194306 -135.055049) (xy 436.225079 -135.101562) (xy 436.248751 -135.152059)
			(xy 436.264819 -135.205466) (xy 436.272939 -135.260642) (xy 436.273448 -135.288528) (xy 436.272939 -135.316414)
			(xy 436.264819 -135.37159) (xy 436.248751 -135.424997) (xy 436.225079 -135.475494) (xy 436.194306 -135.522007)
			(xy 436.157089 -135.563544) (xy 436.114221 -135.599219) (xy 436.066615 -135.628273) (xy 436.015286 -135.650085)
			(xy 435.961329 -135.664191) (xy 435.905892 -135.670291) (xy 435.850158 -135.668254) (xy 435.795315 -135.658124)
			(xy 435.742531 -135.640117) (xy 435.692931 -135.614616) (xy 435.647573 -135.582165) (xy 435.607424 -135.543456)
			(xy 435.573338 -135.499313) (xy 435.546042 -135.450678) (xy 435.526119 -135.398587) (xy 435.513993 -135.34415)
			(xy 435.509922 -135.288528) (xy 433.793865 -135.288528) (xy 433.814133 -135.291444) (xy 433.866422 -135.306802)
			(xy 433.915995 -135.329446) (xy 433.96184 -135.358913) (xy 434.003025 -135.394605) (xy 434.038712 -135.435794)
			(xy 434.068174 -135.481642) (xy 434.090812 -135.531217) (xy 434.106165 -135.583508) (xy 434.11392 -135.637453)
			(xy 434.114448 -135.664702) (xy 434.113943 -135.692437) (xy 434.105898 -135.747321) (xy 434.089993 -135.800462)
			(xy 434.066562 -135.85074) (xy 434.036099 -135.897097) (xy 433.999246 -135.938556) (xy 433.956779 -135.974242)
			(xy 433.909594 -136.003405) (xy 433.858683 -136.02543) (xy 433.805121 -136.039853) (xy 433.777644 -136.04367)
			(xy 433.75326 -136.046464) (xy 433.73294 -136.046464) (xy 433.70774 -136.046037) (xy 433.657783 -136.039365)
			(xy 433.609137 -136.026184) (xy 433.562645 -136.006723) (xy 433.540662 -135.994394) (xy 433.527587 -135.98824)
			(xy 433.499229 -135.982755) (xy 433.470469 -135.985425) (xy 433.443606 -135.996038) (xy 433.420786 -136.013744)
			(xy 433.411884 -136.025128) (xy 433.398422 -136.044178) (xy 433.388501 -136.057241) (xy 433.367015 -136.08203)
			(xy 433.355496 -136.093708) (xy 433.238148 -136.21131) (xy 433.238148 -136.943957) (xy 448.198123 -136.943957)
			(xy 448.198123 -136.889443) (xy 448.205882 -136.835484) (xy 448.221241 -136.783179) (xy 448.243888 -136.733592)
			(xy 448.273363 -136.687733) (xy 448.309064 -136.646535) (xy 448.350265 -136.610839) (xy 448.396127 -136.581369)
			(xy 448.445716 -136.558727) (xy 448.498023 -136.543373) (xy 448.551983 -136.53562) (xy 448.57924 -136.53516)
			(xy 448.60661 -136.535647) (xy 448.660788 -136.543457) (xy 448.713292 -136.558941) (xy 448.763039 -136.581778)
			(xy 448.809006 -136.6115) (xy 448.829938 -136.62914) (xy 448.841266 -136.638376) (xy 448.867823 -136.650552)
			(xy 448.89674 -136.654725) (xy 448.925657 -136.650552) (xy 448.952214 -136.638376) (xy 448.963542 -136.62914)
			(xy 448.98449 -136.611521) (xy 449.030458 -136.581805) (xy 449.080201 -136.558964) (xy 449.132699 -136.543469)
			(xy 449.186872 -136.535636) (xy 449.21424 -136.53516) (xy 449.241487 -136.535713) (xy 449.295426 -136.543473)
			(xy 449.347711 -136.558831) (xy 449.397279 -136.581472) (xy 449.443121 -136.610937) (xy 449.484303 -136.646626)
			(xy 449.519987 -136.687811) (xy 449.549447 -136.733656) (xy 449.572083 -136.783226) (xy 449.587435 -136.835513)
			(xy 449.59519 -136.889453) (xy 449.59519 -136.943947) (xy 449.587435 -136.997887) (xy 449.572083 -137.050174)
			(xy 449.549447 -137.099744) (xy 449.519987 -137.145589) (xy 449.484303 -137.186774) (xy 449.443121 -137.222463)
			(xy 449.397279 -137.251928) (xy 449.347711 -137.274569) (xy 449.295426 -137.289927) (xy 449.241487 -137.297687)
			(xy 449.21424 -137.298176) (xy 449.18687 -137.297692) (xy 449.132692 -137.28988) (xy 449.080189 -137.274395)
			(xy 449.030441 -137.251557) (xy 448.984474 -137.221836) (xy 448.963542 -137.204196) (xy 448.952214 -137.19496)
			(xy 448.925657 -137.182784) (xy 448.89674 -137.178611) (xy 448.867823 -137.182784) (xy 448.841266 -137.19496)
			(xy 448.829938 -137.204196) (xy 448.809002 -137.22183) (xy 448.76303 -137.251543) (xy 448.713284 -137.27438)
			(xy 448.660784 -137.289872) (xy 448.606609 -137.297701) (xy 448.57924 -137.298176) (xy 448.551983 -137.29778)
			(xy 448.498023 -137.290027) (xy 448.445716 -137.274673) (xy 448.396127 -137.252031) (xy 448.350265 -137.222561)
			(xy 448.309064 -137.186865) (xy 448.273363 -137.145667) (xy 448.243888 -137.099809) (xy 448.221241 -137.050221)
			(xy 448.205882 -136.997916) (xy 448.198123 -136.943957) (xy 433.238148 -136.943957) (xy 433.238148 -138.009122)
			(xy 433.66817 -138.439144) (xy 433.678818 -138.449135) (xy 433.704438 -138.463116) (xy 433.732965 -138.469288)
			(xy 433.762073 -138.467148) (xy 433.789391 -138.456871) (xy 433.812691 -138.439293) (xy 433.830076 -138.415848)
			(xy 433.835556 -138.402314) (xy 433.83581 -138.401298) (xy 433.836064 -138.400536) (xy 433.845627 -138.372959)
			(xy 433.870973 -138.320381) (xy 433.90298 -138.271571) (xy 433.941098 -138.227367) (xy 433.98467 -138.188529)
			(xy 434.032948 -138.155725) (xy 434.058822 -138.142218) (xy 434.071914 -138.133909) (xy 434.092732 -138.110948)
			(xy 434.105719 -138.082808) (xy 434.109684 -138.052069) (xy 434.104263 -138.021554) (xy 434.089954 -137.994062)
			(xy 434.079396 -137.982706) (xy 434.07584 -137.97915) (xy 433.861972 -137.765028) (xy 433.840716 -137.743086)
			(xy 433.803801 -137.694409) (xy 433.77389 -137.641142) (xy 433.751546 -137.584284) (xy 433.743862 -137.554716)
			(xy 433.738068 -137.529071) (xy 433.731831 -137.476864) (xy 433.731416 -137.450576) (xy 433.731894 -137.421441)
			(xy 433.739503 -137.363671) (xy 433.754587 -137.307388) (xy 433.776888 -137.253556) (xy 433.806026 -137.203095)
			(xy 433.8415 -137.156869) (xy 433.882705 -137.115668) (xy 433.928935 -137.080199) (xy 433.979399 -137.051067)
			(xy 434.033234 -137.028771) (xy 434.089518 -137.013693) (xy 434.147289 -137.006091) (xy 434.176424 -137.005568)
			(xy 434.202713 -137.005971) (xy 434.254919 -137.012215) (xy 434.280564 -137.018014) (xy 434.310138 -137.025676)
			(xy 434.367001 -137.048015) (xy 434.420267 -137.077934) (xy 434.468931 -137.114869) (xy 434.490876 -137.136124)
			(xy 435.071012 -137.71626) (xy 435.092269 -137.738202) (xy 435.129187 -137.786877) (xy 435.1591 -137.840144)
			(xy 435.181447 -137.897002) (xy 435.189122 -137.926572) (xy 435.194917 -137.952217) (xy 435.201155 -138.004424)
			(xy 435.201568 -138.030712) (xy 435.201568 -141.697202) (xy 435.201182 -141.723492) (xy 435.194939 -141.775701)
			(xy 435.189122 -141.801342) (xy 435.181462 -141.830918) (xy 435.159127 -141.887783) (xy 435.129212 -141.941052)
			(xy 435.09228 -141.989721) (xy 435.071012 -142.011654) (xy 432.377596 -144.70507) (xy 435.98668 -144.70507)
			(xy 435.990751 -144.649448) (xy 436.002877 -144.595011) (xy 436.0228 -144.54292) (xy 436.050096 -144.494285)
			(xy 436.084182 -144.450142) (xy 436.124331 -144.411433) (xy 436.169689 -144.378982) (xy 436.219289 -144.353481)
			(xy 436.272073 -144.335474) (xy 436.326916 -144.325344) (xy 436.38265 -144.323307) (xy 436.438087 -144.329407)
			(xy 436.492044 -144.343513) (xy 436.543373 -144.365325) (xy 436.590979 -144.394379) (xy 436.633847 -144.430054)
			(xy 436.671064 -144.471591) (xy 436.701837 -144.518104) (xy 436.725509 -144.568601) (xy 436.741577 -144.622008)
			(xy 436.749697 -144.677184) (xy 436.750206 -144.70507) (xy 436.749697 -144.732956) (xy 436.741577 -144.788132)
			(xy 436.725509 -144.841539) (xy 436.701837 -144.892036) (xy 436.671064 -144.938549) (xy 436.633847 -144.980086)
			(xy 436.590979 -145.015761) (xy 436.543373 -145.044815) (xy 436.492044 -145.066627) (xy 436.438087 -145.080733)
			(xy 436.38265 -145.086833) (xy 436.326916 -145.084796) (xy 436.272073 -145.074666) (xy 436.219289 -145.056659)
			(xy 436.169689 -145.031158) (xy 436.124331 -144.998707) (xy 436.084182 -144.959998) (xy 436.050096 -144.915855)
			(xy 436.0228 -144.86722) (xy 436.002877 -144.815129) (xy 435.990751 -144.760692) (xy 435.98668 -144.70507)
			(xy 432.377596 -144.70507) (xy 431.177446 -145.90522) (xy 431.155504 -145.926477) (xy 431.106829 -145.963395)
			(xy 431.053562 -145.993308) (xy 430.996704 -146.015655) (xy 430.967134 -146.02333) (xy 430.941489 -146.029125)
			(xy 430.889282 -146.035364) (xy 430.862994 -146.035776) (xy 426.466762 -146.035776) (xy 426.456772 -146.036267)
			(xy 426.43831 -146.043912) (xy 426.424167 -146.058028) (xy 426.416487 -146.076474) (xy 426.416433 -146.096456)
			(xy 426.424015 -146.114943) (xy 426.430694 -146.12239) (xy 426.440092 -146.131788) (xy 426.462698 -146.15414)
			(xy 448.994276 -146.15414) (xy 449.026369 -146.154604) (xy 449.09015 -146.161818) (xy 449.152723 -146.176123)
			(xy 449.213302 -146.19734) (xy 449.271127 -146.225203) (xy 449.325471 -146.259361) (xy 449.375651 -146.299386)
			(xy 449.398644 -146.32178) (xy 452.961248 -149.884384) (xy 452.983647 -149.907376) (xy 453.023691 -149.957546)
			(xy 453.057865 -150.011885) (xy 453.085739 -150.06971) (xy 453.106961 -150.130292) (xy 453.121264 -150.19287)
			(xy 453.12847 -150.256656) (xy 453.128888 -150.288752) (xy 453.128888 -150.556468) (xy 453.128389 -150.591039)
			(xy 453.120058 -150.659676) (xy 453.103514 -150.726809) (xy 453.078999 -150.791458) (xy 453.046869 -150.85268)
			(xy 453.007594 -150.909583) (xy 452.961745 -150.961337) (xy 452.909993 -151.007186) (xy 452.85309 -151.046463)
			(xy 452.791869 -151.078594) (xy 452.72722 -151.103111) (xy 452.660088 -151.119656) (xy 452.591451 -151.127988)
			(xy 452.55688 -151.128476) (xy 452.521688 -151.127935) (xy 452.451836 -151.119293) (xy 452.383574 -151.102143)
			(xy 452.317933 -151.076742) (xy 452.255906 -151.043477) (xy 452.198431 -151.00285) (xy 452.146378 -150.955475)
			(xy 452.100534 -150.902068) (xy 452.061591 -150.843439) (xy 452.03014 -150.780472) (xy 452.017892 -150.747476)
			(xy 452.011848 -150.733417) (xy 451.992789 -150.709492) (xy 451.967502 -150.69228) (xy 451.938254 -150.683324)
			(xy 451.907665 -150.683427) (xy 451.892924 -150.687532) (xy 451.862444 -150.6982) (xy 451.826376 -150.709072)
			(xy 451.752217 -150.722322) (xy 451.714616 -150.724616) (xy 451.507098 -150.724616) (xy 451.465696 -150.723092)
			(xy 451.452816 -150.748627) (xy 451.42016 -150.795575) (xy 451.380423 -150.836703) (xy 451.334626 -150.870954)
			(xy 451.283946 -150.89745) (xy 451.229684 -150.915508) (xy 451.173234 -150.924667) (xy 451.14464 -150.925276)
			(xy 451.116654 -150.924758) (xy 451.061369 -150.916007) (xy 451.008134 -150.898715) (xy 450.958261 -150.873306)
			(xy 450.912977 -150.840408) (xy 450.873398 -150.800829) (xy 450.840498 -150.755546) (xy 450.815088 -150.705673)
			(xy 450.797794 -150.652439) (xy 450.789042 -150.597154) (xy 450.788532 -150.569168) (xy 450.788532 -150.563072)
			(xy 450.789411 -150.537756) (xy 450.797442 -150.487742) (xy 450.812471 -150.439368) (xy 450.834195 -150.393609)
			(xy 450.862178 -150.351385) (xy 450.878702 -150.332186) (xy 450.413628 -149.867112) (xy 448.479418 -147.933156)
			(xy 425.962318 -147.933156) (xy 425.930225 -147.932691) (xy 425.866444 -147.925477) (xy 425.803872 -147.911172)
			(xy 425.743293 -147.889954) (xy 425.685469 -147.86209) (xy 425.631126 -147.827932) (xy 425.580947 -147.787906)
			(xy 425.55795 -147.765516) (xy 425.23537 -147.442936) (xy 410.18968 -147.442936) (xy 410.18968 -150.423949)
			(xy 420.30348 -150.423949) (xy 420.30348 -150.369451) (xy 420.311235 -150.315508) (xy 420.326587 -150.263217)
			(xy 420.349225 -150.213643) (xy 420.378687 -150.167796) (xy 420.414373 -150.126607) (xy 420.455557 -150.090915)
			(xy 420.501401 -150.061448) (xy 420.550972 -150.038804) (xy 420.603261 -150.023445) (xy 420.657203 -150.015683)
			(xy 420.684452 -150.015194) (xy 420.711821 -150.01569) (xy 420.765999 -150.023501) (xy 420.818502 -150.038983)
			(xy 420.868249 -150.061818) (xy 420.914217 -150.091536) (xy 420.93515 -150.109174) (xy 420.946478 -150.11841)
			(xy 420.973035 -150.130586) (xy 421.001952 -150.134759) (xy 421.030869 -150.130586) (xy 421.057426 -150.11841)
			(xy 421.068754 -150.109174) (xy 421.089687 -150.091533) (xy 421.135655 -150.061809) (xy 421.185401 -150.038963)
			(xy 421.237903 -150.023467) (xy 421.292081 -150.015638) (xy 421.346823 -150.015638) (xy 421.401001 -150.023467)
			(xy 421.453503 -150.038963) (xy 421.503249 -150.061809) (xy 421.549217 -150.091533) (xy 421.57015 -150.109174)
			(xy 421.581478 -150.11841) (xy 421.608035 -150.130586) (xy 421.636952 -150.134759) (xy 421.665869 -150.130586)
			(xy 421.692426 -150.11841) (xy 421.703754 -150.109174) (xy 421.724689 -150.091539) (xy 421.770662 -150.061827)
			(xy 421.820408 -150.038991) (xy 421.872908 -150.023499) (xy 421.927083 -150.015669) (xy 421.954452 -150.015194)
			(xy 421.981707 -150.01565) (xy 422.035664 -150.023402) (xy 422.087968 -150.038753) (xy 422.137554 -150.061393)
			(xy 422.183413 -150.09086) (xy 422.224612 -150.126554) (xy 422.260311 -150.167748) (xy 422.289784 -150.213604)
			(xy 422.31243 -150.263187) (xy 422.327788 -150.315489) (xy 422.335547 -150.369445) (xy 422.335547 -150.423955)
			(xy 422.327788 -150.477911) (xy 422.31243 -150.530213) (xy 422.289784 -150.579796) (xy 422.260311 -150.625652)
			(xy 422.224612 -150.666846) (xy 422.183413 -150.70254) (xy 422.137554 -150.732007) (xy 422.087968 -150.754647)
			(xy 422.035664 -150.769998) (xy 421.981707 -150.77775) (xy 421.954452 -150.77821) (xy 421.927083 -150.777711)
			(xy 421.872905 -150.769901) (xy 421.820403 -150.754419) (xy 421.770655 -150.731585) (xy 421.724687 -150.701868)
			(xy 421.703754 -150.68423) (xy 421.692426 -150.674994) (xy 421.665869 -150.662818) (xy 421.636952 -150.658645)
			(xy 421.608035 -150.662818) (xy 421.581478 -150.674994) (xy 421.57015 -150.68423) (xy 421.549217 -150.701871)
			(xy 421.503249 -150.731595) (xy 421.453503 -150.754441) (xy 421.401001 -150.769937) (xy 421.346823 -150.777766)
			(xy 421.292081 -150.777766) (xy 421.237903 -150.769937) (xy 421.185401 -150.754441) (xy 421.135655 -150.731595)
			(xy 421.089687 -150.701871) (xy 421.068754 -150.68423) (xy 421.057426 -150.674994) (xy 421.030869 -150.662818)
			(xy 421.001952 -150.658645) (xy 420.973035 -150.662818) (xy 420.946478 -150.674994) (xy 420.93515 -150.68423)
			(xy 420.914214 -150.701864) (xy 420.868242 -150.731575) (xy 420.818495 -150.754412) (xy 420.765996 -150.769904)
			(xy 420.711821 -150.777735) (xy 420.684452 -150.77821) (xy 420.657203 -150.777717) (xy 420.603261 -150.769955)
			(xy 420.550972 -150.754596) (xy 420.501401 -150.731952) (xy 420.455557 -150.702485) (xy 420.414373 -150.666793)
			(xy 420.378687 -150.625604) (xy 420.349225 -150.579757) (xy 420.326587 -150.530183) (xy 420.311235 -150.477892)
			(xy 420.30348 -150.423949) (xy 410.18968 -150.423949) (xy 410.18968 -151.116284) (xy 418.675564 -151.116284)
			(xy 418.679635 -151.060662) (xy 418.691761 -151.006225) (xy 418.711684 -150.954134) (xy 418.73898 -150.905499)
			(xy 418.773066 -150.861356) (xy 418.813215 -150.822647) (xy 418.858573 -150.790196) (xy 418.908173 -150.764695)
			(xy 418.960957 -150.746688) (xy 419.0158 -150.736558) (xy 419.071534 -150.734521) (xy 419.126971 -150.740621)
			(xy 419.180928 -150.754727) (xy 419.232257 -150.776539) (xy 419.279863 -150.805593) (xy 419.322731 -150.841268)
			(xy 419.359948 -150.882805) (xy 419.390721 -150.929318) (xy 419.414393 -150.979815) (xy 419.430461 -151.033222)
			(xy 419.438581 -151.088398) (xy 419.43909 -151.116284) (xy 419.439044 -151.118824) (xy 419.681658 -151.118824)
			(xy 419.685729 -151.063202) (xy 419.697855 -151.008765) (xy 419.717778 -150.956674) (xy 419.745074 -150.908039)
			(xy 419.77916 -150.863896) (xy 419.819309 -150.825187) (xy 419.864667 -150.792736) (xy 419.914267 -150.767235)
			(xy 419.967051 -150.749228) (xy 420.021894 -150.739098) (xy 420.077628 -150.737061) (xy 420.133065 -150.743161)
			(xy 420.187022 -150.757267) (xy 420.238351 -150.779079) (xy 420.285957 -150.808133) (xy 420.328825 -150.843808)
			(xy 420.366042 -150.885345) (xy 420.396815 -150.931858) (xy 420.420487 -150.982355) (xy 420.431436 -151.018748)
			(xy 423.976292 -151.018748) (xy 423.976778 -150.991497) (xy 423.984534 -150.937549) (xy 423.999889 -150.885254)
			(xy 424.022531 -150.835677) (xy 424.051997 -150.789827) (xy 424.087688 -150.748636) (xy 424.128879 -150.712945)
			(xy 424.174729 -150.683479) (xy 424.224306 -150.660837) (xy 424.276601 -150.645482) (xy 424.330549 -150.637726)
			(xy 424.385051 -150.637726) (xy 424.438999 -150.645482) (xy 424.491294 -150.660837) (xy 424.540871 -150.683479)
			(xy 424.586721 -150.712945) (xy 424.627912 -150.748636) (xy 424.663603 -150.789827) (xy 424.693069 -150.835677)
			(xy 424.715711 -150.885254) (xy 424.731066 -150.937549) (xy 424.738822 -150.991497) (xy 424.739308 -151.018748)
			(xy 424.739308 -151.019002) (xy 424.739877 -151.034449) (xy 424.749157 -151.063917) (xy 424.766809 -151.089273)
			(xy 424.791224 -151.108204) (xy 424.820177 -151.118986) (xy 424.835574 -151.120348) (xy 424.864452 -151.122457)
			(xy 424.921128 -151.134291) (xy 424.975366 -151.154551) (xy 425.025922 -151.182773) (xy 425.071634 -151.218307)
			(xy 425.111453 -151.26034) (xy 425.144465 -151.307905) (xy 425.169913 -151.359911) (xy 425.187213 -151.415165)
			(xy 425.195968 -151.472399) (xy 425.196508 -151.501348) (xy 425.196022 -151.528599) (xy 425.188266 -151.582547)
			(xy 425.172911 -151.634842) (xy 425.150269 -151.684419) (xy 425.120803 -151.730269) (xy 425.085112 -151.77146)
			(xy 425.043921 -151.807151) (xy 424.998071 -151.836617) (xy 424.948494 -151.859259) (xy 424.896199 -151.874614)
			(xy 424.842251 -151.88237) (xy 424.787749 -151.88237) (xy 424.733801 -151.874614) (xy 424.681506 -151.859259)
			(xy 424.631929 -151.836617) (xy 424.586079 -151.807151) (xy 424.544888 -151.77146) (xy 424.509197 -151.730269)
			(xy 424.479731 -151.684419) (xy 424.457089 -151.634842) (xy 424.441734 -151.582547) (xy 424.433978 -151.528599)
			(xy 424.433492 -151.501348) (xy 424.433492 -151.501094) (xy 424.432927 -151.485647) (xy 424.423646 -151.456178)
			(xy 424.405993 -151.430823) (xy 424.381577 -151.411891) (xy 424.352623 -151.40111) (xy 424.337226 -151.399748)
			(xy 424.308348 -151.397643) (xy 424.251671 -151.385809) (xy 424.197432 -151.365548) (xy 424.146877 -151.337326)
			(xy 424.101165 -151.301791) (xy 424.061346 -151.259758) (xy 424.028333 -151.212193) (xy 424.002885 -151.160186)
			(xy 423.985586 -151.104931) (xy 423.976832 -151.047698) (xy 423.976292 -151.018748) (xy 420.431436 -151.018748)
			(xy 420.436555 -151.035762) (xy 420.444675 -151.090938) (xy 420.445184 -151.118824) (xy 420.444675 -151.14671)
			(xy 420.436555 -151.201886) (xy 420.420487 -151.255293) (xy 420.396815 -151.30579) (xy 420.366042 -151.352303)
			(xy 420.328825 -151.39384) (xy 420.285957 -151.429515) (xy 420.238351 -151.458569) (xy 420.187022 -151.480381)
			(xy 420.133065 -151.494487) (xy 420.077628 -151.500587) (xy 420.021894 -151.49855) (xy 419.967051 -151.48842)
			(xy 419.914267 -151.470413) (xy 419.864667 -151.444912) (xy 419.819309 -151.412461) (xy 419.77916 -151.373752)
			(xy 419.745074 -151.329609) (xy 419.717778 -151.280974) (xy 419.697855 -151.228883) (xy 419.685729 -151.174446)
			(xy 419.681658 -151.118824) (xy 419.439044 -151.118824) (xy 419.438581 -151.14417) (xy 419.430461 -151.199346)
			(xy 419.414393 -151.252753) (xy 419.390721 -151.30325) (xy 419.359948 -151.349763) (xy 419.322731 -151.3913)
			(xy 419.279863 -151.426975) (xy 419.232257 -151.456029) (xy 419.180928 -151.477841) (xy 419.126971 -151.491947)
			(xy 419.071534 -151.498047) (xy 419.0158 -151.49601) (xy 418.960957 -151.48588) (xy 418.908173 -151.467873)
			(xy 418.858573 -151.442372) (xy 418.813215 -151.409921) (xy 418.773066 -151.371212) (xy 418.73898 -151.327069)
			(xy 418.711684 -151.278434) (xy 418.691761 -151.226343) (xy 418.679635 -151.171906) (xy 418.675564 -151.116284)
			(xy 410.18968 -151.116284) (xy 410.18968 -152.03297) (xy 418.678358 -152.03297) (xy 418.682429 -151.977348)
			(xy 418.694555 -151.922911) (xy 418.714478 -151.87082) (xy 418.741774 -151.822185) (xy 418.77586 -151.778042)
			(xy 418.816009 -151.739333) (xy 418.861367 -151.706882) (xy 418.910967 -151.681381) (xy 418.963751 -151.663374)
			(xy 419.018594 -151.653244) (xy 419.074328 -151.651207) (xy 419.129765 -151.657307) (xy 419.183722 -151.671413)
			(xy 419.235051 -151.693225) (xy 419.282657 -151.722279) (xy 419.325525 -151.757954) (xy 419.362742 -151.799491)
			(xy 419.393515 -151.846004) (xy 419.417187 -151.896501) (xy 419.433255 -151.949908) (xy 419.441375 -152.005084)
			(xy 419.441884 -152.03297) (xy 419.441787 -152.038304) (xy 419.676578 -152.038304) (xy 419.680649 -151.982682)
			(xy 419.692775 -151.928245) (xy 419.712698 -151.876154) (xy 419.739994 -151.827519) (xy 419.77408 -151.783376)
			(xy 419.814229 -151.744667) (xy 419.859587 -151.712216) (xy 419.909187 -151.686715) (xy 419.961971 -151.668708)
			(xy 420.016814 -151.658578) (xy 420.072548 -151.656541) (xy 420.127985 -151.662641) (xy 420.181942 -151.676747)
			(xy 420.233271 -151.698559) (xy 420.280877 -151.727613) (xy 420.323745 -151.763288) (xy 420.360962 -151.804825)
			(xy 420.391735 -151.851338) (xy 420.415407 -151.901835) (xy 420.431475 -151.955242) (xy 420.439595 -152.010418)
			(xy 420.440104 -152.038304) (xy 420.439595 -152.06619) (xy 420.431475 -152.121366) (xy 420.415407 -152.174773)
			(xy 420.391735 -152.22527) (xy 420.360962 -152.271783) (xy 420.323745 -152.31332) (xy 420.280877 -152.348995)
			(xy 420.233271 -152.378049) (xy 420.181942 -152.399861) (xy 420.127985 -152.413967) (xy 420.072548 -152.420067)
			(xy 420.016814 -152.41803) (xy 419.961971 -152.4079) (xy 419.909187 -152.389893) (xy 419.859587 -152.364392)
			(xy 419.814229 -152.331941) (xy 419.77408 -152.293232) (xy 419.739994 -152.249089) (xy 419.712698 -152.200454)
			(xy 419.692775 -152.148363) (xy 419.680649 -152.093926) (xy 419.676578 -152.038304) (xy 419.441787 -152.038304)
			(xy 419.441375 -152.060856) (xy 419.433255 -152.116032) (xy 419.417187 -152.169439) (xy 419.393515 -152.219936)
			(xy 419.362742 -152.266449) (xy 419.325525 -152.307986) (xy 419.282657 -152.343661) (xy 419.235051 -152.372715)
			(xy 419.183722 -152.394527) (xy 419.129765 -152.408633) (xy 419.074328 -152.414733) (xy 419.018594 -152.412696)
			(xy 418.963751 -152.402566) (xy 418.910967 -152.384559) (xy 418.861367 -152.359058) (xy 418.816009 -152.326607)
			(xy 418.77586 -152.287898) (xy 418.741774 -152.243755) (xy 418.714478 -152.19512) (xy 418.694555 -152.143029)
			(xy 418.682429 -152.088592) (xy 418.678358 -152.03297) (xy 410.18968 -152.03297) (xy 410.18968 -152.977342)
			(xy 421.425622 -152.977342) (xy 421.429693 -152.92172) (xy 421.441819 -152.867283) (xy 421.461742 -152.815192)
			(xy 421.489038 -152.766557) (xy 421.523124 -152.722414) (xy 421.563273 -152.683705) (xy 421.608631 -152.651254)
			(xy 421.658231 -152.625753) (xy 421.711015 -152.607746) (xy 421.765858 -152.597616) (xy 421.821592 -152.595579)
			(xy 421.877029 -152.601679) (xy 421.930986 -152.615785) (xy 421.982315 -152.637597) (xy 422.029921 -152.666651)
			(xy 422.072789 -152.702326) (xy 422.110006 -152.743863) (xy 422.140779 -152.790376) (xy 422.164451 -152.840873)
			(xy 422.180519 -152.89428) (xy 422.188639 -152.949456) (xy 422.188768 -152.956514) (xy 422.32402 -152.956514)
			(xy 422.328091 -152.900892) (xy 422.340217 -152.846455) (xy 422.36014 -152.794364) (xy 422.387436 -152.745729)
			(xy 422.421522 -152.701586) (xy 422.461671 -152.662877) (xy 422.507029 -152.630426) (xy 422.556629 -152.604925)
			(xy 422.609413 -152.586918) (xy 422.664256 -152.576788) (xy 422.71999 -152.574751) (xy 422.775427 -152.580851)
			(xy 422.829384 -152.594957) (xy 422.880713 -152.616769) (xy 422.928319 -152.645823) (xy 422.971187 -152.681498)
			(xy 423.008404 -152.723035) (xy 423.039177 -152.769548) (xy 423.062849 -152.820045) (xy 423.078917 -152.873452)
			(xy 423.087037 -152.928628) (xy 423.087546 -152.956514) (xy 423.087037 -152.9844) (xy 423.078917 -153.039576)
			(xy 423.062849 -153.092983) (xy 423.039177 -153.14348) (xy 423.008404 -153.189993) (xy 422.971187 -153.23153)
			(xy 422.928319 -153.267205) (xy 422.880713 -153.296259) (xy 422.829384 -153.318071) (xy 422.775427 -153.332177)
			(xy 422.71999 -153.338277) (xy 422.664256 -153.33624) (xy 422.609413 -153.32611) (xy 422.556629 -153.308103)
			(xy 422.507029 -153.282602) (xy 422.461671 -153.250151) (xy 422.421522 -153.211442) (xy 422.387436 -153.167299)
			(xy 422.36014 -153.118664) (xy 422.340217 -153.066573) (xy 422.328091 -153.012136) (xy 422.32402 -152.956514)
			(xy 422.188768 -152.956514) (xy 422.189148 -152.977342) (xy 422.188639 -153.005228) (xy 422.180519 -153.060404)
			(xy 422.164451 -153.113811) (xy 422.140779 -153.164308) (xy 422.110006 -153.210821) (xy 422.072789 -153.252358)
			(xy 422.029921 -153.288033) (xy 421.982315 -153.317087) (xy 421.930986 -153.338899) (xy 421.877029 -153.353005)
			(xy 421.821592 -153.359105) (xy 421.765858 -153.357068) (xy 421.711015 -153.346938) (xy 421.658231 -153.328931)
			(xy 421.608631 -153.30343) (xy 421.563273 -153.270979) (xy 421.523124 -153.23227) (xy 421.489038 -153.188127)
			(xy 421.461742 -153.139492) (xy 421.441819 -153.087401) (xy 421.429693 -153.032964) (xy 421.425622 -152.977342)
			(xy 410.18968 -152.977342) (xy 410.18968 -153.54046) (xy 423.60037 -153.54046) (xy 423.604441 -153.484838)
			(xy 423.616567 -153.430401) (xy 423.63649 -153.37831) (xy 423.663786 -153.329675) (xy 423.697872 -153.285532)
			(xy 423.738021 -153.246823) (xy 423.783379 -153.214372) (xy 423.832979 -153.188871) (xy 423.885763 -153.170864)
			(xy 423.940606 -153.160734) (xy 423.99634 -153.158697) (xy 424.051777 -153.164797) (xy 424.105734 -153.178903)
			(xy 424.157063 -153.200715) (xy 424.204669 -153.229769) (xy 424.247537 -153.265444) (xy 424.284754 -153.306981)
			(xy 424.315527 -153.353494) (xy 424.339199 -153.403991) (xy 424.355267 -153.457398) (xy 424.363387 -153.512574)
			(xy 424.363896 -153.54046) (xy 424.363387 -153.568346) (xy 424.355267 -153.623522) (xy 424.339199 -153.676929)
			(xy 424.315527 -153.727426) (xy 424.284754 -153.773939) (xy 424.283891 -153.774902) (xy 436.385725 -153.774902)
			(xy 436.389718 -153.565161) (xy 436.401694 -153.355724) (xy 436.421635 -153.146895) (xy 436.449512 -152.938976)
			(xy 436.485284 -152.732269) (xy 436.528899 -152.527074) (xy 436.580295 -152.323689) (xy 436.639397 -152.122407)
			(xy 436.706119 -151.923521) (xy 436.780364 -151.72732) (xy 436.862024 -151.534088) (xy 436.950982 -151.344104)
			(xy 437.047109 -151.157645) (xy 437.150264 -150.974981) (xy 437.260299 -150.796376) (xy 437.377053 -150.62209)
			(xy 437.500358 -150.452375) (xy 437.630035 -150.287477) (xy 437.765896 -150.127636) (xy 437.907743 -149.973083)
			(xy 438.055372 -149.824043) (xy 438.208567 -149.68073) (xy 438.367108 -149.543354) (xy 438.530763 -149.412113)
			(xy 438.699297 -149.287198) (xy 438.872463 -149.16879) (xy 439.050013 -149.05706) (xy 439.231687 -148.95217)
			(xy 439.417222 -148.854273) (xy 439.60635 -148.763511) (xy 439.798797 -148.680014) (xy 439.994282 -148.603904)
			(xy 440.192524 -148.535292) (xy 440.393234 -148.474277) (xy 440.596121 -148.420948) (xy 440.800891 -148.375381)
			(xy 441.007248 -148.337642) (xy 441.214892 -148.307788) (xy 441.423522 -148.28586) (xy 441.632835 -148.271891)
			(xy 441.842529 -148.2659) (xy 442.052298 -148.267897) (xy 442.26184 -148.277879) (xy 442.47085 -148.295831)
			(xy 442.679024 -148.321727) (xy 442.886062 -148.355529) (xy 443.091663 -148.397189) (xy 443.295529 -148.446647)
			(xy 443.497364 -148.50383) (xy 443.696876 -148.568655) (xy 443.893775 -148.641029) (xy 444.087776 -148.720846)
			(xy 444.278598 -148.807992) (xy 444.465964 -148.902339) (xy 444.649602 -149.00375) (xy 444.829246 -149.11208)
			(xy 445.004636 -149.22717) (xy 445.175517 -149.348854) (xy 445.341641 -149.476955) (xy 445.502768 -149.611288)
			(xy 445.658665 -149.751657) (xy 445.809104 -149.89786) (xy 445.953868 -150.049684) (xy 446.092747 -150.20691)
			(xy 446.22554 -150.369309) (xy 446.352054 -150.536645) (xy 446.472106 -150.708677) (xy 446.585521 -150.885154)
			(xy 446.692135 -151.065822) (xy 446.791794 -151.250417) (xy 446.884353 -151.438672) (xy 446.969678 -151.630315)
			(xy 447.047645 -151.825067) (xy 447.118141 -152.022647) (xy 447.181064 -152.222766) (xy 447.236323 -152.425137)
			(xy 447.283837 -152.629464) (xy 447.323538 -152.835452) (xy 447.355368 -153.042803) (xy 447.379281 -153.251214)
			(xy 447.395242 -153.460385) (xy 447.403229 -153.670012) (xy 447.403728 -153.774902) (xy 447.403229 -153.879792)
			(xy 447.395242 -154.089419) (xy 447.379281 -154.29859) (xy 447.355368 -154.507001) (xy 447.323538 -154.714352)
			(xy 447.283837 -154.92034) (xy 447.236323 -155.124667) (xy 447.181064 -155.327038) (xy 447.118141 -155.527157)
			(xy 447.047645 -155.724737) (xy 446.969678 -155.919489) (xy 446.884353 -156.111132) (xy 446.791794 -156.299387)
			(xy 446.692135 -156.483982) (xy 446.585521 -156.66465) (xy 446.472106 -156.841127) (xy 446.352054 -157.013159)
			(xy 446.22554 -157.180495) (xy 446.092747 -157.342894) (xy 445.953868 -157.50012) (xy 445.809104 -157.651944)
			(xy 445.658665 -157.798147) (xy 445.502768 -157.938516) (xy 445.341641 -158.072849) (xy 445.175517 -158.20095)
			(xy 445.004636 -158.322634) (xy 444.829246 -158.437724) (xy 444.649602 -158.546054) (xy 444.465964 -158.647465)
			(xy 444.278598 -158.741812) (xy 444.087776 -158.828958) (xy 443.893775 -158.908775) (xy 443.696876 -158.981149)
			(xy 443.497364 -159.045974) (xy 443.295529 -159.103157) (xy 443.091663 -159.152615) (xy 442.886062 -159.194275)
			(xy 442.679024 -159.228077) (xy 442.47085 -159.253973) (xy 442.26184 -159.271925) (xy 442.052298 -159.281907)
			(xy 441.842529 -159.283904) (xy 441.632835 -159.277913) (xy 441.423522 -159.263944) (xy 441.214892 -159.242016)
			(xy 441.007248 -159.212162) (xy 440.800891 -159.174423) (xy 440.596121 -159.128856) (xy 440.393234 -159.075527)
			(xy 440.192524 -159.014512) (xy 439.994282 -158.9459) (xy 439.798797 -158.86979) (xy 439.60635 -158.786293)
			(xy 439.417222 -158.695531) (xy 439.231687 -158.597634) (xy 439.050013 -158.492744) (xy 438.872463 -158.381014)
			(xy 438.699297 -158.262606) (xy 438.530763 -158.137691) (xy 438.367108 -158.00645) (xy 438.208567 -157.869074)
			(xy 438.055372 -157.725761) (xy 437.907743 -157.576721) (xy 437.765896 -157.422168) (xy 437.630035 -157.262327)
			(xy 437.500358 -157.097429) (xy 437.377053 -156.927714) (xy 437.260299 -156.753428) (xy 437.150264 -156.574823)
			(xy 437.047109 -156.392159) (xy 436.950982 -156.2057) (xy 436.862024 -156.015716) (xy 436.780364 -155.822484)
			(xy 436.706119 -155.626283) (xy 436.639397 -155.427397) (xy 436.580295 -155.226115) (xy 436.528899 -155.02273)
			(xy 436.485284 -154.817535) (xy 436.449512 -154.610828) (xy 436.421635 -154.402909) (xy 436.401694 -154.19408)
			(xy 436.389718 -153.984643) (xy 436.385725 -153.774902) (xy 424.283891 -153.774902) (xy 424.247537 -153.815476)
			(xy 424.204669 -153.851151) (xy 424.157063 -153.880205) (xy 424.105734 -153.902017) (xy 424.051777 -153.916123)
			(xy 423.99634 -153.922223) (xy 423.940606 -153.920186) (xy 423.885763 -153.910056) (xy 423.832979 -153.892049)
			(xy 423.783379 -153.866548) (xy 423.738021 -153.834097) (xy 423.697872 -153.795388) (xy 423.663786 -153.751245)
			(xy 423.63649 -153.70261) (xy 423.616567 -153.650519) (xy 423.604441 -153.596082) (xy 423.60037 -153.54046)
			(xy 410.18968 -153.54046) (xy 410.18968 -155.499308) (xy 417.524182 -155.499308) (xy 417.528253 -155.443686)
			(xy 417.540379 -155.389249) (xy 417.560302 -155.337158) (xy 417.587598 -155.288523) (xy 417.621684 -155.24438)
			(xy 417.661833 -155.205671) (xy 417.707191 -155.17322) (xy 417.756791 -155.147719) (xy 417.809575 -155.129712)
			(xy 417.864418 -155.119582) (xy 417.920152 -155.117545) (xy 417.975589 -155.123645) (xy 418.029546 -155.137751)
			(xy 418.080875 -155.159563) (xy 418.128481 -155.188617) (xy 418.162419 -155.21686) (xy 420.484552 -155.21686)
			(xy 420.488623 -155.161238) (xy 420.500749 -155.106801) (xy 420.520672 -155.05471) (xy 420.547968 -155.006075)
			(xy 420.582054 -154.961932) (xy 420.622203 -154.923223) (xy 420.667561 -154.890772) (xy 420.717161 -154.865271)
			(xy 420.769945 -154.847264) (xy 420.824788 -154.837134) (xy 420.880522 -154.835097) (xy 420.935959 -154.841197)
			(xy 420.989916 -154.855303) (xy 421.041245 -154.877115) (xy 421.088851 -154.906169) (xy 421.112505 -154.925854)
			(xy 421.450453 -154.925854) (xy 421.450453 -154.871346) (xy 421.458211 -154.817394) (xy 421.473568 -154.765094)
			(xy 421.496212 -154.715513) (xy 421.525681 -154.669659) (xy 421.561377 -154.628465) (xy 421.602572 -154.592772)
			(xy 421.648427 -154.563304) (xy 421.698009 -154.540662) (xy 421.750309 -154.525307) (xy 421.804262 -154.517552)
			(xy 421.831516 -154.51709) (xy 421.861892 -154.517675) (xy 421.921876 -154.527306) (xy 421.979575 -154.54632)
			(xy 422.033532 -154.574239) (xy 422.082383 -154.610355) (xy 422.104058 -154.631644) (xy 422.113809 -154.640955)
			(xy 422.137082 -154.65455) (xy 422.163099 -154.661592) (xy 422.190051 -154.661592) (xy 422.216068 -154.65455)
			(xy 422.239341 -154.640955) (xy 422.249092 -154.631644) (xy 422.270748 -154.610335) (xy 422.319604 -154.574222)
			(xy 422.373566 -154.546308) (xy 422.43127 -154.527299) (xy 422.491257 -154.517676) (xy 422.521634 -154.51709)
			(xy 422.548884 -154.517582) (xy 422.602827 -154.525342) (xy 422.655118 -154.5407) (xy 422.70469 -154.563343)
			(xy 422.750536 -154.592811) (xy 422.791722 -154.628502) (xy 422.82741 -154.669691) (xy 422.856873 -154.71554)
			(xy 422.879511 -154.765114) (xy 422.894865 -154.817406) (xy 422.90262 -154.87135) (xy 422.90262 -154.92585)
			(xy 422.894865 -154.979794) (xy 422.879511 -155.032086) (xy 422.856873 -155.08166) (xy 422.82741 -155.127509)
			(xy 422.791722 -155.168698) (xy 422.750536 -155.204389) (xy 422.70469 -155.233857) (xy 422.655118 -155.2565)
			(xy 422.602827 -155.271858) (xy 422.548884 -155.279618) (xy 422.521634 -155.280106) (xy 422.491257 -155.279554)
			(xy 422.431272 -155.269915) (xy 422.373572 -155.250893) (xy 422.319615 -155.222967) (xy 422.270766 -155.186844)
			(xy 422.249092 -155.165552) (xy 422.239364 -155.156194) (xy 422.216103 -155.142518) (xy 422.190067 -155.135431)
			(xy 422.163083 -155.135431) (xy 422.137047 -155.142518) (xy 422.113786 -155.156194) (xy 422.104058 -155.165552)
			(xy 422.082379 -155.186837) (xy 422.033529 -155.222953) (xy 421.979573 -155.250871) (xy 421.921874 -155.269886)
			(xy 421.861891 -155.279516) (xy 421.831516 -155.280106) (xy 421.804262 -155.279648) (xy 421.750309 -155.271893)
			(xy 421.698009 -155.256538) (xy 421.648427 -155.233896) (xy 421.602572 -155.204428) (xy 421.561377 -155.168735)
			(xy 421.525681 -155.127541) (xy 421.496212 -155.081687) (xy 421.473568 -155.032106) (xy 421.458211 -154.979806)
			(xy 421.450453 -154.925854) (xy 421.112505 -154.925854) (xy 421.131719 -154.941844) (xy 421.168936 -154.983381)
			(xy 421.199709 -155.029894) (xy 421.223381 -155.080391) (xy 421.239449 -155.133798) (xy 421.247569 -155.188974)
			(xy 421.248078 -155.21686) (xy 421.247569 -155.244746) (xy 421.239449 -155.299922) (xy 421.223381 -155.353329)
			(xy 421.199709 -155.403826) (xy 421.168936 -155.450339) (xy 421.131719 -155.491876) (xy 421.088851 -155.527551)
			(xy 421.041245 -155.556605) (xy 420.989916 -155.578417) (xy 420.935959 -155.592523) (xy 420.880522 -155.598623)
			(xy 420.824788 -155.596586) (xy 420.769945 -155.586456) (xy 420.717161 -155.568449) (xy 420.667561 -155.542948)
			(xy 420.622203 -155.510497) (xy 420.582054 -155.471788) (xy 420.547968 -155.427645) (xy 420.520672 -155.37901)
			(xy 420.500749 -155.326919) (xy 420.488623 -155.272482) (xy 420.484552 -155.21686) (xy 418.162419 -155.21686)
			(xy 418.171349 -155.224292) (xy 418.208566 -155.265829) (xy 418.239339 -155.312342) (xy 418.263011 -155.362839)
			(xy 418.279079 -155.416246) (xy 418.287199 -155.471422) (xy 418.287708 -155.499308) (xy 418.287199 -155.527194)
			(xy 418.279079 -155.58237) (xy 418.263011 -155.635777) (xy 418.239339 -155.686274) (xy 418.208566 -155.732787)
			(xy 418.171349 -155.774324) (xy 418.128481 -155.809999) (xy 418.080875 -155.839053) (xy 418.029546 -155.860865)
			(xy 417.975589 -155.874971) (xy 417.920152 -155.881071) (xy 417.864418 -155.879034) (xy 417.809575 -155.868904)
			(xy 417.756791 -155.850897) (xy 417.707191 -155.825396) (xy 417.661833 -155.792945) (xy 417.621684 -155.754236)
			(xy 417.587598 -155.710093) (xy 417.560302 -155.661458) (xy 417.540379 -155.609367) (xy 417.528253 -155.55493)
			(xy 417.524182 -155.499308) (xy 410.18968 -155.499308) (xy 410.18968 -155.972256) (xy 423.64482 -155.972256)
			(xy 423.648891 -155.916634) (xy 423.661017 -155.862197) (xy 423.68094 -155.810106) (xy 423.708236 -155.761471)
			(xy 423.742322 -155.717328) (xy 423.782471 -155.678619) (xy 423.827829 -155.646168) (xy 423.877429 -155.620667)
			(xy 423.930213 -155.60266) (xy 423.985056 -155.59253) (xy 424.04079 -155.590493) (xy 424.096227 -155.596593)
			(xy 424.150184 -155.610699) (xy 424.201513 -155.632511) (xy 424.249119 -155.661565) (xy 424.291987 -155.69724)
			(xy 424.329204 -155.738777) (xy 424.359977 -155.78529) (xy 424.383649 -155.835787) (xy 424.399717 -155.889194)
			(xy 424.407837 -155.94437) (xy 424.408346 -155.972256) (xy 424.407837 -156.000142) (xy 424.399717 -156.055318)
			(xy 424.383649 -156.108725) (xy 424.359977 -156.159222) (xy 424.329204 -156.205735) (xy 424.291987 -156.247272)
			(xy 424.249119 -156.282947) (xy 424.201513 -156.312001) (xy 424.150184 -156.333813) (xy 424.096227 -156.347919)
			(xy 424.04079 -156.354019) (xy 423.985056 -156.351982) (xy 423.930213 -156.341852) (xy 423.877429 -156.323845)
			(xy 423.827829 -156.298344) (xy 423.782471 -156.265893) (xy 423.742322 -156.227184) (xy 423.708236 -156.183041)
			(xy 423.68094 -156.134406) (xy 423.661017 -156.082315) (xy 423.648891 -156.027878) (xy 423.64482 -155.972256)
			(xy 410.18968 -155.972256) (xy 410.18968 -156.960062) (xy 422.378122 -156.960062) (xy 422.382193 -156.90444)
			(xy 422.394319 -156.850003) (xy 422.414242 -156.797912) (xy 422.441538 -156.749277) (xy 422.475624 -156.705134)
			(xy 422.515773 -156.666425) (xy 422.561131 -156.633974) (xy 422.610731 -156.608473) (xy 422.663515 -156.590466)
			(xy 422.718358 -156.580336) (xy 422.774092 -156.578299) (xy 422.829529 -156.584399) (xy 422.883486 -156.598505)
			(xy 422.934815 -156.620317) (xy 422.982421 -156.649371) (xy 423.025289 -156.685046) (xy 423.062506 -156.726583)
			(xy 423.093279 -156.773096) (xy 423.116951 -156.823593) (xy 423.133019 -156.877) (xy 423.133431 -156.879798)
			(xy 423.523662 -156.879798) (xy 423.527733 -156.824176) (xy 423.539859 -156.769739) (xy 423.559782 -156.717648)
			(xy 423.587078 -156.669013) (xy 423.621164 -156.62487) (xy 423.661313 -156.586161) (xy 423.706671 -156.55371)
			(xy 423.756271 -156.528209) (xy 423.809055 -156.510202) (xy 423.863898 -156.500072) (xy 423.919632 -156.498035)
			(xy 423.975069 -156.504135) (xy 424.029026 -156.518241) (xy 424.080355 -156.540053) (xy 424.127961 -156.569107)
			(xy 424.170829 -156.604782) (xy 424.208046 -156.646319) (xy 424.238819 -156.692832) (xy 424.262491 -156.743329)
			(xy 424.278559 -156.796736) (xy 424.286679 -156.851912) (xy 424.287188 -156.879798) (xy 424.286679 -156.907684)
			(xy 424.278559 -156.96286) (xy 424.262512 -157.016196) (xy 426.587415 -157.016196) (xy 426.591451 -156.932749)
			(xy 426.603523 -156.850081) (xy 426.623516 -156.768964) (xy 426.651245 -156.690155) (xy 426.686451 -156.61439)
			(xy 426.728805 -156.542377) (xy 426.777911 -156.474788) (xy 426.833312 -156.412254) (xy 426.894489 -156.355359)
			(xy 426.960872 -156.304633) (xy 427.03184 -156.260552) (xy 427.106732 -156.223526) (xy 427.184848 -156.1939)
			(xy 427.265458 -156.171952) (xy 427.34781 -156.157887) (xy 427.431136 -156.151835) (xy 427.514656 -156.153854)
			(xy 427.597592 -156.163924) (xy 427.679168 -156.181952) (xy 427.758624 -156.207769) (xy 427.835217 -156.241134)
			(xy 427.908233 -156.281735) (xy 427.976989 -156.329194) (xy 428.040843 -156.383067) (xy 428.0992 -156.442852)
			(xy 428.151515 -156.507989) (xy 428.197298 -156.577872) (xy 428.236123 -156.651847) (xy 428.267628 -156.729224)
			(xy 428.291517 -156.809281) (xy 428.307568 -156.891269) (xy 428.315631 -156.974424) (xy 428.316136 -157.016196)
			(xy 428.315631 -157.057968) (xy 428.307568 -157.141123) (xy 428.291517 -157.223111) (xy 428.267628 -157.303168)
			(xy 428.236123 -157.380545) (xy 428.197298 -157.45452) (xy 428.151515 -157.524403) (xy 428.0992 -157.58954)
			(xy 428.040843 -157.649325) (xy 427.976989 -157.703198) (xy 427.908233 -157.750657) (xy 427.835217 -157.791258)
			(xy 427.758624 -157.824623) (xy 427.679168 -157.85044) (xy 427.597592 -157.868468) (xy 427.514656 -157.878538)
			(xy 427.431136 -157.880557) (xy 427.34781 -157.874505) (xy 427.265458 -157.86044) (xy 427.184848 -157.838492)
			(xy 427.106732 -157.808866) (xy 427.03184 -157.77184) (xy 426.960872 -157.727759) (xy 426.894489 -157.677033)
			(xy 426.833312 -157.620138) (xy 426.777911 -157.557604) (xy 426.728805 -157.490015) (xy 426.686451 -157.418002)
			(xy 426.651245 -157.342237) (xy 426.623516 -157.263428) (xy 426.603523 -157.182311) (xy 426.591451 -157.099643)
			(xy 426.587415 -157.016196) (xy 424.262512 -157.016196) (xy 424.262491 -157.016267) (xy 424.238819 -157.066764)
			(xy 424.208046 -157.113277) (xy 424.170829 -157.154814) (xy 424.127961 -157.190489) (xy 424.080355 -157.219543)
			(xy 424.029026 -157.241355) (xy 423.975069 -157.255461) (xy 423.919632 -157.261561) (xy 423.863898 -157.259524)
			(xy 423.809055 -157.249394) (xy 423.756271 -157.231387) (xy 423.706671 -157.205886) (xy 423.661313 -157.173435)
			(xy 423.621164 -157.134726) (xy 423.587078 -157.090583) (xy 423.559782 -157.041948) (xy 423.539859 -156.989857)
			(xy 423.527733 -156.93542) (xy 423.523662 -156.879798) (xy 423.133431 -156.879798) (xy 423.141139 -156.932176)
			(xy 423.141648 -156.960062) (xy 423.141139 -156.987948) (xy 423.133019 -157.043124) (xy 423.116951 -157.096531)
			(xy 423.093279 -157.147028) (xy 423.062506 -157.193541) (xy 423.025289 -157.235078) (xy 422.982421 -157.270753)
			(xy 422.934815 -157.299807) (xy 422.883486 -157.321619) (xy 422.829529 -157.335725) (xy 422.774092 -157.341825)
			(xy 422.718358 -157.339788) (xy 422.663515 -157.329658) (xy 422.610731 -157.311651) (xy 422.561131 -157.28615)
			(xy 422.515773 -157.253699) (xy 422.475624 -157.21499) (xy 422.441538 -157.170847) (xy 422.414242 -157.122212)
			(xy 422.394319 -157.070121) (xy 422.382193 -157.015684) (xy 422.378122 -156.960062) (xy 410.18968 -156.960062)
			(xy 410.18968 -157.648148) (xy 419.535862 -157.648148) (xy 419.539933 -157.592526) (xy 419.552059 -157.538089)
			(xy 419.571982 -157.485998) (xy 419.599278 -157.437363) (xy 419.633364 -157.39322) (xy 419.673513 -157.354511)
			(xy 419.718871 -157.32206) (xy 419.768471 -157.296559) (xy 419.821255 -157.278552) (xy 419.876098 -157.268422)
			(xy 419.931832 -157.266385) (xy 419.987269 -157.272485) (xy 420.041226 -157.286591) (xy 420.092555 -157.308403)
			(xy 420.140161 -157.337457) (xy 420.183029 -157.373132) (xy 420.220246 -157.414669) (xy 420.251019 -157.461182)
			(xy 420.274691 -157.511679) (xy 420.290759 -157.565086) (xy 420.298879 -157.620262) (xy 420.299388 -157.648148)
			(xy 420.298879 -157.676034) (xy 420.290759 -157.73121) (xy 420.274691 -157.784617) (xy 420.251019 -157.835114)
			(xy 420.220246 -157.881627) (xy 420.183029 -157.923164) (xy 420.140161 -157.958839) (xy 420.092555 -157.987893)
			(xy 420.041226 -158.009705) (xy 419.987269 -158.023811) (xy 419.931832 -158.029911) (xy 419.876098 -158.027874)
			(xy 419.821255 -158.017744) (xy 419.768471 -157.999737) (xy 419.718871 -157.974236) (xy 419.673513 -157.941785)
			(xy 419.633364 -157.903076) (xy 419.599278 -157.858933) (xy 419.571982 -157.810298) (xy 419.552059 -157.758207)
			(xy 419.539933 -157.70377) (xy 419.535862 -157.648148) (xy 410.18968 -157.648148) (xy 410.18968 -161.520378)
			(xy 417.4998 -161.520378) (xy 417.500317 -161.493048) (xy 417.50828 -161.438971) (xy 417.524061 -161.386638)
			(xy 417.547322 -161.337175) (xy 417.577563 -161.291642) (xy 417.614133 -161.251018) (xy 417.656249 -161.216176)
			(xy 417.679378 -161.201608) (xy 417.691578 -161.19365) (xy 417.711251 -161.172189) (xy 417.724061 -161.146045)
			(xy 417.728962 -161.117347) (xy 417.725556 -161.088434) (xy 417.720272 -161.074862) (xy 417.710777 -161.051654)
			(xy 417.697428 -161.00332) (xy 417.690702 -160.95363) (xy 417.6903 -160.928558) (xy 417.690724 -160.903489)
			(xy 417.697474 -160.853806) (xy 417.710806 -160.805471) (xy 417.720272 -160.782254) (xy 417.725563 -160.768687)
			(xy 417.728937 -160.739773) (xy 417.724027 -160.711079) (xy 417.711231 -160.68493) (xy 417.691587 -160.663447)
			(xy 417.679378 -160.655508) (xy 417.656281 -160.640887) (xy 417.61416 -160.60605) (xy 417.57758 -160.565433)
			(xy 417.547327 -160.519907) (xy 417.52405 -160.470451) (xy 417.508247 -160.418124) (xy 417.500259 -160.36405)
			(xy 417.500256 -160.309389) (xy 417.508238 -160.255314) (xy 417.524036 -160.202986) (xy 417.547308 -160.153527)
			(xy 417.577556 -160.107998) (xy 417.614131 -160.067377) (xy 417.656249 -160.032536) (xy 417.679378 -160.017968)
			(xy 417.691605 -160.010048) (xy 417.711279 -159.988577) (xy 417.724084 -159.962423) (xy 417.728979 -159.933716)
			(xy 417.725563 -159.904796) (xy 417.720272 -159.891222) (xy 417.710796 -159.868007) (xy 417.69744 -159.819677)
			(xy 417.690706 -159.769989) (xy 417.6903 -159.744918) (xy 417.690766 -159.718075) (xy 417.698468 -159.664945)
			(xy 417.713716 -159.61347) (xy 417.736193 -159.564717) (xy 417.765435 -159.519694) (xy 417.800836 -159.479334)
			(xy 417.841662 -159.444472) (xy 417.887069 -159.415831) (xy 417.936117 -159.394002) (xy 417.961826 -159.38627)
			(xy 417.976329 -159.38162) (xy 418.0019 -159.365103) (xy 418.021469 -159.341785) (xy 418.033299 -159.313737)
			(xy 418.03634 -159.283448) (xy 418.030322 -159.253608) (xy 418.023548 -159.239966) (xy 418.00892 -159.211818)
			(xy 417.988191 -159.151868) (xy 417.977691 -159.08931) (xy 417.977066 -159.057594) (xy 417.977291 -159.039575)
			(xy 417.980722 -159.0037) (xy 417.983924 -158.985966) (xy 417.986322 -158.970764) (xy 417.982784 -158.940201)
			(xy 417.97031 -158.912077) (xy 417.95003 -158.888941) (xy 417.923782 -158.872889) (xy 417.908994 -158.868618)
			(xy 417.881967 -158.861164) (xy 417.830242 -158.839542) (xy 417.782237 -158.810585) (xy 417.738984 -158.774917)
			(xy 417.701416 -158.733305) (xy 417.670339 -158.686645) (xy 417.646423 -158.63594) (xy 417.630183 -158.582282)
			(xy 417.621967 -158.526825) (xy 417.621466 -158.498794) (xy 417.621972 -158.471544) (xy 417.629729 -158.417598)
			(xy 417.645083 -158.365305) (xy 417.667723 -158.31573) (xy 417.697188 -158.269881) (xy 417.732877 -158.228691)
			(xy 417.774065 -158.193) (xy 417.819912 -158.163533) (xy 417.869487 -158.14089) (xy 417.921779 -158.125533)
			(xy 417.975724 -158.117774) (xy 418.002974 -158.117286) (xy 418.030548 -158.117774) (xy 418.085119 -158.125723)
			(xy 418.137979 -158.141444) (xy 418.188024 -158.16461) (xy 418.234215 -158.194738) (xy 418.275587 -158.231201)
			(xy 418.293804 -158.251906) (xy 418.303702 -158.262804) (xy 418.328352 -158.278879) (xy 418.35656 -158.287263)
			(xy 418.385988 -158.287263) (xy 418.414196 -158.278879) (xy 418.438846 -158.262804) (xy 418.448744 -158.251906)
			(xy 418.466959 -158.2312) (xy 418.50833 -158.194735) (xy 418.55452 -158.164608) (xy 418.604567 -158.141445)
			(xy 418.657428 -158.125729) (xy 418.712 -158.117789) (xy 418.767148 -158.117789) (xy 418.82172 -158.125729)
			(xy 418.874581 -158.141445) (xy 418.924628 -158.164608) (xy 418.970818 -158.194735) (xy 419.012189 -158.2312)
			(xy 419.030404 -158.251906) (xy 419.040302 -158.262804) (xy 419.064952 -158.278879) (xy 419.09316 -158.287263)
			(xy 419.122588 -158.287263) (xy 419.150796 -158.278879) (xy 419.175446 -158.262804) (xy 419.185344 -158.251906)
			(xy 419.203582 -158.23122) (xy 419.244945 -158.194747) (xy 419.291129 -158.164612) (xy 419.341172 -158.141442)
			(xy 419.39403 -158.12572) (xy 419.448601 -158.117775) (xy 419.476174 -158.117286) (xy 419.503426 -158.117779)
			(xy 419.557375 -158.125533) (xy 419.609672 -158.140885) (xy 419.659252 -158.163524) (xy 419.705105 -158.192989)
			(xy 419.746298 -158.22868) (xy 419.781992 -158.269869) (xy 419.81146 -158.31572) (xy 419.834104 -158.365298)
			(xy 419.84946 -158.417593) (xy 419.857218 -158.471542) (xy 419.857682 -158.498794) (xy 419.857167 -158.52665)
			(xy 419.849043 -158.581766) (xy 419.832998 -158.635117) (xy 419.80937 -158.685571) (xy 419.778663 -158.732056)
			(xy 419.741526 -158.773585) (xy 419.69875 -158.809278) (xy 419.651241 -158.838376) (xy 419.600008 -158.860262)
			(xy 419.573202 -158.867856) (xy 419.559077 -158.872105) (xy 419.53393 -158.887501) (xy 419.514215 -158.909425)
			(xy 419.501566 -158.93606) (xy 419.497034 -158.965195) (xy 419.498526 -158.97987) (xy 419.5002 -158.992886)
			(xy 419.501977 -159.019071) (xy 419.502082 -159.032194) (xy 419.501988 -159.046343) (xy 419.499954 -159.074566)
			(xy 419.498018 -159.088582) (xy 419.496394 -159.101927) (xy 419.4995 -159.128623) (xy 419.509476 -159.153579)
			(xy 419.525629 -159.17506) (xy 419.546835 -159.191572) (xy 419.57162 -159.201966) (xy 419.584886 -159.204152)
			(xy 419.612039 -159.208237) (xy 419.664868 -159.223214) (xy 419.715004 -159.245609) (xy 419.761412 -159.274958)
			(xy 419.803135 -159.310656) (xy 419.839311 -159.351965) (xy 419.869192 -159.398033) (xy 419.892162 -159.447908)
			(xy 419.907746 -159.500561) (xy 419.915622 -159.554903) (xy 419.915688 -159.558666) (xy 426.563024 -159.558666)
			(xy 426.563024 -159.47397) (xy 426.571075 -159.389656) (xy 426.587104 -159.30649) (xy 426.610965 -159.225223)
			(xy 426.642444 -159.146593) (xy 426.681255 -159.071312) (xy 426.727045 -159.00006) (xy 426.779401 -158.933484)
			(xy 426.837849 -158.872186) (xy 426.901859 -158.816721) (xy 426.970851 -158.767592) (xy 427.044201 -158.725243)
			(xy 427.121244 -158.690059) (xy 427.201283 -158.662357) (xy 427.283592 -158.642389) (xy 427.367427 -158.630336)
			(xy 427.452028 -158.626306) (xy 427.536629 -158.630336) (xy 427.620464 -158.642389) (xy 427.702773 -158.662357)
			(xy 427.782812 -158.690059) (xy 427.859855 -158.725243) (xy 427.933205 -158.767592) (xy 428.002197 -158.816721)
			(xy 428.066207 -158.872186) (xy 428.124655 -158.933484) (xy 428.177011 -159.00006) (xy 428.222801 -159.071312)
			(xy 428.261612 -159.146593) (xy 428.293091 -159.225223) (xy 428.316952 -159.30649) (xy 428.332981 -159.389656)
			(xy 428.341032 -159.47397) (xy 428.341536 -159.516318) (xy 428.341032 -159.558666) (xy 428.332981 -159.64298)
			(xy 428.316952 -159.726146) (xy 428.293091 -159.807413) (xy 428.261612 -159.886043) (xy 428.222801 -159.961324)
			(xy 428.177011 -160.032576) (xy 428.124655 -160.099152) (xy 428.066207 -160.16045) (xy 428.002197 -160.215915)
			(xy 427.933205 -160.265044) (xy 427.859855 -160.307393) (xy 427.782812 -160.342577) (xy 427.702773 -160.370279)
			(xy 427.620464 -160.390247) (xy 427.536629 -160.4023) (xy 427.452028 -160.406331) (xy 427.367427 -160.4023)
			(xy 427.283592 -160.390247) (xy 427.201283 -160.370279) (xy 427.121244 -160.342577) (xy 427.044201 -160.307393)
			(xy 426.970851 -160.265044) (xy 426.901859 -160.215915) (xy 426.837849 -160.16045) (xy 426.779401 -160.099152)
			(xy 426.727045 -160.032576) (xy 426.681255 -159.961324) (xy 426.642444 -159.886043) (xy 426.610965 -159.807413)
			(xy 426.587104 -159.726146) (xy 426.571075 -159.64298) (xy 426.563024 -159.558666) (xy 419.915688 -159.558666)
			(xy 419.916102 -159.582358) (xy 419.915606 -159.60961) (xy 419.907854 -159.66356) (xy 419.892503 -159.715858)
			(xy 419.869865 -159.765438) (xy 419.840401 -159.811292) (xy 419.804711 -159.852485) (xy 419.763521 -159.888179)
			(xy 419.71767 -159.917648) (xy 419.668092 -159.940291) (xy 419.615795 -159.955647) (xy 419.561846 -159.963403)
			(xy 419.534594 -159.963866) (xy 419.507019 -159.963416) (xy 419.452445 -159.955462) (xy 419.399584 -159.939735)
			(xy 419.349538 -159.916562) (xy 419.303349 -159.886426) (xy 419.261979 -159.849955) (xy 419.243764 -159.829246)
			(xy 419.233866 -159.818348) (xy 419.209216 -159.802273) (xy 419.181008 -159.793889) (xy 419.15158 -159.793889)
			(xy 419.123372 -159.802273) (xy 419.098722 -159.818348) (xy 419.088824 -159.829246) (xy 419.070614 -159.849958)
			(xy 419.029244 -159.886426) (xy 418.983053 -159.916557) (xy 418.933005 -159.939722) (xy 418.880143 -159.955439)
			(xy 418.825569 -159.96338) (xy 418.797994 -159.963866) (xy 418.771493 -159.963405) (xy 418.719002 -159.956063)
			(xy 418.668034 -159.941521) (xy 418.619572 -159.920059) (xy 418.574549 -159.892091) (xy 418.5539 -159.875474)
			(xy 418.541717 -159.866082) (xy 418.51333 -159.854285) (xy 418.482719 -159.851451) (xy 418.452648 -159.857838)
			(xy 418.425831 -159.872868) (xy 418.404689 -159.895186) (xy 418.397436 -159.908748) (xy 418.385321 -159.93243)
			(xy 418.355402 -159.976413) (xy 418.319535 -160.015696) (xy 418.278448 -160.049482) (xy 418.255958 -160.063688)
			(xy 418.243751 -160.071635) (xy 418.224085 -160.093102) (xy 418.211281 -160.119249) (xy 418.206381 -160.147947)
			(xy 418.209783 -160.176861) (xy 418.215064 -160.190434) (xy 418.22456 -160.213641) (xy 418.237908 -160.261976)
			(xy 418.244633 -160.311666) (xy 418.245036 -160.336738) (xy 418.244615 -160.361807) (xy 418.237865 -160.411491)
			(xy 418.224531 -160.459825) (xy 418.215064 -160.483042) (xy 418.209854 -160.496631) (xy 418.206485 -160.525525)
			(xy 418.211389 -160.554198) (xy 418.224168 -160.58033) (xy 418.243789 -160.601805) (xy 418.255958 -160.609788)
			(xy 418.27905 -160.624416) (xy 418.321167 -160.659255) (xy 418.357742 -160.699872) (xy 418.387993 -160.745397)
			(xy 418.411268 -160.794852) (xy 418.427069 -160.847177) (xy 418.435057 -160.901249) (xy 418.43506 -160.955908)
			(xy 418.427078 -161.00998) (xy 418.411283 -161.062307) (xy 418.388014 -161.111765) (xy 418.357769 -161.157294)
			(xy 418.321198 -161.197915) (xy 418.279085 -161.232759) (xy 418.255958 -161.247328) (xy 418.243724 -161.255237)
			(xy 418.224058 -161.276714) (xy 418.211257 -161.302871) (xy 418.206364 -161.331578) (xy 418.209777 -161.360499)
			(xy 418.215064 -161.374074) (xy 418.224541 -161.397289) (xy 418.237896 -161.445619) (xy 418.244629 -161.495307)
			(xy 418.245036 -161.520378) (xy 418.244515 -161.548263) (xy 418.236203 -161.60341) (xy 418.219765 -161.656702)
			(xy 418.195567 -161.706948) (xy 418.164151 -161.753027) (xy 418.126218 -161.793909) (xy 418.082616 -161.828681)
			(xy 418.034318 -161.856566) (xy 417.982403 -161.876941) (xy 417.928032 -161.889351) (xy 417.872418 -161.893519)
			(xy 417.816804 -161.889351) (xy 417.762433 -161.876941) (xy 417.710518 -161.856566) (xy 417.66222 -161.828681)
			(xy 417.618618 -161.793909) (xy 417.580685 -161.753027) (xy 417.549269 -161.706948) (xy 417.525071 -161.656702)
			(xy 417.508633 -161.60341) (xy 417.500321 -161.548263) (xy 417.4998 -161.520378) (xy 410.18968 -161.520378)
			(xy 410.18968 -162.451542) (xy 419.315646 -162.451542) (xy 419.316217 -162.424294) (xy 419.323967 -162.370352)
			(xy 419.339314 -162.318061) (xy 419.361947 -162.268487) (xy 419.391405 -162.222639) (xy 419.427087 -162.18145)
			(xy 419.468269 -162.145757) (xy 419.51411 -162.116289) (xy 419.563679 -162.093645) (xy 419.615966 -162.078285)
			(xy 419.669906 -162.070523) (xy 419.697154 -162.070034) (xy 419.727059 -162.070571) (xy 419.786138 -162.079883)
			(xy 419.814756 -162.088576) (xy 419.82866 -162.09263) (xy 419.857597 -162.09354) (xy 419.885621 -162.086274)
			(xy 419.910469 -162.071418) (xy 419.930134 -162.050171) (xy 419.943028 -162.024251) (xy 419.946074 -162.01009)
			(xy 419.951204 -161.984008) (xy 419.967775 -161.933501) (xy 419.991201 -161.885784) (xy 420.021027 -161.841784)
			(xy 420.056674 -161.802352) (xy 420.097452 -161.768253) (xy 420.142571 -161.740148) (xy 420.191156 -161.718581)
			(xy 420.242265 -161.703971) (xy 420.294908 -161.696601) (xy 420.321486 -161.696146) (xy 420.348736 -161.6967)
			(xy 420.402682 -161.704455) (xy 420.454975 -161.719808) (xy 420.504551 -161.742447) (xy 420.550401 -161.771911)
			(xy 420.59159 -161.8076) (xy 420.627281 -161.848788) (xy 420.656747 -161.894636) (xy 420.679387 -161.944211)
			(xy 420.694742 -161.996504) (xy 420.702499 -162.05045) (xy 420.702499 -162.10495) (xy 420.694742 -162.158896)
			(xy 420.679387 -162.211189) (xy 420.656747 -162.260764) (xy 420.627281 -162.306612) (xy 420.59159 -162.3478)
			(xy 420.550401 -162.383489) (xy 420.504551 -162.412953) (xy 420.454975 -162.435592) (xy 420.402682 -162.450945)
			(xy 420.348736 -162.4587) (xy 420.321486 -162.459162) (xy 420.291581 -162.458639) (xy 420.232502 -162.449318)
			(xy 420.203884 -162.44062) (xy 420.189967 -162.436614) (xy 420.161038 -162.435695) (xy 420.133019 -162.442952)
			(xy 420.108173 -162.457799) (xy 420.088508 -162.479036) (xy 420.075613 -162.504949) (xy 420.072566 -162.519106)
			(xy 420.06599 -162.551947) (xy 420.042863 -162.614798) (xy 420.026592 -162.644074) (xy 420.019587 -162.657057)
			(xy 420.012541 -162.685688) (xy 420.013975 -162.715137) (xy 420.023771 -162.742948) (xy 420.04111 -162.766795)
			(xy 420.064544 -162.78469) (xy 420.078154 -162.790378) (xy 420.104942 -162.801047) (xy 420.155182 -162.829341)
			(xy 420.20059 -162.864876) (xy 420.240131 -162.906842) (xy 420.272903 -162.954283) (xy 420.298159 -163.006117)
			(xy 420.315323 -163.061162) (xy 420.324005 -163.118164) (xy 420.324534 -163.146994) (xy 420.324113 -163.170616)
			(xy 425.480988 -163.170616) (xy 425.48147 -163.143364) (xy 425.489225 -163.089414) (xy 425.504579 -163.037116)
			(xy 425.527219 -162.987537) (xy 425.556685 -162.941684) (xy 425.592377 -162.900491) (xy 425.633568 -162.864797)
			(xy 425.679419 -162.835329) (xy 425.728998 -162.812686) (xy 425.781294 -162.797329) (xy 425.835244 -162.789572)
			(xy 425.862496 -162.789108) (xy 425.890642 -162.789598) (xy 425.946324 -162.797875) (xy 426.000186 -162.814237)
			(xy 426.051064 -162.838327) (xy 426.097854 -162.869626) (xy 426.119036 -162.888168) (xy 426.130841 -162.8982)
			(xy 426.15893 -162.911235) (xy 426.189633 -162.915257) (xy 426.220131 -162.909897) (xy 426.247624 -162.895647)
			(xy 426.25899 -162.88512) (xy 426.280551 -162.864437) (xy 426.328964 -162.829427) (xy 426.382244 -162.802395)
			(xy 426.439087 -162.784001) (xy 426.498103 -162.774696) (xy 426.527976 -162.774122) (xy 426.556122 -162.77462)
			(xy 426.611803 -162.782895) (xy 426.665666 -162.799254) (xy 426.716544 -162.823343) (xy 426.763334 -162.85464)
			(xy 426.784516 -162.873182) (xy 426.796337 -162.883193) (xy 426.82442 -162.896228) (xy 426.855118 -162.900253)
			(xy 426.885612 -162.894899) (xy 426.913103 -162.880657) (xy 426.92447 -162.870134) (xy 426.946042 -162.849463)
			(xy 426.994452 -162.814451) (xy 427.047729 -162.787416) (xy 427.10457 -162.76902) (xy 427.163584 -162.759712)
			(xy 427.193456 -162.759136) (xy 427.22071 -162.759596) (xy 427.274663 -162.767348) (xy 427.326964 -162.782701)
			(xy 427.376547 -162.805342) (xy 427.422402 -162.834809) (xy 427.463596 -162.870504) (xy 427.499291 -162.911698)
			(xy 427.528758 -162.957553) (xy 427.551399 -163.007136) (xy 427.566752 -163.059437) (xy 427.574504 -163.11339)
			(xy 427.574964 -163.140644) (xy 427.57445 -163.169383) (xy 427.565822 -163.22621) (xy 427.548769 -163.2811)
			(xy 427.523676 -163.332812) (xy 427.49111 -163.380175) (xy 427.47184 -163.401502) (xy 427.461724 -163.413001)
			(xy 427.448385 -163.44056) (xy 427.443809 -163.470832) (xy 427.448405 -163.501102) (xy 427.461761 -163.528652)
			(xy 427.47184 -163.540186) (xy 427.491156 -163.561474) (xy 427.523723 -163.608842) (xy 427.548814 -163.66056)
			(xy 427.565863 -163.715457) (xy 427.574482 -163.77229) (xy 427.574477 -163.829774) (xy 427.565849 -163.886606)
			(xy 427.548791 -163.9415) (xy 427.52369 -163.993213) (xy 427.491116 -164.040576) (xy 427.47184 -164.061902)
			(xy 427.461724 -164.073401) (xy 427.448385 -164.10096) (xy 427.443809 -164.131232) (xy 427.448405 -164.161502)
			(xy 427.461761 -164.189052) (xy 427.47184 -164.200586) (xy 427.491156 -164.221874) (xy 427.523723 -164.269242)
			(xy 427.548814 -164.32096) (xy 427.565863 -164.375857) (xy 427.574482 -164.43269) (xy 427.574477 -164.490174)
			(xy 427.565849 -164.547006) (xy 427.548791 -164.6019) (xy 427.52369 -164.653613) (xy 427.491116 -164.700976)
			(xy 427.47184 -164.722302) (xy 427.461724 -164.733801) (xy 427.448385 -164.76136) (xy 427.443809 -164.791632)
			(xy 427.448405 -164.821902) (xy 427.461761 -164.849452) (xy 427.47184 -164.860986) (xy 427.491156 -164.882274)
			(xy 427.523723 -164.929642) (xy 427.548814 -164.98136) (xy 427.565863 -165.036257) (xy 427.574482 -165.09309)
			(xy 427.574477 -165.150574) (xy 427.565849 -165.207406) (xy 427.548791 -165.2623) (xy 427.52369 -165.314013)
			(xy 427.491116 -165.361376) (xy 427.47184 -165.382702) (xy 427.461724 -165.394201) (xy 427.448385 -165.42176)
			(xy 427.443809 -165.452032) (xy 427.448405 -165.482302) (xy 427.461761 -165.509852) (xy 427.47184 -165.521386)
			(xy 427.491156 -165.542674) (xy 427.523723 -165.590042) (xy 427.548814 -165.64176) (xy 427.565863 -165.696657)
			(xy 427.574482 -165.75349) (xy 427.574477 -165.810974) (xy 427.565849 -165.867806) (xy 427.548791 -165.9227)
			(xy 427.52369 -165.974413) (xy 427.491116 -166.021776) (xy 427.47184 -166.043102) (xy 427.461724 -166.054601)
			(xy 427.448385 -166.08216) (xy 427.443809 -166.112432) (xy 427.448405 -166.142702) (xy 427.461761 -166.170252)
			(xy 427.47184 -166.181786) (xy 427.491128 -166.203098) (xy 427.523693 -166.250464) (xy 427.548782 -166.302179)
			(xy 427.565829 -166.357073) (xy 427.574446 -166.413904) (xy 427.57457 -166.4208) (xy 430.96942 -166.4208)
			(xy 430.969965 -166.392062) (xy 430.978586 -166.335237) (xy 430.995632 -166.280347) (xy 431.020718 -166.228635)
			(xy 431.053277 -166.181271) (xy 431.072544 -166.159942) (xy 431.082618 -166.148409) (xy 431.095963 -166.120863)
			(xy 431.100549 -166.0906) (xy 431.095963 -166.060337) (xy 431.082618 -166.032791) (xy 431.072544 -166.021258)
			(xy 431.053272 -165.999932) (xy 431.020705 -165.95257) (xy 430.995612 -165.900858) (xy 430.978561 -165.845967)
			(xy 430.969938 -165.789139) (xy 430.969938 -165.731661) (xy 430.978561 -165.674833) (xy 430.995612 -165.619942)
			(xy 431.020705 -165.56823) (xy 431.053272 -165.520868) (xy 431.072544 -165.499542) (xy 431.082618 -165.488009)
			(xy 431.095963 -165.460463) (xy 431.100549 -165.4302) (xy 431.095963 -165.399937) (xy 431.082618 -165.372391)
			(xy 431.072544 -165.360858) (xy 431.053272 -165.339532) (xy 431.020705 -165.29217) (xy 430.995612 -165.240458)
			(xy 430.978561 -165.185567) (xy 430.969938 -165.128739) (xy 430.969938 -165.071261) (xy 430.978561 -165.014433)
			(xy 430.995612 -164.959542) (xy 431.020705 -164.90783) (xy 431.053272 -164.860468) (xy 431.072544 -164.839142)
			(xy 431.082618 -164.827609) (xy 431.095963 -164.800063) (xy 431.100549 -164.7698) (xy 431.095963 -164.739537)
			(xy 431.082618 -164.711991) (xy 431.072544 -164.700458) (xy 431.053272 -164.679132) (xy 431.020705 -164.63177)
			(xy 430.995612 -164.580058) (xy 430.978561 -164.525167) (xy 430.969938 -164.468339) (xy 430.969938 -164.410861)
			(xy 430.978561 -164.354033) (xy 430.995612 -164.299142) (xy 431.020705 -164.24743) (xy 431.053272 -164.200068)
			(xy 431.072544 -164.178742) (xy 431.082618 -164.167209) (xy 431.095963 -164.139663) (xy 431.100549 -164.1094)
			(xy 431.095963 -164.079137) (xy 431.082618 -164.051591) (xy 431.072544 -164.040058) (xy 431.053274 -164.01873)
			(xy 431.020708 -163.971368) (xy 430.995615 -163.919657) (xy 430.978564 -163.864766) (xy 430.969941 -163.807939)
			(xy 430.96942 -163.7792) (xy 430.96983 -163.753378) (xy 430.976782 -163.702204) (xy 430.990572 -163.652435)
			(xy 431.010949 -163.604981) (xy 431.037539 -163.560709) (xy 431.069858 -163.520427) (xy 431.088292 -163.50234)
			(xy 431.09798 -163.492559) (xy 431.112152 -163.468967) (xy 431.119503 -163.442447) (xy 431.1195 -163.414926)
			(xy 431.112141 -163.388407) (xy 431.097962 -163.36482) (xy 431.088292 -163.35502) (xy 431.069869 -163.336925)
			(xy 431.037565 -163.296636) (xy 431.010985 -163.252362) (xy 430.990611 -163.204911) (xy 430.976815 -163.155148)
			(xy 430.96985 -163.10398) (xy 430.96942 -163.07816) (xy 430.969941 -163.049421) (xy 430.978567 -162.992595)
			(xy 430.995619 -162.937705) (xy 431.020711 -162.885993) (xy 431.053274 -162.83863) (xy 431.072544 -162.817302)
			(xy 431.082657 -162.8058) (xy 431.095999 -162.778243) (xy 431.100577 -162.747971) (xy 431.095981 -162.717701)
			(xy 431.082624 -162.690151) (xy 431.072544 -162.678618) (xy 431.053255 -162.657306) (xy 431.020691 -162.60994)
			(xy 430.995602 -162.558225) (xy 430.978556 -162.503331) (xy 430.969938 -162.4465) (xy 430.96942 -162.41776)
			(xy 430.969841 -162.390506) (xy 430.977603 -162.336555) (xy 430.992965 -162.284257) (xy 431.015613 -162.234678)
			(xy 431.045086 -162.188827) (xy 431.080784 -162.147636) (xy 431.121981 -162.111945) (xy 431.167838 -162.08248)
			(xy 431.217421 -162.059841) (xy 431.269722 -162.044489) (xy 431.323674 -162.036736) (xy 431.350928 -162.036252)
			(xy 431.379073 -162.036771) (xy 431.434754 -162.04504) (xy 431.488617 -162.061394) (xy 431.539495 -162.085478)
			(xy 431.586286 -162.116772) (xy 431.607468 -162.135312) (xy 431.619251 -162.145371) (xy 431.647348 -162.158396)
			(xy 431.678057 -162.16241) (xy 431.708558 -162.157044) (xy 431.736054 -162.142792) (xy 431.747422 -162.132264)
			(xy 431.76902 -162.111621) (xy 431.817422 -162.076604) (xy 431.870692 -162.049563) (xy 431.927528 -162.031161)
			(xy 431.986538 -162.021846) (xy 432.016408 -162.021266) (xy 432.045147 -162.021794) (xy 432.101973 -162.030417)
			(xy 432.156864 -162.047466) (xy 432.208576 -162.072557) (xy 432.255939 -162.10512) (xy 432.277266 -162.12439)
			(xy 432.2888 -162.134462) (xy 432.316346 -162.147804) (xy 432.346608 -162.152389) (xy 432.37687 -162.147804)
			(xy 432.404416 -162.134462) (xy 432.41595 -162.12439) (xy 432.437282 -162.105124) (xy 432.484642 -162.072556)
			(xy 432.536352 -162.047461) (xy 432.591242 -162.03041) (xy 432.648069 -162.021787) (xy 432.676808 -162.021266)
			(xy 432.704058 -162.02177) (xy 432.758004 -162.029527) (xy 432.810297 -162.044882) (xy 432.859872 -162.067522)
			(xy 432.905721 -162.096987) (xy 432.946911 -162.132676) (xy 432.982602 -162.173864) (xy 433.012069 -162.219712)
			(xy 433.034712 -162.269286) (xy 433.050069 -162.321578) (xy 433.057828 -162.375524) (xy 433.058316 -162.402774)
			(xy 433.057772 -162.431512) (xy 433.049154 -162.488338) (xy 433.032108 -162.543229) (xy 433.007021 -162.594941)
			(xy 432.974461 -162.642304) (xy 432.955192 -162.663632) (xy 432.945149 -162.675188) (xy 432.931809 -162.702727)
			(xy 432.927221 -162.732981) (xy 432.931798 -162.763237) (xy 432.945127 -162.790781) (xy 432.955192 -162.802316)
			(xy 432.974455 -162.823649) (xy 433.007022 -162.87101) (xy 433.032115 -162.92272) (xy 433.049167 -162.977609)
			(xy 433.057793 -163.034436) (xy 433.058316 -163.063174) (xy 433.057878 -163.088995) (xy 433.05093 -163.140167)
			(xy 433.037145 -163.189935) (xy 433.016773 -163.237389) (xy 432.990188 -163.281662) (xy 432.957875 -163.321945)
			(xy 432.939444 -163.340034) (xy 432.92978 -163.349838) (xy 432.915601 -163.373422) (xy 432.908243 -163.399937)
			(xy 432.908242 -163.427455) (xy 432.915598 -163.453971) (xy 432.929774 -163.477556) (xy 432.939444 -163.487354)
			(xy 432.957891 -163.505427) (xy 432.990194 -163.545719) (xy 433.016773 -163.589997) (xy 433.037143 -163.637453)
			(xy 433.050933 -163.68722) (xy 433.05789 -163.738393) (xy 433.058316 -163.764214) (xy 433.057796 -163.792953)
			(xy 433.049172 -163.84978) (xy 433.032121 -163.904671) (xy 433.007029 -163.956383) (xy 432.974463 -164.003745)
			(xy 432.955192 -164.025072) (xy 432.94511 -164.036597) (xy 432.931774 -164.064147) (xy 432.927194 -164.09441)
			(xy 432.93178 -164.124673) (xy 432.945121 -164.15222) (xy 432.955192 -164.163756) (xy 432.974476 -164.185071)
			(xy 433.007039 -164.232436) (xy 433.032129 -164.28415) (xy 433.049177 -164.339042) (xy 433.057798 -164.395871)
			(xy 433.057797 -164.45335) (xy 433.049173 -164.510178) (xy 433.032122 -164.565069) (xy 433.007029 -164.616782)
			(xy 432.974463 -164.664145) (xy 432.955192 -164.685472) (xy 432.94511 -164.696997) (xy 432.931774 -164.724547)
			(xy 432.927194 -164.75481) (xy 432.93178 -164.785073) (xy 432.945121 -164.81262) (xy 432.955192 -164.824156)
			(xy 432.974476 -164.845471) (xy 433.007039 -164.892836) (xy 433.032129 -164.94455) (xy 433.049177 -164.999442)
			(xy 433.057798 -165.056271) (xy 433.057797 -165.11375) (xy 433.049173 -165.170578) (xy 433.032122 -165.225469)
			(xy 433.007029 -165.277182) (xy 432.974463 -165.324545) (xy 432.955192 -165.345872) (xy 432.94511 -165.357397)
			(xy 432.931774 -165.384947) (xy 432.927194 -165.41521) (xy 432.93178 -165.445473) (xy 432.945121 -165.47302)
			(xy 432.955192 -165.484556) (xy 432.974474 -165.505873) (xy 433.007038 -165.553238) (xy 433.032128 -165.604952)
			(xy 433.049176 -165.659845) (xy 433.057796 -165.716674) (xy 433.058316 -165.745414) (xy 433.057835 -165.772665)
			(xy 433.050077 -165.826613) (xy 433.034721 -165.878907) (xy 433.012078 -165.928484) (xy 432.982611 -165.974334)
			(xy 432.946919 -166.015524) (xy 432.905729 -166.051215) (xy 432.859879 -166.080681) (xy 432.810301 -166.103323)
			(xy 432.758007 -166.118678) (xy 432.704059 -166.126436) (xy 432.676808 -166.126922) (xy 432.649163 -166.126403)
			(xy 432.594453 -166.118406) (xy 432.541471 -166.102593) (xy 432.491328 -166.079296) (xy 432.445074 -166.049002)
			(xy 432.40368 -166.012347) (xy 432.38547 -165.99154) (xy 432.377861 -165.983437) (xy 432.35771 -165.974116)
			(xy 432.335506 -165.974116) (xy 432.315355 -165.983437) (xy 432.307746 -165.99154) (xy 432.294792 -166.006272)
			(xy 432.28471 -166.017797) (xy 432.271374 -166.045347) (xy 432.266794 -166.07561) (xy 432.27138 -166.105873)
			(xy 432.284721 -166.13342) (xy 432.294792 -166.144956) (xy 432.314074 -166.166273) (xy 432.346638 -166.213638)
			(xy 432.371728 -166.265352) (xy 432.388776 -166.320245) (xy 432.397396 -166.377074) (xy 432.397916 -166.405814)
			(xy 432.397371 -166.4341) (xy 432.389016 -166.490053) (xy 432.372492 -166.544159) (xy 432.34816 -166.595232)
			(xy 432.316555 -166.642153) (xy 432.29784 -166.66337) (xy 432.28775 -166.675307) (xy 432.274637 -166.703659)
			(xy 432.270696 -166.734646) (xy 432.276295 -166.765378) (xy 432.290912 -166.792984) (xy 432.30165 -166.80434)
			(xy 432.322827 -166.826023) (xy 432.358792 -166.874803) (xy 432.386591 -166.928657) (xy 432.405522 -166.98623)
			(xy 432.415111 -167.046071) (xy 432.415696 -167.076374) (xy 432.41522 -167.103627) (xy 432.407467 -167.157578)
			(xy 432.392113 -167.209876) (xy 432.369473 -167.259457) (xy 432.340007 -167.305311) (xy 432.304314 -167.346504)
			(xy 432.263122 -167.382198) (xy 432.217269 -167.411666) (xy 432.167689 -167.434308) (xy 432.115392 -167.449664)
			(xy 432.061441 -167.457419) (xy 432.034188 -167.457882) (xy 432.006043 -167.457345) (xy 431.950364 -167.449079)
			(xy 431.896502 -167.432729) (xy 431.845623 -167.408649) (xy 431.798831 -167.37736) (xy 431.777648 -167.358822)
			(xy 431.765855 -167.348775) (xy 431.737762 -167.335744) (xy 431.707055 -167.331725) (xy 431.676555 -167.337089)
			(xy 431.649061 -167.351341) (xy 431.637694 -167.36187) (xy 431.616095 -167.382511) (xy 431.567692 -167.417527)
			(xy 431.514422 -167.444567) (xy 431.457587 -167.462971) (xy 431.398578 -167.472287) (xy 431.368708 -167.472868)
			(xy 431.341454 -167.472437) (xy 431.287499 -167.46468) (xy 431.235198 -167.449323) (xy 431.185616 -167.426679)
			(xy 431.139761 -167.397208) (xy 431.098567 -167.361511) (xy 431.062873 -167.320314) (xy 431.033406 -167.274456)
			(xy 431.010766 -167.224872) (xy 430.995413 -167.172569) (xy 430.987661 -167.118615) (xy 430.9872 -167.09136)
			(xy 430.987726 -167.063073) (xy 430.996085 -167.007119) (xy 431.012613 -166.953013) (xy 431.036949 -166.90194)
			(xy 431.068559 -166.85502) (xy 431.087276 -166.833804) (xy 431.09739 -166.821886) (xy 431.110498 -166.793527)
			(xy 431.114434 -166.762534) (xy 431.108828 -166.7318) (xy 431.094206 -166.704191) (xy 431.083466 -166.692834)
			(xy 431.062279 -166.67116) (xy 431.026315 -166.622378) (xy 430.998518 -166.568521) (xy 430.979589 -166.510947)
			(xy 430.970003 -166.451103) (xy 430.96942 -166.4208) (xy 427.57457 -166.4208) (xy 427.574964 -166.442644)
			(xy 427.574563 -166.469898) (xy 427.566799 -166.523851) (xy 427.551436 -166.57615) (xy 427.528787 -166.625731)
			(xy 427.499312 -166.671583) (xy 427.463612 -166.712774) (xy 427.422412 -166.748465) (xy 427.376553 -166.777929)
			(xy 427.326968 -166.800567) (xy 427.274665 -166.815918) (xy 427.22071 -166.823669) (xy 427.193456 -166.824152)
			(xy 427.16531 -166.823641) (xy 427.10963 -166.815371) (xy 427.055766 -166.799015) (xy 427.004888 -166.774928)
			(xy 426.958098 -166.743633) (xy 426.936916 -166.725092) (xy 426.925069 -166.715116) (xy 426.896995 -166.702081)
			(xy 426.866306 -166.698051) (xy 426.835818 -166.703395) (xy 426.80833 -166.717624) (xy 426.796962 -166.72814)
			(xy 426.775372 -166.748791) (xy 426.726968 -166.783807) (xy 426.673695 -166.810846) (xy 426.616858 -166.829247)
			(xy 426.557847 -166.838559) (xy 426.527976 -166.839138) (xy 426.499237 -166.838619) (xy 426.44241 -166.829993)
			(xy 426.38752 -166.812942) (xy 426.335808 -166.78785) (xy 426.288445 -166.755284) (xy 426.267118 -166.736014)
			(xy 426.255584 -166.725942) (xy 426.228038 -166.7126) (xy 426.197776 -166.708015) (xy 426.167514 -166.7126)
			(xy 426.139968 -166.725942) (xy 426.128434 -166.736014) (xy 426.10711 -166.755288) (xy 426.059748 -166.787856)
			(xy 426.008036 -166.812948) (xy 425.953144 -166.829998) (xy 425.896315 -166.838619) (xy 425.867576 -166.839138)
			(xy 425.840326 -166.838645) (xy 425.78638 -166.830886) (xy 425.734087 -166.815529) (xy 425.684512 -166.792887)
			(xy 425.638663 -166.763421) (xy 425.597474 -166.727731) (xy 425.561782 -166.686542) (xy 425.532316 -166.640694)
			(xy 425.509673 -166.591119) (xy 425.494316 -166.538826) (xy 425.486556 -166.48488) (xy 425.486068 -166.45763)
			(xy 425.486619 -166.428892) (xy 425.495236 -166.372066) (xy 425.51228 -166.317176) (xy 425.537366 -166.265464)
			(xy 425.569924 -166.2181) (xy 425.589192 -166.196772) (xy 425.599232 -166.185214) (xy 425.612575 -166.157676)
			(xy 425.617164 -166.127422) (xy 425.612588 -166.097166) (xy 425.599257 -166.069623) (xy 425.589192 -166.058088)
			(xy 425.569952 -166.036735) (xy 425.537389 -165.989376) (xy 425.512298 -165.937668) (xy 425.495247 -165.882782)
			(xy 425.486622 -165.825959) (xy 425.486619 -165.768485) (xy 425.495237 -165.711661) (xy 425.512282 -165.656773)
			(xy 425.537367 -165.605062) (xy 425.569925 -165.557699) (xy 425.589192 -165.536372) (xy 425.599232 -165.524814)
			(xy 425.612575 -165.497276) (xy 425.617164 -165.467022) (xy 425.612588 -165.436766) (xy 425.599257 -165.409223)
			(xy 425.589192 -165.397688) (xy 425.569952 -165.376335) (xy 425.537389 -165.328976) (xy 425.512298 -165.277268)
			(xy 425.495247 -165.222382) (xy 425.486622 -165.165559) (xy 425.486619 -165.108085) (xy 425.495237 -165.051261)
			(xy 425.512282 -164.996373) (xy 425.537367 -164.944662) (xy 425.569925 -164.897299) (xy 425.589192 -164.875972)
			(xy 425.599232 -164.864414) (xy 425.612575 -164.836876) (xy 425.617164 -164.806622) (xy 425.612588 -164.776366)
			(xy 425.599257 -164.748823) (xy 425.589192 -164.737288) (xy 425.569952 -164.715935) (xy 425.537389 -164.668576)
			(xy 425.512298 -164.616868) (xy 425.495247 -164.561982) (xy 425.486622 -164.505159) (xy 425.486619 -164.447685)
			(xy 425.495237 -164.390861) (xy 425.512282 -164.335973) (xy 425.537367 -164.284262) (xy 425.569925 -164.236899)
			(xy 425.589192 -164.215572) (xy 425.599232 -164.204014) (xy 425.612575 -164.176476) (xy 425.617164 -164.146222)
			(xy 425.612588 -164.115966) (xy 425.599257 -164.088423) (xy 425.589192 -164.076888) (xy 425.569945 -164.05554)
			(xy 425.537373 -164.008185) (xy 425.512276 -163.956479) (xy 425.49522 -163.901592) (xy 425.486592 -163.844768)
			(xy 425.486068 -163.81603) (xy 425.486539 -163.788401) (xy 425.494478 -163.733716) (xy 425.510222 -163.680748)
			(xy 425.533443 -163.630605) (xy 425.563654 -163.584337) (xy 425.581572 -163.5633) (xy 425.590996 -163.551771)
			(xy 425.603448 -163.524742) (xy 425.607576 -163.495271) (xy 425.603028 -163.465862) (xy 425.590191 -163.439014)
			(xy 425.580556 -163.427664) (xy 425.561911 -163.406478) (xy 425.530459 -163.35962) (xy 425.506249 -163.308641)
			(xy 425.489809 -163.254654) (xy 425.481497 -163.198834) (xy 425.480988 -163.170616) (xy 420.324113 -163.170616)
			(xy 420.324048 -163.174245) (xy 420.316292 -163.228193) (xy 420.300937 -163.280488) (xy 420.278295 -163.330065)
			(xy 420.248829 -163.375915) (xy 420.213138 -163.417106) (xy 420.171947 -163.452797) (xy 420.126097 -163.482263)
			(xy 420.07652 -163.504905) (xy 420.024225 -163.52026) (xy 419.970277 -163.528016) (xy 419.915775 -163.528016)
			(xy 419.861827 -163.52026) (xy 419.809532 -163.504905) (xy 419.759955 -163.482263) (xy 419.714105 -163.452797)
			(xy 419.672914 -163.417106) (xy 419.637223 -163.375915) (xy 419.607757 -163.330065) (xy 419.585115 -163.280488)
			(xy 419.56976 -163.228193) (xy 419.562004 -163.174245) (xy 419.561518 -163.146994) (xy 419.56191 -163.121758)
			(xy 419.568529 -163.071724) (xy 419.581704 -163.023004) (xy 419.601202 -162.976452) (xy 419.613588 -162.954462)
			(xy 419.620627 -162.941499) (xy 419.627653 -162.912862) (xy 419.626205 -162.883412) (xy 419.616403 -162.855603)
			(xy 419.599064 -162.831754) (xy 419.575634 -162.813852) (xy 419.562026 -162.808158) (xy 419.535269 -162.797416)
			(xy 419.485027 -162.769136) (xy 419.439617 -162.733613) (xy 419.400072 -162.691658) (xy 419.367296 -162.644228)
			(xy 419.342035 -162.592402) (xy 419.324865 -162.537365) (xy 419.316178 -162.480369) (xy 419.315646 -162.451542)
			(xy 410.18968 -162.451542) (xy 410.18968 -164.19025) (xy 419.374572 -164.19025) (xy 419.374572 -164.13575)
			(xy 419.382328 -164.081803) (xy 419.397682 -164.02951) (xy 419.420321 -163.979933) (xy 419.449786 -163.934084)
			(xy 419.485475 -163.892893) (xy 419.526663 -163.857201) (xy 419.572511 -163.827734) (xy 419.622085 -163.805091)
			(xy 419.674378 -163.789733) (xy 419.728324 -163.781974) (xy 419.755574 -163.781486) (xy 419.785261 -163.782065)
			(xy 419.843919 -163.79126) (xy 419.900444 -163.809431) (xy 419.953471 -163.836139) (xy 420.001721 -163.870741)
			(xy 420.044027 -163.912399) (xy 420.062152 -163.935918) (xy 420.070578 -163.946525) (xy 420.091891 -163.963232)
			(xy 420.116845 -163.973751) (xy 420.143686 -163.977341) (xy 420.170527 -163.973751) (xy 420.195481 -163.963232)
			(xy 420.216794 -163.946525) (xy 420.22522 -163.935918) (xy 420.243349 -163.912402) (xy 420.285654 -163.870741)
			(xy 420.333902 -163.836136) (xy 420.386928 -163.809424) (xy 420.443453 -163.79125) (xy 420.502111 -163.782051)
			(xy 420.531798 -163.781486) (xy 420.559051 -163.781961) (xy 420.613001 -163.789718) (xy 420.665298 -163.805073)
			(xy 420.714878 -163.827715) (xy 420.76073 -163.857183) (xy 420.801923 -163.892876) (xy 420.837616 -163.934068)
			(xy 420.867084 -163.979921) (xy 420.889726 -164.0295) (xy 420.905082 -164.081797) (xy 420.912839 -164.135747)
			(xy 420.912839 -164.190253) (xy 420.905082 -164.244203) (xy 420.889726 -164.2965) (xy 420.867084 -164.346079)
			(xy 420.837616 -164.391932) (xy 420.801923 -164.433124) (xy 420.76073 -164.468817) (xy 420.714878 -164.498285)
			(xy 420.665298 -164.520927) (xy 420.613001 -164.536282) (xy 420.559051 -164.544039) (xy 420.531798 -164.544502)
			(xy 420.50211 -164.543948) (xy 420.443451 -164.534749) (xy 420.386925 -164.516573) (xy 420.333898 -164.48986)
			(xy 420.285649 -164.455254) (xy 420.243344 -164.413591) (xy 420.22522 -164.39007) (xy 420.216794 -164.379463)
			(xy 420.195481 -164.362756) (xy 420.170527 -164.352237) (xy 420.143686 -164.348647) (xy 420.116845 -164.352237)
			(xy 420.091891 -164.362756) (xy 420.070578 -164.379463) (xy 420.062152 -164.39007) (xy 420.044036 -164.413597)
			(xy 420.001729 -164.455258) (xy 419.953478 -164.489861) (xy 419.900449 -164.516572) (xy 419.843922 -164.534744)
			(xy 419.785262 -164.543939) (xy 419.755574 -164.544502) (xy 419.728324 -164.544026) (xy 419.674378 -164.536267)
			(xy 419.622085 -164.520909) (xy 419.572511 -164.498266) (xy 419.526663 -164.468799) (xy 419.485475 -164.433107)
			(xy 419.449786 -164.391916) (xy 419.420321 -164.346067) (xy 419.397682 -164.29649) (xy 419.382328 -164.244197)
			(xy 419.374572 -164.19025) (xy 410.18968 -164.19025) (xy 410.18968 -164.941953) (xy 418.557175 -164.941953)
			(xy 418.564931 -164.888006) (xy 418.580286 -164.835711) (xy 418.602926 -164.786133) (xy 418.632392 -164.740282)
			(xy 418.668083 -164.699091) (xy 418.709272 -164.663399) (xy 418.755122 -164.633932) (xy 418.804699 -164.61129)
			(xy 418.856994 -164.595934) (xy 418.910941 -164.588176) (xy 418.965444 -164.588175) (xy 419.019392 -164.595931)
			(xy 419.071687 -164.611285) (xy 419.121265 -164.633925) (xy 419.167116 -164.66339) (xy 419.208307 -164.699081)
			(xy 419.243999 -164.74027) (xy 419.273467 -164.78612) (xy 419.296109 -164.835697) (xy 419.311466 -164.887991)
			(xy 419.319224 -164.941939) (xy 419.31971 -164.96919) (xy 419.319282 -164.994581) (xy 419.312524 -165.044913)
			(xy 419.306248 -165.06952) (xy 419.302808 -165.084167) (xy 419.303729 -165.114225) (xy 419.31336 -165.142715)
			(xy 419.330866 -165.167167) (xy 419.354731 -165.185465) (xy 419.38289 -165.196023) (xy 419.412902 -165.197929)
			(xy 419.42766 -165.194996) (xy 419.449255 -165.190239) (xy 419.49318 -165.18514) (xy 419.51529 -165.184836)
			(xy 419.542541 -165.185267) (xy 419.59649 -165.193022) (xy 419.648785 -165.208376) (xy 419.698364 -165.231015)
			(xy 419.744216 -165.26048) (xy 419.785408 -165.29617) (xy 419.821101 -165.337359) (xy 419.85057 -165.383209)
			(xy 419.873213 -165.432785) (xy 419.888571 -165.48508) (xy 419.896331 -165.539027) (xy 419.896334 -165.59353)
			(xy 419.88858 -165.647479) (xy 419.873228 -165.699775) (xy 419.85059 -165.749354) (xy 419.821127 -165.795207)
			(xy 419.785438 -165.8364) (xy 419.74425 -165.872094) (xy 419.698401 -165.901564) (xy 419.648825 -165.924209)
			(xy 419.596532 -165.939569) (xy 419.542584 -165.94733) (xy 419.488081 -165.947335) (xy 419.434132 -165.939583)
			(xy 419.381836 -165.924232) (xy 419.332256 -165.901596) (xy 419.286403 -165.872134) (xy 419.245208 -165.836446)
			(xy 419.209512 -165.795259) (xy 419.180041 -165.749411) (xy 419.157395 -165.699836) (xy 419.142034 -165.647543)
			(xy 419.134271 -165.593595) (xy 419.133782 -165.566344) (xy 419.134216 -165.540953) (xy 419.14097 -165.490622)
			(xy 419.147244 -165.466014) (xy 419.150657 -165.451361) (xy 419.149744 -165.421304) (xy 419.14012 -165.392815)
			(xy 419.122618 -165.368362) (xy 419.098755 -165.350064) (xy 419.070599 -165.339507) (xy 419.040588 -165.337604)
			(xy 419.025832 -165.340538) (xy 419.004238 -165.345297) (xy 418.960312 -165.350394) (xy 418.938202 -165.350698)
			(xy 418.910951 -165.350224) (xy 418.857003 -165.342468) (xy 418.804708 -165.327113) (xy 418.755131 -165.304473)
			(xy 418.70928 -165.275007) (xy 418.668089 -165.239315) (xy 418.632397 -165.198125) (xy 418.602931 -165.152275)
			(xy 418.580289 -165.102698) (xy 418.564933 -165.050404) (xy 418.557176 -164.996456) (xy 418.557175 -164.941953)
			(xy 410.18968 -164.941953) (xy 410.18968 -165.787957) (xy 416.453709 -165.787957) (xy 416.453709 -165.733443)
			(xy 416.461468 -165.679483) (xy 416.476827 -165.627176) (xy 416.499474 -165.577588) (xy 416.528948 -165.531728)
			(xy 416.56465 -165.49053) (xy 416.605851 -165.454832) (xy 416.651713 -165.425361) (xy 416.701302 -165.402717)
			(xy 416.75361 -165.387362) (xy 416.807571 -165.379607) (xy 416.834828 -165.379146) (xy 416.862199 -165.379584)
			(xy 416.91638 -165.387407) (xy 416.968884 -165.402902) (xy 417.01863 -165.42575) (xy 417.064596 -165.455481)
			(xy 417.085526 -165.473126) (xy 417.096854 -165.482362) (xy 417.123411 -165.494538) (xy 417.152328 -165.498711)
			(xy 417.181245 -165.494538) (xy 417.207802 -165.482362) (xy 417.21913 -165.473126) (xy 417.240081 -165.45551)
			(xy 417.286048 -165.425794) (xy 417.335791 -165.402953) (xy 417.388287 -165.387457) (xy 417.44246 -165.379623)
			(xy 417.469828 -165.379146) (xy 417.497075 -165.379726) (xy 417.551013 -165.387485) (xy 417.603298 -165.402841)
			(xy 417.652865 -165.425481) (xy 417.698707 -165.454944) (xy 417.739889 -165.490631) (xy 417.775573 -165.531816)
			(xy 417.805033 -165.577659) (xy 417.827669 -165.627228) (xy 417.843021 -165.679515) (xy 417.850776 -165.733453)
			(xy 417.850776 -165.787947) (xy 417.843021 -165.841885) (xy 417.827669 -165.894172) (xy 417.805033 -165.943741)
			(xy 417.775573 -165.989584) (xy 417.739889 -166.030769) (xy 417.698707 -166.066456) (xy 417.652865 -166.095919)
			(xy 417.603298 -166.118559) (xy 417.551013 -166.133915) (xy 417.497075 -166.141674) (xy 417.469828 -166.142162)
			(xy 417.442458 -166.141689) (xy 417.388279 -166.133874) (xy 417.335775 -166.118387) (xy 417.286028 -166.095547)
			(xy 417.240062 -166.065823) (xy 417.21913 -166.048182) (xy 417.207802 -166.038946) (xy 417.181245 -166.02677)
			(xy 417.152328 -166.022597) (xy 417.123411 -166.02677) (xy 417.096854 -166.038946) (xy 417.085526 -166.048182)
			(xy 417.064593 -166.06582) (xy 417.01862 -166.095532) (xy 416.968873 -166.118369) (xy 416.916373 -166.13386)
			(xy 416.862197 -166.141688) (xy 416.834828 -166.142162) (xy 416.807571 -166.141793) (xy 416.75361 -166.134038)
			(xy 416.701302 -166.118683) (xy 416.651713 -166.096039) (xy 416.605851 -166.066568) (xy 416.56465 -166.03087)
			(xy 416.528948 -165.989672) (xy 416.499474 -165.943812) (xy 416.476827 -165.894224) (xy 416.461468 -165.841917)
			(xy 416.453709 -165.787957) (xy 410.18968 -165.787957) (xy 410.18968 -170.156378) (xy 417.4998 -170.156378)
			(xy 417.500317 -170.129048) (xy 417.50828 -170.074971) (xy 417.524061 -170.022638) (xy 417.547322 -169.973175)
			(xy 417.577563 -169.927642) (xy 417.614133 -169.887018) (xy 417.656249 -169.852176) (xy 417.679378 -169.837608)
			(xy 417.691578 -169.82965) (xy 417.711251 -169.808189) (xy 417.724061 -169.782045) (xy 417.728962 -169.753347)
			(xy 417.725556 -169.724434) (xy 417.720272 -169.710862) (xy 417.710777 -169.687654) (xy 417.697428 -169.63932)
			(xy 417.690702 -169.58963) (xy 417.6903 -169.564558) (xy 417.690724 -169.539489) (xy 417.697474 -169.489806)
			(xy 417.710806 -169.441471) (xy 417.720272 -169.418254) (xy 417.725563 -169.404687) (xy 417.728937 -169.375773)
			(xy 417.724027 -169.347079) (xy 417.711231 -169.32093) (xy 417.691587 -169.299447) (xy 417.679378 -169.291508)
			(xy 417.656281 -169.276887) (xy 417.61416 -169.24205) (xy 417.57758 -169.201433) (xy 417.547327 -169.155907)
			(xy 417.52405 -169.106451) (xy 417.508247 -169.054124) (xy 417.500259 -169.00005) (xy 417.500256 -168.945389)
			(xy 417.508238 -168.891314) (xy 417.524036 -168.838986) (xy 417.547308 -168.789527) (xy 417.577556 -168.743998)
			(xy 417.614131 -168.703377) (xy 417.656249 -168.668536) (xy 417.679378 -168.653968) (xy 417.691605 -168.646048)
			(xy 417.711279 -168.624577) (xy 417.724084 -168.598423) (xy 417.728979 -168.569716) (xy 417.725563 -168.540796)
			(xy 417.720272 -168.527222) (xy 417.710796 -168.504007) (xy 417.69744 -168.455677) (xy 417.690706 -168.405989)
			(xy 417.6903 -168.380918) (xy 417.690766 -168.354075) (xy 417.698468 -168.300945) (xy 417.713716 -168.24947)
			(xy 417.736193 -168.200717) (xy 417.765435 -168.155694) (xy 417.800836 -168.115334) (xy 417.841662 -168.080472)
			(xy 417.887069 -168.051831) (xy 417.936117 -168.030002) (xy 417.961826 -168.02227) (xy 417.976329 -168.01762)
			(xy 418.0019 -168.001103) (xy 418.021469 -167.977785) (xy 418.033299 -167.949737) (xy 418.03634 -167.919448)
			(xy 418.030322 -167.889608) (xy 418.023548 -167.875966) (xy 418.00892 -167.847818) (xy 417.988191 -167.787868)
			(xy 417.977691 -167.72531) (xy 417.977066 -167.693594) (xy 417.977291 -167.675575) (xy 417.980722 -167.6397)
			(xy 417.983924 -167.621966) (xy 417.986322 -167.606764) (xy 417.982784 -167.576201) (xy 417.97031 -167.548077)
			(xy 417.95003 -167.524941) (xy 417.923782 -167.508889) (xy 417.908994 -167.504618) (xy 417.881967 -167.497164)
			(xy 417.830242 -167.475542) (xy 417.782237 -167.446585) (xy 417.738984 -167.410917) (xy 417.701416 -167.369305)
			(xy 417.670339 -167.322645) (xy 417.646423 -167.27194) (xy 417.630183 -167.218282) (xy 417.621967 -167.162825)
			(xy 417.621466 -167.134794) (xy 417.621972 -167.107544) (xy 417.629729 -167.053598) (xy 417.645083 -167.001305)
			(xy 417.667723 -166.95173) (xy 417.697188 -166.905881) (xy 417.732877 -166.864691) (xy 417.774065 -166.829)
			(xy 417.819912 -166.799533) (xy 417.869487 -166.77689) (xy 417.921779 -166.761533) (xy 417.975724 -166.753774)
			(xy 418.002974 -166.753286) (xy 418.030548 -166.753774) (xy 418.085119 -166.761723) (xy 418.137979 -166.777444)
			(xy 418.188024 -166.80061) (xy 418.234215 -166.830738) (xy 418.275587 -166.867201) (xy 418.293804 -166.887906)
			(xy 418.303702 -166.898804) (xy 418.328352 -166.914879) (xy 418.35656 -166.923263) (xy 418.385988 -166.923263)
			(xy 418.414196 -166.914879) (xy 418.438846 -166.898804) (xy 418.448744 -166.887906) (xy 418.466959 -166.8672)
			(xy 418.50833 -166.830735) (xy 418.55452 -166.800608) (xy 418.604567 -166.777445) (xy 418.657428 -166.761729)
			(xy 418.712 -166.753789) (xy 418.767148 -166.753789) (xy 418.82172 -166.761729) (xy 418.874581 -166.777445)
			(xy 418.924628 -166.800608) (xy 418.970818 -166.830735) (xy 419.012189 -166.8672) (xy 419.030404 -166.887906)
			(xy 419.040302 -166.898804) (xy 419.064952 -166.914879) (xy 419.09316 -166.923263) (xy 419.122588 -166.923263)
			(xy 419.150796 -166.914879) (xy 419.175446 -166.898804) (xy 419.185344 -166.887906) (xy 419.203582 -166.86722)
			(xy 419.244945 -166.830747) (xy 419.291129 -166.800612) (xy 419.341172 -166.777442) (xy 419.39403 -166.76172)
			(xy 419.448601 -166.753775) (xy 419.476174 -166.753286) (xy 419.503426 -166.753779) (xy 419.557375 -166.761533)
			(xy 419.609672 -166.776885) (xy 419.659252 -166.799524) (xy 419.705105 -166.828989) (xy 419.746298 -166.86468)
			(xy 419.781992 -166.905869) (xy 419.81146 -166.95172) (xy 419.834104 -167.001298) (xy 419.84946 -167.053593)
			(xy 419.857218 -167.107542) (xy 419.857682 -167.134794) (xy 419.857167 -167.16265) (xy 419.849043 -167.217766)
			(xy 419.832998 -167.271117) (xy 419.80937 -167.321571) (xy 419.778663 -167.368056) (xy 419.741526 -167.409585)
			(xy 419.69875 -167.445278) (xy 419.651241 -167.474376) (xy 419.600008 -167.496262) (xy 419.573202 -167.503856)
			(xy 419.559077 -167.508105) (xy 419.53393 -167.523501) (xy 419.514215 -167.545425) (xy 419.501566 -167.57206)
			(xy 419.497034 -167.601195) (xy 419.498526 -167.61587) (xy 419.5002 -167.628886) (xy 419.501977 -167.655071)
			(xy 419.502082 -167.668194) (xy 419.501988 -167.682343) (xy 419.499954 -167.710566) (xy 419.498018 -167.724582)
			(xy 419.496394 -167.737927) (xy 419.4995 -167.764623) (xy 419.509476 -167.789579) (xy 419.525629 -167.81106)
			(xy 419.546835 -167.827572) (xy 419.57162 -167.837966) (xy 419.584886 -167.840152) (xy 419.612039 -167.844237)
			(xy 419.664868 -167.859214) (xy 419.715004 -167.881609) (xy 419.761412 -167.910958) (xy 419.803135 -167.946656)
			(xy 419.839311 -167.987965) (xy 419.869192 -168.034033) (xy 419.892162 -168.083908) (xy 419.907746 -168.136561)
			(xy 419.915622 -168.190903) (xy 419.916102 -168.218358) (xy 419.915606 -168.24561) (xy 419.907854 -168.29956)
			(xy 419.892503 -168.351858) (xy 419.869865 -168.401438) (xy 419.840401 -168.447292) (xy 419.804711 -168.488485)
			(xy 419.763521 -168.524179) (xy 419.71767 -168.553648) (xy 419.668092 -168.576291) (xy 419.615795 -168.591647)
			(xy 419.561846 -168.599403) (xy 419.534594 -168.599866) (xy 419.507019 -168.599416) (xy 419.452445 -168.591462)
			(xy 419.399584 -168.575735) (xy 419.349538 -168.552562) (xy 419.303349 -168.522426) (xy 419.261979 -168.485955)
			(xy 419.243764 -168.465246) (xy 419.233866 -168.454348) (xy 419.209216 -168.438273) (xy 419.181008 -168.429889)
			(xy 419.15158 -168.429889) (xy 419.123372 -168.438273) (xy 419.098722 -168.454348) (xy 419.088824 -168.465246)
			(xy 419.070614 -168.485958) (xy 419.029244 -168.522426) (xy 418.983053 -168.552557) (xy 418.933005 -168.575722)
			(xy 418.880143 -168.591439) (xy 418.825569 -168.59938) (xy 418.797994 -168.599866) (xy 418.771493 -168.599405)
			(xy 418.719002 -168.592063) (xy 418.668034 -168.577521) (xy 418.619572 -168.556059) (xy 418.574549 -168.528091)
			(xy 418.5539 -168.511474) (xy 418.541717 -168.502082) (xy 418.51333 -168.490285) (xy 418.482719 -168.487451)
			(xy 418.452648 -168.493838) (xy 418.425831 -168.508868) (xy 418.404689 -168.531186) (xy 418.397436 -168.544748)
			(xy 418.385321 -168.56843) (xy 418.355402 -168.612413) (xy 418.319535 -168.651696) (xy 418.278448 -168.685482)
			(xy 418.255958 -168.699688) (xy 418.243751 -168.707635) (xy 418.224085 -168.729102) (xy 418.211281 -168.755249)
			(xy 418.206381 -168.783947) (xy 418.209783 -168.812861) (xy 418.215064 -168.826434) (xy 418.22456 -168.849641)
			(xy 418.237908 -168.897976) (xy 418.244633 -168.947666) (xy 418.245036 -168.972738) (xy 418.244615 -168.997807)
			(xy 418.237865 -169.047491) (xy 418.224531 -169.095825) (xy 418.215064 -169.119042) (xy 418.209854 -169.132631)
			(xy 418.206485 -169.161525) (xy 418.211389 -169.190198) (xy 418.224168 -169.21633) (xy 418.243789 -169.237805)
			(xy 418.255958 -169.245788) (xy 418.27905 -169.260416) (xy 418.321167 -169.295255) (xy 418.357742 -169.335872)
			(xy 418.387993 -169.381397) (xy 418.411268 -169.430852) (xy 418.427069 -169.483177) (xy 418.435057 -169.537249)
			(xy 418.43506 -169.591908) (xy 418.427078 -169.64598) (xy 418.411283 -169.698307) (xy 418.388014 -169.747765)
			(xy 418.357769 -169.793294) (xy 418.321198 -169.833915) (xy 418.279085 -169.868759) (xy 418.255958 -169.883328)
			(xy 418.243724 -169.891237) (xy 418.224058 -169.912714) (xy 418.211257 -169.938871) (xy 418.208732 -169.953686)
			(xy 426.587415 -169.953686) (xy 426.591451 -169.870239) (xy 426.603523 -169.787571) (xy 426.623516 -169.706454)
			(xy 426.651245 -169.627645) (xy 426.686451 -169.55188) (xy 426.728805 -169.479867) (xy 426.777911 -169.412278)
			(xy 426.833312 -169.349744) (xy 426.894489 -169.292849) (xy 426.960872 -169.242123) (xy 427.03184 -169.198042)
			(xy 427.106732 -169.161016) (xy 427.184848 -169.13139) (xy 427.265458 -169.109442) (xy 427.34781 -169.095377)
			(xy 427.431136 -169.089325) (xy 427.514656 -169.091344) (xy 427.597592 -169.101414) (xy 427.679168 -169.119442)
			(xy 427.758624 -169.145259) (xy 427.835217 -169.178624) (xy 427.908233 -169.219225) (xy 427.976989 -169.266684)
			(xy 428.040843 -169.320557) (xy 428.0992 -169.380342) (xy 428.151515 -169.445479) (xy 428.197298 -169.515362)
			(xy 428.236123 -169.589337) (xy 428.267628 -169.666714) (xy 428.291517 -169.746771) (xy 428.307568 -169.828759)
			(xy 428.315631 -169.911914) (xy 428.316136 -169.953686) (xy 428.315631 -169.995458) (xy 428.307568 -170.078613)
			(xy 428.291517 -170.160601) (xy 428.267628 -170.240658) (xy 428.236123 -170.318035) (xy 428.197298 -170.39201)
			(xy 428.151515 -170.461893) (xy 428.0992 -170.52703) (xy 428.040843 -170.586815) (xy 427.976989 -170.640688)
			(xy 427.908233 -170.688147) (xy 427.835217 -170.728748) (xy 427.758624 -170.762113) (xy 427.679168 -170.78793)
			(xy 427.597592 -170.805958) (xy 427.514656 -170.816028) (xy 427.431136 -170.818047) (xy 427.34781 -170.811995)
			(xy 427.265458 -170.79793) (xy 427.184848 -170.775982) (xy 427.106732 -170.746356) (xy 427.03184 -170.70933)
			(xy 426.960872 -170.665249) (xy 426.894489 -170.614523) (xy 426.833312 -170.557628) (xy 426.777911 -170.495094)
			(xy 426.728805 -170.427505) (xy 426.686451 -170.355492) (xy 426.651245 -170.279727) (xy 426.623516 -170.200918)
			(xy 426.603523 -170.119801) (xy 426.591451 -170.037133) (xy 426.587415 -169.953686) (xy 418.208732 -169.953686)
			(xy 418.206364 -169.967578) (xy 418.209777 -169.996499) (xy 418.215064 -170.010074) (xy 418.224541 -170.033289)
			(xy 418.237896 -170.081619) (xy 418.244629 -170.131307) (xy 418.245036 -170.156378) (xy 418.244515 -170.184263)
			(xy 418.236203 -170.23941) (xy 418.219765 -170.292702) (xy 418.195567 -170.342948) (xy 418.164151 -170.389027)
			(xy 418.126218 -170.429909) (xy 418.082616 -170.464681) (xy 418.034318 -170.492566) (xy 417.982403 -170.512941)
			(xy 417.928032 -170.525351) (xy 417.872418 -170.529519) (xy 417.816804 -170.525351) (xy 417.762433 -170.512941)
			(xy 417.710518 -170.492566) (xy 417.66222 -170.464681) (xy 417.618618 -170.429909) (xy 417.580685 -170.389027)
			(xy 417.549269 -170.342948) (xy 417.525071 -170.292702) (xy 417.508633 -170.23941) (xy 417.500321 -170.184263)
			(xy 417.4998 -170.156378) (xy 410.18968 -170.156378) (xy 410.18968 -171.087542) (xy 419.315646 -171.087542)
			(xy 419.316217 -171.060294) (xy 419.323967 -171.006352) (xy 419.339314 -170.954061) (xy 419.361947 -170.904487)
			(xy 419.391405 -170.858639) (xy 419.427087 -170.81745) (xy 419.468269 -170.781757) (xy 419.51411 -170.752289)
			(xy 419.563679 -170.729645) (xy 419.615966 -170.714285) (xy 419.669906 -170.706523) (xy 419.697154 -170.706034)
			(xy 419.727059 -170.706571) (xy 419.786138 -170.715883) (xy 419.814756 -170.724576) (xy 419.82866 -170.72863)
			(xy 419.857597 -170.72954) (xy 419.885621 -170.722274) (xy 419.910469 -170.707418) (xy 419.930134 -170.686171)
			(xy 419.943028 -170.660251) (xy 419.946074 -170.64609) (xy 419.951204 -170.620008) (xy 419.967775 -170.569501)
			(xy 419.991201 -170.521784) (xy 420.021027 -170.477784) (xy 420.056674 -170.438352) (xy 420.097452 -170.404253)
			(xy 420.142571 -170.376148) (xy 420.191156 -170.354581) (xy 420.242265 -170.339971) (xy 420.294908 -170.332601)
			(xy 420.321486 -170.332146) (xy 420.348736 -170.3327) (xy 420.402682 -170.340455) (xy 420.454975 -170.355808)
			(xy 420.504551 -170.378447) (xy 420.550401 -170.407911) (xy 420.59159 -170.4436) (xy 420.627281 -170.484788)
			(xy 420.656747 -170.530636) (xy 420.679387 -170.580211) (xy 420.694742 -170.632504) (xy 420.702499 -170.68645)
			(xy 420.702499 -170.74095) (xy 420.694742 -170.794896) (xy 420.679387 -170.847189) (xy 420.656747 -170.896764)
			(xy 420.627281 -170.942612) (xy 420.59159 -170.9838) (xy 420.550401 -171.019489) (xy 420.504551 -171.048953)
			(xy 420.454975 -171.071592) (xy 420.402682 -171.086945) (xy 420.348736 -171.0947) (xy 420.321486 -171.095162)
			(xy 420.291581 -171.094639) (xy 420.232502 -171.085318) (xy 420.203884 -171.07662) (xy 420.189967 -171.072614)
			(xy 420.161038 -171.071695) (xy 420.133019 -171.078952) (xy 420.108173 -171.093799) (xy 420.088508 -171.115036)
			(xy 420.075613 -171.140949) (xy 420.072566 -171.155106) (xy 420.06599 -171.187947) (xy 420.042863 -171.250798)
			(xy 420.026592 -171.280074) (xy 420.019587 -171.293057) (xy 420.012541 -171.321688) (xy 420.013975 -171.351137)
			(xy 420.023771 -171.378948) (xy 420.04111 -171.402795) (xy 420.064544 -171.42069) (xy 420.078154 -171.426378)
			(xy 420.104942 -171.437047) (xy 420.155182 -171.465341) (xy 420.20059 -171.500876) (xy 420.240131 -171.542842)
			(xy 420.272903 -171.590283) (xy 420.298159 -171.642117) (xy 420.315323 -171.697162) (xy 420.324005 -171.754164)
			(xy 420.324534 -171.782994) (xy 420.324048 -171.810245) (xy 420.316292 -171.864193) (xy 420.300937 -171.916488)
			(xy 420.278295 -171.966065) (xy 420.248829 -172.011915) (xy 420.213138 -172.053106) (xy 420.171947 -172.088797)
			(xy 420.126097 -172.118263) (xy 420.07652 -172.140905) (xy 420.024225 -172.15626) (xy 419.970277 -172.164016)
			(xy 419.915775 -172.164016) (xy 419.861827 -172.15626) (xy 419.809532 -172.140905) (xy 419.759955 -172.118263)
			(xy 419.714105 -172.088797) (xy 419.672914 -172.053106) (xy 419.637223 -172.011915) (xy 419.607757 -171.966065)
			(xy 419.585115 -171.916488) (xy 419.56976 -171.864193) (xy 419.562004 -171.810245) (xy 419.561518 -171.782994)
			(xy 419.56191 -171.757758) (xy 419.568529 -171.707724) (xy 419.581704 -171.659004) (xy 419.601202 -171.612452)
			(xy 419.613588 -171.590462) (xy 419.620627 -171.577499) (xy 419.627653 -171.548862) (xy 419.626205 -171.519412)
			(xy 419.616403 -171.491603) (xy 419.599064 -171.467754) (xy 419.575634 -171.449852) (xy 419.562026 -171.444158)
			(xy 419.535269 -171.433416) (xy 419.485027 -171.405136) (xy 419.439617 -171.369613) (xy 419.400072 -171.327658)
			(xy 419.367296 -171.280228) (xy 419.342035 -171.228402) (xy 419.324865 -171.173365) (xy 419.316178 -171.116369)
			(xy 419.315646 -171.087542) (xy 410.18968 -171.087542) (xy 410.18968 -172.82625) (xy 419.374572 -172.82625)
			(xy 419.374572 -172.77175) (xy 419.382328 -172.717803) (xy 419.397682 -172.66551) (xy 419.420321 -172.615933)
			(xy 419.449786 -172.570084) (xy 419.485475 -172.528893) (xy 419.526663 -172.493201) (xy 419.572511 -172.463734)
			(xy 419.622085 -172.441091) (xy 419.674378 -172.425733) (xy 419.728324 -172.417974) (xy 419.755574 -172.417486)
			(xy 419.78151 -172.417935) (xy 419.832905 -172.42496) (xy 419.882874 -172.438884) (xy 419.930495 -172.459451)
			(xy 419.97489 -172.48628) (xy 419.987115 -172.496156) (xy 426.563024 -172.496156) (xy 426.563024 -172.41146)
			(xy 426.571075 -172.327146) (xy 426.587104 -172.24398) (xy 426.610965 -172.162713) (xy 426.642444 -172.084083)
			(xy 426.681255 -172.008802) (xy 426.727045 -171.93755) (xy 426.779401 -171.870974) (xy 426.837849 -171.809676)
			(xy 426.901859 -171.754211) (xy 426.970851 -171.705082) (xy 427.044201 -171.662733) (xy 427.121244 -171.627549)
			(xy 427.201283 -171.599847) (xy 427.283592 -171.579879) (xy 427.367427 -171.567826) (xy 427.452028 -171.563796)
			(xy 427.536629 -171.567826) (xy 427.620464 -171.579879) (xy 427.702773 -171.599847) (xy 427.782812 -171.627549)
			(xy 427.859855 -171.662733) (xy 427.933205 -171.705082) (xy 428.002197 -171.754211) (xy 428.066207 -171.809676)
			(xy 428.124655 -171.870974) (xy 428.177011 -171.93755) (xy 428.222801 -172.008802) (xy 428.261612 -172.084083)
			(xy 428.293091 -172.162713) (xy 428.316952 -172.24398) (xy 428.332981 -172.327146) (xy 428.341032 -172.41146)
			(xy 428.341536 -172.453808) (xy 428.341032 -172.496156) (xy 428.332981 -172.58047) (xy 428.316952 -172.663636)
			(xy 428.293091 -172.744903) (xy 428.261612 -172.823533) (xy 428.222801 -172.898814) (xy 428.177011 -172.970066)
			(xy 428.124655 -173.036642) (xy 428.066207 -173.09794) (xy 428.002197 -173.153405) (xy 427.933205 -173.202534)
			(xy 427.859855 -173.244883) (xy 427.782812 -173.280067) (xy 427.702773 -173.307769) (xy 427.620464 -173.327737)
			(xy 427.536629 -173.33979) (xy 427.452028 -173.343821) (xy 427.367427 -173.33979) (xy 427.283592 -173.327737)
			(xy 427.201283 -173.307769) (xy 427.121244 -173.280067) (xy 427.044201 -173.244883) (xy 426.970851 -173.202534)
			(xy 426.901859 -173.153405) (xy 426.837849 -173.09794) (xy 426.779401 -173.036642) (xy 426.727045 -172.970066)
			(xy 426.681255 -172.898814) (xy 426.642444 -172.823533) (xy 426.610965 -172.744903) (xy 426.587104 -172.663636)
			(xy 426.571075 -172.58047) (xy 426.563024 -172.496156) (xy 419.987115 -172.496156) (xy 420.015241 -172.518878)
			(xy 420.050803 -172.556642) (xy 420.066216 -172.577506) (xy 420.075441 -172.589618) (xy 420.099609 -172.608114)
			(xy 420.128159 -172.618654) (xy 420.158548 -172.620298) (xy 420.188068 -172.6129) (xy 420.201344 -172.605446)
			(xy 420.223766 -172.592408) (xy 420.271398 -172.571875) (xy 420.321372 -172.557986) (xy 420.372767 -172.550998)
			(xy 420.398702 -172.550582) (xy 420.425952 -172.551088) (xy 420.479898 -172.558845) (xy 420.532192 -172.5742)
			(xy 420.581767 -172.59684) (xy 420.627616 -172.626306) (xy 420.668805 -172.661997) (xy 420.704495 -172.703186)
			(xy 420.733961 -172.749035) (xy 420.756601 -172.79861) (xy 420.771956 -172.850904) (xy 420.779712 -172.90485)
			(xy 420.779712 -172.95935) (xy 420.771956 -173.013296) (xy 420.756601 -173.06559) (xy 420.733961 -173.115165)
			(xy 420.704495 -173.161014) (xy 420.668805 -173.202203) (xy 420.627616 -173.237894) (xy 420.581767 -173.26736)
			(xy 420.532192 -173.29) (xy 420.479898 -173.305355) (xy 420.425952 -173.313112) (xy 420.398702 -173.313598)
			(xy 420.372765 -173.313174) (xy 420.321369 -173.306145) (xy 420.271399 -173.292217) (xy 420.223778 -173.271647)
			(xy 420.179382 -173.244813) (xy 420.139033 -173.212212) (xy 420.103472 -173.174444) (xy 420.08806 -173.153578)
			(xy 420.07886 -173.141445) (xy 420.054684 -173.122952) (xy 420.026127 -173.112417) (xy 419.995733 -173.110778)
			(xy 419.966209 -173.118181) (xy 419.952932 -173.125638) (xy 419.930497 -173.138654) (xy 419.88287 -173.15919)
			(xy 419.8329 -173.173085) (xy 419.781507 -173.180081) (xy 419.755574 -173.180502) (xy 419.728324 -173.180026)
			(xy 419.674378 -173.172267) (xy 419.622085 -173.156909) (xy 419.572511 -173.134266) (xy 419.526663 -173.104799)
			(xy 419.485475 -173.069107) (xy 419.449786 -173.027916) (xy 419.420321 -172.982067) (xy 419.397682 -172.93249)
			(xy 419.382328 -172.880197) (xy 419.374572 -172.82625) (xy 410.18968 -172.82625) (xy 410.18968 -173.577953)
			(xy 418.557175 -173.577953) (xy 418.564931 -173.524006) (xy 418.580286 -173.471711) (xy 418.602926 -173.422133)
			(xy 418.632392 -173.376282) (xy 418.668083 -173.335091) (xy 418.709272 -173.299399) (xy 418.755122 -173.269932)
			(xy 418.804699 -173.24729) (xy 418.856994 -173.231934) (xy 418.910941 -173.224176) (xy 418.965444 -173.224175)
			(xy 419.019392 -173.231931) (xy 419.071687 -173.247285) (xy 419.121265 -173.269925) (xy 419.167116 -173.29939)
			(xy 419.208307 -173.335081) (xy 419.243999 -173.37627) (xy 419.273467 -173.42212) (xy 419.296109 -173.471697)
			(xy 419.311466 -173.523991) (xy 419.319224 -173.577939) (xy 419.31971 -173.60519) (xy 419.319282 -173.630581)
			(xy 419.312524 -173.680913) (xy 419.306248 -173.70552) (xy 419.302808 -173.720167) (xy 419.303729 -173.750225)
			(xy 419.31336 -173.778715) (xy 419.330866 -173.803167) (xy 419.354731 -173.821465) (xy 419.38289 -173.832023)
			(xy 419.412902 -173.833929) (xy 419.42766 -173.830996) (xy 419.449255 -173.826239) (xy 419.49318 -173.82114)
			(xy 419.51529 -173.820836) (xy 419.542541 -173.821267) (xy 419.59649 -173.829022) (xy 419.648785 -173.844376)
			(xy 419.698364 -173.867015) (xy 419.744216 -173.89648) (xy 419.785408 -173.93217) (xy 419.821101 -173.973359)
			(xy 419.85057 -174.019209) (xy 419.873213 -174.068785) (xy 419.888571 -174.12108) (xy 419.896331 -174.175027)
			(xy 419.896334 -174.22953) (xy 419.88858 -174.283479) (xy 419.873228 -174.335775) (xy 419.85059 -174.385354)
			(xy 419.821127 -174.431207) (xy 419.785438 -174.4724) (xy 419.74425 -174.508094) (xy 419.698401 -174.537564)
			(xy 419.648825 -174.560209) (xy 419.596532 -174.575569) (xy 419.542584 -174.58333) (xy 419.488081 -174.583335)
			(xy 419.434132 -174.575583) (xy 419.381836 -174.560232) (xy 419.332256 -174.537596) (xy 419.286403 -174.508134)
			(xy 419.245208 -174.472446) (xy 419.209512 -174.431259) (xy 419.180041 -174.385411) (xy 419.157395 -174.335836)
			(xy 419.142034 -174.283543) (xy 419.134271 -174.229595) (xy 419.133782 -174.202344) (xy 419.134216 -174.176953)
			(xy 419.14097 -174.126622) (xy 419.147244 -174.102014) (xy 419.150657 -174.087361) (xy 419.149744 -174.057304)
			(xy 419.14012 -174.028815) (xy 419.122618 -174.004362) (xy 419.098755 -173.986064) (xy 419.070599 -173.975507)
			(xy 419.040588 -173.973604) (xy 419.025832 -173.976538) (xy 419.004238 -173.981297) (xy 418.960312 -173.986394)
			(xy 418.938202 -173.986698) (xy 418.910951 -173.986224) (xy 418.857003 -173.978468) (xy 418.804708 -173.963113)
			(xy 418.755131 -173.940473) (xy 418.70928 -173.911007) (xy 418.668089 -173.875315) (xy 418.632397 -173.834125)
			(xy 418.602931 -173.788275) (xy 418.580289 -173.738698) (xy 418.564933 -173.686404) (xy 418.557176 -173.632456)
			(xy 418.557175 -173.577953) (xy 410.18968 -173.577953) (xy 410.18968 -174.423957) (xy 416.453709 -174.423957)
			(xy 416.453709 -174.369443) (xy 416.461468 -174.315483) (xy 416.476827 -174.263176) (xy 416.499474 -174.213588)
			(xy 416.528948 -174.167728) (xy 416.56465 -174.12653) (xy 416.605851 -174.090832) (xy 416.651713 -174.061361)
			(xy 416.701302 -174.038717) (xy 416.75361 -174.023362) (xy 416.807571 -174.015607) (xy 416.834828 -174.015146)
			(xy 416.862199 -174.015584) (xy 416.91638 -174.023407) (xy 416.968884 -174.038902) (xy 417.01863 -174.06175)
			(xy 417.064596 -174.091481) (xy 417.085526 -174.109126) (xy 417.096854 -174.118362) (xy 417.123411 -174.130538)
			(xy 417.152328 -174.134711) (xy 417.181245 -174.130538) (xy 417.207802 -174.118362) (xy 417.21913 -174.109126)
			(xy 417.240081 -174.09151) (xy 417.286048 -174.061794) (xy 417.335791 -174.038953) (xy 417.388287 -174.023457)
			(xy 417.44246 -174.015623) (xy 417.469828 -174.015146) (xy 417.497075 -174.015726) (xy 417.551013 -174.023485)
			(xy 417.603298 -174.038841) (xy 417.652865 -174.061481) (xy 417.698707 -174.090944) (xy 417.739889 -174.126631)
			(xy 417.775573 -174.167816) (xy 417.805033 -174.213659) (xy 417.827669 -174.263228) (xy 417.843021 -174.315515)
			(xy 417.850776 -174.369453) (xy 417.850776 -174.423947) (xy 417.843021 -174.477885) (xy 417.827669 -174.530172)
			(xy 417.805033 -174.579741) (xy 417.775573 -174.625584) (xy 417.739889 -174.666769) (xy 417.698707 -174.702456)
			(xy 417.652865 -174.731919) (xy 417.603298 -174.754559) (xy 417.551013 -174.769915) (xy 417.497075 -174.777674)
			(xy 417.469828 -174.778162) (xy 417.442458 -174.777689) (xy 417.388279 -174.769874) (xy 417.335775 -174.754387)
			(xy 417.286028 -174.731547) (xy 417.240062 -174.701823) (xy 417.21913 -174.684182) (xy 417.207802 -174.674946)
			(xy 417.181245 -174.66277) (xy 417.152328 -174.658597) (xy 417.123411 -174.66277) (xy 417.096854 -174.674946)
			(xy 417.085526 -174.684182) (xy 417.064593 -174.70182) (xy 417.01862 -174.731532) (xy 416.968873 -174.754369)
			(xy 416.916373 -174.76986) (xy 416.862197 -174.777688) (xy 416.834828 -174.778162) (xy 416.807571 -174.777793)
			(xy 416.75361 -174.770038) (xy 416.701302 -174.754683) (xy 416.651713 -174.732039) (xy 416.605851 -174.702568)
			(xy 416.56465 -174.66687) (xy 416.528948 -174.625672) (xy 416.499474 -174.579812) (xy 416.476827 -174.530224)
			(xy 416.461468 -174.477917) (xy 416.453709 -174.423957) (xy 410.18968 -174.423957) (xy 410.18968 -178.792378)
			(xy 417.4998 -178.792378) (xy 417.500317 -178.765048) (xy 417.50828 -178.710971) (xy 417.524061 -178.658638)
			(xy 417.547322 -178.609175) (xy 417.577563 -178.563642) (xy 417.614133 -178.523018) (xy 417.656249 -178.488176)
			(xy 417.679378 -178.473608) (xy 417.691578 -178.46565) (xy 417.711251 -178.444189) (xy 417.724061 -178.418045)
			(xy 417.728962 -178.389347) (xy 417.725556 -178.360434) (xy 417.720272 -178.346862) (xy 417.710777 -178.323654)
			(xy 417.697428 -178.27532) (xy 417.690702 -178.22563) (xy 417.6903 -178.200558) (xy 417.690724 -178.175489)
			(xy 417.697474 -178.125806) (xy 417.710806 -178.077471) (xy 417.720272 -178.054254) (xy 417.725563 -178.040687)
			(xy 417.728937 -178.011773) (xy 417.724027 -177.983079) (xy 417.711231 -177.95693) (xy 417.691587 -177.935447)
			(xy 417.679378 -177.927508) (xy 417.656281 -177.912887) (xy 417.61416 -177.87805) (xy 417.57758 -177.837433)
			(xy 417.547327 -177.791907) (xy 417.52405 -177.742451) (xy 417.508247 -177.690124) (xy 417.500259 -177.63605)
			(xy 417.500256 -177.581389) (xy 417.508238 -177.527314) (xy 417.524036 -177.474986) (xy 417.547308 -177.425527)
			(xy 417.577556 -177.379998) (xy 417.614131 -177.339377) (xy 417.656249 -177.304536) (xy 417.679378 -177.289968)
			(xy 417.691605 -177.282048) (xy 417.711279 -177.260577) (xy 417.724084 -177.234423) (xy 417.728979 -177.205716)
			(xy 417.725563 -177.176796) (xy 417.720272 -177.163222) (xy 417.710796 -177.140007) (xy 417.69744 -177.091677)
			(xy 417.690706 -177.041989) (xy 417.6903 -177.016918) (xy 417.690766 -176.990075) (xy 417.698468 -176.936945)
			(xy 417.713716 -176.88547) (xy 417.736193 -176.836717) (xy 417.765435 -176.791694) (xy 417.800836 -176.751334)
			(xy 417.841662 -176.716472) (xy 417.887069 -176.687831) (xy 417.936117 -176.666002) (xy 417.961826 -176.65827)
			(xy 417.976329 -176.65362) (xy 418.0019 -176.637103) (xy 418.021469 -176.613785) (xy 418.033299 -176.585737)
			(xy 418.03634 -176.555448) (xy 418.030322 -176.525608) (xy 418.023548 -176.511966) (xy 418.00892 -176.483818)
			(xy 417.988191 -176.423868) (xy 417.977691 -176.36131) (xy 417.977066 -176.329594) (xy 417.977291 -176.311575)
			(xy 417.980722 -176.2757) (xy 417.983924 -176.257966) (xy 417.986322 -176.242764) (xy 417.982784 -176.212201)
			(xy 417.97031 -176.184077) (xy 417.95003 -176.160941) (xy 417.923782 -176.144889) (xy 417.908994 -176.140618)
			(xy 417.881967 -176.133164) (xy 417.830242 -176.111542) (xy 417.782237 -176.082585) (xy 417.738984 -176.046917)
			(xy 417.701416 -176.005305) (xy 417.670339 -175.958645) (xy 417.646423 -175.90794) (xy 417.630183 -175.854282)
			(xy 417.621967 -175.798825) (xy 417.621466 -175.770794) (xy 417.621972 -175.743544) (xy 417.629729 -175.689598)
			(xy 417.645083 -175.637305) (xy 417.667723 -175.58773) (xy 417.697188 -175.541881) (xy 417.732877 -175.500691)
			(xy 417.774065 -175.465) (xy 417.819912 -175.435533) (xy 417.869487 -175.41289) (xy 417.921779 -175.397533)
			(xy 417.975724 -175.389774) (xy 418.002974 -175.389286) (xy 418.030548 -175.389774) (xy 418.085119 -175.397723)
			(xy 418.137979 -175.413444) (xy 418.188024 -175.43661) (xy 418.234215 -175.466738) (xy 418.275587 -175.503201)
			(xy 418.293804 -175.523906) (xy 418.303702 -175.534804) (xy 418.328352 -175.550879) (xy 418.35656 -175.559263)
			(xy 418.385988 -175.559263) (xy 418.414196 -175.550879) (xy 418.438846 -175.534804) (xy 418.448744 -175.523906)
			(xy 418.466959 -175.5032) (xy 418.50833 -175.466735) (xy 418.55452 -175.436608) (xy 418.604567 -175.413445)
			(xy 418.657428 -175.397729) (xy 418.712 -175.389789) (xy 418.767148 -175.389789) (xy 418.82172 -175.397729)
			(xy 418.874581 -175.413445) (xy 418.924628 -175.436608) (xy 418.970818 -175.466735) (xy 419.012189 -175.5032)
			(xy 419.030404 -175.523906) (xy 419.040302 -175.534804) (xy 419.064952 -175.550879) (xy 419.09316 -175.559263)
			(xy 419.122588 -175.559263) (xy 419.150796 -175.550879) (xy 419.175446 -175.534804) (xy 419.185344 -175.523906)
			(xy 419.203582 -175.50322) (xy 419.244945 -175.466747) (xy 419.291129 -175.436612) (xy 419.341172 -175.413442)
			(xy 419.39403 -175.39772) (xy 419.448601 -175.389775) (xy 419.476174 -175.389286) (xy 419.503426 -175.389779)
			(xy 419.557375 -175.397533) (xy 419.609672 -175.412885) (xy 419.659252 -175.435524) (xy 419.705105 -175.464989)
			(xy 419.746298 -175.50068) (xy 419.781992 -175.541869) (xy 419.81146 -175.58772) (xy 419.815725 -175.597058)
			(xy 434.095902 -175.597058) (xy 434.099991 -175.541176) (xy 434.112174 -175.486486) (xy 434.13219 -175.434152)
			(xy 434.159613 -175.38529) (xy 434.193858 -175.340942) (xy 434.234194 -175.302052) (xy 434.279764 -175.26945)
			(xy 434.329595 -175.243831) (xy 434.382625 -175.225739) (xy 434.437723 -175.215562) (xy 434.493717 -175.213516)
			(xy 434.549412 -175.219644) (xy 434.603621 -175.233816) (xy 434.655189 -175.25573) (xy 434.703017 -175.284919)
			(xy 434.746085 -175.32076) (xy 434.783475 -175.36249) (xy 434.814391 -175.40922) (xy 434.838174 -175.459953)
			(xy 434.854316 -175.513609) (xy 434.862475 -175.569043) (xy 434.862986 -175.597058) (xy 434.862601 -175.61814)
			(xy 435.603902 -175.61814) (xy 435.607973 -175.562518) (xy 435.620099 -175.508081) (xy 435.640022 -175.45599)
			(xy 435.667318 -175.407355) (xy 435.701404 -175.363212) (xy 435.741553 -175.324503) (xy 435.786911 -175.292052)
			(xy 435.836511 -175.266551) (xy 435.889295 -175.248544) (xy 435.944138 -175.238414) (xy 435.999872 -175.236377)
			(xy 436.055309 -175.242477) (xy 436.109266 -175.256583) (xy 436.160595 -175.278395) (xy 436.208201 -175.307449)
			(xy 436.251069 -175.343124) (xy 436.288286 -175.384661) (xy 436.319059 -175.431174) (xy 436.342731 -175.481671)
			(xy 436.358799 -175.535078) (xy 436.366919 -175.590254) (xy 436.367428 -175.61814) (xy 436.366919 -175.646026)
			(xy 436.358799 -175.701202) (xy 436.342731 -175.754609) (xy 436.319059 -175.805106) (xy 436.288286 -175.851619)
			(xy 436.251069 -175.893156) (xy 436.208201 -175.928831) (xy 436.160595 -175.957885) (xy 436.109266 -175.979697)
			(xy 436.055309 -175.993803) (xy 435.999872 -175.999903) (xy 435.944138 -175.997866) (xy 435.889295 -175.987736)
			(xy 435.836511 -175.969729) (xy 435.786911 -175.944228) (xy 435.741553 -175.911777) (xy 435.701404 -175.873068)
			(xy 435.667318 -175.828925) (xy 435.640022 -175.78029) (xy 435.620099 -175.728199) (xy 435.607973 -175.673762)
			(xy 435.603902 -175.61814) (xy 434.862601 -175.61814) (xy 434.862475 -175.625073) (xy 434.854316 -175.680507)
			(xy 434.838174 -175.734163) (xy 434.814391 -175.784896) (xy 434.783475 -175.831626) (xy 434.746085 -175.873356)
			(xy 434.703017 -175.909197) (xy 434.655189 -175.938386) (xy 434.603621 -175.9603) (xy 434.549412 -175.974472)
			(xy 434.493717 -175.9806) (xy 434.437723 -175.978554) (xy 434.382625 -175.968377) (xy 434.329595 -175.950285)
			(xy 434.279764 -175.924666) (xy 434.234194 -175.892064) (xy 434.193858 -175.853174) (xy 434.159613 -175.808826)
			(xy 434.13219 -175.759964) (xy 434.112174 -175.70763) (xy 434.099991 -175.65294) (xy 434.095902 -175.597058)
			(xy 419.815725 -175.597058) (xy 419.834104 -175.637298) (xy 419.84946 -175.689593) (xy 419.857218 -175.743542)
			(xy 419.857682 -175.770794) (xy 419.857167 -175.79865) (xy 419.849043 -175.853766) (xy 419.832998 -175.907117)
			(xy 419.80937 -175.957571) (xy 419.778663 -176.004056) (xy 419.765342 -176.018952) (xy 444.68161 -176.018952)
			(xy 444.682033 -175.991699) (xy 444.689797 -175.937748) (xy 444.705159 -175.885451) (xy 444.727807 -175.835872)
			(xy 444.75728 -175.790021) (xy 444.792978 -175.748831) (xy 444.834174 -175.71314) (xy 444.88003 -175.683675)
			(xy 444.929613 -175.661036) (xy 444.981912 -175.645683) (xy 445.035865 -175.637929) (xy 445.063118 -175.637444)
			(xy 445.08913 -175.637893) (xy 445.140672 -175.644964) (xy 445.190775 -175.658973) (xy 445.238509 -175.67966)
			(xy 445.28299 -175.706641) (xy 445.323393 -175.739415) (xy 445.341502 -175.758094) (xy 445.351381 -175.768042)
			(xy 445.37536 -175.78255) (xy 445.402382 -175.789987) (xy 445.430407 -175.789795) (xy 445.457324 -175.781987)
			(xy 445.481102 -175.767151) (xy 445.490854 -175.757078) (xy 445.509036 -175.737781) (xy 445.549776 -175.703855)
			(xy 445.594821 -175.675895) (xy 445.643302 -175.65444) (xy 445.694287 -175.639904) (xy 445.746794 -175.632565)
			(xy 445.773302 -175.63211) (xy 445.800556 -175.632554) (xy 445.854508 -175.640311) (xy 445.906808 -175.655668)
			(xy 445.956389 -175.678312) (xy 446.002243 -175.707782) (xy 446.043436 -175.743478) (xy 446.07913 -175.784673)
			(xy 446.108597 -175.830529) (xy 446.131239 -175.880111) (xy 446.146593 -175.932411) (xy 446.154348 -175.986364)
			(xy 446.15481 -176.013618) (xy 446.15429 -176.041314) (xy 446.146295 -176.096126) (xy 446.130461 -176.149206)
			(xy 446.10712 -176.19944) (xy 446.076763 -176.245773) (xy 446.040027 -176.28723) (xy 446.019174 -176.305464)
			(xy 446.012336 -176.311719) (xy 446.003266 -176.32786) (xy 446.000545 -176.346174) (xy 446.004531 -176.364255)
			(xy 446.014699 -176.379727) (xy 446.021968 -176.385474) (xy 446.049146 -176.407064) (xy 446.060474 -176.4163)
			(xy 446.087031 -176.428476) (xy 446.115948 -176.432649) (xy 446.144865 -176.428476) (xy 446.171422 -176.4163)
			(xy 446.18275 -176.407064) (xy 446.203685 -176.389429) (xy 446.249658 -176.359718) (xy 446.299405 -176.336882)
			(xy 446.351904 -176.32139) (xy 446.406079 -176.313559) (xy 446.433448 -176.313084) (xy 446.460696 -176.313589)
			(xy 446.514638 -176.321351) (xy 446.566926 -176.33671) (xy 446.616496 -176.359353) (xy 446.662339 -176.38882)
			(xy 446.703523 -176.424511) (xy 446.739209 -176.465699) (xy 446.76867 -176.511546) (xy 446.791307 -176.561119)
			(xy 446.806659 -176.613409) (xy 446.814414 -176.667352) (xy 446.814414 -176.721848) (xy 446.806659 -176.775791)
			(xy 446.791307 -176.828081) (xy 446.76867 -176.877654) (xy 446.739209 -176.923501) (xy 446.703523 -176.964689)
			(xy 446.662339 -177.00038) (xy 446.616496 -177.029847) (xy 446.566926 -177.05249) (xy 446.514638 -177.067849)
			(xy 446.460696 -177.075611) (xy 446.433448 -177.0761) (xy 446.406079 -177.075606) (xy 446.351901 -177.067795)
			(xy 446.299398 -177.052312) (xy 446.249651 -177.029477) (xy 446.203683 -176.999758) (xy 446.18275 -176.98212)
			(xy 446.171422 -176.972884) (xy 446.144865 -176.960708) (xy 446.115948 -176.956535) (xy 446.087031 -176.960708)
			(xy 446.060474 -176.972884) (xy 446.049146 -176.98212) (xy 446.02821 -176.999754) (xy 445.982238 -177.029466)
			(xy 445.932491 -177.052303) (xy 445.879992 -177.067795) (xy 445.825817 -177.075625) (xy 445.798448 -177.0761)
			(xy 445.772434 -177.075691) (xy 445.72089 -177.068614) (xy 445.670786 -177.054599) (xy 445.623051 -177.033904)
			(xy 445.578571 -177.006916) (xy 445.538171 -176.974133) (xy 445.520064 -176.95545) (xy 445.510219 -176.945464)
			(xy 445.486231 -176.930952) (xy 445.4592 -176.923515) (xy 445.431165 -176.923714) (xy 445.404242 -176.931534)
			(xy 445.380462 -176.946385) (xy 445.370712 -176.956466) (xy 445.352556 -176.975788) (xy 445.311809 -177.00971)
			(xy 445.266759 -177.037665) (xy 445.218272 -177.059116) (xy 445.167283 -177.073648) (xy 445.114774 -177.080982)
			(xy 445.088264 -177.081434) (xy 445.061013 -177.080956) (xy 445.007066 -177.073195) (xy 444.954773 -177.057837)
			(xy 444.905197 -177.035193) (xy 444.859349 -177.005726) (xy 444.818159 -176.970034) (xy 444.782468 -176.928843)
			(xy 444.753002 -176.882994) (xy 444.73036 -176.833417) (xy 444.715003 -176.781124) (xy 444.707244 -176.727177)
			(xy 444.706756 -176.699926) (xy 444.707283 -176.671461) (xy 444.715757 -176.615165) (xy 444.732506 -176.560755)
			(xy 444.757158 -176.509439) (xy 444.789165 -176.462358) (xy 444.808102 -176.4411) (xy 444.816772 -176.431026)
			(xy 444.829184 -176.407541) (xy 444.835101 -176.381646) (xy 444.834121 -176.3551) (xy 444.826309 -176.329712)
			(xy 444.812199 -176.307206) (xy 444.802768 -176.297844) (xy 444.784021 -176.279718) (xy 444.751106 -176.239272)
			(xy 444.724005 -176.194722) (xy 444.703222 -176.146895) (xy 444.689146 -176.096685) (xy 444.682038 -176.045025)
			(xy 444.68161 -176.018952) (xy 419.765342 -176.018952) (xy 419.741526 -176.045585) (xy 419.69875 -176.081278)
			(xy 419.651241 -176.110376) (xy 419.600008 -176.132262) (xy 419.573202 -176.139856) (xy 419.559077 -176.144105)
			(xy 419.53393 -176.159501) (xy 419.514215 -176.181425) (xy 419.501566 -176.20806) (xy 419.497034 -176.237195)
			(xy 419.498526 -176.25187) (xy 419.5002 -176.264886) (xy 419.501977 -176.291071) (xy 419.502082 -176.304194)
			(xy 419.501988 -176.318343) (xy 419.499954 -176.346566) (xy 419.498018 -176.360582) (xy 419.496394 -176.373927)
			(xy 419.4995 -176.400623) (xy 419.509476 -176.425579) (xy 419.525629 -176.44706) (xy 419.546835 -176.463572)
			(xy 419.57162 -176.473966) (xy 419.584886 -176.476152) (xy 419.612039 -176.480237) (xy 419.664868 -176.495214)
			(xy 419.715004 -176.517609) (xy 419.761412 -176.546958) (xy 419.803135 -176.582656) (xy 419.839311 -176.623965)
			(xy 419.869192 -176.670033) (xy 419.892162 -176.719908) (xy 419.907746 -176.772561) (xy 419.915622 -176.826903)
			(xy 419.916102 -176.854358) (xy 419.915606 -176.88161) (xy 419.912259 -176.904904) (xy 434.675278 -176.904904)
			(xy 434.679349 -176.849282) (xy 434.691475 -176.794845) (xy 434.711398 -176.742754) (xy 434.738694 -176.694119)
			(xy 434.77278 -176.649976) (xy 434.812929 -176.611267) (xy 434.858287 -176.578816) (xy 434.907887 -176.553315)
			(xy 434.960671 -176.535308) (xy 435.015514 -176.525178) (xy 435.071248 -176.523141) (xy 435.126685 -176.529241)
			(xy 435.180642 -176.543347) (xy 435.231971 -176.565159) (xy 435.279577 -176.594213) (xy 435.322445 -176.629888)
			(xy 435.359662 -176.671425) (xy 435.390435 -176.717938) (xy 435.414107 -176.768435) (xy 435.430175 -176.821842)
			(xy 435.438295 -176.877018) (xy 435.438804 -176.904904) (xy 435.438295 -176.93279) (xy 435.430175 -176.987966)
			(xy 435.414107 -177.041373) (xy 435.390435 -177.09187) (xy 435.359662 -177.138383) (xy 435.322445 -177.17992)
			(xy 435.279577 -177.215595) (xy 435.231971 -177.244649) (xy 435.180642 -177.266461) (xy 435.126685 -177.280567)
			(xy 435.071248 -177.286667) (xy 435.015514 -177.28463) (xy 434.960671 -177.2745) (xy 434.907887 -177.256493)
			(xy 434.858287 -177.230992) (xy 434.812929 -177.198541) (xy 434.77278 -177.159832) (xy 434.738694 -177.115689)
			(xy 434.711398 -177.067054) (xy 434.691475 -177.014963) (xy 434.679349 -176.960526) (xy 434.675278 -176.904904)
			(xy 419.912259 -176.904904) (xy 419.907854 -176.93556) (xy 419.892503 -176.987858) (xy 419.869865 -177.037438)
			(xy 419.840401 -177.083292) (xy 419.804711 -177.124485) (xy 419.763521 -177.160179) (xy 419.71767 -177.189648)
			(xy 419.668092 -177.212291) (xy 419.615795 -177.227647) (xy 419.561846 -177.235403) (xy 419.534594 -177.235866)
			(xy 419.507019 -177.235416) (xy 419.452445 -177.227462) (xy 419.399584 -177.211735) (xy 419.349538 -177.188562)
			(xy 419.303349 -177.158426) (xy 419.261979 -177.121955) (xy 419.243764 -177.101246) (xy 419.233866 -177.090348)
			(xy 419.209216 -177.074273) (xy 419.181008 -177.065889) (xy 419.15158 -177.065889) (xy 419.123372 -177.074273)
			(xy 419.098722 -177.090348) (xy 419.088824 -177.101246) (xy 419.070614 -177.121958) (xy 419.029244 -177.158426)
			(xy 418.983053 -177.188557) (xy 418.933005 -177.211722) (xy 418.880143 -177.227439) (xy 418.825569 -177.23538)
			(xy 418.797994 -177.235866) (xy 418.771493 -177.235405) (xy 418.719002 -177.228063) (xy 418.668034 -177.213521)
			(xy 418.619572 -177.192059) (xy 418.574549 -177.164091) (xy 418.5539 -177.147474) (xy 418.541717 -177.138082)
			(xy 418.51333 -177.126285) (xy 418.482719 -177.123451) (xy 418.452648 -177.129838) (xy 418.425831 -177.144868)
			(xy 418.404689 -177.167186) (xy 418.397436 -177.180748) (xy 418.385321 -177.20443) (xy 418.355402 -177.248413)
			(xy 418.319535 -177.287696) (xy 418.278448 -177.321482) (xy 418.255958 -177.335688) (xy 418.243751 -177.343635)
			(xy 418.224085 -177.365102) (xy 418.211281 -177.391249) (xy 418.206381 -177.419947) (xy 418.209783 -177.448861)
			(xy 418.215064 -177.462434) (xy 418.22456 -177.485641) (xy 418.237908 -177.533976) (xy 418.244633 -177.583666)
			(xy 418.245036 -177.608738) (xy 418.244615 -177.633807) (xy 418.237865 -177.683491) (xy 418.224531 -177.731825)
			(xy 418.215064 -177.755042) (xy 418.209854 -177.768631) (xy 418.206485 -177.797525) (xy 418.211389 -177.826198)
			(xy 418.224168 -177.85233) (xy 418.243789 -177.873805) (xy 418.255958 -177.881788) (xy 418.27905 -177.896416)
			(xy 418.321167 -177.931255) (xy 418.357742 -177.971872) (xy 418.387993 -178.017397) (xy 418.400677 -178.044348)
			(xy 434.953662 -178.044348) (xy 434.957733 -177.988726) (xy 434.969859 -177.934289) (xy 434.989782 -177.882198)
			(xy 435.017078 -177.833563) (xy 435.051164 -177.78942) (xy 435.091313 -177.750711) (xy 435.136671 -177.71826)
			(xy 435.186271 -177.692759) (xy 435.239055 -177.674752) (xy 435.293898 -177.664622) (xy 435.349632 -177.662585)
			(xy 435.405069 -177.668685) (xy 435.459026 -177.682791) (xy 435.510355 -177.704603) (xy 435.557961 -177.733657)
			(xy 435.600829 -177.769332) (xy 435.638046 -177.810869) (xy 435.668819 -177.857382) (xy 435.692491 -177.907879)
			(xy 435.708559 -177.961286) (xy 435.716679 -178.016462) (xy 435.717188 -178.044348) (xy 435.716679 -178.072234)
			(xy 435.708559 -178.12741) (xy 435.692491 -178.180817) (xy 435.668819 -178.231314) (xy 435.638046 -178.277827)
			(xy 435.600829 -178.319364) (xy 435.557961 -178.355039) (xy 435.510355 -178.384093) (xy 435.459026 -178.405905)
			(xy 435.405069 -178.420011) (xy 435.349632 -178.426111) (xy 435.293898 -178.424074) (xy 435.239055 -178.413944)
			(xy 435.186271 -178.395937) (xy 435.136671 -178.370436) (xy 435.091313 -178.337985) (xy 435.051164 -178.299276)
			(xy 435.017078 -178.255133) (xy 434.989782 -178.206498) (xy 434.969859 -178.154407) (xy 434.957733 -178.09997)
			(xy 434.953662 -178.044348) (xy 418.400677 -178.044348) (xy 418.411268 -178.066852) (xy 418.427069 -178.119177)
			(xy 418.435057 -178.173249) (xy 418.43506 -178.227908) (xy 418.427078 -178.28198) (xy 418.411283 -178.334307)
			(xy 418.388014 -178.383765) (xy 418.357769 -178.429294) (xy 418.321198 -178.469915) (xy 418.279085 -178.504759)
			(xy 418.255958 -178.519328) (xy 418.243724 -178.527237) (xy 418.224058 -178.548714) (xy 418.22228 -178.552348)
			(xy 430.915572 -178.552348) (xy 430.916058 -178.525097) (xy 430.923814 -178.471149) (xy 430.939169 -178.418854)
			(xy 430.961811 -178.369277) (xy 430.991277 -178.323427) (xy 431.026968 -178.282236) (xy 431.068159 -178.246545)
			(xy 431.114009 -178.217079) (xy 431.163586 -178.194437) (xy 431.215881 -178.179082) (xy 431.269829 -178.171326)
			(xy 431.324331 -178.171326) (xy 431.378279 -178.179082) (xy 431.430574 -178.194437) (xy 431.480151 -178.217079)
			(xy 431.526001 -178.246545) (xy 431.567192 -178.282236) (xy 431.602883 -178.323427) (xy 431.632349 -178.369277)
			(xy 431.654991 -178.418854) (xy 431.670346 -178.471149) (xy 431.678102 -178.525097) (xy 431.678588 -178.552348)
			(xy 431.678009 -178.582075) (xy 431.66878 -178.640807) (xy 431.652522 -178.691286) (xy 433.98897 -178.691286)
			(xy 433.993041 -178.635664) (xy 434.005167 -178.581227) (xy 434.02509 -178.529136) (xy 434.052386 -178.480501)
			(xy 434.086472 -178.436358) (xy 434.126621 -178.397649) (xy 434.171979 -178.365198) (xy 434.221579 -178.339697)
			(xy 434.274363 -178.32169) (xy 434.329206 -178.31156) (xy 434.38494 -178.309523) (xy 434.440377 -178.315623)
			(xy 434.494334 -178.329729) (xy 434.545663 -178.351541) (xy 434.593269 -178.380595) (xy 434.636137 -178.41627)
			(xy 434.673354 -178.457807) (xy 434.704127 -178.50432) (xy 434.727799 -178.554817) (xy 434.743867 -178.608224)
			(xy 434.751987 -178.6634) (xy 434.752496 -178.691286) (xy 434.751987 -178.719172) (xy 434.743867 -178.774348)
			(xy 434.727799 -178.827755) (xy 434.72424 -178.835348) (xy 444.707304 -178.835348) (xy 444.707304 -178.780852)
			(xy 444.715059 -178.726911) (xy 444.730411 -178.674623) (xy 444.753048 -178.625052) (xy 444.782509 -178.579206)
			(xy 444.818194 -178.53802) (xy 444.859377 -178.502331) (xy 444.90522 -178.472866) (xy 444.954789 -178.450224)
			(xy 445.007076 -178.434867) (xy 445.061016 -178.427107) (xy 445.088264 -178.426618) (xy 445.114278 -178.427013)
			(xy 445.165823 -178.434092) (xy 445.215928 -178.44811) (xy 445.263663 -178.468807) (xy 445.308143 -178.495798)
			(xy 445.348542 -178.528584) (xy 445.366648 -178.547268) (xy 445.376576 -178.557164) (xy 445.40054 -178.571678)
			(xy 445.42755 -178.579125) (xy 445.455566 -178.578943) (xy 445.482476 -178.571145) (xy 445.506249 -178.55632)
			(xy 445.516 -178.546252) (xy 445.534154 -178.526928) (xy 445.574901 -178.493005) (xy 445.619952 -178.46505)
			(xy 445.668438 -178.4436) (xy 445.719428 -178.429068) (xy 445.771938 -178.421735) (xy 445.798448 -178.421284)
			(xy 445.825818 -178.42176) (xy 445.879998 -178.429572) (xy 445.932501 -178.445058) (xy 445.982249 -178.467898)
			(xy 446.028215 -178.497622) (xy 446.049146 -178.515264) (xy 446.060474 -178.5245) (xy 446.087031 -178.536676)
			(xy 446.115948 -178.540849) (xy 446.144865 -178.536676) (xy 446.171422 -178.5245) (xy 446.18275 -178.515264)
			(xy 446.203685 -178.497629) (xy 446.249658 -178.467918) (xy 446.299405 -178.445082) (xy 446.351904 -178.42959)
			(xy 446.406079 -178.421759) (xy 446.433448 -178.421284) (xy 446.460696 -178.421789) (xy 446.514638 -178.429551)
			(xy 446.566926 -178.44491) (xy 446.616496 -178.467553) (xy 446.662339 -178.49702) (xy 446.703523 -178.532711)
			(xy 446.739209 -178.573899) (xy 446.76867 -178.619746) (xy 446.791307 -178.669319) (xy 446.806659 -178.721609)
			(xy 446.814414 -178.775552) (xy 446.814414 -178.830048) (xy 446.806659 -178.883991) (xy 446.791307 -178.936281)
			(xy 446.76867 -178.985854) (xy 446.739209 -179.031701) (xy 446.703523 -179.072889) (xy 446.662339 -179.10858)
			(xy 446.616496 -179.138047) (xy 446.566926 -179.16069) (xy 446.514638 -179.176049) (xy 446.460696 -179.183811)
			(xy 446.433448 -179.1843) (xy 446.406079 -179.183806) (xy 446.351901 -179.175995) (xy 446.299398 -179.160512)
			(xy 446.249651 -179.137677) (xy 446.203683 -179.107958) (xy 446.18275 -179.09032) (xy 446.171422 -179.081084)
			(xy 446.144865 -179.068908) (xy 446.115948 -179.064735) (xy 446.087031 -179.068908) (xy 446.060474 -179.081084)
			(xy 446.049146 -179.09032) (xy 446.02821 -179.107954) (xy 445.982238 -179.137666) (xy 445.932491 -179.160503)
			(xy 445.879992 -179.175995) (xy 445.825817 -179.183825) (xy 445.798448 -179.1843) (xy 445.772434 -179.183891)
			(xy 445.72089 -179.176814) (xy 445.670786 -179.162799) (xy 445.623051 -179.142104) (xy 445.578571 -179.115116)
			(xy 445.538171 -179.082333) (xy 445.520064 -179.06365) (xy 445.510219 -179.053664) (xy 445.486231 -179.039152)
			(xy 445.4592 -179.031715) (xy 445.431165 -179.031914) (xy 445.404242 -179.039734) (xy 445.380462 -179.054585)
			(xy 445.370712 -179.064666) (xy 445.352556 -179.083988) (xy 445.311809 -179.11791) (xy 445.266759 -179.145865)
			(xy 445.218272 -179.167316) (xy 445.167283 -179.181848) (xy 445.114774 -179.189182) (xy 445.088264 -179.189634)
			(xy 445.061016 -179.189093) (xy 445.007076 -179.181333) (xy 444.954789 -179.165976) (xy 444.90522 -179.143334)
			(xy 444.859377 -179.113869) (xy 444.818194 -179.07818) (xy 444.782509 -179.036994) (xy 444.753048 -178.991148)
			(xy 444.730411 -178.941577) (xy 444.715059 -178.889289) (xy 444.707304 -178.835348) (xy 434.72424 -178.835348)
			(xy 434.704127 -178.878252) (xy 434.673354 -178.924765) (xy 434.636137 -178.966302) (xy 434.593269 -179.001977)
			(xy 434.545663 -179.031031) (xy 434.494334 -179.052843) (xy 434.440377 -179.066949) (xy 434.38494 -179.073049)
			(xy 434.329206 -179.071012) (xy 434.274363 -179.060882) (xy 434.221579 -179.042875) (xy 434.171979 -179.017374)
			(xy 434.126621 -178.984923) (xy 434.086472 -178.946214) (xy 434.052386 -178.902071) (xy 434.02509 -178.853436)
			(xy 434.005167 -178.801345) (xy 433.993041 -178.746908) (xy 433.98897 -178.691286) (xy 431.652522 -178.691286)
			(xy 431.650554 -178.697398) (xy 431.623772 -178.750477) (xy 431.589081 -178.79876) (xy 431.568606 -178.820318)
			(xy 431.559494 -178.83014) (xy 431.546293 -178.853443) (xy 431.539604 -178.879377) (xy 431.539887 -178.906158)
			(xy 431.547121 -178.931945) (xy 431.56081 -178.954965) (xy 431.57013 -178.96459) (xy 431.58827 -178.982779)
			(xy 431.620002 -179.023176) (xy 431.633376 -179.045108) (xy 431.641506 -179.057796) (xy 431.663615 -179.07824)
			(xy 431.690727 -179.091344) (xy 431.720482 -179.095966) (xy 431.750292 -179.091704) (xy 431.77756 -179.07893)
			(xy 431.799915 -179.058754) (xy 431.808128 -179.046124) (xy 431.822982 -179.022263) (xy 431.858628 -178.978807)
			(xy 431.900265 -178.941053) (xy 431.946992 -178.909818) (xy 431.997798 -178.88578) (xy 432.051581 -178.869458)
			(xy 432.107177 -178.861206) (xy 432.13528 -178.860704) (xy 432.162535 -178.861142) (xy 432.21649 -178.868896)
			(xy 432.268791 -178.884251) (xy 432.318376 -178.906893) (xy 432.364233 -178.936362) (xy 432.405429 -178.972057)
			(xy 432.441126 -179.013251) (xy 432.470597 -179.059107) (xy 432.493242 -179.10869) (xy 432.508599 -179.160991)
			(xy 432.516357 -179.214945) (xy 432.516357 -179.269455) (xy 432.508599 -179.323409) (xy 432.493242 -179.37571)
			(xy 432.470597 -179.425293) (xy 432.441126 -179.471149) (xy 432.405429 -179.512343) (xy 432.364233 -179.548038)
			(xy 432.318376 -179.577507) (xy 432.268791 -179.600149) (xy 432.21649 -179.615504) (xy 432.162535 -179.623258)
			(xy 432.13528 -179.62372) (xy 432.106914 -179.623166) (xy 432.050806 -179.614767) (xy 431.996558 -179.598159)
			(xy 431.945366 -179.573705) (xy 431.898356 -179.541945) (xy 431.856564 -179.503578) (xy 431.820909 -179.459449)
			(xy 431.806096 -179.435252) (xy 431.798001 -179.422542) (xy 431.775882 -179.402103) (xy 431.748764 -179.389006)
			(xy 431.719003 -179.384389) (xy 431.689191 -179.388654) (xy 431.661919 -179.40143) (xy 431.63956 -179.421605)
			(xy 431.631344 -179.434236) (xy 431.616495 -179.458101) (xy 431.58085 -179.501559) (xy 431.539213 -179.539314)
			(xy 431.492484 -179.570549) (xy 431.441678 -179.594587) (xy 431.387893 -179.610907) (xy 431.332295 -179.619156)
			(xy 431.304192 -179.619656) (xy 431.276943 -179.61913) (xy 431.222999 -179.611373) (xy 431.170708 -179.59602)
			(xy 431.121134 -179.573381) (xy 431.075286 -179.543919) (xy 431.034097 -179.508231) (xy 430.998405 -179.467046)
			(xy 430.968938 -179.421201) (xy 430.946294 -179.37163) (xy 430.930935 -179.31934) (xy 430.923173 -179.265397)
			(xy 430.922684 -179.238148) (xy 430.923269 -179.208422) (xy 430.932497 -179.14969) (xy 430.950722 -179.093099)
			(xy 430.977503 -179.04002) (xy 431.012192 -178.991737) (xy 431.032666 -178.970178) (xy 431.041785 -178.960361)
			(xy 431.054989 -178.937057) (xy 431.061679 -178.911121) (xy 431.061396 -178.884338) (xy 431.054158 -178.858549)
			(xy 431.040465 -178.835529) (xy 431.031142 -178.825906) (xy 431.01323 -178.807853) (xy 430.981796 -178.767877)
			(xy 430.955952 -178.724079) (xy 430.936156 -178.677236) (xy 430.922758 -178.628178) (xy 430.915995 -178.577775)
			(xy 430.915572 -178.552348) (xy 418.22228 -178.552348) (xy 418.211257 -178.574871) (xy 418.206364 -178.603578)
			(xy 418.209777 -178.632499) (xy 418.215064 -178.646074) (xy 418.224541 -178.669289) (xy 418.237896 -178.717619)
			(xy 418.244629 -178.767307) (xy 418.245036 -178.792378) (xy 418.244515 -178.820263) (xy 418.236203 -178.87541)
			(xy 418.219765 -178.928702) (xy 418.195567 -178.978948) (xy 418.164151 -179.025027) (xy 418.126218 -179.065909)
			(xy 418.082616 -179.100681) (xy 418.034318 -179.128566) (xy 417.982403 -179.148941) (xy 417.928032 -179.161351)
			(xy 417.872418 -179.165519) (xy 417.816804 -179.161351) (xy 417.762433 -179.148941) (xy 417.710518 -179.128566)
			(xy 417.66222 -179.100681) (xy 417.618618 -179.065909) (xy 417.580685 -179.025027) (xy 417.549269 -178.978948)
			(xy 417.525071 -178.928702) (xy 417.508633 -178.87541) (xy 417.500321 -178.820263) (xy 417.4998 -178.792378)
			(xy 410.18968 -178.792378) (xy 410.18968 -179.723542) (xy 419.315646 -179.723542) (xy 419.316217 -179.696294)
			(xy 419.323967 -179.642352) (xy 419.339314 -179.590061) (xy 419.361947 -179.540487) (xy 419.391405 -179.494639)
			(xy 419.427087 -179.45345) (xy 419.468269 -179.417757) (xy 419.51411 -179.388289) (xy 419.563679 -179.365645)
			(xy 419.615966 -179.350285) (xy 419.669906 -179.342523) (xy 419.697154 -179.342034) (xy 419.727059 -179.342571)
			(xy 419.786138 -179.351883) (xy 419.814756 -179.360576) (xy 419.82866 -179.36463) (xy 419.857597 -179.36554)
			(xy 419.885621 -179.358274) (xy 419.910469 -179.343418) (xy 419.930134 -179.322171) (xy 419.943028 -179.296251)
			(xy 419.946074 -179.28209) (xy 419.951204 -179.256008) (xy 419.967775 -179.205501) (xy 419.991201 -179.157784)
			(xy 420.021027 -179.113784) (xy 420.056674 -179.074352) (xy 420.097452 -179.040253) (xy 420.142571 -179.012148)
			(xy 420.191156 -178.990581) (xy 420.242265 -178.975971) (xy 420.294908 -178.968601) (xy 420.321486 -178.968146)
			(xy 420.348736 -178.9687) (xy 420.402682 -178.976455) (xy 420.454975 -178.991808) (xy 420.504551 -179.014447)
			(xy 420.550401 -179.043911) (xy 420.59159 -179.0796) (xy 420.627281 -179.120788) (xy 420.656747 -179.166636)
			(xy 420.679387 -179.216211) (xy 420.694742 -179.268504) (xy 420.702499 -179.32245) (xy 420.702499 -179.37695)
			(xy 420.694742 -179.430896) (xy 420.679387 -179.483189) (xy 420.656747 -179.532764) (xy 420.627281 -179.578612)
			(xy 420.59159 -179.6198) (xy 420.550401 -179.655489) (xy 420.504551 -179.684953) (xy 420.454975 -179.707592)
			(xy 420.402682 -179.722945) (xy 420.348736 -179.7307) (xy 420.321486 -179.731162) (xy 420.291581 -179.730639)
			(xy 420.232502 -179.721318) (xy 420.203884 -179.71262) (xy 420.189967 -179.708614) (xy 420.161038 -179.707695)
			(xy 420.133019 -179.714952) (xy 420.108173 -179.729799) (xy 420.088508 -179.751036) (xy 420.075613 -179.776949)
			(xy 420.072566 -179.791106) (xy 420.06599 -179.823947) (xy 420.042863 -179.886798) (xy 420.026592 -179.916074)
			(xy 420.019587 -179.929057) (xy 420.012541 -179.957688) (xy 420.013975 -179.987137) (xy 420.023771 -180.014948)
			(xy 420.04111 -180.038795) (xy 420.064544 -180.05669) (xy 420.078154 -180.062378) (xy 420.104942 -180.073047)
			(xy 420.155182 -180.101341) (xy 420.20059 -180.136876) (xy 420.240131 -180.178842) (xy 420.269517 -180.221382)
			(xy 430.50409 -180.221382) (xy 430.508161 -180.16576) (xy 430.520287 -180.111323) (xy 430.54021 -180.059232)
			(xy 430.567506 -180.010597) (xy 430.601592 -179.966454) (xy 430.641741 -179.927745) (xy 430.687099 -179.895294)
			(xy 430.736699 -179.869793) (xy 430.789483 -179.851786) (xy 430.844326 -179.841656) (xy 430.90006 -179.839619)
			(xy 430.955497 -179.845719) (xy 431.009454 -179.859825) (xy 431.060783 -179.881637) (xy 431.108389 -179.910691)
			(xy 431.151257 -179.946366) (xy 431.188474 -179.987903) (xy 431.219247 -180.034416) (xy 431.242919 -180.084913)
			(xy 431.258987 -180.13832) (xy 431.267107 -180.193496) (xy 431.267616 -180.221382) (xy 431.267107 -180.249268)
			(xy 431.258987 -180.304444) (xy 431.242919 -180.357851) (xy 431.219247 -180.408348) (xy 431.188474 -180.454861)
			(xy 431.151257 -180.496398) (xy 431.108389 -180.532073) (xy 431.060783 -180.561127) (xy 431.009454 -180.582939)
			(xy 430.955497 -180.597045) (xy 430.90006 -180.603145) (xy 430.844326 -180.601108) (xy 430.789483 -180.590978)
			(xy 430.736699 -180.572971) (xy 430.687099 -180.54747) (xy 430.641741 -180.515019) (xy 430.601592 -180.47631)
			(xy 430.567506 -180.432167) (xy 430.54021 -180.383532) (xy 430.520287 -180.331441) (xy 430.508161 -180.277004)
			(xy 430.50409 -180.221382) (xy 420.269517 -180.221382) (xy 420.272903 -180.226283) (xy 420.298159 -180.278117)
			(xy 420.315323 -180.333162) (xy 420.324005 -180.390164) (xy 420.324534 -180.418994) (xy 420.324048 -180.446245)
			(xy 420.316292 -180.500193) (xy 420.300937 -180.552488) (xy 420.278295 -180.602065) (xy 420.248829 -180.647915)
			(xy 420.213138 -180.689106) (xy 420.171947 -180.724797) (xy 420.126097 -180.754263) (xy 420.07652 -180.776905)
			(xy 420.024225 -180.79226) (xy 419.970277 -180.800016) (xy 419.915775 -180.800016) (xy 419.861827 -180.79226)
			(xy 419.809532 -180.776905) (xy 419.759955 -180.754263) (xy 419.714105 -180.724797) (xy 419.672914 -180.689106)
			(xy 419.637223 -180.647915) (xy 419.607757 -180.602065) (xy 419.585115 -180.552488) (xy 419.56976 -180.500193)
			(xy 419.562004 -180.446245) (xy 419.561518 -180.418994) (xy 419.56191 -180.393758) (xy 419.568529 -180.343724)
			(xy 419.581704 -180.295004) (xy 419.601202 -180.248452) (xy 419.613588 -180.226462) (xy 419.620627 -180.213499)
			(xy 419.627653 -180.184862) (xy 419.626205 -180.155412) (xy 419.616403 -180.127603) (xy 419.599064 -180.103754)
			(xy 419.575634 -180.085852) (xy 419.562026 -180.080158) (xy 419.535269 -180.069416) (xy 419.485027 -180.041136)
			(xy 419.439617 -180.005613) (xy 419.400072 -179.963658) (xy 419.367296 -179.916228) (xy 419.342035 -179.864402)
			(xy 419.324865 -179.809365) (xy 419.316178 -179.752369) (xy 419.315646 -179.723542) (xy 410.18968 -179.723542)
			(xy 410.18968 -180.943548) (xy 444.707304 -180.943548) (xy 444.707304 -180.889052) (xy 444.715059 -180.835111)
			(xy 444.730411 -180.782823) (xy 444.753048 -180.733252) (xy 444.782509 -180.687406) (xy 444.818194 -180.64622)
			(xy 444.859377 -180.610531) (xy 444.90522 -180.581066) (xy 444.954789 -180.558424) (xy 445.007076 -180.543067)
			(xy 445.061016 -180.535307) (xy 445.088264 -180.534818) (xy 445.114278 -180.535213) (xy 445.165823 -180.542292)
			(xy 445.215928 -180.55631) (xy 445.263663 -180.577007) (xy 445.308143 -180.603998) (xy 445.348542 -180.636784)
			(xy 445.366648 -180.655468) (xy 445.376576 -180.665364) (xy 445.40054 -180.679878) (xy 445.42755 -180.687325)
			(xy 445.455566 -180.687143) (xy 445.482476 -180.679345) (xy 445.506249 -180.66452) (xy 445.516 -180.654452)
			(xy 445.534154 -180.635128) (xy 445.574901 -180.601205) (xy 445.619952 -180.57325) (xy 445.668438 -180.5518)
			(xy 445.719428 -180.537268) (xy 445.771938 -180.529935) (xy 445.798448 -180.529484) (xy 445.825818 -180.52996)
			(xy 445.879998 -180.537772) (xy 445.932501 -180.553258) (xy 445.982249 -180.576098) (xy 446.028215 -180.605822)
			(xy 446.049146 -180.623464) (xy 446.060474 -180.6327) (xy 446.087031 -180.644876) (xy 446.115948 -180.649049)
			(xy 446.144865 -180.644876) (xy 446.171422 -180.6327) (xy 446.18275 -180.623464) (xy 446.203685 -180.605829)
			(xy 446.249658 -180.576118) (xy 446.299405 -180.553282) (xy 446.351904 -180.53779) (xy 446.406079 -180.529959)
			(xy 446.433448 -180.529484) (xy 446.460696 -180.529989) (xy 446.514638 -180.537751) (xy 446.566926 -180.55311)
			(xy 446.616496 -180.575753) (xy 446.662339 -180.60522) (xy 446.703523 -180.640911) (xy 446.739209 -180.682099)
			(xy 446.76867 -180.727946) (xy 446.791307 -180.777519) (xy 446.806659 -180.829809) (xy 446.814414 -180.883752)
			(xy 446.814414 -180.938248) (xy 446.806659 -180.992191) (xy 446.791307 -181.044481) (xy 446.76867 -181.094054)
			(xy 446.739209 -181.139901) (xy 446.703523 -181.181089) (xy 446.662339 -181.21678) (xy 446.616496 -181.246247)
			(xy 446.566926 -181.26889) (xy 446.514638 -181.284249) (xy 446.460696 -181.292011) (xy 446.433448 -181.2925)
			(xy 446.406079 -181.292006) (xy 446.351901 -181.284195) (xy 446.299398 -181.268712) (xy 446.249651 -181.245877)
			(xy 446.203683 -181.216158) (xy 446.18275 -181.19852) (xy 446.171422 -181.189284) (xy 446.144865 -181.177108)
			(xy 446.115948 -181.172935) (xy 446.087031 -181.177108) (xy 446.060474 -181.189284) (xy 446.049146 -181.19852)
			(xy 446.02821 -181.216154) (xy 445.982238 -181.245866) (xy 445.932491 -181.268703) (xy 445.879992 -181.284195)
			(xy 445.825817 -181.292025) (xy 445.798448 -181.2925) (xy 445.772434 -181.292091) (xy 445.72089 -181.285014)
			(xy 445.670786 -181.270999) (xy 445.623051 -181.250304) (xy 445.578571 -181.223316) (xy 445.538171 -181.190533)
			(xy 445.520064 -181.17185) (xy 445.510219 -181.161864) (xy 445.486231 -181.147352) (xy 445.4592 -181.139915)
			(xy 445.431165 -181.140114) (xy 445.404242 -181.147934) (xy 445.380462 -181.162785) (xy 445.370712 -181.172866)
			(xy 445.352556 -181.192188) (xy 445.311809 -181.22611) (xy 445.266759 -181.254065) (xy 445.218272 -181.275516)
			(xy 445.167283 -181.290048) (xy 445.114774 -181.297382) (xy 445.088264 -181.297834) (xy 445.061016 -181.297293)
			(xy 445.007076 -181.289533) (xy 444.954789 -181.274176) (xy 444.90522 -181.251534) (xy 444.859377 -181.222069)
			(xy 444.818194 -181.18638) (xy 444.782509 -181.145194) (xy 444.753048 -181.099348) (xy 444.730411 -181.049777)
			(xy 444.715059 -180.997489) (xy 444.707304 -180.943548) (xy 410.18968 -180.943548) (xy 410.18968 -181.46225)
			(xy 419.374572 -181.46225) (xy 419.374572 -181.40775) (xy 419.382328 -181.353803) (xy 419.397682 -181.30151)
			(xy 419.420321 -181.251933) (xy 419.449786 -181.206084) (xy 419.485475 -181.164893) (xy 419.526663 -181.129201)
			(xy 419.572511 -181.099734) (xy 419.622085 -181.077091) (xy 419.674378 -181.061733) (xy 419.728324 -181.053974)
			(xy 419.755574 -181.053486) (xy 419.785261 -181.054065) (xy 419.843919 -181.06326) (xy 419.900444 -181.081431)
			(xy 419.953471 -181.108139) (xy 420.001721 -181.142741) (xy 420.044027 -181.184399) (xy 420.062152 -181.207918)
			(xy 420.070578 -181.218525) (xy 420.091891 -181.235232) (xy 420.116845 -181.245751) (xy 420.143686 -181.249341)
			(xy 420.170527 -181.245751) (xy 420.195481 -181.235232) (xy 420.216794 -181.218525) (xy 420.22522 -181.207918)
			(xy 420.243349 -181.184402) (xy 420.285654 -181.142741) (xy 420.333902 -181.108136) (xy 420.386928 -181.081424)
			(xy 420.443453 -181.06325) (xy 420.502111 -181.054051) (xy 420.531798 -181.053486) (xy 420.559051 -181.053961)
			(xy 420.613001 -181.061718) (xy 420.665298 -181.077073) (xy 420.714878 -181.099715) (xy 420.76073 -181.129183)
			(xy 420.801923 -181.164876) (xy 420.837616 -181.206068) (xy 420.867084 -181.251921) (xy 420.889726 -181.3015)
			(xy 420.905082 -181.353797) (xy 420.912839 -181.407747) (xy 420.912839 -181.462253) (xy 420.905082 -181.516203)
			(xy 420.889726 -181.5685) (xy 420.867084 -181.618079) (xy 420.837616 -181.663932) (xy 420.801923 -181.705124)
			(xy 420.76073 -181.740817) (xy 420.714878 -181.770285) (xy 420.665298 -181.792927) (xy 420.613001 -181.808282)
			(xy 420.559051 -181.816039) (xy 420.531798 -181.816502) (xy 420.50211 -181.815948) (xy 420.443451 -181.806749)
			(xy 420.386925 -181.788573) (xy 420.333898 -181.76186) (xy 420.285649 -181.727254) (xy 420.243344 -181.685591)
			(xy 420.22522 -181.66207) (xy 420.216794 -181.651463) (xy 420.195481 -181.634756) (xy 420.170527 -181.624237)
			(xy 420.143686 -181.620647) (xy 420.116845 -181.624237) (xy 420.091891 -181.634756) (xy 420.070578 -181.651463)
			(xy 420.062152 -181.66207) (xy 420.044036 -181.685597) (xy 420.001729 -181.727258) (xy 419.953478 -181.761861)
			(xy 419.900449 -181.788572) (xy 419.843922 -181.806744) (xy 419.785262 -181.815939) (xy 419.755574 -181.816502)
			(xy 419.728324 -181.816026) (xy 419.674378 -181.808267) (xy 419.622085 -181.792909) (xy 419.572511 -181.770266)
			(xy 419.526663 -181.740799) (xy 419.485475 -181.705107) (xy 419.449786 -181.663916) (xy 419.420321 -181.618067)
			(xy 419.397682 -181.56849) (xy 419.382328 -181.516197) (xy 419.374572 -181.46225) (xy 410.18968 -181.46225)
			(xy 410.18968 -182.213953) (xy 418.557175 -182.213953) (xy 418.564931 -182.160006) (xy 418.580286 -182.107711)
			(xy 418.602926 -182.058133) (xy 418.632392 -182.012282) (xy 418.668083 -181.971091) (xy 418.709272 -181.935399)
			(xy 418.755122 -181.905932) (xy 418.804699 -181.88329) (xy 418.856994 -181.867934) (xy 418.910941 -181.860176)
			(xy 418.965444 -181.860175) (xy 419.019392 -181.867931) (xy 419.071687 -181.883285) (xy 419.121265 -181.905925)
			(xy 419.167116 -181.93539) (xy 419.208307 -181.971081) (xy 419.243999 -182.01227) (xy 419.273467 -182.05812)
			(xy 419.296109 -182.107697) (xy 419.311466 -182.159991) (xy 419.319224 -182.213939) (xy 419.31971 -182.24119)
			(xy 419.319282 -182.266581) (xy 419.312524 -182.316913) (xy 419.306248 -182.34152) (xy 419.302808 -182.356167)
			(xy 419.303729 -182.386225) (xy 419.31336 -182.414715) (xy 419.330866 -182.439167) (xy 419.354731 -182.457465)
			(xy 419.38289 -182.468023) (xy 419.412902 -182.469929) (xy 419.42766 -182.466996) (xy 419.449255 -182.462239)
			(xy 419.49318 -182.45714) (xy 419.51529 -182.456836) (xy 419.542541 -182.457267) (xy 419.59649 -182.465022)
			(xy 419.648785 -182.480376) (xy 419.698364 -182.503015) (xy 419.744216 -182.53248) (xy 419.785408 -182.56817)
			(xy 419.821101 -182.609359) (xy 419.85057 -182.655209) (xy 419.87006 -182.697882) (xy 433.914294 -182.697882)
			(xy 433.918365 -182.64226) (xy 433.930491 -182.587823) (xy 433.950414 -182.535732) (xy 433.97771 -182.487097)
			(xy 434.011796 -182.442954) (xy 434.051945 -182.404245) (xy 434.097303 -182.371794) (xy 434.146903 -182.346293)
			(xy 434.199687 -182.328286) (xy 434.25453 -182.318156) (xy 434.310264 -182.316119) (xy 434.365701 -182.322219)
			(xy 434.419658 -182.336325) (xy 434.470987 -182.358137) (xy 434.518593 -182.387191) (xy 434.561461 -182.422866)
			(xy 434.598678 -182.464403) (xy 434.629451 -182.510916) (xy 434.653123 -182.561413) (xy 434.669191 -182.61482)
			(xy 434.677311 -182.669996) (xy 434.67782 -182.697882) (xy 434.677311 -182.725768) (xy 434.669191 -182.780944)
			(xy 434.653123 -182.834351) (xy 434.629451 -182.884848) (xy 434.598678 -182.931361) (xy 434.561461 -182.972898)
			(xy 434.518593 -183.008573) (xy 434.470987 -183.037627) (xy 434.461508 -183.041655) (xy 444.697021 -183.041655)
			(xy 444.697021 -182.987145) (xy 444.704779 -182.933188) (xy 444.720136 -182.880885) (xy 444.742781 -182.831301)
			(xy 444.772252 -182.785443) (xy 444.80795 -182.744247) (xy 444.849146 -182.70855) (xy 444.895004 -182.679079)
			(xy 444.944589 -182.656435) (xy 444.996892 -182.641078) (xy 445.050849 -182.633321) (xy 445.078104 -182.632858)
			(xy 445.104116 -182.633312) (xy 445.155658 -182.640381) (xy 445.205761 -182.654389) (xy 445.253495 -182.675075)
			(xy 445.297977 -182.702055) (xy 445.338379 -182.734829) (xy 445.356488 -182.753508) (xy 445.366376 -182.76345)
			(xy 445.39035 -182.77797) (xy 445.417371 -182.785417) (xy 445.445399 -182.785227) (xy 445.472317 -182.777415)
			(xy 445.496092 -182.76257) (xy 445.50584 -182.752492) (xy 445.524031 -182.733205) (xy 445.564769 -182.699277)
			(xy 445.609812 -182.671316) (xy 445.658292 -182.649859) (xy 445.709275 -182.63532) (xy 445.76178 -182.62798)
			(xy 445.788288 -182.627524) (xy 445.815658 -182.627991) (xy 445.869838 -182.635808) (xy 445.922341 -182.651296)
			(xy 445.972088 -182.674138) (xy 446.018054 -182.703863) (xy 446.038986 -182.721504) (xy 446.050314 -182.73074)
			(xy 446.076871 -182.742916) (xy 446.105788 -182.747089) (xy 446.134705 -182.742916) (xy 446.161262 -182.73074)
			(xy 446.17259 -182.721504) (xy 446.193516 -182.703857) (xy 446.23949 -182.674146) (xy 446.289239 -182.651312)
			(xy 446.341741 -182.635822) (xy 446.395918 -182.627997) (xy 446.423288 -182.627524) (xy 446.450544 -182.627922)
			(xy 446.504501 -182.635678) (xy 446.556804 -182.651035) (xy 446.60639 -182.673678) (xy 446.652249 -182.703149)
			(xy 446.693446 -182.738845) (xy 446.729144 -182.780042) (xy 446.758616 -182.825899) (xy 446.781261 -182.875484)
			(xy 446.796619 -182.927788) (xy 446.804377 -182.981744) (xy 446.804377 -183.036256) (xy 446.796619 -183.090212)
			(xy 446.781261 -183.142516) (xy 446.758616 -183.192101) (xy 446.729144 -183.237958) (xy 446.693446 -183.279155)
			(xy 446.652249 -183.314851) (xy 446.60639 -183.344322) (xy 446.556804 -183.366965) (xy 446.504501 -183.382322)
			(xy 446.450544 -183.390078) (xy 446.423288 -183.39054) (xy 446.395917 -183.390096) (xy 446.341736 -183.382275)
			(xy 446.289232 -183.366781) (xy 446.239486 -183.343935) (xy 446.19352 -183.314204) (xy 446.17259 -183.29656)
			(xy 446.161262 -183.287324) (xy 446.134705 -183.275148) (xy 446.105788 -183.270975) (xy 446.076871 -183.275148)
			(xy 446.050314 -183.287324) (xy 446.038986 -183.29656) (xy 446.018027 -183.314166) (xy 445.972062 -183.343884)
			(xy 445.922322 -183.366727) (xy 445.869827 -183.382226) (xy 445.815655 -183.390062) (xy 445.788288 -183.39054)
			(xy 445.762276 -183.390092) (xy 445.710734 -183.383021) (xy 445.660631 -183.369013) (xy 445.612896 -183.348326)
			(xy 445.568415 -183.321344) (xy 445.528013 -183.288569) (xy 445.509904 -183.26989) (xy 445.500024 -183.25994)
			(xy 445.476048 -183.24542) (xy 445.449024 -183.237975) (xy 445.420995 -183.238166) (xy 445.394076 -183.24598)
			(xy 445.3703 -183.260827) (xy 445.360552 -183.270906) (xy 445.342364 -183.290197) (xy 445.301626 -183.324124)
			(xy 445.256582 -183.352085) (xy 445.208102 -183.373541) (xy 445.157118 -183.388079) (xy 445.104612 -183.395419)
			(xy 445.078104 -183.395874) (xy 445.050849 -183.395479) (xy 444.996892 -183.387722) (xy 444.944589 -183.372365)
			(xy 444.895004 -183.349721) (xy 444.849146 -183.32025) (xy 444.80795 -183.284553) (xy 444.772252 -183.243357)
			(xy 444.742781 -183.197499) (xy 444.720136 -183.147915) (xy 444.704779 -183.095612) (xy 444.697021 -183.041655)
			(xy 434.461508 -183.041655) (xy 434.419658 -183.059439) (xy 434.365701 -183.073545) (xy 434.310264 -183.079645)
			(xy 434.25453 -183.077608) (xy 434.199687 -183.067478) (xy 434.146903 -183.049471) (xy 434.097303 -183.02397)
			(xy 434.051945 -182.991519) (xy 434.011796 -182.95281) (xy 433.97771 -182.908667) (xy 433.950414 -182.860032)
			(xy 433.930491 -182.807941) (xy 433.918365 -182.753504) (xy 433.914294 -182.697882) (xy 419.87006 -182.697882)
			(xy 419.873213 -182.704785) (xy 419.888571 -182.75708) (xy 419.896331 -182.811027) (xy 419.896334 -182.86553)
			(xy 419.88858 -182.919479) (xy 419.873228 -182.971775) (xy 419.85059 -183.021354) (xy 419.821127 -183.067207)
			(xy 419.785438 -183.1084) (xy 419.74425 -183.144094) (xy 419.698401 -183.173564) (xy 419.648825 -183.196209)
			(xy 419.596532 -183.211569) (xy 419.542584 -183.21933) (xy 419.488081 -183.219335) (xy 419.434132 -183.211583)
			(xy 419.381836 -183.196232) (xy 419.332256 -183.173596) (xy 419.286403 -183.144134) (xy 419.245208 -183.108446)
			(xy 419.209512 -183.067259) (xy 419.180041 -183.021411) (xy 419.157395 -182.971836) (xy 419.142034 -182.919543)
			(xy 419.134271 -182.865595) (xy 419.133782 -182.838344) (xy 419.134216 -182.812953) (xy 419.14097 -182.762622)
			(xy 419.147244 -182.738014) (xy 419.150657 -182.723361) (xy 419.149744 -182.693304) (xy 419.14012 -182.664815)
			(xy 419.122618 -182.640362) (xy 419.098755 -182.622064) (xy 419.070599 -182.611507) (xy 419.040588 -182.609604)
			(xy 419.025832 -182.612538) (xy 419.004238 -182.617297) (xy 418.960312 -182.622394) (xy 418.938202 -182.622698)
			(xy 418.910951 -182.622224) (xy 418.857003 -182.614468) (xy 418.804708 -182.599113) (xy 418.755131 -182.576473)
			(xy 418.70928 -182.547007) (xy 418.668089 -182.511315) (xy 418.632397 -182.470125) (xy 418.602931 -182.424275)
			(xy 418.580289 -182.374698) (xy 418.564933 -182.322404) (xy 418.557176 -182.268456) (xy 418.557175 -182.213953)
			(xy 410.18968 -182.213953) (xy 410.18968 -183.059957) (xy 416.453709 -183.059957) (xy 416.453709 -183.005443)
			(xy 416.461468 -182.951483) (xy 416.476827 -182.899176) (xy 416.499474 -182.849588) (xy 416.528948 -182.803728)
			(xy 416.56465 -182.76253) (xy 416.605851 -182.726832) (xy 416.651713 -182.697361) (xy 416.701302 -182.674717)
			(xy 416.75361 -182.659362) (xy 416.807571 -182.651607) (xy 416.834828 -182.651146) (xy 416.862199 -182.651584)
			(xy 416.91638 -182.659407) (xy 416.968884 -182.674902) (xy 417.01863 -182.69775) (xy 417.064596 -182.727481)
			(xy 417.085526 -182.745126) (xy 417.096854 -182.754362) (xy 417.123411 -182.766538) (xy 417.152328 -182.770711)
			(xy 417.181245 -182.766538) (xy 417.207802 -182.754362) (xy 417.21913 -182.745126) (xy 417.240081 -182.72751)
			(xy 417.286048 -182.697794) (xy 417.335791 -182.674953) (xy 417.388287 -182.659457) (xy 417.44246 -182.651623)
			(xy 417.469828 -182.651146) (xy 417.497075 -182.651726) (xy 417.551013 -182.659485) (xy 417.603298 -182.674841)
			(xy 417.652865 -182.697481) (xy 417.698707 -182.726944) (xy 417.739889 -182.762631) (xy 417.775573 -182.803816)
			(xy 417.805033 -182.849659) (xy 417.827669 -182.899228) (xy 417.843021 -182.951515) (xy 417.850776 -183.005453)
			(xy 417.850776 -183.059947) (xy 417.843021 -183.113885) (xy 417.827669 -183.166172) (xy 417.805033 -183.215741)
			(xy 417.775573 -183.261584) (xy 417.739889 -183.302769) (xy 417.698707 -183.338456) (xy 417.652865 -183.367919)
			(xy 417.603298 -183.390559) (xy 417.551013 -183.405915) (xy 417.497075 -183.413674) (xy 417.469828 -183.414162)
			(xy 417.442458 -183.413689) (xy 417.388279 -183.405874) (xy 417.335775 -183.390387) (xy 417.286028 -183.367547)
			(xy 417.240062 -183.337823) (xy 417.21913 -183.320182) (xy 417.207802 -183.310946) (xy 417.181245 -183.29877)
			(xy 417.152328 -183.294597) (xy 417.123411 -183.29877) (xy 417.096854 -183.310946) (xy 417.085526 -183.320182)
			(xy 417.064593 -183.33782) (xy 417.01862 -183.367532) (xy 416.968873 -183.390369) (xy 416.916373 -183.40586)
			(xy 416.862197 -183.413688) (xy 416.834828 -183.414162) (xy 416.807571 -183.413793) (xy 416.75361 -183.406038)
			(xy 416.701302 -183.390683) (xy 416.651713 -183.368039) (xy 416.605851 -183.338568) (xy 416.56465 -183.30287)
			(xy 416.528948 -183.261672) (xy 416.499474 -183.215812) (xy 416.476827 -183.166224) (xy 416.461468 -183.113917)
			(xy 416.453709 -183.059957) (xy 410.18968 -183.059957) (xy 410.18968 -183.822848) (xy 410.90342 -184.536588)
			(xy 424.778422 -184.536588) (xy 424.782493 -184.480966) (xy 424.794619 -184.426529) (xy 424.814542 -184.374438)
			(xy 424.841838 -184.325803) (xy 424.875924 -184.28166) (xy 424.916073 -184.242951) (xy 424.961431 -184.2105)
			(xy 425.011031 -184.184999) (xy 425.063815 -184.166992) (xy 425.118658 -184.156862) (xy 425.174392 -184.154825)
			(xy 425.229829 -184.160925) (xy 425.283786 -184.175031) (xy 425.335115 -184.196843) (xy 425.382721 -184.225897)
			(xy 425.425589 -184.261572) (xy 425.462806 -184.303109) (xy 425.493579 -184.349622) (xy 425.517251 -184.400119)
			(xy 425.533319 -184.453526) (xy 425.541439 -184.508702) (xy 425.541948 -184.536588) (xy 425.541439 -184.564474)
			(xy 425.533319 -184.61965) (xy 425.517251 -184.673057) (xy 425.493579 -184.723554) (xy 425.462806 -184.770067)
			(xy 425.46035 -184.772808) (xy 431.191922 -184.772808) (xy 431.195993 -184.717186) (xy 431.208119 -184.662749)
			(xy 431.228042 -184.610658) (xy 431.255338 -184.562023) (xy 431.289424 -184.51788) (xy 431.329573 -184.479171)
			(xy 431.374931 -184.44672) (xy 431.424531 -184.421219) (xy 431.477315 -184.403212) (xy 431.532158 -184.393082)
			(xy 431.587892 -184.391045) (xy 431.643329 -184.397145) (xy 431.697286 -184.411251) (xy 431.748615 -184.433063)
			(xy 431.796221 -184.462117) (xy 431.839089 -184.497792) (xy 431.876306 -184.539329) (xy 431.907079 -184.585842)
			(xy 431.930751 -184.636339) (xy 431.946819 -184.689746) (xy 431.954939 -184.744922) (xy 431.955448 -184.772808)
			(xy 431.954939 -184.800694) (xy 431.946819 -184.85587) (xy 431.930751 -184.909277) (xy 431.907079 -184.959774)
			(xy 431.876306 -185.006287) (xy 431.839089 -185.047824) (xy 431.796221 -185.083499) (xy 431.748615 -185.112553)
			(xy 431.697286 -185.134365) (xy 431.643329 -185.148471) (xy 431.587892 -185.154571) (xy 431.532158 -185.152534)
			(xy 431.477315 -185.142404) (xy 431.424531 -185.124397) (xy 431.374931 -185.098896) (xy 431.329573 -185.066445)
			(xy 431.289424 -185.027736) (xy 431.255338 -184.983593) (xy 431.228042 -184.934958) (xy 431.208119 -184.882867)
			(xy 431.195993 -184.82843) (xy 431.191922 -184.772808) (xy 425.46035 -184.772808) (xy 425.425589 -184.811604)
			(xy 425.382721 -184.847279) (xy 425.335115 -184.876333) (xy 425.283786 -184.898145) (xy 425.229829 -184.912251)
			(xy 425.174392 -184.918351) (xy 425.118658 -184.916314) (xy 425.063815 -184.906184) (xy 425.011031 -184.888177)
			(xy 424.961431 -184.862676) (xy 424.916073 -184.830225) (xy 424.875924 -184.791516) (xy 424.841838 -184.747373)
			(xy 424.814542 -184.698738) (xy 424.794619 -184.646647) (xy 424.782493 -184.59221) (xy 424.778422 -184.536588)
			(xy 410.90342 -184.536588) (xy 411.63748 -185.270648)
		)
		(stroke
			(width 0)
			(type solid)
		)
		(fill yes)
		(layer "In13.Cu")
		(net "GND")
	)
	(gr_poly
		(pts
			(xy 328.584052 -112.088168) (xy 328.597322 -112.087732) (xy 328.622962 -112.080872) (xy 328.645964 -112.067629)
			(xy 328.66477 -112.048901) (xy 328.678109 -112.025955) (xy 328.685076 -112.000344) (xy 328.685652 -111.987076)
			(xy 328.686276 -111.95992) (xy 328.694266 -111.906192) (xy 328.709797 -111.85414) (xy 328.732553 -111.804818)
			(xy 328.762075 -111.759222) (xy 328.797765 -111.718274) (xy 328.838902 -111.682802) (xy 328.884655 -111.653524)
			(xy 328.934098 -111.631031) (xy 328.986231 -111.615778) (xy 329.040001 -111.608074) (xy 329.094319 -111.608074)
			(xy 329.148089 -111.615778) (xy 329.200222 -111.631031) (xy 329.249665 -111.653524) (xy 329.295418 -111.682802)
			(xy 329.336555 -111.718274) (xy 329.372245 -111.759222) (xy 329.401767 -111.804818) (xy 329.424523 -111.85414)
			(xy 329.440054 -111.906192) (xy 329.448044 -111.95992) (xy 329.448668 -111.987076) (xy 329.449159 -112.000355)
			(xy 329.456133 -112.025985) (xy 329.469483 -112.048948) (xy 329.488306 -112.067689) (xy 329.511327 -112.080938)
			(xy 329.536987 -112.0878) (xy 329.550268 -112.088168) (xy 330.049632 -112.088168) (xy 330.063083 -112.087752)
			(xy 330.08905 -112.080721) (xy 330.11228 -112.067154) (xy 330.131163 -112.047993) (xy 330.144388 -112.024566)
			(xy 330.151039 -111.998499) (xy 330.151232 -111.985044) (xy 330.151232 -111.978948) (xy 330.151718 -111.951697)
			(xy 330.159474 -111.897749) (xy 330.174829 -111.845454) (xy 330.197471 -111.795877) (xy 330.226937 -111.750027)
			(xy 330.262628 -111.708836) (xy 330.303819 -111.673145) (xy 330.349669 -111.643679) (xy 330.399246 -111.621037)
			(xy 330.451541 -111.605682) (xy 330.505489 -111.597926) (xy 330.559991 -111.597926) (xy 330.613939 -111.605682)
			(xy 330.666234 -111.621037) (xy 330.715811 -111.643679) (xy 330.761661 -111.673145) (xy 330.802852 -111.708836)
			(xy 330.838543 -111.750027) (xy 330.868009 -111.795877) (xy 330.890651 -111.845454) (xy 330.906006 -111.897749)
			(xy 330.913762 -111.951697) (xy 330.914248 -111.978948) (xy 330.914248 -111.985044) (xy 330.914455 -111.998501)
			(xy 330.921088 -112.024575) (xy 330.934305 -112.048009) (xy 330.953188 -112.067174) (xy 330.976423 -112.080738)
			(xy 331.002396 -112.087757) (xy 331.015848 -112.088168) (xy 422.98874 -112.088168) (xy 423.76852 -111.308388)
			(xy 434.84038 -111.308388) (xy 436.17642 -109.972348) (xy 436.17642 -103.896668) (xy 433.63388 -101.354128)
			(xy 429.313594 -101.354128) (xy 429.298617 -101.354702) (xy 429.269973 -101.36347) (xy 429.245099 -101.380164)
			(xy 429.226131 -101.40335) (xy 429.214697 -101.431039) (xy 429.211778 -101.460852) (xy 429.217626 -101.490233)
			(xy 429.231737 -101.516657) (xy 429.241966 -101.52761) (xy 429.95215 -102.237794) (xy 429.96612 -102.24135)
			(xy 429.993525 -102.248448) (xy 430.04602 -102.269638) (xy 430.094803 -102.298359) (xy 430.138802 -102.33398)
			(xy 430.177047 -102.375717) (xy 430.208699 -102.422652) (xy 430.233061 -102.473752) (xy 430.249596 -102.527893)
			(xy 430.257941 -102.583885) (xy 430.258474 -102.61219) (xy 430.258011 -102.639442) (xy 430.252508 -102.677722)
			(xy 432.170078 -102.677722) (xy 432.170564 -102.650471) (xy 432.17832 -102.596523) (xy 432.193675 -102.544228)
			(xy 432.216317 -102.494651) (xy 432.245783 -102.448801) (xy 432.281474 -102.40761) (xy 432.322665 -102.371919)
			(xy 432.368515 -102.342453) (xy 432.418092 -102.319811) (xy 432.470387 -102.304456) (xy 432.524335 -102.2967)
			(xy 432.578837 -102.2967) (xy 432.632785 -102.304456) (xy 432.68508 -102.319811) (xy 432.734657 -102.342453)
			(xy 432.780507 -102.371919) (xy 432.821698 -102.40761) (xy 432.857389 -102.448801) (xy 432.886855 -102.494651)
			(xy 432.909497 -102.544228) (xy 432.924852 -102.596523) (xy 432.932608 -102.650471) (xy 432.933094 -102.677722)
			(xy 432.932429 -102.709434) (xy 432.921911 -102.771982) (xy 432.901216 -102.831937) (xy 432.886612 -102.860094)
			(xy 432.880202 -102.872935) (xy 432.87402 -102.900946) (xy 432.875883 -102.929571) (xy 432.885645 -102.956544)
			(xy 432.902533 -102.979732) (xy 432.92521 -102.997299) (xy 432.951882 -103.007855) (xy 432.966114 -103.0097)
			(xy 432.991746 -103.012642) (xy 433.04194 -103.024582) (xy 433.090069 -103.043172) (xy 433.135256 -103.068076)
			(xy 433.176676 -103.098838) (xy 433.213577 -103.134899) (xy 433.229766 -103.154988) (xy 433.239663 -103.166793)
			(xy 433.264987 -103.184312) (xy 433.29438 -103.193488) (xy 433.325172 -103.193488) (xy 433.354565 -103.184312)
			(xy 433.379889 -103.166793) (xy 433.389786 -103.154988) (xy 433.407982 -103.132509) (xy 433.450001 -103.092774)
			(xy 433.497535 -103.059835) (xy 433.549495 -103.034446) (xy 433.604692 -103.017188) (xy 433.66186 -103.008458)
			(xy 433.690776 -103.007922) (xy 433.718032 -103.008323) (xy 433.77199 -103.016078) (xy 433.824295 -103.031433)
			(xy 433.873882 -103.054076) (xy 433.919742 -103.083546) (xy 433.960941 -103.119242) (xy 433.99664 -103.160439)
			(xy 434.026112 -103.206297) (xy 434.048758 -103.255883) (xy 434.064117 -103.308187) (xy 434.071875 -103.362144)
			(xy 434.071875 -103.416656) (xy 434.064117 -103.470613) (xy 434.048758 -103.522917) (xy 434.026112 -103.572503)
			(xy 433.99664 -103.618361) (xy 433.960941 -103.659558) (xy 433.919742 -103.695254) (xy 433.873882 -103.724724)
			(xy 433.824295 -103.747367) (xy 433.77199 -103.762722) (xy 433.718032 -103.770477) (xy 433.690776 -103.770938)
			(xy 433.66186 -103.770388) (xy 433.604689 -103.761669) (xy 433.54949 -103.744419) (xy 433.497528 -103.719033)
			(xy 433.449993 -103.686094) (xy 433.407976 -103.646356) (xy 433.389786 -103.623872) (xy 433.379889 -103.612067)
			(xy 433.354565 -103.594548) (xy 433.325172 -103.585372) (xy 433.29438 -103.585372) (xy 433.264987 -103.594548)
			(xy 433.239663 -103.612067) (xy 433.229766 -103.623872) (xy 433.211587 -103.646366) (xy 433.169566 -103.686102)
			(xy 433.122029 -103.71904) (xy 433.070065 -103.744427) (xy 433.014865 -103.761681) (xy 432.957693 -103.770406)
			(xy 432.928776 -103.770938) (xy 432.901526 -103.770445) (xy 432.84758 -103.762686) (xy 432.795287 -103.747329)
			(xy 432.745712 -103.724687) (xy 432.699863 -103.695221) (xy 432.658674 -103.659531) (xy 432.622982 -103.618342)
			(xy 432.593516 -103.572494) (xy 432.570873 -103.522919) (xy 432.555516 -103.470626) (xy 432.547756 -103.41668)
			(xy 432.547268 -103.38943) (xy 432.547919 -103.357717) (xy 432.558443 -103.295169) (xy 432.579144 -103.235215)
			(xy 432.59375 -103.207058) (xy 432.600171 -103.194225) (xy 432.606338 -103.166213) (xy 432.604464 -103.137592)
			(xy 432.594699 -103.110624) (xy 432.577814 -103.087439) (xy 432.555143 -103.069869) (xy 432.528478 -103.059304)
			(xy 432.514248 -103.057452) (xy 432.48632 -103.054223) (xy 432.431787 -103.040557) (xy 432.37985 -103.019038)
			(xy 432.331631 -102.990132) (xy 432.288175 -102.954464) (xy 432.250422 -102.912807) (xy 432.219189 -102.866062)
			(xy 432.195152 -102.81524) (xy 432.178831 -102.761442) (xy 432.17058 -102.705832) (xy 432.170078 -102.677722)
			(xy 430.252508 -102.677722) (xy 430.250255 -102.693393) (xy 430.2349 -102.74569) (xy 430.212257 -102.795269)
			(xy 430.182789 -102.841121) (xy 430.147095 -102.882312) (xy 430.105902 -102.918004) (xy 430.060048 -102.947469)
			(xy 430.010467 -102.970108) (xy 429.958169 -102.98546) (xy 429.904218 -102.993213) (xy 429.876966 -102.993698)
			(xy 429.848662 -102.993181) (xy 429.792675 -102.98481) (xy 429.73854 -102.968259) (xy 429.687445 -102.94389)
			(xy 429.640512 -102.912238) (xy 429.598772 -102.873998) (xy 429.56314 -102.83001) (xy 429.5344 -102.78124)
			(xy 429.513182 -102.728758) (xy 429.506126 -102.701344) (xy 429.50257 -102.687374) (xy 428.169324 -101.354128)
			(xy 415.27476 -101.354128) (xy 413.60598 -99.685348) (xy 413.60598 -24.267668) (xy 412.5468 -23.208488)
			(xy 395.43482 -23.208488) (xy 390.985248 -27.658314) (xy 390.985248 -28.842208) (xy 390.984736 -28.867191)
			(xy 390.976884 -28.916538) (xy 390.961422 -28.964053) (xy 390.938727 -29.008569) (xy 390.909359 -29.048995)
			(xy 390.89203 -29.066998) (xy 390.353804 -29.60497) (xy 390.353804 -29.877258) (xy 412.083756 -29.877258)
			(xy 412.087827 -29.821636) (xy 412.099953 -29.767199) (xy 412.119876 -29.715108) (xy 412.147172 -29.666473)
			(xy 412.181258 -29.62233) (xy 412.221407 -29.583621) (xy 412.266765 -29.55117) (xy 412.316365 -29.525669)
			(xy 412.369149 -29.507662) (xy 412.423992 -29.497532) (xy 412.479726 -29.495495) (xy 412.535163 -29.501595)
			(xy 412.58912 -29.515701) (xy 412.640449 -29.537513) (xy 412.688055 -29.566567) (xy 412.730923 -29.602242)
			(xy 412.76814 -29.643779) (xy 412.798913 -29.690292) (xy 412.822585 -29.740789) (xy 412.838653 -29.794196)
			(xy 412.846773 -29.849372) (xy 412.847282 -29.877258) (xy 412.846773 -29.905144) (xy 412.838653 -29.96032)
			(xy 412.822585 -30.013727) (xy 412.798913 -30.064224) (xy 412.76814 -30.110737) (xy 412.730923 -30.152274)
			(xy 412.688055 -30.187949) (xy 412.640449 -30.217003) (xy 412.58912 -30.238815) (xy 412.535163 -30.252921)
			(xy 412.479726 -30.259021) (xy 412.423992 -30.256984) (xy 412.369149 -30.246854) (xy 412.316365 -30.228847)
			(xy 412.266765 -30.203346) (xy 412.221407 -30.170895) (xy 412.181258 -30.132186) (xy 412.147172 -30.088043)
			(xy 412.119876 -30.039408) (xy 412.099953 -29.987317) (xy 412.087827 -29.93288) (xy 412.083756 -29.877258)
			(xy 390.353804 -29.877258) (xy 390.353804 -29.979874) (xy 390.368883 -30.003443) (xy 390.392715 -30.054063)
			(xy 390.408892 -30.107623) (xy 390.417064 -30.162973) (xy 390.417558 -30.190948) (xy 390.417072 -30.218199)
			(xy 390.409316 -30.272147) (xy 390.393961 -30.324442) (xy 390.371319 -30.374019) (xy 390.341853 -30.419869)
			(xy 390.306162 -30.46106) (xy 390.264971 -30.496751) (xy 390.219121 -30.526217) (xy 390.169544 -30.548859)
			(xy 390.117249 -30.564214) (xy 390.063301 -30.57197) (xy 390.008799 -30.57197) (xy 389.954851 -30.564214)
			(xy 389.902556 -30.548859) (xy 389.852979 -30.526217) (xy 389.807129 -30.496751) (xy 389.765938 -30.46106)
			(xy 389.730247 -30.419869) (xy 389.700781 -30.374019) (xy 389.678139 -30.324442) (xy 389.662784 -30.272147)
			(xy 389.655028 -30.218199) (xy 389.654542 -30.190948) (xy 389.655038 -30.162974) (xy 389.663221 -30.107629)
			(xy 389.679406 -30.054074) (xy 389.703244 -30.003459) (xy 389.718296 -29.979874) (xy 389.718296 -29.473398)
			(xy 389.718738 -29.44842) (xy 389.726515 -29.399073) (xy 389.741924 -29.351552) (xy 389.764584 -29.307031)
			(xy 389.793936 -29.266608) (xy 389.81126 -29.248608) (xy 389.834628 -29.22524) (xy 389.84407 -29.215087)
			(xy 389.857616 -29.190909) (xy 389.86417 -29.16398) (xy 389.863248 -29.136281) (xy 389.854918 -29.109848)
			(xy 389.839793 -29.086625) (xy 389.818986 -29.068318) (xy 389.806688 -29.061918) (xy 389.781352 -29.049227)
			(xy 389.734424 -29.017467) (xy 389.713216 -28.998672) (xy 389.677402 -28.965906) (xy 389.47344 -29.169868)
			(xy 384.43408 -29.169868) (xy 383.15392 -30.450028) (xy 383.15392 -31.018988) (xy 388.110982 -31.018988)
			(xy 388.115053 -30.963366) (xy 388.127179 -30.908929) (xy 388.147102 -30.856838) (xy 388.174398 -30.808203)
			(xy 388.208484 -30.76406) (xy 388.248633 -30.725351) (xy 388.293991 -30.6929) (xy 388.343591 -30.667399)
			(xy 388.396375 -30.649392) (xy 388.451218 -30.639262) (xy 388.506952 -30.637225) (xy 388.562389 -30.643325)
			(xy 388.616346 -30.657431) (xy 388.667675 -30.679243) (xy 388.715281 -30.708297) (xy 388.758149 -30.743972)
			(xy 388.795366 -30.785509) (xy 388.826139 -30.832022) (xy 388.849811 -30.882519) (xy 388.865879 -30.935926)
			(xy 388.873999 -30.991102) (xy 388.874508 -31.018988) (xy 388.873999 -31.046874) (xy 388.865879 -31.10205)
			(xy 388.849811 -31.155457) (xy 388.826139 -31.205954) (xy 388.795366 -31.252467) (xy 388.758149 -31.294004)
			(xy 388.715281 -31.329679) (xy 388.667675 -31.358733) (xy 388.616346 -31.380545) (xy 388.562389 -31.394651)
			(xy 388.506952 -31.400751) (xy 388.451218 -31.398714) (xy 388.396375 -31.388584) (xy 388.343591 -31.370577)
			(xy 388.293991 -31.345076) (xy 388.248633 -31.312625) (xy 388.208484 -31.273916) (xy 388.174398 -31.229773)
			(xy 388.147102 -31.181138) (xy 388.127179 -31.129047) (xy 388.115053 -31.07461) (xy 388.110982 -31.018988)
			(xy 383.15392 -31.018988) (xy 383.15392 -31.968948) (xy 388.110982 -31.968948) (xy 388.115053 -31.913326)
			(xy 388.127179 -31.858889) (xy 388.147102 -31.806798) (xy 388.174398 -31.758163) (xy 388.208484 -31.71402)
			(xy 388.248633 -31.675311) (xy 388.293991 -31.64286) (xy 388.343591 -31.617359) (xy 388.396375 -31.599352)
			(xy 388.451218 -31.589222) (xy 388.506952 -31.587185) (xy 388.506961 -31.587186) (xy 394.069822 -31.587186)
			(xy 394.073893 -31.531564) (xy 394.086019 -31.477127) (xy 394.105942 -31.425036) (xy 394.133238 -31.376401)
			(xy 394.167324 -31.332258) (xy 394.207473 -31.293549) (xy 394.252831 -31.261098) (xy 394.302431 -31.235597)
			(xy 394.355215 -31.21759) (xy 394.410058 -31.20746) (xy 394.465792 -31.205423) (xy 394.521229 -31.211523)
			(xy 394.575186 -31.225629) (xy 394.626515 -31.247441) (xy 394.674121 -31.276495) (xy 394.716989 -31.31217)
			(xy 394.754206 -31.353707) (xy 394.784979 -31.40022) (xy 394.808651 -31.450717) (xy 394.824719 -31.504124)
			(xy 394.832839 -31.5593) (xy 394.833348 -31.587186) (xy 394.832839 -31.615072) (xy 394.824719 -31.670248)
			(xy 394.808651 -31.723655) (xy 394.784979 -31.774152) (xy 394.754206 -31.820665) (xy 394.716989 -31.862202)
			(xy 394.674121 -31.897877) (xy 394.626515 -31.926931) (xy 394.575186 -31.948743) (xy 394.521229 -31.962849)
			(xy 394.465792 -31.968949) (xy 394.410058 -31.966912) (xy 394.355215 -31.956782) (xy 394.302431 -31.938775)
			(xy 394.252831 -31.913274) (xy 394.207473 -31.880823) (xy 394.167324 -31.842114) (xy 394.133238 -31.797971)
			(xy 394.105942 -31.749336) (xy 394.086019 -31.697245) (xy 394.073893 -31.642808) (xy 394.069822 -31.587186)
			(xy 388.506961 -31.587186) (xy 388.562389 -31.593285) (xy 388.616346 -31.607391) (xy 388.667675 -31.629203)
			(xy 388.715281 -31.658257) (xy 388.758149 -31.693932) (xy 388.795366 -31.735469) (xy 388.826139 -31.781982)
			(xy 388.849811 -31.832479) (xy 388.865879 -31.885886) (xy 388.873999 -31.941062) (xy 388.874508 -31.968948)
			(xy 388.873999 -31.996834) (xy 388.865879 -32.05201) (xy 388.849811 -32.105417) (xy 388.826139 -32.155914)
			(xy 388.795366 -32.202427) (xy 388.758149 -32.243964) (xy 388.715281 -32.279639) (xy 388.667675 -32.308693)
			(xy 388.616346 -32.330505) (xy 388.562389 -32.344611) (xy 388.506952 -32.350711) (xy 388.451218 -32.348674)
			(xy 388.396375 -32.338544) (xy 388.343591 -32.320537) (xy 388.293991 -32.295036) (xy 388.248633 -32.262585)
			(xy 388.208484 -32.223876) (xy 388.174398 -32.179733) (xy 388.147102 -32.131098) (xy 388.127179 -32.079007)
			(xy 388.115053 -32.02457) (xy 388.110982 -31.968948) (xy 383.15392 -31.968948) (xy 383.15392 -32.456374)
			(xy 394.127988 -32.456374) (xy 394.132059 -32.400752) (xy 394.144185 -32.346315) (xy 394.164108 -32.294224)
			(xy 394.191404 -32.245589) (xy 394.22549 -32.201446) (xy 394.265639 -32.162737) (xy 394.310997 -32.130286)
			(xy 394.360597 -32.104785) (xy 394.413381 -32.086778) (xy 394.468224 -32.076648) (xy 394.523958 -32.074611)
			(xy 394.579395 -32.080711) (xy 394.633352 -32.094817) (xy 394.684681 -32.116629) (xy 394.732287 -32.145683)
			(xy 394.775155 -32.181358) (xy 394.812372 -32.222895) (xy 394.843145 -32.269408) (xy 394.866817 -32.319905)
			(xy 394.882885 -32.373312) (xy 394.891005 -32.428488) (xy 394.891514 -32.456374) (xy 394.891005 -32.48426)
			(xy 394.882885 -32.539436) (xy 394.866817 -32.592843) (xy 394.843145 -32.64334) (xy 394.812372 -32.689853)
			(xy 394.775155 -32.73139) (xy 394.732287 -32.767065) (xy 394.684681 -32.796119) (xy 394.633352 -32.817931)
			(xy 394.579395 -32.832037) (xy 394.523958 -32.838137) (xy 394.468224 -32.8361) (xy 394.413381 -32.82597)
			(xy 394.360597 -32.807963) (xy 394.310997 -32.782462) (xy 394.265639 -32.750011) (xy 394.22549 -32.711302)
			(xy 394.191404 -32.667159) (xy 394.164108 -32.618524) (xy 394.144185 -32.566433) (xy 394.132059 -32.511996)
			(xy 394.127988 -32.456374) (xy 383.15392 -32.456374) (xy 383.15392 -32.918908) (xy 388.110982 -32.918908)
			(xy 388.115053 -32.863286) (xy 388.127179 -32.808849) (xy 388.147102 -32.756758) (xy 388.174398 -32.708123)
			(xy 388.208484 -32.66398) (xy 388.248633 -32.625271) (xy 388.293991 -32.59282) (xy 388.343591 -32.567319)
			(xy 388.396375 -32.549312) (xy 388.451218 -32.539182) (xy 388.506952 -32.537145) (xy 388.562389 -32.543245)
			(xy 388.616346 -32.557351) (xy 388.667675 -32.579163) (xy 388.715281 -32.608217) (xy 388.758149 -32.643892)
			(xy 388.795366 -32.685429) (xy 388.826139 -32.731942) (xy 388.849811 -32.782439) (xy 388.865879 -32.835846)
			(xy 388.873999 -32.891022) (xy 388.874508 -32.918908) (xy 388.873999 -32.946794) (xy 388.865879 -33.00197)
			(xy 388.849811 -33.055377) (xy 388.826139 -33.105874) (xy 388.795366 -33.152387) (xy 388.758149 -33.193924)
			(xy 388.715281 -33.229599) (xy 388.667675 -33.258653) (xy 388.616346 -33.280465) (xy 388.562389 -33.294571)
			(xy 388.506952 -33.300671) (xy 388.451218 -33.298634) (xy 388.396375 -33.288504) (xy 388.343591 -33.270497)
			(xy 388.293991 -33.244996) (xy 388.248633 -33.212545) (xy 388.208484 -33.173836) (xy 388.174398 -33.129693)
			(xy 388.147102 -33.081058) (xy 388.127179 -33.028967) (xy 388.115053 -32.97453) (xy 388.110982 -32.918908)
			(xy 383.15392 -32.918908) (xy 383.15392 -33.785048) (xy 384.58902 -35.220148) (xy 385.336032 -35.220148)
			(xy 385.340103 -35.164526) (xy 385.352229 -35.110089) (xy 385.372152 -35.057998) (xy 385.399448 -35.009363)
			(xy 385.433534 -34.96522) (xy 385.473683 -34.926511) (xy 385.519041 -34.89406) (xy 385.568641 -34.868559)
			(xy 385.621425 -34.850552) (xy 385.676268 -34.840422) (xy 385.732002 -34.838385) (xy 385.787439 -34.844485)
			(xy 385.841396 -34.858591) (xy 385.892725 -34.880403) (xy 385.940331 -34.909457) (xy 385.983199 -34.945132)
			(xy 386.020416 -34.986669) (xy 386.051189 -35.033182) (xy 386.074861 -35.083679) (xy 386.085428 -35.118802)
			(xy 394.394688 -35.118802) (xy 394.398759 -35.06318) (xy 394.410885 -35.008743) (xy 394.430808 -34.956652)
			(xy 394.458104 -34.908017) (xy 394.49219 -34.863874) (xy 394.532339 -34.825165) (xy 394.577697 -34.792714)
			(xy 394.627297 -34.767213) (xy 394.680081 -34.749206) (xy 394.734924 -34.739076) (xy 394.790658 -34.737039)
			(xy 394.846095 -34.743139) (xy 394.900052 -34.757245) (xy 394.951381 -34.779057) (xy 394.998987 -34.808111)
			(xy 395.041855 -34.843786) (xy 395.079072 -34.885323) (xy 395.109845 -34.931836) (xy 395.133517 -34.982333)
			(xy 395.149585 -35.03574) (xy 395.157705 -35.090916) (xy 395.158214 -35.118802) (xy 395.157705 -35.146688)
			(xy 395.149585 -35.201864) (xy 395.133517 -35.255271) (xy 395.109845 -35.305768) (xy 395.079072 -35.352281)
			(xy 395.041855 -35.393818) (xy 394.998987 -35.429493) (xy 394.951381 -35.458547) (xy 394.900052 -35.480359)
			(xy 394.846095 -35.494465) (xy 394.790658 -35.500565) (xy 394.734924 -35.498528) (xy 394.680081 -35.488398)
			(xy 394.627297 -35.470391) (xy 394.577697 -35.44489) (xy 394.532339 -35.412439) (xy 394.49219 -35.37373)
			(xy 394.458104 -35.329587) (xy 394.430808 -35.280952) (xy 394.410885 -35.228861) (xy 394.398759 -35.174424)
			(xy 394.394688 -35.118802) (xy 386.085428 -35.118802) (xy 386.090929 -35.137086) (xy 386.099049 -35.192262)
			(xy 386.099558 -35.220148) (xy 386.099049 -35.248034) (xy 386.090929 -35.30321) (xy 386.074861 -35.356617)
			(xy 386.051189 -35.407114) (xy 386.020416 -35.453627) (xy 385.983199 -35.495164) (xy 385.940331 -35.530839)
			(xy 385.892725 -35.559893) (xy 385.841396 -35.581705) (xy 385.810745 -35.589718) (xy 387.393432 -35.589718)
			(xy 387.397503 -35.534096) (xy 387.409629 -35.479659) (xy 387.429552 -35.427568) (xy 387.456848 -35.378933)
			(xy 387.490934 -35.33479) (xy 387.531083 -35.296081) (xy 387.576441 -35.26363) (xy 387.626041 -35.238129)
			(xy 387.678825 -35.220122) (xy 387.733668 -35.209992) (xy 387.789402 -35.207955) (xy 387.844839 -35.214055)
			(xy 387.898796 -35.228161) (xy 387.950125 -35.249973) (xy 387.997731 -35.279027) (xy 388.040599 -35.314702)
			(xy 388.077816 -35.356239) (xy 388.108589 -35.402752) (xy 388.132261 -35.453249) (xy 388.148329 -35.506656)
			(xy 388.156449 -35.561832) (xy 388.156958 -35.589718) (xy 388.156449 -35.617604) (xy 388.148329 -35.67278)
			(xy 388.132261 -35.726187) (xy 388.108589 -35.776684) (xy 388.077816 -35.823197) (xy 388.040599 -35.864734)
			(xy 387.997731 -35.900409) (xy 387.950125 -35.929463) (xy 387.898796 -35.951275) (xy 387.878833 -35.956494)
			(xy 391.387836 -35.956494) (xy 391.391907 -35.900872) (xy 391.404033 -35.846435) (xy 391.423956 -35.794344)
			(xy 391.451252 -35.745709) (xy 391.485338 -35.701566) (xy 391.525487 -35.662857) (xy 391.570845 -35.630406)
			(xy 391.620445 -35.604905) (xy 391.673229 -35.586898) (xy 391.728072 -35.576768) (xy 391.783806 -35.574731)
			(xy 391.839243 -35.580831) (xy 391.8932 -35.594937) (xy 391.944529 -35.616749) (xy 391.992135 -35.645803)
			(xy 392.035003 -35.681478) (xy 392.07222 -35.723015) (xy 392.102993 -35.769528) (xy 392.126665 -35.820025)
			(xy 392.142733 -35.873432) (xy 392.150853 -35.928608) (xy 392.151362 -35.956494) (xy 392.150853 -35.98438)
			(xy 392.142733 -36.039556) (xy 392.126665 -36.092963) (xy 392.102993 -36.14346) (xy 392.07222 -36.189973)
			(xy 392.035003 -36.23151) (xy 391.992135 -36.267185) (xy 391.944529 -36.296239) (xy 391.8932 -36.318051)
			(xy 391.839243 -36.332157) (xy 391.783806 -36.338257) (xy 391.728072 -36.33622) (xy 391.673229 -36.32609)
			(xy 391.620445 -36.308083) (xy 391.570845 -36.282582) (xy 391.525487 -36.250131) (xy 391.485338 -36.211422)
			(xy 391.451252 -36.167279) (xy 391.423956 -36.118644) (xy 391.404033 -36.066553) (xy 391.391907 -36.012116)
			(xy 391.387836 -35.956494) (xy 387.878833 -35.956494) (xy 387.844839 -35.965381) (xy 387.789402 -35.971481)
			(xy 387.733668 -35.969444) (xy 387.678825 -35.959314) (xy 387.626041 -35.941307) (xy 387.576441 -35.915806)
			(xy 387.531083 -35.883355) (xy 387.490934 -35.844646) (xy 387.456848 -35.800503) (xy 387.429552 -35.751868)
			(xy 387.409629 -35.699777) (xy 387.397503 -35.64534) (xy 387.393432 -35.589718) (xy 385.810745 -35.589718)
			(xy 385.787439 -35.595811) (xy 385.732002 -35.601911) (xy 385.676268 -35.599874) (xy 385.621425 -35.589744)
			(xy 385.568641 -35.571737) (xy 385.519041 -35.546236) (xy 385.473683 -35.513785) (xy 385.433534 -35.475076)
			(xy 385.399448 -35.430933) (xy 385.372152 -35.382298) (xy 385.352229 -35.330207) (xy 385.340103 -35.27577)
			(xy 385.336032 -35.220148) (xy 384.58902 -35.220148) (xy 386.510022 -37.14115) (xy 387.243064 -37.14115)
			(xy 387.247135 -37.085528) (xy 387.259261 -37.031091) (xy 387.279184 -36.979) (xy 387.30648 -36.930365)
			(xy 387.340566 -36.886222) (xy 387.380715 -36.847513) (xy 387.426073 -36.815062) (xy 387.475673 -36.789561)
			(xy 387.528457 -36.771554) (xy 387.5833 -36.761424) (xy 387.639034 -36.759387) (xy 387.694471 -36.765487)
			(xy 387.748428 -36.779593) (xy 387.799757 -36.801405) (xy 387.847363 -36.830459) (xy 387.890231 -36.866134)
			(xy 387.927448 -36.907671) (xy 387.958221 -36.954184) (xy 387.981893 -37.004681) (xy 387.997961 -37.058088)
			(xy 388.006081 -37.113264) (xy 388.00659 -37.14115) (xy 388.006081 -37.169036) (xy 387.997961 -37.224212)
			(xy 387.981893 -37.277619) (xy 387.958221 -37.328116) (xy 387.927448 -37.374629) (xy 387.890231 -37.416166)
			(xy 387.847363 -37.451841) (xy 387.799757 -37.480895) (xy 387.748428 -37.502707) (xy 387.694471 -37.516813)
			(xy 387.678285 -37.518594) (xy 394.854428 -37.518594) (xy 394.858499 -37.462972) (xy 394.870625 -37.408535)
			(xy 394.890548 -37.356444) (xy 394.917844 -37.307809) (xy 394.95193 -37.263666) (xy 394.992079 -37.224957)
			(xy 395.037437 -37.192506) (xy 395.087037 -37.167005) (xy 395.139821 -37.148998) (xy 395.194664 -37.138868)
			(xy 395.250398 -37.136831) (xy 395.305835 -37.142931) (xy 395.359792 -37.157037) (xy 395.411121 -37.178849)
			(xy 395.458727 -37.207903) (xy 395.501595 -37.243578) (xy 395.538812 -37.285115) (xy 395.569585 -37.331628)
			(xy 395.593257 -37.382125) (xy 395.609325 -37.435532) (xy 395.617445 -37.490708) (xy 395.617954 -37.518594)
			(xy 395.617445 -37.54648) (xy 395.609325 -37.601656) (xy 395.593257 -37.655063) (xy 395.569585 -37.70556)
			(xy 395.538812 -37.752073) (xy 395.501595 -37.79361) (xy 395.458727 -37.829285) (xy 395.411121 -37.858339)
			(xy 395.359792 -37.880151) (xy 395.305835 -37.894257) (xy 395.250398 -37.900357) (xy 395.194664 -37.89832)
			(xy 395.139821 -37.88819) (xy 395.087037 -37.870183) (xy 395.037437 -37.844682) (xy 394.992079 -37.812231)
			(xy 394.95193 -37.773522) (xy 394.917844 -37.729379) (xy 394.890548 -37.680744) (xy 394.870625 -37.628653)
			(xy 394.858499 -37.574216) (xy 394.854428 -37.518594) (xy 387.678285 -37.518594) (xy 387.639034 -37.522913)
			(xy 387.5833 -37.520876) (xy 387.528457 -37.510746) (xy 387.475673 -37.492739) (xy 387.426073 -37.467238)
			(xy 387.380715 -37.434787) (xy 387.340566 -37.396078) (xy 387.30648 -37.351935) (xy 387.279184 -37.3033)
			(xy 387.259261 -37.251209) (xy 387.247135 -37.196772) (xy 387.243064 -37.14115) (xy 386.510022 -37.14115)
			(xy 388.007098 -38.638226) (xy 388.016878 -38.647446) (xy 388.040167 -38.660847) (xy 388.066149 -38.667694)
			(xy 388.093017 -38.667513) (xy 388.118904 -38.660314) (xy 388.142009 -38.6466) (xy 388.151624 -38.63721)
			(xy 388.169651 -38.619272) (xy 388.209633 -38.587844) (xy 388.253437 -38.562007) (xy 388.300286 -38.542221)
			(xy 388.349348 -38.528835) (xy 388.399754 -38.522088) (xy 388.425182 -38.52164) (xy 388.452434 -38.522102)
			(xy 388.506385 -38.529857) (xy 388.558682 -38.545212) (xy 388.608261 -38.567854) (xy 388.654113 -38.597323)
			(xy 388.695304 -38.633017) (xy 388.730995 -38.674211) (xy 388.76046 -38.720065) (xy 388.783098 -38.769646)
			(xy 388.798449 -38.821945) (xy 388.8062 -38.875896) (xy 388.80669 -38.903148) (xy 388.806267 -38.928576)
			(xy 388.799505 -38.978979) (xy 388.786109 -39.028038) (xy 388.766315 -39.074883) (xy 388.740474 -39.118684)
			(xy 388.709044 -39.158664) (xy 388.69112 -39.176706) (xy 388.681809 -39.186378) (xy 388.668161 -39.209486)
			(xy 388.660994 -39.23535) (xy 388.6608 -39.262187) (xy 388.667593 -39.288151) (xy 388.680906 -39.311454)
			(xy 388.690104 -39.321232) (xy 388.80542 -39.436548) (xy 389.622282 -39.436548) (xy 389.626353 -39.380926)
			(xy 389.638479 -39.326489) (xy 389.658402 -39.274398) (xy 389.685698 -39.225763) (xy 389.719784 -39.18162)
			(xy 389.759933 -39.142911) (xy 389.805291 -39.11046) (xy 389.854891 -39.084959) (xy 389.907675 -39.066952)
			(xy 389.962518 -39.056822) (xy 390.018252 -39.054785) (xy 390.073689 -39.060885) (xy 390.127646 -39.074991)
			(xy 390.178975 -39.096803) (xy 390.226581 -39.125857) (xy 390.269449 -39.161532) (xy 390.306666 -39.203069)
			(xy 390.337439 -39.249582) (xy 390.361111 -39.300079) (xy 390.377179 -39.353486) (xy 390.385299 -39.408662)
			(xy 390.385808 -39.436548) (xy 390.385299 -39.464434) (xy 390.377179 -39.51961) (xy 390.361111 -39.573017)
			(xy 390.337439 -39.623514) (xy 390.331236 -39.63289) (xy 392.16203 -39.63289) (xy 392.162516 -39.605639)
			(xy 392.170272 -39.551691) (xy 392.185627 -39.499396) (xy 392.208269 -39.449819) (xy 392.237735 -39.403969)
			(xy 392.273426 -39.362778) (xy 392.314617 -39.327087) (xy 392.360467 -39.297621) (xy 392.410044 -39.274979)
			(xy 392.462339 -39.259624) (xy 392.516287 -39.251868) (xy 392.570789 -39.251868) (xy 392.624737 -39.259624)
			(xy 392.677032 -39.274979) (xy 392.726609 -39.297621) (xy 392.772459 -39.327087) (xy 392.81365 -39.362778)
			(xy 392.849341 -39.403969) (xy 392.878807 -39.449819) (xy 392.901449 -39.499396) (xy 392.916804 -39.551691)
			(xy 392.92456 -39.605639) (xy 392.925046 -39.63289) (xy 392.924619 -39.658681) (xy 392.917653 -39.709792)
			(xy 392.903862 -39.759497) (xy 392.883497 -39.806889) (xy 392.856929 -39.851104) (xy 392.824644 -39.891333)
			(xy 392.78723 -39.926844) (xy 392.76655 -39.942262) (xy 392.754555 -39.951581) (xy 392.736203 -39.975765)
			(xy 392.725775 -40.004276) (xy 392.724191 -40.034593) (xy 392.731593 -40.064036) (xy 392.747326 -40.089999)
			(xy 392.769998 -40.110189) (xy 392.783568 -40.117014) (xy 392.808018 -40.128857) (xy 392.853625 -40.158373)
			(xy 392.894584 -40.19406) (xy 392.930067 -40.235196) (xy 392.959355 -40.28095) (xy 392.981858 -40.330395)
			(xy 392.997118 -40.382533) (xy 393.004828 -40.436308) (xy 393.00531 -40.46347) (xy 393.004824 -40.490721)
			(xy 392.997068 -40.544669) (xy 392.981713 -40.596964) (xy 392.959071 -40.646541) (xy 392.929605 -40.692391)
			(xy 392.893914 -40.733582) (xy 392.852723 -40.769273) (xy 392.806873 -40.798739) (xy 392.757296 -40.821381)
			(xy 392.705001 -40.836736) (xy 392.651053 -40.844492) (xy 392.596551 -40.844492) (xy 392.542603 -40.836736)
			(xy 392.490308 -40.821381) (xy 392.440731 -40.798739) (xy 392.394881 -40.769273) (xy 392.35369 -40.733582)
			(xy 392.317999 -40.692391) (xy 392.288533 -40.646541) (xy 392.265891 -40.596964) (xy 392.250536 -40.544669)
			(xy 392.24278 -40.490721) (xy 392.242294 -40.46347) (xy 392.242716 -40.437679) (xy 392.249686 -40.386569)
			(xy 392.26348 -40.336865) (xy 392.283846 -40.289474) (xy 392.310414 -40.245259) (xy 392.342699 -40.205029)
			(xy 392.380111 -40.169517) (xy 392.40079 -40.154098) (xy 392.412818 -40.144821) (xy 392.431162 -40.120625)
			(xy 392.441583 -40.092106) (xy 392.44316 -40.061783) (xy 392.435753 -40.032337) (xy 392.420017 -40.006369)
			(xy 392.397343 -39.986175) (xy 392.383772 -39.979346) (xy 392.359292 -39.967562) (xy 392.313686 -39.938035)
			(xy 392.27273 -39.902339) (xy 392.237251 -39.861194) (xy 392.207966 -39.815432) (xy 392.185469 -39.765979)
			(xy 392.170214 -39.713835) (xy 392.162509 -39.660055) (xy 392.16203 -39.63289) (xy 390.331236 -39.63289)
			(xy 390.306666 -39.670027) (xy 390.269449 -39.711564) (xy 390.226581 -39.747239) (xy 390.178975 -39.776293)
			(xy 390.127646 -39.798105) (xy 390.073689 -39.812211) (xy 390.018252 -39.818311) (xy 389.962518 -39.816274)
			(xy 389.907675 -39.806144) (xy 389.854891 -39.788137) (xy 389.805291 -39.762636) (xy 389.759933 -39.730185)
			(xy 389.719784 -39.691476) (xy 389.685698 -39.647333) (xy 389.658402 -39.598698) (xy 389.638479 -39.546607)
			(xy 389.626353 -39.49217) (xy 389.622282 -39.436548) (xy 388.80542 -39.436548) (xy 396.473426 -47.104554)
			(xy 396.483554 -47.114035) (xy 396.507706 -47.12766) (xy 396.534635 -47.134279) (xy 396.562351 -47.133403)
			(xy 396.588808 -47.125097) (xy 396.612052 -47.109975) (xy 396.630366 -47.089152) (xy 396.642397 -47.064168)
			(xy 396.647257 -47.036867) (xy 396.6464 -47.02302) (xy 396.642803 -46.980253) (xy 396.642578 -46.894423)
			(xy 396.650281 -46.808939) (xy 396.665848 -46.724532) (xy 396.689145 -46.641923) (xy 396.719973 -46.56182)
			(xy 396.758068 -46.484907) (xy 396.803105 -46.411842) (xy 396.854698 -46.343249) (xy 396.912407 -46.279715)
			(xy 396.975738 -46.221783) (xy 397.044149 -46.169949) (xy 397.117056 -46.124655) (xy 397.193834 -46.08629)
			(xy 397.273829 -46.05518) (xy 397.356354 -46.031593) (xy 397.440706 -46.01573) (xy 397.526163 -46.007726)
			(xy 397.611993 -46.00765) (xy 397.697464 -46.015502) (xy 397.781843 -46.031216) (xy 397.864411 -46.054657)
			(xy 397.94446 -46.085624) (xy 398.021307 -46.123853) (xy 398.094294 -46.169018) (xy 398.162797 -46.22073)
			(xy 398.22623 -46.27855) (xy 398.284051 -46.341981) (xy 398.335766 -46.410483) (xy 398.380933 -46.483468)
			(xy 398.419164 -46.560314) (xy 398.450134 -46.640362) (xy 398.473578 -46.722929) (xy 398.489294 -46.807308)
			(xy 398.497149 -46.892779) (xy 398.497075 -46.978609) (xy 398.489074 -47.064066) (xy 398.473213 -47.148418)
			(xy 398.449629 -47.230945) (xy 398.418522 -47.31094) (xy 398.380159 -47.38772) (xy 398.334867 -47.460628)
			(xy 398.283035 -47.52904) (xy 398.225105 -47.592373) (xy 398.161573 -47.650084) (xy 398.092982 -47.701679)
			(xy 398.019918 -47.746718) (xy 397.943006 -47.784816) (xy 397.862904 -47.815646) (xy 397.780296 -47.838946)
			(xy 397.695889 -47.854515) (xy 397.610406 -47.862221) (xy 397.524575 -47.861998) (xy 397.481806 -47.858426)
			(xy 397.467969 -47.857581) (xy 397.440695 -47.862475) (xy 397.415742 -47.874522) (xy 397.394946 -47.892835)
			(xy 397.37984 -47.916065) (xy 397.371535 -47.942501) (xy 397.370645 -47.970196) (xy 397.377233 -47.997111)
			(xy 397.390816 -48.021263) (xy 397.400272 -48.0314) (xy 398.2212 -48.852328) (xy 398.2212 -49.009554)
			(xy 406.97023 -49.009554) (xy 406.970773 -48.980216) (xy 406.979775 -48.922235) (xy 406.997544 -48.866314)
			(xy 407.023663 -48.813772) (xy 407.057515 -48.765846) (xy 407.098303 -48.723665) (xy 407.12136 -48.705516)
			(xy 407.133326 -48.695672) (xy 407.151249 -48.67042) (xy 407.160798 -48.640962) (xy 407.161098 -48.609997)
			(xy 407.152121 -48.58036) (xy 407.134691 -48.554765) (xy 407.122884 -48.544734) (xy 407.100725 -48.526527)
			(xy 407.061586 -48.484608) (xy 407.029162 -48.437304) (xy 407.004181 -48.385681) (xy 406.987207 -48.330901)
			(xy 406.978621 -48.274197) (xy 406.978104 -48.245522) (xy 406.97859 -48.218271) (xy 406.986346 -48.164323)
			(xy 407.001701 -48.112028) (xy 407.024343 -48.062451) (xy 407.053809 -48.016601) (xy 407.0895 -47.97541)
			(xy 407.130691 -47.939719) (xy 407.176541 -47.910253) (xy 407.226118 -47.887611) (xy 407.278413 -47.872256)
			(xy 407.332361 -47.8645) (xy 407.386863 -47.8645) (xy 407.440811 -47.872256) (xy 407.493106 -47.887611)
			(xy 407.542683 -47.910253) (xy 407.588533 -47.939719) (xy 407.629724 -47.97541) (xy 407.665415 -48.016601)
			(xy 407.694881 -48.062451) (xy 407.717523 -48.112028) (xy 407.732878 -48.164323) (xy 407.740634 -48.218271)
			(xy 407.74112 -48.245522) (xy 407.74054 -48.274858) (xy 407.731543 -48.332837) (xy 407.71378 -48.388756)
			(xy 407.687668 -48.441298) (xy 407.653823 -48.489225) (xy 407.613043 -48.531409) (xy 407.58999 -48.54956)
			(xy 407.577953 -48.559322) (xy 407.560039 -48.584599) (xy 407.550504 -48.614076) (xy 407.550218 -48.645056)
			(xy 407.559208 -48.674704) (xy 407.576652 -48.700307) (xy 407.588466 -48.710342) (xy 407.610624 -48.72855)
			(xy 407.64976 -48.77047) (xy 407.682184 -48.817774) (xy 407.707164 -48.869397) (xy 407.724139 -48.924177)
			(xy 407.732727 -48.980879) (xy 407.733246 -49.009554) (xy 407.73276 -49.036805) (xy 407.725004 -49.090753)
			(xy 407.709649 -49.143048) (xy 407.687007 -49.192625) (xy 407.657541 -49.238475) (xy 407.62185 -49.279666)
			(xy 407.580659 -49.315357) (xy 407.534809 -49.344823) (xy 407.485232 -49.367465) (xy 407.432937 -49.38282)
			(xy 407.378989 -49.390576) (xy 407.324487 -49.390576) (xy 407.270539 -49.38282) (xy 407.218244 -49.367465)
			(xy 407.168667 -49.344823) (xy 407.122817 -49.315357) (xy 407.081626 -49.279666) (xy 407.045935 -49.238475)
			(xy 407.016469 -49.192625) (xy 406.993827 -49.143048) (xy 406.978472 -49.090753) (xy 406.970716 -49.036805)
			(xy 406.97023 -49.009554) (xy 398.2212 -49.009554) (xy 398.2212 -50.307494) (xy 406.964386 -50.307494)
			(xy 406.968457 -50.251872) (xy 406.980583 -50.197435) (xy 407.000506 -50.145344) (xy 407.027802 -50.096709)
			(xy 407.061888 -50.052566) (xy 407.102037 -50.013857) (xy 407.147395 -49.981406) (xy 407.196995 -49.955905)
			(xy 407.249779 -49.937898) (xy 407.304622 -49.927768) (xy 407.360356 -49.925731) (xy 407.415793 -49.931831)
			(xy 407.46975 -49.945937) (xy 407.521079 -49.967749) (xy 407.568685 -49.996803) (xy 407.611553 -50.032478)
			(xy 407.64877 -50.074015) (xy 407.679543 -50.120528) (xy 407.703215 -50.171025) (xy 407.719283 -50.224432)
			(xy 407.727403 -50.279608) (xy 407.727912 -50.307494) (xy 407.727403 -50.33538) (xy 407.719283 -50.390556)
			(xy 407.703215 -50.443963) (xy 407.679543 -50.49446) (xy 407.64877 -50.540973) (xy 407.611553 -50.58251)
			(xy 407.568685 -50.618185) (xy 407.521079 -50.647239) (xy 407.46975 -50.669051) (xy 407.415793 -50.683157)
			(xy 407.360356 -50.689257) (xy 407.304622 -50.68722) (xy 407.249779 -50.67709) (xy 407.196995 -50.659083)
			(xy 407.147395 -50.633582) (xy 407.102037 -50.601131) (xy 407.061888 -50.562422) (xy 407.027802 -50.518279)
			(xy 407.000506 -50.469644) (xy 406.980583 -50.417553) (xy 406.968457 -50.363116) (xy 406.964386 -50.307494)
			(xy 398.2212 -50.307494) (xy 398.2212 -51.410108) (xy 406.914602 -51.410108) (xy 406.918673 -51.354486)
			(xy 406.930799 -51.300049) (xy 406.950722 -51.247958) (xy 406.978018 -51.199323) (xy 407.012104 -51.15518)
			(xy 407.052253 -51.116471) (xy 407.097611 -51.08402) (xy 407.147211 -51.058519) (xy 407.199995 -51.040512)
			(xy 407.254838 -51.030382) (xy 407.310572 -51.028345) (xy 407.366009 -51.034445) (xy 407.419966 -51.048551)
			(xy 407.471295 -51.070363) (xy 407.518901 -51.099417) (xy 407.561769 -51.135092) (xy 407.598986 -51.176629)
			(xy 407.629759 -51.223142) (xy 407.653431 -51.273639) (xy 407.669499 -51.327046) (xy 407.677619 -51.382222)
			(xy 407.678128 -51.410108) (xy 407.677619 -51.437994) (xy 407.669499 -51.49317) (xy 407.653431 -51.546577)
			(xy 407.629759 -51.597074) (xy 407.598986 -51.643587) (xy 407.561769 -51.685124) (xy 407.518901 -51.720799)
			(xy 407.471295 -51.749853) (xy 407.419966 -51.771665) (xy 407.366009 -51.785771) (xy 407.310572 -51.791871)
			(xy 407.254838 -51.789834) (xy 407.199995 -51.779704) (xy 407.147211 -51.761697) (xy 407.097611 -51.736196)
			(xy 407.052253 -51.703745) (xy 407.012104 -51.665036) (xy 406.978018 -51.620893) (xy 406.950722 -51.572258)
			(xy 406.930799 -51.520167) (xy 406.918673 -51.46573) (xy 406.914602 -51.410108) (xy 398.2212 -51.410108)
			(xy 398.2212 -52.553108) (xy 406.927302 -52.553108) (xy 406.931373 -52.497486) (xy 406.943499 -52.443049)
			(xy 406.963422 -52.390958) (xy 406.990718 -52.342323) (xy 407.024804 -52.29818) (xy 407.064953 -52.259471)
			(xy 407.110311 -52.22702) (xy 407.159911 -52.201519) (xy 407.212695 -52.183512) (xy 407.267538 -52.173382)
			(xy 407.323272 -52.171345) (xy 407.378709 -52.177445) (xy 407.432666 -52.191551) (xy 407.483995 -52.213363)
			(xy 407.531601 -52.242417) (xy 407.574469 -52.278092) (xy 407.611686 -52.319629) (xy 407.642459 -52.366142)
			(xy 407.666131 -52.416639) (xy 407.682199 -52.470046) (xy 407.690319 -52.525222) (xy 407.690828 -52.553108)
			(xy 407.690319 -52.580994) (xy 407.682199 -52.63617) (xy 407.666131 -52.689577) (xy 407.642459 -52.740074)
			(xy 407.611686 -52.786587) (xy 407.574469 -52.828124) (xy 407.531601 -52.863799) (xy 407.483995 -52.892853)
			(xy 407.432666 -52.914665) (xy 407.378709 -52.928771) (xy 407.323272 -52.934871) (xy 407.267538 -52.932834)
			(xy 407.212695 -52.922704) (xy 407.159911 -52.904697) (xy 407.110311 -52.879196) (xy 407.064953 -52.846745)
			(xy 407.024804 -52.808036) (xy 406.990718 -52.763893) (xy 406.963422 -52.715258) (xy 406.943499 -52.663167)
			(xy 406.931373 -52.60873) (xy 406.927302 -52.553108) (xy 398.2212 -52.553108) (xy 398.2212 -54.743604)
			(xy 405.114758 -54.743604) (xy 405.118829 -54.687982) (xy 405.130955 -54.633545) (xy 405.150878 -54.581454)
			(xy 405.178174 -54.532819) (xy 405.21226 -54.488676) (xy 405.252409 -54.449967) (xy 405.297767 -54.417516)
			(xy 405.347367 -54.392015) (xy 405.400151 -54.374008) (xy 405.454994 -54.363878) (xy 405.510728 -54.361841)
			(xy 405.566165 -54.367941) (xy 405.620122 -54.382047) (xy 405.671451 -54.403859) (xy 405.719057 -54.432913)
			(xy 405.761925 -54.468588) (xy 405.799142 -54.510125) (xy 405.829915 -54.556638) (xy 405.853587 -54.607135)
			(xy 405.869655 -54.660542) (xy 405.877775 -54.715718) (xy 405.878284 -54.743604) (xy 405.877775 -54.77149)
			(xy 405.869655 -54.826666) (xy 405.853587 -54.880073) (xy 405.829915 -54.93057) (xy 405.799142 -54.977083)
			(xy 405.761925 -55.01862) (xy 405.719057 -55.054295) (xy 405.671451 -55.083349) (xy 405.620122 -55.105161)
			(xy 405.566165 -55.119267) (xy 405.510728 -55.125367) (xy 405.454994 -55.12333) (xy 405.400151 -55.1132)
			(xy 405.347367 -55.095193) (xy 405.297767 -55.069692) (xy 405.252409 -55.037241) (xy 405.21226 -54.998532)
			(xy 405.178174 -54.954389) (xy 405.150878 -54.905754) (xy 405.130955 -54.853663) (xy 405.118829 -54.799226)
			(xy 405.114758 -54.743604) (xy 398.2212 -54.743604) (xy 398.2212 -56.622188) (xy 407.014172 -56.622188)
			(xy 407.014673 -56.593485) (xy 407.023262 -56.536725) (xy 407.04026 -56.481893) (xy 407.065283 -56.430227)
			(xy 407.097766 -56.382894) (xy 407.136975 -56.340964) (xy 407.182024 -56.305383) (xy 407.206704 -56.290718)
			(xy 407.219273 -56.28295) (xy 407.239682 -56.261605) (xy 407.253124 -56.235309) (xy 407.258473 -56.206265)
			(xy 407.255281 -56.176906) (xy 407.243814 -56.14969) (xy 407.225035 -56.126898) (xy 407.213054 -56.118252)
			(xy 407.191202 -56.102958) (xy 407.151548 -56.067291) (xy 407.117245 -56.02645) (xy 407.088963 -55.981231)
			(xy 407.067253 -55.932515) (xy 407.052536 -55.88125) (xy 407.045101 -55.828436) (xy 407.044652 -55.801768)
			(xy 407.045138 -55.774517) (xy 407.052894 -55.720569) (xy 407.068249 -55.668274) (xy 407.090891 -55.618697)
			(xy 407.120357 -55.572847) (xy 407.156048 -55.531656) (xy 407.197239 -55.495965) (xy 407.243089 -55.466499)
			(xy 407.292666 -55.443857) (xy 407.344961 -55.428502) (xy 407.398909 -55.420746) (xy 407.453411 -55.420746)
			(xy 407.507359 -55.428502) (xy 407.559654 -55.443857) (xy 407.609231 -55.466499) (xy 407.655081 -55.495965)
			(xy 407.696272 -55.531656) (xy 407.731963 -55.572847) (xy 407.761429 -55.618697) (xy 407.784071 -55.668274)
			(xy 407.799426 -55.720569) (xy 407.807182 -55.774517) (xy 407.807668 -55.801768) (xy 407.807162 -55.830472)
			(xy 407.798577 -55.887233) (xy 407.781582 -55.942066) (xy 407.756561 -55.993733) (xy 407.724078 -56.041066)
			(xy 407.684868 -56.082995) (xy 407.639817 -56.118575) (xy 407.615136 -56.133238) (xy 407.602513 -56.14093)
			(xy 407.582093 -56.162288) (xy 407.568647 -56.188601) (xy 407.563302 -56.217663) (xy 407.566506 -56.247038)
			(xy 407.57799 -56.274265) (xy 407.596793 -56.29706) (xy 407.608786 -56.305704) (xy 407.630673 -56.320949)
			(xy 407.670325 -56.356626) (xy 407.704623 -56.397476) (xy 407.7329 -56.442703) (xy 407.754605 -56.491427)
			(xy 407.769315 -56.542698) (xy 407.776743 -56.595518) (xy 407.777188 -56.622188) (xy 407.776702 -56.649439)
			(xy 407.768946 -56.703387) (xy 407.753591 -56.755682) (xy 407.730949 -56.805259) (xy 407.701483 -56.851109)
			(xy 407.665792 -56.8923) (xy 407.624601 -56.927991) (xy 407.578751 -56.957457) (xy 407.529174 -56.980099)
			(xy 407.476879 -56.995454) (xy 407.422931 -57.00321) (xy 407.368429 -57.00321) (xy 407.314481 -56.995454)
			(xy 407.262186 -56.980099) (xy 407.212609 -56.957457) (xy 407.166759 -56.927991) (xy 407.125568 -56.8923)
			(xy 407.089877 -56.851109) (xy 407.060411 -56.805259) (xy 407.037769 -56.755682) (xy 407.022414 -56.703387)
			(xy 407.014658 -56.649439) (xy 407.014172 -56.622188) (xy 398.2212 -56.622188) (xy 398.2212 -62.249812)
			(xy 399.302222 -62.249812) (xy 399.306293 -62.19419) (xy 399.318419 -62.139753) (xy 399.338342 -62.087662)
			(xy 399.365638 -62.039027) (xy 399.399724 -61.994884) (xy 399.439873 -61.956175) (xy 399.485231 -61.923724)
			(xy 399.534831 -61.898223) (xy 399.587615 -61.880216) (xy 399.642458 -61.870086) (xy 399.698192 -61.868049)
			(xy 399.753629 -61.874149) (xy 399.807586 -61.888255) (xy 399.858915 -61.910067) (xy 399.906521 -61.939121)
			(xy 399.949389 -61.974796) (xy 399.986606 -62.016333) (xy 400.017379 -62.062846) (xy 400.041051 -62.113343)
			(xy 400.057119 -62.16675) (xy 400.065239 -62.221926) (xy 400.065748 -62.249812) (xy 400.065239 -62.277698)
			(xy 400.057119 -62.332874) (xy 400.041051 -62.386281) (xy 400.017379 -62.436778) (xy 399.986606 -62.483291)
			(xy 399.949389 -62.524828) (xy 399.906521 -62.560503) (xy 399.858915 -62.589557) (xy 399.807586 -62.611369)
			(xy 399.753629 -62.625475) (xy 399.698192 -62.631575) (xy 399.642458 -62.629538) (xy 399.587615 -62.619408)
			(xy 399.534831 -62.601401) (xy 399.485231 -62.5759) (xy 399.439873 -62.543449) (xy 399.399724 -62.50474)
			(xy 399.365638 -62.460597) (xy 399.338342 -62.411962) (xy 399.318419 -62.359871) (xy 399.306293 -62.305434)
			(xy 399.302222 -62.249812) (xy 398.2212 -62.249812) (xy 398.2212 -63.762128) (xy 399.607022 -63.762128)
			(xy 399.611093 -63.706506) (xy 399.623219 -63.652069) (xy 399.643142 -63.599978) (xy 399.670438 -63.551343)
			(xy 399.704524 -63.5072) (xy 399.744673 -63.468491) (xy 399.790031 -63.43604) (xy 399.839631 -63.410539)
			(xy 399.892415 -63.392532) (xy 399.947258 -63.382402) (xy 400.002992 -63.380365) (xy 400.058429 -63.386465)
			(xy 400.112386 -63.400571) (xy 400.163715 -63.422383) (xy 400.211321 -63.451437) (xy 400.254189 -63.487112)
			(xy 400.291406 -63.528649) (xy 400.322179 -63.575162) (xy 400.345851 -63.625659) (xy 400.361919 -63.679066)
			(xy 400.370039 -63.734242) (xy 400.370548 -63.762128) (xy 400.370039 -63.790014) (xy 400.361919 -63.84519)
			(xy 400.345851 -63.898597) (xy 400.322179 -63.949094) (xy 400.291406 -63.995607) (xy 400.254189 -64.037144)
			(xy 400.211321 -64.072819) (xy 400.163715 -64.101873) (xy 400.112386 -64.123685) (xy 400.058429 -64.137791)
			(xy 400.002992 -64.143891) (xy 399.947258 -64.141854) (xy 399.892415 -64.131724) (xy 399.839631 -64.113717)
			(xy 399.790031 -64.088216) (xy 399.744673 -64.055765) (xy 399.704524 -64.017056) (xy 399.670438 -63.972913)
			(xy 399.643142 -63.924278) (xy 399.623219 -63.872187) (xy 399.611093 -63.81775) (xy 399.607022 -63.762128)
			(xy 398.2212 -63.762128) (xy 398.2212 -66.404236) (xy 398.251656 -66.434959) (xy 398.307344 -66.50117)
			(xy 398.356626 -66.572277) (xy 398.399074 -66.647664) (xy 398.434319 -66.726675) (xy 398.462054 -66.808624)
			(xy 398.482039 -66.8928) (xy 398.4941 -66.978471) (xy 398.498133 -67.064893) (xy 398.494102 -67.151315)
			(xy 398.482042 -67.236986) (xy 398.462058 -67.321162) (xy 398.434324 -67.403112) (xy 398.399081 -67.482124)
			(xy 398.356634 -67.557511) (xy 398.307353 -67.628619) (xy 398.251665 -67.69483) (xy 398.2212 -67.725544)
			(xy 398.2212 -70.839076) (xy 398.221731 -70.854071) (xy 398.23044 -70.88277) (xy 398.247114 -70.907698)
			(xy 398.270313 -70.926704) (xy 398.298035 -70.938148) (xy 398.327885 -70.941041) (xy 398.357289 -70.935134)
			(xy 398.383706 -70.920936) (xy 398.394682 -70.910704) (xy 402.569172 -66.736214) (xy 402.569172 -62.423548)
			(xy 402.569731 -62.394575) (xy 402.578839 -62.337347) (xy 402.596791 -62.28225) (xy 402.623145 -62.230642)
			(xy 402.65725 -62.183794) (xy 402.677376 -62.162944) (xy 407.14676 -57.693306) (xy 407.150062 -57.687972)
			(xy 407.164953 -57.664182) (xy 407.200614 -57.620844) (xy 407.242238 -57.583197) (xy 407.288926 -57.552051)
			(xy 407.339673 -57.52808) (xy 407.393383 -57.511798) (xy 407.448898 -57.503558) (xy 407.47696 -57.50306)
			(xy 407.504216 -57.50352) (xy 407.558173 -57.511272) (xy 407.610477 -57.526625) (xy 407.660064 -57.549264)
			(xy 407.705925 -57.578731) (xy 407.747125 -57.614424) (xy 407.782826 -57.655617) (xy 407.812301 -57.701472)
			(xy 407.83495 -57.751055) (xy 407.850312 -57.803357) (xy 407.858075 -57.857312) (xy 407.858468 -57.884568)
			(xy 407.857972 -57.912632) (xy 407.84975 -57.968154) (xy 407.833479 -58.021871) (xy 407.809511 -58.072623)
			(xy 407.778362 -58.119314) (xy 407.740706 -58.160936) (xy 407.697356 -58.196588) (xy 407.673556 -58.211466)
			(xy 407.668222 -58.214768) (xy 406.283922 -59.599068) (xy 407.084782 -59.599068) (xy 407.088853 -59.543446)
			(xy 407.100979 -59.489009) (xy 407.120902 -59.436918) (xy 407.148198 -59.388283) (xy 407.182284 -59.34414)
			(xy 407.222433 -59.305431) (xy 407.267791 -59.27298) (xy 407.317391 -59.247479) (xy 407.370175 -59.229472)
			(xy 407.425018 -59.219342) (xy 407.480752 -59.217305) (xy 407.536189 -59.223405) (xy 407.590146 -59.237511)
			(xy 407.641475 -59.259323) (xy 407.689081 -59.288377) (xy 407.731949 -59.324052) (xy 407.769166 -59.365589)
			(xy 407.799939 -59.412102) (xy 407.823611 -59.462599) (xy 407.839679 -59.516006) (xy 407.847799 -59.571182)
			(xy 407.848308 -59.599068) (xy 407.847799 -59.626954) (xy 407.839679 -59.68213) (xy 407.823611 -59.735537)
			(xy 407.799939 -59.786034) (xy 407.769166 -59.832547) (xy 407.731949 -59.874084) (xy 407.689081 -59.909759)
			(xy 407.641475 -59.938813) (xy 407.590146 -59.960625) (xy 407.536189 -59.974731) (xy 407.480752 -59.980831)
			(xy 407.425018 -59.978794) (xy 407.370175 -59.968664) (xy 407.317391 -59.950657) (xy 407.267791 -59.925156)
			(xy 407.222433 -59.892705) (xy 407.182284 -59.853996) (xy 407.148198 -59.809853) (xy 407.120902 -59.761218)
			(xy 407.100979 -59.709127) (xy 407.088853 -59.65469) (xy 407.084782 -59.599068) (xy 406.283922 -59.599068)
			(xy 405.369522 -60.513468) (xy 407.094942 -60.513468) (xy 407.099013 -60.457846) (xy 407.111139 -60.403409)
			(xy 407.131062 -60.351318) (xy 407.158358 -60.302683) (xy 407.192444 -60.25854) (xy 407.232593 -60.219831)
			(xy 407.277951 -60.18738) (xy 407.327551 -60.161879) (xy 407.380335 -60.143872) (xy 407.435178 -60.133742)
			(xy 407.490912 -60.131705) (xy 407.546349 -60.137805) (xy 407.600306 -60.151911) (xy 407.651635 -60.173723)
			(xy 407.699241 -60.202777) (xy 407.742109 -60.238452) (xy 407.779326 -60.279989) (xy 407.810099 -60.326502)
			(xy 407.833771 -60.376999) (xy 407.849839 -60.430406) (xy 407.857959 -60.485582) (xy 407.858468 -60.513468)
			(xy 407.857959 -60.541354) (xy 407.849839 -60.59653) (xy 407.833771 -60.649937) (xy 407.810099 -60.700434)
			(xy 407.779326 -60.746947) (xy 407.742109 -60.788484) (xy 407.699241 -60.824159) (xy 407.651635 -60.853213)
			(xy 407.600306 -60.875025) (xy 407.546349 -60.889131) (xy 407.490912 -60.895231) (xy 407.435178 -60.893194)
			(xy 407.380335 -60.883064) (xy 407.327551 -60.865057) (xy 407.277951 -60.839556) (xy 407.232593 -60.807105)
			(xy 407.192444 -60.768396) (xy 407.158358 -60.724253) (xy 407.131062 -60.675618) (xy 407.111139 -60.623527)
			(xy 407.099013 -60.56909) (xy 407.094942 -60.513468) (xy 405.369522 -60.513468) (xy 404.295102 -61.587888)
			(xy 407.107642 -61.587888) (xy 407.111713 -61.532266) (xy 407.123839 -61.477829) (xy 407.143762 -61.425738)
			(xy 407.171058 -61.377103) (xy 407.205144 -61.33296) (xy 407.245293 -61.294251) (xy 407.290651 -61.2618)
			(xy 407.340251 -61.236299) (xy 407.393035 -61.218292) (xy 407.447878 -61.208162) (xy 407.503612 -61.206125)
			(xy 407.559049 -61.212225) (xy 407.613006 -61.226331) (xy 407.664335 -61.248143) (xy 407.711941 -61.277197)
			(xy 407.754809 -61.312872) (xy 407.792026 -61.354409) (xy 407.822799 -61.400922) (xy 407.846471 -61.451419)
			(xy 407.862539 -61.504826) (xy 407.870659 -61.560002) (xy 407.871168 -61.587888) (xy 407.870659 -61.615774)
			(xy 407.862539 -61.67095) (xy 407.846471 -61.724357) (xy 407.822799 -61.774854) (xy 407.792026 -61.821367)
			(xy 407.754809 -61.862904) (xy 407.711941 -61.898579) (xy 407.664335 -61.927633) (xy 407.613006 -61.949445)
			(xy 407.559049 -61.963551) (xy 407.503612 -61.969651) (xy 407.447878 -61.967614) (xy 407.393035 -61.957484)
			(xy 407.340251 -61.939477) (xy 407.290651 -61.913976) (xy 407.245293 -61.881525) (xy 407.205144 -61.842816)
			(xy 407.171058 -61.798673) (xy 407.143762 -61.750038) (xy 407.123839 -61.697947) (xy 407.111713 -61.64351)
			(xy 407.107642 -61.587888) (xy 404.295102 -61.587888) (xy 403.306788 -62.576202) (xy 403.306788 -63.754508)
			(xy 405.517602 -63.754508) (xy 405.521673 -63.698886) (xy 405.533799 -63.644449) (xy 405.553722 -63.592358)
			(xy 405.581018 -63.543723) (xy 405.615104 -63.49958) (xy 405.655253 -63.460871) (xy 405.700611 -63.42842)
			(xy 405.750211 -63.402919) (xy 405.802995 -63.384912) (xy 405.857838 -63.374782) (xy 405.913572 -63.372745)
			(xy 405.969009 -63.378845) (xy 406.022966 -63.392951) (xy 406.074295 -63.414763) (xy 406.121901 -63.443817)
			(xy 406.164769 -63.479492) (xy 406.201986 -63.521029) (xy 406.232759 -63.567542) (xy 406.256431 -63.618039)
			(xy 406.272499 -63.671446) (xy 406.280619 -63.726622) (xy 406.281128 -63.754508) (xy 406.280619 -63.782394)
			(xy 406.272499 -63.83757) (xy 406.256431 -63.890977) (xy 406.232759 -63.941474) (xy 406.201986 -63.987987)
			(xy 406.164769 -64.029524) (xy 406.121901 -64.065199) (xy 406.074295 -64.094253) (xy 406.022966 -64.116065)
			(xy 405.969009 -64.130171) (xy 405.913572 -64.136271) (xy 405.857838 -64.134234) (xy 405.802995 -64.124104)
			(xy 405.750211 -64.106097) (xy 405.700611 -64.080596) (xy 405.655253 -64.048145) (xy 405.615104 -64.009436)
			(xy 405.581018 -63.965293) (xy 405.553722 -63.916658) (xy 405.533799 -63.864567) (xy 405.521673 -63.81013)
			(xy 405.517602 -63.754508) (xy 403.306788 -63.754508) (xy 403.306788 -66.888868) (xy 403.306227 -66.917841)
			(xy 403.297117 -66.975066) (xy 403.279161 -67.03016) (xy 403.252804 -67.081765) (xy 403.218695 -67.128608)
			(xy 403.198584 -67.149472) (xy 398.2212 -72.12711) (xy 398.2212 -78.6003) (xy 399.007076 -78.6003)
			(xy 399.007607 -78.572342) (xy 399.015782 -78.517028) (xy 399.031941 -78.463498) (xy 399.055739 -78.4129)
			(xy 399.086667 -78.366316) (xy 399.124062 -78.324745) (xy 399.167123 -78.289076) (xy 399.214929 -78.260073)
			(xy 399.240502 -78.248764) (xy 399.25406 -78.242569) (xy 399.277016 -78.223568) (xy 399.293522 -78.198757)
			(xy 399.302178 -78.170242) (xy 399.302249 -78.140443) (xy 399.29373 -78.111887) (xy 399.285968 -78.099158)
			(xy 399.271082 -78.075654) (xy 399.247535 -78.025249) (xy 399.231555 -77.971961) (xy 399.223479 -77.916917)
			(xy 399.222976 -77.8891) (xy 399.223478 -77.861849) (xy 399.231234 -77.807903) (xy 399.246588 -77.75561)
			(xy 399.269228 -77.706034) (xy 399.298693 -77.660184) (xy 399.334383 -77.618994) (xy 399.375571 -77.583303)
			(xy 399.421419 -77.553836) (xy 399.470995 -77.531194) (xy 399.523287 -77.515837) (xy 399.577233 -77.508079)
			(xy 399.604484 -77.507592) (xy 399.615174 -77.507638) (xy 399.636522 -77.508784) (xy 399.647156 -77.509878)
			(xy 399.660695 -77.511012) (xy 399.687534 -77.506841) (xy 399.712319 -77.49573) (xy 399.733289 -77.478469)
			(xy 399.748957 -77.456282) (xy 399.758209 -77.430745) (xy 399.760389 -77.403671) (xy 399.755342 -77.376983)
			(xy 399.749772 -77.36459) (xy 399.737647 -77.338508) (xy 399.720563 -77.283589) (xy 399.711933 -77.226724)
			(xy 399.711418 -77.197966) (xy 399.711871 -77.169262) (xy 399.72045 -77.112499) (xy 399.737438 -77.057662)
			(xy 399.762452 -77.00599) (xy 399.794926 -76.958651) (xy 399.834129 -76.916712) (xy 399.879173 -76.881122)
			(xy 399.929043 -76.852685) (xy 399.982611 -76.832041) (xy 400.038667 -76.819659) (xy 400.067272 -76.81722)
			(xy 400.080701 -76.815912) (xy 400.106181 -76.807051) (xy 400.128449 -76.791826) (xy 400.145953 -76.7713)
			(xy 400.15747 -76.746906) (xy 400.162195 -76.720347) (xy 400.159799 -76.693478) (xy 400.150449 -76.668174)
			(xy 400.142964 -76.656946) (xy 400.126279 -76.632546) (xy 400.099797 -76.579704) (xy 400.081779 -76.52341)
			(xy 400.072657 -76.465011) (xy 400.072098 -76.435458) (xy 400.072584 -76.408207) (xy 400.08034 -76.354259)
			(xy 400.095695 -76.301964) (xy 400.118337 -76.252387) (xy 400.147803 -76.206537) (xy 400.183494 -76.165346)
			(xy 400.224685 -76.129655) (xy 400.270535 -76.100189) (xy 400.320112 -76.077547) (xy 400.372407 -76.062192)
			(xy 400.426355 -76.054436) (xy 400.480857 -76.054436) (xy 400.534805 -76.062192) (xy 400.5871 -76.077547)
			(xy 400.636677 -76.100189) (xy 400.682527 -76.129655) (xy 400.723718 -76.165346) (xy 400.759409 -76.206537)
			(xy 400.788875 -76.252387) (xy 400.811517 -76.301964) (xy 400.826872 -76.354259) (xy 400.834628 -76.408207)
			(xy 400.835114 -76.435458) (xy 400.834654 -76.464161) (xy 400.826073 -76.520923) (xy 400.809083 -76.575758)
			(xy 400.784069 -76.627427) (xy 400.751595 -76.674766) (xy 400.712393 -76.716703) (xy 400.667351 -76.752293)
			(xy 400.617484 -76.780732) (xy 400.563918 -76.801378) (xy 400.507864 -76.813764) (xy 400.47926 -76.816204)
			(xy 400.46585 -76.817649) (xy 400.440385 -76.826494) (xy 400.418127 -76.8417) (xy 400.400628 -76.862204)
			(xy 400.38911 -76.886576) (xy 400.384377 -76.913114) (xy 400.38676 -76.939965) (xy 400.396092 -76.965255)
			(xy 400.403568 -76.976478) (xy 400.420267 -77.000869) (xy 400.446745 -77.053715) (xy 400.464759 -77.110011)
			(xy 400.473877 -77.168412) (xy 400.474434 -77.197966) (xy 400.473913 -77.225217) (xy 400.466161 -77.279164)
			(xy 400.450811 -77.33146) (xy 400.428174 -77.381038) (xy 400.398712 -77.42689) (xy 400.363025 -77.468082)
			(xy 400.321838 -77.503776) (xy 400.275991 -77.533246) (xy 400.226416 -77.55589) (xy 400.174123 -77.571249)
			(xy 400.120177 -77.579009) (xy 400.092926 -77.579474) (xy 400.082236 -77.579427) (xy 400.060888 -77.578282)
			(xy 400.050254 -77.577188) (xy 400.036713 -77.576112) (xy 400.009882 -77.580279) (xy 399.985104 -77.591384)
			(xy 399.964138 -77.608637) (xy 399.948472 -77.630814) (xy 399.939218 -77.656341) (xy 399.937034 -77.683405)
			(xy 399.942073 -77.710085) (xy 399.947638 -77.722476) (xy 399.959745 -77.748565) (xy 399.976837 -77.803481)
			(xy 399.985473 -77.860343) (xy 399.985992 -77.8891) (xy 399.98548 -77.917059) (xy 399.977305 -77.972375)
			(xy 399.961144 -78.025906) (xy 399.937343 -78.076506) (xy 399.906413 -78.123089) (xy 399.869015 -78.16466)
			(xy 399.82595 -78.200328) (xy 399.778141 -78.229329) (xy 399.752566 -78.240636) (xy 399.739016 -78.246851)
			(xy 399.716052 -78.265842) (xy 399.699539 -78.290648) (xy 399.690879 -78.319162) (xy 399.690809 -78.348961)
			(xy 399.699334 -78.377516) (xy 399.7071 -78.390242) (xy 399.721982 -78.413748) (xy 399.745531 -78.464152)
			(xy 399.761512 -78.51744) (xy 399.769589 -78.572483) (xy 399.770092 -78.6003) (xy 399.769606 -78.627551)
			(xy 399.76185 -78.681499) (xy 399.746495 -78.733794) (xy 399.723853 -78.783371) (xy 399.694387 -78.829221)
			(xy 399.658696 -78.870412) (xy 399.617505 -78.906103) (xy 399.571655 -78.935569) (xy 399.522078 -78.958211)
			(xy 399.469783 -78.973566) (xy 399.415835 -78.981322) (xy 399.361333 -78.981322) (xy 399.307385 -78.973566)
			(xy 399.25509 -78.958211) (xy 399.205513 -78.935569) (xy 399.159663 -78.906103) (xy 399.118472 -78.870412)
			(xy 399.082781 -78.829221) (xy 399.053315 -78.783371) (xy 399.030673 -78.733794) (xy 399.015318 -78.681499)
			(xy 399.007562 -78.627551) (xy 399.007076 -78.6003) (xy 398.2212 -78.6003) (xy 398.2212 -82.235548)
			(xy 386.10794 -94.348808) (xy 380.834138 -94.348808) (xy 380.819787 -94.349336) (xy 380.792238 -94.357396)
			(xy 380.76802 -94.372804) (xy 380.749047 -94.394344) (xy 380.736818 -94.420313) (xy 380.7323 -94.448659)
			(xy 380.735849 -94.477143) (xy 380.747185 -94.503514) (xy 380.755906 -94.514924) (xy 380.772301 -94.535526)
			(xy 380.799871 -94.580383) (xy 380.821018 -94.628602) (xy 380.83534 -94.679268) (xy 380.842567 -94.731422)
			(xy 380.843028 -94.757748) (xy 380.842539 -94.784998) (xy 380.834777 -94.838941) (xy 380.819418 -94.891231)
			(xy 380.796774 -94.940804) (xy 380.767307 -94.98665) (xy 380.731616 -95.027836) (xy 380.690427 -95.063524)
			(xy 380.644579 -95.092988) (xy 380.595005 -95.115628) (xy 380.542714 -95.130983) (xy 380.48877 -95.138741)
			(xy 380.46152 -95.139256) (xy 380.434854 -95.138812) (xy 380.382043 -95.131382) (xy 380.330782 -95.116665)
			(xy 380.282072 -95.094947) (xy 380.236865 -95.066653) (xy 380.216156 -95.049848) (xy 380.204121 -95.040511)
			(xy 380.176058 -95.028709) (xy 380.145765 -95.025695) (xy 380.115927 -95.031734) (xy 380.089189 -95.046291)
			(xy 380.067924 -95.068076) (xy 380.054017 -95.095157) (xy 380.050802 -95.110046) (xy 380.045713 -95.136198)
			(xy 380.029237 -95.186865) (xy 380.005873 -95.234747) (xy 379.976074 -95.278911) (xy 379.940419 -95.3185)
			(xy 379.899603 -95.352744) (xy 379.85442 -95.380974) (xy 379.805748 -95.402644) (xy 379.754534 -95.417331)
			(xy 379.701775 -95.424749) (xy 379.675136 -95.42526) (xy 379.647885 -95.424799) (xy 379.593937 -95.417047)
			(xy 379.541641 -95.401696) (xy 379.492063 -95.379059) (xy 379.446211 -95.349596) (xy 379.405019 -95.313906)
			(xy 379.369326 -95.272718) (xy 379.339858 -95.226869) (xy 379.317216 -95.177293) (xy 379.30186 -95.124998)
			(xy 379.294103 -95.071051) (xy 379.294103 -95.016549) (xy 379.30186 -94.962602) (xy 379.317216 -94.910307)
			(xy 379.339858 -94.860731) (xy 379.369326 -94.814882) (xy 379.405019 -94.773694) (xy 379.446211 -94.738005)
			(xy 379.492063 -94.708541) (xy 379.541641 -94.685904) (xy 379.593937 -94.670553) (xy 379.647885 -94.662801)
			(xy 379.675136 -94.662244) (xy 379.701803 -94.662685) (xy 379.754617 -94.670109) (xy 379.805882 -94.684822)
			(xy 379.854595 -94.706535) (xy 379.899807 -94.734826) (xy 379.9205 -94.751652) (xy 379.932536 -94.760997)
			(xy 379.960607 -94.772811) (xy 379.990912 -94.775835) (xy 380.020764 -94.769801) (xy 380.047514 -94.755242)
			(xy 380.068791 -94.733452) (xy 380.082707 -94.706361) (xy 380.085854 -94.691454) (xy 380.090488 -94.66732)
			(xy 380.105145 -94.620412) (xy 380.125701 -94.575773) (xy 380.151816 -94.534142) (xy 380.167134 -94.514924)
			(xy 380.175867 -94.503521) (xy 380.187201 -94.477143) (xy 380.190749 -94.448653) (xy 380.186229 -94.420301)
			(xy 380.174 -94.394327) (xy 380.155027 -94.37278) (xy 380.130808 -94.357363) (xy 380.103255 -94.349293)
			(xy 380.088902 -94.348808) (xy 379.62078 -94.348808) (xy 376.765566 -97.204022) (xy 381.494282 -97.204022)
			(xy 381.498353 -97.1484) (xy 381.510479 -97.093963) (xy 381.530402 -97.041872) (xy 381.557698 -96.993237)
			(xy 381.591784 -96.949094) (xy 381.631933 -96.910385) (xy 381.677291 -96.877934) (xy 381.726891 -96.852433)
			(xy 381.779675 -96.834426) (xy 381.834518 -96.824296) (xy 381.890252 -96.822259) (xy 381.945689 -96.828359)
			(xy 381.999646 -96.842465) (xy 382.050975 -96.864277) (xy 382.098581 -96.893331) (xy 382.141449 -96.929006)
			(xy 382.178666 -96.970543) (xy 382.209439 -97.017056) (xy 382.233111 -97.067553) (xy 382.249179 -97.12096)
			(xy 382.257299 -97.176136) (xy 382.257808 -97.204022) (xy 382.257299 -97.231908) (xy 382.249179 -97.287084)
			(xy 382.233111 -97.340491) (xy 382.209439 -97.390988) (xy 382.178666 -97.437501) (xy 382.141449 -97.479038)
			(xy 382.098581 -97.514713) (xy 382.050975 -97.543767) (xy 381.999646 -97.565579) (xy 381.945689 -97.579685)
			(xy 381.890252 -97.585785) (xy 381.834518 -97.583748) (xy 381.779675 -97.573618) (xy 381.726891 -97.555611)
			(xy 381.677291 -97.53011) (xy 381.631933 -97.497659) (xy 381.591784 -97.45895) (xy 381.557698 -97.414807)
			(xy 381.530402 -97.366172) (xy 381.510479 -97.314081) (xy 381.498353 -97.259644) (xy 381.494282 -97.204022)
			(xy 376.765566 -97.204022) (xy 371.90934 -102.060248) (xy 374.331992 -102.060248) (xy 374.332478 -102.032997)
			(xy 374.340234 -101.979049) (xy 374.355589 -101.926754) (xy 374.378231 -101.877177) (xy 374.407697 -101.831327)
			(xy 374.443388 -101.790136) (xy 374.484579 -101.754445) (xy 374.530429 -101.724979) (xy 374.580006 -101.702337)
			(xy 374.632301 -101.686982) (xy 374.686249 -101.679226) (xy 374.740751 -101.679226) (xy 374.794699 -101.686982)
			(xy 374.846994 -101.702337) (xy 374.896571 -101.724979) (xy 374.942421 -101.754445) (xy 374.983612 -101.790136)
			(xy 375.019303 -101.831327) (xy 375.048769 -101.877177) (xy 375.071411 -101.926754) (xy 375.086766 -101.979049)
			(xy 375.094522 -102.032997) (xy 375.095008 -102.060248) (xy 375.09447 -102.089509) (xy 375.08552 -102.147342)
			(xy 375.067852 -102.203133) (xy 375.041881 -102.255576) (xy 375.008213 -102.303443) (xy 374.988328 -102.324916)
			(xy 374.979107 -102.33507) (xy 374.966034 -102.359172) (xy 374.959856 -102.385887) (xy 374.961018 -102.413282)
			(xy 374.969438 -102.439377) (xy 374.984505 -102.462285) (xy 375.005132 -102.480351) (xy 375.017284 -102.486714)
			(xy 375.04223 -102.499374) (xy 375.08844 -102.530899) (xy 375.129552 -102.568835) (xy 375.164684 -102.612367)
			(xy 375.193082 -102.660562) (xy 375.214138 -102.712388) (xy 375.221246 -102.739444) (xy 375.225057 -102.752772)
			(xy 375.23864 -102.776918) (xy 375.258209 -102.796528) (xy 375.282326 -102.810163) (xy 375.309219 -102.816819)
			(xy 375.336912 -102.816007) (xy 375.350278 -102.812342) (xy 375.377906 -102.804294) (xy 375.434791 -102.795616)
			(xy 375.463562 -102.79507) (xy 375.490815 -102.795575) (xy 375.544767 -102.803327) (xy 375.597066 -102.818679)
			(xy 375.646648 -102.841318) (xy 375.692504 -102.870783) (xy 375.733699 -102.906475) (xy 375.769394 -102.947666)
			(xy 375.798864 -102.993518) (xy 375.821508 -103.043098) (xy 375.836865 -103.095396) (xy 375.844623 -103.149347)
			(xy 375.844623 -103.184452) (xy 375.986546 -103.184452) (xy 375.990617 -103.12883) (xy 376.002743 -103.074393)
			(xy 376.022666 -103.022302) (xy 376.049962 -102.973667) (xy 376.084048 -102.929524) (xy 376.124197 -102.890815)
			(xy 376.169555 -102.858364) (xy 376.219155 -102.832863) (xy 376.271939 -102.814856) (xy 376.326782 -102.804726)
			(xy 376.382516 -102.802689) (xy 376.437953 -102.808789) (xy 376.49191 -102.822895) (xy 376.543239 -102.844707)
			(xy 376.590845 -102.873761) (xy 376.633713 -102.909436) (xy 376.67093 -102.950973) (xy 376.701703 -102.997486)
			(xy 376.725375 -103.047983) (xy 376.741443 -103.10139) (xy 376.749563 -103.156566) (xy 376.750072 -103.184452)
			(xy 376.749563 -103.212338) (xy 376.741443 -103.267514) (xy 376.725375 -103.320921) (xy 376.701703 -103.371418)
			(xy 376.67093 -103.417931) (xy 376.640254 -103.452168) (xy 378.175518 -103.452168) (xy 378.179589 -103.396546)
			(xy 378.191715 -103.342109) (xy 378.211638 -103.290018) (xy 378.238934 -103.241383) (xy 378.27302 -103.19724)
			(xy 378.313169 -103.158531) (xy 378.358527 -103.12608) (xy 378.408127 -103.100579) (xy 378.460911 -103.082572)
			(xy 378.515754 -103.072442) (xy 378.571488 -103.070405) (xy 378.626925 -103.076505) (xy 378.680882 -103.090611)
			(xy 378.732211 -103.112423) (xy 378.779817 -103.141477) (xy 378.822685 -103.177152) (xy 378.823991 -103.17861)
			(xy 379.48184 -103.17861) (xy 379.485911 -103.122988) (xy 379.498037 -103.068551) (xy 379.51796 -103.01646)
			(xy 379.545256 -102.967825) (xy 379.579342 -102.923682) (xy 379.619491 -102.884973) (xy 379.664849 -102.852522)
			(xy 379.714449 -102.827021) (xy 379.767233 -102.809014) (xy 379.822076 -102.798884) (xy 379.87781 -102.796847)
			(xy 379.933247 -102.802947) (xy 379.987204 -102.817053) (xy 380.038533 -102.838865) (xy 380.086139 -102.867919)
			(xy 380.129007 -102.903594) (xy 380.166224 -102.945131) (xy 380.196997 -102.991644) (xy 380.220669 -103.042141)
			(xy 380.236737 -103.095548) (xy 380.244857 -103.150724) (xy 380.245366 -103.17861) (xy 380.244857 -103.206496)
			(xy 380.236737 -103.261672) (xy 380.220669 -103.315079) (xy 380.196997 -103.365576) (xy 380.166224 -103.412089)
			(xy 380.129007 -103.453626) (xy 380.097186 -103.480108) (xy 419.431722 -103.480108) (xy 419.435793 -103.424486)
			(xy 419.447919 -103.370049) (xy 419.467842 -103.317958) (xy 419.495138 -103.269323) (xy 419.529224 -103.22518)
			(xy 419.569373 -103.186471) (xy 419.614731 -103.15402) (xy 419.664331 -103.128519) (xy 419.717115 -103.110512)
			(xy 419.771958 -103.100382) (xy 419.827692 -103.098345) (xy 419.883129 -103.104445) (xy 419.937086 -103.118551)
			(xy 419.988415 -103.140363) (xy 420.036021 -103.169417) (xy 420.078889 -103.205092) (xy 420.116106 -103.246629)
			(xy 420.136139 -103.276908) (xy 430.696876 -103.276908) (xy 430.700947 -103.221286) (xy 430.713073 -103.166849)
			(xy 430.732996 -103.114758) (xy 430.760292 -103.066123) (xy 430.794378 -103.02198) (xy 430.834527 -102.983271)
			(xy 430.879885 -102.95082) (xy 430.929485 -102.925319) (xy 430.982269 -102.907312) (xy 431.037112 -102.897182)
			(xy 431.092846 -102.895145) (xy 431.148283 -102.901245) (xy 431.20224 -102.915351) (xy 431.253569 -102.937163)
			(xy 431.301175 -102.966217) (xy 431.344043 -103.001892) (xy 431.38126 -103.043429) (xy 431.412033 -103.089942)
			(xy 431.435705 -103.140439) (xy 431.451773 -103.193846) (xy 431.459893 -103.249022) (xy 431.460402 -103.276908)
			(xy 431.459893 -103.304794) (xy 431.451773 -103.35997) (xy 431.435705 -103.413377) (xy 431.412033 -103.463874)
			(xy 431.38126 -103.510387) (xy 431.344043 -103.551924) (xy 431.301175 -103.587599) (xy 431.253569 -103.616653)
			(xy 431.20224 -103.638465) (xy 431.148283 -103.652571) (xy 431.092846 -103.658671) (xy 431.037112 -103.656634)
			(xy 430.982269 -103.646504) (xy 430.929485 -103.628497) (xy 430.879885 -103.602996) (xy 430.834527 -103.570545)
			(xy 430.794378 -103.531836) (xy 430.760292 -103.487693) (xy 430.732996 -103.439058) (xy 430.713073 -103.386967)
			(xy 430.700947 -103.33253) (xy 430.696876 -103.276908) (xy 420.136139 -103.276908) (xy 420.146879 -103.293142)
			(xy 420.170551 -103.343639) (xy 420.186619 -103.397046) (xy 420.194739 -103.452222) (xy 420.195248 -103.480108)
			(xy 420.194739 -103.507994) (xy 420.186619 -103.56317) (xy 420.170551 -103.616577) (xy 420.146879 -103.667074)
			(xy 420.116106 -103.713587) (xy 420.078889 -103.755124) (xy 420.036021 -103.790799) (xy 419.988415 -103.819853)
			(xy 419.937086 -103.841665) (xy 419.883129 -103.855771) (xy 419.827692 -103.861871) (xy 419.771958 -103.859834)
			(xy 419.717115 -103.849704) (xy 419.664331 -103.831697) (xy 419.614731 -103.806196) (xy 419.569373 -103.773745)
			(xy 419.529224 -103.735036) (xy 419.495138 -103.690893) (xy 419.467842 -103.642258) (xy 419.447919 -103.590167)
			(xy 419.435793 -103.53573) (xy 419.431722 -103.480108) (xy 380.097186 -103.480108) (xy 380.086139 -103.489301)
			(xy 380.038533 -103.518355) (xy 379.987204 -103.540167) (xy 379.933247 -103.554273) (xy 379.87781 -103.560373)
			(xy 379.822076 -103.558336) (xy 379.767233 -103.548206) (xy 379.714449 -103.530199) (xy 379.664849 -103.504698)
			(xy 379.619491 -103.472247) (xy 379.579342 -103.433538) (xy 379.545256 -103.389395) (xy 379.51796 -103.34076)
			(xy 379.498037 -103.288669) (xy 379.485911 -103.234232) (xy 379.48184 -103.17861) (xy 378.823991 -103.17861)
			(xy 378.859902 -103.218689) (xy 378.890675 -103.265202) (xy 378.914347 -103.315699) (xy 378.930415 -103.369106)
			(xy 378.938535 -103.424282) (xy 378.939044 -103.452168) (xy 378.938535 -103.480054) (xy 378.930415 -103.53523)
			(xy 378.914347 -103.588637) (xy 378.890675 -103.639134) (xy 378.859902 -103.685647) (xy 378.822685 -103.727184)
			(xy 378.779817 -103.762859) (xy 378.732211 -103.791913) (xy 378.680882 -103.813725) (xy 378.626925 -103.827831)
			(xy 378.571488 -103.833931) (xy 378.515754 -103.831894) (xy 378.460911 -103.821764) (xy 378.408127 -103.803757)
			(xy 378.358527 -103.778256) (xy 378.313169 -103.745805) (xy 378.27302 -103.707096) (xy 378.238934 -103.662953)
			(xy 378.211638 -103.614318) (xy 378.191715 -103.562227) (xy 378.179589 -103.50779) (xy 378.175518 -103.452168)
			(xy 376.640254 -103.452168) (xy 376.633713 -103.459468) (xy 376.590845 -103.495143) (xy 376.543239 -103.524197)
			(xy 376.49191 -103.546009) (xy 376.437953 -103.560115) (xy 376.382516 -103.566215) (xy 376.326782 -103.564178)
			(xy 376.271939 -103.554048) (xy 376.219155 -103.536041) (xy 376.169555 -103.51054) (xy 376.124197 -103.478089)
			(xy 376.084048 -103.43938) (xy 376.049962 -103.395237) (xy 376.022666 -103.346602) (xy 376.002743 -103.294511)
			(xy 375.990617 -103.240074) (xy 375.986546 -103.184452) (xy 375.844623 -103.184452) (xy 375.844623 -103.203853)
			(xy 375.836865 -103.257804) (xy 375.821508 -103.310102) (xy 375.798864 -103.359682) (xy 375.769394 -103.405534)
			(xy 375.733699 -103.446725) (xy 375.692504 -103.482417) (xy 375.646648 -103.511882) (xy 375.597066 -103.534521)
			(xy 375.544767 -103.549873) (xy 375.490815 -103.557625) (xy 375.463562 -103.558086) (xy 375.43533 -103.557591)
			(xy 375.379486 -103.549251) (xy 375.325481 -103.532774) (xy 375.274493 -103.508518) (xy 375.227635 -103.477014)
			(xy 375.185931 -103.43895) (xy 375.150291 -103.395156) (xy 375.121493 -103.346588) (xy 375.100166 -103.294308)
			(xy 375.092976 -103.267002) (xy 375.089287 -103.253635) (xy 375.075678 -103.229482) (xy 375.056083 -103.209872)
			(xy 375.031942 -103.196244) (xy 375.005027 -103.1896) (xy 374.977317 -103.190428) (xy 374.963944 -103.194104)
			(xy 374.93632 -103.202167) (xy 374.879432 -103.210835) (xy 374.85066 -103.211376) (xy 374.823406 -103.210959)
			(xy 374.769454 -103.203197) (xy 374.717156 -103.187835) (xy 374.667577 -103.165187) (xy 374.621725 -103.135713)
			(xy 374.580535 -103.100014) (xy 374.544844 -103.058817) (xy 374.515379 -103.01296) (xy 374.49274 -102.963376)
			(xy 374.477388 -102.911075) (xy 374.469636 -102.857122) (xy 374.469152 -102.829868) (xy 374.469711 -102.800608)
			(xy 374.478658 -102.742777) (xy 374.496321 -102.686986) (xy 374.522287 -102.634543) (xy 374.55595 -102.586674)
			(xy 374.575832 -102.5652) (xy 374.585016 -102.555018) (xy 374.59808 -102.530922) (xy 374.604255 -102.504217)
			(xy 374.603096 -102.476832) (xy 374.594685 -102.450744) (xy 374.579631 -102.427839) (xy 374.55902 -102.409769)
			(xy 374.546876 -102.403402) (xy 374.523048 -102.391374) (xy 374.478746 -102.361599) (xy 374.439028 -102.325939)
			(xy 374.404671 -102.285089) (xy 374.376344 -102.239847) (xy 374.354603 -102.191098) (xy 374.33987 -102.139794)
			(xy 374.332435 -102.086937) (xy 374.331992 -102.060248) (xy 371.90934 -102.060248) (xy 370.96192 -103.007668)
			(xy 370.96192 -103.264525) (xy 371.291418 -103.264525) (xy 371.291422 -103.21003) (xy 371.29918 -103.15609)
			(xy 371.314536 -103.103804) (xy 371.337176 -103.054235) (xy 371.36664 -103.008392) (xy 371.402328 -102.967209)
			(xy 371.443513 -102.931524) (xy 371.489358 -102.902063) (xy 371.538928 -102.879427) (xy 371.591216 -102.864075)
			(xy 371.645156 -102.85632) (xy 371.699651 -102.85632) (xy 371.753591 -102.864076) (xy 371.805878 -102.879429)
			(xy 371.855448 -102.902067) (xy 371.901292 -102.931528) (xy 371.942477 -102.967214) (xy 371.978164 -103.008398)
			(xy 372.007627 -103.054241) (xy 372.030267 -103.10381) (xy 372.045621 -103.156097) (xy 372.053379 -103.210037)
			(xy 372.053866 -103.237284) (xy 372.053545 -103.260506) (xy 372.047938 -103.306609) (xy 372.04269 -103.329232)
			(xy 372.039638 -103.342908) (xy 372.040471 -103.370911) (xy 372.04888 -103.397634) (xy 372.064232 -103.421069)
			(xy 372.085373 -103.439451) (xy 372.110713 -103.4514) (xy 372.138345 -103.456015) (xy 372.166192 -103.452951)
			(xy 372.179342 -103.448104) (xy 372.20213 -103.439251) (xy 372.249414 -103.426825) (xy 372.297899 -103.42055)
			(xy 372.322344 -103.420164) (xy 372.349592 -103.420725) (xy 372.403532 -103.428487) (xy 372.455818 -103.443846)
			(xy 372.505387 -103.46649) (xy 372.551228 -103.495958) (xy 372.592409 -103.531649) (xy 372.628092 -103.572838)
			(xy 372.65755 -103.618686) (xy 372.680183 -103.668259) (xy 372.695531 -103.720549) (xy 372.703281 -103.774491)
			(xy 372.703275 -103.828986) (xy 372.695514 -103.882927) (xy 372.680156 -103.935213) (xy 372.657513 -103.984782)
			(xy 372.628046 -104.030624) (xy 372.595331 -104.068372) (xy 373.23776 -104.068372) (xy 373.238289 -104.040031)
			(xy 373.246667 -103.98397) (xy 373.263249 -103.929767) (xy 373.28767 -103.878615) (xy 373.319393 -103.83164)
			(xy 373.357717 -103.789877) (xy 373.401801 -103.754246) (xy 373.425974 -103.739442) (xy 373.438637 -103.731298)
			(xy 373.458958 -103.709103) (xy 373.471939 -103.681956) (xy 373.476455 -103.652205) (xy 373.472116 -103.622428)
			(xy 373.459298 -103.595203) (xy 373.43911 -103.572888) (xy 373.426482 -103.56469) (xy 373.402594 -103.549828)
			(xy 373.359076 -103.514171) (xy 373.321267 -103.47251) (xy 373.289987 -103.425747) (xy 373.265913 -103.374898)
			(xy 373.249569 -103.321064) (xy 373.241309 -103.265414) (xy 373.240808 -103.237284) (xy 373.241294 -103.210033)
			(xy 373.24905 -103.156085) (xy 373.264405 -103.10379) (xy 373.287047 -103.054213) (xy 373.316513 -103.008363)
			(xy 373.352204 -102.967172) (xy 373.393395 -102.931481) (xy 373.439245 -102.902015) (xy 373.488822 -102.879373)
			(xy 373.541117 -102.864018) (xy 373.595065 -102.856262) (xy 373.649567 -102.856262) (xy 373.703515 -102.864018)
			(xy 373.75581 -102.879373) (xy 373.805387 -102.902015) (xy 373.851237 -102.931481) (xy 373.892428 -102.967172)
			(xy 373.928119 -103.008363) (xy 373.957585 -103.054213) (xy 373.980227 -103.10379) (xy 373.995582 -103.156085)
			(xy 374.003338 -103.210033) (xy 374.003824 -103.237284) (xy 374.003347 -103.265627) (xy 373.99496 -103.32169)
			(xy 373.97837 -103.375895) (xy 373.95394 -103.427047) (xy 373.92221 -103.474022) (xy 373.883877 -103.515783)
			(xy 373.839787 -103.551412) (xy 373.81561 -103.566214) (xy 373.802896 -103.574284) (xy 373.782575 -103.596495)
			(xy 373.769598 -103.623659) (xy 373.765089 -103.653424) (xy 373.769437 -103.683212) (xy 373.782267 -103.710446)
			(xy 373.802468 -103.732766) (xy 373.815102 -103.740966) (xy 373.838967 -103.755864) (xy 373.882486 -103.791514)
			(xy 373.920296 -103.833169) (xy 373.95158 -103.879926) (xy 373.975657 -103.930769) (xy 373.992006 -103.984598)
			(xy 374.000272 -104.040244) (xy 374.000776 -104.068372) (xy 374.00029 -104.095623) (xy 373.992534 -104.149571)
			(xy 373.977179 -104.201866) (xy 373.954537 -104.251443) (xy 373.925071 -104.297293) (xy 373.88938 -104.338484)
			(xy 373.848189 -104.374175) (xy 373.802339 -104.403641) (xy 373.752762 -104.426283) (xy 373.700467 -104.441638)
			(xy 373.696141 -104.44226) (xy 376.211082 -104.44226) (xy 376.215153 -104.386638) (xy 376.227279 -104.332201)
			(xy 376.247202 -104.28011) (xy 376.274498 -104.231475) (xy 376.308584 -104.187332) (xy 376.348733 -104.148623)
			(xy 376.394091 -104.116172) (xy 376.443691 -104.090671) (xy 376.496475 -104.072664) (xy 376.551318 -104.062534)
			(xy 376.607052 -104.060497) (xy 376.662489 -104.066597) (xy 376.716446 -104.080703) (xy 376.767775 -104.102515)
			(xy 376.815381 -104.131569) (xy 376.858249 -104.167244) (xy 376.868431 -104.178608) (xy 377.696982 -104.178608)
			(xy 377.701053 -104.122986) (xy 377.713179 -104.068549) (xy 377.733102 -104.016458) (xy 377.760398 -103.967823)
			(xy 377.794484 -103.92368) (xy 377.834633 -103.884971) (xy 377.879991 -103.85252) (xy 377.929591 -103.827019)
			(xy 377.982375 -103.809012) (xy 378.037218 -103.798882) (xy 378.092952 -103.796845) (xy 378.148389 -103.802945)
			(xy 378.202346 -103.817051) (xy 378.253675 -103.838863) (xy 378.301281 -103.867917) (xy 378.344149 -103.903592)
			(xy 378.381366 -103.945129) (xy 378.412139 -103.991642) (xy 378.435811 -104.042139) (xy 378.451879 -104.095546)
			(xy 378.459999 -104.150722) (xy 378.460508 -104.178608) (xy 378.459999 -104.206494) (xy 378.451879 -104.26167)
			(xy 378.435811 -104.315077) (xy 378.412139 -104.365574) (xy 378.381366 -104.412087) (xy 378.344149 -104.453624)
			(xy 378.320263 -104.473502) (xy 378.937518 -104.473502) (xy 378.941589 -104.41788) (xy 378.953715 -104.363443)
			(xy 378.973638 -104.311352) (xy 379.000934 -104.262717) (xy 379.03502 -104.218574) (xy 379.075169 -104.179865)
			(xy 379.120527 -104.147414) (xy 379.170127 -104.121913) (xy 379.222911 -104.103906) (xy 379.277754 -104.093776)
			(xy 379.333488 -104.091739) (xy 379.388925 -104.097839) (xy 379.442882 -104.111945) (xy 379.494211 -104.133757)
			(xy 379.541817 -104.162811) (xy 379.584685 -104.198486) (xy 379.621902 -104.240023) (xy 379.652675 -104.286536)
			(xy 379.671856 -104.327452) (xy 433.394102 -104.327452) (xy 433.398173 -104.27183) (xy 433.410299 -104.217393)
			(xy 433.430222 -104.165302) (xy 433.457518 -104.116667) (xy 433.491604 -104.072524) (xy 433.531753 -104.033815)
			(xy 433.577111 -104.001364) (xy 433.626711 -103.975863) (xy 433.679495 -103.957856) (xy 433.734338 -103.947726)
			(xy 433.790072 -103.945689) (xy 433.845509 -103.951789) (xy 433.899466 -103.965895) (xy 433.950795 -103.987707)
			(xy 433.998401 -104.016761) (xy 434.041269 -104.052436) (xy 434.078486 -104.093973) (xy 434.109259 -104.140486)
			(xy 434.132931 -104.190983) (xy 434.148999 -104.24439) (xy 434.157119 -104.299566) (xy 434.157628 -104.327452)
			(xy 434.157119 -104.355338) (xy 434.148999 -104.410514) (xy 434.132931 -104.463921) (xy 434.109259 -104.514418)
			(xy 434.078486 -104.560931) (xy 434.041269 -104.602468) (xy 433.998401 -104.638143) (xy 433.950795 -104.667197)
			(xy 433.899466 -104.689009) (xy 433.845509 -104.703115) (xy 433.790072 -104.709215) (xy 433.734338 -104.707178)
			(xy 433.679495 -104.697048) (xy 433.626711 -104.679041) (xy 433.577111 -104.65354) (xy 433.531753 -104.621089)
			(xy 433.491604 -104.58238) (xy 433.457518 -104.538237) (xy 433.430222 -104.489602) (xy 433.410299 -104.437511)
			(xy 433.398173 -104.383074) (xy 433.394102 -104.327452) (xy 379.671856 -104.327452) (xy 379.676347 -104.337033)
			(xy 379.692415 -104.39044) (xy 379.700535 -104.445616) (xy 379.701044 -104.473502) (xy 379.700535 -104.501388)
			(xy 379.692415 -104.556564) (xy 379.676347 -104.609971) (xy 379.652675 -104.660468) (xy 379.621902 -104.706981)
			(xy 379.584685 -104.748518) (xy 379.541817 -104.784193) (xy 379.494211 -104.813247) (xy 379.442882 -104.835059)
			(xy 379.388925 -104.849165) (xy 379.333488 -104.855265) (xy 379.277754 -104.853228) (xy 379.222911 -104.843098)
			(xy 379.170127 -104.825091) (xy 379.120527 -104.79959) (xy 379.075169 -104.767139) (xy 379.03502 -104.72843)
			(xy 379.000934 -104.684287) (xy 378.973638 -104.635652) (xy 378.953715 -104.583561) (xy 378.941589 -104.529124)
			(xy 378.937518 -104.473502) (xy 378.320263 -104.473502) (xy 378.301281 -104.489299) (xy 378.253675 -104.518353)
			(xy 378.202346 -104.540165) (xy 378.148389 -104.554271) (xy 378.092952 -104.560371) (xy 378.037218 -104.558334)
			(xy 377.982375 -104.548204) (xy 377.929591 -104.530197) (xy 377.879991 -104.504696) (xy 377.834633 -104.472245)
			(xy 377.794484 -104.433536) (xy 377.760398 -104.389393) (xy 377.733102 -104.340758) (xy 377.713179 -104.288667)
			(xy 377.701053 -104.23423) (xy 377.696982 -104.178608) (xy 376.868431 -104.178608) (xy 376.895466 -104.208781)
			(xy 376.926239 -104.255294) (xy 376.949911 -104.305791) (xy 376.965979 -104.359198) (xy 376.974099 -104.414374)
			(xy 376.974608 -104.44226) (xy 376.974099 -104.470146) (xy 376.965979 -104.525322) (xy 376.949911 -104.578729)
			(xy 376.926239 -104.629226) (xy 376.895466 -104.675739) (xy 376.858249 -104.717276) (xy 376.815381 -104.752951)
			(xy 376.767775 -104.782005) (xy 376.716446 -104.803817) (xy 376.662489 -104.817923) (xy 376.607052 -104.824023)
			(xy 376.551318 -104.821986) (xy 376.496475 -104.811856) (xy 376.443691 -104.793849) (xy 376.394091 -104.768348)
			(xy 376.348733 -104.735897) (xy 376.308584 -104.697188) (xy 376.274498 -104.653045) (xy 376.247202 -104.60441)
			(xy 376.227279 -104.552319) (xy 376.215153 -104.497882) (xy 376.211082 -104.44226) (xy 373.696141 -104.44226)
			(xy 373.646519 -104.449394) (xy 373.592017 -104.449394) (xy 373.538069 -104.441638) (xy 373.485774 -104.426283)
			(xy 373.436197 -104.403641) (xy 373.390347 -104.374175) (xy 373.349156 -104.338484) (xy 373.313465 -104.297293)
			(xy 373.283999 -104.251443) (xy 373.261357 -104.201866) (xy 373.246002 -104.149571) (xy 373.238246 -104.095623)
			(xy 373.23776 -104.068372) (xy 372.595331 -104.068372) (xy 372.592355 -104.071806) (xy 372.551166 -104.107489)
			(xy 372.505319 -104.136947) (xy 372.455746 -104.159581) (xy 372.403456 -104.174929) (xy 372.349515 -104.18268)
			(xy 372.295019 -104.182675) (xy 372.241079 -104.174915) (xy 372.188792 -104.159558) (xy 372.139223 -104.136915)
			(xy 372.09338 -104.107449) (xy 372.052198 -104.071758) (xy 372.016514 -104.030571) (xy 371.987055 -103.984724)
			(xy 371.964421 -103.935151) (xy 371.949072 -103.882861) (xy 371.94132 -103.82892) (xy 371.940836 -103.801672)
			(xy 371.941168 -103.778451) (xy 371.946767 -103.732347) (xy 371.952012 -103.709724) (xy 371.955004 -103.696036)
			(xy 371.954184 -103.668038) (xy 371.945786 -103.641316) (xy 371.930443 -103.617883) (xy 371.909309 -103.5995)
			(xy 371.883975 -103.587552) (xy 371.856348 -103.582937) (xy 371.828506 -103.586004) (xy 371.81536 -103.590852)
			(xy 371.792573 -103.599707) (xy 371.745288 -103.612132) (xy 371.696803 -103.618406) (xy 371.672358 -103.618792)
			(xy 371.645111 -103.618277) (xy 371.591172 -103.610516) (xy 371.538886 -103.595158) (xy 371.489318 -103.572515)
			(xy 371.443477 -103.543049) (xy 371.402296 -103.507359) (xy 371.366613 -103.466171) (xy 371.337154 -103.420325)
			(xy 371.31452 -103.370754) (xy 371.29917 -103.318465) (xy 371.291418 -103.264525) (xy 370.96192 -103.264525)
			(xy 370.96192 -105.207308) (xy 416.720272 -105.207308) (xy 416.724343 -105.151686) (xy 416.736469 -105.097249)
			(xy 416.756392 -105.045158) (xy 416.783688 -104.996523) (xy 416.817774 -104.95238) (xy 416.857923 -104.913671)
			(xy 416.903281 -104.88122) (xy 416.952881 -104.855719) (xy 417.005665 -104.837712) (xy 417.060508 -104.827582)
			(xy 417.116242 -104.825545) (xy 417.171679 -104.831645) (xy 417.225636 -104.845751) (xy 417.276965 -104.867563)
			(xy 417.324571 -104.896617) (xy 417.367439 -104.932292) (xy 417.404656 -104.973829) (xy 417.435429 -105.020342)
			(xy 417.459101 -105.070839) (xy 417.475169 -105.124246) (xy 417.483289 -105.179422) (xy 417.483798 -105.207308)
			(xy 417.483289 -105.235194) (xy 417.475169 -105.29037) (xy 417.459101 -105.343777) (xy 417.435429 -105.394274)
			(xy 417.404656 -105.440787) (xy 417.367439 -105.482324) (xy 417.324571 -105.517999) (xy 417.276965 -105.547053)
			(xy 417.225636 -105.568865) (xy 417.171679 -105.582971) (xy 417.116242 -105.589071) (xy 417.060508 -105.587034)
			(xy 417.005665 -105.576904) (xy 416.952881 -105.558897) (xy 416.903281 -105.533396) (xy 416.857923 -105.500945)
			(xy 416.817774 -105.462236) (xy 416.783688 -105.418093) (xy 416.756392 -105.369458) (xy 416.736469 -105.317367)
			(xy 416.724343 -105.26293) (xy 416.720272 -105.207308) (xy 370.96192 -105.207308) (xy 370.96192 -105.883202)
			(xy 377.285502 -105.883202) (xy 377.289573 -105.82758) (xy 377.301699 -105.773143) (xy 377.321622 -105.721052)
			(xy 377.348918 -105.672417) (xy 377.383004 -105.628274) (xy 377.423153 -105.589565) (xy 377.468511 -105.557114)
			(xy 377.518111 -105.531613) (xy 377.570895 -105.513606) (xy 377.625738 -105.503476) (xy 377.681472 -105.501439)
			(xy 377.736909 -105.507539) (xy 377.790866 -105.521645) (xy 377.842195 -105.543457) (xy 377.889801 -105.572511)
			(xy 377.932669 -105.608186) (xy 377.969886 -105.649723) (xy 378.000659 -105.696236) (xy 378.024331 -105.746733)
			(xy 378.040399 -105.80014) (xy 378.044399 -105.827322) (xy 429.906682 -105.827322) (xy 429.910753 -105.7717)
			(xy 429.922879 -105.717263) (xy 429.942802 -105.665172) (xy 429.970098 -105.616537) (xy 430.004184 -105.572394)
			(xy 430.044333 -105.533685) (xy 430.089691 -105.501234) (xy 430.139291 -105.475733) (xy 430.192075 -105.457726)
			(xy 430.246918 -105.447596) (xy 430.302652 -105.445559) (xy 430.358089 -105.451659) (xy 430.412046 -105.465765)
			(xy 430.463375 -105.487577) (xy 430.510981 -105.516631) (xy 430.553849 -105.552306) (xy 430.591066 -105.593843)
			(xy 430.621839 -105.640356) (xy 430.645511 -105.690853) (xy 430.661579 -105.74426) (xy 430.669699 -105.799436)
			(xy 430.670208 -105.827322) (xy 430.669699 -105.855208) (xy 430.661579 -105.910384) (xy 430.645511 -105.963791)
			(xy 430.621839 -106.014288) (xy 430.591066 -106.060801) (xy 430.553849 -106.102338) (xy 430.510981 -106.138013)
			(xy 430.463375 -106.167067) (xy 430.412046 -106.188879) (xy 430.358089 -106.202985) (xy 430.302652 -106.209085)
			(xy 430.246918 -106.207048) (xy 430.192075 -106.196918) (xy 430.139291 -106.178911) (xy 430.089691 -106.15341)
			(xy 430.044333 -106.120959) (xy 430.004184 -106.08225) (xy 429.970098 -106.038107) (xy 429.942802 -105.989472)
			(xy 429.922879 -105.937381) (xy 429.910753 -105.882944) (xy 429.906682 -105.827322) (xy 378.044399 -105.827322)
			(xy 378.048519 -105.855316) (xy 378.049028 -105.883202) (xy 378.048519 -105.911088) (xy 378.040399 -105.966264)
			(xy 378.024331 -106.019671) (xy 378.000659 -106.070168) (xy 377.969886 -106.116681) (xy 377.932669 -106.158218)
			(xy 377.889801 -106.193893) (xy 377.842195 -106.222947) (xy 377.790866 -106.244759) (xy 377.736909 -106.258865)
			(xy 377.681472 -106.264965) (xy 377.625738 -106.262928) (xy 377.570895 -106.252798) (xy 377.518111 -106.234791)
			(xy 377.468511 -106.20929) (xy 377.423153 -106.176839) (xy 377.383004 -106.13813) (xy 377.348918 -106.093987)
			(xy 377.321622 -106.045352) (xy 377.301699 -105.993261) (xy 377.289573 -105.938824) (xy 377.285502 -105.883202)
			(xy 370.96192 -105.883202) (xy 370.96192 -106.012488) (xy 370.701824 -106.272584) (xy 372.94134 -106.272584)
			(xy 372.945411 -106.216962) (xy 372.957537 -106.162525) (xy 372.97746 -106.110434) (xy 373.004756 -106.061799)
			(xy 373.038842 -106.017656) (xy 373.078991 -105.978947) (xy 373.124349 -105.946496) (xy 373.173949 -105.920995)
			(xy 373.226733 -105.902988) (xy 373.281576 -105.892858) (xy 373.33731 -105.890821) (xy 373.392747 -105.896921)
			(xy 373.446704 -105.911027) (xy 373.498033 -105.932839) (xy 373.545639 -105.961893) (xy 373.588507 -105.997568)
			(xy 373.625724 -106.039105) (xy 373.656497 -106.085618) (xy 373.680169 -106.136115) (xy 373.696237 -106.189522)
			(xy 373.704357 -106.244698) (xy 373.704866 -106.272584) (xy 373.704375 -106.299508) (xy 373.838722 -106.299508)
			(xy 373.842793 -106.243886) (xy 373.854919 -106.189449) (xy 373.874842 -106.137358) (xy 373.902138 -106.088723)
			(xy 373.936224 -106.04458) (xy 373.976373 -106.005871) (xy 374.021731 -105.97342) (xy 374.071331 -105.947919)
			(xy 374.124115 -105.929912) (xy 374.178958 -105.919782) (xy 374.234692 -105.917745) (xy 374.290129 -105.923845)
			(xy 374.344086 -105.937951) (xy 374.395415 -105.959763) (xy 374.443021 -105.988817) (xy 374.485889 -106.024492)
			(xy 374.523106 -106.066029) (xy 374.553879 -106.112542) (xy 374.577551 -106.163039) (xy 374.593619 -106.216446)
			(xy 374.601739 -106.271622) (xy 374.602248 -106.299508) (xy 374.601739 -106.327394) (xy 374.593619 -106.38257)
			(xy 374.577551 -106.435977) (xy 374.553879 -106.486474) (xy 374.528014 -106.525568) (xy 375.889518 -106.525568)
			(xy 375.893589 -106.469946) (xy 375.905715 -106.415509) (xy 375.925638 -106.363418) (xy 375.952934 -106.314783)
			(xy 375.98702 -106.27064) (xy 376.027169 -106.231931) (xy 376.072527 -106.19948) (xy 376.122127 -106.173979)
			(xy 376.174911 -106.155972) (xy 376.229754 -106.145842) (xy 376.285488 -106.143805) (xy 376.340925 -106.149905)
			(xy 376.394882 -106.164011) (xy 376.446211 -106.185823) (xy 376.493817 -106.214877) (xy 376.536685 -106.250552)
			(xy 376.573902 -106.292089) (xy 376.604675 -106.338602) (xy 376.628347 -106.389099) (xy 376.644415 -106.442506)
			(xy 376.651817 -106.492802) (xy 378.937518 -106.492802) (xy 378.941589 -106.43718) (xy 378.953715 -106.382743)
			(xy 378.973638 -106.330652) (xy 379.000934 -106.282017) (xy 379.03502 -106.237874) (xy 379.075169 -106.199165)
			(xy 379.120527 -106.166714) (xy 379.170127 -106.141213) (xy 379.222911 -106.123206) (xy 379.277754 -106.113076)
			(xy 379.333488 -106.111039) (xy 379.388925 -106.117139) (xy 379.442882 -106.131245) (xy 379.494211 -106.153057)
			(xy 379.541817 -106.182111) (xy 379.584685 -106.217786) (xy 379.621902 -106.259323) (xy 379.652675 -106.305836)
			(xy 379.676347 -106.356333) (xy 379.692415 -106.40974) (xy 379.700535 -106.464916) (xy 379.701044 -106.492802)
			(xy 379.700535 -106.520688) (xy 379.692415 -106.575864) (xy 379.676347 -106.629271) (xy 379.652675 -106.679768)
			(xy 379.621902 -106.726281) (xy 379.584685 -106.767818) (xy 379.541817 -106.803493) (xy 379.494211 -106.832547)
			(xy 379.442882 -106.854359) (xy 379.388925 -106.868465) (xy 379.333488 -106.874565) (xy 379.277754 -106.872528)
			(xy 379.222911 -106.862398) (xy 379.170127 -106.844391) (xy 379.120527 -106.81889) (xy 379.075169 -106.786439)
			(xy 379.03502 -106.74773) (xy 379.000934 -106.703587) (xy 378.973638 -106.654952) (xy 378.953715 -106.602861)
			(xy 378.941589 -106.548424) (xy 378.937518 -106.492802) (xy 376.651817 -106.492802) (xy 376.652535 -106.497682)
			(xy 376.653044 -106.525568) (xy 376.652535 -106.553454) (xy 376.644415 -106.60863) (xy 376.628347 -106.662037)
			(xy 376.604675 -106.712534) (xy 376.573902 -106.759047) (xy 376.536685 -106.800584) (xy 376.493817 -106.836259)
			(xy 376.446211 -106.865313) (xy 376.394882 -106.887125) (xy 376.340925 -106.901231) (xy 376.285488 -106.907331)
			(xy 376.229754 -106.905294) (xy 376.174911 -106.895164) (xy 376.122127 -106.877157) (xy 376.072527 -106.851656)
			(xy 376.027169 -106.819205) (xy 375.98702 -106.780496) (xy 375.952934 -106.736353) (xy 375.925638 -106.687718)
			(xy 375.905715 -106.635627) (xy 375.893589 -106.58119) (xy 375.889518 -106.525568) (xy 374.528014 -106.525568)
			(xy 374.523106 -106.532987) (xy 374.485889 -106.574524) (xy 374.443021 -106.610199) (xy 374.395415 -106.639253)
			(xy 374.344086 -106.661065) (xy 374.290129 -106.675171) (xy 374.234692 -106.681271) (xy 374.178958 -106.679234)
			(xy 374.124115 -106.669104) (xy 374.071331 -106.651097) (xy 374.021731 -106.625596) (xy 373.976373 -106.593145)
			(xy 373.936224 -106.554436) (xy 373.902138 -106.510293) (xy 373.874842 -106.461658) (xy 373.854919 -106.409567)
			(xy 373.842793 -106.35513) (xy 373.838722 -106.299508) (xy 373.704375 -106.299508) (xy 373.704357 -106.30047)
			(xy 373.696237 -106.355646) (xy 373.680169 -106.409053) (xy 373.656497 -106.45955) (xy 373.625724 -106.506063)
			(xy 373.588507 -106.5476) (xy 373.545639 -106.583275) (xy 373.498033 -106.612329) (xy 373.446704 -106.634141)
			(xy 373.392747 -106.648247) (xy 373.33731 -106.654347) (xy 373.281576 -106.65231) (xy 373.226733 -106.64218)
			(xy 373.173949 -106.624173) (xy 373.124349 -106.598672) (xy 373.078991 -106.566221) (xy 373.038842 -106.527512)
			(xy 373.004756 -106.483369) (xy 372.97746 -106.434734) (xy 372.957537 -106.382643) (xy 372.945411 -106.328206)
			(xy 372.94134 -106.272584) (xy 370.701824 -106.272584) (xy 370.13134 -106.843068) (xy 369.36172 -106.843068)
			(xy 369.0874 -106.568748) (xy 369.0874 -105.910888) (xy 368.577876 -105.40111) (xy 368.55775 -105.38026)
			(xy 368.523647 -105.33341) (xy 368.497293 -105.281802) (xy 368.479338 -105.226706) (xy 368.470224 -105.169479)
			(xy 368.469672 -105.140506) (xy 368.469672 -104.681528) (xy 368.46927 -104.66813) (xy 368.462302 -104.642255)
			(xy 368.448839 -104.619087) (xy 368.429809 -104.600222) (xy 368.406524 -104.586961) (xy 368.38059 -104.580218)
			(xy 368.353795 -104.580458) (xy 368.327986 -104.587665) (xy 368.316256 -104.594152) (xy 368.294037 -104.606883)
			(xy 368.246916 -104.626934) (xy 368.197538 -104.640504) (xy 368.146789 -104.647349) (xy 368.121184 -104.647746)
			(xy 368.093931 -104.647259) (xy 368.039979 -104.6395) (xy 367.987681 -104.624142) (xy 367.938101 -104.601498)
			(xy 367.892248 -104.572028) (xy 367.851056 -104.536333) (xy 367.815363 -104.495139) (xy 367.785895 -104.449285)
			(xy 367.763253 -104.399704) (xy 367.747897 -104.347405) (xy 367.74014 -104.293453) (xy 367.74014 -104.238947)
			(xy 367.747897 -104.184995) (xy 367.763253 -104.132696) (xy 367.785895 -104.083115) (xy 367.815362 -104.037261)
			(xy 367.851056 -103.996067) (xy 367.892248 -103.960372) (xy 367.938101 -103.930902) (xy 367.987681 -103.908258)
			(xy 368.039979 -103.8929) (xy 368.093931 -103.885141) (xy 368.121184 -103.88473) (xy 368.146788 -103.885141)
			(xy 368.197538 -103.891983) (xy 368.246918 -103.905545) (xy 368.294042 -103.925585) (xy 368.316256 -103.938324)
			(xy 368.329702 -103.945692) (xy 368.359512 -103.952813) (xy 368.390092 -103.950781) (xy 368.418698 -103.939781)
			(xy 368.44276 -103.920798) (xy 368.460118 -103.895539) (xy 368.469212 -103.866272) (xy 368.469672 -103.850948)
			(xy 368.469672 -94.710504) (xy 368.469289 -94.697186) (xy 368.462416 -94.671453) (xy 368.449113 -94.648378)
			(xy 368.430286 -94.629536) (xy 368.407222 -94.616214) (xy 368.381494 -94.609321) (xy 368.354858 -94.609328)
			(xy 368.34191 -94.61246) (xy 368.317722 -94.618511) (xy 368.268288 -94.625008) (xy 368.243358 -94.625414)
			(xy 368.216108 -94.624925) (xy 368.162164 -94.617164) (xy 368.109874 -94.601805) (xy 368.060301 -94.579161)
			(xy 368.014455 -94.549693) (xy 367.973269 -94.514001) (xy 367.937582 -94.472811) (xy 367.908119 -94.426962)
			(xy 367.88548 -94.377387) (xy 367.870127 -94.325095) (xy 367.862372 -94.27115) (xy 367.862372 -94.21665)
			(xy 367.870127 -94.162705) (xy 367.88548 -94.110413) (xy 367.908119 -94.060838) (xy 367.937582 -94.014989)
			(xy 367.973269 -93.973799) (xy 368.014455 -93.938107) (xy 368.060301 -93.908639) (xy 368.109874 -93.885995)
			(xy 368.162164 -93.870636) (xy 368.216108 -93.862875) (xy 368.243358 -93.862398) (xy 368.268287 -93.862808)
			(xy 368.31772 -93.869312) (xy 368.34191 -93.875352) (xy 368.35487 -93.878348) (xy 368.381461 -93.878304)
			(xy 368.407138 -93.871396) (xy 368.43016 -93.858092) (xy 368.448966 -93.839293) (xy 368.46228 -93.816276)
			(xy 368.469199 -93.790602) (xy 368.469672 -93.777308) (xy 368.469672 -93.734128) (xy 368.470233 -93.705155)
			(xy 368.479343 -93.647929) (xy 368.497298 -93.592835) (xy 368.523653 -93.541228) (xy 368.55776 -93.494383)
			(xy 368.577876 -93.473524) (xy 369.840256 -92.211144) (xy 369.861106 -92.191019) (xy 369.907955 -92.156917)
			(xy 369.959564 -92.130568) (xy 370.014661 -92.112619) (xy 370.071887 -92.103514) (xy 370.10086 -92.10294)
			(xy 371.091968 -92.10294) (xy 371.10416 -92.090748) (xy 371.10416 -90.079576) (xy 371.10374 -90.066083)
			(xy 371.096666 -90.04004) (xy 371.083018 -90.016758) (xy 371.063749 -89.997864) (xy 371.040204 -89.984676)
			(xy 371.014027 -89.978114) (xy 371.000528 -89.977976) (xy 370.9924 -89.977976) (xy 370.965151 -89.97749)
			(xy 370.911208 -89.969734) (xy 370.858918 -89.95438) (xy 370.809345 -89.931741) (xy 370.763498 -89.902277)
			(xy 370.722311 -89.866589) (xy 370.686623 -89.825402) (xy 370.657159 -89.779555) (xy 370.63452 -89.729982)
			(xy 370.619166 -89.677692) (xy 370.61141 -89.623749) (xy 370.61141 -89.569251) (xy 370.619166 -89.515308)
			(xy 370.63452 -89.463018) (xy 370.657159 -89.413445) (xy 370.686623 -89.367598) (xy 370.722311 -89.326411)
			(xy 370.763498 -89.290723) (xy 370.809345 -89.261259) (xy 370.858918 -89.23862) (xy 370.911208 -89.223266)
			(xy 370.965151 -89.21551) (xy 370.9924 -89.21496) (xy 371.000528 -89.21496) (xy 371.01403 -89.214817)
			(xy 371.040218 -89.208273) (xy 371.063775 -89.195092) (xy 371.083052 -89.176197) (xy 371.096701 -89.152909)
			(xy 371.103768 -89.126857) (xy 371.10416 -89.11336) (xy 371.10416 -87.637366) (xy 371.103672 -87.627397)
			(xy 371.096052 -87.608973) (xy 371.081978 -87.594849) (xy 371.063581 -87.587164) (xy 371.053614 -87.586566)
			(xy 371.026457 -87.585945) (xy 370.972726 -87.577959) (xy 370.920672 -87.562432) (xy 370.871346 -87.539678)
			(xy 370.825748 -87.510157) (xy 370.784798 -87.474466) (xy 370.749325 -87.433327) (xy 370.720047 -87.387572)
			(xy 370.697555 -87.338127) (xy 370.682306 -87.285991) (xy 370.674606 -87.232218) (xy 370.674138 -87.205058)
			(xy 370.674299 -87.188656) (xy 370.6771 -87.155971) (xy 370.679726 -87.13978) (xy 370.681545 -87.126648)
			(xy 370.679153 -87.100255) (xy 370.670057 -87.075364) (xy 370.654869 -87.053647) (xy 370.634608 -87.036564)
			(xy 370.610637 -87.025264) (xy 370.597684 -87.022432) (xy 370.582171 -87.01947) (xy 370.551654 -87.011327)
			(xy 370.536724 -87.006176) (xy 370.523405 -87.001908) (xy 370.495509 -87.00004) (xy 370.468152 -87.005809)
			(xy 370.443384 -87.018781) (xy 370.423064 -87.037984) (xy 370.408714 -87.061979) (xy 370.401409 -87.088967)
			(xy 370.401088 -87.10295) (xy 370.401088 -87.107268) (xy 370.400627 -87.13452) (xy 370.392875 -87.188469)
			(xy 370.377524 -87.240765) (xy 370.354886 -87.290345) (xy 370.325423 -87.336199) (xy 370.289735 -87.377392)
			(xy 370.248547 -87.413087) (xy 370.202698 -87.442558) (xy 370.153122 -87.465203) (xy 370.100827 -87.480562)
			(xy 370.04688 -87.488323) (xy 369.992376 -87.488327) (xy 369.938427 -87.480574) (xy 369.886131 -87.465222)
			(xy 369.836551 -87.442584) (xy 369.790698 -87.413121) (xy 369.749505 -87.377432) (xy 369.71381 -87.336243)
			(xy 369.684341 -87.290394) (xy 369.661696 -87.240818) (xy 369.646337 -87.188524) (xy 369.638577 -87.134576)
			(xy 369.638574 -87.080072) (xy 369.646327 -87.026123) (xy 369.661679 -86.973827) (xy 369.684317 -86.924248)
			(xy 369.713781 -86.878395) (xy 369.749471 -86.837202) (xy 369.79066 -86.801508) (xy 369.836509 -86.772039)
			(xy 369.886086 -86.749394) (xy 369.93838 -86.734036) (xy 369.992328 -86.726277) (xy 370.01958 -86.72576)
			(xy 370.052375 -86.726467) (xy 370.116995 -86.737709) (xy 370.148104 -86.748112) (xy 370.161421 -86.752376)
			(xy 370.18931 -86.754237) (xy 370.216659 -86.748465) (xy 370.241417 -86.735492) (xy 370.261729 -86.716291)
			(xy 370.276072 -86.6923) (xy 370.283372 -86.665318) (xy 370.28374 -86.651338) (xy 370.28374 -86.64702)
			(xy 370.284202 -86.619767) (xy 370.291957 -86.565817) (xy 370.307312 -86.513519) (xy 370.329954 -86.46394)
			(xy 370.359422 -86.418088) (xy 370.395116 -86.376897) (xy 370.43631 -86.341205) (xy 370.482164 -86.31174)
			(xy 370.531746 -86.289102) (xy 370.584044 -86.273751) (xy 370.637995 -86.266) (xy 370.665248 -86.265512)
			(xy 370.694759 -86.266067) (xy 370.753076 -86.275165) (xy 370.809296 -86.293136) (xy 370.862078 -86.319551)
			(xy 370.910161 -86.353781) (xy 370.931694 -86.37397) (xy 370.942744 -86.383984) (xy 370.969207 -86.397703)
			(xy 370.998503 -86.403201) (xy 371.028139 -86.40001) (xy 371.055594 -86.388402) (xy 371.07853 -86.369364)
			(xy 371.094996 -86.344517) (xy 371.10359 -86.315976) (xy 371.10416 -86.301072) (xy 371.10416 -85.832188)
			(xy 370.44122 -85.169248) (xy 348.70898 -85.169248) (xy 346.457524 -87.420704) (xy 364.42091 -87.420704)
			(xy 364.424981 -87.365082) (xy 364.437107 -87.310645) (xy 364.45703 -87.258554) (xy 364.484326 -87.209919)
			(xy 364.518412 -87.165776) (xy 364.558561 -87.127067) (xy 364.603919 -87.094616) (xy 364.653519 -87.069115)
			(xy 364.706303 -87.051108) (xy 364.761146 -87.040978) (xy 364.81688 -87.038941) (xy 364.872317 -87.045041)
			(xy 364.926274 -87.059147) (xy 364.977603 -87.080959) (xy 365.025209 -87.110013) (xy 365.068077 -87.145688)
			(xy 365.105294 -87.187225) (xy 365.136067 -87.233738) (xy 365.159739 -87.284235) (xy 365.175807 -87.337642)
			(xy 365.183927 -87.392818) (xy 365.184436 -87.420704) (xy 365.183927 -87.44859) (xy 365.175807 -87.503766)
			(xy 365.159739 -87.557173) (xy 365.136067 -87.60767) (xy 365.105294 -87.654183) (xy 365.068077 -87.69572)
			(xy 365.025209 -87.731395) (xy 364.977603 -87.760449) (xy 364.926274 -87.782261) (xy 364.872317 -87.796367)
			(xy 364.81688 -87.802467) (xy 364.761146 -87.80043) (xy 364.706303 -87.7903) (xy 364.653519 -87.772293)
			(xy 364.603919 -87.746792) (xy 364.558561 -87.714341) (xy 364.518412 -87.675632) (xy 364.484326 -87.631489)
			(xy 364.45703 -87.582854) (xy 364.437107 -87.530763) (xy 364.424981 -87.476326) (xy 364.42091 -87.420704)
			(xy 346.457524 -87.420704) (xy 345.9226 -87.955628) (xy 337.17484 -87.955628) (xy 337.12658 -87.907368)
			(xy 327.66 -87.907368) (xy 323.614034 -91.953334) (xy 366.84534 -91.953334) (xy 366.849411 -91.897712)
			(xy 366.861537 -91.843275) (xy 366.88146 -91.791184) (xy 366.908756 -91.742549) (xy 366.942842 -91.698406)
			(xy 366.982991 -91.659697) (xy 367.028349 -91.627246) (xy 367.077949 -91.601745) (xy 367.130733 -91.583738)
			(xy 367.185576 -91.573608) (xy 367.24131 -91.571571) (xy 367.296747 -91.577671) (xy 367.350704 -91.591777)
			(xy 367.402033 -91.613589) (xy 367.449639 -91.642643) (xy 367.492507 -91.678318) (xy 367.529724 -91.719855)
			(xy 367.560497 -91.766368) (xy 367.584169 -91.816865) (xy 367.600237 -91.870272) (xy 367.608357 -91.925448)
			(xy 367.608866 -91.953334) (xy 367.608357 -91.98122) (xy 367.600237 -92.036396) (xy 367.584169 -92.089803)
			(xy 367.560497 -92.1403) (xy 367.529724 -92.186813) (xy 367.492507 -92.22835) (xy 367.449639 -92.264025)
			(xy 367.402033 -92.293079) (xy 367.350704 -92.314891) (xy 367.296747 -92.328997) (xy 367.24131 -92.335097)
			(xy 367.185576 -92.33306) (xy 367.130733 -92.32293) (xy 367.077949 -92.304923) (xy 367.028349 -92.279422)
			(xy 366.982991 -92.246971) (xy 366.942842 -92.208262) (xy 366.908756 -92.164119) (xy 366.88146 -92.115484)
			(xy 366.861537 -92.063393) (xy 366.849411 -92.008956) (xy 366.84534 -91.953334) (xy 323.614034 -91.953334)
			(xy 317.75654 -97.810828) (xy 296.17416 -97.810828) (xy 294.078406 -95.715328) (xy 293.4208 -95.715328)
			(xy 293.395816 -95.714817) (xy 293.346467 -95.706968) (xy 293.298949 -95.691509) (xy 293.254428 -95.66882)
			(xy 293.213996 -95.639457) (xy 293.19601 -95.62211) (xy 292.740588 -95.166688) (xy 280.74366 -95.166688)
			(xy 275.26488 -89.687908) (xy 253.735332 -89.687908) (xy 251.96927 -91.45397) (xy 251.951286 -91.471326)
			(xy 251.910874 -91.50073) (xy 251.866356 -91.523442) (xy 251.81883 -91.538901) (xy 251.769469 -91.546725)
			(xy 251.74448 -91.547188) (xy 251.676154 -91.547188) (xy 250.903771 -92.319348) (xy 264.723372 -92.319348)
			(xy 264.723858 -92.292097) (xy 264.731614 -92.238149) (xy 264.746969 -92.185854) (xy 264.769611 -92.136277)
			(xy 264.799077 -92.090427) (xy 264.834768 -92.049236) (xy 264.875959 -92.013545) (xy 264.921809 -91.984079)
			(xy 264.971386 -91.961437) (xy 265.023681 -91.946082) (xy 265.077629 -91.938326) (xy 265.132131 -91.938326)
			(xy 265.186079 -91.946082) (xy 265.238374 -91.961437) (xy 265.287951 -91.984079) (xy 265.333801 -92.013545)
			(xy 265.374992 -92.049236) (xy 265.410683 -92.090427) (xy 265.440149 -92.136277) (xy 265.462791 -92.185854)
			(xy 265.478146 -92.238149) (xy 265.485902 -92.292097) (xy 265.486388 -92.319348) (xy 265.48587 -92.347636)
			(xy 265.47751 -92.40359) (xy 265.46098 -92.457696) (xy 265.436642 -92.508769) (xy 265.40503 -92.555688)
			(xy 265.398413 -92.563188) (xy 271.984722 -92.563188) (xy 271.988793 -92.507566) (xy 272.000919 -92.453129)
			(xy 272.020842 -92.401038) (xy 272.048138 -92.352403) (xy 272.082224 -92.30826) (xy 272.122373 -92.269551)
			(xy 272.167731 -92.2371) (xy 272.217331 -92.211599) (xy 272.270115 -92.193592) (xy 272.324958 -92.183462)
			(xy 272.380692 -92.181425) (xy 272.436129 -92.187525) (xy 272.490086 -92.201631) (xy 272.541415 -92.223443)
			(xy 272.589021 -92.252497) (xy 272.631889 -92.288172) (xy 272.669106 -92.329709) (xy 272.699879 -92.376222)
			(xy 272.723551 -92.426719) (xy 272.737972 -92.474652) (xy 273.012642 -92.474652) (xy 273.012642 -92.420148)
			(xy 273.020398 -92.366198) (xy 273.035753 -92.313902) (xy 273.058393 -92.264322) (xy 273.087859 -92.21847)
			(xy 273.123549 -92.177276) (xy 273.164739 -92.141582) (xy 273.210589 -92.112111) (xy 273.260166 -92.089466)
			(xy 273.312461 -92.074106) (xy 273.36641 -92.066344) (xy 273.393662 -92.065856) (xy 273.421032 -92.066331)
			(xy 273.475211 -92.074144) (xy 273.527715 -92.089631) (xy 273.577462 -92.112471) (xy 273.623429 -92.142195)
			(xy 273.64436 -92.159836) (xy 273.655688 -92.169072) (xy 273.682245 -92.181248) (xy 273.711162 -92.185421)
			(xy 273.740079 -92.181248) (xy 273.766636 -92.169072) (xy 273.777964 -92.159836) (xy 273.798903 -92.142206)
			(xy 273.844874 -92.112491) (xy 273.894619 -92.089653) (xy 273.947118 -92.07416) (xy 274.001293 -92.066331)
			(xy 274.028662 -92.065856) (xy 274.055914 -92.066389) (xy 274.109864 -92.074141) (xy 274.162161 -92.089492)
			(xy 274.211742 -92.11213) (xy 274.257595 -92.141594) (xy 274.298789 -92.177284) (xy 274.334483 -92.218474)
			(xy 274.363952 -92.264325) (xy 274.386595 -92.313903) (xy 274.401951 -92.366199) (xy 274.409709 -92.420148)
			(xy 274.409709 -92.474652) (xy 274.401951 -92.528601) (xy 274.386595 -92.580897) (xy 274.363952 -92.630475)
			(xy 274.334483 -92.676326) (xy 274.298789 -92.717516) (xy 274.257595 -92.753206) (xy 274.211742 -92.78267)
			(xy 274.162161 -92.805308) (xy 274.109864 -92.82066) (xy 274.055914 -92.828411) (xy 274.028662 -92.828872)
			(xy 274.001293 -92.828376) (xy 273.947115 -92.820567) (xy 273.894612 -92.805085) (xy 273.844864 -92.78225)
			(xy 273.798896 -92.752531) (xy 273.777964 -92.734892) (xy 273.766636 -92.725656) (xy 273.740079 -92.71348)
			(xy 273.711162 -92.709307) (xy 273.682245 -92.71348) (xy 273.655688 -92.725656) (xy 273.64436 -92.734892)
			(xy 273.623415 -92.752515) (xy 273.577446 -92.78223) (xy 273.527702 -92.805069) (xy 273.475204 -92.820564)
			(xy 273.42103 -92.828396) (xy 273.393662 -92.828872) (xy 273.36641 -92.828456) (xy 273.312461 -92.820694)
			(xy 273.260166 -92.805334) (xy 273.210589 -92.782689) (xy 273.164739 -92.753218) (xy 273.123549 -92.717524)
			(xy 273.087859 -92.67633) (xy 273.058393 -92.630478) (xy 273.035753 -92.580898) (xy 273.020398 -92.528602)
			(xy 273.012642 -92.474652) (xy 272.737972 -92.474652) (xy 272.739619 -92.480126) (xy 272.747739 -92.535302)
			(xy 272.748248 -92.563188) (xy 272.747739 -92.591074) (xy 272.739619 -92.64625) (xy 272.723551 -92.699657)
			(xy 272.699879 -92.750154) (xy 272.669106 -92.796667) (xy 272.631889 -92.838204) (xy 272.589021 -92.873879)
			(xy 272.541415 -92.902933) (xy 272.490086 -92.924745) (xy 272.436129 -92.938851) (xy 272.380692 -92.944951)
			(xy 272.324958 -92.942914) (xy 272.270115 -92.932784) (xy 272.217331 -92.914777) (xy 272.167731 -92.889276)
			(xy 272.122373 -92.856825) (xy 272.082224 -92.818116) (xy 272.048138 -92.773973) (xy 272.020842 -92.725338)
			(xy 272.000919 -92.673247) (xy 271.988793 -92.61881) (xy 271.984722 -92.563188) (xy 265.398413 -92.563188)
			(xy 265.386312 -92.576904) (xy 265.376591 -92.588217) (xy 265.363656 -92.615083) (xy 265.359028 -92.64454)
			(xy 265.363101 -92.674078) (xy 265.375529 -92.701182) (xy 265.395252 -92.723544) (xy 265.407648 -92.731844)
			(xy 265.430903 -92.746865) (xy 265.473236 -92.782536) (xy 265.509967 -92.823954) (xy 265.540321 -92.870248)
			(xy 265.563662 -92.920446) (xy 265.579498 -92.973491) (xy 265.587497 -93.028269) (xy 265.587988 -93.055948)
			(xy 265.587502 -93.083199) (xy 265.579746 -93.137147) (xy 265.564391 -93.189442) (xy 265.541749 -93.239019)
			(xy 265.512283 -93.284869) (xy 265.476592 -93.32606) (xy 265.435401 -93.361751) (xy 265.389551 -93.391217)
			(xy 265.339974 -93.413859) (xy 265.287679 -93.429214) (xy 265.233731 -93.43697) (xy 265.179229 -93.43697)
			(xy 265.125281 -93.429214) (xy 265.072986 -93.413859) (xy 265.023409 -93.391217) (xy 264.977559 -93.361751)
			(xy 264.936368 -93.32606) (xy 264.900677 -93.284869) (xy 264.871211 -93.239019) (xy 264.848569 -93.189442)
			(xy 264.833214 -93.137147) (xy 264.825458 -93.083199) (xy 264.824972 -93.055948) (xy 264.825498 -93.027661)
			(xy 264.833858 -92.971708) (xy 264.850387 -92.917602) (xy 264.874723 -92.866529) (xy 264.906332 -92.819608)
			(xy 264.925048 -92.798392) (xy 264.934784 -92.787088) (xy 264.947724 -92.76022) (xy 264.952354 -92.730759)
			(xy 264.948278 -92.701217) (xy 264.935845 -92.67411) (xy 264.916112 -92.651749) (xy 264.903712 -92.643452)
			(xy 264.880446 -92.628448) (xy 264.838115 -92.592772) (xy 264.801386 -92.551351) (xy 264.771034 -92.505054)
			(xy 264.747695 -92.454854) (xy 264.73186 -92.401807) (xy 264.723863 -92.347028) (xy 264.723372 -92.319348)
			(xy 250.903771 -92.319348) (xy 250.79706 -92.426028) (xy 250.79706 -92.917825) (xy 252.235514 -92.917825)
			(xy 252.235518 -92.863329) (xy 252.243276 -92.809388) (xy 252.258632 -92.757101) (xy 252.281273 -92.707531)
			(xy 252.310738 -92.661688) (xy 252.346427 -92.620504) (xy 252.387613 -92.584819) (xy 252.433459 -92.555358)
			(xy 252.483031 -92.532721) (xy 252.53532 -92.51737) (xy 252.589261 -92.509616) (xy 252.643756 -92.509617)
			(xy 252.697697 -92.517373) (xy 252.749985 -92.532727) (xy 252.799556 -92.555366) (xy 252.8454 -92.584829)
			(xy 252.886585 -92.620517) (xy 252.922272 -92.661702) (xy 252.951735 -92.707546) (xy 252.974374 -92.757117)
			(xy 252.989727 -92.809405) (xy 252.997483 -92.863346) (xy 252.99797 -92.890594) (xy 252.997917 -92.901284)
			(xy 252.996775 -92.922632) (xy 252.995684 -92.933266) (xy 252.994571 -92.947304) (xy 252.999195 -92.97507)
			(xy 253.011234 -93.000515) (xy 253.029771 -93.021698) (xy 253.053394 -93.037005) (xy 253.080302 -93.04527)
			(xy 253.108445 -93.045863) (xy 253.122176 -93.04274) (xy 253.145766 -93.037025) (xy 253.193918 -93.030911)
			(xy 253.218188 -93.030548) (xy 253.245443 -93.031042) (xy 253.299397 -93.038798) (xy 253.351699 -93.054154)
			(xy 253.401282 -93.076797) (xy 253.447139 -93.106266) (xy 253.488334 -93.141962) (xy 253.524031 -93.183157)
			(xy 253.5535 -93.229013) (xy 253.576144 -93.278596) (xy 253.591501 -93.330898) (xy 253.599258 -93.384852)
			(xy 253.599257 -93.439361) (xy 253.596207 -93.46057) (xy 256.128264 -93.46057) (xy 256.132335 -93.404948)
			(xy 256.144461 -93.350511) (xy 256.164384 -93.29842) (xy 256.19168 -93.249785) (xy 256.225766 -93.205642)
			(xy 256.265915 -93.166933) (xy 256.311273 -93.134482) (xy 256.360873 -93.108981) (xy 256.413657 -93.090974)
			(xy 256.4685 -93.080844) (xy 256.524234 -93.078807) (xy 256.579671 -93.084907) (xy 256.633628 -93.099013)
			(xy 256.684957 -93.120825) (xy 256.732563 -93.149879) (xy 256.775431 -93.185554) (xy 256.812648 -93.227091)
			(xy 256.843421 -93.273604) (xy 256.867093 -93.324101) (xy 256.883161 -93.377508) (xy 256.891281 -93.432684)
			(xy 256.89179 -93.46057) (xy 256.891753 -93.462602) (xy 257.977384 -93.462602) (xy 257.981455 -93.40698)
			(xy 257.993581 -93.352543) (xy 258.013504 -93.300452) (xy 258.0408 -93.251817) (xy 258.074886 -93.207674)
			(xy 258.115035 -93.168965) (xy 258.160393 -93.136514) (xy 258.209993 -93.111013) (xy 258.262777 -93.093006)
			(xy 258.31762 -93.082876) (xy 258.373354 -93.080839) (xy 258.428791 -93.086939) (xy 258.482748 -93.101045)
			(xy 258.534077 -93.122857) (xy 258.581683 -93.151911) (xy 258.624551 -93.187586) (xy 258.661768 -93.229123)
			(xy 258.692541 -93.275636) (xy 258.716213 -93.326133) (xy 258.732281 -93.37954) (xy 258.740401 -93.434716)
			(xy 258.74091 -93.462602) (xy 258.740401 -93.490488) (xy 258.732281 -93.545664) (xy 258.716213 -93.599071)
			(xy 258.692541 -93.649568) (xy 258.661768 -93.696081) (xy 258.624551 -93.737618) (xy 258.619893 -93.741494)
			(xy 273.244562 -93.741494) (xy 273.248633 -93.685872) (xy 273.260759 -93.631435) (xy 273.280682 -93.579344)
			(xy 273.307978 -93.530709) (xy 273.342064 -93.486566) (xy 273.382213 -93.447857) (xy 273.427571 -93.415406)
			(xy 273.477171 -93.389905) (xy 273.529955 -93.371898) (xy 273.584798 -93.361768) (xy 273.640532 -93.359731)
			(xy 273.695969 -93.365831) (xy 273.749926 -93.379937) (xy 273.801255 -93.401749) (xy 273.848861 -93.430803)
			(xy 273.891729 -93.466478) (xy 273.928946 -93.508015) (xy 273.959719 -93.554528) (xy 273.983391 -93.605025)
			(xy 273.999459 -93.658432) (xy 274.007579 -93.713608) (xy 274.008088 -93.741494) (xy 274.007579 -93.76938)
			(xy 273.999459 -93.824556) (xy 273.983391 -93.877963) (xy 273.959719 -93.92846) (xy 273.928946 -93.974973)
			(xy 273.891729 -94.01651) (xy 273.848861 -94.052185) (xy 273.801255 -94.081239) (xy 273.749926 -94.103051)
			(xy 273.695969 -94.117157) (xy 273.640532 -94.123257) (xy 273.584798 -94.12122) (xy 273.529955 -94.11109)
			(xy 273.477171 -94.093083) (xy 273.427571 -94.067582) (xy 273.382213 -94.035131) (xy 273.342064 -93.996422)
			(xy 273.307978 -93.952279) (xy 273.280682 -93.903644) (xy 273.260759 -93.851553) (xy 273.248633 -93.797116)
			(xy 273.244562 -93.741494) (xy 258.619893 -93.741494) (xy 258.581683 -93.773293) (xy 258.534077 -93.802347)
			(xy 258.482748 -93.824159) (xy 258.428791 -93.838265) (xy 258.373354 -93.844365) (xy 258.31762 -93.842328)
			(xy 258.262777 -93.832198) (xy 258.209993 -93.814191) (xy 258.160393 -93.78869) (xy 258.115035 -93.756239)
			(xy 258.074886 -93.71753) (xy 258.0408 -93.673387) (xy 258.013504 -93.624752) (xy 257.993581 -93.572661)
			(xy 257.981455 -93.518224) (xy 257.977384 -93.462602) (xy 256.891753 -93.462602) (xy 256.891281 -93.488456)
			(xy 256.883161 -93.543632) (xy 256.867093 -93.597039) (xy 256.843421 -93.647536) (xy 256.812648 -93.694049)
			(xy 256.775431 -93.735586) (xy 256.732563 -93.771261) (xy 256.684957 -93.800315) (xy 256.633628 -93.822127)
			(xy 256.579671 -93.836233) (xy 256.524234 -93.842333) (xy 256.4685 -93.840296) (xy 256.413657 -93.830166)
			(xy 256.360873 -93.812159) (xy 256.311273 -93.786658) (xy 256.265915 -93.754207) (xy 256.225766 -93.715498)
			(xy 256.19168 -93.671355) (xy 256.164384 -93.62272) (xy 256.144461 -93.570629) (xy 256.132335 -93.516192)
			(xy 256.128264 -93.46057) (xy 253.596207 -93.46057) (xy 253.591498 -93.493315) (xy 253.57614 -93.545616)
			(xy 253.553494 -93.595199) (xy 253.524023 -93.641054) (xy 253.488325 -93.682248) (xy 253.447128 -93.717942)
			(xy 253.401271 -93.747409) (xy 253.351686 -93.770051) (xy 253.299384 -93.785405) (xy 253.245429 -93.793159)
			(xy 253.19092 -93.793155) (xy 253.136966 -93.785394) (xy 253.084666 -93.770033) (xy 253.035085 -93.747385)
			(xy 252.989231 -93.717911) (xy 252.948039 -93.682212) (xy 252.912347 -93.641013) (xy 252.882882 -93.595154)
			(xy 252.860243 -93.545569) (xy 252.844891 -93.493266) (xy 252.83714 -93.439311) (xy 252.83668 -93.412056)
			(xy 252.83673 -93.401366) (xy 252.837873 -93.380018) (xy 252.838966 -93.369384) (xy 252.840094 -93.355344)
			(xy 252.83548 -93.327569) (xy 252.823444 -93.302116) (xy 252.804903 -93.280927) (xy 252.781273 -93.265619)
			(xy 252.754356 -93.25736) (xy 252.726207 -93.256779) (xy 252.712474 -93.25991) (xy 252.688882 -93.265617)
			(xy 252.640731 -93.271735) (xy 252.616462 -93.272102) (xy 252.589214 -93.271581) (xy 252.535274 -93.26382)
			(xy 252.482987 -93.248462) (xy 252.433418 -93.22582) (xy 252.387576 -93.196353) (xy 252.346394 -93.160663)
			(xy 252.31071 -93.119475) (xy 252.281251 -93.073628) (xy 252.258616 -93.024055) (xy 252.243267 -92.971766)
			(xy 252.235514 -92.917825) (xy 250.79706 -92.917825) (xy 250.79706 -93.470222) (xy 250.797659 -93.485341)
			(xy 250.806599 -93.514231) (xy 250.823601 -93.53924) (xy 250.847178 -93.558179) (xy 250.875264 -93.569391)
			(xy 250.905401 -93.571895) (xy 250.934953 -93.56547) (xy 250.948444 -93.558614) (xy 250.969946 -93.546934)
			(xy 251.015304 -93.528578) (xy 251.062641 -93.516184) (xy 251.111176 -93.509958) (xy 251.135642 -93.509592)
			(xy 251.162891 -93.510081) (xy 251.216834 -93.517842) (xy 251.269124 -93.533201) (xy 251.318696 -93.555844)
			(xy 251.363312 -93.584522) (xy 251.569218 -93.584522) (xy 251.573289 -93.5289) (xy 251.585415 -93.474463)
			(xy 251.605338 -93.422372) (xy 251.632634 -93.373737) (xy 251.66672 -93.329594) (xy 251.706869 -93.290885)
			(xy 251.752227 -93.258434) (xy 251.801827 -93.232933) (xy 251.854611 -93.214926) (xy 251.909454 -93.204796)
			(xy 251.965188 -93.202759) (xy 252.020625 -93.208859) (xy 252.074582 -93.222965) (xy 252.125911 -93.244777)
			(xy 252.173517 -93.273831) (xy 252.216385 -93.309506) (xy 252.253602 -93.351043) (xy 252.284375 -93.397556)
			(xy 252.308047 -93.448053) (xy 252.324115 -93.50146) (xy 252.332235 -93.556636) (xy 252.332744 -93.584522)
			(xy 252.332235 -93.612408) (xy 252.324115 -93.667584) (xy 252.308047 -93.720991) (xy 252.284375 -93.771488)
			(xy 252.253602 -93.818001) (xy 252.216385 -93.859538) (xy 252.173517 -93.895213) (xy 252.125911 -93.924267)
			(xy 252.074582 -93.946079) (xy 252.020625 -93.960185) (xy 251.965188 -93.966285) (xy 251.909454 -93.964248)
			(xy 251.854611 -93.954118) (xy 251.801827 -93.936111) (xy 251.752227 -93.91061) (xy 251.706869 -93.878159)
			(xy 251.66672 -93.83945) (xy 251.632634 -93.795307) (xy 251.605338 -93.746672) (xy 251.585415 -93.694581)
			(xy 251.573289 -93.640144) (xy 251.569218 -93.584522) (xy 251.363312 -93.584522) (xy 251.364541 -93.585312)
			(xy 251.405726 -93.621003) (xy 251.441413 -93.662192) (xy 251.470876 -93.708041) (xy 251.493514 -93.757615)
			(xy 251.508867 -93.809907) (xy 251.516622 -93.863851) (xy 251.516622 -93.918349) (xy 251.508867 -93.972293)
			(xy 251.506306 -93.981016) (xy 255.193546 -93.981016) (xy 255.194032 -93.953765) (xy 255.201788 -93.899817)
			(xy 255.217143 -93.847522) (xy 255.239785 -93.797945) (xy 255.269251 -93.752095) (xy 255.304942 -93.710904)
			(xy 255.346133 -93.675213) (xy 255.391983 -93.645747) (xy 255.44156 -93.623105) (xy 255.493855 -93.60775)
			(xy 255.547803 -93.599994) (xy 255.602305 -93.599994) (xy 255.656253 -93.60775) (xy 255.708548 -93.623105)
			(xy 255.758125 -93.645747) (xy 255.803975 -93.675213) (xy 255.845166 -93.710904) (xy 255.880857 -93.752095)
			(xy 255.910323 -93.797945) (xy 255.932965 -93.847522) (xy 255.94832 -93.899817) (xy 255.956076 -93.953765)
			(xy 255.956562 -93.981016) (xy 255.956047 -94.008653) (xy 255.948058 -94.063347) (xy 255.932265 -94.116318)
			(xy 255.908998 -94.166457) (xy 255.878742 -94.212716) (xy 255.860804 -94.233746) (xy 255.851116 -94.245497)
			(xy 255.838547 -94.273221) (xy 255.834698 -94.303417) (xy 255.839911 -94.333408) (xy 255.853724 -94.360534)
			(xy 255.874912 -94.38239) (xy 255.887982 -94.39021) (xy 255.913234 -94.404734) (xy 255.959448 -94.440193)
			(xy 255.999731 -94.482269) (xy 256.033144 -94.529983) (xy 256.05891 -94.582224) (xy 256.07643 -94.637777)
			(xy 256.085295 -94.695349) (xy 256.085848 -94.724474) (xy 256.085362 -94.751725) (xy 256.077606 -94.805673)
			(xy 256.062251 -94.857968) (xy 256.039609 -94.907545) (xy 256.022266 -94.934532) (xy 257.452366 -94.934532)
			(xy 257.456437 -94.87891) (xy 257.468563 -94.824473) (xy 257.488486 -94.772382) (xy 257.515782 -94.723747)
			(xy 257.549868 -94.679604) (xy 257.590017 -94.640895) (xy 257.635375 -94.608444) (xy 257.684975 -94.582943)
			(xy 257.737759 -94.564936) (xy 257.792602 -94.554806) (xy 257.848336 -94.552769) (xy 257.903773 -94.558869)
			(xy 257.95773 -94.572975) (xy 258.009059 -94.594787) (xy 258.056665 -94.623841) (xy 258.099533 -94.659516)
			(xy 258.13675 -94.701053) (xy 258.167523 -94.747566) (xy 258.191195 -94.798063) (xy 258.207263 -94.85147)
			(xy 258.215383 -94.906646) (xy 258.215892 -94.934532) (xy 258.215383 -94.962418) (xy 258.207263 -95.017594)
			(xy 258.191195 -95.071001) (xy 258.167523 -95.121498) (xy 258.139306 -95.164148) (xy 259.968998 -95.164148)
			(xy 259.973069 -95.108526) (xy 259.985195 -95.054089) (xy 260.005118 -95.001998) (xy 260.032414 -94.953363)
			(xy 260.0665 -94.90922) (xy 260.106649 -94.870511) (xy 260.152007 -94.83806) (xy 260.201607 -94.812559)
			(xy 260.254391 -94.794552) (xy 260.309234 -94.784422) (xy 260.364968 -94.782385) (xy 260.420405 -94.788485)
			(xy 260.474362 -94.802591) (xy 260.525691 -94.824403) (xy 260.573297 -94.853457) (xy 260.616165 -94.889132)
			(xy 260.653382 -94.930669) (xy 260.684155 -94.977182) (xy 260.707827 -95.027679) (xy 260.723895 -95.081086)
			(xy 260.732015 -95.136262) (xy 260.732524 -95.164148) (xy 260.732015 -95.192034) (xy 260.723895 -95.24721)
			(xy 260.707827 -95.300617) (xy 260.684155 -95.351114) (xy 260.653382 -95.397627) (xy 260.616165 -95.439164)
			(xy 260.58587 -95.464376) (xy 261.084312 -95.464376) (xy 261.088383 -95.408754) (xy 261.100509 -95.354317)
			(xy 261.120432 -95.302226) (xy 261.147728 -95.253591) (xy 261.181814 -95.209448) (xy 261.221963 -95.170739)
			(xy 261.267321 -95.138288) (xy 261.316921 -95.112787) (xy 261.369705 -95.09478) (xy 261.424548 -95.08465)
			(xy 261.480282 -95.082613) (xy 261.535719 -95.088713) (xy 261.589676 -95.102819) (xy 261.641005 -95.124631)
			(xy 261.688611 -95.153685) (xy 261.731479 -95.18936) (xy 261.768696 -95.230897) (xy 261.794442 -95.269812)
			(xy 264.700258 -95.269812) (xy 264.700717 -95.242441) (xy 264.708534 -95.188261) (xy 264.724024 -95.135758)
			(xy 264.746868 -95.086011) (xy 264.776595 -95.040045) (xy 264.794238 -95.019114) (xy 264.80346 -95.007777)
			(xy 264.815634 -94.981222) (xy 264.819808 -94.952309) (xy 264.81564 -94.923395) (xy 264.80347 -94.896838)
			(xy 264.794238 -94.88551) (xy 264.776596 -94.86458) (xy 264.746883 -94.818607) (xy 264.724047 -94.768859)
			(xy 264.708557 -94.716358) (xy 264.700731 -94.662181) (xy 264.700258 -94.634812) (xy 264.700744 -94.607561)
			(xy 264.7085 -94.553613) (xy 264.723855 -94.501318) (xy 264.746497 -94.451741) (xy 264.775963 -94.405891)
			(xy 264.811654 -94.3647) (xy 264.852845 -94.329009) (xy 264.898695 -94.299543) (xy 264.948272 -94.276901)
			(xy 265.000567 -94.261546) (xy 265.054515 -94.25379) (xy 265.109017 -94.25379) (xy 265.162965 -94.261546)
			(xy 265.21526 -94.276901) (xy 265.264837 -94.299543) (xy 265.310687 -94.329009) (xy 265.351878 -94.3647)
			(xy 265.387569 -94.405891) (xy 265.417035 -94.451741) (xy 265.439677 -94.501318) (xy 265.455032 -94.553613)
			(xy 265.462788 -94.607561) (xy 265.463274 -94.634812) (xy 265.462821 -94.662183) (xy 265.455001 -94.716363)
			(xy 265.439509 -94.768866) (xy 265.416665 -94.818613) (xy 265.386937 -94.864579) (xy 265.369294 -94.88551)
			(xy 265.360046 -94.896829) (xy 265.347871 -94.92339) (xy 265.343701 -94.952309) (xy 265.347876 -94.981228)
			(xy 265.360056 -95.007786) (xy 265.369294 -95.019114) (xy 265.377833 -95.029274) (xy 273.244562 -95.029274)
			(xy 273.248633 -94.973652) (xy 273.260759 -94.919215) (xy 273.280682 -94.867124) (xy 273.307978 -94.818489)
			(xy 273.342064 -94.774346) (xy 273.382213 -94.735637) (xy 273.427571 -94.703186) (xy 273.477171 -94.677685)
			(xy 273.529955 -94.659678) (xy 273.584798 -94.649548) (xy 273.640532 -94.647511) (xy 273.695969 -94.653611)
			(xy 273.749926 -94.667717) (xy 273.801255 -94.689529) (xy 273.848861 -94.718583) (xy 273.891729 -94.754258)
			(xy 273.928946 -94.795795) (xy 273.959719 -94.842308) (xy 273.983391 -94.892805) (xy 273.999459 -94.946212)
			(xy 274.007579 -95.001388) (xy 274.008088 -95.029274) (xy 274.007579 -95.05716) (xy 273.999459 -95.112336)
			(xy 273.983391 -95.165743) (xy 273.959719 -95.21624) (xy 273.928946 -95.262753) (xy 273.891729 -95.30429)
			(xy 273.848861 -95.339965) (xy 273.801255 -95.369019) (xy 273.749926 -95.390831) (xy 273.695969 -95.404937)
			(xy 273.640532 -95.411037) (xy 273.584798 -95.409) (xy 273.529955 -95.39887) (xy 273.477171 -95.380863)
			(xy 273.427571 -95.355362) (xy 273.382213 -95.322911) (xy 273.342064 -95.284202) (xy 273.307978 -95.240059)
			(xy 273.280682 -95.191424) (xy 273.260759 -95.139333) (xy 273.248633 -95.084896) (xy 273.244562 -95.029274)
			(xy 265.377833 -95.029274) (xy 265.386905 -95.040068) (xy 265.416622 -95.086035) (xy 265.439463 -95.135777)
			(xy 265.45496 -95.188273) (xy 265.462796 -95.242444) (xy 265.463274 -95.269812) (xy 265.462788 -95.297063)
			(xy 265.455032 -95.351011) (xy 265.439677 -95.403306) (xy 265.417035 -95.452883) (xy 265.387569 -95.498733)
			(xy 265.351878 -95.539924) (xy 265.310687 -95.575615) (xy 265.264837 -95.605081) (xy 265.21526 -95.627723)
			(xy 265.162965 -95.643078) (xy 265.109017 -95.650834) (xy 265.054515 -95.650834) (xy 265.000567 -95.643078)
			(xy 264.948272 -95.627723) (xy 264.898695 -95.605081) (xy 264.852845 -95.575615) (xy 264.811654 -95.539924)
			(xy 264.775963 -95.498733) (xy 264.746497 -95.452883) (xy 264.723855 -95.403306) (xy 264.7085 -95.351011)
			(xy 264.700744 -95.297063) (xy 264.700258 -95.269812) (xy 261.794442 -95.269812) (xy 261.799469 -95.27741)
			(xy 261.823141 -95.327907) (xy 261.839209 -95.381314) (xy 261.847329 -95.43649) (xy 261.847838 -95.464376)
			(xy 261.847329 -95.492262) (xy 261.839209 -95.547438) (xy 261.823141 -95.600845) (xy 261.799469 -95.651342)
			(xy 261.768696 -95.697855) (xy 261.731479 -95.739392) (xy 261.688611 -95.775067) (xy 261.641005 -95.804121)
			(xy 261.589676 -95.825933) (xy 261.535719 -95.840039) (xy 261.480282 -95.846139) (xy 261.424548 -95.844102)
			(xy 261.369705 -95.833972) (xy 261.316921 -95.815965) (xy 261.267321 -95.790464) (xy 261.221963 -95.758013)
			(xy 261.181814 -95.719304) (xy 261.147728 -95.675161) (xy 261.120432 -95.626526) (xy 261.100509 -95.574435)
			(xy 261.088383 -95.519998) (xy 261.084312 -95.464376) (xy 260.58587 -95.464376) (xy 260.573297 -95.474839)
			(xy 260.525691 -95.503893) (xy 260.474362 -95.525705) (xy 260.420405 -95.539811) (xy 260.364968 -95.545911)
			(xy 260.309234 -95.543874) (xy 260.254391 -95.533744) (xy 260.201607 -95.515737) (xy 260.152007 -95.490236)
			(xy 260.106649 -95.457785) (xy 260.0665 -95.419076) (xy 260.032414 -95.374933) (xy 260.005118 -95.326298)
			(xy 259.985195 -95.274207) (xy 259.973069 -95.21977) (xy 259.968998 -95.164148) (xy 258.139306 -95.164148)
			(xy 258.13675 -95.168011) (xy 258.099533 -95.209548) (xy 258.056665 -95.245223) (xy 258.009059 -95.274277)
			(xy 257.95773 -95.296089) (xy 257.903773 -95.310195) (xy 257.848336 -95.316295) (xy 257.792602 -95.314258)
			(xy 257.737759 -95.304128) (xy 257.684975 -95.286121) (xy 257.635375 -95.26062) (xy 257.590017 -95.228169)
			(xy 257.549868 -95.18946) (xy 257.515782 -95.145317) (xy 257.488486 -95.096682) (xy 257.468563 -95.044591)
			(xy 257.456437 -94.990154) (xy 257.452366 -94.934532) (xy 256.022266 -94.934532) (xy 256.010143 -94.953395)
			(xy 255.974452 -94.994586) (xy 255.933261 -95.030277) (xy 255.887411 -95.059743) (xy 255.837834 -95.082385)
			(xy 255.785539 -95.09774) (xy 255.731591 -95.105496) (xy 255.677089 -95.105496) (xy 255.623141 -95.09774)
			(xy 255.570846 -95.082385) (xy 255.521269 -95.059743) (xy 255.475419 -95.030277) (xy 255.434228 -94.994586)
			(xy 255.398537 -94.953395) (xy 255.369071 -94.907545) (xy 255.346429 -94.857968) (xy 255.331074 -94.805673)
			(xy 255.323318 -94.751725) (xy 255.322832 -94.724474) (xy 255.323318 -94.696836) (xy 255.33131 -94.642139)
			(xy 255.347109 -94.589167) (xy 255.370383 -94.539029) (xy 255.400647 -94.492772) (xy 255.41859 -94.471744)
			(xy 255.428291 -94.460003) (xy 255.44086 -94.432276) (xy 255.444708 -94.402076) (xy 255.439492 -94.372083)
			(xy 255.425676 -94.344956) (xy 255.404484 -94.323099) (xy 255.391412 -94.31528) (xy 255.366154 -94.300765)
			(xy 255.31994 -94.265305) (xy 255.279658 -94.223227) (xy 255.246246 -94.175512) (xy 255.22048 -94.123269)
			(xy 255.202962 -94.067714) (xy 255.194099 -94.010141) (xy 255.193546 -93.981016) (xy 251.506306 -93.981016)
			(xy 251.493514 -94.024585) (xy 251.470876 -94.074159) (xy 251.441413 -94.120008) (xy 251.405726 -94.161197)
			(xy 251.364541 -94.196888) (xy 251.318696 -94.226356) (xy 251.269124 -94.248999) (xy 251.216834 -94.264358)
			(xy 251.162891 -94.272119) (xy 251.135642 -94.272608) (xy 251.111178 -94.272215) (xy 251.062651 -94.265965)
			(xy 251.015318 -94.253575) (xy 250.969953 -94.235247) (xy 250.948444 -94.223586) (xy 250.934982 -94.216662)
			(xy 250.905417 -94.210226) (xy 250.875264 -94.212728) (xy 250.847165 -94.22395) (xy 250.823584 -94.242908)
			(xy 250.806586 -94.267939) (xy 250.797664 -94.296851) (xy 250.79706 -94.311978) (xy 250.79706 -94.432628)
			(xy 253.475742 -94.432628) (xy 253.479813 -94.377006) (xy 253.491939 -94.322569) (xy 253.511862 -94.270478)
			(xy 253.539158 -94.221843) (xy 253.573244 -94.1777) (xy 253.613393 -94.138991) (xy 253.658751 -94.10654)
			(xy 253.708351 -94.081039) (xy 253.761135 -94.063032) (xy 253.815978 -94.052902) (xy 253.871712 -94.050865)
			(xy 253.927149 -94.056965) (xy 253.981106 -94.071071) (xy 254.032435 -94.092883) (xy 254.080041 -94.121937)
			(xy 254.122909 -94.157612) (xy 254.160126 -94.199149) (xy 254.190899 -94.245662) (xy 254.214571 -94.296159)
			(xy 254.230639 -94.349566) (xy 254.238759 -94.404742) (xy 254.239268 -94.432628) (xy 254.238759 -94.460514)
			(xy 254.230639 -94.51569) (xy 254.214571 -94.569097) (xy 254.190899 -94.619594) (xy 254.160126 -94.666107)
			(xy 254.122909 -94.707644) (xy 254.080041 -94.743319) (xy 254.032435 -94.772373) (xy 253.981106 -94.794185)
			(xy 253.927149 -94.808291) (xy 253.871712 -94.814391) (xy 253.815978 -94.812354) (xy 253.761135 -94.802224)
			(xy 253.708351 -94.784217) (xy 253.658751 -94.758716) (xy 253.613393 -94.726265) (xy 253.573244 -94.687556)
			(xy 253.539158 -94.643413) (xy 253.511862 -94.594778) (xy 253.491939 -94.542687) (xy 253.479813 -94.48825)
			(xy 253.475742 -94.432628) (xy 250.79706 -94.432628) (xy 250.79706 -95.595948) (xy 250.950982 -95.595948)
			(xy 250.955053 -95.540326) (xy 250.967179 -95.485889) (xy 250.987102 -95.433798) (xy 251.014398 -95.385163)
			(xy 251.048484 -95.34102) (xy 251.088633 -95.302311) (xy 251.133991 -95.26986) (xy 251.183591 -95.244359)
			(xy 251.236375 -95.226352) (xy 251.291218 -95.216222) (xy 251.346952 -95.214185) (xy 251.402389 -95.220285)
			(xy 251.456346 -95.234391) (xy 251.507675 -95.256203) (xy 251.555281 -95.285257) (xy 251.598149 -95.320932)
			(xy 251.635366 -95.362469) (xy 251.666139 -95.408982) (xy 251.689811 -95.459479) (xy 251.705879 -95.512886)
			(xy 251.713999 -95.568062) (xy 251.714508 -95.595948) (xy 251.713999 -95.623834) (xy 251.705879 -95.67901)
			(xy 251.689811 -95.732417) (xy 251.666139 -95.782914) (xy 251.635366 -95.829427) (xy 251.598149 -95.870964)
			(xy 251.555281 -95.906639) (xy 251.507675 -95.935693) (xy 251.456346 -95.957505) (xy 251.402389 -95.971611)
			(xy 251.346952 -95.977711) (xy 251.291218 -95.975674) (xy 251.236375 -95.965544) (xy 251.183591 -95.947537)
			(xy 251.133991 -95.922036) (xy 251.088633 -95.889585) (xy 251.048484 -95.850876) (xy 251.014398 -95.806733)
			(xy 250.987102 -95.758098) (xy 250.967179 -95.706007) (xy 250.955053 -95.65157) (xy 250.950982 -95.595948)
			(xy 250.79706 -95.595948) (xy 250.79706 -96.354392) (xy 252.268988 -96.354392) (xy 252.273059 -96.29877)
			(xy 252.285185 -96.244333) (xy 252.305108 -96.192242) (xy 252.332404 -96.143607) (xy 252.36649 -96.099464)
			(xy 252.406639 -96.060755) (xy 252.451997 -96.028304) (xy 252.501597 -96.002803) (xy 252.554381 -95.984796)
			(xy 252.609224 -95.974666) (xy 252.664958 -95.972629) (xy 252.720395 -95.978729) (xy 252.774352 -95.992835)
			(xy 252.825681 -96.014647) (xy 252.873287 -96.043701) (xy 252.916155 -96.079376) (xy 252.953372 -96.120913)
			(xy 252.984145 -96.167426) (xy 253.007817 -96.217923) (xy 253.023885 -96.27133) (xy 253.032005 -96.326506)
			(xy 253.032064 -96.329754) (xy 273.244562 -96.329754) (xy 273.248633 -96.274132) (xy 273.260759 -96.219695)
			(xy 273.280682 -96.167604) (xy 273.307978 -96.118969) (xy 273.342064 -96.074826) (xy 273.382213 -96.036117)
			(xy 273.427571 -96.003666) (xy 273.477171 -95.978165) (xy 273.529955 -95.960158) (xy 273.584798 -95.950028)
			(xy 273.640532 -95.947991) (xy 273.695969 -95.954091) (xy 273.749926 -95.968197) (xy 273.801255 -95.990009)
			(xy 273.848861 -96.019063) (xy 273.891729 -96.054738) (xy 273.928946 -96.096275) (xy 273.959719 -96.142788)
			(xy 273.983391 -96.193285) (xy 273.999459 -96.246692) (xy 274.007579 -96.301868) (xy 274.008088 -96.329754)
			(xy 274.007579 -96.35764) (xy 273.999459 -96.412816) (xy 273.99839 -96.416368) (xy 289.296092 -96.416368)
			(xy 289.300163 -96.360746) (xy 289.312289 -96.306309) (xy 289.332212 -96.254218) (xy 289.359508 -96.205583)
			(xy 289.393594 -96.16144) (xy 289.433743 -96.122731) (xy 289.479101 -96.09028) (xy 289.528701 -96.064779)
			(xy 289.581485 -96.046772) (xy 289.636328 -96.036642) (xy 289.692062 -96.034605) (xy 289.747499 -96.040705)
			(xy 289.801456 -96.054811) (xy 289.852785 -96.076623) (xy 289.900391 -96.105677) (xy 289.943259 -96.141352)
			(xy 289.980476 -96.182889) (xy 290.011249 -96.229402) (xy 290.034921 -96.279899) (xy 290.050989 -96.333306)
			(xy 290.059109 -96.388482) (xy 290.059618 -96.416368) (xy 290.059109 -96.444254) (xy 290.050989 -96.49943)
			(xy 290.034921 -96.552837) (xy 290.011249 -96.603334) (xy 289.980476 -96.649847) (xy 289.943259 -96.691384)
			(xy 289.900391 -96.727059) (xy 289.852785 -96.756113) (xy 289.801456 -96.777925) (xy 289.747499 -96.792031)
			(xy 289.692062 -96.798131) (xy 289.636328 -96.796094) (xy 289.581485 -96.785964) (xy 289.528701 -96.767957)
			(xy 289.479101 -96.742456) (xy 289.433743 -96.710005) (xy 289.393594 -96.671296) (xy 289.359508 -96.627153)
			(xy 289.332212 -96.578518) (xy 289.312289 -96.526427) (xy 289.300163 -96.47199) (xy 289.296092 -96.416368)
			(xy 273.99839 -96.416368) (xy 273.983391 -96.466223) (xy 273.959719 -96.51672) (xy 273.928946 -96.563233)
			(xy 273.891729 -96.60477) (xy 273.848861 -96.640445) (xy 273.801255 -96.669499) (xy 273.749926 -96.691311)
			(xy 273.695969 -96.705417) (xy 273.640532 -96.711517) (xy 273.584798 -96.70948) (xy 273.529955 -96.69935)
			(xy 273.477171 -96.681343) (xy 273.427571 -96.655842) (xy 273.382213 -96.623391) (xy 273.342064 -96.584682)
			(xy 273.307978 -96.540539) (xy 273.280682 -96.491904) (xy 273.260759 -96.439813) (xy 273.248633 -96.385376)
			(xy 273.244562 -96.329754) (xy 253.032064 -96.329754) (xy 253.032514 -96.354392) (xy 253.032005 -96.382278)
			(xy 253.023885 -96.437454) (xy 253.007817 -96.490861) (xy 252.984145 -96.541358) (xy 252.953372 -96.587871)
			(xy 252.916155 -96.629408) (xy 252.873287 -96.665083) (xy 252.825681 -96.694137) (xy 252.774352 -96.715949)
			(xy 252.720395 -96.730055) (xy 252.664958 -96.736155) (xy 252.609224 -96.734118) (xy 252.554381 -96.723988)
			(xy 252.501597 -96.705981) (xy 252.451997 -96.68048) (xy 252.406639 -96.648029) (xy 252.36649 -96.60932)
			(xy 252.332404 -96.565177) (xy 252.305108 -96.516542) (xy 252.285185 -96.464451) (xy 252.273059 -96.410014)
			(xy 252.268988 -96.354392) (xy 250.79706 -96.354392) (xy 250.79706 -97.026222) (xy 250.817103 -97.044434)
			(xy 250.852356 -97.085541) (xy 250.881447 -97.131218) (xy 250.90379 -97.180548) (xy 250.918939 -97.23254)
			(xy 250.924256 -97.269808) (xy 253.007874 -97.269808) (xy 253.011945 -97.214186) (xy 253.024071 -97.159749)
			(xy 253.043994 -97.107658) (xy 253.07129 -97.059023) (xy 253.105376 -97.01488) (xy 253.145525 -96.976171)
			(xy 253.190883 -96.94372) (xy 253.240483 -96.918219) (xy 253.293267 -96.900212) (xy 253.34811 -96.890082)
			(xy 253.403844 -96.888045) (xy 253.459281 -96.894145) (xy 253.513238 -96.908251) (xy 253.564567 -96.930063)
			(xy 253.612173 -96.959117) (xy 253.655041 -96.994792) (xy 253.692258 -97.036329) (xy 253.723031 -97.082842)
			(xy 253.746703 -97.133339) (xy 253.762771 -97.186746) (xy 253.770891 -97.241922) (xy 253.771368 -97.26803)
			(xy 255.198116 -97.26803) (xy 255.202187 -97.212408) (xy 255.214313 -97.157971) (xy 255.234236 -97.10588)
			(xy 255.261532 -97.057245) (xy 255.295618 -97.013102) (xy 255.335767 -96.974393) (xy 255.381125 -96.941942)
			(xy 255.430725 -96.916441) (xy 255.483509 -96.898434) (xy 255.538352 -96.888304) (xy 255.594086 -96.886267)
			(xy 255.649523 -96.892367) (xy 255.70348 -96.906473) (xy 255.754809 -96.928285) (xy 255.802415 -96.957339)
			(xy 255.845283 -96.993014) (xy 255.8825 -97.034551) (xy 255.913273 -97.081064) (xy 255.936945 -97.131561)
			(xy 255.953013 -97.184968) (xy 255.961133 -97.240144) (xy 255.961642 -97.26803) (xy 255.961535 -97.273872)
			(xy 257.590034 -97.273872) (xy 257.594105 -97.21825) (xy 257.606231 -97.163813) (xy 257.626154 -97.111722)
			(xy 257.65345 -97.063087) (xy 257.687536 -97.018944) (xy 257.727685 -96.980235) (xy 257.773043 -96.947784)
			(xy 257.822643 -96.922283) (xy 257.875427 -96.904276) (xy 257.93027 -96.894146) (xy 257.986004 -96.892109)
			(xy 258.041441 -96.898209) (xy 258.095398 -96.912315) (xy 258.146727 -96.934127) (xy 258.194333 -96.963181)
			(xy 258.237201 -96.998856) (xy 258.274418 -97.040393) (xy 258.305191 -97.086906) (xy 258.328863 -97.137403)
			(xy 258.344931 -97.19081) (xy 258.353051 -97.245986) (xy 258.35356 -97.273872) (xy 258.353051 -97.301758)
			(xy 258.349329 -97.327052) (xy 261.008858 -97.327052) (xy 261.008858 -97.272548) (xy 261.016614 -97.2186)
			(xy 261.031969 -97.166304) (xy 261.054609 -97.116726) (xy 261.084075 -97.070875) (xy 261.119766 -97.029683)
			(xy 261.160955 -96.993989) (xy 261.206805 -96.964521) (xy 261.256382 -96.941877) (xy 261.308676 -96.926519)
			(xy 261.362624 -96.918759) (xy 261.389876 -96.918272) (xy 261.416693 -96.918741) (xy 261.469797 -96.926258)
			(xy 261.521328 -96.941132) (xy 261.570269 -96.963071) (xy 261.615659 -96.991643) (xy 261.656603 -97.026287)
			(xy 261.692296 -97.066319) (xy 261.722036 -97.110952) (xy 261.734046 -97.134934) (xy 261.740971 -97.148224)
			(xy 261.761191 -97.170323) (xy 261.786948 -97.185614) (xy 261.816031 -97.192785) (xy 261.845945 -97.191219)
			(xy 261.87412 -97.181051) (xy 261.886446 -97.172526) (xy 261.911376 -97.154591) (xy 261.965745 -97.126043)
			(xy 262.023987 -97.10658) (xy 262.084596 -97.096705) (xy 262.1153 -97.096072) (xy 262.142563 -97.096556)
			(xy 262.196535 -97.104319) (xy 262.248852 -97.119687) (xy 262.298447 -97.142347) (xy 262.344312 -97.171836)
			(xy 262.38551 -97.207555) (xy 262.421204 -97.248776) (xy 262.450666 -97.294658) (xy 262.473295 -97.344268)
			(xy 262.488631 -97.396594) (xy 262.496361 -97.45057) (xy 262.496808 -97.477834) (xy 262.496808 -98.227642)
			(xy 272.78533 -98.227642) (xy 272.789401 -98.17202) (xy 272.801527 -98.117583) (xy 272.82145 -98.065492)
			(xy 272.848746 -98.016857) (xy 272.882832 -97.972714) (xy 272.922981 -97.934005) (xy 272.968339 -97.901554)
			(xy 273.017939 -97.876053) (xy 273.070723 -97.858046) (xy 273.125566 -97.847916) (xy 273.1813 -97.845879)
			(xy 273.236737 -97.851979) (xy 273.290694 -97.866085) (xy 273.342023 -97.887897) (xy 273.389629 -97.916951)
			(xy 273.432497 -97.952626) (xy 273.469714 -97.994163) (xy 273.500487 -98.040676) (xy 273.524159 -98.091173)
			(xy 273.540227 -98.14458) (xy 273.548347 -98.199756) (xy 273.548856 -98.227642) (xy 273.548347 -98.255528)
			(xy 273.540227 -98.310704) (xy 273.524159 -98.364111) (xy 273.500487 -98.414608) (xy 273.469714 -98.461121)
			(xy 273.432497 -98.502658) (xy 273.389629 -98.538333) (xy 273.342023 -98.567387) (xy 273.290694 -98.589199)
			(xy 273.236737 -98.603305) (xy 273.1813 -98.609405) (xy 273.125566 -98.607368) (xy 273.070723 -98.597238)
			(xy 273.017939 -98.579231) (xy 272.968339 -98.55373) (xy 272.922981 -98.521279) (xy 272.882832 -98.48257)
			(xy 272.848746 -98.438427) (xy 272.82145 -98.389792) (xy 272.801527 -98.337701) (xy 272.789401 -98.283264)
			(xy 272.78533 -98.227642) (xy 262.496808 -98.227642) (xy 262.496808 -98.341434) (xy 262.496321 -98.370241)
			(xy 262.487666 -98.427201) (xy 262.470543 -98.482212) (xy 262.445343 -98.534021) (xy 262.412637 -98.581452)
			(xy 262.373169 -98.623425) (xy 262.327839 -98.658984) (xy 262.277676 -98.687322) (xy 262.250936 -98.69805)
			(xy 262.23826 -98.703398) (xy 262.216121 -98.71971) (xy 262.199139 -98.741339) (xy 262.188545 -98.766716)
			(xy 262.185109 -98.794) (xy 262.189079 -98.821211) (xy 262.200167 -98.846375) (xy 262.208518 -98.857308)
			(xy 262.224707 -98.877825) (xy 262.251908 -98.922451) (xy 262.272757 -98.970375) (xy 262.286863 -99.020698)
			(xy 262.293961 -99.072476) (xy 262.29437 -99.098608) (xy 262.294325 -99.101148) (xy 266.089382 -99.101148)
			(xy 266.093453 -99.045526) (xy 266.105579 -98.991089) (xy 266.125502 -98.938998) (xy 266.152798 -98.890363)
			(xy 266.186884 -98.84622) (xy 266.227033 -98.807511) (xy 266.272391 -98.77506) (xy 266.321991 -98.749559)
			(xy 266.374775 -98.731552) (xy 266.429618 -98.721422) (xy 266.485352 -98.719385) (xy 266.540789 -98.725485)
			(xy 266.594746 -98.739591) (xy 266.646075 -98.761403) (xy 266.693681 -98.790457) (xy 266.736549 -98.826132)
			(xy 266.773766 -98.867669) (xy 266.804539 -98.914182) (xy 266.828211 -98.964679) (xy 266.844279 -99.018086)
			(xy 266.852399 -99.073262) (xy 266.852908 -99.101148) (xy 266.852399 -99.129034) (xy 266.844279 -99.18421)
			(xy 266.828211 -99.237617) (xy 266.804539 -99.288114) (xy 266.773766 -99.334627) (xy 266.736549 -99.376164)
			(xy 266.693681 -99.411839) (xy 266.646075 -99.440893) (xy 266.594746 -99.462705) (xy 266.540789 -99.476811)
			(xy 266.485352 -99.482911) (xy 266.429618 -99.480874) (xy 266.374775 -99.470744) (xy 266.321991 -99.452737)
			(xy 266.272391 -99.427236) (xy 266.227033 -99.394785) (xy 266.186884 -99.356076) (xy 266.152798 -99.311933)
			(xy 266.125502 -99.263298) (xy 266.105579 -99.211207) (xy 266.093453 -99.15677) (xy 266.089382 -99.101148)
			(xy 262.294325 -99.101148) (xy 262.293884 -99.125859) (xy 262.286128 -99.179807) (xy 262.270773 -99.232102)
			(xy 262.248131 -99.281679) (xy 262.218665 -99.327529) (xy 262.182974 -99.36872) (xy 262.141783 -99.404411)
			(xy 262.095933 -99.433877) (xy 262.046356 -99.456519) (xy 261.994061 -99.471874) (xy 261.940113 -99.47963)
			(xy 261.885611 -99.47963) (xy 261.831663 -99.471874) (xy 261.779368 -99.456519) (xy 261.729791 -99.433877)
			(xy 261.683941 -99.404411) (xy 261.64275 -99.36872) (xy 261.607059 -99.327529) (xy 261.577593 -99.281679)
			(xy 261.554951 -99.232102) (xy 261.539596 -99.179807) (xy 261.53184 -99.125859) (xy 261.531354 -99.098608)
			(xy 261.531625 -99.078969) (xy 261.535701 -99.039903) (xy 261.539482 -99.02063) (xy 261.541802 -99.00717)
			(xy 261.540035 -98.979925) (xy 261.531115 -98.954122) (xy 261.515678 -98.931603) (xy 261.494827 -98.913977)
			(xy 261.470053 -98.902504) (xy 261.443124 -98.898004) (xy 261.4295 -98.898964) (xy 261.419622 -98.899922)
			(xy 261.3998 -98.900938) (xy 261.389876 -98.900996) (xy 261.362625 -98.900533) (xy 261.308678 -98.892773)
			(xy 261.256385 -98.877415) (xy 261.206809 -98.854772) (xy 261.16096 -98.825304) (xy 261.119771 -98.789612)
			(xy 261.084081 -98.748421) (xy 261.054616 -98.70257) (xy 261.031976 -98.652993) (xy 261.016622 -98.600698)
			(xy 261.008866 -98.546751) (xy 261.008866 -98.492249) (xy 261.016622 -98.438302) (xy 261.031976 -98.386007)
			(xy 261.054616 -98.33643) (xy 261.084081 -98.290579) (xy 261.119771 -98.249388) (xy 261.16096 -98.213696)
			(xy 261.206809 -98.184228) (xy 261.256385 -98.161585) (xy 261.308678 -98.146227) (xy 261.362625 -98.138467)
			(xy 261.389876 -98.13798) (xy 261.414925 -98.138381) (xy 261.464592 -98.144925) (xy 261.512979 -98.157903)
			(xy 261.559255 -98.177092) (xy 261.581138 -98.189288) (xy 261.594612 -98.196464) (xy 261.624342 -98.203323)
			(xy 261.654771 -98.201102) (xy 261.68319 -98.19) (xy 261.707067 -98.171005) (xy 261.724274 -98.14581)
			(xy 261.73328 -98.116659) (xy 261.733792 -98.101404) (xy 261.733792 -97.717864) (xy 261.733283 -97.702602)
			(xy 261.724289 -97.673434) (xy 261.707084 -97.648222) (xy 261.683202 -97.629214) (xy 261.654772 -97.618105)
			(xy 261.62433 -97.615885) (xy 261.594589 -97.622752) (xy 261.581138 -97.62998) (xy 261.55926 -97.642188)
			(xy 261.51299 -97.661403) (xy 261.464601 -97.674385) (xy 261.414927 -97.680912) (xy 261.389876 -97.681288)
			(xy 261.362624 -97.680841) (xy 261.308676 -97.673081) (xy 261.256382 -97.657723) (xy 261.206805 -97.635079)
			(xy 261.160955 -97.605611) (xy 261.119766 -97.569917) (xy 261.084075 -97.528725) (xy 261.054609 -97.482874)
			(xy 261.031969 -97.433296) (xy 261.016614 -97.381) (xy 261.008858 -97.327052) (xy 258.349329 -97.327052)
			(xy 258.344931 -97.356934) (xy 258.328863 -97.410341) (xy 258.305191 -97.460838) (xy 258.274418 -97.507351)
			(xy 258.237201 -97.548888) (xy 258.194333 -97.584563) (xy 258.146727 -97.613617) (xy 258.095398 -97.635429)
			(xy 258.041441 -97.649535) (xy 257.986004 -97.655635) (xy 257.93027 -97.653598) (xy 257.875427 -97.643468)
			(xy 257.822643 -97.625461) (xy 257.773043 -97.59996) (xy 257.727685 -97.567509) (xy 257.687536 -97.5288)
			(xy 257.65345 -97.484657) (xy 257.626154 -97.436022) (xy 257.606231 -97.383931) (xy 257.594105 -97.329494)
			(xy 257.590034 -97.273872) (xy 255.961535 -97.273872) (xy 255.961133 -97.295916) (xy 255.953013 -97.351092)
			(xy 255.936945 -97.404499) (xy 255.913273 -97.454996) (xy 255.8825 -97.501509) (xy 255.845283 -97.543046)
			(xy 255.802415 -97.578721) (xy 255.754809 -97.607775) (xy 255.70348 -97.629587) (xy 255.649523 -97.643693)
			(xy 255.594086 -97.649793) (xy 255.538352 -97.647756) (xy 255.483509 -97.637626) (xy 255.430725 -97.619619)
			(xy 255.381125 -97.594118) (xy 255.335767 -97.561667) (xy 255.295618 -97.522958) (xy 255.261532 -97.478815)
			(xy 255.234236 -97.43018) (xy 255.214313 -97.378089) (xy 255.202187 -97.323652) (xy 255.198116 -97.26803)
			(xy 253.771368 -97.26803) (xy 253.7714 -97.269808) (xy 253.770891 -97.297694) (xy 253.762771 -97.35287)
			(xy 253.746703 -97.406277) (xy 253.723031 -97.456774) (xy 253.692258 -97.503287) (xy 253.655041 -97.544824)
			(xy 253.612173 -97.580499) (xy 253.564567 -97.609553) (xy 253.513238 -97.631365) (xy 253.459281 -97.645471)
			(xy 253.403844 -97.651571) (xy 253.34811 -97.649534) (xy 253.293267 -97.639404) (xy 253.240483 -97.621397)
			(xy 253.190883 -97.595896) (xy 253.145525 -97.563445) (xy 253.105376 -97.524736) (xy 253.07129 -97.480593)
			(xy 253.043994 -97.431958) (xy 253.024071 -97.379867) (xy 253.011945 -97.32543) (xy 253.007874 -97.269808)
			(xy 250.924256 -97.269808) (xy 250.926588 -97.286151) (xy 250.926584 -97.340305) (xy 250.918927 -97.393914)
			(xy 250.903771 -97.445904) (xy 250.88142 -97.49523) (xy 250.852323 -97.540903) (xy 250.817064 -97.582006)
			(xy 250.79706 -97.600262) (xy 250.79706 -99.18573) (xy 250.82881 -99.19843) (xy 250.854938 -99.209484)
			(xy 250.903871 -99.238189) (xy 250.948014 -99.273824) (xy 250.986395 -99.315601) (xy 251.018166 -99.362601)
			(xy 251.042629 -99.413787) (xy 251.059243 -99.468031) (xy 251.066756 -99.518216) (xy 253.01143 -99.518216)
			(xy 253.015501 -99.462594) (xy 253.027627 -99.408157) (xy 253.04755 -99.356066) (xy 253.074846 -99.307431)
			(xy 253.108932 -99.263288) (xy 253.149081 -99.224579) (xy 253.194439 -99.192128) (xy 253.244039 -99.166627)
			(xy 253.296823 -99.14862) (xy 253.351666 -99.13849) (xy 253.4074 -99.136453) (xy 253.462837 -99.142553)
			(xy 253.516794 -99.156659) (xy 253.568123 -99.178471) (xy 253.615729 -99.207525) (xy 253.658597 -99.2432)
			(xy 253.695814 -99.284737) (xy 253.726587 -99.33125) (xy 253.750259 -99.381747) (xy 253.766327 -99.435154)
			(xy 253.774447 -99.49033) (xy 253.774956 -99.518216) (xy 253.774447 -99.546102) (xy 253.770589 -99.572318)
			(xy 255.291588 -99.572318) (xy 255.295659 -99.516696) (xy 255.307785 -99.462259) (xy 255.327708 -99.410168)
			(xy 255.355004 -99.361533) (xy 255.38909 -99.31739) (xy 255.429239 -99.278681) (xy 255.474597 -99.24623)
			(xy 255.524197 -99.220729) (xy 255.576981 -99.202722) (xy 255.631824 -99.192592) (xy 255.687558 -99.190555)
			(xy 255.742995 -99.196655) (xy 255.796952 -99.210761) (xy 255.848281 -99.232573) (xy 255.895887 -99.261627)
			(xy 255.938755 -99.297302) (xy 255.975972 -99.338839) (xy 256.006745 -99.385352) (xy 256.013066 -99.398836)
			(xy 257.58978 -99.398836) (xy 257.593851 -99.343214) (xy 257.605977 -99.288777) (xy 257.6259 -99.236686)
			(xy 257.653196 -99.188051) (xy 257.687282 -99.143908) (xy 257.727431 -99.105199) (xy 257.772789 -99.072748)
			(xy 257.822389 -99.047247) (xy 257.875173 -99.02924) (xy 257.930016 -99.01911) (xy 257.98575 -99.017073)
			(xy 258.041187 -99.023173) (xy 258.095144 -99.037279) (xy 258.146473 -99.059091) (xy 258.194079 -99.088145)
			(xy 258.236947 -99.12382) (xy 258.274164 -99.165357) (xy 258.304937 -99.21187) (xy 258.328609 -99.262367)
			(xy 258.344677 -99.315774) (xy 258.352797 -99.37095) (xy 258.353306 -99.398836) (xy 258.352797 -99.426722)
			(xy 258.344677 -99.481898) (xy 258.328609 -99.535305) (xy 258.304937 -99.585802) (xy 258.274164 -99.632315)
			(xy 258.236947 -99.673852) (xy 258.194079 -99.709527) (xy 258.146473 -99.738581) (xy 258.095144 -99.760393)
			(xy 258.041187 -99.774499) (xy 257.98575 -99.780599) (xy 257.930016 -99.778562) (xy 257.875173 -99.768432)
			(xy 257.822389 -99.750425) (xy 257.772789 -99.724924) (xy 257.727431 -99.692473) (xy 257.687282 -99.653764)
			(xy 257.653196 -99.609621) (xy 257.6259 -99.560986) (xy 257.605977 -99.508895) (xy 257.593851 -99.454458)
			(xy 257.58978 -99.398836) (xy 256.013066 -99.398836) (xy 256.030417 -99.435849) (xy 256.046485 -99.489256)
			(xy 256.054605 -99.544432) (xy 256.055114 -99.572318) (xy 256.054605 -99.600204) (xy 256.046485 -99.65538)
			(xy 256.030417 -99.708787) (xy 256.006745 -99.759284) (xy 255.975972 -99.805797) (xy 255.938755 -99.847334)
			(xy 255.895887 -99.883009) (xy 255.848281 -99.912063) (xy 255.796952 -99.933875) (xy 255.742995 -99.947981)
			(xy 255.687558 -99.954081) (xy 255.631824 -99.952044) (xy 255.576981 -99.941914) (xy 255.524197 -99.923907)
			(xy 255.474597 -99.898406) (xy 255.429239 -99.865955) (xy 255.38909 -99.827246) (xy 255.355004 -99.783103)
			(xy 255.327708 -99.734468) (xy 255.307785 -99.682377) (xy 255.295659 -99.62794) (xy 255.291588 -99.572318)
			(xy 253.770589 -99.572318) (xy 253.766327 -99.601278) (xy 253.750259 -99.654685) (xy 253.726587 -99.705182)
			(xy 253.695814 -99.751695) (xy 253.658597 -99.793232) (xy 253.615729 -99.828907) (xy 253.568123 -99.857961)
			(xy 253.516794 -99.879773) (xy 253.462837 -99.893879) (xy 253.4074 -99.899979) (xy 253.351666 -99.897942)
			(xy 253.296823 -99.887812) (xy 253.244039 -99.869805) (xy 253.194439 -99.844304) (xy 253.149081 -99.811853)
			(xy 253.108932 -99.773144) (xy 253.074846 -99.729001) (xy 253.04755 -99.680366) (xy 253.027627 -99.628275)
			(xy 253.015501 -99.573838) (xy 253.01143 -99.518216) (xy 251.066756 -99.518216) (xy 251.067642 -99.524137)
			(xy 251.067642 -99.580868) (xy 251.059242 -99.636974) (xy 251.042627 -99.691217) (xy 251.018164 -99.742403)
			(xy 250.986392 -99.789402) (xy 250.948011 -99.831179) (xy 250.903867 -99.866813) (xy 250.854934 -99.895518)
			(xy 250.82881 -99.906582) (xy 250.79706 -99.919282) (xy 250.79706 -100.167948) (xy 260.430262 -100.167948)
			(xy 260.434333 -100.112326) (xy 260.446459 -100.057889) (xy 260.466382 -100.005798) (xy 260.493678 -99.957163)
			(xy 260.527764 -99.91302) (xy 260.567913 -99.874311) (xy 260.613271 -99.84186) (xy 260.662871 -99.816359)
			(xy 260.715655 -99.798352) (xy 260.770498 -99.788222) (xy 260.826232 -99.786185) (xy 260.881669 -99.792285)
			(xy 260.935626 -99.806391) (xy 260.986955 -99.828203) (xy 261.034561 -99.857257) (xy 261.077429 -99.892932)
			(xy 261.114646 -99.934469) (xy 261.145419 -99.980982) (xy 261.169091 -100.031479) (xy 261.185159 -100.084886)
			(xy 261.193279 -100.140062) (xy 261.193788 -100.167948) (xy 261.193279 -100.195834) (xy 261.185159 -100.25101)
			(xy 261.169091 -100.304417) (xy 261.145419 -100.354914) (xy 261.114646 -100.401427) (xy 261.077429 -100.442964)
			(xy 261.034561 -100.478639) (xy 260.986955 -100.507693) (xy 260.935626 -100.529505) (xy 260.881669 -100.543611)
			(xy 260.826232 -100.549711) (xy 260.770498 -100.547674) (xy 260.715655 -100.537544) (xy 260.662871 -100.519537)
			(xy 260.613271 -100.494036) (xy 260.567913 -100.461585) (xy 260.527764 -100.422876) (xy 260.493678 -100.378733)
			(xy 260.466382 -100.330098) (xy 260.446459 -100.278007) (xy 260.434333 -100.22357) (xy 260.430262 -100.167948)
			(xy 250.79706 -100.167948) (xy 250.79706 -101.78288) (xy 253.084582 -101.78288) (xy 253.088653 -101.727258)
			(xy 253.100779 -101.672821) (xy 253.120702 -101.62073) (xy 253.147998 -101.572095) (xy 253.182084 -101.527952)
			(xy 253.222233 -101.489243) (xy 253.267591 -101.456792) (xy 253.317191 -101.431291) (xy 253.369975 -101.413284)
			(xy 253.424818 -101.403154) (xy 253.480552 -101.401117) (xy 253.535989 -101.407217) (xy 253.589946 -101.421323)
			(xy 253.641275 -101.443135) (xy 253.688881 -101.472189) (xy 253.731749 -101.507864) (xy 253.768966 -101.549401)
			(xy 253.799739 -101.595914) (xy 253.823411 -101.646411) (xy 253.839479 -101.699818) (xy 253.847599 -101.754994)
			(xy 253.848108 -101.78288) (xy 253.847599 -101.810766) (xy 253.840863 -101.85654) (xy 255.332482 -101.85654)
			(xy 255.336553 -101.800918) (xy 255.348679 -101.746481) (xy 255.368602 -101.69439) (xy 255.395898 -101.645755)
			(xy 255.429984 -101.601612) (xy 255.470133 -101.562903) (xy 255.515491 -101.530452) (xy 255.565091 -101.504951)
			(xy 255.617875 -101.486944) (xy 255.672718 -101.476814) (xy 255.728452 -101.474777) (xy 255.783889 -101.480877)
			(xy 255.837846 -101.494983) (xy 255.889175 -101.516795) (xy 255.936781 -101.545849) (xy 255.979649 -101.581524)
			(xy 256.016866 -101.623061) (xy 256.047639 -101.669574) (xy 256.071311 -101.720071) (xy 256.087379 -101.773478)
			(xy 256.095499 -101.828654) (xy 256.096008 -101.85654) (xy 256.095994 -101.857302) (xy 257.59486 -101.857302)
			(xy 257.598931 -101.80168) (xy 257.611057 -101.747243) (xy 257.63098 -101.695152) (xy 257.658276 -101.646517)
			(xy 257.692362 -101.602374) (xy 257.732511 -101.563665) (xy 257.777869 -101.531214) (xy 257.827469 -101.505713)
			(xy 257.880253 -101.487706) (xy 257.935096 -101.477576) (xy 257.99083 -101.475539) (xy 258.046267 -101.481639)
			(xy 258.100224 -101.495745) (xy 258.151553 -101.517557) (xy 258.199159 -101.546611) (xy 258.242027 -101.582286)
			(xy 258.279244 -101.623823) (xy 258.310017 -101.670336) (xy 258.333689 -101.720833) (xy 258.34097 -101.745034)
			(xy 260.361174 -101.745034) (xy 260.365245 -101.689412) (xy 260.377371 -101.634975) (xy 260.397294 -101.582884)
			(xy 260.42459 -101.534249) (xy 260.458676 -101.490106) (xy 260.498825 -101.451397) (xy 260.544183 -101.418946)
			(xy 260.593783 -101.393445) (xy 260.646567 -101.375438) (xy 260.70141 -101.365308) (xy 260.757144 -101.363271)
			(xy 260.812581 -101.369371) (xy 260.866538 -101.383477) (xy 260.917867 -101.405289) (xy 260.965473 -101.434343)
			(xy 261.008341 -101.470018) (xy 261.045558 -101.511555) (xy 261.076331 -101.558068) (xy 261.100003 -101.608565)
			(xy 261.116071 -101.661972) (xy 261.124191 -101.717148) (xy 261.1247 -101.745034) (xy 261.124191 -101.77292)
			(xy 261.11966 -101.803708) (xy 262.218422 -101.803708) (xy 262.222493 -101.748086) (xy 262.234619 -101.693649)
			(xy 262.254542 -101.641558) (xy 262.281838 -101.592923) (xy 262.315924 -101.54878) (xy 262.356073 -101.510071)
			(xy 262.401431 -101.47762) (xy 262.451031 -101.452119) (xy 262.503815 -101.434112) (xy 262.558658 -101.423982)
			(xy 262.614392 -101.421945) (xy 262.669829 -101.428045) (xy 262.723786 -101.442151) (xy 262.775115 -101.463963)
			(xy 262.822721 -101.493017) (xy 262.865589 -101.528692) (xy 262.902806 -101.570229) (xy 262.933579 -101.616742)
			(xy 262.957251 -101.667239) (xy 262.973319 -101.720646) (xy 262.981439 -101.775822) (xy 262.981948 -101.803708)
			(xy 262.981439 -101.831594) (xy 262.973319 -101.88677) (xy 262.957251 -101.940177) (xy 262.933579 -101.990674)
			(xy 262.902806 -102.037187) (xy 262.865589 -102.078724) (xy 262.822721 -102.114399) (xy 262.775115 -102.143453)
			(xy 262.723786 -102.165265) (xy 262.669829 -102.179371) (xy 262.614392 -102.185471) (xy 262.558658 -102.183434)
			(xy 262.503815 -102.173304) (xy 262.451031 -102.155297) (xy 262.401431 -102.129796) (xy 262.356073 -102.097345)
			(xy 262.315924 -102.058636) (xy 262.281838 -102.014493) (xy 262.254542 -101.965858) (xy 262.234619 -101.913767)
			(xy 262.222493 -101.85933) (xy 262.218422 -101.803708) (xy 261.11966 -101.803708) (xy 261.116071 -101.828096)
			(xy 261.100003 -101.881503) (xy 261.076331 -101.932) (xy 261.045558 -101.978513) (xy 261.008341 -102.02005)
			(xy 260.965473 -102.055725) (xy 260.917867 -102.084779) (xy 260.866538 -102.106591) (xy 260.812581 -102.120697)
			(xy 260.757144 -102.126797) (xy 260.70141 -102.12476) (xy 260.646567 -102.11463) (xy 260.593783 -102.096623)
			(xy 260.544183 -102.071122) (xy 260.498825 -102.038671) (xy 260.458676 -101.999962) (xy 260.42459 -101.955819)
			(xy 260.397294 -101.907184) (xy 260.377371 -101.855093) (xy 260.365245 -101.800656) (xy 260.361174 -101.745034)
			(xy 258.34097 -101.745034) (xy 258.349757 -101.77424) (xy 258.357877 -101.829416) (xy 258.358386 -101.857302)
			(xy 258.357877 -101.885188) (xy 258.349757 -101.940364) (xy 258.333689 -101.993771) (xy 258.310017 -102.044268)
			(xy 258.279244 -102.090781) (xy 258.242027 -102.132318) (xy 258.199159 -102.167993) (xy 258.151553 -102.197047)
			(xy 258.100224 -102.218859) (xy 258.046267 -102.232965) (xy 257.99083 -102.239065) (xy 257.935096 -102.237028)
			(xy 257.880253 -102.226898) (xy 257.827469 -102.208891) (xy 257.777869 -102.18339) (xy 257.732511 -102.150939)
			(xy 257.692362 -102.11223) (xy 257.658276 -102.068087) (xy 257.63098 -102.019452) (xy 257.611057 -101.967361)
			(xy 257.598931 -101.912924) (xy 257.59486 -101.857302) (xy 256.095994 -101.857302) (xy 256.095499 -101.884426)
			(xy 256.087379 -101.939602) (xy 256.071311 -101.993009) (xy 256.047639 -102.043506) (xy 256.016866 -102.090019)
			(xy 255.979649 -102.131556) (xy 255.936781 -102.167231) (xy 255.889175 -102.196285) (xy 255.837846 -102.218097)
			(xy 255.783889 -102.232203) (xy 255.728452 -102.238303) (xy 255.672718 -102.236266) (xy 255.617875 -102.226136)
			(xy 255.565091 -102.208129) (xy 255.515491 -102.182628) (xy 255.470133 -102.150177) (xy 255.429984 -102.111468)
			(xy 255.395898 -102.067325) (xy 255.368602 -102.01869) (xy 255.348679 -101.966599) (xy 255.336553 -101.912162)
			(xy 255.332482 -101.85654) (xy 253.840863 -101.85654) (xy 253.839479 -101.865942) (xy 253.823411 -101.919349)
			(xy 253.799739 -101.969846) (xy 253.768966 -102.016359) (xy 253.731749 -102.057896) (xy 253.688881 -102.093571)
			(xy 253.641275 -102.122625) (xy 253.589946 -102.144437) (xy 253.535989 -102.158543) (xy 253.480552 -102.164643)
			(xy 253.424818 -102.162606) (xy 253.369975 -102.152476) (xy 253.317191 -102.134469) (xy 253.267591 -102.108968)
			(xy 253.222233 -102.076517) (xy 253.182084 -102.037808) (xy 253.147998 -101.993665) (xy 253.120702 -101.94503)
			(xy 253.100779 -101.892939) (xy 253.088653 -101.838502) (xy 253.084582 -101.78288) (xy 250.79706 -101.78288)
			(xy 250.79706 -102.63886) (xy 252.17577 -102.63886) (xy 252.179841 -102.583238) (xy 252.191967 -102.528801)
			(xy 252.21189 -102.47671) (xy 252.239186 -102.428075) (xy 252.273272 -102.383932) (xy 252.313421 -102.345223)
			(xy 252.358779 -102.312772) (xy 252.408379 -102.287271) (xy 252.461163 -102.269264) (xy 252.516006 -102.259134)
			(xy 252.57174 -102.257097) (xy 252.627177 -102.263197) (xy 252.681134 -102.277303) (xy 252.732463 -102.299115)
			(xy 252.780069 -102.328169) (xy 252.822937 -102.363844) (xy 252.860154 -102.405381) (xy 252.890927 -102.451894)
			(xy 252.914599 -102.502391) (xy 252.930667 -102.555798) (xy 252.938787 -102.610974) (xy 252.939296 -102.63886)
			(xy 252.938787 -102.666746) (xy 252.930667 -102.721922) (xy 252.914599 -102.775329) (xy 252.890927 -102.825826)
			(xy 252.860154 -102.872339) (xy 252.822937 -102.913876) (xy 252.780069 -102.949551) (xy 252.732463 -102.978605)
			(xy 252.681134 -103.000417) (xy 252.627177 -103.014523) (xy 252.57174 -103.020623) (xy 252.516006 -103.018586)
			(xy 252.461163 -103.008456) (xy 252.408379 -102.990449) (xy 252.358779 -102.964948) (xy 252.313421 -102.932497)
			(xy 252.273272 -102.893788) (xy 252.239186 -102.849645) (xy 252.21189 -102.80101) (xy 252.191967 -102.748919)
			(xy 252.179841 -102.694482) (xy 252.17577 -102.63886) (xy 250.79706 -102.63886) (xy 250.79706 -103.429308)
			(xy 250.797554 -103.444316) (xy 250.806205 -103.473056) (xy 250.822846 -103.498034) (xy 250.846036 -103.517088)
			(xy 250.873767 -103.52857) (xy 250.903638 -103.531484) (xy 250.918472 -103.52913) (xy 250.936759 -103.525709)
			(xy 250.973783 -103.522022) (xy 250.992386 -103.521764) (xy 251.018063 -103.522207) (xy 251.068947 -103.52914)
			(xy 251.118443 -103.542828) (xy 251.165659 -103.563026) (xy 251.209742 -103.589368) (xy 251.249898 -103.62138)
			(xy 251.267976 -103.63962) (xy 251.277562 -103.649108) (xy 251.300603 -103.663112) (xy 251.326508 -103.67059)
			(xy 251.353467 -103.67102) (xy 251.379597 -103.664372) (xy 251.403072 -103.65111) (xy 251.422254 -103.632162)
			(xy 251.435801 -103.60885) (xy 251.43968 -103.595932) (xy 251.447397 -103.569346) (xy 251.469454 -103.518572)
			(xy 251.498625 -103.471524) (xy 251.534296 -103.429192) (xy 251.575717 -103.392466) (xy 251.622015 -103.362119)
			(xy 251.672218 -103.338791) (xy 251.725267 -103.322972) (xy 251.780047 -103.314995) (xy 251.807726 -103.3145)
			(xy 251.834975 -103.314988) (xy 251.888919 -103.322747) (xy 251.94121 -103.338104) (xy 251.990783 -103.360746)
			(xy 252.036629 -103.390212) (xy 252.077815 -103.425903) (xy 252.113503 -103.467092) (xy 252.142966 -103.51294)
			(xy 252.165605 -103.562515) (xy 252.180959 -103.614806) (xy 252.188714 -103.668751) (xy 252.188714 -103.723249)
			(xy 252.180959 -103.777194) (xy 252.165605 -103.829485) (xy 252.142966 -103.87906) (xy 252.113503 -103.924908)
			(xy 252.077815 -103.966097) (xy 252.036629 -104.001788) (xy 251.990783 -104.031254) (xy 251.94121 -104.053896)
			(xy 251.888919 -104.069253) (xy 251.834975 -104.077012) (xy 251.807726 -104.077516) (xy 251.782049 -104.077074)
			(xy 251.731165 -104.070142) (xy 251.681668 -104.056454) (xy 251.634452 -104.036257) (xy 251.590368 -104.009915)
			(xy 251.550212 -103.977902) (xy 251.532136 -103.95966) (xy 251.522548 -103.950172) (xy 251.499505 -103.936167)
			(xy 251.473598 -103.928689) (xy 251.446637 -103.928257) (xy 251.420504 -103.934904) (xy 251.397025 -103.948164)
			(xy 251.377839 -103.967111) (xy 251.364286 -103.990423) (xy 251.360432 -104.003348) (xy 251.352716 -104.029935)
			(xy 251.330661 -104.080712) (xy 251.301492 -104.127764) (xy 251.265821 -104.1701) (xy 251.224401 -104.206829)
			(xy 251.178102 -104.237178) (xy 251.127899 -104.260509) (xy 251.074848 -104.276331) (xy 251.020066 -104.28431)
			(xy 250.992386 -104.28478) (xy 250.973783 -104.284519) (xy 250.93676 -104.280831) (xy 250.918472 -104.277414)
			(xy 250.903652 -104.275018) (xy 250.873793 -104.27798) (xy 250.846081 -104.289485) (xy 250.822904 -104.308542)
			(xy 250.806261 -104.333508) (xy 250.798577 -104.358948) (xy 257.534662 -104.358948) (xy 257.538733 -104.303326)
			(xy 257.550859 -104.248889) (xy 257.570782 -104.196798) (xy 257.598078 -104.148163) (xy 257.632164 -104.10402)
			(xy 257.672313 -104.065311) (xy 257.717671 -104.03286) (xy 257.767271 -104.007359) (xy 257.820055 -103.989352)
			(xy 257.874898 -103.979222) (xy 257.930632 -103.977185) (xy 257.986069 -103.983285) (xy 258.040026 -103.997391)
			(xy 258.091355 -104.019203) (xy 258.138961 -104.048257) (xy 258.181829 -104.083932) (xy 258.219046 -104.125469)
			(xy 258.249819 -104.171982) (xy 258.273491 -104.222479) (xy 258.289559 -104.275886) (xy 258.297679 -104.331062)
			(xy 258.298188 -104.358948) (xy 258.297679 -104.386834) (xy 258.289559 -104.44201) (xy 258.273491 -104.495417)
			(xy 258.249819 -104.545914) (xy 258.219046 -104.592427) (xy 258.181829 -104.633964) (xy 258.138961 -104.669639)
			(xy 258.091355 -104.698693) (xy 258.040026 -104.720505) (xy 257.986069 -104.734611) (xy 257.930632 -104.740711)
			(xy 257.874898 -104.738674) (xy 257.820055 -104.728544) (xy 257.767271 -104.710537) (xy 257.717671 -104.685036)
			(xy 257.672313 -104.652585) (xy 257.632164 -104.613876) (xy 257.598078 -104.569733) (xy 257.570782 -104.521098)
			(xy 257.550859 -104.469007) (xy 257.538733 -104.41457) (xy 257.534662 -104.358948) (xy 250.798577 -104.358948)
			(xy 250.797585 -104.362232) (xy 250.79706 -104.377236) (xy 250.79706 -105.556812) (xy 252.956568 -105.556812)
			(xy 252.957158 -105.527621) (xy 252.966064 -105.469922) (xy 252.983654 -105.414254) (xy 253.00952 -105.361914)
			(xy 253.043055 -105.314124) (xy 253.083479 -105.272001) (xy 253.129847 -105.236526) (xy 253.155196 -105.22204)
			(xy 253.167776 -105.214685) (xy 253.188362 -105.194073) (xy 253.202296 -105.16849) (xy 253.208446 -105.140015)
			(xy 253.206311 -105.110962) (xy 253.196066 -105.083692) (xy 253.178543 -105.06042) (xy 253.167134 -105.051352)
			(xy 253.143672 -105.033254) (xy 253.102147 -104.990986) (xy 253.06766 -104.942804) (xy 253.041042 -104.889866)
			(xy 253.022933 -104.833448) (xy 253.01377 -104.774908) (xy 253.01321 -104.745282) (xy 253.013696 -104.718031)
			(xy 253.021452 -104.664083) (xy 253.036807 -104.611788) (xy 253.059449 -104.562211) (xy 253.088915 -104.516361)
			(xy 253.124606 -104.47517) (xy 253.165797 -104.439479) (xy 253.211647 -104.410013) (xy 253.261224 -104.387371)
			(xy 253.313519 -104.372016) (xy 253.367467 -104.36426) (xy 253.421969 -104.36426) (xy 253.475917 -104.372016)
			(xy 253.528212 -104.387371) (xy 253.577789 -104.410013) (xy 253.623639 -104.439479) (xy 253.66483 -104.47517)
			(xy 253.700521 -104.516361) (xy 253.729987 -104.562211) (xy 253.752629 -104.611788) (xy 253.767984 -104.664083)
			(xy 253.77574 -104.718031) (xy 253.776226 -104.745282) (xy 253.775635 -104.774473) (xy 253.766729 -104.832172)
			(xy 253.749139 -104.887841) (xy 253.723274 -104.940181) (xy 253.689739 -104.98797) (xy 253.649315 -105.030094)
			(xy 253.602947 -105.065568) (xy 253.577598 -105.080054) (xy 253.565024 -105.087417) (xy 253.544439 -105.108027)
			(xy 253.530506 -105.133609) (xy 253.524356 -105.162082) (xy 253.526489 -105.191133) (xy 253.536732 -105.218402)
			(xy 253.554253 -105.241674) (xy 253.56566 -105.250742) (xy 253.589118 -105.268845) (xy 253.630643 -105.311112)
			(xy 253.639974 -105.324148) (xy 254.919224 -105.324148) (xy 254.923295 -105.268526) (xy 254.935421 -105.214089)
			(xy 254.955344 -105.161998) (xy 254.98264 -105.113363) (xy 255.016726 -105.06922) (xy 255.056875 -105.030511)
			(xy 255.102233 -104.99806) (xy 255.151833 -104.972559) (xy 255.204617 -104.954552) (xy 255.25946 -104.944422)
			(xy 255.315194 -104.942385) (xy 255.370631 -104.948485) (xy 255.424588 -104.962591) (xy 255.475917 -104.984403)
			(xy 255.523523 -105.013457) (xy 255.566391 -105.049132) (xy 255.603608 -105.090669) (xy 255.634381 -105.137182)
			(xy 255.658053 -105.187679) (xy 255.674121 -105.241086) (xy 255.682241 -105.296262) (xy 255.68275 -105.324148)
			(xy 255.682241 -105.352034) (xy 255.674121 -105.40721) (xy 255.658053 -105.460617) (xy 255.634381 -105.511114)
			(xy 255.603608 -105.557627) (xy 255.566391 -105.599164) (xy 255.523523 -105.634839) (xy 255.475917 -105.663893)
			(xy 255.438606 -105.679748) (xy 256.264662 -105.679748) (xy 256.268733 -105.624126) (xy 256.280859 -105.569689)
			(xy 256.300782 -105.517598) (xy 256.328078 -105.468963) (xy 256.362164 -105.42482) (xy 256.402313 -105.386111)
			(xy 256.447671 -105.35366) (xy 256.497271 -105.328159) (xy 256.550055 -105.310152) (xy 256.604898 -105.300022)
			(xy 256.660632 -105.297985) (xy 256.716069 -105.304085) (xy 256.770026 -105.318191) (xy 256.821355 -105.340003)
			(xy 256.868961 -105.369057) (xy 256.911829 -105.404732) (xy 256.949046 -105.446269) (xy 256.979819 -105.492782)
			(xy 257.003491 -105.543279) (xy 257.019559 -105.596686) (xy 257.027679 -105.651862) (xy 257.028188 -105.679748)
			(xy 257.027679 -105.707634) (xy 257.019559 -105.76281) (xy 257.003491 -105.816217) (xy 256.979819 -105.866714)
			(xy 256.949046 -105.913227) (xy 256.911829 -105.954764) (xy 256.868961 -105.990439) (xy 256.821355 -106.019493)
			(xy 256.770026 -106.041305) (xy 256.716069 -106.055411) (xy 256.660632 -106.061511) (xy 256.604898 -106.059474)
			(xy 256.550055 -106.049344) (xy 256.497271 -106.031337) (xy 256.447671 -106.005836) (xy 256.402313 -105.973385)
			(xy 256.362164 -105.934676) (xy 256.328078 -105.890533) (xy 256.300782 -105.841898) (xy 256.280859 -105.789807)
			(xy 256.268733 -105.73537) (xy 256.264662 -105.679748) (xy 255.438606 -105.679748) (xy 255.424588 -105.685705)
			(xy 255.370631 -105.699811) (xy 255.315194 -105.705911) (xy 255.25946 -105.703874) (xy 255.204617 -105.693744)
			(xy 255.151833 -105.675737) (xy 255.102233 -105.650236) (xy 255.056875 -105.617785) (xy 255.016726 -105.579076)
			(xy 254.98264 -105.534933) (xy 254.955344 -105.486298) (xy 254.935421 -105.434207) (xy 254.923295 -105.37977)
			(xy 254.919224 -105.324148) (xy 253.639974 -105.324148) (xy 253.665131 -105.359293) (xy 253.69175 -105.41223)
			(xy 253.709859 -105.468647) (xy 253.719023 -105.527186) (xy 253.719584 -105.556812) (xy 253.719098 -105.584063)
			(xy 253.711342 -105.638011) (xy 253.695987 -105.690306) (xy 253.673345 -105.739883) (xy 253.643879 -105.785733)
			(xy 253.608188 -105.826924) (xy 253.566997 -105.862615) (xy 253.521147 -105.892081) (xy 253.47157 -105.914723)
			(xy 253.419275 -105.930078) (xy 253.365327 -105.937834) (xy 253.310825 -105.937834) (xy 253.256877 -105.930078)
			(xy 253.204582 -105.914723) (xy 253.155005 -105.892081) (xy 253.109155 -105.862615) (xy 253.067964 -105.826924)
			(xy 253.032273 -105.785733) (xy 253.002807 -105.739883) (xy 252.980165 -105.690306) (xy 252.96481 -105.638011)
			(xy 252.957054 -105.584063) (xy 252.956568 -105.556812) (xy 250.79706 -105.556812) (xy 250.79706 -105.79608)
			(xy 250.89739 -105.89641) (xy 250.914746 -105.914394) (xy 250.944151 -105.954806) (xy 250.966864 -105.999324)
			(xy 250.982325 -106.04685) (xy 250.990152 -106.096211) (xy 250.990608 -106.1212) (xy 250.990608 -106.419142)
			(xy 251.672598 -107.101386) (xy 251.683087 -107.111186) (xy 251.708216 -107.125038) (xy 251.736205 -107.131359)
			(xy 251.764847 -107.12965) (xy 251.791886 -107.120047) (xy 251.815189 -107.103305) (xy 251.83292 -107.080745)
			(xy 251.84368 -107.054146) (xy 251.845572 -107.039918) (xy 251.848449 -107.015785) (xy 251.859532 -106.968463)
			(xy 251.876518 -106.922925) (xy 251.887482 -106.901234) (xy 251.894193 -106.887296) (xy 251.89973 -106.856877)
			(xy 251.895914 -106.826194) (xy 251.883094 -106.798057) (xy 251.862444 -106.775044) (xy 251.835856 -106.759262)
			(xy 251.820934 -106.755184) (xy 251.793487 -106.748101) (xy 251.740907 -106.72693) (xy 251.692038 -106.698211)
			(xy 251.647956 -106.662579) (xy 251.609631 -106.620816) (xy 251.577907 -106.573842) (xy 251.553483 -106.522692)
			(xy 251.536896 -106.46849) (xy 251.52851 -106.412431) (xy 251.528072 -106.38409) (xy 251.528558 -106.356839)
			(xy 251.536314 -106.302891) (xy 251.551669 -106.250596) (xy 251.574311 -106.201019) (xy 251.603777 -106.155169)
			(xy 251.639468 -106.113978) (xy 251.680659 -106.078287) (xy 251.726509 -106.048821) (xy 251.776086 -106.026179)
			(xy 251.828381 -106.010824) (xy 251.882329 -106.003068) (xy 251.936831 -106.003068) (xy 251.990779 -106.010824)
			(xy 252.043074 -106.026179) (xy 252.092651 -106.048821) (xy 252.138501 -106.078287) (xy 252.179692 -106.113978)
			(xy 252.215383 -106.155169) (xy 252.244849 -106.201019) (xy 252.267491 -106.250596) (xy 252.282846 -106.302891)
			(xy 252.290602 -106.356839) (xy 252.291088 -106.38409) (xy 252.290476 -106.414892) (xy 252.281935 -106.467148)
			(xy 252.913132 -106.467148) (xy 252.917203 -106.411526) (xy 252.929329 -106.357089) (xy 252.949252 -106.304998)
			(xy 252.976548 -106.256363) (xy 253.010634 -106.21222) (xy 253.050783 -106.173511) (xy 253.096141 -106.14106)
			(xy 253.145741 -106.115559) (xy 253.198525 -106.097552) (xy 253.253368 -106.087422) (xy 253.309102 -106.085385)
			(xy 253.364539 -106.091485) (xy 253.418496 -106.105591) (xy 253.469825 -106.127403) (xy 253.517431 -106.156457)
			(xy 253.560299 -106.192132) (xy 253.597516 -106.233669) (xy 253.628289 -106.280182) (xy 253.651961 -106.330679)
			(xy 253.668029 -106.384086) (xy 253.676149 -106.439262) (xy 253.676658 -106.467148) (xy 253.676149 -106.495034)
			(xy 253.668029 -106.55021) (xy 253.651961 -106.603617) (xy 253.628289 -106.654114) (xy 253.597516 -106.700627)
			(xy 253.560299 -106.742164) (xy 253.517431 -106.777839) (xy 253.469825 -106.806893) (xy 253.440882 -106.819192)
			(xy 259.017768 -106.819192) (xy 259.021839 -106.76357) (xy 259.033965 -106.709133) (xy 259.053888 -106.657042)
			(xy 259.081184 -106.608407) (xy 259.11527 -106.564264) (xy 259.155419 -106.525555) (xy 259.200777 -106.493104)
			(xy 259.250377 -106.467603) (xy 259.303161 -106.449596) (xy 259.358004 -106.439466) (xy 259.413738 -106.437429)
			(xy 259.469175 -106.443529) (xy 259.523132 -106.457635) (xy 259.574461 -106.479447) (xy 259.622067 -106.508501)
			(xy 259.664935 -106.544176) (xy 259.702152 -106.585713) (xy 259.732925 -106.632226) (xy 259.756597 -106.682723)
			(xy 259.760516 -106.695748) (xy 262.742172 -106.695748) (xy 262.742672 -106.667008) (xy 262.751301 -106.61018)
			(xy 262.768357 -106.555289) (xy 262.793454 -106.503578) (xy 262.826023 -106.456216) (xy 262.845296 -106.43489)
			(xy 262.855318 -106.423317) (xy 262.868662 -106.395785) (xy 262.873254 -106.365535) (xy 262.868683 -106.335283)
			(xy 262.855358 -106.307741) (xy 262.845296 -106.296206) (xy 262.826011 -106.274891) (xy 262.793444 -106.227527)
			(xy 262.768354 -106.175812) (xy 262.751307 -106.120918) (xy 262.74269 -106.064088) (xy 262.742172 -106.035348)
			(xy 262.742658 -106.008097) (xy 262.750414 -105.954149) (xy 262.765769 -105.901854) (xy 262.788411 -105.852277)
			(xy 262.817877 -105.806427) (xy 262.853568 -105.765236) (xy 262.894759 -105.729545) (xy 262.940609 -105.700079)
			(xy 262.990186 -105.677437) (xy 263.042481 -105.662082) (xy 263.096429 -105.654326) (xy 263.150931 -105.654326)
			(xy 263.204879 -105.662082) (xy 263.257174 -105.677437) (xy 263.306751 -105.700079) (xy 263.352601 -105.729545)
			(xy 263.393792 -105.765236) (xy 263.429483 -105.806427) (xy 263.458949 -105.852277) (xy 263.481591 -105.901854)
			(xy 263.496946 -105.954149) (xy 263.504702 -106.008097) (xy 263.505188 -106.035348) (xy 263.504697 -106.064088)
			(xy 263.496067 -106.120917) (xy 263.479009 -106.175808) (xy 263.45391 -106.22752) (xy 263.421338 -106.27488)
			(xy 263.402064 -106.296206) (xy 263.391942 -106.307701) (xy 263.378601 -106.33526) (xy 263.374023 -106.365535)
			(xy 263.378622 -106.395807) (xy 263.391982 -106.423357) (xy 263.402064 -106.43489) (xy 263.421358 -106.456197)
			(xy 263.453921 -106.503565) (xy 263.479009 -106.555281) (xy 263.496054 -106.610176) (xy 263.504671 -106.667008)
			(xy 263.505188 -106.695748) (xy 263.504702 -106.722999) (xy 263.496946 -106.776947) (xy 263.481591 -106.829242)
			(xy 263.458949 -106.878819) (xy 263.429483 -106.924669) (xy 263.393792 -106.96586) (xy 263.352601 -107.001551)
			(xy 263.306751 -107.031017) (xy 263.257174 -107.053659) (xy 263.204879 -107.069014) (xy 263.150931 -107.07677)
			(xy 263.096429 -107.07677) (xy 263.042481 -107.069014) (xy 262.990186 -107.053659) (xy 262.940609 -107.031017)
			(xy 262.894759 -107.001551) (xy 262.853568 -106.96586) (xy 262.817877 -106.924669) (xy 262.788411 -106.878819)
			(xy 262.765769 -106.829242) (xy 262.750414 -106.776947) (xy 262.742658 -106.722999) (xy 262.742172 -106.695748)
			(xy 259.760516 -106.695748) (xy 259.772665 -106.73613) (xy 259.780785 -106.791306) (xy 259.781294 -106.819192)
			(xy 259.780785 -106.847078) (xy 259.772665 -106.902254) (xy 259.756597 -106.955661) (xy 259.732925 -107.006158)
			(xy 259.702152 -107.052671) (xy 259.664935 -107.094208) (xy 259.622067 -107.129883) (xy 259.574461 -107.158937)
			(xy 259.523132 -107.180749) (xy 259.469175 -107.194855) (xy 259.413738 -107.200955) (xy 259.358004 -107.198918)
			(xy 259.303161 -107.188788) (xy 259.250377 -107.170781) (xy 259.200777 -107.14528) (xy 259.155419 -107.112829)
			(xy 259.11527 -107.07412) (xy 259.081184 -107.029977) (xy 259.053888 -106.981342) (xy 259.033965 -106.929251)
			(xy 259.021839 -106.874814) (xy 259.017768 -106.819192) (xy 253.440882 -106.819192) (xy 253.418496 -106.828705)
			(xy 253.364539 -106.842811) (xy 253.309102 -106.848911) (xy 253.253368 -106.846874) (xy 253.198525 -106.836744)
			(xy 253.145741 -106.818737) (xy 253.096141 -106.793236) (xy 253.050783 -106.760785) (xy 253.010634 -106.722076)
			(xy 252.976548 -106.677933) (xy 252.949252 -106.629298) (xy 252.929329 -106.577207) (xy 252.917203 -106.52277)
			(xy 252.913132 -106.467148) (xy 252.281935 -106.467148) (xy 252.280539 -106.47569) (xy 252.260969 -106.534103)
			(xy 252.247146 -106.561636) (xy 252.240429 -106.575575) (xy 252.234882 -106.605999) (xy 252.238693 -106.636689)
			(xy 252.251513 -106.664833) (xy 252.272167 -106.687851) (xy 252.298763 -106.703634) (xy 252.313694 -106.707686)
			(xy 252.341137 -106.714771) (xy 252.393709 -106.735947) (xy 252.442569 -106.764668) (xy 252.486641 -106.800303)
			(xy 252.524956 -106.842067) (xy 252.556669 -106.88904) (xy 252.581082 -106.940189) (xy 252.597659 -106.994387)
			(xy 252.606033 -107.050442) (xy 252.606556 -107.07878) (xy 252.606063 -107.106811) (xy 252.59786 -107.162268)
			(xy 252.581629 -107.215929) (xy 252.557719 -107.266635) (xy 252.526644 -107.313296) (xy 252.489075 -107.354906)
			(xy 252.44582 -107.390569) (xy 252.397811 -107.419517) (xy 252.346082 -107.441127) (xy 252.291747 -107.454932)
			(xy 252.26391 -107.458256) (xy 252.249688 -107.460209) (xy 252.223083 -107.470961) (xy 252.200517 -107.488684)
			(xy 252.183766 -107.511983) (xy 252.174153 -107.53902) (xy 252.172435 -107.567663) (xy 252.178748 -107.595655)
			(xy 252.192593 -107.620789) (xy 252.202442 -107.63123) (xy 252.23724 -107.666028) (xy 255.402842 -107.666028)
			(xy 255.417417 -107.665551) (xy 255.445379 -107.65731) (xy 255.469876 -107.64151) (xy 255.488917 -107.619437)
			(xy 255.500952 -107.592887) (xy 255.505001 -107.564019) (xy 255.500736 -107.535182) (xy 255.495044 -107.521756)
			(xy 255.483882 -107.496483) (xy 255.468142 -107.443526) (xy 255.460201 -107.388852) (xy 255.459738 -107.361228)
			(xy 255.460224 -107.333977) (xy 255.46798 -107.280029) (xy 255.483335 -107.227734) (xy 255.505977 -107.178157)
			(xy 255.535443 -107.132307) (xy 255.571134 -107.091116) (xy 255.612325 -107.055425) (xy 255.658175 -107.025959)
			(xy 255.707752 -107.003317) (xy 255.760047 -106.987962) (xy 255.813995 -106.980206) (xy 255.868497 -106.980206)
			(xy 255.922445 -106.987962) (xy 255.97474 -107.003317) (xy 256.024317 -107.025959) (xy 256.070167 -107.055425)
			(xy 256.111358 -107.091116) (xy 256.147049 -107.132307) (xy 256.176515 -107.178157) (xy 256.199157 -107.227734)
			(xy 256.214512 -107.280029) (xy 256.222268 -107.333977) (xy 256.222754 -107.361228) (xy 256.222283 -107.388852)
			(xy 256.21435 -107.443526) (xy 256.198611 -107.496484) (xy 256.187448 -107.521756) (xy 256.18176 -107.535183)
			(xy 256.177495 -107.56402) (xy 256.181545 -107.592887) (xy 256.193579 -107.619437) (xy 256.212619 -107.64151)
			(xy 256.237115 -107.657311) (xy 256.265075 -107.665554) (xy 256.27965 -107.666028) (xy 263.58088 -107.666028)
			(xy 267.81252 -103.434388) (xy 269.064232 -103.434388) (xy 269.41907 -103.07955) (xy 269.437054 -103.062196)
			(xy 269.477467 -103.032795) (xy 269.521986 -103.010087) (xy 269.569512 -102.994633) (xy 269.618872 -102.986814)
			(xy 269.64386 -102.986332) (xy 274.44192 -102.986332) (xy 274.466903 -102.986845) (xy 274.516249 -102.994698)
			(xy 274.563763 -103.010161) (xy 274.608279 -103.032855) (xy 274.648705 -103.062223) (xy 274.66671 -103.07955)
			(xy 275.021548 -103.434388) (xy 275.5011 -103.434388) (xy 275.523198 -103.456232) (xy 276.562566 -103.456232)
			(xy 276.586145 -103.441187) (xy 276.636775 -103.417423) (xy 276.690335 -103.401313) (xy 276.745674 -103.393204)
			(xy 276.77364 -103.392732) (xy 276.800886 -103.393221) (xy 276.854824 -103.400981) (xy 276.907109 -103.416338)
			(xy 276.956676 -103.438979) (xy 277.002516 -103.468443) (xy 277.043697 -103.504131) (xy 277.079381 -103.545316)
			(xy 277.10884 -103.59116) (xy 277.131476 -103.640729) (xy 277.146827 -103.693015) (xy 277.154582 -103.746953)
			(xy 277.154582 -103.801447) (xy 277.146827 -103.855385) (xy 277.131476 -103.907671) (xy 277.10884 -103.95724)
			(xy 277.079381 -104.003084) (xy 277.043697 -104.044269) (xy 277.002516 -104.079957) (xy 276.956676 -104.109421)
			(xy 276.907109 -104.132062) (xy 276.854824 -104.147419) (xy 276.800886 -104.155179) (xy 276.77364 -104.155748)
			(xy 276.747437 -104.155316) (xy 276.695525 -104.148146) (xy 276.645083 -104.133934) (xy 276.597063 -104.11295)
			(xy 276.574504 -104.099614) (xy 276.562312 -104.092248) (xy 276.40407 -104.092248) (xy 276.389097 -104.092769)
			(xy 276.360435 -104.101444) (xy 276.335526 -104.118067) (xy 276.316516 -104.141205) (xy 276.305044 -104.168866)
			(xy 276.302096 -104.198667) (xy 276.307928 -104.228039) (xy 276.322036 -104.254453) (xy 276.332188 -104.265476)
			(xy 278.25954 -106.192828) (xy 309.210962 -106.192828) (xy 309.215033 -106.137206) (xy 309.227159 -106.082769)
			(xy 309.247082 -106.030678) (xy 309.274378 -105.982043) (xy 309.308464 -105.9379) (xy 309.348613 -105.899191)
			(xy 309.393971 -105.86674) (xy 309.443571 -105.841239) (xy 309.496355 -105.823232) (xy 309.551198 -105.813102)
			(xy 309.606932 -105.811065) (xy 309.662369 -105.817165) (xy 309.716326 -105.831271) (xy 309.767655 -105.853083)
			(xy 309.815261 -105.882137) (xy 309.858129 -105.917812) (xy 309.895346 -105.959349) (xy 309.926119 -106.005862)
			(xy 309.949791 -106.056359) (xy 309.965859 -106.109766) (xy 309.973979 -106.164942) (xy 309.974488 -106.192828)
			(xy 309.973979 -106.220714) (xy 309.965859 -106.27589) (xy 309.949791 -106.329297) (xy 309.926119 -106.379794)
			(xy 309.895346 -106.426307) (xy 309.858129 -106.467844) (xy 309.815261 -106.503519) (xy 309.767655 -106.532573)
			(xy 309.716326 -106.554385) (xy 309.662369 -106.568491) (xy 309.606932 -106.574591) (xy 309.551198 -106.572554)
			(xy 309.496355 -106.562424) (xy 309.443571 -106.544417) (xy 309.393971 -106.518916) (xy 309.348613 -106.486465)
			(xy 309.308464 -106.447756) (xy 309.274378 -106.403613) (xy 309.247082 -106.354978) (xy 309.227159 -106.302887)
			(xy 309.215033 -106.24845) (xy 309.210962 -106.192828) (xy 278.25954 -106.192828) (xy 279.577059 -107.510347)
			(xy 339.272926 -107.510347) (xy 339.272926 -107.455853) (xy 339.280681 -107.401914) (xy 339.296033 -107.349627)
			(xy 339.31867 -107.300058) (xy 339.348131 -107.254214) (xy 339.383816 -107.21303) (xy 339.424998 -107.177343)
			(xy 339.47084 -107.14788) (xy 339.520409 -107.12524) (xy 339.572694 -107.109885) (xy 339.626633 -107.102128)
			(xy 339.65388 -107.10164) (xy 339.68125 -107.102108) (xy 339.73543 -107.109924) (xy 339.787933 -107.125412)
			(xy 339.83768 -107.148254) (xy 339.883647 -107.177978) (xy 339.904578 -107.19562) (xy 339.915906 -107.204856)
			(xy 339.942463 -107.217032) (xy 339.97138 -107.221205) (xy 340.000297 -107.217032) (xy 340.026854 -107.204856)
			(xy 340.038182 -107.19562) (xy 340.059115 -107.177979) (xy 340.105083 -107.148255) (xy 340.154829 -107.125409)
			(xy 340.207331 -107.109913) (xy 340.261509 -107.102084) (xy 340.316251 -107.102084) (xy 340.370429 -107.109913)
			(xy 340.422931 -107.125409) (xy 340.472677 -107.148255) (xy 340.518645 -107.177979) (xy 340.539578 -107.19562)
			(xy 340.550906 -107.204856) (xy 340.577463 -107.217032) (xy 340.60638 -107.221205) (xy 340.635297 -107.217032)
			(xy 340.661854 -107.204856) (xy 340.673182 -107.19562) (xy 340.694115 -107.177979) (xy 340.740083 -107.148255)
			(xy 340.789829 -107.125409) (xy 340.842331 -107.109913) (xy 340.896509 -107.102084) (xy 340.951251 -107.102084)
			(xy 341.005429 -107.109913) (xy 341.057931 -107.125409) (xy 341.107677 -107.148255) (xy 341.153645 -107.177979)
			(xy 341.174578 -107.19562) (xy 341.185906 -107.204856) (xy 341.212463 -107.217032) (xy 341.24138 -107.221205)
			(xy 341.270297 -107.217032) (xy 341.296854 -107.204856) (xy 341.308182 -107.19562) (xy 341.329113 -107.177979)
			(xy 341.375085 -107.148267) (xy 341.424833 -107.125431) (xy 341.477334 -107.10994) (xy 341.531511 -107.102113)
			(xy 341.55888 -107.10164) (xy 341.586137 -107.102006) (xy 341.640097 -107.109761) (xy 341.692404 -107.125117)
			(xy 341.741993 -107.147762) (xy 341.747296 -107.15117) (xy 428.930814 -107.15117) (xy 428.934885 -107.095548)
			(xy 428.947011 -107.041111) (xy 428.966934 -106.98902) (xy 428.99423 -106.940385) (xy 429.028316 -106.896242)
			(xy 429.068465 -106.857533) (xy 429.113823 -106.825082) (xy 429.163423 -106.799581) (xy 429.216207 -106.781574)
			(xy 429.27105 -106.771444) (xy 429.326784 -106.769407) (xy 429.368344 -106.77398) (xy 433.340254 -106.77398)
			(xy 433.344325 -106.718358) (xy 433.356451 -106.663921) (xy 433.376374 -106.61183) (xy 433.40367 -106.563195)
			(xy 433.437756 -106.519052) (xy 433.477905 -106.480343) (xy 433.523263 -106.447892) (xy 433.572863 -106.422391)
			(xy 433.625647 -106.404384) (xy 433.68049 -106.394254) (xy 433.736224 -106.392217) (xy 433.791661 -106.398317)
			(xy 433.845618 -106.412423) (xy 433.896947 -106.434235) (xy 433.944553 -106.463289) (xy 433.987421 -106.498964)
			(xy 434.024638 -106.540501) (xy 434.055411 -106.587014) (xy 434.079083 -106.637511) (xy 434.095151 -106.690918)
			(xy 434.103271 -106.746094) (xy 434.10378 -106.77398) (xy 434.103271 -106.801866) (xy 434.095151 -106.857042)
			(xy 434.079083 -106.910449) (xy 434.055411 -106.960946) (xy 434.024638 -107.007459) (xy 433.987421 -107.048996)
			(xy 433.944553 -107.084671) (xy 433.896947 -107.113725) (xy 433.845618 -107.135537) (xy 433.791661 -107.149643)
			(xy 433.736224 -107.155743) (xy 433.68049 -107.153706) (xy 433.625647 -107.143576) (xy 433.572863 -107.125569)
			(xy 433.523263 -107.100068) (xy 433.477905 -107.067617) (xy 433.437756 -107.028908) (xy 433.40367 -106.984765)
			(xy 433.376374 -106.93613) (xy 433.356451 -106.884039) (xy 433.344325 -106.829602) (xy 433.340254 -106.77398)
			(xy 429.368344 -106.77398) (xy 429.382221 -106.775507) (xy 429.436178 -106.789613) (xy 429.487507 -106.811425)
			(xy 429.535113 -106.840479) (xy 429.577981 -106.876154) (xy 429.615198 -106.917691) (xy 429.645971 -106.964204)
			(xy 429.669643 -107.014701) (xy 429.685711 -107.068108) (xy 429.693831 -107.123284) (xy 429.69434 -107.15117)
			(xy 429.693831 -107.179056) (xy 429.685711 -107.234232) (xy 429.669643 -107.287639) (xy 429.669403 -107.28815)
			(xy 430.264576 -107.28815) (xy 430.264576 -107.23365) (xy 430.272331 -107.179705) (xy 430.287685 -107.127412)
			(xy 430.310324 -107.077836) (xy 430.339788 -107.031987) (xy 430.375476 -106.990798) (xy 430.416663 -106.955106)
			(xy 430.46251 -106.925639) (xy 430.512084 -106.902996) (xy 430.564375 -106.887638) (xy 430.61832 -106.879878)
			(xy 430.64557 -106.87939) (xy 430.672671 -106.879881) (xy 430.726329 -106.887549) (xy 430.778362 -106.902734)
			(xy 430.827721 -106.925132) (xy 430.873413 -106.95429) (xy 430.914517 -106.989622) (xy 430.950207 -107.030417)
			(xy 430.979764 -107.075852) (xy 431.002592 -107.125013) (xy 431.018231 -107.176911) (xy 431.026368 -107.2305)
			(xy 431.027078 -107.257596) (xy 431.027686 -107.271487) (xy 431.035494 -107.298161) (xy 431.050204 -107.321743)
			(xy 431.070727 -107.340486) (xy 431.095543 -107.353002) (xy 431.122814 -107.358364) (xy 431.150522 -107.356176)
			(xy 431.16373 -107.35183) (xy 431.195585 -107.340909) (xy 431.261888 -107.329156) (xy 431.295556 -107.328462)
			(xy 431.323565 -107.328982) (xy 431.378981 -107.337174) (xy 431.432602 -107.353388) (xy 431.483272 -107.377274)
			(xy 431.529901 -107.408318) (xy 431.571485 -107.445853) (xy 431.589688 -107.467146) (xy 431.598926 -107.477639)
			(xy 431.621933 -107.493507) (xy 431.648375 -107.50256) (xy 431.67628 -107.504124) (xy 431.703567 -107.498081)
			(xy 431.728203 -107.484883) (xy 431.74835 -107.465513) (xy 431.755804 -107.453684) (xy 431.770568 -107.429362)
			(xy 431.806195 -107.385002) (xy 431.848012 -107.346423) (xy 431.895094 -107.31448) (xy 431.946397 -107.289882)
			(xy 432.000784 -107.273174) (xy 432.057048 -107.264726) (xy 432.085496 -107.2642) (xy 432.11275 -107.264647)
			(xy 432.166702 -107.272404) (xy 432.219002 -107.28776) (xy 432.268583 -107.310402) (xy 432.314438 -107.339871)
			(xy 432.355632 -107.375565) (xy 432.391327 -107.416759) (xy 432.420796 -107.462613) (xy 432.443439 -107.512195)
			(xy 432.458795 -107.564494) (xy 432.466553 -107.618446) (xy 432.466553 -107.672954) (xy 432.458795 -107.726906)
			(xy 432.443439 -107.779205) (xy 432.420796 -107.828787) (xy 432.391327 -107.874641) (xy 432.355632 -107.915835)
			(xy 432.314438 -107.951529) (xy 432.268583 -107.980998) (xy 432.219002 -108.00364) (xy 432.166702 -108.018996)
			(xy 432.11275 -108.026753) (xy 432.085496 -108.027216) (xy 432.057485 -108.026737) (xy 432.002067 -108.018538)
			(xy 431.948445 -108.002317) (xy 431.897775 -107.978423) (xy 431.851147 -107.947371) (xy 431.809565 -107.909829)
			(xy 431.791364 -107.888532) (xy 431.782079 -107.87808) (xy 431.759086 -107.862198) (xy 431.732654 -107.853132)
			(xy 431.704753 -107.851559) (xy 431.677469 -107.857596) (xy 431.652837 -107.870793) (xy 431.632697 -107.890165)
			(xy 431.625248 -107.901994) (xy 431.610092 -107.926885) (xy 431.573457 -107.972201) (xy 431.530354 -108.011417)
			(xy 431.506376 -108.027978) (xy 431.495092 -108.03605) (xy 431.476923 -108.056997) (xy 431.46507 -108.082066)
			(xy 431.460412 -108.1094) (xy 431.463292 -108.136979) (xy 431.473497 -108.162762) (xy 431.490273 -108.184841)
			(xy 431.496663 -108.19003) (xy 434.248558 -108.19003) (xy 434.252629 -108.134408) (xy 434.264755 -108.079971)
			(xy 434.284678 -108.02788) (xy 434.311974 -107.979245) (xy 434.34606 -107.935102) (xy 434.386209 -107.896393)
			(xy 434.431567 -107.863942) (xy 434.481167 -107.838441) (xy 434.533951 -107.820434) (xy 434.588794 -107.810304)
			(xy 434.644528 -107.808267) (xy 434.699965 -107.814367) (xy 434.753922 -107.828473) (xy 434.805251 -107.850285)
			(xy 434.852857 -107.879339) (xy 434.895725 -107.915014) (xy 434.932942 -107.956551) (xy 434.963715 -108.003064)
			(xy 434.987387 -108.053561) (xy 435.003455 -108.106968) (xy 435.011575 -108.162144) (xy 435.012084 -108.19003)
			(xy 435.011575 -108.217916) (xy 435.003455 -108.273092) (xy 434.987387 -108.326499) (xy 434.963715 -108.376996)
			(xy 434.932942 -108.423509) (xy 434.895725 -108.465046) (xy 434.852857 -108.500721) (xy 434.805251 -108.529775)
			(xy 434.753922 -108.551587) (xy 434.699965 -108.565693) (xy 434.644528 -108.571793) (xy 434.588794 -108.569756)
			(xy 434.533951 -108.559626) (xy 434.481167 -108.541619) (xy 434.431567 -108.516118) (xy 434.386209 -108.483667)
			(xy 434.34606 -108.444958) (xy 434.311974 -108.400815) (xy 434.284678 -108.35218) (xy 434.264755 -108.300089)
			(xy 434.252629 -108.245652) (xy 434.248558 -108.19003) (xy 431.496663 -108.19003) (xy 431.501042 -108.193586)
			(xy 431.524051 -108.211729) (xy 431.564722 -108.253909) (xy 431.598468 -108.30181) (xy 431.624493 -108.354307)
			(xy 431.642188 -108.410166) (xy 431.651135 -108.468073) (xy 431.651664 -108.49737) (xy 431.651178 -108.524621)
			(xy 431.643422 -108.578569) (xy 431.628067 -108.630864) (xy 431.605425 -108.680441) (xy 431.575959 -108.726291)
			(xy 431.540268 -108.767482) (xy 431.499077 -108.803173) (xy 431.453227 -108.832639) (xy 431.40365 -108.855281)
			(xy 431.351355 -108.870636) (xy 431.297407 -108.878392) (xy 431.242905 -108.878392) (xy 431.188957 -108.870636)
			(xy 431.136662 -108.855281) (xy 431.087085 -108.832639) (xy 431.041235 -108.803173) (xy 431.000044 -108.767482)
			(xy 430.964353 -108.726291) (xy 430.934887 -108.680441) (xy 430.912245 -108.630864) (xy 430.89689 -108.578569)
			(xy 430.889134 -108.524621) (xy 430.888648 -108.49737) (xy 430.889057 -108.470502) (xy 430.89659 -108.417297)
			(xy 430.911516 -108.365675) (xy 430.933541 -108.31666) (xy 430.962227 -108.271222) (xy 430.997007 -108.23026)
			(xy 431.037192 -108.194585) (xy 431.059336 -108.179362) (xy 431.070676 -108.171363) (xy 431.088845 -108.1504)
			(xy 431.100694 -108.125315) (xy 431.105344 -108.097966) (xy 431.102454 -108.070376) (xy 431.092236 -108.044584)
			(xy 431.075446 -108.022501) (xy 431.06467 -108.013754) (xy 431.041903 -107.995752) (xy 431.001562 -107.954029)
			(xy 430.968 -107.906679) (xy 430.941992 -107.854796) (xy 430.924137 -107.799573) (xy 430.914846 -107.742285)
			(xy 430.914048 -107.713272) (xy 430.913351 -107.699387) (xy 430.905561 -107.672718) (xy 430.890868 -107.649138)
			(xy 430.87036 -107.630394) (xy 430.845557 -107.617875) (xy 430.818297 -107.61251) (xy 430.7906 -107.614695)
			(xy 430.777396 -107.619038) (xy 430.745539 -107.629955) (xy 430.679238 -107.64171) (xy 430.64557 -107.642406)
			(xy 430.61832 -107.641922) (xy 430.564375 -107.634162) (xy 430.512084 -107.618804) (xy 430.46251 -107.596161)
			(xy 430.416663 -107.566694) (xy 430.375476 -107.531002) (xy 430.339788 -107.489813) (xy 430.310324 -107.443964)
			(xy 430.287685 -107.394388) (xy 430.272331 -107.342095) (xy 430.264576 -107.28815) (xy 429.669403 -107.28815)
			(xy 429.645971 -107.338136) (xy 429.615198 -107.384649) (xy 429.577981 -107.426186) (xy 429.535113 -107.461861)
			(xy 429.487507 -107.490915) (xy 429.436178 -107.512727) (xy 429.382221 -107.526833) (xy 429.326784 -107.532933)
			(xy 429.27105 -107.530896) (xy 429.216207 -107.520766) (xy 429.163423 -107.502759) (xy 429.113823 -107.477258)
			(xy 429.068465 -107.444807) (xy 429.028316 -107.406098) (xy 428.99423 -107.361955) (xy 428.966934 -107.31332)
			(xy 428.947011 -107.261229) (xy 428.934885 -107.206792) (xy 428.930814 -107.15117) (xy 341.747296 -107.15117)
			(xy 341.787854 -107.177233) (xy 341.829055 -107.212931) (xy 341.864755 -107.25413) (xy 341.894229 -107.299989)
			(xy 341.916876 -107.349577) (xy 341.932235 -107.401883) (xy 341.939993 -107.455843) (xy 341.939993 -107.510357)
			(xy 341.932235 -107.564317) (xy 341.916876 -107.616623) (xy 341.894229 -107.666211) (xy 341.864755 -107.71207)
			(xy 341.829055 -107.753269) (xy 341.787854 -107.788967) (xy 341.741993 -107.818438) (xy 341.692404 -107.841083)
			(xy 341.640097 -107.856439) (xy 341.586137 -107.864194) (xy 341.55888 -107.864656) (xy 341.531509 -107.864212)
			(xy 341.477328 -107.856391) (xy 341.424825 -107.840897) (xy 341.375078 -107.81805) (xy 341.329113 -107.78832)
			(xy 341.308182 -107.770676) (xy 341.296854 -107.76144) (xy 341.270297 -107.749264) (xy 341.24138 -107.745091)
			(xy 341.212463 -107.749264) (xy 341.185906 -107.76144) (xy 341.174578 -107.770676) (xy 341.153645 -107.788317)
			(xy 341.107677 -107.818041) (xy 341.057931 -107.840887) (xy 341.005429 -107.856383) (xy 340.951251 -107.864212)
			(xy 340.896509 -107.864212) (xy 340.842331 -107.856383) (xy 340.789829 -107.840887) (xy 340.740083 -107.818041)
			(xy 340.694115 -107.788317) (xy 340.673182 -107.770676) (xy 340.661854 -107.76144) (xy 340.635297 -107.749264)
			(xy 340.60638 -107.745091) (xy 340.577463 -107.749264) (xy 340.550906 -107.76144) (xy 340.539578 -107.770676)
			(xy 340.518645 -107.788317) (xy 340.472677 -107.818041) (xy 340.422931 -107.840887) (xy 340.370429 -107.856383)
			(xy 340.316251 -107.864212) (xy 340.261509 -107.864212) (xy 340.207331 -107.856383) (xy 340.154829 -107.840887)
			(xy 340.105083 -107.818041) (xy 340.059115 -107.788317) (xy 340.038182 -107.770676) (xy 340.026854 -107.76144)
			(xy 340.000297 -107.749264) (xy 339.97138 -107.745091) (xy 339.942463 -107.749264) (xy 339.915906 -107.76144)
			(xy 339.904578 -107.770676) (xy 339.883624 -107.788288) (xy 339.837658 -107.818005) (xy 339.787916 -107.840846)
			(xy 339.73542 -107.856344) (xy 339.681248 -107.864179) (xy 339.65388 -107.864656) (xy 339.626633 -107.864072)
			(xy 339.572694 -107.856315) (xy 339.520409 -107.84096) (xy 339.47084 -107.81832) (xy 339.424998 -107.788857)
			(xy 339.383816 -107.75317) (xy 339.348131 -107.711986) (xy 339.31867 -107.666142) (xy 339.296033 -107.616573)
			(xy 339.280681 -107.564286) (xy 339.272926 -107.510347) (xy 279.577059 -107.510347) (xy 280.409396 -108.342684)
			(xy 369.63934 -108.342684) (xy 369.643411 -108.287062) (xy 369.655537 -108.232625) (xy 369.67546 -108.180534)
			(xy 369.702756 -108.131899) (xy 369.736842 -108.087756) (xy 369.776991 -108.049047) (xy 369.822349 -108.016596)
			(xy 369.871949 -107.991095) (xy 369.924733 -107.973088) (xy 369.979576 -107.962958) (xy 370.03531 -107.960921)
			(xy 370.090747 -107.967021) (xy 370.144704 -107.981127) (xy 370.196033 -108.002939) (xy 370.243639 -108.031993)
			(xy 370.286507 -108.067668) (xy 370.323724 -108.109205) (xy 370.354497 -108.155718) (xy 370.378169 -108.206215)
			(xy 370.394237 -108.259622) (xy 370.402357 -108.314798) (xy 370.402866 -108.342684) (xy 370.402357 -108.37057)
			(xy 370.394237 -108.425746) (xy 370.378169 -108.479153) (xy 370.354497 -108.52965) (xy 370.323724 -108.576163)
			(xy 370.286507 -108.6177) (xy 370.2695 -108.631853) (xy 376.759436 -108.631853) (xy 376.759436 -108.577347)
			(xy 376.767192 -108.523396) (xy 376.782548 -108.471098) (xy 376.805189 -108.421517) (xy 376.834656 -108.375663)
			(xy 376.870348 -108.334469) (xy 376.911539 -108.298774) (xy 376.957391 -108.269304) (xy 377.00697 -108.246658)
			(xy 377.059267 -108.231299) (xy 377.113217 -108.223538) (xy 377.14047 -108.22305) (xy 377.166086 -108.223483)
			(xy 377.216856 -108.23034) (xy 377.266251 -108.243935) (xy 377.31338 -108.264022) (xy 377.357394 -108.290241)
			(xy 377.377706 -108.305854) (xy 377.389521 -108.314693) (xy 377.41688 -108.325718) (xy 377.446248 -108.32847)
			(xy 377.475179 -108.32272) (xy 377.501264 -108.308948) (xy 377.522328 -108.288299) (xy 377.536619 -108.262495)
			(xy 377.540266 -108.248196) (xy 377.549303 -108.20954) (xy 377.574397 -108.13422) (xy 377.607181 -108.061915)
			(xy 377.647302 -107.993408) (xy 377.694324 -107.929442) (xy 377.747739 -107.870708) (xy 377.806969 -107.817843)
			(xy 377.871371 -107.771419) (xy 377.940249 -107.731939) (xy 378.012856 -107.69983) (xy 378.088407 -107.675441)
			(xy 378.166084 -107.659034) (xy 378.245045 -107.650788) (xy 378.28474 -107.65028) (xy 378.323383 -107.650795)
			(xy 378.400273 -107.658618) (xy 378.475977 -107.674179) (xy 378.549718 -107.697319) (xy 378.62074 -107.7278)
			(xy 378.688314 -107.76531) (xy 378.751747 -107.809463) (xy 378.810387 -107.859807) (xy 378.863634 -107.915826)
			(xy 378.91094 -107.976943) (xy 378.95182 -108.042533) (xy 378.985856 -108.111921) (xy 379.012697 -108.184398)
			(xy 379.032069 -108.259217) (xy 379.043772 -108.335613) (xy 379.047686 -108.4128) (xy 379.043772 -108.489987)
			(xy 379.032069 -108.566383) (xy 379.012697 -108.641202) (xy 378.985856 -108.713679) (xy 378.95182 -108.783067)
			(xy 378.91094 -108.848657) (xy 378.863634 -108.909774) (xy 378.810387 -108.965793) (xy 378.751747 -109.016137)
			(xy 378.688314 -109.06029) (xy 378.62074 -109.0978) (xy 378.549718 -109.128281) (xy 378.475977 -109.151421)
			(xy 378.400273 -109.166982) (xy 378.323383 -109.174805) (xy 378.28474 -109.175296) (xy 378.245796 -109.17479)
			(xy 378.168314 -109.166854) (xy 378.092044 -109.151059) (xy 378.017783 -109.127571) (xy 377.946303 -109.096635)
			(xy 377.878349 -109.058572) (xy 377.81463 -109.01378) (xy 377.755809 -108.962725) (xy 377.7025 -108.905939)
			(xy 377.655258 -108.844014) (xy 377.6345 -108.81106) (xy 377.626364 -108.798795) (xy 377.604471 -108.779146)
			(xy 377.577885 -108.766551) (xy 377.548813 -108.762055) (xy 377.519665 -108.766031) (xy 377.492859 -108.778148)
			(xy 377.470618 -108.797403) (xy 377.462288 -108.809536) (xy 377.447159 -108.832342) (xy 377.411458 -108.873819)
			(xy 377.370199 -108.909771) (xy 377.324227 -108.939462) (xy 377.274486 -108.962282) (xy 377.221996 -108.977764)
			(xy 377.167833 -108.985591) (xy 377.14047 -108.986066) (xy 377.113217 -108.985662) (xy 377.059267 -108.977901)
			(xy 377.00697 -108.962542) (xy 376.957391 -108.939896) (xy 376.911539 -108.910426) (xy 376.870348 -108.874731)
			(xy 376.834656 -108.833537) (xy 376.805189 -108.787683) (xy 376.782548 -108.738102) (xy 376.767192 -108.685804)
			(xy 376.759436 -108.631853) (xy 370.2695 -108.631853) (xy 370.243639 -108.653375) (xy 370.196033 -108.682429)
			(xy 370.144704 -108.704241) (xy 370.090747 -108.718347) (xy 370.03531 -108.724447) (xy 369.979576 -108.72241)
			(xy 369.924733 -108.71228) (xy 369.871949 -108.694273) (xy 369.822349 -108.668772) (xy 369.776991 -108.636321)
			(xy 369.736842 -108.597612) (xy 369.702756 -108.553469) (xy 369.67546 -108.504834) (xy 369.655537 -108.452743)
			(xy 369.643411 -108.398306) (xy 369.63934 -108.342684) (xy 280.409396 -108.342684) (xy 281.12466 -109.057948)
			(xy 322.840602 -109.057948) (xy 322.844673 -109.002326) (xy 322.856799 -108.947889) (xy 322.876722 -108.895798)
			(xy 322.904018 -108.847163) (xy 322.938104 -108.80302) (xy 322.978253 -108.764311) (xy 323.023611 -108.73186)
			(xy 323.073211 -108.706359) (xy 323.125995 -108.688352) (xy 323.180838 -108.678222) (xy 323.236572 -108.676185)
			(xy 323.292009 -108.682285) (xy 323.345966 -108.696391) (xy 323.397295 -108.718203) (xy 323.444901 -108.747257)
			(xy 323.487769 -108.782932) (xy 323.524986 -108.824469) (xy 323.555759 -108.870982) (xy 323.579431 -108.921479)
			(xy 323.595499 -108.974886) (xy 323.603619 -109.030062) (xy 323.604128 -109.057948) (xy 325.809862 -109.057948)
			(xy 325.813933 -109.002326) (xy 325.826059 -108.947889) (xy 325.845982 -108.895798) (xy 325.873278 -108.847163)
			(xy 325.907364 -108.80302) (xy 325.947513 -108.764311) (xy 325.992871 -108.73186) (xy 326.042471 -108.706359)
			(xy 326.095255 -108.688352) (xy 326.150098 -108.678222) (xy 326.205832 -108.676185) (xy 326.261269 -108.682285)
			(xy 326.315226 -108.696391) (xy 326.366555 -108.718203) (xy 326.414161 -108.747257) (xy 326.457029 -108.782932)
			(xy 326.494246 -108.824469) (xy 326.525019 -108.870982) (xy 326.548691 -108.921479) (xy 326.564759 -108.974886)
			(xy 326.572834 -109.029754) (xy 372.985536 -109.029754) (xy 372.989607 -108.974132) (xy 373.001733 -108.919695)
			(xy 373.021656 -108.867604) (xy 373.048952 -108.818969) (xy 373.083038 -108.774826) (xy 373.123187 -108.736117)
			(xy 373.168545 -108.703666) (xy 373.218145 -108.678165) (xy 373.270929 -108.660158) (xy 373.325772 -108.650028)
			(xy 373.381506 -108.647991) (xy 373.436943 -108.654091) (xy 373.4909 -108.668197) (xy 373.542229 -108.690009)
			(xy 373.589835 -108.719063) (xy 373.632703 -108.754738) (xy 373.66992 -108.796275) (xy 373.700693 -108.842788)
			(xy 373.724365 -108.893285) (xy 373.740433 -108.946692) (xy 373.748553 -109.001868) (xy 373.749062 -109.029754)
			(xy 373.748553 -109.05764) (xy 373.740433 -109.112816) (xy 373.724365 -109.166223) (xy 373.700693 -109.21672)
			(xy 373.66992 -109.263233) (xy 373.632703 -109.30477) (xy 373.589835 -109.340445) (xy 373.542229 -109.369499)
			(xy 373.4909 -109.391311) (xy 373.436943 -109.405417) (xy 373.381506 -109.411517) (xy 373.325772 -109.40948)
			(xy 373.270929 -109.39935) (xy 373.218145 -109.381343) (xy 373.168545 -109.355842) (xy 373.123187 -109.323391)
			(xy 373.083038 -109.284682) (xy 373.048952 -109.240539) (xy 373.021656 -109.191904) (xy 373.001733 -109.139813)
			(xy 372.989607 -109.085376) (xy 372.985536 -109.029754) (xy 326.572834 -109.029754) (xy 326.572879 -109.030062)
			(xy 326.573388 -109.057948) (xy 326.572879 -109.085834) (xy 326.564759 -109.14101) (xy 326.548691 -109.194417)
			(xy 326.525019 -109.244914) (xy 326.494246 -109.291427) (xy 326.457029 -109.332964) (xy 326.414161 -109.368639)
			(xy 326.366555 -109.397693) (xy 326.315226 -109.419505) (xy 326.261269 -109.433611) (xy 326.205832 -109.439711)
			(xy 326.150098 -109.437674) (xy 326.095255 -109.427544) (xy 326.042471 -109.409537) (xy 325.992871 -109.384036)
			(xy 325.947513 -109.351585) (xy 325.907364 -109.312876) (xy 325.873278 -109.268733) (xy 325.845982 -109.220098)
			(xy 325.826059 -109.168007) (xy 325.813933 -109.11357) (xy 325.809862 -109.057948) (xy 323.604128 -109.057948)
			(xy 323.603619 -109.085834) (xy 323.595499 -109.14101) (xy 323.579431 -109.194417) (xy 323.555759 -109.244914)
			(xy 323.524986 -109.291427) (xy 323.487769 -109.332964) (xy 323.444901 -109.368639) (xy 323.397295 -109.397693)
			(xy 323.345966 -109.419505) (xy 323.292009 -109.433611) (xy 323.236572 -109.439711) (xy 323.180838 -109.437674)
			(xy 323.125995 -109.427544) (xy 323.073211 -109.409537) (xy 323.023611 -109.384036) (xy 322.978253 -109.351585)
			(xy 322.938104 -109.312876) (xy 322.904018 -109.268733) (xy 322.876722 -109.220098) (xy 322.856799 -109.168007)
			(xy 322.844673 -109.11357) (xy 322.840602 -109.057948) (xy 281.12466 -109.057948) (xy 281.729942 -109.66323)
			(xy 433.334158 -109.66323) (xy 433.338229 -109.607608) (xy 433.350355 -109.553171) (xy 433.370278 -109.50108)
			(xy 433.397574 -109.452445) (xy 433.43166 -109.408302) (xy 433.471809 -109.369593) (xy 433.517167 -109.337142)
			(xy 433.566767 -109.311641) (xy 433.619551 -109.293634) (xy 433.674394 -109.283504) (xy 433.730128 -109.281467)
			(xy 433.785565 -109.287567) (xy 433.839522 -109.301673) (xy 433.890851 -109.323485) (xy 433.938457 -109.352539)
			(xy 433.981325 -109.388214) (xy 434.018542 -109.429751) (xy 434.049315 -109.476264) (xy 434.072987 -109.526761)
			(xy 434.089055 -109.580168) (xy 434.097175 -109.635344) (xy 434.097684 -109.66323) (xy 434.097175 -109.691116)
			(xy 434.089055 -109.746292) (xy 434.072987 -109.799699) (xy 434.049315 -109.850196) (xy 434.018542 -109.896709)
			(xy 433.981325 -109.938246) (xy 433.938457 -109.973921) (xy 433.890851 -110.002975) (xy 433.839522 -110.024787)
			(xy 433.785565 -110.038893) (xy 433.730128 -110.044993) (xy 433.674394 -110.042956) (xy 433.619551 -110.032826)
			(xy 433.566767 -110.014819) (xy 433.517167 -109.989318) (xy 433.471809 -109.956867) (xy 433.43166 -109.918158)
			(xy 433.397574 -109.874015) (xy 433.370278 -109.82538) (xy 433.350355 -109.773289) (xy 433.338229 -109.718852)
			(xy 433.334158 -109.66323) (xy 281.729942 -109.66323) (xy 282.39466 -110.327948) (xy 318.697862 -110.327948)
			(xy 318.701933 -110.272326) (xy 318.714059 -110.217889) (xy 318.733982 -110.165798) (xy 318.761278 -110.117163)
			(xy 318.795364 -110.07302) (xy 318.835513 -110.034311) (xy 318.880871 -110.00186) (xy 318.930471 -109.976359)
			(xy 318.983255 -109.958352) (xy 319.038098 -109.948222) (xy 319.093832 -109.946185) (xy 319.149269 -109.952285)
			(xy 319.203226 -109.966391) (xy 319.254555 -109.988203) (xy 319.302161 -110.017257) (xy 319.345029 -110.052932)
			(xy 319.382246 -110.094469) (xy 319.413019 -110.140982) (xy 319.436691 -110.191479) (xy 319.452759 -110.244886)
			(xy 319.460879 -110.300062) (xy 319.461388 -110.327948) (xy 322.761862 -110.327948) (xy 322.765933 -110.272326)
			(xy 322.778059 -110.217889) (xy 322.797982 -110.165798) (xy 322.825278 -110.117163) (xy 322.859364 -110.07302)
			(xy 322.899513 -110.034311) (xy 322.944871 -110.00186) (xy 322.994471 -109.976359) (xy 323.047255 -109.958352)
			(xy 323.102098 -109.948222) (xy 323.157832 -109.946185) (xy 323.213269 -109.952285) (xy 323.267226 -109.966391)
			(xy 323.318555 -109.988203) (xy 323.366161 -110.017257) (xy 323.409029 -110.052932) (xy 323.446246 -110.094469)
			(xy 323.477019 -110.140982) (xy 323.500691 -110.191479) (xy 323.516759 -110.244886) (xy 323.524879 -110.300062)
			(xy 323.525388 -110.327948) (xy 324.806562 -110.327948) (xy 324.810633 -110.272326) (xy 324.822759 -110.217889)
			(xy 324.842682 -110.165798) (xy 324.869978 -110.117163) (xy 324.904064 -110.07302) (xy 324.944213 -110.034311)
			(xy 324.989571 -110.00186) (xy 325.039171 -109.976359) (xy 325.091955 -109.958352) (xy 325.146798 -109.948222)
			(xy 325.202532 -109.946185) (xy 325.257969 -109.952285) (xy 325.311926 -109.966391) (xy 325.363255 -109.988203)
			(xy 325.410861 -110.017257) (xy 325.453729 -110.052932) (xy 325.490946 -110.094469) (xy 325.521719 -110.140982)
			(xy 325.545391 -110.191479) (xy 325.561459 -110.244886) (xy 325.569579 -110.300062) (xy 325.570088 -110.327948)
			(xy 325.569579 -110.355834) (xy 325.566954 -110.373668) (xy 372.926862 -110.373668) (xy 372.930933 -110.318046)
			(xy 372.943059 -110.263609) (xy 372.962982 -110.211518) (xy 372.990278 -110.162883) (xy 373.024364 -110.11874)
			(xy 373.064513 -110.080031) (xy 373.109871 -110.04758) (xy 373.159471 -110.022079) (xy 373.212255 -110.004072)
			(xy 373.267098 -109.993942) (xy 373.322832 -109.991905) (xy 373.378269 -109.998005) (xy 373.432226 -110.012111)
			(xy 373.483555 -110.033923) (xy 373.531161 -110.062977) (xy 373.574029 -110.098652) (xy 373.611246 -110.140189)
			(xy 373.642019 -110.186702) (xy 373.665691 -110.237199) (xy 373.678856 -110.280958) (xy 417.983922 -110.280958)
			(xy 417.987993 -110.225336) (xy 418.000119 -110.170899) (xy 418.020042 -110.118808) (xy 418.047338 -110.070173)
			(xy 418.081424 -110.02603) (xy 418.121573 -109.987321) (xy 418.166931 -109.95487) (xy 418.216531 -109.929369)
			(xy 418.269315 -109.911362) (xy 418.324158 -109.901232) (xy 418.379892 -109.899195) (xy 418.435329 -109.905295)
			(xy 418.489286 -109.919401) (xy 418.540615 -109.941213) (xy 418.588221 -109.970267) (xy 418.631089 -110.005942)
			(xy 418.668306 -110.047479) (xy 418.699079 -110.093992) (xy 418.722751 -110.144489) (xy 418.738819 -110.197896)
			(xy 418.746939 -110.253072) (xy 418.747448 -110.280958) (xy 419.761922 -110.280958) (xy 419.765993 -110.225336)
			(xy 419.778119 -110.170899) (xy 419.798042 -110.118808) (xy 419.825338 -110.070173) (xy 419.859424 -110.02603)
			(xy 419.899573 -109.987321) (xy 419.944931 -109.95487) (xy 419.994531 -109.929369) (xy 420.047315 -109.911362)
			(xy 420.102158 -109.901232) (xy 420.157892 -109.899195) (xy 420.213329 -109.905295) (xy 420.267286 -109.919401)
			(xy 420.318615 -109.941213) (xy 420.366221 -109.970267) (xy 420.409089 -110.005942) (xy 420.446306 -110.047479)
			(xy 420.477079 -110.093992) (xy 420.500751 -110.144489) (xy 420.516819 -110.197896) (xy 420.524939 -110.253072)
			(xy 420.525448 -110.280958) (xy 421.539922 -110.280958) (xy 421.543993 -110.225336) (xy 421.556119 -110.170899)
			(xy 421.576042 -110.118808) (xy 421.603338 -110.070173) (xy 421.637424 -110.02603) (xy 421.677573 -109.987321)
			(xy 421.722931 -109.95487) (xy 421.772531 -109.929369) (xy 421.825315 -109.911362) (xy 421.880158 -109.901232)
			(xy 421.935892 -109.899195) (xy 421.991329 -109.905295) (xy 422.045286 -109.919401) (xy 422.096615 -109.941213)
			(xy 422.144221 -109.970267) (xy 422.187089 -110.005942) (xy 422.224306 -110.047479) (xy 422.255079 -110.093992)
			(xy 422.278751 -110.144489) (xy 422.294819 -110.197896) (xy 422.302939 -110.253072) (xy 422.303369 -110.27664)
			(xy 427.901098 -110.27664) (xy 427.905169 -110.221018) (xy 427.917295 -110.166581) (xy 427.937218 -110.11449)
			(xy 427.964514 -110.065855) (xy 427.9986 -110.021712) (xy 428.038749 -109.983003) (xy 428.084107 -109.950552)
			(xy 428.133707 -109.925051) (xy 428.186491 -109.907044) (xy 428.241334 -109.896914) (xy 428.297068 -109.894877)
			(xy 428.352505 -109.900977) (xy 428.406462 -109.915083) (xy 428.457791 -109.936895) (xy 428.505397 -109.965949)
			(xy 428.548265 -110.001624) (xy 428.585482 -110.043161) (xy 428.616255 -110.089674) (xy 428.639927 -110.140171)
			(xy 428.642394 -110.14837) (xy 430.710338 -110.14837) (xy 430.714409 -110.092748) (xy 430.726535 -110.038311)
			(xy 430.746458 -109.98622) (xy 430.773754 -109.937585) (xy 430.80784 -109.893442) (xy 430.847989 -109.854733)
			(xy 430.893347 -109.822282) (xy 430.942947 -109.796781) (xy 430.995731 -109.778774) (xy 431.050574 -109.768644)
			(xy 431.106308 -109.766607) (xy 431.161745 -109.772707) (xy 431.215702 -109.786813) (xy 431.267031 -109.808625)
			(xy 431.314637 -109.837679) (xy 431.357505 -109.873354) (xy 431.394722 -109.914891) (xy 431.425495 -109.961404)
			(xy 431.449167 -110.011901) (xy 431.465235 -110.065308) (xy 431.473355 -110.120484) (xy 431.473841 -110.1471)
			(xy 431.703478 -110.1471) (xy 431.707549 -110.091478) (xy 431.719675 -110.037041) (xy 431.739598 -109.98495)
			(xy 431.766894 -109.936315) (xy 431.80098 -109.892172) (xy 431.841129 -109.853463) (xy 431.886487 -109.821012)
			(xy 431.936087 -109.795511) (xy 431.988871 -109.777504) (xy 432.043714 -109.767374) (xy 432.099448 -109.765337)
			(xy 432.154885 -109.771437) (xy 432.208842 -109.785543) (xy 432.260171 -109.807355) (xy 432.307777 -109.836409)
			(xy 432.350645 -109.872084) (xy 432.387862 -109.913621) (xy 432.418635 -109.960134) (xy 432.442307 -110.010631)
			(xy 432.458375 -110.064038) (xy 432.466495 -110.119214) (xy 432.467004 -110.1471) (xy 432.592478 -110.1471)
			(xy 432.596549 -110.091478) (xy 432.608675 -110.037041) (xy 432.628598 -109.98495) (xy 432.655894 -109.936315)
			(xy 432.68998 -109.892172) (xy 432.730129 -109.853463) (xy 432.775487 -109.821012) (xy 432.825087 -109.795511)
			(xy 432.877871 -109.777504) (xy 432.932714 -109.767374) (xy 432.988448 -109.765337) (xy 433.043885 -109.771437)
			(xy 433.097842 -109.785543) (xy 433.149171 -109.807355) (xy 433.196777 -109.836409) (xy 433.239645 -109.872084)
			(xy 433.276862 -109.913621) (xy 433.307635 -109.960134) (xy 433.331307 -110.010631) (xy 433.347375 -110.064038)
			(xy 433.355495 -110.119214) (xy 433.356004 -110.1471) (xy 433.355495 -110.174986) (xy 433.347375 -110.230162)
			(xy 433.331307 -110.283569) (xy 433.307635 -110.334066) (xy 433.276862 -110.380579) (xy 433.239645 -110.422116)
			(xy 433.196777 -110.457791) (xy 433.149171 -110.486845) (xy 433.097842 -110.508657) (xy 433.043885 -110.522763)
			(xy 432.988448 -110.528863) (xy 432.932714 -110.526826) (xy 432.877871 -110.516696) (xy 432.825087 -110.498689)
			(xy 432.775487 -110.473188) (xy 432.730129 -110.440737) (xy 432.68998 -110.402028) (xy 432.655894 -110.357885)
			(xy 432.628598 -110.30925) (xy 432.608675 -110.257159) (xy 432.596549 -110.202722) (xy 432.592478 -110.1471)
			(xy 432.467004 -110.1471) (xy 432.466495 -110.174986) (xy 432.458375 -110.230162) (xy 432.442307 -110.283569)
			(xy 432.418635 -110.334066) (xy 432.387862 -110.380579) (xy 432.350645 -110.422116) (xy 432.307777 -110.457791)
			(xy 432.260171 -110.486845) (xy 432.208842 -110.508657) (xy 432.154885 -110.522763) (xy 432.099448 -110.528863)
			(xy 432.043714 -110.526826) (xy 431.988871 -110.516696) (xy 431.936087 -110.498689) (xy 431.886487 -110.473188)
			(xy 431.841129 -110.440737) (xy 431.80098 -110.402028) (xy 431.766894 -110.357885) (xy 431.739598 -110.30925)
			(xy 431.719675 -110.257159) (xy 431.707549 -110.202722) (xy 431.703478 -110.1471) (xy 431.473841 -110.1471)
			(xy 431.473864 -110.14837) (xy 431.473355 -110.176256) (xy 431.465235 -110.231432) (xy 431.449167 -110.284839)
			(xy 431.425495 -110.335336) (xy 431.394722 -110.381849) (xy 431.357505 -110.423386) (xy 431.314637 -110.459061)
			(xy 431.267031 -110.488115) (xy 431.215702 -110.509927) (xy 431.161745 -110.524033) (xy 431.106308 -110.530133)
			(xy 431.050574 -110.528096) (xy 430.995731 -110.517966) (xy 430.942947 -110.499959) (xy 430.893347 -110.474458)
			(xy 430.847989 -110.442007) (xy 430.80784 -110.403298) (xy 430.773754 -110.359155) (xy 430.746458 -110.31052)
			(xy 430.726535 -110.258429) (xy 430.714409 -110.203992) (xy 430.710338 -110.14837) (xy 428.642394 -110.14837)
			(xy 428.655995 -110.193578) (xy 428.664115 -110.248754) (xy 428.664624 -110.27664) (xy 428.664115 -110.304526)
			(xy 428.655995 -110.359702) (xy 428.639927 -110.413109) (xy 428.616255 -110.463606) (xy 428.585482 -110.510119)
			(xy 428.548265 -110.551656) (xy 428.505397 -110.587331) (xy 428.457791 -110.616385) (xy 428.406462 -110.638197)
			(xy 428.352505 -110.652303) (xy 428.297068 -110.658403) (xy 428.241334 -110.656366) (xy 428.186491 -110.646236)
			(xy 428.133707 -110.628229) (xy 428.084107 -110.602728) (xy 428.038749 -110.570277) (xy 427.9986 -110.531568)
			(xy 427.964514 -110.487425) (xy 427.937218 -110.43879) (xy 427.917295 -110.386699) (xy 427.905169 -110.332262)
			(xy 427.901098 -110.27664) (xy 422.303369 -110.27664) (xy 422.303448 -110.280958) (xy 422.302939 -110.308844)
			(xy 422.294819 -110.36402) (xy 422.278751 -110.417427) (xy 422.255079 -110.467924) (xy 422.224306 -110.514437)
			(xy 422.187089 -110.555974) (xy 422.144221 -110.591649) (xy 422.096615 -110.620703) (xy 422.045286 -110.642515)
			(xy 421.991329 -110.656621) (xy 421.935892 -110.662721) (xy 421.880158 -110.660684) (xy 421.825315 -110.650554)
			(xy 421.772531 -110.632547) (xy 421.722931 -110.607046) (xy 421.677573 -110.574595) (xy 421.637424 -110.535886)
			(xy 421.603338 -110.491743) (xy 421.576042 -110.443108) (xy 421.556119 -110.391017) (xy 421.543993 -110.33658)
			(xy 421.539922 -110.280958) (xy 420.525448 -110.280958) (xy 420.524939 -110.308844) (xy 420.516819 -110.36402)
			(xy 420.500751 -110.417427) (xy 420.477079 -110.467924) (xy 420.446306 -110.514437) (xy 420.409089 -110.555974)
			(xy 420.366221 -110.591649) (xy 420.318615 -110.620703) (xy 420.267286 -110.642515) (xy 420.213329 -110.656621)
			(xy 420.157892 -110.662721) (xy 420.102158 -110.660684) (xy 420.047315 -110.650554) (xy 419.994531 -110.632547)
			(xy 419.944931 -110.607046) (xy 419.899573 -110.574595) (xy 419.859424 -110.535886) (xy 419.825338 -110.491743)
			(xy 419.798042 -110.443108) (xy 419.778119 -110.391017) (xy 419.765993 -110.33658) (xy 419.761922 -110.280958)
			(xy 418.747448 -110.280958) (xy 418.746939 -110.308844) (xy 418.738819 -110.36402) (xy 418.722751 -110.417427)
			(xy 418.699079 -110.467924) (xy 418.668306 -110.514437) (xy 418.631089 -110.555974) (xy 418.588221 -110.591649)
			(xy 418.540615 -110.620703) (xy 418.489286 -110.642515) (xy 418.435329 -110.656621) (xy 418.379892 -110.662721)
			(xy 418.324158 -110.660684) (xy 418.269315 -110.650554) (xy 418.216531 -110.632547) (xy 418.166931 -110.607046)
			(xy 418.121573 -110.574595) (xy 418.081424 -110.535886) (xy 418.047338 -110.491743) (xy 418.020042 -110.443108)
			(xy 418.000119 -110.391017) (xy 417.987993 -110.33658) (xy 417.983922 -110.280958) (xy 373.678856 -110.280958)
			(xy 373.681759 -110.290606) (xy 373.689879 -110.345782) (xy 373.690388 -110.373668) (xy 373.689879 -110.401554)
			(xy 373.681759 -110.45673) (xy 373.665691 -110.510137) (xy 373.642019 -110.560634) (xy 373.611246 -110.607147)
			(xy 373.574029 -110.648684) (xy 373.531161 -110.684359) (xy 373.483555 -110.713413) (xy 373.432226 -110.735225)
			(xy 373.378269 -110.749331) (xy 373.322832 -110.755431) (xy 373.267098 -110.753394) (xy 373.212255 -110.743264)
			(xy 373.159471 -110.725257) (xy 373.109871 -110.699756) (xy 373.064513 -110.667305) (xy 373.024364 -110.628596)
			(xy 372.990278 -110.584453) (xy 372.962982 -110.535818) (xy 372.943059 -110.483727) (xy 372.930933 -110.42929)
			(xy 372.926862 -110.373668) (xy 325.566954 -110.373668) (xy 325.561459 -110.41101) (xy 325.545391 -110.464417)
			(xy 325.521719 -110.514914) (xy 325.490946 -110.561427) (xy 325.453729 -110.602964) (xy 325.410861 -110.638639)
			(xy 325.363255 -110.667693) (xy 325.311926 -110.689505) (xy 325.257969 -110.703611) (xy 325.202532 -110.709711)
			(xy 325.146798 -110.707674) (xy 325.091955 -110.697544) (xy 325.039171 -110.679537) (xy 324.989571 -110.654036)
			(xy 324.944213 -110.621585) (xy 324.904064 -110.582876) (xy 324.869978 -110.538733) (xy 324.842682 -110.490098)
			(xy 324.822759 -110.438007) (xy 324.810633 -110.38357) (xy 324.806562 -110.327948) (xy 323.525388 -110.327948)
			(xy 323.524879 -110.355834) (xy 323.516759 -110.41101) (xy 323.500691 -110.464417) (xy 323.477019 -110.514914)
			(xy 323.446246 -110.561427) (xy 323.409029 -110.602964) (xy 323.366161 -110.638639) (xy 323.318555 -110.667693)
			(xy 323.267226 -110.689505) (xy 323.213269 -110.703611) (xy 323.157832 -110.709711) (xy 323.102098 -110.707674)
			(xy 323.047255 -110.697544) (xy 322.994471 -110.679537) (xy 322.944871 -110.654036) (xy 322.899513 -110.621585)
			(xy 322.859364 -110.582876) (xy 322.825278 -110.538733) (xy 322.797982 -110.490098) (xy 322.778059 -110.438007)
			(xy 322.765933 -110.38357) (xy 322.761862 -110.327948) (xy 319.461388 -110.327948) (xy 319.460879 -110.355834)
			(xy 319.452759 -110.41101) (xy 319.436691 -110.464417) (xy 319.413019 -110.514914) (xy 319.382246 -110.561427)
			(xy 319.345029 -110.602964) (xy 319.302161 -110.638639) (xy 319.254555 -110.667693) (xy 319.203226 -110.689505)
			(xy 319.149269 -110.703611) (xy 319.093832 -110.709711) (xy 319.038098 -110.707674) (xy 318.983255 -110.697544)
			(xy 318.930471 -110.679537) (xy 318.880871 -110.654036) (xy 318.835513 -110.621585) (xy 318.795364 -110.582876)
			(xy 318.761278 -110.538733) (xy 318.733982 -110.490098) (xy 318.714059 -110.438007) (xy 318.701933 -110.38357)
			(xy 318.697862 -110.327948) (xy 282.39466 -110.327948) (xy 284.15488 -112.088168)
		)
		(stroke
			(width 0)
			(type solid)
		)
		(fill yes)
		(layer "In13.Cu")
		(net "P3V3_AUX")
	)
	(gr_poly
		(pts
			(xy 239.18926 -407.02484) (xy 239.18926 -401.193) (xy 238.8235 -400.82724) (xy 234.817666 -400.82724)
			(xy 234.802672 -400.827777) (xy 234.773976 -400.836488) (xy 234.749042 -400.853151) (xy 234.730016 -400.876333)
			(xy 234.718535 -400.904037) (xy 234.715587 -400.933881) (xy 234.721426 -400.963296) (xy 234.735549 -400.989752)
			(xy 234.745784 -401.000722) (xy 235.419039 -401.673822) (xy 238.03559 -401.673822) (xy 238.039661 -401.6182)
			(xy 238.051787 -401.563763) (xy 238.07171 -401.511672) (xy 238.099006 -401.463037) (xy 238.133092 -401.418894)
			(xy 238.173241 -401.380185) (xy 238.218599 -401.347734) (xy 238.268199 -401.322233) (xy 238.320983 -401.304226)
			(xy 238.375826 -401.294096) (xy 238.43156 -401.292059) (xy 238.486997 -401.298159) (xy 238.540954 -401.312265)
			(xy 238.592283 -401.334077) (xy 238.639889 -401.363131) (xy 238.682757 -401.398806) (xy 238.719974 -401.440343)
			(xy 238.750747 -401.486856) (xy 238.774419 -401.537353) (xy 238.790487 -401.59076) (xy 238.798607 -401.645936)
			(xy 238.799116 -401.673822) (xy 238.798607 -401.701708) (xy 238.790487 -401.756884) (xy 238.774419 -401.810291)
			(xy 238.750747 -401.860788) (xy 238.719974 -401.907301) (xy 238.682757 -401.948838) (xy 238.639889 -401.984513)
			(xy 238.592283 -402.013567) (xy 238.540954 -402.035379) (xy 238.486997 -402.049485) (xy 238.43156 -402.055585)
			(xy 238.375826 -402.053548) (xy 238.320983 -402.043418) (xy 238.268199 -402.025411) (xy 238.218599 -401.99991)
			(xy 238.173241 -401.967459) (xy 238.133092 -401.92875) (xy 238.099006 -401.884607) (xy 238.07171 -401.835972)
			(xy 238.051787 -401.783881) (xy 238.039661 -401.729444) (xy 238.03559 -401.673822) (xy 235.419039 -401.673822)
			(xy 235.849414 -402.104098) (xy 235.861606 -402.107908) (xy 235.887345 -402.116229) (xy 235.936356 -402.139122)
			(xy 235.981641 -402.168707) (xy 236.022294 -402.204393) (xy 236.057498 -402.245464) (xy 236.086547 -402.291096)
			(xy 236.10886 -402.340373) (xy 236.123988 -402.392308) (xy 236.131628 -402.445859) (xy 236.132116 -402.472906)
			(xy 236.13163 -402.500157) (xy 236.123873 -402.554105) (xy 236.108517 -402.606399) (xy 236.085876 -402.655976)
			(xy 236.056409 -402.701826) (xy 236.020718 -402.743017) (xy 235.979528 -402.778708) (xy 235.933678 -402.808175)
			(xy 235.884101 -402.830816) (xy 235.831807 -402.846172) (xy 235.777859 -402.85393) (xy 235.750608 -402.854414)
			(xy 235.72356 -402.853943) (xy 235.670006 -402.846303) (xy 235.618069 -402.831174) (xy 235.568789 -402.808861)
			(xy 235.523155 -402.77981) (xy 235.482083 -402.744605) (xy 235.446395 -402.703951) (xy 235.416808 -402.658663)
			(xy 235.393914 -402.60965) (xy 235.38561 -402.583904) (xy 235.3818 -402.571712) (xy 233.976418 -401.166076)
			(xy 233.904028 -401.166076) (xy 233.904028 -401.229576) (xy 233.90987 -401.240752) (xy 233.923918 -401.26849)
			(xy 233.943824 -401.327391) (xy 233.95394 -401.388736) (xy 233.954574 -401.419822) (xy 233.954088 -401.447073)
			(xy 233.946332 -401.501021) (xy 233.930977 -401.553316) (xy 233.908335 -401.602893) (xy 233.878869 -401.648743)
			(xy 233.843178 -401.689934) (xy 233.801987 -401.725625) (xy 233.756137 -401.755091) (xy 233.70656 -401.777733)
			(xy 233.654265 -401.793088) (xy 233.600317 -401.800844) (xy 233.545815 -401.800844) (xy 233.491867 -401.793088)
			(xy 233.439572 -401.777733) (xy 233.389995 -401.755091) (xy 233.344145 -401.725625) (xy 233.302954 -401.689934)
			(xy 233.267263 -401.648743) (xy 233.237797 -401.602893) (xy 233.215155 -401.553316) (xy 233.1998 -401.501021)
			(xy 233.192044 -401.447073) (xy 233.191558 -401.419822) (xy 233.19214 -401.389253) (xy 233.201834 -401.32889)
			(xy 233.210862 -401.29968) (xy 233.214759 -401.286506) (xy 233.216143 -401.259078) (xy 233.210159 -401.232275)
			(xy 233.197242 -401.20804) (xy 233.178328 -401.188129) (xy 233.154787 -401.173985) (xy 233.128327 -401.166634)
			(xy 233.114596 -401.166076) (xy 232.634536 -401.166076) (xy 232.620802 -401.166561) (xy 232.594343 -401.173946)
			(xy 232.570807 -401.188112) (xy 232.551894 -401.208034) (xy 232.538971 -401.232274) (xy 232.53297 -401.259081)
			(xy 232.534326 -401.286518) (xy 232.53827 -401.29968) (xy 232.547304 -401.32889) (xy 232.557006 -401.389253)
			(xy 232.557574 -401.419822) (xy 232.557088 -401.447073) (xy 232.549332 -401.501021) (xy 232.533977 -401.553316)
			(xy 232.511335 -401.602893) (xy 232.481869 -401.648743) (xy 232.446178 -401.689934) (xy 232.404987 -401.725625)
			(xy 232.359137 -401.755091) (xy 232.30956 -401.777733) (xy 232.257265 -401.793088) (xy 232.203317 -401.800844)
			(xy 232.148815 -401.800844) (xy 232.094867 -401.793088) (xy 232.042572 -401.777733) (xy 231.992995 -401.755091)
			(xy 231.947145 -401.725625) (xy 231.905954 -401.689934) (xy 231.870263 -401.648743) (xy 231.840797 -401.602893)
			(xy 231.818155 -401.553316) (xy 231.8028 -401.501021) (xy 231.795044 -401.447073) (xy 231.794558 -401.419822)
			(xy 231.79514 -401.389253) (xy 231.804834 -401.32889) (xy 231.813862 -401.29968) (xy 231.817759 -401.286506)
			(xy 231.819143 -401.259078) (xy 231.813159 -401.232275) (xy 231.800242 -401.20804) (xy 231.781328 -401.188129)
			(xy 231.757787 -401.173985) (xy 231.731327 -401.166634) (xy 231.717596 -401.166076) (xy 231.212136 -401.166076)
			(xy 231.198402 -401.166561) (xy 231.171943 -401.173946) (xy 231.148407 -401.188112) (xy 231.129494 -401.208034)
			(xy 231.116571 -401.232274) (xy 231.11057 -401.259081) (xy 231.111926 -401.286518) (xy 231.11587 -401.29968)
			(xy 231.124904 -401.32889) (xy 231.134606 -401.389253) (xy 231.135174 -401.419822) (xy 231.134688 -401.447073)
			(xy 231.126932 -401.501021) (xy 231.111577 -401.553316) (xy 231.088935 -401.602893) (xy 231.059469 -401.648743)
			(xy 231.023778 -401.689934) (xy 230.982587 -401.725625) (xy 230.936737 -401.755091) (xy 230.88716 -401.777733)
			(xy 230.834865 -401.793088) (xy 230.780917 -401.800844) (xy 230.726415 -401.800844) (xy 230.672467 -401.793088)
			(xy 230.620172 -401.777733) (xy 230.570595 -401.755091) (xy 230.524745 -401.725625) (xy 230.483554 -401.689934)
			(xy 230.447863 -401.648743) (xy 230.418397 -401.602893) (xy 230.395755 -401.553316) (xy 230.3804 -401.501021)
			(xy 230.372644 -401.447073) (xy 230.372158 -401.419822) (xy 230.37274 -401.389253) (xy 230.382434 -401.32889)
			(xy 230.391462 -401.29968) (xy 230.395359 -401.286506) (xy 230.396743 -401.259078) (xy 230.390759 -401.232275)
			(xy 230.377842 -401.20804) (xy 230.358928 -401.188129) (xy 230.335387 -401.173985) (xy 230.308927 -401.166634)
			(xy 230.295196 -401.166076) (xy 228.978714 -401.166076) (xy 228.669088 -401.475702) (xy 228.659807 -401.485572)
			(xy 228.646351 -401.509076) (xy 228.639549 -401.53529) (xy 228.639878 -401.562371) (xy 228.647316 -401.588412)
			(xy 228.66134 -401.611582) (xy 228.680961 -401.630249) (xy 228.69271 -401.636992) (xy 228.718281 -401.651395)
			(xy 228.76506 -401.686834) (xy 228.80586 -401.729019) (xy 228.83972 -401.776953) (xy 228.86584 -401.829508)
			(xy 228.883604 -401.885442) (xy 228.892594 -401.943436) (xy 228.893116 -401.97278) (xy 228.892654 -402.000034)
			(xy 228.884899 -402.053987) (xy 228.869545 -402.106288) (xy 228.846904 -402.155871) (xy 228.817437 -402.201728)
			(xy 228.781743 -402.242923) (xy 228.74055 -402.27862) (xy 228.694696 -402.308091) (xy 228.645114 -402.330735)
			(xy 228.592815 -402.346093) (xy 228.538862 -402.353852) (xy 228.511608 -402.354288) (xy 228.482265 -402.35375)
			(xy 228.424271 -402.344764) (xy 228.368338 -402.327003) (xy 228.315784 -402.300885) (xy 228.26785 -402.267027)
			(xy 228.225666 -402.226228) (xy 228.190229 -402.17945) (xy 228.17582 -402.153882) (xy 228.169017 -402.14218)
			(xy 228.150353 -402.122588) (xy 228.127198 -402.108587) (xy 228.10118 -402.101158) (xy 228.074123 -402.100823)
			(xy 228.047928 -402.107607) (xy 228.024435 -402.121032) (xy 228.01453 -402.13026) (xy 227.627688 -402.517102)
			(xy 227.608983 -402.535123) (xy 227.56696 -402.565649) (xy 227.520679 -402.589223) (xy 227.471279 -402.605264)
			(xy 227.419978 -402.613377) (xy 227.394008 -402.613876) (xy 225.311462 -402.613876) (xy 225.297492 -402.642324)
			(xy 225.285321 -402.665867) (xy 225.255447 -402.709642) (xy 225.243449 -402.722842) (xy 230.371648 -402.722842)
			(xy 230.375719 -402.66722) (xy 230.387845 -402.612783) (xy 230.407768 -402.560692) (xy 230.435064 -402.512057)
			(xy 230.46915 -402.467914) (xy 230.509299 -402.429205) (xy 230.554657 -402.396754) (xy 230.604257 -402.371253)
			(xy 230.657041 -402.353246) (xy 230.711884 -402.343116) (xy 230.767618 -402.341079) (xy 230.823055 -402.347179)
			(xy 230.877012 -402.361285) (xy 230.928341 -402.383097) (xy 230.975947 -402.412151) (xy 231.018815 -402.447826)
			(xy 231.056032 -402.489363) (xy 231.086805 -402.535876) (xy 231.110477 -402.586373) (xy 231.126545 -402.63978)
			(xy 231.134665 -402.694956) (xy 231.135174 -402.722842) (xy 233.191048 -402.722842) (xy 233.195119 -402.66722)
			(xy 233.207245 -402.612783) (xy 233.227168 -402.560692) (xy 233.254464 -402.512057) (xy 233.28855 -402.467914)
			(xy 233.328699 -402.429205) (xy 233.374057 -402.396754) (xy 233.423657 -402.371253) (xy 233.476441 -402.353246)
			(xy 233.531284 -402.343116) (xy 233.587018 -402.341079) (xy 233.642455 -402.347179) (xy 233.696412 -402.361285)
			(xy 233.747741 -402.383097) (xy 233.795347 -402.412151) (xy 233.838215 -402.447826) (xy 233.875432 -402.489363)
			(xy 233.906205 -402.535876) (xy 233.929877 -402.586373) (xy 233.945945 -402.63978) (xy 233.954065 -402.694956)
			(xy 233.954574 -402.722842) (xy 233.954065 -402.750728) (xy 233.945945 -402.805904) (xy 233.929877 -402.859311)
			(xy 233.906205 -402.909808) (xy 233.875432 -402.956321) (xy 233.860687 -402.972778) (xy 234.60659 -402.972778)
			(xy 234.610661 -402.917156) (xy 234.622787 -402.862719) (xy 234.64271 -402.810628) (xy 234.670006 -402.761993)
			(xy 234.704092 -402.71785) (xy 234.744241 -402.679141) (xy 234.789599 -402.64669) (xy 234.839199 -402.621189)
			(xy 234.891983 -402.603182) (xy 234.946826 -402.593052) (xy 235.00256 -402.591015) (xy 235.057997 -402.597115)
			(xy 235.111954 -402.611221) (xy 235.163283 -402.633033) (xy 235.210889 -402.662087) (xy 235.253757 -402.697762)
			(xy 235.290974 -402.739299) (xy 235.321747 -402.785812) (xy 235.345419 -402.836309) (xy 235.361487 -402.889716)
			(xy 235.369607 -402.944892) (xy 235.370116 -402.972778) (xy 235.369607 -403.000664) (xy 235.361487 -403.05584)
			(xy 235.345419 -403.109247) (xy 235.321747 -403.159744) (xy 235.290974 -403.206257) (xy 235.253757 -403.247794)
			(xy 235.210889 -403.283469) (xy 235.163283 -403.312523) (xy 235.111954 -403.334335) (xy 235.057997 -403.348441)
			(xy 235.00256 -403.354541) (xy 234.946826 -403.352504) (xy 234.891983 -403.342374) (xy 234.839199 -403.324367)
			(xy 234.789599 -403.298866) (xy 234.744241 -403.266415) (xy 234.704092 -403.227706) (xy 234.670006 -403.183563)
			(xy 234.64271 -403.134928) (xy 234.622787 -403.082837) (xy 234.610661 -403.0284) (xy 234.60659 -402.972778)
			(xy 233.860687 -402.972778) (xy 233.838215 -402.997858) (xy 233.795347 -403.033533) (xy 233.747741 -403.062587)
			(xy 233.696412 -403.084399) (xy 233.642455 -403.098505) (xy 233.587018 -403.104605) (xy 233.531284 -403.102568)
			(xy 233.476441 -403.092438) (xy 233.423657 -403.074431) (xy 233.374057 -403.04893) (xy 233.328699 -403.016479)
			(xy 233.28855 -402.97777) (xy 233.254464 -402.933627) (xy 233.227168 -402.884992) (xy 233.207245 -402.832901)
			(xy 233.195119 -402.778464) (xy 233.191048 -402.722842) (xy 231.135174 -402.722842) (xy 231.134665 -402.750728)
			(xy 231.126545 -402.805904) (xy 231.110477 -402.859311) (xy 231.086805 -402.909808) (xy 231.056032 -402.956321)
			(xy 231.018815 -402.997858) (xy 230.975947 -403.033533) (xy 230.928341 -403.062587) (xy 230.877012 -403.084399)
			(xy 230.823055 -403.098505) (xy 230.767618 -403.104605) (xy 230.711884 -403.102568) (xy 230.657041 -403.092438)
			(xy 230.604257 -403.074431) (xy 230.554657 -403.04893) (xy 230.509299 -403.016479) (xy 230.46915 -402.97777)
			(xy 230.435064 -402.933627) (xy 230.407768 -402.884992) (xy 230.387845 -402.832901) (xy 230.375719 -402.778464)
			(xy 230.371648 -402.722842) (xy 225.243449 -402.722842) (xy 225.219801 -402.74886) (xy 225.179068 -402.782765)
			(xy 225.134034 -402.810705) (xy 225.085565 -402.832142) (xy 225.034596 -402.846662) (xy 224.982107 -402.853986)
			(xy 224.955608 -402.854414) (xy 224.924701 -402.853812) (xy 224.863693 -402.843853) (xy 224.834196 -402.834602)
			(xy 224.820381 -402.830515) (xy 224.791606 -402.829379) (xy 224.763656 -402.836311) (xy 224.738747 -402.850762)
			(xy 224.718855 -402.871584) (xy 224.705558 -402.897128) (xy 224.699911 -402.925365) (xy 224.700592 -402.939758)
			(xy 224.702116 -402.972778) (xy 224.701654 -403.000032) (xy 224.6939 -403.053985) (xy 224.678546 -403.106286)
			(xy 224.655905 -403.155869) (xy 224.626438 -403.201725) (xy 224.590745 -403.242921) (xy 224.549553 -403.278618)
			(xy 224.503699 -403.308089) (xy 224.454118 -403.330734) (xy 224.401819 -403.346093) (xy 224.347866 -403.353852)
			(xy 224.293358 -403.353853) (xy 224.239405 -403.346098) (xy 224.187105 -403.330743) (xy 224.137522 -403.3081)
			(xy 224.091667 -403.278632) (xy 224.050472 -403.242938) (xy 224.014776 -403.201745) (xy 223.985306 -403.15589)
			(xy 223.962662 -403.106308) (xy 223.947305 -403.054009) (xy 223.939548 -403.000056) (xy 223.939547 -402.945548)
			(xy 223.947304 -402.891595) (xy 223.962661 -402.839295) (xy 223.985304 -402.789713) (xy 224.014774 -402.743859)
			(xy 224.050469 -402.702665) (xy 224.091663 -402.66697) (xy 224.137519 -402.637501) (xy 224.187101 -402.614859)
			(xy 224.239401 -402.599503) (xy 224.293354 -402.591747) (xy 224.320608 -402.59127) (xy 224.346397 -402.591695)
			(xy 224.397504 -402.59864) (xy 224.447212 -402.6124) (xy 224.494615 -402.632727) (xy 224.51695 -402.645626)
			(xy 224.525987 -402.650508) (xy 224.546312 -402.653344) (xy 224.566123 -402.647993) (xy 224.582257 -402.635311)
			(xy 224.592136 -402.617323) (xy 224.594181 -402.596904) (xy 224.591626 -402.586952) (xy 224.59061 -402.583904)
			(xy 224.5868 -402.571712) (xy 223.451928 -401.436586) (xy 223.441835 -401.427134) (xy 223.417771 -401.413536)
			(xy 223.390939 -401.406901) (xy 223.36331 -401.407715) (xy 223.336916 -401.415919) (xy 223.313693 -401.430909)
			(xy 223.29535 -401.451585) (xy 223.283232 -401.476427) (xy 223.280224 -401.489926) (xy 223.274903 -401.515843)
			(xy 223.258061 -401.565998) (xy 223.234456 -401.613347) (xy 223.204541 -401.656985) (xy 223.168889 -401.696076)
			(xy 223.128181 -401.72987) (xy 223.083198 -401.757722) (xy 223.034801 -401.779097) (xy 222.983917 -401.793586)
			(xy 222.931519 -401.800912) (xy 222.905066 -401.80133) (xy 222.877816 -401.800842) (xy 222.823871 -401.793082)
			(xy 222.771579 -401.777724) (xy 222.722004 -401.755081) (xy 222.676157 -401.725614) (xy 222.634969 -401.689923)
			(xy 222.599279 -401.648734) (xy 222.569813 -401.602885) (xy 222.547172 -401.55331) (xy 222.531816 -401.501018)
			(xy 222.524057 -401.447072) (xy 222.523558 -401.419822) (xy 222.523793 -401.399667) (xy 222.527994 -401.359578)
			(xy 222.53194 -401.339812) (xy 222.534573 -401.324917) (xy 222.531987 -401.294795) (xy 222.520699 -401.266749)
			(xy 222.501699 -401.243234) (xy 222.476649 -401.226308) (xy 222.447742 -401.217454) (xy 222.432626 -401.216876)
			(xy 221.980506 -401.216876) (xy 221.96539 -401.217427) (xy 221.936483 -401.226278) (xy 221.911435 -401.243207)
			(xy 221.892443 -401.266729) (xy 221.881172 -401.294782) (xy 221.87861 -401.324905) (xy 221.881192 -401.339812)
			(xy 221.885136 -401.359578) (xy 221.889337 -401.399667) (xy 221.889574 -401.419822) (xy 221.889088 -401.447073)
			(xy 221.881332 -401.501021) (xy 221.865977 -401.553316) (xy 221.843335 -401.602893) (xy 221.813869 -401.648743)
			(xy 221.778178 -401.689934) (xy 221.736987 -401.725625) (xy 221.691137 -401.755091) (xy 221.64156 -401.777733)
			(xy 221.589265 -401.793088) (xy 221.535317 -401.800844) (xy 221.480815 -401.800844) (xy 221.426867 -401.793088)
			(xy 221.374572 -401.777733) (xy 221.324995 -401.755091) (xy 221.279145 -401.725625) (xy 221.237954 -401.689934)
			(xy 221.202263 -401.648743) (xy 221.172797 -401.602893) (xy 221.150155 -401.553316) (xy 221.1348 -401.501021)
			(xy 221.127044 -401.447073) (xy 221.126558 -401.419822) (xy 221.126793 -401.399667) (xy 221.130994 -401.359578)
			(xy 221.13494 -401.339812) (xy 221.137573 -401.324917) (xy 221.134987 -401.294795) (xy 221.123699 -401.266749)
			(xy 221.104699 -401.243234) (xy 221.079649 -401.226308) (xy 221.050742 -401.217454) (xy 221.035626 -401.216876)
			(xy 220.558106 -401.216876) (xy 220.54299 -401.217427) (xy 220.514083 -401.226278) (xy 220.489035 -401.243207)
			(xy 220.470043 -401.266729) (xy 220.458772 -401.294782) (xy 220.45621 -401.324905) (xy 220.458792 -401.339812)
			(xy 220.462736 -401.359578) (xy 220.466937 -401.399667) (xy 220.467174 -401.419822) (xy 220.466688 -401.447073)
			(xy 220.458932 -401.501021) (xy 220.443577 -401.553316) (xy 220.420935 -401.602893) (xy 220.391469 -401.648743)
			(xy 220.355778 -401.689934) (xy 220.314587 -401.725625) (xy 220.268737 -401.755091) (xy 220.21916 -401.777733)
			(xy 220.166865 -401.793088) (xy 220.112917 -401.800844) (xy 220.058415 -401.800844) (xy 220.004467 -401.793088)
			(xy 219.952172 -401.777733) (xy 219.902595 -401.755091) (xy 219.856745 -401.725625) (xy 219.815554 -401.689934)
			(xy 219.779863 -401.648743) (xy 219.750397 -401.602893) (xy 219.727755 -401.553316) (xy 219.7124 -401.501021)
			(xy 219.704644 -401.447073) (xy 219.704158 -401.419822) (xy 219.704393 -401.399667) (xy 219.708594 -401.359578)
			(xy 219.71254 -401.339812) (xy 219.715173 -401.324917) (xy 219.712587 -401.294795) (xy 219.701299 -401.266749)
			(xy 219.682299 -401.243234) (xy 219.657249 -401.226308) (xy 219.628342 -401.217454) (xy 219.613226 -401.216876)
			(xy 218.209114 -401.216876) (xy 217.967052 -401.459192) (xy 217.957448 -401.469494) (xy 217.943799 -401.49412)
			(xy 217.937385 -401.521535) (xy 217.938691 -401.54966) (xy 217.947618 -401.576362) (xy 217.96349 -401.599617)
			(xy 217.985103 -401.617661) (xy 217.997786 -401.623784) (xy 218.022792 -401.635357) (xy 218.06947 -401.664638)
			(xy 218.111448 -401.70033) (xy 218.147854 -401.741692) (xy 218.177929 -401.787861) (xy 218.201047 -401.837878)
			(xy 218.216728 -401.8907) (xy 218.224646 -401.945229) (xy 218.225116 -401.97278) (xy 218.224654 -402.000034)
			(xy 218.216899 -402.053987) (xy 218.201545 -402.106288) (xy 218.178904 -402.155871) (xy 218.149437 -402.201728)
			(xy 218.113743 -402.242923) (xy 218.07255 -402.27862) (xy 218.026696 -402.308091) (xy 217.977114 -402.330735)
			(xy 217.924815 -402.346093) (xy 217.870862 -402.353852) (xy 217.843608 -402.354288) (xy 217.816058 -402.353805)
			(xy 217.761531 -402.345881) (xy 217.708711 -402.330197) (xy 217.658696 -402.307079) (xy 217.612525 -402.277008)
			(xy 217.57116 -402.24061) (xy 217.53546 -402.19864) (xy 217.506167 -402.151972) (xy 217.494612 -402.126958)
			(xy 217.488505 -402.114247) (xy 217.470501 -402.092557) (xy 217.447245 -402.076625) (xy 217.420517 -402.06767)
			(xy 217.392357 -402.066375) (xy 217.36492 -402.072841) (xy 217.340301 -402.086572) (xy 217.33002 -402.096224)
			(xy 216.934288 -402.491702) (xy 216.915583 -402.509723) (xy 216.87356 -402.540249) (xy 216.827279 -402.563823)
			(xy 216.777879 -402.579864) (xy 216.726578 -402.587977) (xy 216.700608 -402.588476) (xy 214.652606 -402.588476)
			(xy 214.639652 -402.619718) (xy 214.628394 -402.645406) (xy 214.599452 -402.693445) (xy 214.563791 -402.736731)
			(xy 214.52218 -402.774334) (xy 214.475514 -402.805442) (xy 214.424799 -402.829388) (xy 214.371126 -402.845654)
			(xy 214.31565 -402.853891) (xy 214.287608 -402.854414) (xy 214.256701 -402.853812) (xy 214.195693 -402.843853)
			(xy 214.166196 -402.834602) (xy 214.152381 -402.830515) (xy 214.123606 -402.829379) (xy 214.095656 -402.836311)
			(xy 214.070747 -402.850762) (xy 214.050855 -402.871584) (xy 214.037558 -402.897128) (xy 214.031911 -402.925365)
			(xy 214.032592 -402.939758) (xy 214.034116 -402.972778) (xy 214.033654 -403.000032) (xy 214.0259 -403.053985)
			(xy 214.010546 -403.106286) (xy 213.987905 -403.155869) (xy 213.958438 -403.201725) (xy 213.922745 -403.242921)
			(xy 213.881553 -403.278618) (xy 213.835699 -403.308089) (xy 213.786118 -403.330734) (xy 213.733819 -403.346093)
			(xy 213.679866 -403.353852) (xy 213.625358 -403.353853) (xy 213.571405 -403.346098) (xy 213.519105 -403.330743)
			(xy 213.469522 -403.3081) (xy 213.423667 -403.278632) (xy 213.382472 -403.242938) (xy 213.346776 -403.201745)
			(xy 213.317306 -403.15589) (xy 213.294662 -403.106308) (xy 213.279305 -403.054009) (xy 213.271548 -403.000056)
			(xy 213.271547 -402.945548) (xy 213.279304 -402.891595) (xy 213.294661 -402.839295) (xy 213.317304 -402.789713)
			(xy 213.346774 -402.743859) (xy 213.382469 -402.702665) (xy 213.423663 -402.66697) (xy 213.469519 -402.637501)
			(xy 213.519101 -402.614859) (xy 213.571401 -402.599503) (xy 213.625354 -402.591747) (xy 213.652608 -402.59127)
			(xy 213.678397 -402.591695) (xy 213.729504 -402.59864) (xy 213.779212 -402.6124) (xy 213.826615 -402.632727)
			(xy 213.84895 -402.645626) (xy 213.857987 -402.650508) (xy 213.878312 -402.653344) (xy 213.898123 -402.647993)
			(xy 213.914257 -402.635311) (xy 213.924136 -402.617323) (xy 213.926181 -402.596904) (xy 213.923626 -402.586952)
			(xy 213.92261 -402.583904) (xy 213.9188 -402.571712) (xy 212.783928 -401.436586) (xy 212.773835 -401.427134)
			(xy 212.749771 -401.413536) (xy 212.722939 -401.406901) (xy 212.69531 -401.407715) (xy 212.668916 -401.415919)
			(xy 212.645693 -401.430909) (xy 212.62735 -401.451585) (xy 212.615232 -401.476427) (xy 212.612224 -401.489926)
			(xy 212.606903 -401.515843) (xy 212.590061 -401.565998) (xy 212.566456 -401.613347) (xy 212.536541 -401.656985)
			(xy 212.500889 -401.696076) (xy 212.460181 -401.72987) (xy 212.415198 -401.757722) (xy 212.366801 -401.779097)
			(xy 212.315917 -401.793586) (xy 212.263519 -401.800912) (xy 212.237066 -401.80133) (xy 212.209816 -401.800842)
			(xy 212.155871 -401.793082) (xy 212.103579 -401.777724) (xy 212.054004 -401.755081) (xy 212.008157 -401.725614)
			(xy 211.966969 -401.689923) (xy 211.931279 -401.648734) (xy 211.901813 -401.602885) (xy 211.879172 -401.55331)
			(xy 211.863816 -401.501018) (xy 211.856057 -401.447072) (xy 211.855558 -401.419822) (xy 211.855724 -401.40477)
			(xy 211.858141 -401.374763) (xy 211.860384 -401.359878) (xy 211.862213 -401.345319) (xy 211.858404 -401.316237)
			(xy 211.846487 -401.289436) (xy 211.827443 -401.267128) (xy 211.802844 -401.251154) (xy 211.77472 -401.242829)
			(xy 211.760054 -401.242276) (xy 211.317078 -401.242276) (xy 211.302408 -401.242764) (xy 211.27428 -401.251105)
			(xy 211.24968 -401.267095) (xy 211.230637 -401.289415) (xy 211.218721 -401.316225) (xy 211.214912 -401.345316)
			(xy 211.216748 -401.359878) (xy 211.218987 -401.374763) (xy 211.221399 -401.40477) (xy 211.221574 -401.419822)
			(xy 211.221088 -401.447073) (xy 211.213332 -401.501021) (xy 211.197977 -401.553316) (xy 211.175335 -401.602893)
			(xy 211.145869 -401.648743) (xy 211.110178 -401.689934) (xy 211.068987 -401.725625) (xy 211.023137 -401.755091)
			(xy 210.97356 -401.777733) (xy 210.921265 -401.793088) (xy 210.867317 -401.800844) (xy 210.812815 -401.800844)
			(xy 210.758867 -401.793088) (xy 210.706572 -401.777733) (xy 210.656995 -401.755091) (xy 210.611145 -401.725625)
			(xy 210.569954 -401.689934) (xy 210.534263 -401.648743) (xy 210.504797 -401.602893) (xy 210.482155 -401.553316)
			(xy 210.4668 -401.501021) (xy 210.459044 -401.447073) (xy 210.458558 -401.419822) (xy 210.458724 -401.40477)
			(xy 210.461141 -401.374763) (xy 210.463384 -401.359878) (xy 210.465213 -401.345319) (xy 210.461404 -401.316237)
			(xy 210.449487 -401.289436) (xy 210.430443 -401.267128) (xy 210.405844 -401.251154) (xy 210.37772 -401.242829)
			(xy 210.363054 -401.242276) (xy 209.894678 -401.242276) (xy 209.880008 -401.242764) (xy 209.85188 -401.251105)
			(xy 209.82728 -401.267095) (xy 209.808237 -401.289415) (xy 209.796321 -401.316225) (xy 209.792512 -401.345316)
			(xy 209.794348 -401.359878) (xy 209.796587 -401.374763) (xy 209.798999 -401.40477) (xy 209.799174 -401.419822)
			(xy 209.798688 -401.447073) (xy 209.790932 -401.501021) (xy 209.775577 -401.553316) (xy 209.752935 -401.602893)
			(xy 209.723469 -401.648743) (xy 209.687778 -401.689934) (xy 209.646587 -401.725625) (xy 209.600737 -401.755091)
			(xy 209.55116 -401.777733) (xy 209.498865 -401.793088) (xy 209.444917 -401.800844) (xy 209.390415 -401.800844)
			(xy 209.336467 -401.793088) (xy 209.284172 -401.777733) (xy 209.234595 -401.755091) (xy 209.188745 -401.725625)
			(xy 209.147554 -401.689934) (xy 209.111863 -401.648743) (xy 209.082397 -401.602893) (xy 209.059755 -401.553316)
			(xy 209.0444 -401.501021) (xy 209.036644 -401.447073) (xy 209.036158 -401.419822) (xy 209.036324 -401.40477)
			(xy 209.038741 -401.374763) (xy 209.040984 -401.359878) (xy 209.042813 -401.345319) (xy 209.039004 -401.316237)
			(xy 209.027087 -401.289436) (xy 209.008043 -401.267128) (xy 208.983444 -401.251154) (xy 208.95532 -401.242829)
			(xy 208.940654 -401.242276) (xy 207.566514 -401.242276) (xy 207.333088 -401.475702) (xy 207.323807 -401.485572)
			(xy 207.310351 -401.509076) (xy 207.303549 -401.53529) (xy 207.303878 -401.562371) (xy 207.311316 -401.588412)
			(xy 207.32534 -401.611582) (xy 207.344961 -401.630249) (xy 207.35671 -401.636992) (xy 207.382281 -401.651395)
			(xy 207.42906 -401.686834) (xy 207.46986 -401.729019) (xy 207.50372 -401.776953) (xy 207.52984 -401.829508)
			(xy 207.547604 -401.885442) (xy 207.556594 -401.943436) (xy 207.557116 -401.97278) (xy 207.556654 -402.000034)
			(xy 207.548899 -402.053987) (xy 207.533545 -402.106288) (xy 207.510904 -402.155871) (xy 207.481437 -402.201728)
			(xy 207.445743 -402.242923) (xy 207.40455 -402.27862) (xy 207.358696 -402.308091) (xy 207.309114 -402.330735)
			(xy 207.256815 -402.346093) (xy 207.202862 -402.353852) (xy 207.175608 -402.354288) (xy 207.146265 -402.35375)
			(xy 207.088271 -402.344764) (xy 207.032338 -402.327003) (xy 206.979784 -402.300885) (xy 206.93185 -402.267027)
			(xy 206.889666 -402.226228) (xy 206.854229 -402.17945) (xy 206.83982 -402.153882) (xy 206.833017 -402.14218)
			(xy 206.814353 -402.122588) (xy 206.791198 -402.108587) (xy 206.76518 -402.101158) (xy 206.738123 -402.100823)
			(xy 206.711928 -402.107607) (xy 206.688435 -402.121032) (xy 206.67853 -402.13026) (xy 206.291688 -402.517102)
			(xy 206.272983 -402.535123) (xy 206.23096 -402.565649) (xy 206.184679 -402.589223) (xy 206.135279 -402.605264)
			(xy 206.083978 -402.613377) (xy 206.058008 -402.613876) (xy 203.975462 -402.613876) (xy 203.961492 -402.642324)
			(xy 203.949321 -402.665867) (xy 203.919447 -402.709642) (xy 203.907449 -402.722842) (xy 209.035648 -402.722842)
			(xy 209.039719 -402.66722) (xy 209.051845 -402.612783) (xy 209.071768 -402.560692) (xy 209.099064 -402.512057)
			(xy 209.13315 -402.467914) (xy 209.173299 -402.429205) (xy 209.218657 -402.396754) (xy 209.268257 -402.371253)
			(xy 209.321041 -402.353246) (xy 209.375884 -402.343116) (xy 209.431618 -402.341079) (xy 209.487055 -402.347179)
			(xy 209.541012 -402.361285) (xy 209.592341 -402.383097) (xy 209.639947 -402.412151) (xy 209.682815 -402.447826)
			(xy 209.720032 -402.489363) (xy 209.750805 -402.535876) (xy 209.774477 -402.586373) (xy 209.790545 -402.63978)
			(xy 209.798665 -402.694956) (xy 209.799174 -402.722842) (xy 211.855048 -402.722842) (xy 211.859119 -402.66722)
			(xy 211.871245 -402.612783) (xy 211.891168 -402.560692) (xy 211.918464 -402.512057) (xy 211.95255 -402.467914)
			(xy 211.992699 -402.429205) (xy 212.038057 -402.396754) (xy 212.087657 -402.371253) (xy 212.140441 -402.353246)
			(xy 212.195284 -402.343116) (xy 212.251018 -402.341079) (xy 212.306455 -402.347179) (xy 212.360412 -402.361285)
			(xy 212.411741 -402.383097) (xy 212.459347 -402.412151) (xy 212.502215 -402.447826) (xy 212.539432 -402.489363)
			(xy 212.570205 -402.535876) (xy 212.593877 -402.586373) (xy 212.609945 -402.63978) (xy 212.618065 -402.694956)
			(xy 212.618574 -402.722842) (xy 212.618065 -402.750728) (xy 212.609945 -402.805904) (xy 212.593877 -402.859311)
			(xy 212.570205 -402.909808) (xy 212.539432 -402.956321) (xy 212.502215 -402.997858) (xy 212.459347 -403.033533)
			(xy 212.411741 -403.062587) (xy 212.360412 -403.084399) (xy 212.306455 -403.098505) (xy 212.251018 -403.104605)
			(xy 212.195284 -403.102568) (xy 212.140441 -403.092438) (xy 212.087657 -403.074431) (xy 212.038057 -403.04893)
			(xy 211.992699 -403.016479) (xy 211.95255 -402.97777) (xy 211.918464 -402.933627) (xy 211.891168 -402.884992)
			(xy 211.871245 -402.832901) (xy 211.859119 -402.778464) (xy 211.855048 -402.722842) (xy 209.799174 -402.722842)
			(xy 209.798665 -402.750728) (xy 209.790545 -402.805904) (xy 209.774477 -402.859311) (xy 209.750805 -402.909808)
			(xy 209.720032 -402.956321) (xy 209.682815 -402.997858) (xy 209.639947 -403.033533) (xy 209.592341 -403.062587)
			(xy 209.541012 -403.084399) (xy 209.487055 -403.098505) (xy 209.431618 -403.104605) (xy 209.375884 -403.102568)
			(xy 209.321041 -403.092438) (xy 209.268257 -403.074431) (xy 209.218657 -403.04893) (xy 209.173299 -403.016479)
			(xy 209.13315 -402.97777) (xy 209.099064 -402.933627) (xy 209.071768 -402.884992) (xy 209.051845 -402.832901)
			(xy 209.039719 -402.778464) (xy 209.035648 -402.722842) (xy 203.907449 -402.722842) (xy 203.883801 -402.74886)
			(xy 203.843068 -402.782765) (xy 203.798034 -402.810705) (xy 203.749565 -402.832142) (xy 203.698596 -402.846662)
			(xy 203.646107 -402.853986) (xy 203.619608 -402.854414) (xy 203.588701 -402.853812) (xy 203.527693 -402.843853)
			(xy 203.498196 -402.834602) (xy 203.484381 -402.830515) (xy 203.455606 -402.829379) (xy 203.427656 -402.836311)
			(xy 203.402747 -402.850762) (xy 203.382855 -402.871584) (xy 203.369558 -402.897128) (xy 203.363911 -402.925365)
			(xy 203.364592 -402.939758) (xy 203.366116 -402.972778) (xy 203.365654 -403.000032) (xy 203.3579 -403.053985)
			(xy 203.342546 -403.106286) (xy 203.319905 -403.155869) (xy 203.290438 -403.201725) (xy 203.254745 -403.242921)
			(xy 203.213553 -403.278618) (xy 203.167699 -403.308089) (xy 203.118118 -403.330734) (xy 203.065819 -403.346093)
			(xy 203.011866 -403.353852) (xy 202.957358 -403.353853) (xy 202.903405 -403.346098) (xy 202.851105 -403.330743)
			(xy 202.801522 -403.3081) (xy 202.755667 -403.278632) (xy 202.714472 -403.242938) (xy 202.678776 -403.201745)
			(xy 202.649306 -403.15589) (xy 202.626662 -403.106308) (xy 202.611305 -403.054009) (xy 202.603548 -403.000056)
			(xy 202.603547 -402.945548) (xy 202.611304 -402.891595) (xy 202.626661 -402.839295) (xy 202.649304 -402.789713)
			(xy 202.678774 -402.743859) (xy 202.714469 -402.702665) (xy 202.755663 -402.66697) (xy 202.801519 -402.637501)
			(xy 202.851101 -402.614859) (xy 202.903401 -402.599503) (xy 202.957354 -402.591747) (xy 202.984608 -402.59127)
			(xy 203.015515 -402.591873) (xy 203.076522 -402.601835) (xy 203.10602 -402.611082) (xy 203.119833 -402.615167)
			(xy 203.148603 -402.616299) (xy 203.176547 -402.609365) (xy 203.20145 -402.594915) (xy 203.221336 -402.574093)
			(xy 203.234627 -402.548553) (xy 203.24027 -402.520319) (xy 203.239624 -402.505926) (xy 203.2381 -402.472906)
			(xy 203.238491 -402.44797) (xy 203.244958 -402.398519) (xy 203.257809 -402.350331) (xy 203.276824 -402.304227)
			(xy 203.2889 -402.282406) (xy 203.2889 -402.019008) (xy 202.233022 -400.962876) (xy 201.896472 -400.962876)
			(xy 201.882911 -400.963319) (xy 201.856752 -400.970486) (xy 201.833399 -400.984282) (xy 201.814498 -401.003735)
			(xy 201.801379 -401.027475) (xy 201.794967 -401.053829) (xy 201.795713 -401.080942) (xy 201.803564 -401.106904)
			(xy 201.817969 -401.129887) (xy 201.827638 -401.139406) (xy 201.846662 -401.157525) (xy 201.880053 -401.198085)
			(xy 201.907557 -401.242846) (xy 201.928653 -401.29096) (xy 201.942943 -401.341515) (xy 201.950154 -401.393554)
			(xy 201.950574 -401.419822) (xy 201.950088 -401.447073) (xy 201.942332 -401.501021) (xy 201.926977 -401.553316)
			(xy 201.904335 -401.602893) (xy 201.874869 -401.648743) (xy 201.839178 -401.689934) (xy 201.797987 -401.725625)
			(xy 201.752137 -401.755091) (xy 201.70256 -401.777733) (xy 201.650265 -401.793088) (xy 201.596317 -401.800844)
			(xy 201.541815 -401.800844) (xy 201.487867 -401.793088) (xy 201.435572 -401.777733) (xy 201.385995 -401.755091)
			(xy 201.340145 -401.725625) (xy 201.298954 -401.689934) (xy 201.263263 -401.648743) (xy 201.233797 -401.602893)
			(xy 201.211155 -401.553316) (xy 201.1958 -401.501021) (xy 201.188044 -401.447073) (xy 201.187558 -401.419822)
			(xy 201.187996 -401.393554) (xy 201.195204 -401.341515) (xy 201.209488 -401.290958) (xy 201.230577 -401.24284)
			(xy 201.258072 -401.198073) (xy 201.291451 -401.157504) (xy 201.310494 -401.139406) (xy 201.320212 -401.129912)
			(xy 201.334682 -401.106929) (xy 201.342581 -401.080944) (xy 201.343351 -401.053796) (xy 201.336938 -401.027406)
			(xy 201.323794 -401.003639) (xy 201.304851 -400.984177) (xy 201.281448 -400.970398) (xy 201.25524 -400.963275)
			(xy 201.24166 -400.962876) (xy 200.499472 -400.962876) (xy 200.485911 -400.963319) (xy 200.459752 -400.970486)
			(xy 200.436399 -400.984282) (xy 200.417498 -401.003735) (xy 200.404379 -401.027475) (xy 200.397967 -401.053829)
			(xy 200.398713 -401.080942) (xy 200.406564 -401.106904) (xy 200.420969 -401.129887) (xy 200.430638 -401.139406)
			(xy 200.449662 -401.157525) (xy 200.483053 -401.198085) (xy 200.510557 -401.242846) (xy 200.531653 -401.29096)
			(xy 200.545943 -401.341515) (xy 200.553154 -401.393554) (xy 200.553574 -401.419822) (xy 200.553088 -401.447073)
			(xy 200.545332 -401.501021) (xy 200.529977 -401.553316) (xy 200.507335 -401.602893) (xy 200.477869 -401.648743)
			(xy 200.442178 -401.689934) (xy 200.400987 -401.725625) (xy 200.355137 -401.755091) (xy 200.30556 -401.777733)
			(xy 200.253265 -401.793088) (xy 200.199317 -401.800844) (xy 200.144815 -401.800844) (xy 200.090867 -401.793088)
			(xy 200.038572 -401.777733) (xy 199.988995 -401.755091) (xy 199.943145 -401.725625) (xy 199.901954 -401.689934)
			(xy 199.866263 -401.648743) (xy 199.836797 -401.602893) (xy 199.814155 -401.553316) (xy 199.7988 -401.501021)
			(xy 199.791044 -401.447073) (xy 199.790558 -401.419822) (xy 199.790996 -401.393554) (xy 199.798204 -401.341515)
			(xy 199.812488 -401.290958) (xy 199.833577 -401.24284) (xy 199.861072 -401.198073) (xy 199.894451 -401.157504)
			(xy 199.913494 -401.139406) (xy 199.923212 -401.129912) (xy 199.937682 -401.106929) (xy 199.945581 -401.080944)
			(xy 199.946351 -401.053796) (xy 199.939938 -401.027406) (xy 199.926794 -401.003639) (xy 199.907851 -400.984177)
			(xy 199.884448 -400.970398) (xy 199.85824 -400.963275) (xy 199.84466 -400.962876) (xy 199.077072 -400.962876)
			(xy 199.063511 -400.963319) (xy 199.037352 -400.970486) (xy 199.013999 -400.984282) (xy 198.995098 -401.003735)
			(xy 198.981979 -401.027475) (xy 198.975567 -401.053829) (xy 198.976313 -401.080942) (xy 198.984164 -401.106904)
			(xy 198.998569 -401.129887) (xy 199.008238 -401.139406) (xy 199.027262 -401.157525) (xy 199.060653 -401.198085)
			(xy 199.088157 -401.242846) (xy 199.109253 -401.29096) (xy 199.123543 -401.341515) (xy 199.130754 -401.393554)
			(xy 199.131174 -401.419822) (xy 199.130688 -401.447073) (xy 199.122932 -401.501021) (xy 199.107577 -401.553316)
			(xy 199.084935 -401.602893) (xy 199.055469 -401.648743) (xy 199.019778 -401.689934) (xy 198.978587 -401.725625)
			(xy 198.932737 -401.755091) (xy 198.88316 -401.777733) (xy 198.830865 -401.793088) (xy 198.776917 -401.800844)
			(xy 198.722415 -401.800844) (xy 198.668467 -401.793088) (xy 198.616172 -401.777733) (xy 198.566595 -401.755091)
			(xy 198.520745 -401.725625) (xy 198.479554 -401.689934) (xy 198.443863 -401.648743) (xy 198.414397 -401.602893)
			(xy 198.391755 -401.553316) (xy 198.3764 -401.501021) (xy 198.368644 -401.447073) (xy 198.368158 -401.419822)
			(xy 198.368596 -401.393554) (xy 198.375804 -401.341515) (xy 198.390088 -401.290958) (xy 198.411177 -401.24284)
			(xy 198.438672 -401.198073) (xy 198.472051 -401.157504) (xy 198.491094 -401.139406) (xy 198.500812 -401.129912)
			(xy 198.515282 -401.106929) (xy 198.523181 -401.080944) (xy 198.523951 -401.053796) (xy 198.517538 -401.027406)
			(xy 198.504394 -401.003639) (xy 198.485451 -400.984177) (xy 198.462048 -400.970398) (xy 198.43584 -400.963275)
			(xy 198.42226 -400.962876) (xy 196.881242 -400.962876) (xy 196.867209 -400.963329) (xy 196.840204 -400.970976)
			(xy 196.816295 -400.985677) (xy 196.797285 -401.006326) (xy 196.784605 -401.031366) (xy 196.779211 -401.058909)
			(xy 196.78151 -401.086882) (xy 196.791329 -401.113176) (xy 196.807926 -401.135809) (xy 196.818758 -401.14474)
			(xy 196.841173 -401.16292) (xy 196.880783 -401.204892) (xy 196.913614 -401.252355) (xy 196.938916 -401.304224)
			(xy 196.956111 -401.359314) (xy 196.964806 -401.416366) (xy 196.965316 -401.445222) (xy 196.96483 -401.472473)
			(xy 196.957074 -401.526421) (xy 196.941719 -401.578716) (xy 196.919077 -401.628293) (xy 196.889611 -401.674143)
			(xy 196.85392 -401.715334) (xy 196.812729 -401.751025) (xy 196.766879 -401.780491) (xy 196.717302 -401.803133)
			(xy 196.665007 -401.818488) (xy 196.611059 -401.826244) (xy 196.556557 -401.826244) (xy 196.502609 -401.818488)
			(xy 196.450314 -401.803133) (xy 196.400737 -401.780491) (xy 196.354887 -401.751025) (xy 196.313696 -401.715334)
			(xy 196.278005 -401.674143) (xy 196.248539 -401.628293) (xy 196.225897 -401.578716) (xy 196.210542 -401.526421)
			(xy 196.202786 -401.472473) (xy 196.2023 -401.445222) (xy 196.202829 -401.416366) (xy 196.211521 -401.359312)
			(xy 196.228709 -401.304219) (xy 196.254002 -401.252345) (xy 196.286821 -401.204873) (xy 196.326418 -401.162888)
			(xy 196.348858 -401.14474) (xy 196.35967 -401.135771) (xy 196.376313 -401.113152) (xy 196.386168 -401.086856)
			(xy 196.388489 -401.05887) (xy 196.383101 -401.03131) (xy 196.370413 -401.006258) (xy 196.351381 -400.985608)
			(xy 196.327446 -400.970922) (xy 196.300416 -400.963308) (xy 196.286374 -400.962876) (xy 196.125084 -400.962876)
			(xy 194.652138 -402.435822) (xy 195.05879 -402.435822) (xy 195.062861 -402.3802) (xy 195.074987 -402.325763)
			(xy 195.09491 -402.273672) (xy 195.122206 -402.225037) (xy 195.156292 -402.180894) (xy 195.196441 -402.142185)
			(xy 195.241799 -402.109734) (xy 195.291399 -402.084233) (xy 195.344183 -402.066226) (xy 195.399026 -402.056096)
			(xy 195.45476 -402.054059) (xy 195.510197 -402.060159) (xy 195.564154 -402.074265) (xy 195.615483 -402.096077)
			(xy 195.663089 -402.125131) (xy 195.705957 -402.160806) (xy 195.743174 -402.202343) (xy 195.773947 -402.248856)
			(xy 195.797619 -402.299353) (xy 195.813687 -402.35276) (xy 195.821807 -402.407936) (xy 195.822316 -402.435822)
			(xy 195.821807 -402.463708) (xy 195.813687 -402.518884) (xy 195.797619 -402.572291) (xy 195.773947 -402.622788)
			(xy 195.743174 -402.669301) (xy 195.705957 -402.710838) (xy 195.691533 -402.722842) (xy 198.367648 -402.722842)
			(xy 198.371719 -402.66722) (xy 198.383845 -402.612783) (xy 198.403768 -402.560692) (xy 198.431064 -402.512057)
			(xy 198.46515 -402.467914) (xy 198.505299 -402.429205) (xy 198.550657 -402.396754) (xy 198.600257 -402.371253)
			(xy 198.653041 -402.353246) (xy 198.707884 -402.343116) (xy 198.763618 -402.341079) (xy 198.819055 -402.347179)
			(xy 198.873012 -402.361285) (xy 198.924341 -402.383097) (xy 198.971947 -402.412151) (xy 199.014815 -402.447826)
			(xy 199.052032 -402.489363) (xy 199.082805 -402.535876) (xy 199.106477 -402.586373) (xy 199.122545 -402.63978)
			(xy 199.130665 -402.694956) (xy 199.131174 -402.722842) (xy 201.187048 -402.722842) (xy 201.191119 -402.66722)
			(xy 201.203245 -402.612783) (xy 201.223168 -402.560692) (xy 201.250464 -402.512057) (xy 201.28455 -402.467914)
			(xy 201.324699 -402.429205) (xy 201.370057 -402.396754) (xy 201.419657 -402.371253) (xy 201.472441 -402.353246)
			(xy 201.527284 -402.343116) (xy 201.583018 -402.341079) (xy 201.638455 -402.347179) (xy 201.692412 -402.361285)
			(xy 201.743741 -402.383097) (xy 201.791347 -402.412151) (xy 201.834215 -402.447826) (xy 201.871432 -402.489363)
			(xy 201.902205 -402.535876) (xy 201.925877 -402.586373) (xy 201.941945 -402.63978) (xy 201.950065 -402.694956)
			(xy 201.950574 -402.722842) (xy 201.950065 -402.750728) (xy 201.941945 -402.805904) (xy 201.925877 -402.859311)
			(xy 201.902205 -402.909808) (xy 201.871432 -402.956321) (xy 201.834215 -402.997858) (xy 201.791347 -403.033533)
			(xy 201.743741 -403.062587) (xy 201.692412 -403.084399) (xy 201.638455 -403.098505) (xy 201.583018 -403.104605)
			(xy 201.527284 -403.102568) (xy 201.472441 -403.092438) (xy 201.419657 -403.074431) (xy 201.370057 -403.04893)
			(xy 201.324699 -403.016479) (xy 201.28455 -402.97777) (xy 201.250464 -402.933627) (xy 201.223168 -402.884992)
			(xy 201.203245 -402.832901) (xy 201.191119 -402.778464) (xy 201.187048 -402.722842) (xy 199.131174 -402.722842)
			(xy 199.130665 -402.750728) (xy 199.122545 -402.805904) (xy 199.106477 -402.859311) (xy 199.082805 -402.909808)
			(xy 199.052032 -402.956321) (xy 199.014815 -402.997858) (xy 198.971947 -403.033533) (xy 198.924341 -403.062587)
			(xy 198.873012 -403.084399) (xy 198.819055 -403.098505) (xy 198.763618 -403.104605) (xy 198.707884 -403.102568)
			(xy 198.653041 -403.092438) (xy 198.600257 -403.074431) (xy 198.550657 -403.04893) (xy 198.505299 -403.016479)
			(xy 198.46515 -402.97777) (xy 198.431064 -402.933627) (xy 198.403768 -402.884992) (xy 198.383845 -402.832901)
			(xy 198.371719 -402.778464) (xy 198.367648 -402.722842) (xy 195.691533 -402.722842) (xy 195.663089 -402.746513)
			(xy 195.615483 -402.775567) (xy 195.564154 -402.797379) (xy 195.510197 -402.811485) (xy 195.45476 -402.817585)
			(xy 195.399026 -402.815548) (xy 195.344183 -402.805418) (xy 195.291399 -402.787411) (xy 195.241799 -402.76191)
			(xy 195.196441 -402.729459) (xy 195.156292 -402.69075) (xy 195.122206 -402.646607) (xy 195.09491 -402.597972)
			(xy 195.074987 -402.545881) (xy 195.062861 -402.491444) (xy 195.05879 -402.435822) (xy 194.652138 -402.435822)
			(xy 194.31508 -402.77288) (xy 194.29636 -402.790898) (xy 194.254348 -402.821463) (xy 194.208076 -402.84509)
			(xy 194.158681 -402.861198) (xy 194.107377 -402.869392) (xy 194.0814 -402.869908) (xy 193.489326 -402.869908)
			(xy 193.477729 -402.869789) (xy 193.454594 -402.868139) (xy 193.443098 -402.866606) (xy 193.433515 -402.86567)
			(xy 193.414814 -402.87019) (xy 193.399094 -402.881283) (xy 193.388567 -402.897388) (xy 193.384714 -402.916238)
			(xy 193.388079 -402.935181) (xy 193.392806 -402.943568) (xy 193.406349 -402.966303) (xy 193.42772 -403.014714)
			(xy 193.442199 -403.065612) (xy 193.449511 -403.118023) (xy 193.449956 -403.144482) (xy 193.44951 -403.171177)
			(xy 193.442066 -403.224044) (xy 193.427321 -403.275357) (xy 193.405563 -403.324111) (xy 193.377217 -403.369354)
			(xy 193.342838 -403.410202) (xy 193.303098 -403.445855) (xy 193.258774 -403.475616) (xy 193.210732 -403.498905)
			(xy 193.159911 -403.515265) (xy 193.107305 -403.524376) (xy 193.08064 -403.525736) (xy 193.067216 -403.526541)
			(xy 193.041481 -403.53432) (xy 193.018674 -403.548553) (xy 193.000378 -403.568252) (xy 192.987866 -403.592047)
			(xy 192.982006 -403.618285) (xy 192.983207 -403.645143) (xy 192.986914 -403.65807) (xy 192.995327 -403.686284)
			(xy 193.004379 -403.744458) (xy 193.004948 -403.773894) (xy 193.004462 -403.801145) (xy 192.996706 -403.855093)
			(xy 192.981351 -403.907388) (xy 192.958709 -403.956965) (xy 192.929243 -404.002815) (xy 192.893552 -404.044006)
			(xy 192.852361 -404.079697) (xy 192.806511 -404.109163) (xy 192.756934 -404.131805) (xy 192.704639 -404.14716)
			(xy 192.650691 -404.154916) (xy 192.596189 -404.154916) (xy 192.542241 -404.14716) (xy 192.489946 -404.131805)
			(xy 192.440369 -404.109163) (xy 192.394519 -404.079697) (xy 192.353328 -404.044006) (xy 192.317637 -404.002815)
			(xy 192.288171 -403.956965) (xy 192.265529 -403.907388) (xy 192.250174 -403.855093) (xy 192.242418 -403.801145)
			(xy 192.241932 -403.773894) (xy 192.24238 -403.7472) (xy 192.249826 -403.694334) (xy 192.264574 -403.643024)
			(xy 192.286333 -403.594272) (xy 192.314679 -403.549031) (xy 192.349057 -403.508185) (xy 192.388797 -403.472534)
			(xy 192.43312 -403.442773) (xy 192.481161 -403.419485) (xy 192.53198 -403.403125) (xy 192.584584 -403.394013)
			(xy 192.611248 -403.39264) (xy 192.624672 -403.391837) (xy 192.650406 -403.38406) (xy 192.673213 -403.369827)
			(xy 192.691507 -403.350128) (xy 192.704016 -403.326332) (xy 192.709871 -403.300094) (xy 192.708665 -403.273238)
			(xy 192.704974 -403.260306) (xy 192.696555 -403.232093) (xy 192.687493 -403.173919) (xy 192.68694 -403.144482)
			(xy 192.687418 -403.117037) (xy 192.695283 -403.062714) (xy 192.71085 -403.010078) (xy 192.733797 -402.960215)
			(xy 192.76365 -402.914153) (xy 192.799794 -402.872843) (xy 192.841483 -402.837137) (xy 192.887857 -402.807771)
			(xy 192.937959 -402.785352) (xy 192.990757 -402.770341) (xy 193.017902 -402.766276) (xy 193.031848 -402.76393)
			(xy 193.057757 -402.75262) (xy 193.079576 -402.734645) (xy 193.095637 -402.711381) (xy 193.104711 -402.684607)
			(xy 193.106104 -402.656372) (xy 193.09971 -402.628835) (xy 193.086018 -402.604102) (xy 193.076322 -402.59381)
			(xy 192.979802 -402.49729) (xy 192.96761 -402.49348) (xy 192.94187 -402.485159) (xy 192.892859 -402.462268)
			(xy 192.847572 -402.432683) (xy 192.806919 -402.396997) (xy 192.771715 -402.355926) (xy 192.742666 -402.310294)
			(xy 192.720354 -402.261016) (xy 192.705227 -402.209081) (xy 192.697588 -402.155529) (xy 192.6971 -402.128482)
			(xy 192.697587 -402.101232) (xy 192.705346 -402.047286) (xy 192.720702 -401.994994) (xy 192.743345 -401.94542)
			(xy 192.772812 -401.899572) (xy 192.808503 -401.858385) (xy 192.849693 -401.822696) (xy 192.895543 -401.793232)
			(xy 192.945119 -401.770593) (xy 192.997412 -401.75524) (xy 193.051358 -401.747485) (xy 193.078608 -401.746974)
			(xy 193.105656 -401.747446) (xy 193.159208 -401.755088) (xy 193.211145 -401.770218) (xy 193.260423 -401.792532)
			(xy 193.306056 -401.821583) (xy 193.347127 -401.856788) (xy 193.382814 -401.897442) (xy 193.412401 -401.942729)
			(xy 193.435295 -401.991741) (xy 193.443606 -402.017484) (xy 193.447416 -402.029676) (xy 193.626232 -402.208492)
			(xy 193.944494 -402.208492) (xy 195.754498 -400.398742) (xy 195.773202 -400.380718) (xy 195.815223 -400.350187)
			(xy 195.861503 -400.326607) (xy 195.910904 -400.310562) (xy 195.962207 -400.302445) (xy 195.988178 -400.301968)
			(xy 197.466204 -400.301968) (xy 197.481203 -400.301435) (xy 197.509908 -400.292728) (xy 197.534852 -400.276065)
			(xy 197.553886 -400.25288) (xy 197.565371 -400.225169) (xy 197.568321 -400.195317) (xy 197.562479 -400.165894)
			(xy 197.54835 -400.139433) (xy 197.538086 -400.128486) (xy 196.88048 -399.47088) (xy 193.666364 -399.47088)
			(xy 192.69837 -400.439128) (xy 191.772286 -400.439128) (xy 191.62776 -400.5834) (xy 186.20232 -400.5834)
			(xy 185.667396 -400.048476) (xy 185.657264 -400.038988) (xy 185.633096 -400.025361) (xy 185.606148 -400.018758)
			(xy 185.578418 -400.019669) (xy 185.551962 -400.028028) (xy 185.528741 -400.043214) (xy 185.510479 -400.064101)
			(xy 185.504074 -400.076416) (xy 185.492046 -400.10035) (xy 185.462288 -400.144887) (xy 185.426599 -400.184829)
			(xy 185.385678 -400.219393) (xy 185.340329 -400.247899) (xy 185.291442 -400.269789) (xy 185.239976 -400.284633)
			(xy 185.18694 -400.292139) (xy 185.160158 -400.29257) (xy 185.13291 -400.292081) (xy 185.078969 -400.284319)
			(xy 185.026681 -400.26896) (xy 184.977112 -400.246316) (xy 184.931269 -400.216848) (xy 184.890087 -400.181156)
			(xy 184.854404 -400.139967) (xy 184.824946 -400.094118) (xy 184.802312 -400.044544) (xy 184.786964 -399.992253)
			(xy 184.779213 -399.93831) (xy 184.77865 -399.911062) (xy 184.779098 -399.884279) (xy 184.786582 -399.831238)
			(xy 184.80141 -399.779765) (xy 184.823293 -399.730872) (xy 184.851799 -399.68552) (xy 184.886368 -399.644601)
			(xy 184.92632 -399.608919) (xy 184.97087 -399.579176) (xy 184.994804 -399.567146) (xy 185.007083 -399.560707)
			(xy 185.027893 -399.542405) (xy 185.043023 -399.519186) (xy 185.051361 -399.492757) (xy 185.052294 -399.465059)
			(xy 185.045752 -399.438128) (xy 185.032218 -399.413944) (xy 185.022744 -399.403824) (xy 183.95188 -398.33296)
			(xy 183.94172 -398.328896) (xy 183.916722 -398.318925) (xy 183.869581 -398.292963) (xy 183.826558 -398.260631)
			(xy 183.788508 -398.222572) (xy 183.756186 -398.179541) (xy 183.730236 -398.132393) (xy 183.720232 -398.107408)
			(xy 183.716168 -398.097248) (xy 183.31688 -397.69796) (xy 182.15864 -397.69796) (xy 182.14375 -397.698472)
			(xy 182.115234 -397.707052) (xy 182.090406 -397.723495) (xy 182.071378 -397.746401) (xy 182.059767 -397.773824)
			(xy 182.056562 -397.80343) (xy 182.062035 -397.832702) (xy 182.07572 -397.85915) (xy 182.085742 -397.870172)
			(xy 182.105706 -397.891626) (xy 182.139477 -397.939519) (xy 182.165522 -397.992015) (xy 182.183229 -398.047878)
			(xy 182.192181 -398.105793) (xy 182.192676 -398.135094) (xy 182.19219 -398.162345) (xy 182.184434 -398.216293)
			(xy 182.169079 -398.268588) (xy 182.146437 -398.318165) (xy 182.116971 -398.364015) (xy 182.08128 -398.405206)
			(xy 182.040089 -398.440897) (xy 181.994239 -398.470363) (xy 181.944662 -398.493005) (xy 181.892367 -398.50836)
			(xy 181.838419 -398.516116) (xy 181.783917 -398.516116) (xy 181.729969 -398.50836) (xy 181.677674 -398.493005)
			(xy 181.628097 -398.470363) (xy 181.582247 -398.440897) (xy 181.541056 -398.405206) (xy 181.505365 -398.364015)
			(xy 181.475899 -398.318165) (xy 181.453257 -398.268588) (xy 181.437902 -398.216293) (xy 181.430146 -398.162345)
			(xy 181.42966 -398.135094) (xy 181.430195 -398.105795) (xy 181.43915 -398.047885) (xy 181.45685 -397.992024)
			(xy 181.482879 -397.939524) (xy 181.516625 -397.891618) (xy 181.536594 -397.870172) (xy 181.546576 -397.85912)
			(xy 181.56024 -397.832673) (xy 181.5657 -397.803409) (xy 181.562493 -397.773815) (xy 181.550893 -397.7464)
			(xy 181.531882 -397.723493) (xy 181.507076 -397.707037) (xy 181.47858 -397.69843) (xy 181.463696 -397.69796)
			(xy 179.14112 -397.69796) (xy 177.880518 -398.958562) (xy 180.52237 -398.958562) (xy 180.526441 -398.90294)
			(xy 180.538567 -398.848503) (xy 180.55849 -398.796412) (xy 180.585786 -398.747777) (xy 180.619872 -398.703634)
			(xy 180.660021 -398.664925) (xy 180.705379 -398.632474) (xy 180.754979 -398.606973) (xy 180.807763 -398.588966)
			(xy 180.862606 -398.578836) (xy 180.91834 -398.576799) (xy 180.973777 -398.582899) (xy 181.027734 -398.597005)
			(xy 181.079063 -398.618817) (xy 181.126669 -398.647871) (xy 181.169537 -398.683546) (xy 181.206754 -398.725083)
			(xy 181.237527 -398.771596) (xy 181.261199 -398.822093) (xy 181.277267 -398.8755) (xy 181.285387 -398.930676)
			(xy 181.285896 -398.958562) (xy 181.285387 -398.986448) (xy 181.277267 -399.041624) (xy 181.261199 -399.095031)
			(xy 181.237527 -399.145528) (xy 181.206754 -399.192041) (xy 181.169537 -399.233578) (xy 181.126669 -399.269253)
			(xy 181.079063 -399.298307) (xy 181.027734 -399.320119) (xy 180.973777 -399.334225) (xy 180.91834 -399.340325)
			(xy 180.862606 -399.338288) (xy 180.807763 -399.328158) (xy 180.754979 -399.310151) (xy 180.705379 -399.28465)
			(xy 180.660021 -399.252199) (xy 180.619872 -399.21349) (xy 180.585786 -399.169347) (xy 180.55849 -399.120712)
			(xy 180.538567 -399.068621) (xy 180.526441 -399.014184) (xy 180.52237 -398.958562) (xy 177.880518 -398.958562)
			(xy 177.57648 -399.2626) (xy 177.57648 -400.250755) (xy 180.238837 -400.250755) (xy 180.238837 -400.196245)
			(xy 180.246594 -400.142291) (xy 180.261952 -400.08999) (xy 180.284596 -400.040407) (xy 180.314066 -399.994551)
			(xy 180.349762 -399.953357) (xy 180.390958 -399.917661) (xy 180.436814 -399.888192) (xy 180.486398 -399.865549)
			(xy 180.538699 -399.850193) (xy 180.592653 -399.842436) (xy 180.619908 -399.841974) (xy 180.645036 -399.842382)
			(xy 180.694858 -399.848982) (xy 180.743382 -399.862066) (xy 180.789768 -399.881407) (xy 180.833213 -399.906672)
			(xy 180.853334 -399.92173) (xy 180.864458 -399.929706) (xy 180.88974 -399.940152) (xy 180.916889 -399.943504)
			(xy 180.943953 -399.93952) (xy 180.968985 -399.928488) (xy 180.990185 -399.911201) (xy 181.006029 -399.888901)
			(xy 181.015377 -399.863193) (xy 181.01691 -399.849594) (xy 181.01967 -399.821296) (xy 181.03265 -399.76594)
			(xy 181.053702 -399.713124) (xy 181.082358 -399.664017) (xy 181.117986 -399.619706) (xy 181.159794 -399.581173)
			(xy 181.206858 -399.549271) (xy 181.258136 -399.524707) (xy 181.312491 -399.508025) (xy 181.368719 -399.499595)
			(xy 181.397148 -399.499074) (xy 181.425808 -399.499602) (xy 181.48248 -399.50819) (xy 181.537233 -399.52515)
			(xy 181.588836 -399.550102) (xy 181.636131 -399.582486) (xy 181.678056 -399.621573) (xy 181.713668 -399.666487)
			(xy 181.728364 -399.691098) (xy 181.736191 -399.703693) (xy 181.757705 -399.724083) (xy 181.784166 -399.73744)
			(xy 181.813347 -399.742642) (xy 181.842793 -399.73925) (xy 181.870027 -399.72755) (xy 181.892758 -399.708527)
			(xy 181.901338 -399.696432) (xy 181.916539 -399.67415) (xy 181.952215 -399.633696) (xy 181.993235 -399.598671)
			(xy 182.038779 -399.569774) (xy 182.087941 -399.547582) (xy 182.139738 -399.532538) (xy 182.193139 -399.52494)
			(xy 182.220108 -399.524474) (xy 182.247358 -399.524997) (xy 182.301302 -399.532754) (xy 182.353593 -399.548109)
			(xy 182.403167 -399.570749) (xy 182.449014 -399.600214) (xy 182.490201 -399.635904) (xy 182.52589 -399.677092)
			(xy 182.555354 -399.72294) (xy 182.577994 -399.772514) (xy 182.593348 -399.824806) (xy 182.593698 -399.827242)
			(xy 183.49925 -399.827242) (xy 183.503321 -399.77162) (xy 183.515447 -399.717183) (xy 183.53537 -399.665092)
			(xy 183.562666 -399.616457) (xy 183.596752 -399.572314) (xy 183.636901 -399.533605) (xy 183.682259 -399.501154)
			(xy 183.731859 -399.475653) (xy 183.784643 -399.457646) (xy 183.839486 -399.447516) (xy 183.89522 -399.445479)
			(xy 183.950657 -399.451579) (xy 184.004614 -399.465685) (xy 184.055943 -399.487497) (xy 184.103549 -399.516551)
			(xy 184.146417 -399.552226) (xy 184.183634 -399.593763) (xy 184.214407 -399.640276) (xy 184.238079 -399.690773)
			(xy 184.254147 -399.74418) (xy 184.262267 -399.799356) (xy 184.262776 -399.827242) (xy 184.262267 -399.855128)
			(xy 184.254147 -399.910304) (xy 184.238079 -399.963711) (xy 184.214407 -400.014208) (xy 184.183634 -400.060721)
			(xy 184.146417 -400.102258) (xy 184.103549 -400.137933) (xy 184.055943 -400.166987) (xy 184.004614 -400.188799)
			(xy 183.950657 -400.202905) (xy 183.89522 -400.209005) (xy 183.839486 -400.206968) (xy 183.784643 -400.196838)
			(xy 183.731859 -400.178831) (xy 183.682259 -400.15333) (xy 183.636901 -400.120879) (xy 183.596752 -400.08217)
			(xy 183.562666 -400.038027) (xy 183.53537 -399.989392) (xy 183.515447 -399.937301) (xy 183.503321 -399.882864)
			(xy 183.49925 -399.827242) (xy 182.593698 -399.827242) (xy 182.601104 -399.87875) (xy 182.601104 -399.93325)
			(xy 182.593348 -399.987194) (xy 182.577994 -400.039486) (xy 182.555354 -400.08906) (xy 182.52589 -400.134908)
			(xy 182.490201 -400.176096) (xy 182.449014 -400.211786) (xy 182.403167 -400.241251) (xy 182.353593 -400.263891)
			(xy 182.301302 -400.279246) (xy 182.247358 -400.287003) (xy 182.220108 -400.28749) (xy 182.191449 -400.286936)
			(xy 182.134777 -400.278355) (xy 182.080024 -400.261401) (xy 182.02842 -400.236454) (xy 181.981124 -400.204074)
			(xy 181.939199 -400.164988) (xy 181.903587 -400.120076) (xy 181.888892 -400.095466) (xy 181.881126 -400.082826)
			(xy 181.859603 -400.062422) (xy 181.833129 -400.049057) (xy 181.803931 -400.043856) (xy 181.77447 -400.047258)
			(xy 181.747226 -400.058977) (xy 181.724494 -400.078025) (xy 181.715918 -400.090132) (xy 181.700734 -400.112426)
			(xy 181.665056 -400.152882) (xy 181.624034 -400.187907) (xy 181.578487 -400.216803) (xy 181.529322 -400.238993)
			(xy 181.477521 -400.254034) (xy 181.424118 -400.261627) (xy 181.397148 -400.26209) (xy 181.372019 -400.261693)
			(xy 181.322198 -400.255088) (xy 181.273674 -400.242001) (xy 181.227288 -400.222658) (xy 181.183843 -400.197392)
			(xy 181.163722 -400.182334) (xy 181.152662 -400.17426) (xy 181.127361 -400.163808) (xy 181.100193 -400.160458)
			(xy 181.073111 -400.16445) (xy 181.048064 -400.175498) (xy 181.026856 -400.192806) (xy 181.011012 -400.215129)
			(xy 181.001671 -400.240861) (xy 181.000146 -400.25447) (xy 180.997301 -400.282758) (xy 180.984328 -400.338108)
			(xy 180.963285 -400.39092) (xy 180.934638 -400.440025) (xy 180.89902 -400.484335) (xy 180.857222 -400.522868)
			(xy 180.810168 -400.554772) (xy 180.7589 -400.57934) (xy 180.704554 -400.596028) (xy 180.648333 -400.604465)
			(xy 180.619908 -400.60499) (xy 180.592653 -400.604564) (xy 180.538699 -400.596807) (xy 180.486398 -400.581451)
			(xy 180.436814 -400.558808) (xy 180.390958 -400.529339) (xy 180.349762 -400.493643) (xy 180.314066 -400.452449)
			(xy 180.284596 -400.406593) (xy 180.261952 -400.35701) (xy 180.246594 -400.304709) (xy 180.238837 -400.250755)
			(xy 177.57648 -400.250755) (xy 177.57648 -401.239482) (xy 180.73319 -401.239482) (xy 180.737261 -401.18386)
			(xy 180.749387 -401.129423) (xy 180.76931 -401.077332) (xy 180.796606 -401.028697) (xy 180.830692 -400.984554)
			(xy 180.870841 -400.945845) (xy 180.916199 -400.913394) (xy 180.965799 -400.887893) (xy 181.018583 -400.869886)
			(xy 181.073426 -400.859756) (xy 181.12916 -400.857719) (xy 181.184597 -400.863819) (xy 181.238554 -400.877925)
			(xy 181.289883 -400.899737) (xy 181.337489 -400.928791) (xy 181.380357 -400.964466) (xy 181.417574 -401.006003)
			(xy 181.448347 -401.052516) (xy 181.472019 -401.103013) (xy 181.488087 -401.15642) (xy 181.496207 -401.211596)
			(xy 181.496716 -401.239482) (xy 181.496207 -401.267368) (xy 181.488087 -401.322544) (xy 181.472019 -401.375951)
			(xy 181.448347 -401.426448) (xy 181.417574 -401.472961) (xy 181.380357 -401.514498) (xy 181.337489 -401.550173)
			(xy 181.289883 -401.579227) (xy 181.238554 -401.601039) (xy 181.184597 -401.615145) (xy 181.12916 -401.621245)
			(xy 181.073426 -401.619208) (xy 181.018583 -401.609078) (xy 180.965799 -401.591071) (xy 180.916199 -401.56557)
			(xy 180.870841 -401.533119) (xy 180.830692 -401.49441) (xy 180.796606 -401.450267) (xy 180.76931 -401.401632)
			(xy 180.749387 -401.349541) (xy 180.737261 -401.295104) (xy 180.73319 -401.239482) (xy 177.57648 -401.239482)
			(xy 177.57648 -402.255482) (xy 177.95443 -402.255482) (xy 177.958501 -402.19986) (xy 177.970627 -402.145423)
			(xy 177.99055 -402.093332) (xy 178.017846 -402.044697) (xy 178.051932 -402.000554) (xy 178.092081 -401.961845)
			(xy 178.137439 -401.929394) (xy 178.187039 -401.903893) (xy 178.239823 -401.885886) (xy 178.294666 -401.875756)
			(xy 178.3504 -401.873719) (xy 178.395304 -401.87866) (xy 183.125023 -401.87866) (xy 183.125023 -401.824148)
			(xy 183.13278 -401.770191) (xy 183.148138 -401.717888) (xy 183.170783 -401.668302) (xy 183.200254 -401.622444)
			(xy 183.235952 -401.581247) (xy 183.277149 -401.54555) (xy 183.323008 -401.51608) (xy 183.372593 -401.493436)
			(xy 183.424897 -401.478079) (xy 183.478854 -401.470322) (xy 183.50611 -401.46986) (xy 183.52643 -401.470368)
			(xy 183.540635 -401.470587) (xy 183.568303 -401.464213) (xy 183.593141 -401.450457) (xy 183.613224 -401.430385)
			(xy 183.626993 -401.405555) (xy 183.633382 -401.37789) (xy 183.63311 -401.363688) (xy 183.632602 -401.343368)
			(xy 183.633088 -401.316117) (xy 183.640844 -401.262169) (xy 183.656199 -401.209874) (xy 183.678841 -401.160297)
			(xy 183.708307 -401.114447) (xy 183.743998 -401.073256) (xy 183.785189 -401.037565) (xy 183.831039 -401.008099)
			(xy 183.880616 -400.985457) (xy 183.932911 -400.970102) (xy 183.986859 -400.962346) (xy 184.041361 -400.962346)
			(xy 184.095309 -400.970102) (xy 184.147604 -400.985457) (xy 184.197181 -401.008099) (xy 184.243031 -401.037565)
			(xy 184.284222 -401.073256) (xy 184.319913 -401.114447) (xy 184.349379 -401.160297) (xy 184.372021 -401.209874)
			(xy 184.387376 -401.262169) (xy 184.395132 -401.316117) (xy 184.395618 -401.343368) (xy 184.39511 -401.363688)
			(xy 184.39486 -401.377892) (xy 184.401247 -401.405559) (xy 184.408871 -401.419314) (xy 185.10961 -401.419314)
			(xy 185.113681 -401.363692) (xy 185.125807 -401.309255) (xy 185.14573 -401.257164) (xy 185.173026 -401.208529)
			(xy 185.207112 -401.164386) (xy 185.247261 -401.125677) (xy 185.292619 -401.093226) (xy 185.342219 -401.067725)
			(xy 185.395003 -401.049718) (xy 185.449846 -401.039588) (xy 185.50558 -401.037551) (xy 185.561017 -401.043651)
			(xy 185.614974 -401.057757) (xy 185.666303 -401.079569) (xy 185.713909 -401.108623) (xy 185.756777 -401.144298)
			(xy 185.793994 -401.185835) (xy 185.824767 -401.232348) (xy 185.848439 -401.282845) (xy 185.864507 -401.336252)
			(xy 185.872627 -401.391428) (xy 185.873136 -401.419314) (xy 186.53201 -401.419314) (xy 186.536081 -401.363692)
			(xy 186.548207 -401.309255) (xy 186.56813 -401.257164) (xy 186.595426 -401.208529) (xy 186.629512 -401.164386)
			(xy 186.669661 -401.125677) (xy 186.715019 -401.093226) (xy 186.764619 -401.067725) (xy 186.817403 -401.049718)
			(xy 186.872246 -401.039588) (xy 186.92798 -401.037551) (xy 186.983417 -401.043651) (xy 187.037374 -401.057757)
			(xy 187.088703 -401.079569) (xy 187.136309 -401.108623) (xy 187.179177 -401.144298) (xy 187.216394 -401.185835)
			(xy 187.247167 -401.232348) (xy 187.270839 -401.282845) (xy 187.286907 -401.336252) (xy 187.289038 -401.350734)
			(xy 187.92901 -401.350734) (xy 187.933081 -401.295112) (xy 187.945207 -401.240675) (xy 187.96513 -401.188584)
			(xy 187.992426 -401.139949) (xy 188.026512 -401.095806) (xy 188.066661 -401.057097) (xy 188.112019 -401.024646)
			(xy 188.161619 -400.999145) (xy 188.214403 -400.981138) (xy 188.269246 -400.971008) (xy 188.32498 -400.968971)
			(xy 188.380417 -400.975071) (xy 188.434374 -400.989177) (xy 188.485703 -401.010989) (xy 188.533309 -401.040043)
			(xy 188.571519 -401.071842) (xy 190.01943 -401.071842) (xy 190.023501 -401.01622) (xy 190.035627 -400.961783)
			(xy 190.05555 -400.909692) (xy 190.082846 -400.861057) (xy 190.116932 -400.816914) (xy 190.157081 -400.778205)
			(xy 190.202439 -400.745754) (xy 190.252039 -400.720253) (xy 190.304823 -400.702246) (xy 190.359666 -400.692116)
			(xy 190.4154 -400.690079) (xy 190.470837 -400.696179) (xy 190.524794 -400.710285) (xy 190.576123 -400.732097)
			(xy 190.623729 -400.761151) (xy 190.666597 -400.796826) (xy 190.703814 -400.838363) (xy 190.734587 -400.884876)
			(xy 190.758259 -400.935373) (xy 190.774327 -400.98878) (xy 190.782447 -401.043956) (xy 190.782956 -401.071842)
			(xy 190.782447 -401.099728) (xy 190.78057 -401.112482) (xy 192.68643 -401.112482) (xy 192.690501 -401.05686)
			(xy 192.702627 -401.002423) (xy 192.72255 -400.950332) (xy 192.749846 -400.901697) (xy 192.783932 -400.857554)
			(xy 192.824081 -400.818845) (xy 192.869439 -400.786394) (xy 192.919039 -400.760893) (xy 192.971823 -400.742886)
			(xy 193.026666 -400.732756) (xy 193.0824 -400.730719) (xy 193.137837 -400.736819) (xy 193.191794 -400.750925)
			(xy 193.243123 -400.772737) (xy 193.290729 -400.801791) (xy 193.333597 -400.837466) (xy 193.370814 -400.879003)
			(xy 193.401587 -400.925516) (xy 193.425259 -400.976013) (xy 193.441327 -401.02942) (xy 193.449447 -401.084596)
			(xy 193.449956 -401.112482) (xy 193.449447 -401.140368) (xy 193.441327 -401.195544) (xy 193.425259 -401.248951)
			(xy 193.401587 -401.299448) (xy 193.370814 -401.345961) (xy 193.333597 -401.387498) (xy 193.290729 -401.423173)
			(xy 193.243123 -401.452227) (xy 193.191794 -401.474039) (xy 193.137837 -401.488145) (xy 193.0824 -401.494245)
			(xy 193.026666 -401.492208) (xy 192.971823 -401.482078) (xy 192.919039 -401.464071) (xy 192.869439 -401.43857)
			(xy 192.824081 -401.406119) (xy 192.783932 -401.36741) (xy 192.749846 -401.323267) (xy 192.72255 -401.274632)
			(xy 192.702627 -401.222541) (xy 192.690501 -401.168104) (xy 192.68643 -401.112482) (xy 190.78057 -401.112482)
			(xy 190.774327 -401.154904) (xy 190.758259 -401.208311) (xy 190.734587 -401.258808) (xy 190.703814 -401.305321)
			(xy 190.666597 -401.346858) (xy 190.623729 -401.382533) (xy 190.576123 -401.411587) (xy 190.524794 -401.433399)
			(xy 190.470837 -401.447505) (xy 190.4154 -401.453605) (xy 190.359666 -401.451568) (xy 190.304823 -401.441438)
			(xy 190.252039 -401.423431) (xy 190.202439 -401.39793) (xy 190.157081 -401.365479) (xy 190.116932 -401.32677)
			(xy 190.082846 -401.282627) (xy 190.05555 -401.233992) (xy 190.035627 -401.181901) (xy 190.023501 -401.127464)
			(xy 190.01943 -401.071842) (xy 188.571519 -401.071842) (xy 188.576177 -401.075718) (xy 188.613394 -401.117255)
			(xy 188.644167 -401.163768) (xy 188.667839 -401.214265) (xy 188.683907 -401.267672) (xy 188.692027 -401.322848)
			(xy 188.692536 -401.350734) (xy 188.692027 -401.37862) (xy 188.683907 -401.433796) (xy 188.667839 -401.487203)
			(xy 188.644167 -401.5377) (xy 188.613394 -401.584213) (xy 188.576177 -401.62575) (xy 188.533309 -401.661425)
			(xy 188.485703 -401.690479) (xy 188.434374 -401.712291) (xy 188.380417 -401.726397) (xy 188.32498 -401.732497)
			(xy 188.269246 -401.73046) (xy 188.214403 -401.72033) (xy 188.161619 -401.702323) (xy 188.112019 -401.676822)
			(xy 188.066661 -401.644371) (xy 188.026512 -401.605662) (xy 187.992426 -401.561519) (xy 187.96513 -401.512884)
			(xy 187.945207 -401.460793) (xy 187.933081 -401.406356) (xy 187.92901 -401.350734) (xy 187.289038 -401.350734)
			(xy 187.295027 -401.391428) (xy 187.295536 -401.419314) (xy 187.295027 -401.4472) (xy 187.286907 -401.502376)
			(xy 187.270839 -401.555783) (xy 187.247167 -401.60628) (xy 187.216394 -401.652793) (xy 187.179177 -401.69433)
			(xy 187.136309 -401.730005) (xy 187.088703 -401.759059) (xy 187.037374 -401.780871) (xy 186.983417 -401.794977)
			(xy 186.92798 -401.801077) (xy 186.872246 -401.79904) (xy 186.817403 -401.78891) (xy 186.764619 -401.770903)
			(xy 186.715019 -401.745402) (xy 186.669661 -401.712951) (xy 186.629512 -401.674242) (xy 186.595426 -401.630099)
			(xy 186.56813 -401.581464) (xy 186.548207 -401.529373) (xy 186.536081 -401.474936) (xy 186.53201 -401.419314)
			(xy 185.873136 -401.419314) (xy 185.872627 -401.4472) (xy 185.864507 -401.502376) (xy 185.848439 -401.555783)
			(xy 185.824767 -401.60628) (xy 185.793994 -401.652793) (xy 185.756777 -401.69433) (xy 185.713909 -401.730005)
			(xy 185.666303 -401.759059) (xy 185.614974 -401.780871) (xy 185.561017 -401.794977) (xy 185.50558 -401.801077)
			(xy 185.449846 -401.79904) (xy 185.395003 -401.78891) (xy 185.342219 -401.770903) (xy 185.292619 -401.745402)
			(xy 185.247261 -401.712951) (xy 185.207112 -401.674242) (xy 185.173026 -401.630099) (xy 185.14573 -401.581464)
			(xy 185.125807 -401.529373) (xy 185.113681 -401.474936) (xy 185.10961 -401.419314) (xy 184.408871 -401.419314)
			(xy 184.415012 -401.430395) (xy 184.435088 -401.450476) (xy 184.459921 -401.464245) (xy 184.487587 -401.470638)
			(xy 184.50179 -401.470368) (xy 184.52211 -401.46986) (xy 184.549362 -401.470366) (xy 184.603312 -401.478124)
			(xy 184.655609 -401.493482) (xy 184.705188 -401.516126) (xy 184.751039 -401.545595) (xy 184.79223 -401.581289)
			(xy 184.827922 -401.622483) (xy 184.857388 -401.668336) (xy 184.880028 -401.717917) (xy 184.895381 -401.770214)
			(xy 184.903136 -401.824165) (xy 184.903133 -401.87867) (xy 184.895374 -401.93262) (xy 184.880016 -401.984916)
			(xy 184.857371 -402.034494) (xy 184.827901 -402.080345) (xy 184.821404 -402.087842) (xy 190.01994 -402.087842)
			(xy 190.020426 -402.060591) (xy 190.028182 -402.006643) (xy 190.043537 -401.954348) (xy 190.066179 -401.904771)
			(xy 190.095645 -401.858921) (xy 190.131336 -401.81773) (xy 190.172527 -401.782039) (xy 190.218377 -401.752573)
			(xy 190.267954 -401.729931) (xy 190.320249 -401.714576) (xy 190.374197 -401.70682) (xy 190.428699 -401.70682)
			(xy 190.482647 -401.714576) (xy 190.534942 -401.729931) (xy 190.584519 -401.752573) (xy 190.630369 -401.782039)
			(xy 190.67156 -401.81773) (xy 190.707251 -401.858921) (xy 190.736717 -401.904771) (xy 190.759359 -401.954348)
			(xy 190.774714 -402.006643) (xy 190.78247 -402.060591) (xy 190.782956 -402.087842) (xy 190.782413 -402.117414)
			(xy 190.773294 -402.175851) (xy 190.755264 -402.23218) (xy 190.728757 -402.285051) (xy 190.694407 -402.333198)
			(xy 190.653038 -402.375467) (xy 190.605641 -402.410843) (xy 190.579756 -402.425154) (xy 190.567631 -402.432101)
			(xy 190.547352 -402.451305) (xy 190.53304 -402.475288) (xy 190.525765 -402.502253) (xy 190.526074 -402.530181)
			(xy 190.533942 -402.556979) (xy 190.548781 -402.580639) (xy 190.56948 -402.599391) (xy 190.581788 -402.606002)
			(xy 190.605265 -402.618167) (xy 190.648886 -402.648055) (xy 190.687958 -402.683684) (xy 190.721733 -402.724369)
			(xy 190.749563 -402.76933) (xy 190.770913 -402.817706) (xy 190.785375 -402.868567) (xy 190.79267 -402.920939)
			(xy 190.793116 -402.947378) (xy 190.79263 -402.974629) (xy 190.784874 -403.028577) (xy 190.769519 -403.080872)
			(xy 190.746877 -403.130449) (xy 190.717411 -403.176299) (xy 190.68172 -403.21749) (xy 190.640529 -403.253181)
			(xy 190.594679 -403.282647) (xy 190.545102 -403.305289) (xy 190.492807 -403.320644) (xy 190.438859 -403.3284)
			(xy 190.384357 -403.3284) (xy 190.330409 -403.320644) (xy 190.278114 -403.305289) (xy 190.228537 -403.282647)
			(xy 190.182687 -403.253181) (xy 190.141496 -403.21749) (xy 190.105805 -403.176299) (xy 190.076339 -403.130449)
			(xy 190.053697 -403.080872) (xy 190.038342 -403.028577) (xy 190.030586 -402.974629) (xy 190.0301 -402.947378)
			(xy 190.03063 -402.917805) (xy 190.039748 -402.859366) (xy 190.057777 -402.803035) (xy 190.084286 -402.750163)
			(xy 190.118639 -402.702016) (xy 190.160012 -402.659749) (xy 190.207413 -402.624375) (xy 190.2333 -402.610066)
			(xy 190.245491 -402.603231) (xy 190.265766 -402.584002) (xy 190.280071 -402.559999) (xy 190.287337 -402.533017)
			(xy 190.287018 -402.505075) (xy 190.279139 -402.478266) (xy 190.26429 -402.454595) (xy 190.243582 -402.435833)
			(xy 190.231268 -402.429218) (xy 190.207812 -402.417013) (xy 190.164189 -402.387133) (xy 190.125114 -402.351512)
			(xy 190.091337 -402.310833) (xy 190.063504 -402.265876) (xy 190.04215 -402.217506) (xy 190.027685 -402.166648)
			(xy 190.020387 -402.114279) (xy 190.01994 -402.087842) (xy 184.821404 -402.087842) (xy 184.792206 -402.121535)
			(xy 184.751011 -402.157226) (xy 184.705157 -402.186691) (xy 184.655577 -402.20933) (xy 184.603278 -402.224683)
			(xy 184.549328 -402.232436) (xy 184.494823 -402.232433) (xy 184.440873 -402.224672) (xy 184.388577 -402.209313)
			(xy 184.338999 -402.186667) (xy 184.293149 -402.157197) (xy 184.251959 -402.1215) (xy 184.216269 -402.080306)
			(xy 184.186805 -402.034451) (xy 184.164167 -401.98487) (xy 184.148815 -401.932571) (xy 184.141063 -401.878621)
			(xy 184.140602 -401.851368) (xy 184.14111 -401.831048) (xy 184.14141 -401.816841) (xy 184.135026 -401.789161)
			(xy 184.121256 -401.764316) (xy 184.101168 -401.744231) (xy 184.076319 -401.730466) (xy 184.048638 -401.724088)
			(xy 184.03443 -401.724368) (xy 184.01411 -401.724876) (xy 183.99379 -401.724368) (xy 183.979584 -401.724037)
			(xy 183.951905 -401.730434) (xy 183.927062 -401.744213) (xy 183.90698 -401.764306) (xy 183.893214 -401.789156)
			(xy 183.886832 -401.816839) (xy 183.88711 -401.831048) (xy 183.887618 -401.851368) (xy 183.887179 -401.878624)
			(xy 183.879426 -401.932581) (xy 183.864072 -401.984886) (xy 183.841431 -402.034473) (xy 183.811963 -402.080333)
			(xy 183.776268 -402.121533) (xy 183.735073 -402.157233) (xy 183.689217 -402.186707) (xy 183.639633 -402.209355)
			(xy 183.58733 -402.224715) (xy 183.533374 -402.232476) (xy 183.478862 -402.232478) (xy 183.424905 -402.224723)
			(xy 183.372601 -402.209367) (xy 183.323015 -402.186724) (xy 183.277156 -402.157255) (xy 183.235957 -402.121558)
			(xy 183.200259 -402.080362) (xy 183.170786 -402.034505) (xy 183.14814 -401.98492) (xy 183.132782 -401.932616)
			(xy 183.125023 -401.87866) (xy 178.395304 -401.87866) (xy 178.405837 -401.879819) (xy 178.459794 -401.893925)
			(xy 178.511123 -401.915737) (xy 178.558729 -401.944791) (xy 178.601597 -401.980466) (xy 178.638814 -402.022003)
			(xy 178.669587 -402.068516) (xy 178.693259 -402.119013) (xy 178.709327 -402.17242) (xy 178.717447 -402.227596)
			(xy 178.717956 -402.255482) (xy 178.717447 -402.283368) (xy 178.709327 -402.338544) (xy 178.693259 -402.391951)
			(xy 178.669587 -402.442448) (xy 178.638814 -402.488961) (xy 178.601597 -402.530498) (xy 178.558729 -402.566173)
			(xy 178.511123 -402.595227) (xy 178.459794 -402.617039) (xy 178.405837 -402.631145) (xy 178.3504 -402.637245)
			(xy 178.294666 -402.635208) (xy 178.239823 -402.625078) (xy 178.187039 -402.607071) (xy 178.137439 -402.58157)
			(xy 178.092081 -402.549119) (xy 178.051932 -402.51041) (xy 178.017846 -402.466267) (xy 177.99055 -402.417632)
			(xy 177.970627 -402.365541) (xy 177.958501 -402.311104) (xy 177.95443 -402.255482) (xy 177.57648 -402.255482)
			(xy 177.57648 -405.303482) (xy 177.95443 -405.303482) (xy 177.958501 -405.24786) (xy 177.970627 -405.193423)
			(xy 177.99055 -405.141332) (xy 178.017846 -405.092697) (xy 178.051932 -405.048554) (xy 178.092081 -405.009845)
			(xy 178.137439 -404.977394) (xy 178.187039 -404.951893) (xy 178.239823 -404.933886) (xy 178.294666 -404.923756)
			(xy 178.3504 -404.921719) (xy 178.405837 -404.927819) (xy 178.459794 -404.941925) (xy 178.511123 -404.963737)
			(xy 178.558729 -404.992791) (xy 178.601597 -405.028466) (xy 178.638814 -405.070003) (xy 178.669587 -405.116516)
			(xy 178.693259 -405.167013) (xy 178.709327 -405.22042) (xy 178.717447 -405.275596) (xy 178.717956 -405.303482)
			(xy 178.717447 -405.331368) (xy 178.709327 -405.386544) (xy 178.693259 -405.439951) (xy 178.669587 -405.490448)
			(xy 178.638814 -405.536961) (xy 178.601597 -405.578498) (xy 178.558729 -405.614173) (xy 178.511123 -405.643227)
			(xy 178.459794 -405.665039) (xy 178.405837 -405.679145) (xy 178.3504 -405.685245) (xy 178.294666 -405.683208)
			(xy 178.239823 -405.673078) (xy 178.187039 -405.655071) (xy 178.137439 -405.62957) (xy 178.092081 -405.597119)
			(xy 178.051932 -405.55841) (xy 178.017846 -405.514267) (xy 177.99055 -405.465632) (xy 177.970627 -405.413541)
			(xy 177.958501 -405.359104) (xy 177.95443 -405.303482) (xy 177.57648 -405.303482) (xy 177.57648 -407.67762)
			(xy 178.365912 -408.467052) (xy 179.1208 -407.712164) (xy 179.1208 -406.60447) (xy 179.120311 -406.589803)
			(xy 179.111968 -406.561679) (xy 179.095978 -406.537086) (xy 179.073659 -406.518049) (xy 179.046851 -406.506139)
			(xy 179.017763 -406.502336) (xy 179.003198 -406.50414) (xy 178.988061 -406.506416) (xy 178.957544 -406.508833)
			(xy 178.942238 -406.508966) (xy 178.914986 -406.508505) (xy 178.861037 -406.500754) (xy 178.808741 -406.485403)
			(xy 178.759161 -406.462765) (xy 178.713308 -406.433301) (xy 178.672116 -406.397611) (xy 178.636422 -406.356422)
			(xy 178.606953 -406.310572) (xy 178.584311 -406.260995) (xy 178.568954 -406.2087) (xy 178.561197 -406.154752)
			(xy 178.561197 -406.100248) (xy 178.568954 -406.0463) (xy 178.584311 -405.994005) (xy 178.606953 -405.944428)
			(xy 178.636422 -405.898578) (xy 178.672116 -405.857389) (xy 178.713308 -405.821699) (xy 178.759161 -405.792235)
			(xy 178.808741 -405.769597) (xy 178.861037 -405.754246) (xy 178.914986 -405.746495) (xy 178.942238 -405.74595)
			(xy 178.957544 -405.746081) (xy 178.988062 -405.748497) (xy 179.003198 -405.750776) (xy 179.017763 -405.752607)
			(xy 179.04686 -405.748804) (xy 179.073677 -405.736891) (xy 179.096005 -405.717849) (xy 179.112003 -405.693249)
			(xy 179.120352 -405.665118) (xy 179.1208 -405.650446) (xy 179.1208 -404.278592) (xy 179.1213 -404.252612)
			(xy 179.129466 -404.201296) (xy 179.145563 -404.151891) (xy 179.169196 -404.105614) (xy 179.19978 -404.063607)
			(xy 179.217828 -404.044912) (xy 180.1368 -403.12594) (xy 180.155521 -403.107926) (xy 180.197535 -403.077369)
			(xy 180.243808 -403.053752) (xy 180.293202 -403.037655) (xy 180.344505 -403.029473) (xy 180.37048 -403.028912)
			(xy 180.694076 -403.028912) (xy 180.708027 -403.02848) (xy 180.73489 -403.020936) (xy 180.758708 -403.006403)
			(xy 180.777705 -402.985966) (xy 180.790462 -402.961151) (xy 180.796027 -402.933809) (xy 180.793985 -402.905982)
			(xy 180.784488 -402.879746) (xy 180.768246 -402.857059) (xy 180.757576 -402.848064) (xy 180.735646 -402.829845)
			(xy 180.696919 -402.788007) (xy 180.664848 -402.740872) (xy 180.640147 -402.689489) (xy 180.623367 -402.635003)
			(xy 180.614881 -402.578628) (xy 180.61432 -402.550122) (xy 180.614806 -402.522871) (xy 180.622562 -402.468923)
			(xy 180.637917 -402.416628) (xy 180.660559 -402.367051) (xy 180.690025 -402.321201) (xy 180.725716 -402.28001)
			(xy 180.766907 -402.244319) (xy 180.812757 -402.214853) (xy 180.862334 -402.192211) (xy 180.914629 -402.176856)
			(xy 180.968577 -402.1691) (xy 181.023079 -402.1691) (xy 181.077027 -402.176856) (xy 181.129322 -402.192211)
			(xy 181.178899 -402.214853) (xy 181.224749 -402.244319) (xy 181.26594 -402.28001) (xy 181.301631 -402.321201)
			(xy 181.331097 -402.367051) (xy 181.353739 -402.416628) (xy 181.369094 -402.468923) (xy 181.37685 -402.522871)
			(xy 181.377336 -402.550122) (xy 181.376853 -402.577721) (xy 181.368906 -402.632343) (xy 181.353167 -402.685248)
			(xy 181.335986 -402.722334) (xy 185.10961 -402.722334) (xy 185.113681 -402.666712) (xy 185.125807 -402.612275)
			(xy 185.14573 -402.560184) (xy 185.173026 -402.511549) (xy 185.207112 -402.467406) (xy 185.247261 -402.428697)
			(xy 185.292619 -402.396246) (xy 185.342219 -402.370745) (xy 185.395003 -402.352738) (xy 185.449846 -402.342608)
			(xy 185.50558 -402.340571) (xy 185.561017 -402.346671) (xy 185.614974 -402.360777) (xy 185.666303 -402.382589)
			(xy 185.713909 -402.411643) (xy 185.756777 -402.447318) (xy 185.793994 -402.488855) (xy 185.824767 -402.535368)
			(xy 185.848439 -402.585865) (xy 185.864507 -402.639272) (xy 185.866638 -402.653754) (xy 187.92901 -402.653754)
			(xy 187.933081 -402.598132) (xy 187.945207 -402.543695) (xy 187.96513 -402.491604) (xy 187.992426 -402.442969)
			(xy 188.026512 -402.398826) (xy 188.066661 -402.360117) (xy 188.112019 -402.327666) (xy 188.161619 -402.302165)
			(xy 188.214403 -402.284158) (xy 188.269246 -402.274028) (xy 188.32498 -402.271991) (xy 188.380417 -402.278091)
			(xy 188.434374 -402.292197) (xy 188.485703 -402.314009) (xy 188.533309 -402.343063) (xy 188.576177 -402.378738)
			(xy 188.613394 -402.420275) (xy 188.644167 -402.466788) (xy 188.667839 -402.517285) (xy 188.683907 -402.570692)
			(xy 188.692027 -402.625868) (xy 188.692536 -402.653754) (xy 188.692027 -402.68164) (xy 188.683907 -402.736816)
			(xy 188.667839 -402.790223) (xy 188.644167 -402.84072) (xy 188.613394 -402.887233) (xy 188.576177 -402.92877)
			(xy 188.533309 -402.964445) (xy 188.485703 -402.993499) (xy 188.434374 -403.015311) (xy 188.380417 -403.029417)
			(xy 188.32498 -403.035517) (xy 188.269246 -403.03348) (xy 188.214403 -403.02335) (xy 188.161619 -403.005343)
			(xy 188.112019 -402.979842) (xy 188.066661 -402.947391) (xy 188.026512 -402.908682) (xy 187.992426 -402.864539)
			(xy 187.96513 -402.815904) (xy 187.945207 -402.763813) (xy 187.933081 -402.709376) (xy 187.92901 -402.653754)
			(xy 185.866638 -402.653754) (xy 185.872627 -402.694448) (xy 185.873136 -402.722334) (xy 185.872627 -402.75022)
			(xy 185.864507 -402.805396) (xy 185.848439 -402.858803) (xy 185.824767 -402.9093) (xy 185.793994 -402.955813)
			(xy 185.756777 -402.99735) (xy 185.713909 -403.033025) (xy 185.666303 -403.062079) (xy 185.614974 -403.083891)
			(xy 185.561017 -403.097997) (xy 185.50558 -403.104097) (xy 185.449846 -403.10206) (xy 185.395003 -403.09193)
			(xy 185.342219 -403.073923) (xy 185.292619 -403.048422) (xy 185.247261 -403.015971) (xy 185.207112 -402.977262)
			(xy 185.173026 -402.933119) (xy 185.14573 -402.884484) (xy 185.125807 -402.832393) (xy 185.113681 -402.777956)
			(xy 185.10961 -402.722334) (xy 181.335986 -402.722334) (xy 181.329965 -402.735332) (xy 181.299784 -402.781547)
			(xy 181.263256 -402.822928) (xy 181.221143 -402.85861) (xy 181.174326 -402.887848) (xy 181.149244 -402.899372)
			(xy 181.136789 -402.905359) (xy 181.115415 -402.922857) (xy 181.099513 -402.945445) (xy 181.090246 -402.971467)
			(xy 181.088292 -402.999022) (xy 181.093795 -403.026092) (xy 181.106352 -403.050696) (xy 181.125043 -403.071036)
			(xy 181.136544 -403.078696) (xy 181.152565 -403.088968) (xy 181.18236 -403.112648) (xy 181.19598 -403.12594)
			(xy 181.551326 -403.481032) (xy 181.563518 -403.484842) (xy 181.589259 -403.493163) (xy 181.638273 -403.516054)
			(xy 181.683563 -403.545639) (xy 181.72422 -403.581325) (xy 181.75943 -403.622394) (xy 181.788485 -403.668025)
			(xy 181.810805 -403.717303) (xy 181.825941 -403.769239) (xy 181.83359 -403.822792) (xy 181.834028 -403.84984)
			(xy 181.83354 -403.87709) (xy 181.825778 -403.931034) (xy 181.81042 -403.983325) (xy 181.791223 -404.025354)
			(xy 185.10961 -404.025354) (xy 185.113681 -403.969732) (xy 185.125807 -403.915295) (xy 185.14573 -403.863204)
			(xy 185.173026 -403.814569) (xy 185.207112 -403.770426) (xy 185.247261 -403.731717) (xy 185.292619 -403.699266)
			(xy 185.342219 -403.673765) (xy 185.395003 -403.655758) (xy 185.449846 -403.645628) (xy 185.50558 -403.643591)
			(xy 185.561017 -403.649691) (xy 185.614974 -403.663797) (xy 185.666303 -403.685609) (xy 185.713909 -403.714663)
			(xy 185.756777 -403.750338) (xy 185.793994 -403.791875) (xy 185.824767 -403.838388) (xy 185.848439 -403.888885)
			(xy 185.864507 -403.942292) (xy 185.872627 -403.997468) (xy 185.873136 -404.025354) (xy 186.53201 -404.025354)
			(xy 186.536081 -403.969732) (xy 186.548207 -403.915295) (xy 186.56813 -403.863204) (xy 186.595426 -403.814569)
			(xy 186.629512 -403.770426) (xy 186.669661 -403.731717) (xy 186.715019 -403.699266) (xy 186.764619 -403.673765)
			(xy 186.817403 -403.655758) (xy 186.872246 -403.645628) (xy 186.92798 -403.643591) (xy 186.983417 -403.649691)
			(xy 187.037374 -403.663797) (xy 187.088703 -403.685609) (xy 187.136309 -403.714663) (xy 187.179177 -403.750338)
			(xy 187.216394 -403.791875) (xy 187.247167 -403.838388) (xy 187.270839 -403.888885) (xy 187.286907 -403.942292)
			(xy 187.295027 -403.997468) (xy 187.295536 -404.025354) (xy 187.295351 -404.035514) (xy 187.92901 -404.035514)
			(xy 187.933081 -403.979892) (xy 187.945207 -403.925455) (xy 187.96513 -403.873364) (xy 187.992426 -403.824729)
			(xy 188.026512 -403.780586) (xy 188.066661 -403.741877) (xy 188.112019 -403.709426) (xy 188.161619 -403.683925)
			(xy 188.214403 -403.665918) (xy 188.269246 -403.655788) (xy 188.32498 -403.653751) (xy 188.380417 -403.659851)
			(xy 188.434374 -403.673957) (xy 188.485703 -403.695769) (xy 188.533309 -403.724823) (xy 188.576177 -403.760498)
			(xy 188.613394 -403.802035) (xy 188.644167 -403.848548) (xy 188.667839 -403.899045) (xy 188.683907 -403.952452)
			(xy 188.692027 -404.007628) (xy 188.692536 -404.035514) (xy 188.692341 -404.046182) (xy 190.03213 -404.046182)
			(xy 190.036201 -403.99056) (xy 190.048327 -403.936123) (xy 190.06825 -403.884032) (xy 190.095546 -403.835397)
			(xy 190.129632 -403.791254) (xy 190.169781 -403.752545) (xy 190.215139 -403.720094) (xy 190.264739 -403.694593)
			(xy 190.317523 -403.676586) (xy 190.372366 -403.666456) (xy 190.4281 -403.664419) (xy 190.483537 -403.670519)
			(xy 190.537494 -403.684625) (xy 190.588823 -403.706437) (xy 190.636429 -403.735491) (xy 190.679297 -403.771166)
			(xy 190.716514 -403.812703) (xy 190.747287 -403.859216) (xy 190.770959 -403.909713) (xy 190.787027 -403.96312)
			(xy 190.795147 -404.018296) (xy 190.795656 -404.046182) (xy 190.795147 -404.074068) (xy 190.787027 -404.129244)
			(xy 190.770959 -404.182651) (xy 190.747287 -404.233148) (xy 190.716514 -404.279661) (xy 190.679297 -404.321198)
			(xy 190.636429 -404.356873) (xy 190.588823 -404.385927) (xy 190.537494 -404.407739) (xy 190.483537 -404.421845)
			(xy 190.4281 -404.427945) (xy 190.372366 -404.425908) (xy 190.317523 -404.415778) (xy 190.264739 -404.397771)
			(xy 190.215139 -404.37227) (xy 190.169781 -404.339819) (xy 190.129632 -404.30111) (xy 190.095546 -404.256967)
			(xy 190.06825 -404.208332) (xy 190.048327 -404.156241) (xy 190.036201 -404.101804) (xy 190.03213 -404.046182)
			(xy 188.692341 -404.046182) (xy 188.692027 -404.0634) (xy 188.683907 -404.118576) (xy 188.667839 -404.171983)
			(xy 188.644167 -404.22248) (xy 188.613394 -404.268993) (xy 188.576177 -404.31053) (xy 188.533309 -404.346205)
			(xy 188.485703 -404.375259) (xy 188.434374 -404.397071) (xy 188.380417 -404.411177) (xy 188.32498 -404.417277)
			(xy 188.269246 -404.41524) (xy 188.214403 -404.40511) (xy 188.161619 -404.387103) (xy 188.112019 -404.361602)
			(xy 188.066661 -404.329151) (xy 188.026512 -404.290442) (xy 187.992426 -404.246299) (xy 187.96513 -404.197664)
			(xy 187.945207 -404.145573) (xy 187.933081 -404.091136) (xy 187.92901 -404.035514) (xy 187.295351 -404.035514)
			(xy 187.295027 -404.05324) (xy 187.286907 -404.108416) (xy 187.270839 -404.161823) (xy 187.247167 -404.21232)
			(xy 187.216394 -404.258833) (xy 187.179177 -404.30037) (xy 187.136309 -404.336045) (xy 187.088703 -404.365099)
			(xy 187.037374 -404.386911) (xy 186.983417 -404.401017) (xy 186.92798 -404.407117) (xy 186.872246 -404.40508)
			(xy 186.817403 -404.39495) (xy 186.764619 -404.376943) (xy 186.715019 -404.351442) (xy 186.669661 -404.318991)
			(xy 186.629512 -404.280282) (xy 186.595426 -404.236139) (xy 186.56813 -404.187504) (xy 186.548207 -404.135413)
			(xy 186.536081 -404.080976) (xy 186.53201 -404.025354) (xy 185.873136 -404.025354) (xy 185.872627 -404.05324)
			(xy 185.864507 -404.108416) (xy 185.848439 -404.161823) (xy 185.824767 -404.21232) (xy 185.793994 -404.258833)
			(xy 185.756777 -404.30037) (xy 185.713909 -404.336045) (xy 185.666303 -404.365099) (xy 185.614974 -404.386911)
			(xy 185.561017 -404.401017) (xy 185.50558 -404.407117) (xy 185.449846 -404.40508) (xy 185.395003 -404.39495)
			(xy 185.342219 -404.376943) (xy 185.292619 -404.351442) (xy 185.247261 -404.318991) (xy 185.207112 -404.280282)
			(xy 185.173026 -404.236139) (xy 185.14573 -404.187504) (xy 185.125807 -404.135413) (xy 185.113681 -404.080976)
			(xy 185.10961 -404.025354) (xy 181.791223 -404.025354) (xy 181.787777 -404.032899) (xy 181.75831 -404.078746)
			(xy 181.722619 -404.119933) (xy 181.68143 -404.155622) (xy 181.635581 -404.185087) (xy 181.586007 -404.207727)
			(xy 181.533715 -404.223083) (xy 181.47977 -404.230841) (xy 181.45252 -404.231348) (xy 181.425115 -404.230875)
			(xy 181.37087 -404.223029) (xy 181.318307 -404.207495) (xy 181.268511 -404.184595) (xy 181.222507 -404.1548)
			(xy 181.201568 -404.137114) (xy 181.190719 -404.128243) (xy 181.165396 -404.116264) (xy 181.137771 -404.111617)
			(xy 181.109922 -404.11465) (xy 181.083945 -404.125136) (xy 181.061794 -404.142286) (xy 181.045137 -404.164809)
			(xy 181.03977 -404.177754) (xy 181.028979 -404.204764) (xy 181.0004 -404.255419) (xy 180.964463 -404.30115)
			(xy 180.922001 -404.340896) (xy 180.873998 -404.373736) (xy 180.821566 -404.398909) (xy 180.793898 -404.407878)
			(xy 180.781706 -404.411688) (xy 180.685948 -404.507446) (xy 180.685948 -405.02586) (xy 180.686447 -405.04021)
			(xy 180.689137 -405.049482) (xy 190.01943 -405.049482) (xy 190.023501 -404.99386) (xy 190.035627 -404.939423)
			(xy 190.05555 -404.887332) (xy 190.082846 -404.838697) (xy 190.116932 -404.794554) (xy 190.157081 -404.755845)
			(xy 190.202439 -404.723394) (xy 190.252039 -404.697893) (xy 190.304823 -404.679886) (xy 190.359666 -404.669756)
			(xy 190.4154 -404.667719) (xy 190.470837 -404.673819) (xy 190.524794 -404.687925) (xy 190.576123 -404.709737)
			(xy 190.623729 -404.738791) (xy 190.666597 -404.774466) (xy 190.703814 -404.816003) (xy 190.734587 -404.862516)
			(xy 190.758259 -404.913013) (xy 190.774327 -404.96642) (xy 190.782447 -405.021596) (xy 190.782956 -405.049482)
			(xy 190.782447 -405.077368) (xy 190.778701 -405.102822) (xy 193.45859 -405.102822) (xy 193.462661 -405.0472)
			(xy 193.474787 -404.992763) (xy 193.49471 -404.940672) (xy 193.522006 -404.892037) (xy 193.556092 -404.847894)
			(xy 193.596241 -404.809185) (xy 193.641599 -404.776734) (xy 193.691199 -404.751233) (xy 193.743983 -404.733226)
			(xy 193.798826 -404.723096) (xy 193.85456 -404.721059) (xy 193.909997 -404.727159) (xy 193.963954 -404.741265)
			(xy 194.015283 -404.763077) (xy 194.062889 -404.792131) (xy 194.105757 -404.827806) (xy 194.142974 -404.869343)
			(xy 194.173747 -404.915856) (xy 194.197419 -404.966353) (xy 194.213487 -405.01976) (xy 194.221607 -405.074936)
			(xy 194.222116 -405.102822) (xy 194.221607 -405.130708) (xy 194.213487 -405.185884) (xy 194.197419 -405.239291)
			(xy 194.173747 -405.289788) (xy 194.142974 -405.336301) (xy 194.105757 -405.377838) (xy 194.062889 -405.413513)
			(xy 194.015283 -405.442567) (xy 193.963954 -405.464379) (xy 193.909997 -405.478485) (xy 193.85456 -405.484585)
			(xy 193.798826 -405.482548) (xy 193.743983 -405.472418) (xy 193.691199 -405.454411) (xy 193.641599 -405.42891)
			(xy 193.596241 -405.396459) (xy 193.556092 -405.35775) (xy 193.522006 -405.313607) (xy 193.49471 -405.264972)
			(xy 193.474787 -405.212881) (xy 193.462661 -405.158444) (xy 193.45859 -405.102822) (xy 190.778701 -405.102822)
			(xy 190.774327 -405.132544) (xy 190.758259 -405.185951) (xy 190.734587 -405.236448) (xy 190.703814 -405.282961)
			(xy 190.666597 -405.324498) (xy 190.623729 -405.360173) (xy 190.576123 -405.389227) (xy 190.524794 -405.411039)
			(xy 190.470837 -405.425145) (xy 190.4154 -405.431245) (xy 190.359666 -405.429208) (xy 190.304823 -405.419078)
			(xy 190.252039 -405.401071) (xy 190.202439 -405.37557) (xy 190.157081 -405.343119) (xy 190.116932 -405.30441)
			(xy 190.082846 -405.260267) (xy 190.05555 -405.211632) (xy 190.035627 -405.159541) (xy 190.023501 -405.105104)
			(xy 190.01943 -405.049482) (xy 180.689137 -405.049482) (xy 180.694445 -405.067773) (xy 180.709792 -405.092024)
			(xy 180.731279 -405.11105) (xy 180.75721 -405.12335) (xy 180.785538 -405.127954) (xy 180.814029 -405.124497)
			(xy 180.827426 -405.119332) (xy 180.851314 -405.109532) (xy 180.901069 -405.095732) (xy 180.952231 -405.088772)
			(xy 180.978048 -405.088344) (xy 181.0053 -405.088833) (xy 181.05925 -405.096596) (xy 181.111545 -405.111957)
			(xy 181.161123 -405.134604) (xy 181.206973 -405.164075) (xy 181.248163 -405.199771) (xy 181.283853 -405.240966)
			(xy 181.313319 -405.286819) (xy 181.335959 -405.3364) (xy 181.351314 -405.388697) (xy 181.35907 -405.442648)
			(xy 181.35907 -405.497152) (xy 181.351314 -405.551103) (xy 181.335959 -405.6034) (xy 181.313319 -405.652981)
			(xy 181.283853 -405.698834) (xy 181.248163 -405.740029) (xy 181.206973 -405.775725) (xy 181.161123 -405.805196)
			(xy 181.111545 -405.827843) (xy 181.05925 -405.843204) (xy 181.0053 -405.850967) (xy 180.978048 -405.85136)
			(xy 180.952232 -405.850929) (xy 180.901073 -405.84396) (xy 180.851321 -405.830155) (xy 180.827426 -405.820372)
			(xy 180.814028 -405.815182) (xy 180.785521 -405.811695) (xy 180.757171 -405.816284) (xy 180.731219 -405.828584)
			(xy 180.709718 -405.847624) (xy 180.694369 -405.871897) (xy 180.686384 -405.899484) (xy 180.685948 -405.913844)
			(xy 180.685948 -406.179349) (xy 181.425874 -406.179349) (xy 181.425874 -406.124851) (xy 181.433629 -406.070907)
			(xy 181.448982 -406.018616) (xy 181.471619 -405.969041) (xy 181.501081 -405.923193) (xy 181.536768 -405.882003)
			(xy 181.577953 -405.846311) (xy 181.623797 -405.816843) (xy 181.673369 -405.794199) (xy 181.725658 -405.77884)
			(xy 181.779601 -405.771077) (xy 181.80685 -405.770588) (xy 181.835046 -405.771058) (xy 181.890822 -405.779374)
			(xy 181.944769 -405.795802) (xy 181.995713 -405.819986) (xy 182.042546 -405.851399) (xy 182.08425 -405.889358)
			(xy 182.119917 -405.933038) (xy 182.148773 -405.981489) (xy 182.17019 -406.033656) (xy 182.177436 -406.06091)
			(xy 182.181212 -406.074447) (xy 182.195036 -406.098903) (xy 182.215011 -406.118655) (xy 182.23962 -406.132203)
			(xy 182.266993 -406.138518) (xy 182.29505 -406.137121) (xy 182.3085 -406.133046) (xy 182.338106 -406.123683)
			(xy 182.399375 -406.113607) (xy 182.43042 -406.11298) (xy 182.457708 -406.113458) (xy 182.511729 -406.121226)
			(xy 182.56409 -406.136614) (xy 182.613724 -406.159309) (xy 182.636922 -406.173686) (xy 182.649389 -406.18114)
			(xy 182.677243 -406.189344) (xy 182.706279 -406.189384) (xy 182.734154 -406.181257) (xy 182.758619 -406.165618)
			(xy 182.777699 -406.14373) (xy 182.784242 -406.13076) (xy 182.795994 -406.106252) (xy 182.825496 -406.060601)
			(xy 182.861179 -406.019601) (xy 182.902321 -405.984082) (xy 182.948089 -405.954762) (xy 182.997555 -405.932237)
			(xy 183.049718 -405.916961) (xy 183.103521 -405.909245) (xy 183.130698 -405.908764) (xy 183.157949 -405.909283)
			(xy 183.211896 -405.917039) (xy 183.26419 -405.932394) (xy 183.313767 -405.955035) (xy 183.359617 -405.984501)
			(xy 183.394448 -406.014682) (xy 184.04535 -406.014682) (xy 184.049421 -405.95906) (xy 184.061547 -405.904623)
			(xy 184.08147 -405.852532) (xy 184.108766 -405.803897) (xy 184.142852 -405.759754) (xy 184.183001 -405.721045)
			(xy 184.228359 -405.688594) (xy 184.277959 -405.663093) (xy 184.330743 -405.645086) (xy 184.385586 -405.634956)
			(xy 184.44132 -405.632919) (xy 184.496757 -405.639019) (xy 184.550714 -405.653125) (xy 184.602043 -405.674937)
			(xy 184.649649 -405.703991) (xy 184.692517 -405.739666) (xy 184.729734 -405.781203) (xy 184.760507 -405.827716)
			(xy 184.784179 -405.878213) (xy 184.800247 -405.93162) (xy 184.808367 -405.986796) (xy 184.808876 -406.014682)
			(xy 184.808367 -406.042568) (xy 184.800247 -406.097744) (xy 184.784179 -406.151151) (xy 184.760507 -406.201648)
			(xy 184.729734 -406.248161) (xy 184.692517 -406.289698) (xy 184.649649 -406.325373) (xy 184.602043 -406.354427)
			(xy 184.550714 -406.376239) (xy 184.496757 -406.390345) (xy 184.44132 -406.396445) (xy 184.385586 -406.394408)
			(xy 184.330743 -406.384278) (xy 184.277959 -406.366271) (xy 184.228359 -406.34077) (xy 184.183001 -406.308319)
			(xy 184.142852 -406.26961) (xy 184.108766 -406.225467) (xy 184.08147 -406.176832) (xy 184.061547 -406.124741)
			(xy 184.049421 -406.070304) (xy 184.04535 -406.014682) (xy 183.394448 -406.014682) (xy 183.400807 -406.020192)
			(xy 183.436498 -406.061381) (xy 183.465964 -406.107231) (xy 183.488605 -406.156808) (xy 183.50396 -406.209102)
			(xy 183.511717 -406.263049) (xy 183.511717 -406.317551) (xy 183.50396 -406.371498) (xy 183.488605 -406.423792)
			(xy 183.465964 -406.473369) (xy 183.436498 -406.519219) (xy 183.400807 -406.560408) (xy 183.359617 -406.596099)
			(xy 183.313767 -406.625565) (xy 183.26419 -406.648206) (xy 183.211896 -406.663561) (xy 183.157949 -406.671317)
			(xy 183.130698 -406.67178) (xy 183.10341 -406.671299) (xy 183.049389 -406.663533) (xy 182.997028 -406.648146)
			(xy 182.947394 -406.625451) (xy 182.924196 -406.611074) (xy 182.911729 -406.603615) (xy 182.883875 -406.595401)
			(xy 182.854835 -406.595356) (xy 182.826956 -406.603484) (xy 182.80249 -406.619129) (xy 182.783415 -406.641026)
			(xy 182.776876 -406.654) (xy 182.765091 -406.678492) (xy 182.735596 -406.724143) (xy 182.699918 -406.765145)
			(xy 182.658781 -406.800667) (xy 182.613018 -406.829988) (xy 182.563555 -406.852517) (xy 182.511396 -406.867795)
			(xy 182.457596 -406.875513) (xy 182.43042 -406.875996) (xy 182.402225 -406.875475) (xy 182.346451 -406.867169)
			(xy 182.292505 -406.850749) (xy 182.241561 -406.826573) (xy 182.194727 -406.795167) (xy 182.153022 -406.757213)
			(xy 182.117353 -406.713538) (xy 182.088497 -406.665091) (xy 182.06708 -406.612926) (xy 182.059834 -406.585674)
			(xy 182.056103 -406.572122) (xy 182.04227 -406.547664) (xy 182.022285 -406.527912) (xy 181.997667 -406.514366)
			(xy 181.970286 -406.508055) (xy 181.942222 -406.509459) (xy 181.92877 -406.513538) (xy 181.899159 -406.522884)
			(xy 181.837894 -406.532971) (xy 181.80685 -406.533604) (xy 181.779601 -406.533123) (xy 181.725658 -406.52536)
			(xy 181.673369 -406.510001) (xy 181.623797 -406.487357) (xy 181.577953 -406.457889) (xy 181.536768 -406.422197)
			(xy 181.501081 -406.381007) (xy 181.471619 -406.335159) (xy 181.448982 -406.285584) (xy 181.433629 -406.233293)
			(xy 181.425874 -406.179349) (xy 180.685948 -406.179349) (xy 180.685948 -406.389332) (xy 180.686507 -406.404261)
			(xy 180.695218 -406.432821) (xy 180.711824 -406.457637) (xy 180.734903 -406.476583) (xy 180.762479 -406.488035)
			(xy 180.79219 -406.491013) (xy 180.821491 -406.485261) (xy 180.847871 -406.471273) (xy 180.858922 -406.461214)
			(xy 180.880525 -406.440594) (xy 180.92895 -406.40565) (xy 180.982227 -406.378675) (xy 181.039056 -406.360329)
			(xy 181.098049 -406.351059) (xy 181.127908 -406.35047) (xy 181.15516 -406.350956) (xy 181.20911 -406.358714)
			(xy 181.261407 -406.374071) (xy 181.310986 -406.396714) (xy 181.356838 -406.426182) (xy 181.39803 -406.461876)
			(xy 181.433723 -406.503068) (xy 181.46319 -406.548921) (xy 181.485832 -406.5985) (xy 181.501187 -406.650797)
			(xy 181.508944 -406.704748) (xy 181.508944 -406.759252) (xy 181.501187 -406.813203) (xy 181.485832 -406.8655)
			(xy 181.46319 -406.915079) (xy 181.433723 -406.960932) (xy 181.39803 -407.002124) (xy 181.356838 -407.037818)
			(xy 181.354109 -407.039572) (xy 184.79719 -407.039572) (xy 184.801261 -406.98395) (xy 184.813387 -406.929513)
			(xy 184.83331 -406.877422) (xy 184.860606 -406.828787) (xy 184.894692 -406.784644) (xy 184.934841 -406.745935)
			(xy 184.980199 -406.713484) (xy 185.029799 -406.687983) (xy 185.082583 -406.669976) (xy 185.137426 -406.659846)
			(xy 185.19316 -406.657809) (xy 185.248597 -406.663909) (xy 185.302554 -406.678015) (xy 185.353883 -406.699827)
			(xy 185.401489 -406.728881) (xy 185.444357 -406.764556) (xy 185.481574 -406.806093) (xy 185.512347 -406.852606)
			(xy 185.536019 -406.903103) (xy 185.552087 -406.95651) (xy 185.560207 -407.011686) (xy 185.560716 -407.039572)
			(xy 185.560207 -407.067458) (xy 185.552087 -407.122634) (xy 185.536019 -407.176041) (xy 185.512347 -407.226538)
			(xy 185.501111 -407.243521) (xy 185.674029 -407.243521) (xy 185.677756 -407.190272) (xy 185.688869 -407.138064)
			(xy 185.707152 -407.087914) (xy 185.732248 -407.040802) (xy 185.763666 -406.997649) (xy 185.800793 -406.959297)
			(xy 185.821574 -406.942544) (xy 185.833346 -406.93261) (xy 185.850867 -406.907297) (xy 185.860047 -406.877913)
			(xy 185.860054 -406.847128) (xy 185.850885 -406.817741) (xy 185.833375 -406.792421) (xy 185.821574 -406.782524)
			(xy 185.800824 -406.765731) (xy 185.763693 -406.727383) (xy 185.73227 -406.684233) (xy 185.707169 -406.637125)
			(xy 185.688881 -406.586977) (xy 185.677762 -406.534769) (xy 185.674029 -406.481521) (xy 185.677756 -406.428272)
			(xy 185.688869 -406.376064) (xy 185.707152 -406.325914) (xy 185.732248 -406.278802) (xy 185.763666 -406.235649)
			(xy 185.800793 -406.197297) (xy 185.821574 -406.180544) (xy 185.833346 -406.17061) (xy 185.850867 -406.145297)
			(xy 185.860047 -406.115913) (xy 185.860054 -406.085128) (xy 185.850885 -406.055741) (xy 185.833375 -406.030421)
			(xy 185.821574 -406.020524) (xy 185.799097 -406.002326) (xy 185.759362 -405.960307) (xy 185.726423 -405.912773)
			(xy 185.701034 -405.860813) (xy 185.683776 -405.805618) (xy 185.675045 -405.748449) (xy 185.674508 -405.719534)
			(xy 185.674987 -405.692281) (xy 185.68274 -405.63833) (xy 185.698092 -405.586032) (xy 185.720732 -405.53645)
			(xy 185.750198 -405.490596) (xy 185.78589 -405.449403) (xy 185.827082 -405.413709) (xy 185.872935 -405.384241)
			(xy 185.922515 -405.361599) (xy 185.974812 -405.346244) (xy 186.028763 -405.338488) (xy 186.056016 -405.338026)
			(xy 186.084931 -405.338595) (xy 186.1421 -405.347312) (xy 186.197299 -405.364559) (xy 186.249261 -405.389942)
			(xy 186.296796 -405.422877) (xy 186.338814 -405.46261) (xy 186.357006 -405.485092) (xy 186.366903 -405.496897)
			(xy 186.392227 -405.514416) (xy 186.42162 -405.523592) (xy 186.452412 -405.523592) (xy 186.481805 -405.514416)
			(xy 186.507129 -405.496897) (xy 186.517026 -405.485092) (xy 186.533779 -405.464309) (xy 186.572133 -405.427179)
			(xy 186.615287 -405.395757) (xy 186.662401 -405.370658) (xy 186.712553 -405.352372) (xy 186.764764 -405.341255)
			(xy 186.818016 -405.337525) (xy 186.871268 -405.341255) (xy 186.923479 -405.352372) (xy 186.973631 -405.370658)
			(xy 187.020745 -405.395757) (xy 187.063899 -405.427179) (xy 187.102253 -405.464309) (xy 187.119006 -405.485092)
			(xy 187.128903 -405.496897) (xy 187.154227 -405.514416) (xy 187.18362 -405.523592) (xy 187.214412 -405.523592)
			(xy 187.243805 -405.514416) (xy 187.269129 -405.496897) (xy 187.279026 -405.485092) (xy 187.295779 -405.464309)
			(xy 187.334133 -405.427179) (xy 187.377287 -405.395757) (xy 187.424401 -405.370658) (xy 187.474553 -405.352372)
			(xy 187.526764 -405.341255) (xy 187.580016 -405.337525) (xy 187.633268 -405.341255) (xy 187.685479 -405.352372)
			(xy 187.735631 -405.370658) (xy 187.782745 -405.395757) (xy 187.825899 -405.427179) (xy 187.864253 -405.464309)
			(xy 187.881006 -405.485092) (xy 187.890903 -405.496897) (xy 187.916227 -405.514416) (xy 187.94562 -405.523592)
			(xy 187.976412 -405.523592) (xy 188.005805 -405.514416) (xy 188.031129 -405.496897) (xy 188.041026 -405.485092)
			(xy 188.057779 -405.464309) (xy 188.096133 -405.427179) (xy 188.139287 -405.395757) (xy 188.186401 -405.370658)
			(xy 188.236553 -405.352372) (xy 188.288764 -405.341255) (xy 188.342016 -405.337525) (xy 188.395268 -405.341255)
			(xy 188.447479 -405.352372) (xy 188.497631 -405.370658) (xy 188.544745 -405.395757) (xy 188.587899 -405.427179)
			(xy 188.626253 -405.464309) (xy 188.643006 -405.485092) (xy 188.652903 -405.496897) (xy 188.678227 -405.514416)
			(xy 188.70762 -405.523592) (xy 188.738412 -405.523592) (xy 188.767805 -405.514416) (xy 188.793129 -405.496897)
			(xy 188.803026 -405.485092) (xy 188.8212 -405.462594) (xy 188.863224 -405.42286) (xy 188.910762 -405.389923)
			(xy 188.962727 -405.364537) (xy 189.017927 -405.347284) (xy 189.075099 -405.338559) (xy 189.104016 -405.338026)
			(xy 189.131271 -405.33844) (xy 189.185225 -405.3462) (xy 189.237526 -405.36156) (xy 189.287109 -405.384207)
			(xy 189.332963 -405.41368) (xy 189.374157 -405.449379) (xy 189.40985 -405.490577) (xy 189.439317 -405.536435)
			(xy 189.461958 -405.586021) (xy 189.477311 -405.638324) (xy 189.485063 -405.692279) (xy 189.485524 -405.719534)
			(xy 189.484987 -405.748451) (xy 189.476266 -405.805622) (xy 189.459013 -405.860822) (xy 189.433625 -405.912784)
			(xy 189.400684 -405.960318) (xy 189.360943 -406.002334) (xy 189.338458 -406.020524) (xy 189.326615 -406.030382)
			(xy 189.30909 -406.055714) (xy 189.299913 -406.085119) (xy 189.29992 -406.115923) (xy 189.309108 -406.145324)
			(xy 189.326644 -406.170649) (xy 189.338458 -406.180544) (xy 189.356861 -406.195317) (xy 189.390229 -406.228691)
			(xy 189.405006 -406.247092) (xy 189.414903 -406.258897) (xy 189.440227 -406.276416) (xy 189.46962 -406.285592)
			(xy 189.500412 -406.285592) (xy 189.529805 -406.276416) (xy 189.555129 -406.258897) (xy 189.565026 -406.247092)
			(xy 189.5832 -406.224594) (xy 189.625224 -406.18486) (xy 189.672762 -406.151923) (xy 189.724727 -406.126537)
			(xy 189.779927 -406.109284) (xy 189.837099 -406.100559) (xy 189.866016 -406.100026) (xy 189.893271 -406.10044)
			(xy 189.947225 -406.1082) (xy 189.999526 -406.12356) (xy 190.049109 -406.146207) (xy 190.094963 -406.17568)
			(xy 190.136157 -406.211379) (xy 190.17185 -406.252577) (xy 190.201317 -406.298435) (xy 190.223958 -406.348021)
			(xy 190.239311 -406.400324) (xy 190.247063 -406.454279) (xy 190.247524 -406.481534) (xy 190.246987 -406.510451)
			(xy 190.238266 -406.567622) (xy 190.221013 -406.622822) (xy 190.195625 -406.674784) (xy 190.162684 -406.722318)
			(xy 190.122943 -406.764334) (xy 190.100458 -406.782524) (xy 190.088615 -406.792382) (xy 190.07109 -406.817714)
			(xy 190.061913 -406.847119) (xy 190.06192 -406.877923) (xy 190.071108 -406.907324) (xy 190.088644 -406.932649)
			(xy 190.100458 -406.942544) (xy 190.121274 -406.959258) (xy 190.158403 -406.997616) (xy 190.189823 -407.040776)
			(xy 190.21492 -407.087894) (xy 190.233204 -407.138051) (xy 190.244318 -407.190266) (xy 190.248045 -407.243521)
			(xy 190.244312 -407.296775) (xy 190.233192 -407.34899) (xy 190.214903 -407.399144) (xy 190.189801 -407.446259)
			(xy 190.158376 -407.489416) (xy 190.121243 -407.52777) (xy 190.100458 -407.544524) (xy 190.088615 -407.554382)
			(xy 190.07109 -407.579714) (xy 190.061913 -407.609119) (xy 190.06192 -407.639923) (xy 190.071108 -407.669324)
			(xy 190.088644 -407.694649) (xy 190.100458 -407.704544) (xy 190.122954 -407.722721) (xy 190.16269 -407.764742)
			(xy 190.195629 -407.81228) (xy 190.221016 -407.864244) (xy 190.238268 -407.919445) (xy 190.246992 -407.976617)
			(xy 190.247524 -408.005534) (xy 190.247007 -408.032791) (xy 190.239249 -408.086749) (xy 190.223894 -408.139055)
			(xy 190.201256 -408.188645) (xy 190.171794 -408.234511) (xy 190.136109 -408.275721) (xy 190.094924 -408.311435)
			(xy 190.072264 -408.32659) (xy 190.060268 -408.334787) (xy 190.041248 -408.356742) (xy 190.029185 -408.383166)
			(xy 190.025056 -408.411918) (xy 190.029195 -408.44067) (xy 190.041268 -408.467089) (xy 190.060295 -408.489037)
			(xy 190.072264 -408.497278) (xy 190.099048 -408.515283) (xy 190.146673 -408.558829) (xy 190.167006 -408.583892)
			(xy 190.176903 -408.595697) (xy 190.202227 -408.613216) (xy 190.23162 -408.622392) (xy 190.262412 -408.622392)
			(xy 190.291805 -408.613216) (xy 190.317129 -408.595697) (xy 190.327026 -408.583892) (xy 190.3452 -408.561394)
			(xy 190.387224 -408.52166) (xy 190.434762 -408.488723) (xy 190.486727 -408.463337) (xy 190.541927 -408.446084)
			(xy 190.599099 -408.437359) (xy 190.628016 -408.436826) (xy 190.655271 -408.43724) (xy 190.709225 -408.445)
			(xy 190.761526 -408.46036) (xy 190.811109 -408.483007) (xy 190.856963 -408.51248) (xy 190.898157 -408.548179)
			(xy 190.93385 -408.589377) (xy 190.963317 -408.635235) (xy 190.985958 -408.684821) (xy 191.001311 -408.737124)
			(xy 191.009063 -408.791079) (xy 191.009524 -408.818334) (xy 191.008987 -408.847251) (xy 191.000266 -408.904422)
			(xy 190.983013 -408.959622) (xy 190.957625 -409.011584) (xy 190.924684 -409.059118) (xy 190.884943 -409.101134)
			(xy 190.862458 -409.119324) (xy 190.850615 -409.129182) (xy 190.83309 -409.154514) (xy 190.823913 -409.183919)
			(xy 190.82392 -409.214723) (xy 190.833108 -409.244124) (xy 190.850644 -409.269449) (xy 190.862458 -409.279344)
			(xy 190.884954 -409.297521) (xy 190.92469 -409.339542) (xy 190.957629 -409.38708) (xy 190.983016 -409.439044)
			(xy 191.000268 -409.494245) (xy 191.008992 -409.551417) (xy 191.009524 -409.580334) (xy 191.009054 -409.607585)
			(xy 191.001293 -409.661533) (xy 190.985935 -409.713827) (xy 190.963291 -409.763403) (xy 190.933822 -409.809253)
			(xy 190.898129 -409.850442) (xy 190.856938 -409.886133) (xy 190.811087 -409.915599) (xy 190.76151 -409.938241)
			(xy 190.709215 -409.953597) (xy 190.655267 -409.961355) (xy 190.628016 -409.961842) (xy 190.599098 -409.961334)
			(xy 190.541926 -409.952606) (xy 190.486726 -409.935348) (xy 190.434764 -409.909954) (xy 190.38723 -409.877008)
			(xy 190.345215 -409.837263) (xy 190.327026 -409.814776) (xy 190.317129 -409.802971) (xy 190.291805 -409.785452)
			(xy 190.262412 -409.776276) (xy 190.23162 -409.776276) (xy 190.202227 -409.785452) (xy 190.176903 -409.802971)
			(xy 190.167006 -409.814776) (xy 190.150253 -409.835559) (xy 190.111899 -409.872689) (xy 190.068745 -409.904111)
			(xy 190.021631 -409.92921) (xy 189.971479 -409.947496) (xy 189.919268 -409.958613) (xy 189.866016 -409.962343)
			(xy 189.812764 -409.958613) (xy 189.760553 -409.947496) (xy 189.710401 -409.92921) (xy 189.663287 -409.904111)
			(xy 189.620133 -409.872689) (xy 189.581779 -409.835559) (xy 189.565026 -409.814776) (xy 189.555129 -409.802971)
			(xy 189.529805 -409.785452) (xy 189.500412 -409.776276) (xy 189.46962 -409.776276) (xy 189.440227 -409.785452)
			(xy 189.414903 -409.802971) (xy 189.405006 -409.814776) (xy 189.388253 -409.835559) (xy 189.349899 -409.872689)
			(xy 189.306745 -409.904111) (xy 189.259631 -409.92921) (xy 189.209479 -409.947496) (xy 189.157268 -409.958613)
			(xy 189.104016 -409.962343) (xy 189.050764 -409.958613) (xy 188.998553 -409.947496) (xy 188.948401 -409.92921)
			(xy 188.901287 -409.904111) (xy 188.858133 -409.872689) (xy 188.819779 -409.835559) (xy 188.803026 -409.814776)
			(xy 188.793129 -409.802971) (xy 188.767805 -409.785452) (xy 188.738412 -409.776276) (xy 188.70762 -409.776276)
			(xy 188.678227 -409.785452) (xy 188.652903 -409.802971) (xy 188.643006 -409.814776) (xy 188.626253 -409.835559)
			(xy 188.587899 -409.872689) (xy 188.544745 -409.904111) (xy 188.497631 -409.92921) (xy 188.447479 -409.947496)
			(xy 188.395268 -409.958613) (xy 188.342016 -409.962343) (xy 188.288764 -409.958613) (xy 188.236553 -409.947496)
			(xy 188.186401 -409.92921) (xy 188.139287 -409.904111) (xy 188.096133 -409.872689) (xy 188.057779 -409.835559)
			(xy 188.041026 -409.814776) (xy 188.031129 -409.802971) (xy 188.005805 -409.785452) (xy 187.976412 -409.776276)
			(xy 187.94562 -409.776276) (xy 187.916227 -409.785452) (xy 187.890903 -409.802971) (xy 187.881006 -409.814776)
			(xy 187.864253 -409.835559) (xy 187.825899 -409.872689) (xy 187.782745 -409.904111) (xy 187.735631 -409.92921)
			(xy 187.685479 -409.947496) (xy 187.633268 -409.958613) (xy 187.580016 -409.962343) (xy 187.526764 -409.958613)
			(xy 187.474553 -409.947496) (xy 187.424401 -409.92921) (xy 187.377287 -409.904111) (xy 187.334133 -409.872689)
			(xy 187.295779 -409.835559) (xy 187.279026 -409.814776) (xy 187.269129 -409.802971) (xy 187.243805 -409.785452)
			(xy 187.214412 -409.776276) (xy 187.18362 -409.776276) (xy 187.154227 -409.785452) (xy 187.128903 -409.802971)
			(xy 187.119006 -409.814776) (xy 187.100806 -409.837252) (xy 187.058788 -409.876988) (xy 187.011256 -409.909929)
			(xy 186.959296 -409.935319) (xy 186.9041 -409.952577) (xy 186.846932 -409.961307) (xy 186.818016 -409.961842)
			(xy 186.790767 -409.961307) (xy 186.736823 -409.953554) (xy 186.684531 -409.938202) (xy 186.634956 -409.915565)
			(xy 186.589107 -409.886104) (xy 186.547918 -409.850418) (xy 186.512226 -409.809233) (xy 186.482759 -409.763388)
			(xy 186.460115 -409.713816) (xy 186.444757 -409.661526) (xy 186.436997 -409.607583) (xy 186.436508 -409.580334)
			(xy 186.437048 -409.551418) (xy 186.445772 -409.494248) (xy 186.463025 -409.439049) (xy 186.488413 -409.387087)
			(xy 186.521353 -409.339553) (xy 186.56109 -409.297535) (xy 186.583574 -409.279344) (xy 186.595346 -409.26941)
			(xy 186.612867 -409.244097) (xy 186.622047 -409.214713) (xy 186.622054 -409.183928) (xy 186.612885 -409.154541)
			(xy 186.595375 -409.129221) (xy 186.583574 -409.119324) (xy 186.561097 -409.101126) (xy 186.521362 -409.059107)
			(xy 186.488423 -409.011573) (xy 186.463034 -408.959613) (xy 186.445776 -408.904418) (xy 186.437045 -408.847249)
			(xy 186.436508 -408.818334) (xy 186.437031 -408.791078) (xy 186.444793 -408.737121) (xy 186.460148 -408.684817)
			(xy 186.482786 -408.635228) (xy 186.512246 -408.589362) (xy 186.547929 -408.548152) (xy 186.58911 -408.512435)
			(xy 186.611768 -408.497278) (xy 186.623662 -408.488953) (xy 186.642664 -408.467027) (xy 186.654719 -408.440636)
			(xy 186.658853 -408.411918) (xy 186.65473 -408.383199) (xy 186.642683 -408.356804) (xy 186.62369 -408.334871)
			(xy 186.611768 -408.32659) (xy 186.584984 -408.308585) (xy 186.537358 -408.265039) (xy 186.517026 -408.239976)
			(xy 186.507129 -408.228171) (xy 186.481805 -408.210652) (xy 186.452412 -408.201476) (xy 186.42162 -408.201476)
			(xy 186.392227 -408.210652) (xy 186.366903 -408.228171) (xy 186.357006 -408.239976) (xy 186.338806 -408.262452)
			(xy 186.296788 -408.302188) (xy 186.249256 -408.335129) (xy 186.197296 -408.360519) (xy 186.1421 -408.377777)
			(xy 186.084932 -408.386507) (xy 186.056016 -408.387042) (xy 186.028767 -408.386507) (xy 185.974823 -408.378754)
			(xy 185.922531 -408.363402) (xy 185.872956 -408.340765) (xy 185.827107 -408.311304) (xy 185.785918 -408.275618)
			(xy 185.750226 -408.234433) (xy 185.720759 -408.188588) (xy 185.698115 -408.139016) (xy 185.682757 -408.086726)
			(xy 185.674997 -408.032783) (xy 185.674508 -408.005534) (xy 185.675048 -407.976618) (xy 185.683772 -407.919448)
			(xy 185.701025 -407.864249) (xy 185.726413 -407.812287) (xy 185.759353 -407.764753) (xy 185.79909 -407.722735)
			(xy 185.821574 -407.704544) (xy 185.833346 -407.69461) (xy 185.850867 -407.669297) (xy 185.860047 -407.639913)
			(xy 185.860054 -407.609128) (xy 185.850885 -407.579741) (xy 185.833375 -407.554421) (xy 185.821574 -407.544524)
			(xy 185.800824 -407.527731) (xy 185.763693 -407.489383) (xy 185.73227 -407.446233) (xy 185.707169 -407.399125)
			(xy 185.688881 -407.348977) (xy 185.677762 -407.296769) (xy 185.674029 -407.243521) (xy 185.501111 -407.243521)
			(xy 185.481574 -407.273051) (xy 185.444357 -407.314588) (xy 185.401489 -407.350263) (xy 185.353883 -407.379317)
			(xy 185.302554 -407.401129) (xy 185.248597 -407.415235) (xy 185.19316 -407.421335) (xy 185.137426 -407.419298)
			(xy 185.082583 -407.409168) (xy 185.029799 -407.391161) (xy 184.980199 -407.36566) (xy 184.934841 -407.333209)
			(xy 184.894692 -407.2945) (xy 184.860606 -407.250357) (xy 184.83331 -407.201722) (xy 184.813387 -407.149631)
			(xy 184.801261 -407.095194) (xy 184.79719 -407.039572) (xy 181.354109 -407.039572) (xy 181.310986 -407.067286)
			(xy 181.261407 -407.089929) (xy 181.20911 -407.105286) (xy 181.15516 -407.113044) (xy 181.127908 -407.113486)
			(xy 181.098046 -407.112931) (xy 181.039045 -407.103669) (xy 180.98221 -407.085324) (xy 180.928928 -407.058344)
			(xy 180.880503 -407.023388) (xy 180.858922 -407.002742) (xy 180.847935 -406.992617) (xy 180.821533 -406.978662)
			(xy 180.792223 -406.972936) (xy 180.76251 -406.97593) (xy 180.734932 -406.987388) (xy 180.711845 -407.00633)
			(xy 180.695221 -407.031138) (xy 180.68648 -407.059694) (xy 180.685948 -407.074624) (xy 180.685948 -407.546048)
			(xy 180.966872 -407.827226) (xy 180.966872 -408.972512) (xy 180.966831 -408.978016) (xy 180.965684 -408.988963)
			(xy 180.964586 -408.994356) (xy 180.95849 -409.021534) (xy 181.53126 -409.594304) (xy 181.54015 -409.603448)
			(xy 181.628288 -409.568904) (xy 181.628288 -409.325318) (xy 181.628806 -409.309973) (xy 181.637931 -409.280672)
			(xy 181.655387 -409.25543) (xy 181.66715 -409.245562) (xy 181.677743 -409.236661) (xy 181.694121 -409.214375)
			(xy 181.703918 -409.188512) (xy 181.706417 -409.160969) (xy 181.701433 -409.133765) (xy 181.695852 -409.121102)
			(xy 181.683694 -409.094935) (xy 181.666513 -409.039855) (xy 181.657803 -408.982818) (xy 181.657244 -408.95397)
			(xy 181.65773 -408.926719) (xy 181.665486 -408.872771) (xy 181.680841 -408.820476) (xy 181.703483 -408.770899)
			(xy 181.732949 -408.725049) (xy 181.76864 -408.683858) (xy 181.809831 -408.648167) (xy 181.855681 -408.618701)
			(xy 181.905258 -408.596059) (xy 181.957553 -408.580704) (xy 182.011501 -408.572948) (xy 182.066003 -408.572948)
			(xy 182.119951 -408.580704) (xy 182.172246 -408.596059) (xy 182.221823 -408.618701) (xy 182.267673 -408.648167)
			(xy 182.308864 -408.683858) (xy 182.344555 -408.725049) (xy 182.374021 -408.770899) (xy 182.396663 -408.820476)
			(xy 182.412018 -408.872771) (xy 182.419774 -408.926719) (xy 182.42026 -408.95397) (xy 182.41899 -408.984196)
			(xy 182.41833 -408.998473) (xy 182.424022 -409.02647) (xy 182.437237 -409.051799) (xy 182.456943 -409.072484)
			(xy 182.481602 -409.08691) (xy 182.509291 -409.093951) (xy 182.537846 -409.093057) (xy 182.551578 -409.089098)
			(xy 182.580079 -409.080459) (xy 182.638897 -409.071138) (xy 182.668672 -409.070556) (xy 182.697708 -409.071097)
			(xy 182.755109 -409.079896) (xy 182.782972 -409.088082) (xy 182.797441 -409.092081) (xy 182.827443 -409.092395)
			(xy 182.856243 -409.083979) (xy 182.881355 -409.067559) (xy 182.900613 -409.04455) (xy 182.906924 -409.030932)
			(xy 182.918256 -409.005443) (xy 182.947276 -408.957806) (xy 182.982929 -408.914907) (xy 183.024454 -408.877662)
			(xy 183.070962 -408.846866) (xy 183.121462 -408.823177) (xy 183.174876 -408.8071) (xy 183.230062 -408.798978)
			(xy 183.257952 -408.798522) (xy 183.286547 -408.799029) (xy 183.343097 -408.807558) (xy 183.39774 -408.824434)
			(xy 183.449251 -408.849278) (xy 183.496477 -408.881533) (xy 183.538359 -408.920475) (xy 183.573958 -408.965234)
			(xy 183.602478 -409.014805) (xy 183.623278 -409.068078) (xy 183.635892 -409.123859) (xy 183.638444 -409.152344)
			(xy 183.639852 -409.165671) (xy 183.648737 -409.190945) (xy 183.663883 -409.213043) (xy 183.684251 -409.230447)
			(xy 183.708441 -409.241961) (xy 183.734791 -409.246794) (xy 183.748172 -409.24607) (xy 183.779668 -409.2448)
			(xy 183.808644 -409.245336) (xy 183.86593 -409.254097) (xy 183.921232 -409.27142) (xy 183.973278 -409.296909)
			(xy 184.02087 -409.329976) (xy 184.062913 -409.36986) (xy 184.09844 -409.415645) (xy 184.126634 -409.466276)
			(xy 184.146846 -409.520589) (xy 184.158611 -409.577334) (xy 184.160668 -409.606242) (xy 184.162022 -409.621305)
			(xy 184.172384 -409.6497) (xy 184.190589 -409.673831) (xy 184.215047 -409.691592) (xy 184.243627 -409.701435)
			(xy 184.258712 -409.702508) (xy 184.285354 -409.703841) (xy 184.337901 -409.713028) (xy 184.388656 -409.729446)
			(xy 184.436629 -409.752774) (xy 184.480884 -409.782558) (xy 184.520559 -409.818216) (xy 184.554879 -409.859053)
			(xy 184.583176 -409.904274) (xy 184.604897 -409.952995) (xy 184.61962 -410.004267) (xy 184.627056 -410.05709)
			(xy 184.62752 -410.083762) (xy 184.627023 -410.111852) (xy 184.618785 -410.167425) (xy 184.602483 -410.221188)
			(xy 184.578468 -410.271977) (xy 184.563258 -410.295598) (xy 184.55606 -410.307267) (xy 184.547546 -410.333317)
			(xy 184.546273 -410.360694) (xy 184.552334 -410.387422) (xy 184.565291 -410.411572) (xy 184.58421 -410.431402)
			(xy 184.607724 -410.44548) (xy 184.634137 -410.452791) (xy 184.64784 -410.453332) (xy 194.650614 -410.453332)
			(xy 195.165472 -409.938474) (xy 195.165472 -404.06066) (xy 195.165967 -404.034678) (xy 195.174125 -403.983358)
			(xy 195.190218 -403.933948) (xy 195.213848 -403.887668) (xy 195.244432 -403.845657) (xy 195.2625 -403.82698)
			(xy 196.08292 -403.00656) (xy 196.101639 -402.98854) (xy 196.14365 -402.957971) (xy 196.189922 -402.934341)
			(xy 196.239317 -402.918231) (xy 196.290623 -402.910036) (xy 196.3166 -402.909532) (xy 196.977 -402.909532)
			(xy 197.00298 -402.910032) (xy 197.054296 -402.918197) (xy 197.103701 -402.934295) (xy 197.149977 -402.957928)
			(xy 197.191983 -402.988514) (xy 197.21068 -403.00656) (xy 197.571868 -403.367748) (xy 197.589885 -403.386468)
			(xy 197.620448 -403.428481) (xy 197.644072 -403.474753) (xy 197.660176 -403.524148) (xy 197.668366 -403.575452)
			(xy 197.668896 -403.601428) (xy 197.668896 -403.782022) (xy 197.674738 -403.793198) (xy 197.688863 -403.821003)
			(xy 197.708879 -403.880066) (xy 197.71904 -403.941595) (xy 197.719696 -403.972776) (xy 197.719226 -403.999824)
			(xy 197.715512 -404.025862) (xy 198.367648 -404.025862) (xy 198.371719 -403.97024) (xy 198.383845 -403.915803)
			(xy 198.403768 -403.863712) (xy 198.431064 -403.815077) (xy 198.46515 -403.770934) (xy 198.505299 -403.732225)
			(xy 198.550657 -403.699774) (xy 198.600257 -403.674273) (xy 198.653041 -403.656266) (xy 198.707884 -403.646136)
			(xy 198.763618 -403.644099) (xy 198.819055 -403.650199) (xy 198.873012 -403.664305) (xy 198.924341 -403.686117)
			(xy 198.971947 -403.715171) (xy 199.014815 -403.750846) (xy 199.052032 -403.792383) (xy 199.082805 -403.838896)
			(xy 199.106477 -403.889393) (xy 199.122545 -403.9428) (xy 199.130665 -403.997976) (xy 199.131174 -404.025862)
			(xy 199.790048 -404.025862) (xy 199.794119 -403.97024) (xy 199.806245 -403.915803) (xy 199.826168 -403.863712)
			(xy 199.853464 -403.815077) (xy 199.88755 -403.770934) (xy 199.927699 -403.732225) (xy 199.973057 -403.699774)
			(xy 200.022657 -403.674273) (xy 200.075441 -403.656266) (xy 200.130284 -403.646136) (xy 200.186018 -403.644099)
			(xy 200.241455 -403.650199) (xy 200.295412 -403.664305) (xy 200.346741 -403.686117) (xy 200.394347 -403.715171)
			(xy 200.437215 -403.750846) (xy 200.474432 -403.792383) (xy 200.505205 -403.838896) (xy 200.528877 -403.889393)
			(xy 200.544945 -403.9428) (xy 200.553065 -403.997976) (xy 200.553574 -404.025862) (xy 201.187048 -404.025862)
			(xy 201.191119 -403.97024) (xy 201.203245 -403.915803) (xy 201.223168 -403.863712) (xy 201.250464 -403.815077)
			(xy 201.28455 -403.770934) (xy 201.324699 -403.732225) (xy 201.370057 -403.699774) (xy 201.419657 -403.674273)
			(xy 201.472441 -403.656266) (xy 201.527284 -403.646136) (xy 201.583018 -403.644099) (xy 201.638455 -403.650199)
			(xy 201.692412 -403.664305) (xy 201.743741 -403.686117) (xy 201.791347 -403.715171) (xy 201.834215 -403.750846)
			(xy 201.871432 -403.792383) (xy 201.881382 -403.807422) (xy 203.99959 -403.807422) (xy 204.003661 -403.7518)
			(xy 204.015787 -403.697363) (xy 204.03571 -403.645272) (xy 204.063006 -403.596637) (xy 204.097092 -403.552494)
			(xy 204.137241 -403.513785) (xy 204.182599 -403.481334) (xy 204.232199 -403.455833) (xy 204.284983 -403.437826)
			(xy 204.339826 -403.427696) (xy 204.39556 -403.425659) (xy 204.450997 -403.431759) (xy 204.504954 -403.445865)
			(xy 204.556283 -403.467677) (xy 204.603889 -403.496731) (xy 204.646757 -403.532406) (xy 204.683974 -403.573943)
			(xy 204.714747 -403.620456) (xy 204.738419 -403.670953) (xy 204.754487 -403.72436) (xy 204.762607 -403.779536)
			(xy 204.763116 -403.807422) (xy 204.762607 -403.835308) (xy 204.754487 -403.890484) (xy 204.738419 -403.943891)
			(xy 204.714747 -403.994388) (xy 204.683974 -404.040901) (xy 204.646757 -404.082438) (xy 204.603889 -404.118113)
			(xy 204.556283 -404.147167) (xy 204.504954 -404.168979) (xy 204.450997 -404.183085) (xy 204.39556 -404.189185)
			(xy 204.339826 -404.187148) (xy 204.284983 -404.177018) (xy 204.232199 -404.159011) (xy 204.182599 -404.13351)
			(xy 204.137241 -404.101059) (xy 204.097092 -404.06235) (xy 204.063006 -404.018207) (xy 204.03571 -403.969572)
			(xy 204.015787 -403.917481) (xy 204.003661 -403.863044) (xy 203.99959 -403.807422) (xy 201.881382 -403.807422)
			(xy 201.902205 -403.838896) (xy 201.925877 -403.889393) (xy 201.941945 -403.9428) (xy 201.950065 -403.997976)
			(xy 201.950574 -404.025862) (xy 201.950065 -404.053748) (xy 201.941945 -404.108924) (xy 201.925877 -404.162331)
			(xy 201.902205 -404.212828) (xy 201.871432 -404.259341) (xy 201.834215 -404.300878) (xy 201.791347 -404.336553)
			(xy 201.743741 -404.365607) (xy 201.692412 -404.387419) (xy 201.638455 -404.401525) (xy 201.583018 -404.407625)
			(xy 201.527284 -404.405588) (xy 201.472441 -404.395458) (xy 201.419657 -404.377451) (xy 201.370057 -404.35195)
			(xy 201.324699 -404.319499) (xy 201.28455 -404.28079) (xy 201.250464 -404.236647) (xy 201.223168 -404.188012)
			(xy 201.203245 -404.135921) (xy 201.191119 -404.081484) (xy 201.187048 -404.025862) (xy 200.553574 -404.025862)
			(xy 200.553065 -404.053748) (xy 200.544945 -404.108924) (xy 200.528877 -404.162331) (xy 200.505205 -404.212828)
			(xy 200.474432 -404.259341) (xy 200.437215 -404.300878) (xy 200.394347 -404.336553) (xy 200.346741 -404.365607)
			(xy 200.295412 -404.387419) (xy 200.241455 -404.401525) (xy 200.186018 -404.407625) (xy 200.130284 -404.405588)
			(xy 200.075441 -404.395458) (xy 200.022657 -404.377451) (xy 199.973057 -404.35195) (xy 199.927699 -404.319499)
			(xy 199.88755 -404.28079) (xy 199.853464 -404.236647) (xy 199.826168 -404.188012) (xy 199.806245 -404.135921)
			(xy 199.794119 -404.081484) (xy 199.790048 -404.025862) (xy 199.131174 -404.025862) (xy 199.130665 -404.053748)
			(xy 199.122545 -404.108924) (xy 199.106477 -404.162331) (xy 199.082805 -404.212828) (xy 199.052032 -404.259341)
			(xy 199.014815 -404.300878) (xy 198.971947 -404.336553) (xy 198.924341 -404.365607) (xy 198.873012 -404.387419)
			(xy 198.819055 -404.401525) (xy 198.763618 -404.407625) (xy 198.707884 -404.405588) (xy 198.653041 -404.395458)
			(xy 198.600257 -404.377451) (xy 198.550657 -404.35195) (xy 198.505299 -404.319499) (xy 198.46515 -404.28079)
			(xy 198.431064 -404.236647) (xy 198.403768 -404.188012) (xy 198.383845 -404.135921) (xy 198.371719 -404.081484)
			(xy 198.367648 -404.025862) (xy 197.715512 -404.025862) (xy 197.711587 -404.053379) (xy 197.69646 -404.105317)
			(xy 197.674147 -404.154598) (xy 197.645096 -404.200233) (xy 197.609891 -404.241306) (xy 197.569236 -404.276993)
			(xy 197.523947 -404.30658) (xy 197.474933 -404.329472) (xy 197.449186 -404.337774) (xy 197.436994 -404.341584)
			(xy 196.934328 -404.84425) (xy 196.934328 -406.576014) (xy 198.259215 -406.576014) (xy 198.262942 -406.522764)
			(xy 198.274057 -406.470554) (xy 198.292341 -406.420404) (xy 198.317438 -406.373292) (xy 198.348857 -406.330138)
			(xy 198.385985 -406.291785) (xy 198.406766 -406.275032) (xy 198.418551 -406.265112) (xy 198.436073 -406.239795)
			(xy 198.445253 -406.210408) (xy 198.445257 -406.179619) (xy 198.436085 -406.150229) (xy 198.41857 -406.124908)
			(xy 198.406766 -406.115012) (xy 198.384281 -406.096823) (xy 198.344548 -406.054802) (xy 198.31161 -406.007266)
			(xy 198.286222 -405.955305) (xy 198.268966 -405.900107) (xy 198.260236 -405.842938) (xy 198.2597 -405.814022)
			(xy 198.260176 -405.786769) (xy 198.26793 -405.732818) (xy 198.283284 -405.68052) (xy 198.305924 -405.63094)
			(xy 198.335391 -405.585086) (xy 198.371083 -405.543893) (xy 198.412275 -405.508199) (xy 198.458127 -405.478731)
			(xy 198.507707 -405.456089) (xy 198.560005 -405.440733) (xy 198.613955 -405.432977) (xy 198.641208 -405.432514)
			(xy 198.670123 -405.433093) (xy 198.727291 -405.441809) (xy 198.782489 -405.459055) (xy 198.834451 -405.484435)
			(xy 198.881987 -405.517368) (xy 198.924006 -405.557099) (xy 198.942198 -405.57958) (xy 198.952095 -405.591385)
			(xy 198.977419 -405.608904) (xy 199.006812 -405.61808) (xy 199.037604 -405.61808) (xy 199.066997 -405.608904)
			(xy 199.092321 -405.591385) (xy 199.102218 -405.57958) (xy 199.118971 -405.558797) (xy 199.157325 -405.521667)
			(xy 199.200479 -405.490245) (xy 199.247593 -405.465146) (xy 199.297745 -405.44686) (xy 199.349956 -405.435743)
			(xy 199.403208 -405.432013) (xy 199.45646 -405.435743) (xy 199.508671 -405.44686) (xy 199.558823 -405.465146)
			(xy 199.605937 -405.490245) (xy 199.649091 -405.521667) (xy 199.687445 -405.558797) (xy 199.704198 -405.57958)
			(xy 199.714095 -405.591385) (xy 199.739419 -405.608904) (xy 199.768812 -405.61808) (xy 199.799604 -405.61808)
			(xy 199.828997 -405.608904) (xy 199.854321 -405.591385) (xy 199.864218 -405.57958) (xy 199.880971 -405.558797)
			(xy 199.919325 -405.521667) (xy 199.962479 -405.490245) (xy 200.009593 -405.465146) (xy 200.059745 -405.44686)
			(xy 200.111956 -405.435743) (xy 200.165208 -405.432013) (xy 200.21846 -405.435743) (xy 200.270671 -405.44686)
			(xy 200.320823 -405.465146) (xy 200.367937 -405.490245) (xy 200.411091 -405.521667) (xy 200.449445 -405.558797)
			(xy 200.466198 -405.57958) (xy 200.476095 -405.591385) (xy 200.501419 -405.608904) (xy 200.530812 -405.61808)
			(xy 200.561604 -405.61808) (xy 200.590997 -405.608904) (xy 200.616321 -405.591385) (xy 200.626218 -405.57958)
			(xy 200.642971 -405.558797) (xy 200.681325 -405.521667) (xy 200.724479 -405.490245) (xy 200.771593 -405.465146)
			(xy 200.821745 -405.44686) (xy 200.873956 -405.435743) (xy 200.927208 -405.432013) (xy 200.98046 -405.435743)
			(xy 201.032671 -405.44686) (xy 201.082823 -405.465146) (xy 201.129937 -405.490245) (xy 201.173091 -405.521667)
			(xy 201.211445 -405.558797) (xy 201.228198 -405.57958) (xy 201.238095 -405.591385) (xy 201.263419 -405.608904)
			(xy 201.292812 -405.61808) (xy 201.323604 -405.61808) (xy 201.352997 -405.608904) (xy 201.378321 -405.591385)
			(xy 201.388218 -405.57958) (xy 201.406394 -405.557084) (xy 201.448417 -405.51735) (xy 201.495956 -405.484413)
			(xy 201.54792 -405.459027) (xy 201.60312 -405.441774) (xy 201.660291 -405.433048) (xy 201.689208 -405.432514)
			(xy 201.716462 -405.432948) (xy 201.770415 -405.440707) (xy 201.822715 -405.456065) (xy 201.872297 -405.47871)
			(xy 201.918151 -405.508181) (xy 201.959344 -405.543877) (xy 201.995037 -405.585073) (xy 202.024505 -405.63093)
			(xy 202.047146 -405.680513) (xy 202.0625 -405.732814) (xy 202.070254 -405.786768) (xy 202.070716 -405.814022)
			(xy 202.070173 -405.842938) (xy 202.061454 -405.90011) (xy 202.044203 -405.95531) (xy 202.018816 -406.007272)
			(xy 201.985875 -406.054806) (xy 201.946135 -406.096822) (xy 201.92365 -406.115012) (xy 201.911819 -406.124883)
			(xy 201.894296 -406.150212) (xy 201.885119 -406.179613) (xy 201.885123 -406.210413) (xy 201.894308 -406.239812)
			(xy 201.911838 -406.265136) (xy 201.92365 -406.275032) (xy 201.944454 -406.29176) (xy 201.981584 -406.330116)
			(xy 202.013005 -406.373274) (xy 202.038103 -406.420391) (xy 202.056387 -406.470546) (xy 202.067502 -406.52276)
			(xy 202.07123 -406.576014) (xy 202.067499 -406.629267) (xy 202.05638 -406.68148) (xy 202.038092 -406.731634)
			(xy 202.01299 -406.778749) (xy 201.981567 -406.821904) (xy 201.944434 -406.860258) (xy 201.92365 -406.877012)
			(xy 201.911819 -406.886883) (xy 201.894296 -406.912212) (xy 201.885119 -406.941613) (xy 201.885123 -406.972413)
			(xy 201.894308 -407.001812) (xy 201.911838 -407.027136) (xy 201.92365 -407.037032) (xy 201.946159 -407.055192)
			(xy 201.985891 -407.09722) (xy 202.018825 -407.144762) (xy 202.044209 -407.196729) (xy 202.06146 -407.251931)
			(xy 202.070184 -407.309104) (xy 202.070716 -407.338022) (xy 202.070243 -407.365273) (xy 202.062483 -407.419221)
			(xy 202.047126 -407.471516) (xy 202.024483 -407.521092) (xy 201.995015 -407.566942) (xy 201.959322 -407.608132)
			(xy 201.918131 -407.643823) (xy 201.87228 -407.673289) (xy 201.822703 -407.695931) (xy 201.770407 -407.711286)
			(xy 201.716459 -407.719044) (xy 201.689208 -407.71953) (xy 201.66029 -407.719032) (xy 201.603117 -407.710303)
			(xy 201.547916 -407.693043) (xy 201.495954 -407.667647) (xy 201.448421 -407.634699) (xy 201.406406 -407.594952)
			(xy 201.388218 -407.572464) (xy 201.378321 -407.560659) (xy 201.352997 -407.54314) (xy 201.323604 -407.533964)
			(xy 201.292812 -407.533964) (xy 201.263419 -407.54314) (xy 201.238095 -407.560659) (xy 201.228198 -407.572464)
			(xy 201.211445 -407.593247) (xy 201.173091 -407.630377) (xy 201.129937 -407.661799) (xy 201.082823 -407.686898)
			(xy 201.032671 -407.705184) (xy 200.98046 -407.716301) (xy 200.927208 -407.720031) (xy 200.873956 -407.716301)
			(xy 200.821745 -407.705184) (xy 200.771593 -407.686898) (xy 200.724479 -407.661799) (xy 200.681325 -407.630377)
			(xy 200.642971 -407.593247) (xy 200.626218 -407.572464) (xy 200.616321 -407.560659) (xy 200.590997 -407.54314)
			(xy 200.561604 -407.533964) (xy 200.530812 -407.533964) (xy 200.501419 -407.54314) (xy 200.476095 -407.560659)
			(xy 200.466198 -407.572464) (xy 200.449445 -407.593247) (xy 200.411091 -407.630377) (xy 200.367937 -407.661799)
			(xy 200.320823 -407.686898) (xy 200.270671 -407.705184) (xy 200.21846 -407.716301) (xy 200.165208 -407.720031)
			(xy 200.111956 -407.716301) (xy 200.059745 -407.705184) (xy 200.009593 -407.686898) (xy 199.962479 -407.661799)
			(xy 199.919325 -407.630377) (xy 199.880971 -407.593247) (xy 199.864218 -407.572464) (xy 199.854321 -407.560659)
			(xy 199.828997 -407.54314) (xy 199.799604 -407.533964) (xy 199.768812 -407.533964) (xy 199.739419 -407.54314)
			(xy 199.714095 -407.560659) (xy 199.704198 -407.572464) (xy 199.687445 -407.593247) (xy 199.649091 -407.630377)
			(xy 199.605937 -407.661799) (xy 199.558823 -407.686898) (xy 199.508671 -407.705184) (xy 199.45646 -407.716301)
			(xy 199.403208 -407.720031) (xy 199.349956 -407.716301) (xy 199.297745 -407.705184) (xy 199.247593 -407.686898)
			(xy 199.200479 -407.661799) (xy 199.157325 -407.630377) (xy 199.118971 -407.593247) (xy 199.102218 -407.572464)
			(xy 199.092321 -407.560659) (xy 199.066997 -407.54314) (xy 199.037604 -407.533964) (xy 199.006812 -407.533964)
			(xy 198.977419 -407.54314) (xy 198.952095 -407.560659) (xy 198.942198 -407.572464) (xy 198.923999 -407.594941)
			(xy 198.881982 -407.634678) (xy 198.834449 -407.667619) (xy 198.782489 -407.693009) (xy 198.727293 -407.710266)
			(xy 198.670124 -407.718995) (xy 198.641208 -407.71953) (xy 198.613958 -407.719015) (xy 198.560012 -407.71126)
			(xy 198.50772 -407.695907) (xy 198.458144 -407.673268) (xy 198.412294 -407.643805) (xy 198.371105 -407.608117)
			(xy 198.335413 -407.56693) (xy 198.305946 -407.521083) (xy 198.283304 -407.471509) (xy 198.267946 -407.419217)
			(xy 198.260187 -407.365272) (xy 198.2597 -407.338022) (xy 198.260234 -407.309106) (xy 198.26896 -407.251935)
			(xy 198.286215 -407.196737) (xy 198.311603 -407.144775) (xy 198.344544 -407.097241) (xy 198.384282 -407.055223)
			(xy 198.406766 -407.037032) (xy 198.418551 -407.027112) (xy 198.436073 -407.001795) (xy 198.445253 -406.972408)
			(xy 198.445257 -406.941619) (xy 198.436085 -406.912229) (xy 198.41857 -406.886908) (xy 198.406766 -406.877012)
			(xy 198.386005 -406.860233) (xy 198.348874 -406.821883) (xy 198.317452 -406.778731) (xy 198.292352 -406.731621)
			(xy 198.274064 -406.681472) (xy 198.262946 -406.629263) (xy 198.259215 -406.576014) (xy 196.934328 -406.576014)
			(xy 196.934328 -408.406652) (xy 197.498177 -408.406652) (xy 197.498177 -408.352148) (xy 197.505934 -408.2982)
			(xy 197.52129 -408.245904) (xy 197.543931 -408.196327) (xy 197.573398 -408.150476) (xy 197.609091 -408.109285)
			(xy 197.650282 -408.073594) (xy 197.696134 -408.044128) (xy 197.745712 -408.021487) (xy 197.798008 -408.006132)
			(xy 197.851956 -407.998377) (xy 197.879208 -407.997914) (xy 197.908123 -407.998493) (xy 197.965291 -408.007209)
			(xy 198.020489 -408.024455) (xy 198.072451 -408.049835) (xy 198.119987 -408.082768) (xy 198.162006 -408.122499)
			(xy 198.180198 -408.14498) (xy 198.190095 -408.156785) (xy 198.215419 -408.174304) (xy 198.244812 -408.18348)
			(xy 198.275604 -408.18348) (xy 198.304997 -408.174304) (xy 198.330321 -408.156785) (xy 198.340218 -408.14498)
			(xy 198.356971 -408.124197) (xy 198.395325 -408.087067) (xy 198.438479 -408.055645) (xy 198.485593 -408.030546)
			(xy 198.535745 -408.01226) (xy 198.587956 -408.001143) (xy 198.641208 -407.997413) (xy 198.69446 -408.001143)
			(xy 198.746671 -408.01226) (xy 198.796823 -408.030546) (xy 198.843937 -408.055645) (xy 198.887091 -408.087067)
			(xy 198.925445 -408.124197) (xy 198.942198 -408.14498) (xy 198.952095 -408.156785) (xy 198.977419 -408.174304)
			(xy 199.006812 -408.18348) (xy 199.037604 -408.18348) (xy 199.066997 -408.174304) (xy 199.092321 -408.156785)
			(xy 199.102218 -408.14498) (xy 199.118971 -408.124197) (xy 199.157325 -408.087067) (xy 199.200479 -408.055645)
			(xy 199.247593 -408.030546) (xy 199.297745 -408.01226) (xy 199.349956 -408.001143) (xy 199.403208 -407.997413)
			(xy 199.45646 -408.001143) (xy 199.508671 -408.01226) (xy 199.558823 -408.030546) (xy 199.605937 -408.055645)
			(xy 199.649091 -408.087067) (xy 199.687445 -408.124197) (xy 199.704198 -408.14498) (xy 199.714095 -408.156785)
			(xy 199.739419 -408.174304) (xy 199.768812 -408.18348) (xy 199.799604 -408.18348) (xy 199.828997 -408.174304)
			(xy 199.854321 -408.156785) (xy 199.864218 -408.14498) (xy 199.880971 -408.124197) (xy 199.919325 -408.087067)
			(xy 199.962479 -408.055645) (xy 200.009593 -408.030546) (xy 200.059745 -408.01226) (xy 200.111956 -408.001143)
			(xy 200.165208 -407.997413) (xy 200.21846 -408.001143) (xy 200.270671 -408.01226) (xy 200.320823 -408.030546)
			(xy 200.367937 -408.055645) (xy 200.411091 -408.087067) (xy 200.449445 -408.124197) (xy 200.466198 -408.14498)
			(xy 200.476095 -408.156785) (xy 200.501419 -408.174304) (xy 200.530812 -408.18348) (xy 200.561604 -408.18348)
			(xy 200.590997 -408.174304) (xy 200.616321 -408.156785) (xy 200.626218 -408.14498) (xy 200.642971 -408.124197)
			(xy 200.681325 -408.087067) (xy 200.724479 -408.055645) (xy 200.771593 -408.030546) (xy 200.821745 -408.01226)
			(xy 200.873956 -408.001143) (xy 200.927208 -407.997413) (xy 200.98046 -408.001143) (xy 201.032671 -408.01226)
			(xy 201.082823 -408.030546) (xy 201.129937 -408.055645) (xy 201.173091 -408.087067) (xy 201.211445 -408.124197)
			(xy 201.228198 -408.14498) (xy 201.238095 -408.156785) (xy 201.263419 -408.174304) (xy 201.292812 -408.18348)
			(xy 201.323604 -408.18348) (xy 201.352997 -408.174304) (xy 201.378321 -408.156785) (xy 201.388218 -408.14498)
			(xy 201.404971 -408.124197) (xy 201.443325 -408.087067) (xy 201.486479 -408.055645) (xy 201.533593 -408.030546)
			(xy 201.583745 -408.01226) (xy 201.635956 -408.001143) (xy 201.689208 -407.997413) (xy 201.74246 -408.001143)
			(xy 201.794671 -408.01226) (xy 201.844823 -408.030546) (xy 201.891937 -408.055645) (xy 201.935091 -408.087067)
			(xy 201.973445 -408.124197) (xy 201.990198 -408.14498) (xy 202.000095 -408.156785) (xy 202.025419 -408.174304)
			(xy 202.054812 -408.18348) (xy 202.085604 -408.18348) (xy 202.114997 -408.174304) (xy 202.140321 -408.156785)
			(xy 202.150218 -408.14498) (xy 202.168394 -408.122484) (xy 202.210417 -408.08275) (xy 202.257956 -408.049813)
			(xy 202.30992 -408.024427) (xy 202.36512 -408.007174) (xy 202.422291 -407.998448) (xy 202.451208 -407.997914)
			(xy 202.47846 -407.998356) (xy 202.53241 -408.006114) (xy 202.584707 -408.021471) (xy 202.634286 -408.044114)
			(xy 202.680138 -408.073582) (xy 202.72133 -408.109276) (xy 202.757023 -408.150468) (xy 202.78649 -408.196321)
			(xy 202.809132 -408.2459) (xy 202.824487 -408.298197) (xy 202.832244 -408.352148) (xy 202.832244 -408.406652)
			(xy 202.824487 -408.460603) (xy 202.809132 -408.5129) (xy 202.78649 -408.562479) (xy 202.757023 -408.608332)
			(xy 202.72133 -408.649524) (xy 202.680138 -408.685218) (xy 202.634286 -408.714686) (xy 202.584707 -408.737329)
			(xy 202.53241 -408.752686) (xy 202.47846 -408.760444) (xy 202.451208 -408.76093) (xy 202.42229 -408.760432)
			(xy 202.365117 -408.751703) (xy 202.309916 -408.734443) (xy 202.257954 -408.709047) (xy 202.210421 -408.676099)
			(xy 202.168406 -408.636352) (xy 202.150218 -408.613864) (xy 202.140321 -408.602059) (xy 202.114997 -408.58454)
			(xy 202.085604 -408.575364) (xy 202.054812 -408.575364) (xy 202.025419 -408.58454) (xy 202.000095 -408.602059)
			(xy 201.990198 -408.613864) (xy 201.973445 -408.634647) (xy 201.935091 -408.671777) (xy 201.891937 -408.703199)
			(xy 201.844823 -408.728298) (xy 201.794671 -408.746584) (xy 201.74246 -408.757701) (xy 201.689208 -408.761431)
			(xy 201.635956 -408.757701) (xy 201.583745 -408.746584) (xy 201.533593 -408.728298) (xy 201.486479 -408.703199)
			(xy 201.443325 -408.671777) (xy 201.404971 -408.634647) (xy 201.388218 -408.613864) (xy 201.378321 -408.602059)
			(xy 201.352997 -408.58454) (xy 201.323604 -408.575364) (xy 201.292812 -408.575364) (xy 201.263419 -408.58454)
			(xy 201.238095 -408.602059) (xy 201.228198 -408.613864) (xy 201.211445 -408.634647) (xy 201.173091 -408.671777)
			(xy 201.129937 -408.703199) (xy 201.082823 -408.728298) (xy 201.032671 -408.746584) (xy 200.98046 -408.757701)
			(xy 200.927208 -408.761431) (xy 200.873956 -408.757701) (xy 200.821745 -408.746584) (xy 200.771593 -408.728298)
			(xy 200.724479 -408.703199) (xy 200.681325 -408.671777) (xy 200.642971 -408.634647) (xy 200.626218 -408.613864)
			(xy 200.616321 -408.602059) (xy 200.590997 -408.58454) (xy 200.561604 -408.575364) (xy 200.530812 -408.575364)
			(xy 200.501419 -408.58454) (xy 200.476095 -408.602059) (xy 200.466198 -408.613864) (xy 200.449445 -408.634647)
			(xy 200.411091 -408.671777) (xy 200.367937 -408.703199) (xy 200.320823 -408.728298) (xy 200.270671 -408.746584)
			(xy 200.21846 -408.757701) (xy 200.165208 -408.761431) (xy 200.111956 -408.757701) (xy 200.059745 -408.746584)
			(xy 200.009593 -408.728298) (xy 199.962479 -408.703199) (xy 199.919325 -408.671777) (xy 199.880971 -408.634647)
			(xy 199.864218 -408.613864) (xy 199.854321 -408.602059) (xy 199.828997 -408.58454) (xy 199.799604 -408.575364)
			(xy 199.768812 -408.575364) (xy 199.739419 -408.58454) (xy 199.714095 -408.602059) (xy 199.704198 -408.613864)
			(xy 199.687445 -408.634647) (xy 199.649091 -408.671777) (xy 199.605937 -408.703199) (xy 199.558823 -408.728298)
			(xy 199.508671 -408.746584) (xy 199.45646 -408.757701) (xy 199.403208 -408.761431) (xy 199.349956 -408.757701)
			(xy 199.297745 -408.746584) (xy 199.247593 -408.728298) (xy 199.200479 -408.703199) (xy 199.157325 -408.671777)
			(xy 199.118971 -408.634647) (xy 199.102218 -408.613864) (xy 199.092321 -408.602059) (xy 199.066997 -408.58454)
			(xy 199.037604 -408.575364) (xy 199.006812 -408.575364) (xy 198.977419 -408.58454) (xy 198.952095 -408.602059)
			(xy 198.942198 -408.613864) (xy 198.925445 -408.634647) (xy 198.887091 -408.671777) (xy 198.843937 -408.703199)
			(xy 198.796823 -408.728298) (xy 198.746671 -408.746584) (xy 198.69446 -408.757701) (xy 198.641208 -408.761431)
			(xy 198.587956 -408.757701) (xy 198.535745 -408.746584) (xy 198.485593 -408.728298) (xy 198.438479 -408.703199)
			(xy 198.395325 -408.671777) (xy 198.356971 -408.634647) (xy 198.340218 -408.613864) (xy 198.330321 -408.602059)
			(xy 198.304997 -408.58454) (xy 198.275604 -408.575364) (xy 198.244812 -408.575364) (xy 198.215419 -408.58454)
			(xy 198.190095 -408.602059) (xy 198.180198 -408.613864) (xy 198.161999 -408.636341) (xy 198.119982 -408.676078)
			(xy 198.072449 -408.709019) (xy 198.020489 -408.734409) (xy 197.965293 -408.751666) (xy 197.908124 -408.760395)
			(xy 197.879208 -408.76093) (xy 197.851956 -408.760423) (xy 197.798008 -408.752668) (xy 197.745712 -408.737313)
			(xy 197.696134 -408.714672) (xy 197.650282 -408.685206) (xy 197.609091 -408.649515) (xy 197.573398 -408.608324)
			(xy 197.543931 -408.562473) (xy 197.52129 -408.512896) (xy 197.505934 -408.4606) (xy 197.498177 -408.406652)
			(xy 196.934328 -408.406652) (xy 196.934328 -408.944572) (xy 196.934823 -408.959324) (xy 196.943255 -408.987596)
			(xy 196.959423 -409.012274) (xy 196.981976 -409.031296) (xy 197.009027 -409.04307) (xy 197.038316 -409.046614)
			(xy 197.052946 -409.044648) (xy 197.068891 -409.042127) (xy 197.101065 -409.039453) (xy 197.117208 -409.039314)
			(xy 197.146124 -409.039849) (xy 197.203294 -409.048577) (xy 197.258493 -409.065832) (xy 197.310455 -409.09122)
			(xy 197.357992 -409.124157) (xy 197.400013 -409.163891) (xy 197.418198 -409.18638) (xy 197.428095 -409.198185)
			(xy 197.453419 -409.215704) (xy 197.482812 -409.22488) (xy 197.513604 -409.22488) (xy 197.542997 -409.215704)
			(xy 197.568321 -409.198185) (xy 197.578218 -409.18638) (xy 197.594971 -409.165597) (xy 197.633325 -409.128467)
			(xy 197.676479 -409.097045) (xy 197.723593 -409.071946) (xy 197.773745 -409.05366) (xy 197.825956 -409.042543)
			(xy 197.879208 -409.038813) (xy 197.93246 -409.042543) (xy 197.984671 -409.05366) (xy 198.034823 -409.071946)
			(xy 198.081937 -409.097045) (xy 198.125091 -409.128467) (xy 198.163445 -409.165597) (xy 198.180198 -409.18638)
			(xy 198.190095 -409.198185) (xy 198.215419 -409.215704) (xy 198.244812 -409.22488) (xy 198.275604 -409.22488)
			(xy 198.304997 -409.215704) (xy 198.330321 -409.198185) (xy 198.340218 -409.18638) (xy 198.356971 -409.165597)
			(xy 198.395325 -409.128467) (xy 198.438479 -409.097045) (xy 198.485593 -409.071946) (xy 198.535745 -409.05366)
			(xy 198.587956 -409.042543) (xy 198.641208 -409.038813) (xy 198.69446 -409.042543) (xy 198.746671 -409.05366)
			(xy 198.796823 -409.071946) (xy 198.843937 -409.097045) (xy 198.887091 -409.128467) (xy 198.925445 -409.165597)
			(xy 198.942198 -409.18638) (xy 198.952095 -409.198185) (xy 198.977419 -409.215704) (xy 199.006812 -409.22488)
			(xy 199.037604 -409.22488) (xy 199.066997 -409.215704) (xy 199.092321 -409.198185) (xy 199.102218 -409.18638)
			(xy 199.118971 -409.165597) (xy 199.157325 -409.128467) (xy 199.200479 -409.097045) (xy 199.247593 -409.071946)
			(xy 199.297745 -409.05366) (xy 199.349956 -409.042543) (xy 199.403208 -409.038813) (xy 199.45646 -409.042543)
			(xy 199.508671 -409.05366) (xy 199.558823 -409.071946) (xy 199.605937 -409.097045) (xy 199.649091 -409.128467)
			(xy 199.687445 -409.165597) (xy 199.704198 -409.18638) (xy 199.714095 -409.198185) (xy 199.739419 -409.215704)
			(xy 199.768812 -409.22488) (xy 199.799604 -409.22488) (xy 199.828997 -409.215704) (xy 199.854321 -409.198185)
			(xy 199.864218 -409.18638) (xy 199.880971 -409.165597) (xy 199.919325 -409.128467) (xy 199.962479 -409.097045)
			(xy 200.009593 -409.071946) (xy 200.059745 -409.05366) (xy 200.111956 -409.042543) (xy 200.165208 -409.038813)
			(xy 200.21846 -409.042543) (xy 200.270671 -409.05366) (xy 200.320823 -409.071946) (xy 200.367937 -409.097045)
			(xy 200.411091 -409.128467) (xy 200.449445 -409.165597) (xy 200.466198 -409.18638) (xy 200.476095 -409.198185)
			(xy 200.501419 -409.215704) (xy 200.530812 -409.22488) (xy 200.561604 -409.22488) (xy 200.590997 -409.215704)
			(xy 200.616321 -409.198185) (xy 200.626218 -409.18638) (xy 200.642971 -409.165597) (xy 200.681325 -409.128467)
			(xy 200.724479 -409.097045) (xy 200.771593 -409.071946) (xy 200.821745 -409.05366) (xy 200.873956 -409.042543)
			(xy 200.927208 -409.038813) (xy 200.98046 -409.042543) (xy 201.032671 -409.05366) (xy 201.082823 -409.071946)
			(xy 201.129937 -409.097045) (xy 201.173091 -409.128467) (xy 201.211445 -409.165597) (xy 201.228198 -409.18638)
			(xy 201.238095 -409.198185) (xy 201.263419 -409.215704) (xy 201.292812 -409.22488) (xy 201.323604 -409.22488)
			(xy 201.352997 -409.215704) (xy 201.378321 -409.198185) (xy 201.388218 -409.18638) (xy 201.404971 -409.165597)
			(xy 201.443325 -409.128467) (xy 201.486479 -409.097045) (xy 201.533593 -409.071946) (xy 201.583745 -409.05366)
			(xy 201.635956 -409.042543) (xy 201.689208 -409.038813) (xy 201.74246 -409.042543) (xy 201.794671 -409.05366)
			(xy 201.844823 -409.071946) (xy 201.891937 -409.097045) (xy 201.935091 -409.128467) (xy 201.973445 -409.165597)
			(xy 201.990198 -409.18638) (xy 202.000095 -409.198185) (xy 202.025419 -409.215704) (xy 202.054812 -409.22488)
			(xy 202.085604 -409.22488) (xy 202.114997 -409.215704) (xy 202.140321 -409.198185) (xy 202.150218 -409.18638)
			(xy 202.168408 -409.163895) (xy 202.210425 -409.124154) (xy 202.257959 -409.09121) (xy 202.309921 -409.065819)
			(xy 202.36512 -409.048561) (xy 202.422291 -409.039833) (xy 202.451208 -409.039314) (xy 202.478457 -409.039801)
			(xy 202.532401 -409.047558) (xy 202.584692 -409.062913) (xy 202.634265 -409.085553) (xy 202.680112 -409.115018)
			(xy 202.721299 -409.150707) (xy 202.756987 -409.191895) (xy 202.786451 -409.237742) (xy 202.80909 -409.287316)
			(xy 202.824444 -409.339607) (xy 202.8322 -409.393551) (xy 202.8322 -409.448049) (xy 202.824444 -409.501993)
			(xy 202.80909 -409.554284) (xy 202.786451 -409.603858) (xy 202.756987 -409.649705) (xy 202.721299 -409.690893)
			(xy 202.680112 -409.726582) (xy 202.634265 -409.756047) (xy 202.584692 -409.778687) (xy 202.532401 -409.794042)
			(xy 202.478457 -409.801799) (xy 202.451208 -409.80233) (xy 202.422292 -409.801796) (xy 202.365122 -409.793069)
			(xy 202.309923 -409.775814) (xy 202.257962 -409.750425) (xy 202.210427 -409.717485) (xy 202.168408 -409.677749)
			(xy 202.150218 -409.655264) (xy 202.140321 -409.643459) (xy 202.114997 -409.62594) (xy 202.085604 -409.616764)
			(xy 202.054812 -409.616764) (xy 202.025419 -409.62594) (xy 202.000095 -409.643459) (xy 201.990198 -409.655264)
			(xy 201.973445 -409.676047) (xy 201.935091 -409.713177) (xy 201.891937 -409.744599) (xy 201.844823 -409.769698)
			(xy 201.794671 -409.787984) (xy 201.74246 -409.799101) (xy 201.689208 -409.802831) (xy 201.635956 -409.799101)
			(xy 201.583745 -409.787984) (xy 201.533593 -409.769698) (xy 201.486479 -409.744599) (xy 201.443325 -409.713177)
			(xy 201.404971 -409.676047) (xy 201.388218 -409.655264) (xy 201.378321 -409.643459) (xy 201.352997 -409.62594)
			(xy 201.323604 -409.616764) (xy 201.292812 -409.616764) (xy 201.263419 -409.62594) (xy 201.238095 -409.643459)
			(xy 201.228198 -409.655264) (xy 201.211445 -409.676047) (xy 201.173091 -409.713177) (xy 201.129937 -409.744599)
			(xy 201.082823 -409.769698) (xy 201.032671 -409.787984) (xy 200.98046 -409.799101) (xy 200.927208 -409.802831)
			(xy 200.873956 -409.799101) (xy 200.821745 -409.787984) (xy 200.771593 -409.769698) (xy 200.724479 -409.744599)
			(xy 200.681325 -409.713177) (xy 200.642971 -409.676047) (xy 200.626218 -409.655264) (xy 200.616321 -409.643459)
			(xy 200.590997 -409.62594) (xy 200.561604 -409.616764) (xy 200.530812 -409.616764) (xy 200.501419 -409.62594)
			(xy 200.476095 -409.643459) (xy 200.466198 -409.655264) (xy 200.449445 -409.676047) (xy 200.411091 -409.713177)
			(xy 200.367937 -409.744599) (xy 200.320823 -409.769698) (xy 200.270671 -409.787984) (xy 200.21846 -409.799101)
			(xy 200.165208 -409.802831) (xy 200.111956 -409.799101) (xy 200.059745 -409.787984) (xy 200.009593 -409.769698)
			(xy 199.962479 -409.744599) (xy 199.919325 -409.713177) (xy 199.880971 -409.676047) (xy 199.864218 -409.655264)
			(xy 199.854321 -409.643459) (xy 199.828997 -409.62594) (xy 199.799604 -409.616764) (xy 199.768812 -409.616764)
			(xy 199.739419 -409.62594) (xy 199.714095 -409.643459) (xy 199.704198 -409.655264) (xy 199.687445 -409.676047)
			(xy 199.649091 -409.713177) (xy 199.605937 -409.744599) (xy 199.558823 -409.769698) (xy 199.508671 -409.787984)
			(xy 199.45646 -409.799101) (xy 199.403208 -409.802831) (xy 199.349956 -409.799101) (xy 199.297745 -409.787984)
			(xy 199.247593 -409.769698) (xy 199.200479 -409.744599) (xy 199.157325 -409.713177) (xy 199.118971 -409.676047)
			(xy 199.102218 -409.655264) (xy 199.092321 -409.643459) (xy 199.066997 -409.62594) (xy 199.037604 -409.616764)
			(xy 199.006812 -409.616764) (xy 198.977419 -409.62594) (xy 198.952095 -409.643459) (xy 198.942198 -409.655264)
			(xy 198.925445 -409.676047) (xy 198.887091 -409.713177) (xy 198.843937 -409.744599) (xy 198.796823 -409.769698)
			(xy 198.746671 -409.787984) (xy 198.69446 -409.799101) (xy 198.641208 -409.802831) (xy 198.587956 -409.799101)
			(xy 198.535745 -409.787984) (xy 198.485593 -409.769698) (xy 198.438479 -409.744599) (xy 198.395325 -409.713177)
			(xy 198.356971 -409.676047) (xy 198.340218 -409.655264) (xy 198.330321 -409.643459) (xy 198.304997 -409.62594)
			(xy 198.275604 -409.616764) (xy 198.244812 -409.616764) (xy 198.215419 -409.62594) (xy 198.190095 -409.643459)
			(xy 198.180198 -409.655264) (xy 198.163445 -409.676047) (xy 198.125091 -409.713177) (xy 198.081937 -409.744599)
			(xy 198.034823 -409.769698) (xy 197.984671 -409.787984) (xy 197.93246 -409.799101) (xy 197.879208 -409.802831)
			(xy 197.825956 -409.799101) (xy 197.773745 -409.787984) (xy 197.723593 -409.769698) (xy 197.676479 -409.744599)
			(xy 197.633325 -409.713177) (xy 197.594971 -409.676047) (xy 197.578218 -409.655264) (xy 197.568321 -409.643459)
			(xy 197.542997 -409.62594) (xy 197.513604 -409.616764) (xy 197.482812 -409.616764) (xy 197.453419 -409.62594)
			(xy 197.428095 -409.643459) (xy 197.418198 -409.655264) (xy 197.400008 -409.677748) (xy 197.357991 -409.717485)
			(xy 197.310456 -409.750423) (xy 197.258493 -409.775807) (xy 197.203294 -409.793055) (xy 197.146124 -409.801772)
			(xy 197.117208 -409.80233) (xy 197.101065 -409.802197) (xy 197.06889 -409.799524) (xy 197.052946 -409.796996)
			(xy 197.038327 -409.795026) (xy 197.009061 -409.798613) (xy 196.982038 -409.810407) (xy 196.959505 -409.829424)
			(xy 196.94334 -409.854083) (xy 196.934887 -409.88233) (xy 196.934328 -409.897072) (xy 196.934328 -409.938474)
			(xy 197.418706 -410.422852) (xy 204.203554 -410.422852) (xy 204.715872 -409.910534) (xy 204.715872 -409.31084)
			(xy 204.715321 -409.295787) (xy 204.706528 -409.266994) (xy 204.689722 -409.242015) (xy 204.666365 -409.22302)
			(xy 204.638485 -409.211659) (xy 204.608503 -409.208919) (xy 204.579026 -409.215038) (xy 204.565504 -409.221686)
			(xy 204.537152 -409.236543) (xy 204.476715 -409.257609) (xy 204.41361 -409.268292) (xy 204.381608 -409.26893)
			(xy 204.354353 -409.268468) (xy 204.300398 -409.260711) (xy 204.248096 -409.245355) (xy 204.198512 -409.222712)
			(xy 204.152655 -409.193242) (xy 204.111459 -409.157546) (xy 204.075763 -409.116351) (xy 204.046292 -409.070495)
			(xy 204.023648 -409.020911) (xy 204.008291 -408.96861) (xy 204.000533 -408.914655) (xy 204.000533 -408.860145)
			(xy 204.008291 -408.80619) (xy 204.023648 -408.753889) (xy 204.046292 -408.704305) (xy 204.075763 -408.658449)
			(xy 204.111459 -408.617254) (xy 204.152655 -408.581558) (xy 204.198512 -408.552088) (xy 204.248096 -408.529445)
			(xy 204.300398 -408.514089) (xy 204.354353 -408.506332) (xy 204.381608 -408.505914) (xy 204.413609 -408.506567)
			(xy 204.476712 -408.517249) (xy 204.537148 -408.538311) (xy 204.565504 -408.553158) (xy 204.578983 -408.559916)
			(xy 204.608491 -408.566046) (xy 204.638503 -408.563305) (xy 204.666411 -408.55193) (xy 204.689789 -408.53291)
			(xy 204.706604 -408.5079) (xy 204.715394 -408.479073) (xy 204.715872 -408.464004) (xy 204.715872 -404.84552)
			(xy 204.71637 -404.819539) (xy 204.724534 -404.768223) (xy 204.740631 -404.718817) (xy 204.764264 -404.67254)
			(xy 204.794852 -404.630535) (xy 204.8129 -404.61184) (xy 206.06512 -403.35962) (xy 206.075327 -403.349595)
			(xy 206.097201 -403.331154) (xy 206.108808 -403.32279) (xy 206.093455 -403.299077) (xy 206.06916 -403.248079)
			(xy 206.05266 -403.194053) (xy 206.044316 -403.138183) (xy 206.043784 -403.109938) (xy 206.04427 -403.082687)
			(xy 206.052026 -403.028739) (xy 206.067381 -402.976444) (xy 206.090023 -402.926867) (xy 206.119489 -402.881017)
			(xy 206.15518 -402.839826) (xy 206.196371 -402.804135) (xy 206.242221 -402.774669) (xy 206.291798 -402.752027)
			(xy 206.344093 -402.736672) (xy 206.398041 -402.728916) (xy 206.452543 -402.728916) (xy 206.506491 -402.736672)
			(xy 206.558786 -402.752027) (xy 206.608363 -402.774669) (xy 206.654213 -402.804135) (xy 206.695404 -402.839826)
			(xy 206.731095 -402.881017) (xy 206.760561 -402.926867) (xy 206.783203 -402.976444) (xy 206.798558 -403.028739)
			(xy 206.806314 -403.082687) (xy 206.8068 -403.109938) (xy 206.80676 -403.120053) (xy 206.805741 -403.140256)
			(xy 206.804768 -403.150324) (xy 206.803757 -403.164491) (xy 206.808685 -403.192451) (xy 206.821116 -403.217977)
			(xy 206.840088 -403.239098) (xy 206.864139 -403.254185) (xy 206.891412 -403.262074) (xy 206.905606 -403.262592)
			(xy 207.558132 -403.262592) (xy 207.584111 -403.263094) (xy 207.635423 -403.271265) (xy 207.684823 -403.287369)
			(xy 207.731093 -403.311008) (xy 207.773091 -403.3416) (xy 207.791812 -403.35962) (xy 208.036414 -403.603968)
			(xy 208.048606 -403.607778) (xy 208.074047 -403.615984) (xy 208.122517 -403.638523) (xy 208.167367 -403.667607)
			(xy 208.207718 -403.702667) (xy 208.242781 -403.743017) (xy 208.271867 -403.787865) (xy 208.294409 -403.836335)
			(xy 208.302606 -403.861778) (xy 208.306416 -403.87397) (xy 208.458117 -404.025862) (xy 209.035648 -404.025862)
			(xy 209.039719 -403.97024) (xy 209.051845 -403.915803) (xy 209.071768 -403.863712) (xy 209.099064 -403.815077)
			(xy 209.13315 -403.770934) (xy 209.173299 -403.732225) (xy 209.218657 -403.699774) (xy 209.268257 -403.674273)
			(xy 209.321041 -403.656266) (xy 209.375884 -403.646136) (xy 209.431618 -403.644099) (xy 209.487055 -403.650199)
			(xy 209.541012 -403.664305) (xy 209.592341 -403.686117) (xy 209.639947 -403.715171) (xy 209.682815 -403.750846)
			(xy 209.720032 -403.792383) (xy 209.750805 -403.838896) (xy 209.774477 -403.889393) (xy 209.790545 -403.9428)
			(xy 209.798665 -403.997976) (xy 209.799174 -404.025862) (xy 210.458048 -404.025862) (xy 210.462119 -403.97024)
			(xy 210.474245 -403.915803) (xy 210.494168 -403.863712) (xy 210.521464 -403.815077) (xy 210.55555 -403.770934)
			(xy 210.595699 -403.732225) (xy 210.641057 -403.699774) (xy 210.690657 -403.674273) (xy 210.743441 -403.656266)
			(xy 210.798284 -403.646136) (xy 210.854018 -403.644099) (xy 210.909455 -403.650199) (xy 210.963412 -403.664305)
			(xy 211.014741 -403.686117) (xy 211.062347 -403.715171) (xy 211.105215 -403.750846) (xy 211.142432 -403.792383)
			(xy 211.173205 -403.838896) (xy 211.196877 -403.889393) (xy 211.212945 -403.9428) (xy 211.221065 -403.997976)
			(xy 211.221574 -404.025862) (xy 211.855048 -404.025862) (xy 211.859119 -403.97024) (xy 211.871245 -403.915803)
			(xy 211.891168 -403.863712) (xy 211.918464 -403.815077) (xy 211.95255 -403.770934) (xy 211.992699 -403.732225)
			(xy 212.038057 -403.699774) (xy 212.087657 -403.674273) (xy 212.140441 -403.656266) (xy 212.195284 -403.646136)
			(xy 212.251018 -403.644099) (xy 212.306455 -403.650199) (xy 212.360412 -403.664305) (xy 212.411741 -403.686117)
			(xy 212.459347 -403.715171) (xy 212.502215 -403.750846) (xy 212.539432 -403.792383) (xy 212.549382 -403.807422)
			(xy 214.66759 -403.807422) (xy 214.671661 -403.7518) (xy 214.683787 -403.697363) (xy 214.70371 -403.645272)
			(xy 214.731006 -403.596637) (xy 214.765092 -403.552494) (xy 214.805241 -403.513785) (xy 214.850599 -403.481334)
			(xy 214.900199 -403.455833) (xy 214.952983 -403.437826) (xy 215.007826 -403.427696) (xy 215.06356 -403.425659)
			(xy 215.118997 -403.431759) (xy 215.172954 -403.445865) (xy 215.224283 -403.467677) (xy 215.271889 -403.496731)
			(xy 215.314757 -403.532406) (xy 215.351974 -403.573943) (xy 215.382747 -403.620456) (xy 215.406419 -403.670953)
			(xy 215.422487 -403.72436) (xy 215.430607 -403.779536) (xy 215.431116 -403.807422) (xy 215.430607 -403.835308)
			(xy 215.422487 -403.890484) (xy 215.406419 -403.943891) (xy 215.382747 -403.994388) (xy 215.351974 -404.040901)
			(xy 215.314757 -404.082438) (xy 215.271889 -404.118113) (xy 215.224283 -404.147167) (xy 215.172954 -404.168979)
			(xy 215.118997 -404.183085) (xy 215.06356 -404.189185) (xy 215.007826 -404.187148) (xy 214.952983 -404.177018)
			(xy 214.900199 -404.159011) (xy 214.850599 -404.13351) (xy 214.805241 -404.101059) (xy 214.765092 -404.06235)
			(xy 214.731006 -404.018207) (xy 214.70371 -403.969572) (xy 214.683787 -403.917481) (xy 214.671661 -403.863044)
			(xy 214.66759 -403.807422) (xy 212.549382 -403.807422) (xy 212.570205 -403.838896) (xy 212.593877 -403.889393)
			(xy 212.609945 -403.9428) (xy 212.618065 -403.997976) (xy 212.618574 -404.025862) (xy 212.618065 -404.053748)
			(xy 212.609945 -404.108924) (xy 212.593877 -404.162331) (xy 212.570205 -404.212828) (xy 212.539432 -404.259341)
			(xy 212.502215 -404.300878) (xy 212.459347 -404.336553) (xy 212.411741 -404.365607) (xy 212.360412 -404.387419)
			(xy 212.306455 -404.401525) (xy 212.251018 -404.407625) (xy 212.195284 -404.405588) (xy 212.140441 -404.395458)
			(xy 212.087657 -404.377451) (xy 212.038057 -404.35195) (xy 211.992699 -404.319499) (xy 211.95255 -404.28079)
			(xy 211.918464 -404.236647) (xy 211.891168 -404.188012) (xy 211.871245 -404.135921) (xy 211.859119 -404.081484)
			(xy 211.855048 -404.025862) (xy 211.221574 -404.025862) (xy 211.221065 -404.053748) (xy 211.212945 -404.108924)
			(xy 211.196877 -404.162331) (xy 211.173205 -404.212828) (xy 211.142432 -404.259341) (xy 211.105215 -404.300878)
			(xy 211.062347 -404.336553) (xy 211.014741 -404.365607) (xy 210.963412 -404.387419) (xy 210.909455 -404.401525)
			(xy 210.854018 -404.407625) (xy 210.798284 -404.405588) (xy 210.743441 -404.395458) (xy 210.690657 -404.377451)
			(xy 210.641057 -404.35195) (xy 210.595699 -404.319499) (xy 210.55555 -404.28079) (xy 210.521464 -404.236647)
			(xy 210.494168 -404.188012) (xy 210.474245 -404.135921) (xy 210.462119 -404.081484) (xy 210.458048 -404.025862)
			(xy 209.799174 -404.025862) (xy 209.798665 -404.053748) (xy 209.790545 -404.108924) (xy 209.774477 -404.162331)
			(xy 209.750805 -404.212828) (xy 209.720032 -404.259341) (xy 209.682815 -404.300878) (xy 209.639947 -404.336553)
			(xy 209.592341 -404.365607) (xy 209.541012 -404.387419) (xy 209.487055 -404.401525) (xy 209.431618 -404.407625)
			(xy 209.375884 -404.405588) (xy 209.321041 -404.395458) (xy 209.268257 -404.377451) (xy 209.218657 -404.35195)
			(xy 209.173299 -404.319499) (xy 209.13315 -404.28079) (xy 209.099064 -404.236647) (xy 209.071768 -404.188012)
			(xy 209.051845 -404.135921) (xy 209.039719 -404.081484) (xy 209.035648 -404.025862) (xy 208.458117 -404.025862)
			(xy 208.5086 -404.076408) (xy 208.526612 -404.09513) (xy 208.557164 -404.137146) (xy 208.580777 -404.183419)
			(xy 208.596871 -404.232812) (xy 208.605051 -404.284114) (xy 208.605628 -404.310088) (xy 208.605628 -406.576014)
			(xy 208.927215 -406.576014) (xy 208.930942 -406.522764) (xy 208.942057 -406.470554) (xy 208.960341 -406.420404)
			(xy 208.985438 -406.373292) (xy 209.016857 -406.330138) (xy 209.053985 -406.291785) (xy 209.074766 -406.275032)
			(xy 209.086551 -406.265112) (xy 209.104073 -406.239795) (xy 209.113253 -406.210408) (xy 209.113257 -406.179619)
			(xy 209.104085 -406.150229) (xy 209.08657 -406.124908) (xy 209.074766 -406.115012) (xy 209.052281 -406.096823)
			(xy 209.012548 -406.054802) (xy 208.97961 -406.007266) (xy 208.954222 -405.955305) (xy 208.936966 -405.900107)
			(xy 208.928236 -405.842938) (xy 208.9277 -405.814022) (xy 208.928176 -405.786769) (xy 208.93593 -405.732818)
			(xy 208.951284 -405.68052) (xy 208.973924 -405.63094) (xy 209.003391 -405.585086) (xy 209.039083 -405.543893)
			(xy 209.080275 -405.508199) (xy 209.126127 -405.478731) (xy 209.175707 -405.456089) (xy 209.228005 -405.440733)
			(xy 209.281955 -405.432977) (xy 209.309208 -405.432514) (xy 209.338123 -405.433093) (xy 209.395291 -405.441809)
			(xy 209.450489 -405.459055) (xy 209.502451 -405.484435) (xy 209.549987 -405.517368) (xy 209.592006 -405.557099)
			(xy 209.610198 -405.57958) (xy 209.620095 -405.591385) (xy 209.645419 -405.608904) (xy 209.674812 -405.61808)
			(xy 209.705604 -405.61808) (xy 209.734997 -405.608904) (xy 209.760321 -405.591385) (xy 209.770218 -405.57958)
			(xy 209.786971 -405.558797) (xy 209.825325 -405.521667) (xy 209.868479 -405.490245) (xy 209.915593 -405.465146)
			(xy 209.965745 -405.44686) (xy 210.017956 -405.435743) (xy 210.071208 -405.432013) (xy 210.12446 -405.435743)
			(xy 210.176671 -405.44686) (xy 210.226823 -405.465146) (xy 210.273937 -405.490245) (xy 210.317091 -405.521667)
			(xy 210.355445 -405.558797) (xy 210.372198 -405.57958) (xy 210.382095 -405.591385) (xy 210.407419 -405.608904)
			(xy 210.436812 -405.61808) (xy 210.467604 -405.61808) (xy 210.496997 -405.608904) (xy 210.522321 -405.591385)
			(xy 210.532218 -405.57958) (xy 210.548971 -405.558797) (xy 210.587325 -405.521667) (xy 210.630479 -405.490245)
			(xy 210.677593 -405.465146) (xy 210.727745 -405.44686) (xy 210.779956 -405.435743) (xy 210.833208 -405.432013)
			(xy 210.88646 -405.435743) (xy 210.938671 -405.44686) (xy 210.988823 -405.465146) (xy 211.035937 -405.490245)
			(xy 211.079091 -405.521667) (xy 211.117445 -405.558797) (xy 211.134198 -405.57958) (xy 211.144095 -405.591385)
			(xy 211.169419 -405.608904) (xy 211.198812 -405.61808) (xy 211.229604 -405.61808) (xy 211.258997 -405.608904)
			(xy 211.284321 -405.591385) (xy 211.294218 -405.57958) (xy 211.310971 -405.558797) (xy 211.349325 -405.521667)
			(xy 211.392479 -405.490245) (xy 211.439593 -405.465146) (xy 211.489745 -405.44686) (xy 211.541956 -405.435743)
			(xy 211.595208 -405.432013) (xy 211.64846 -405.435743) (xy 211.700671 -405.44686) (xy 211.750823 -405.465146)
			(xy 211.797937 -405.490245) (xy 211.841091 -405.521667) (xy 211.879445 -405.558797) (xy 211.896198 -405.57958)
			(xy 211.906095 -405.591385) (xy 211.931419 -405.608904) (xy 211.960812 -405.61808) (xy 211.991604 -405.61808)
			(xy 212.020997 -405.608904) (xy 212.046321 -405.591385) (xy 212.056218 -405.57958) (xy 212.074394 -405.557084)
			(xy 212.116417 -405.51735) (xy 212.163956 -405.484413) (xy 212.21592 -405.459027) (xy 212.27112 -405.441774)
			(xy 212.328291 -405.433048) (xy 212.357208 -405.432514) (xy 212.384462 -405.432948) (xy 212.438415 -405.440707)
			(xy 212.490715 -405.456065) (xy 212.540297 -405.47871) (xy 212.586151 -405.508181) (xy 212.627344 -405.543877)
			(xy 212.663037 -405.585073) (xy 212.692505 -405.63093) (xy 212.715146 -405.680513) (xy 212.7305 -405.732814)
			(xy 212.738254 -405.786768) (xy 212.738716 -405.814022) (xy 212.738173 -405.842938) (xy 212.729454 -405.90011)
			(xy 212.712203 -405.95531) (xy 212.686816 -406.007272) (xy 212.653875 -406.054806) (xy 212.614135 -406.096822)
			(xy 212.59165 -406.115012) (xy 212.579819 -406.124883) (xy 212.562296 -406.150212) (xy 212.553119 -406.179613)
			(xy 212.553123 -406.210413) (xy 212.562308 -406.239812) (xy 212.579838 -406.265136) (xy 212.59165 -406.275032)
			(xy 212.612454 -406.29176) (xy 212.649584 -406.330116) (xy 212.681005 -406.373274) (xy 212.706103 -406.420391)
			(xy 212.724387 -406.470546) (xy 212.735502 -406.52276) (xy 212.73923 -406.576014) (xy 212.735499 -406.629267)
			(xy 212.72438 -406.68148) (xy 212.706092 -406.731634) (xy 212.68099 -406.778749) (xy 212.649567 -406.821904)
			(xy 212.612434 -406.860258) (xy 212.59165 -406.877012) (xy 212.579819 -406.886883) (xy 212.562296 -406.912212)
			(xy 212.553119 -406.941613) (xy 212.553123 -406.972413) (xy 212.562308 -407.001812) (xy 212.579838 -407.027136)
			(xy 212.59165 -407.037032) (xy 212.614159 -407.055192) (xy 212.653891 -407.09722) (xy 212.686825 -407.144762)
			(xy 212.712209 -407.196729) (xy 212.72946 -407.251931) (xy 212.738184 -407.309104) (xy 212.738716 -407.338022)
			(xy 212.738243 -407.365273) (xy 212.730483 -407.419221) (xy 212.715126 -407.471516) (xy 212.692483 -407.521092)
			(xy 212.663015 -407.566942) (xy 212.627322 -407.608132) (xy 212.586131 -407.643823) (xy 212.54028 -407.673289)
			(xy 212.490703 -407.695931) (xy 212.438407 -407.711286) (xy 212.384459 -407.719044) (xy 212.357208 -407.71953)
			(xy 212.32829 -407.719032) (xy 212.271117 -407.710303) (xy 212.215916 -407.693043) (xy 212.163954 -407.667647)
			(xy 212.116421 -407.634699) (xy 212.074406 -407.594952) (xy 212.056218 -407.572464) (xy 212.046321 -407.560659)
			(xy 212.020997 -407.54314) (xy 211.991604 -407.533964) (xy 211.960812 -407.533964) (xy 211.931419 -407.54314)
			(xy 211.906095 -407.560659) (xy 211.896198 -407.572464) (xy 211.879445 -407.593247) (xy 211.841091 -407.630377)
			(xy 211.797937 -407.661799) (xy 211.750823 -407.686898) (xy 211.700671 -407.705184) (xy 211.64846 -407.716301)
			(xy 211.595208 -407.720031) (xy 211.541956 -407.716301) (xy 211.489745 -407.705184) (xy 211.439593 -407.686898)
			(xy 211.392479 -407.661799) (xy 211.349325 -407.630377) (xy 211.310971 -407.593247) (xy 211.294218 -407.572464)
			(xy 211.284321 -407.560659) (xy 211.258997 -407.54314) (xy 211.229604 -407.533964) (xy 211.198812 -407.533964)
			(xy 211.169419 -407.54314) (xy 211.144095 -407.560659) (xy 211.134198 -407.572464) (xy 211.117445 -407.593247)
			(xy 211.079091 -407.630377) (xy 211.035937 -407.661799) (xy 210.988823 -407.686898) (xy 210.938671 -407.705184)
			(xy 210.88646 -407.716301) (xy 210.833208 -407.720031) (xy 210.779956 -407.716301) (xy 210.727745 -407.705184)
			(xy 210.677593 -407.686898) (xy 210.630479 -407.661799) (xy 210.587325 -407.630377) (xy 210.548971 -407.593247)
			(xy 210.532218 -407.572464) (xy 210.522321 -407.560659) (xy 210.496997 -407.54314) (xy 210.467604 -407.533964)
			(xy 210.436812 -407.533964) (xy 210.407419 -407.54314) (xy 210.382095 -407.560659) (xy 210.372198 -407.572464)
			(xy 210.355445 -407.593247) (xy 210.317091 -407.630377) (xy 210.273937 -407.661799) (xy 210.226823 -407.686898)
			(xy 210.176671 -407.705184) (xy 210.12446 -407.716301) (xy 210.071208 -407.720031) (xy 210.017956 -407.716301)
			(xy 209.965745 -407.705184) (xy 209.915593 -407.686898) (xy 209.868479 -407.661799) (xy 209.825325 -407.630377)
			(xy 209.786971 -407.593247) (xy 209.770218 -407.572464) (xy 209.760321 -407.560659) (xy 209.734997 -407.54314)
			(xy 209.705604 -407.533964) (xy 209.674812 -407.533964) (xy 209.645419 -407.54314) (xy 209.620095 -407.560659)
			(xy 209.610198 -407.572464) (xy 209.591999 -407.594941) (xy 209.549982 -407.634678) (xy 209.502449 -407.667619)
			(xy 209.450489 -407.693009) (xy 209.395293 -407.710266) (xy 209.338124 -407.718995) (xy 209.309208 -407.71953)
			(xy 209.281958 -407.719015) (xy 209.228012 -407.71126) (xy 209.17572 -407.695907) (xy 209.126144 -407.673268)
			(xy 209.080294 -407.643805) (xy 209.039105 -407.608117) (xy 209.003413 -407.56693) (xy 208.973946 -407.521083)
			(xy 208.951304 -407.471509) (xy 208.935946 -407.419217) (xy 208.928187 -407.365272) (xy 208.9277 -407.338022)
			(xy 208.928234 -407.309106) (xy 208.93696 -407.251935) (xy 208.954215 -407.196737) (xy 208.979603 -407.144775)
			(xy 209.012544 -407.097241) (xy 209.052282 -407.055223) (xy 209.074766 -407.037032) (xy 209.086551 -407.027112)
			(xy 209.104073 -407.001795) (xy 209.113253 -406.972408) (xy 209.113257 -406.941619) (xy 209.104085 -406.912229)
			(xy 209.08657 -406.886908) (xy 209.074766 -406.877012) (xy 209.054005 -406.860233) (xy 209.016874 -406.821883)
			(xy 208.985452 -406.778731) (xy 208.960352 -406.731621) (xy 208.942064 -406.681472) (xy 208.930946 -406.629263)
			(xy 208.927215 -406.576014) (xy 208.605628 -406.576014) (xy 208.605628 -407.30932) (xy 208.605127 -407.335299)
			(xy 208.596958 -407.386613) (xy 208.580856 -407.436015) (xy 208.557219 -407.482287) (xy 208.526629 -407.524287)
			(xy 208.5086 -407.543) (xy 207.645132 -408.406652) (xy 208.166177 -408.406652) (xy 208.166177 -408.352148)
			(xy 208.173934 -408.2982) (xy 208.18929 -408.245904) (xy 208.211931 -408.196327) (xy 208.241398 -408.150476)
			(xy 208.277091 -408.109285) (xy 208.318282 -408.073594) (xy 208.364134 -408.044128) (xy 208.413712 -408.021487)
			(xy 208.466008 -408.006132) (xy 208.519956 -407.998377) (xy 208.547208 -407.997914) (xy 208.576123 -407.998493)
			(xy 208.633291 -408.007209) (xy 208.688489 -408.024455) (xy 208.740451 -408.049835) (xy 208.787987 -408.082768)
			(xy 208.830006 -408.122499) (xy 208.848198 -408.14498) (xy 208.858095 -408.156785) (xy 208.883419 -408.174304)
			(xy 208.912812 -408.18348) (xy 208.943604 -408.18348) (xy 208.972997 -408.174304) (xy 208.998321 -408.156785)
			(xy 209.008218 -408.14498) (xy 209.024971 -408.124197) (xy 209.063325 -408.087067) (xy 209.106479 -408.055645)
			(xy 209.153593 -408.030546) (xy 209.203745 -408.01226) (xy 209.255956 -408.001143) (xy 209.309208 -407.997413)
			(xy 209.36246 -408.001143) (xy 209.414671 -408.01226) (xy 209.464823 -408.030546) (xy 209.511937 -408.055645)
			(xy 209.555091 -408.087067) (xy 209.593445 -408.124197) (xy 209.610198 -408.14498) (xy 209.620095 -408.156785)
			(xy 209.645419 -408.174304) (xy 209.674812 -408.18348) (xy 209.705604 -408.18348) (xy 209.734997 -408.174304)
			(xy 209.760321 -408.156785) (xy 209.770218 -408.14498) (xy 209.786971 -408.124197) (xy 209.825325 -408.087067)
			(xy 209.868479 -408.055645) (xy 209.915593 -408.030546) (xy 209.965745 -408.01226) (xy 210.017956 -408.001143)
			(xy 210.071208 -407.997413) (xy 210.12446 -408.001143) (xy 210.176671 -408.01226) (xy 210.226823 -408.030546)
			(xy 210.273937 -408.055645) (xy 210.317091 -408.087067) (xy 210.355445 -408.124197) (xy 210.372198 -408.14498)
			(xy 210.382095 -408.156785) (xy 210.407419 -408.174304) (xy 210.436812 -408.18348) (xy 210.467604 -408.18348)
			(xy 210.496997 -408.174304) (xy 210.522321 -408.156785) (xy 210.532218 -408.14498) (xy 210.548971 -408.124197)
			(xy 210.587325 -408.087067) (xy 210.630479 -408.055645) (xy 210.677593 -408.030546) (xy 210.727745 -408.01226)
			(xy 210.779956 -408.001143) (xy 210.833208 -407.997413) (xy 210.88646 -408.001143) (xy 210.938671 -408.01226)
			(xy 210.988823 -408.030546) (xy 211.035937 -408.055645) (xy 211.079091 -408.087067) (xy 211.117445 -408.124197)
			(xy 211.134198 -408.14498) (xy 211.144095 -408.156785) (xy 211.169419 -408.174304) (xy 211.198812 -408.18348)
			(xy 211.229604 -408.18348) (xy 211.258997 -408.174304) (xy 211.284321 -408.156785) (xy 211.294218 -408.14498)
			(xy 211.310971 -408.124197) (xy 211.349325 -408.087067) (xy 211.392479 -408.055645) (xy 211.439593 -408.030546)
			(xy 211.489745 -408.01226) (xy 211.541956 -408.001143) (xy 211.595208 -407.997413) (xy 211.64846 -408.001143)
			(xy 211.700671 -408.01226) (xy 211.750823 -408.030546) (xy 211.797937 -408.055645) (xy 211.841091 -408.087067)
			(xy 211.879445 -408.124197) (xy 211.896198 -408.14498) (xy 211.906095 -408.156785) (xy 211.931419 -408.174304)
			(xy 211.960812 -408.18348) (xy 211.991604 -408.18348) (xy 212.020997 -408.174304) (xy 212.046321 -408.156785)
			(xy 212.056218 -408.14498) (xy 212.072971 -408.124197) (xy 212.111325 -408.087067) (xy 212.154479 -408.055645)
			(xy 212.201593 -408.030546) (xy 212.251745 -408.01226) (xy 212.303956 -408.001143) (xy 212.357208 -407.997413)
			(xy 212.41046 -408.001143) (xy 212.462671 -408.01226) (xy 212.512823 -408.030546) (xy 212.559937 -408.055645)
			(xy 212.603091 -408.087067) (xy 212.641445 -408.124197) (xy 212.658198 -408.14498) (xy 212.668095 -408.156785)
			(xy 212.693419 -408.174304) (xy 212.722812 -408.18348) (xy 212.753604 -408.18348) (xy 212.782997 -408.174304)
			(xy 212.808321 -408.156785) (xy 212.818218 -408.14498) (xy 212.836394 -408.122484) (xy 212.878417 -408.08275)
			(xy 212.925956 -408.049813) (xy 212.97792 -408.024427) (xy 213.03312 -408.007174) (xy 213.090291 -407.998448)
			(xy 213.119208 -407.997914) (xy 213.14646 -407.998356) (xy 213.20041 -408.006114) (xy 213.252707 -408.021471)
			(xy 213.302286 -408.044114) (xy 213.348138 -408.073582) (xy 213.38933 -408.109276) (xy 213.425023 -408.150468)
			(xy 213.45449 -408.196321) (xy 213.477132 -408.2459) (xy 213.492487 -408.298197) (xy 213.500244 -408.352148)
			(xy 213.500244 -408.406652) (xy 213.492487 -408.460603) (xy 213.477132 -408.5129) (xy 213.45449 -408.562479)
			(xy 213.425023 -408.608332) (xy 213.38933 -408.649524) (xy 213.348138 -408.685218) (xy 213.302286 -408.714686)
			(xy 213.252707 -408.737329) (xy 213.20041 -408.752686) (xy 213.14646 -408.760444) (xy 213.119208 -408.76093)
			(xy 213.09029 -408.760432) (xy 213.033117 -408.751703) (xy 212.977916 -408.734443) (xy 212.925954 -408.709047)
			(xy 212.878421 -408.676099) (xy 212.836406 -408.636352) (xy 212.818218 -408.613864) (xy 212.808321 -408.602059)
			(xy 212.782997 -408.58454) (xy 212.753604 -408.575364) (xy 212.722812 -408.575364) (xy 212.693419 -408.58454)
			(xy 212.668095 -408.602059) (xy 212.658198 -408.613864) (xy 212.641445 -408.634647) (xy 212.603091 -408.671777)
			(xy 212.559937 -408.703199) (xy 212.512823 -408.728298) (xy 212.462671 -408.746584) (xy 212.41046 -408.757701)
			(xy 212.357208 -408.761431) (xy 212.303956 -408.757701) (xy 212.251745 -408.746584) (xy 212.201593 -408.728298)
			(xy 212.154479 -408.703199) (xy 212.111325 -408.671777) (xy 212.072971 -408.634647) (xy 212.056218 -408.613864)
			(xy 212.046321 -408.602059) (xy 212.020997 -408.58454) (xy 211.991604 -408.575364) (xy 211.960812 -408.575364)
			(xy 211.931419 -408.58454) (xy 211.906095 -408.602059) (xy 211.896198 -408.613864) (xy 211.879445 -408.634647)
			(xy 211.841091 -408.671777) (xy 211.797937 -408.703199) (xy 211.750823 -408.728298) (xy 211.700671 -408.746584)
			(xy 211.64846 -408.757701) (xy 211.595208 -408.761431) (xy 211.541956 -408.757701) (xy 211.489745 -408.746584)
			(xy 211.439593 -408.728298) (xy 211.392479 -408.703199) (xy 211.349325 -408.671777) (xy 211.310971 -408.634647)
			(xy 211.294218 -408.613864) (xy 211.284321 -408.602059) (xy 211.258997 -408.58454) (xy 211.229604 -408.575364)
			(xy 211.198812 -408.575364) (xy 211.169419 -408.58454) (xy 211.144095 -408.602059) (xy 211.134198 -408.613864)
			(xy 211.117445 -408.634647) (xy 211.079091 -408.671777) (xy 211.035937 -408.703199) (xy 210.988823 -408.728298)
			(xy 210.938671 -408.746584) (xy 210.88646 -408.757701) (xy 210.833208 -408.761431) (xy 210.779956 -408.757701)
			(xy 210.727745 -408.746584) (xy 210.677593 -408.728298) (xy 210.630479 -408.703199) (xy 210.587325 -408.671777)
			(xy 210.548971 -408.634647) (xy 210.532218 -408.613864) (xy 210.522321 -408.602059) (xy 210.496997 -408.58454)
			(xy 210.467604 -408.575364) (xy 210.436812 -408.575364) (xy 210.407419 -408.58454) (xy 210.382095 -408.602059)
			(xy 210.372198 -408.613864) (xy 210.355445 -408.634647) (xy 210.317091 -408.671777) (xy 210.273937 -408.703199)
			(xy 210.226823 -408.728298) (xy 210.176671 -408.746584) (xy 210.12446 -408.757701) (xy 210.071208 -408.761431)
			(xy 210.017956 -408.757701) (xy 209.965745 -408.746584) (xy 209.915593 -408.728298) (xy 209.868479 -408.703199)
			(xy 209.825325 -408.671777) (xy 209.786971 -408.634647) (xy 209.770218 -408.613864) (xy 209.760321 -408.602059)
			(xy 209.734997 -408.58454) (xy 209.705604 -408.575364) (xy 209.674812 -408.575364) (xy 209.645419 -408.58454)
			(xy 209.620095 -408.602059) (xy 209.610198 -408.613864) (xy 209.593445 -408.634647) (xy 209.555091 -408.671777)
			(xy 209.511937 -408.703199) (xy 209.464823 -408.728298) (xy 209.414671 -408.746584) (xy 209.36246 -408.757701)
			(xy 209.309208 -408.761431) (xy 209.255956 -408.757701) (xy 209.203745 -408.746584) (xy 209.153593 -408.728298)
			(xy 209.106479 -408.703199) (xy 209.063325 -408.671777) (xy 209.024971 -408.634647) (xy 209.008218 -408.613864)
			(xy 208.998321 -408.602059) (xy 208.972997 -408.58454) (xy 208.943604 -408.575364) (xy 208.912812 -408.575364)
			(xy 208.883419 -408.58454) (xy 208.858095 -408.602059) (xy 208.848198 -408.613864) (xy 208.829999 -408.636341)
			(xy 208.787982 -408.676078) (xy 208.740449 -408.709019) (xy 208.688489 -408.734409) (xy 208.633293 -408.751666)
			(xy 208.576124 -408.760395) (xy 208.547208 -408.76093) (xy 208.519956 -408.760423) (xy 208.466008 -408.752668)
			(xy 208.413712 -408.737313) (xy 208.364134 -408.714672) (xy 208.318282 -408.685206) (xy 208.277091 -408.649515)
			(xy 208.241398 -408.608324) (xy 208.211931 -408.562473) (xy 208.18929 -408.512896) (xy 208.173934 -408.4606)
			(xy 208.166177 -408.406652) (xy 207.645132 -408.406652) (xy 207.315308 -408.736546) (xy 207.315308 -408.887422)
			(xy 214.66759 -408.887422) (xy 214.671661 -408.8318) (xy 214.683787 -408.777363) (xy 214.70371 -408.725272)
			(xy 214.731006 -408.676637) (xy 214.765092 -408.632494) (xy 214.805241 -408.593785) (xy 214.850599 -408.561334)
			(xy 214.900199 -408.535833) (xy 214.952983 -408.517826) (xy 215.007826 -408.507696) (xy 215.06356 -408.505659)
			(xy 215.118997 -408.511759) (xy 215.172954 -408.525865) (xy 215.224283 -408.547677) (xy 215.271889 -408.576731)
			(xy 215.314757 -408.612406) (xy 215.351974 -408.653943) (xy 215.382747 -408.700456) (xy 215.406419 -408.750953)
			(xy 215.422487 -408.80436) (xy 215.430607 -408.859536) (xy 215.431116 -408.887422) (xy 215.430607 -408.915308)
			(xy 215.422487 -408.970484) (xy 215.406419 -409.023891) (xy 215.382747 -409.074388) (xy 215.351974 -409.120901)
			(xy 215.314757 -409.162438) (xy 215.271889 -409.198113) (xy 215.224283 -409.227167) (xy 215.172954 -409.248979)
			(xy 215.118997 -409.263085) (xy 215.06356 -409.269185) (xy 215.007826 -409.267148) (xy 214.952983 -409.257018)
			(xy 214.900199 -409.239011) (xy 214.850599 -409.21351) (xy 214.805241 -409.181059) (xy 214.765092 -409.14235)
			(xy 214.731006 -409.098207) (xy 214.70371 -409.049572) (xy 214.683787 -408.997481) (xy 214.671661 -408.943044)
			(xy 214.66759 -408.887422) (xy 207.315308 -408.887422) (xy 207.315308 -409.108402) (xy 207.315755 -409.122193)
			(xy 207.323121 -409.148773) (xy 207.337341 -409.172406) (xy 207.357375 -409.191363) (xy 207.381756 -409.204258)
			(xy 207.408701 -409.210147) (xy 207.436239 -409.208599) (xy 207.462355 -409.199727) (xy 207.485138 -409.184181)
			(xy 207.494378 -409.173934) (xy 207.512594 -409.153227) (xy 207.553965 -409.116759) (xy 207.600154 -409.086627)
			(xy 207.6502 -409.063457) (xy 207.70306 -409.047732) (xy 207.757633 -409.03978) (xy 207.785208 -409.039314)
			(xy 207.814124 -409.039849) (xy 207.871294 -409.048577) (xy 207.926493 -409.065832) (xy 207.978455 -409.09122)
			(xy 208.025992 -409.124157) (xy 208.068013 -409.163891) (xy 208.086198 -409.18638) (xy 208.096095 -409.198185)
			(xy 208.121419 -409.215704) (xy 208.150812 -409.22488) (xy 208.181604 -409.22488) (xy 208.210997 -409.215704)
			(xy 208.236321 -409.198185) (xy 208.246218 -409.18638) (xy 208.262971 -409.165597) (xy 208.301325 -409.128467)
			(xy 208.344479 -409.097045) (xy 208.391593 -409.071946) (xy 208.441745 -409.05366) (xy 208.493956 -409.042543)
			(xy 208.547208 -409.038813) (xy 208.60046 -409.042543) (xy 208.652671 -409.05366) (xy 208.702823 -409.071946)
			(xy 208.749937 -409.097045) (xy 208.793091 -409.128467) (xy 208.831445 -409.165597) (xy 208.848198 -409.18638)
			(xy 208.858095 -409.198185) (xy 208.883419 -409.215704) (xy 208.912812 -409.22488) (xy 208.943604 -409.22488)
			(xy 208.972997 -409.215704) (xy 208.998321 -409.198185) (xy 209.008218 -409.18638) (xy 209.024971 -409.165597)
			(xy 209.063325 -409.128467) (xy 209.106479 -409.097045) (xy 209.153593 -409.071946) (xy 209.203745 -409.05366)
			(xy 209.255956 -409.042543) (xy 209.309208 -409.038813) (xy 209.36246 -409.042543) (xy 209.414671 -409.05366)
			(xy 209.464823 -409.071946) (xy 209.511937 -409.097045) (xy 209.555091 -409.128467) (xy 209.593445 -409.165597)
			(xy 209.610198 -409.18638) (xy 209.620095 -409.198185) (xy 209.645419 -409.215704) (xy 209.674812 -409.22488)
			(xy 209.705604 -409.22488) (xy 209.734997 -409.215704) (xy 209.760321 -409.198185) (xy 209.770218 -409.18638)
			(xy 209.786971 -409.165597) (xy 209.825325 -409.128467) (xy 209.868479 -409.097045) (xy 209.915593 -409.071946)
			(xy 209.965745 -409.05366) (xy 210.017956 -409.042543) (xy 210.071208 -409.038813) (xy 210.12446 -409.042543)
			(xy 210.176671 -409.05366) (xy 210.226823 -409.071946) (xy 210.273937 -409.097045) (xy 210.317091 -409.128467)
			(xy 210.355445 -409.165597) (xy 210.372198 -409.18638) (xy 210.382095 -409.198185) (xy 210.407419 -409.215704)
			(xy 210.436812 -409.22488) (xy 210.467604 -409.22488) (xy 210.496997 -409.215704) (xy 210.522321 -409.198185)
			(xy 210.532218 -409.18638) (xy 210.548971 -409.165597) (xy 210.587325 -409.128467) (xy 210.630479 -409.097045)
			(xy 210.677593 -409.071946) (xy 210.727745 -409.05366) (xy 210.779956 -409.042543) (xy 210.833208 -409.038813)
			(xy 210.88646 -409.042543) (xy 210.938671 -409.05366) (xy 210.988823 -409.071946) (xy 211.035937 -409.097045)
			(xy 211.079091 -409.128467) (xy 211.117445 -409.165597) (xy 211.134198 -409.18638) (xy 211.144095 -409.198185)
			(xy 211.169419 -409.215704) (xy 211.198812 -409.22488) (xy 211.229604 -409.22488) (xy 211.258997 -409.215704)
			(xy 211.284321 -409.198185) (xy 211.294218 -409.18638) (xy 211.310971 -409.165597) (xy 211.349325 -409.128467)
			(xy 211.392479 -409.097045) (xy 211.439593 -409.071946) (xy 211.489745 -409.05366) (xy 211.541956 -409.042543)
			(xy 211.595208 -409.038813) (xy 211.64846 -409.042543) (xy 211.700671 -409.05366) (xy 211.750823 -409.071946)
			(xy 211.797937 -409.097045) (xy 211.841091 -409.128467) (xy 211.879445 -409.165597) (xy 211.896198 -409.18638)
			(xy 211.906095 -409.198185) (xy 211.931419 -409.215704) (xy 211.960812 -409.22488) (xy 211.991604 -409.22488)
			(xy 212.020997 -409.215704) (xy 212.046321 -409.198185) (xy 212.056218 -409.18638) (xy 212.072971 -409.165597)
			(xy 212.111325 -409.128467) (xy 212.154479 -409.097045) (xy 212.201593 -409.071946) (xy 212.251745 -409.05366)
			(xy 212.303956 -409.042543) (xy 212.357208 -409.038813) (xy 212.41046 -409.042543) (xy 212.462671 -409.05366)
			(xy 212.512823 -409.071946) (xy 212.559937 -409.097045) (xy 212.603091 -409.128467) (xy 212.641445 -409.165597)
			(xy 212.658198 -409.18638) (xy 212.668095 -409.198185) (xy 212.693419 -409.215704) (xy 212.722812 -409.22488)
			(xy 212.753604 -409.22488) (xy 212.782997 -409.215704) (xy 212.808321 -409.198185) (xy 212.818218 -409.18638)
			(xy 212.836408 -409.163895) (xy 212.878425 -409.124154) (xy 212.925959 -409.09121) (xy 212.977921 -409.065819)
			(xy 213.03312 -409.048561) (xy 213.090291 -409.039833) (xy 213.119208 -409.039314) (xy 213.146457 -409.039801)
			(xy 213.200401 -409.047558) (xy 213.252692 -409.062913) (xy 213.302265 -409.085553) (xy 213.348112 -409.115018)
			(xy 213.389299 -409.150707) (xy 213.424987 -409.191895) (xy 213.454451 -409.237742) (xy 213.47709 -409.287316)
			(xy 213.492444 -409.339607) (xy 213.5002 -409.393551) (xy 213.5002 -409.448049) (xy 213.492444 -409.501993)
			(xy 213.47709 -409.554284) (xy 213.454451 -409.603858) (xy 213.424987 -409.649705) (xy 213.389299 -409.690893)
			(xy 213.348112 -409.726582) (xy 213.302265 -409.756047) (xy 213.252692 -409.778687) (xy 213.200401 -409.794042)
			(xy 213.146457 -409.801799) (xy 213.119208 -409.80233) (xy 213.090292 -409.801796) (xy 213.033122 -409.793069)
			(xy 212.977923 -409.775814) (xy 212.925962 -409.750425) (xy 212.878427 -409.717485) (xy 212.836408 -409.677749)
			(xy 212.818218 -409.655264) (xy 212.808321 -409.643459) (xy 212.782997 -409.62594) (xy 212.753604 -409.616764)
			(xy 212.722812 -409.616764) (xy 212.693419 -409.62594) (xy 212.668095 -409.643459) (xy 212.658198 -409.655264)
			(xy 212.641445 -409.676047) (xy 212.603091 -409.713177) (xy 212.559937 -409.744599) (xy 212.512823 -409.769698)
			(xy 212.462671 -409.787984) (xy 212.41046 -409.799101) (xy 212.357208 -409.802831) (xy 212.303956 -409.799101)
			(xy 212.251745 -409.787984) (xy 212.201593 -409.769698) (xy 212.154479 -409.744599) (xy 212.111325 -409.713177)
			(xy 212.072971 -409.676047) (xy 212.056218 -409.655264) (xy 212.046321 -409.643459) (xy 212.020997 -409.62594)
			(xy 211.991604 -409.616764) (xy 211.960812 -409.616764) (xy 211.931419 -409.62594) (xy 211.906095 -409.643459)
			(xy 211.896198 -409.655264) (xy 211.879445 -409.676047) (xy 211.841091 -409.713177) (xy 211.797937 -409.744599)
			(xy 211.750823 -409.769698) (xy 211.700671 -409.787984) (xy 211.64846 -409.799101) (xy 211.595208 -409.802831)
			(xy 211.541956 -409.799101) (xy 211.489745 -409.787984) (xy 211.439593 -409.769698) (xy 211.392479 -409.744599)
			(xy 211.349325 -409.713177) (xy 211.310971 -409.676047) (xy 211.294218 -409.655264) (xy 211.284321 -409.643459)
			(xy 211.258997 -409.62594) (xy 211.229604 -409.616764) (xy 211.198812 -409.616764) (xy 211.169419 -409.62594)
			(xy 211.144095 -409.643459) (xy 211.134198 -409.655264) (xy 211.117445 -409.676047) (xy 211.079091 -409.713177)
			(xy 211.035937 -409.744599) (xy 210.988823 -409.769698) (xy 210.938671 -409.787984) (xy 210.88646 -409.799101)
			(xy 210.833208 -409.802831) (xy 210.779956 -409.799101) (xy 210.727745 -409.787984) (xy 210.677593 -409.769698)
			(xy 210.630479 -409.744599) (xy 210.587325 -409.713177) (xy 210.548971 -409.676047) (xy 210.532218 -409.655264)
			(xy 210.522321 -409.643459) (xy 210.496997 -409.62594) (xy 210.467604 -409.616764) (xy 210.436812 -409.616764)
			(xy 210.407419 -409.62594) (xy 210.382095 -409.643459) (xy 210.372198 -409.655264) (xy 210.355445 -409.676047)
			(xy 210.317091 -409.713177) (xy 210.273937 -409.744599) (xy 210.226823 -409.769698) (xy 210.176671 -409.787984)
			(xy 210.12446 -409.799101) (xy 210.071208 -409.802831) (xy 210.017956 -409.799101) (xy 209.965745 -409.787984)
			(xy 209.915593 -409.769698) (xy 209.868479 -409.744599) (xy 209.825325 -409.713177) (xy 209.786971 -409.676047)
			(xy 209.770218 -409.655264) (xy 209.760321 -409.643459) (xy 209.734997 -409.62594) (xy 209.705604 -409.616764)
			(xy 209.674812 -409.616764) (xy 209.645419 -409.62594) (xy 209.620095 -409.643459) (xy 209.610198 -409.655264)
			(xy 209.593445 -409.676047) (xy 209.555091 -409.713177) (xy 209.511937 -409.744599) (xy 209.464823 -409.769698)
			(xy 209.414671 -409.787984) (xy 209.36246 -409.799101) (xy 209.309208 -409.802831) (xy 209.255956 -409.799101)
			(xy 209.203745 -409.787984) (xy 209.153593 -409.769698) (xy 209.106479 -409.744599) (xy 209.063325 -409.713177)
			(xy 209.024971 -409.676047) (xy 209.008218 -409.655264) (xy 208.998321 -409.643459) (xy 208.972997 -409.62594)
			(xy 208.943604 -409.616764) (xy 208.912812 -409.616764) (xy 208.883419 -409.62594) (xy 208.858095 -409.643459)
			(xy 208.848198 -409.655264) (xy 208.831445 -409.676047) (xy 208.793091 -409.713177) (xy 208.749937 -409.744599)
			(xy 208.702823 -409.769698) (xy 208.652671 -409.787984) (xy 208.60046 -409.799101) (xy 208.547208 -409.802831)
			(xy 208.493956 -409.799101) (xy 208.441745 -409.787984) (xy 208.391593 -409.769698) (xy 208.344479 -409.744599)
			(xy 208.301325 -409.713177) (xy 208.262971 -409.676047) (xy 208.246218 -409.655264) (xy 208.236321 -409.643459)
			(xy 208.210997 -409.62594) (xy 208.181604 -409.616764) (xy 208.150812 -409.616764) (xy 208.121419 -409.62594)
			(xy 208.096095 -409.643459) (xy 208.086198 -409.655264) (xy 208.068008 -409.677748) (xy 208.025991 -409.717485)
			(xy 207.978456 -409.750423) (xy 207.926493 -409.775807) (xy 207.871294 -409.793055) (xy 207.814124 -409.801772)
			(xy 207.785208 -409.80233) (xy 207.757634 -409.801844) (xy 207.70306 -409.793903) (xy 207.650198 -409.778185)
			(xy 207.600152 -409.755019) (xy 207.553963 -409.724886) (xy 207.512595 -409.688416) (xy 207.494378 -409.66771)
			(xy 207.485123 -409.657499) (xy 207.462337 -409.642018) (xy 207.43624 -409.633194) (xy 207.408735 -409.631672)
			(xy 207.381824 -409.637562) (xy 207.35747 -409.650435) (xy 207.337445 -409.669352) (xy 207.323209 -409.692936)
			(xy 207.3158 -409.719469) (xy 207.315308 -409.733242) (xy 207.315308 -409.874974) (xy 207.375506 -409.935172)
			(xy 215.082374 -409.935172) (xy 215.625172 -409.392374) (xy 215.625172 -404.6093) (xy 215.625672 -404.58332)
			(xy 215.633838 -404.532005) (xy 215.649937 -404.482601) (xy 215.673573 -404.436327) (xy 215.704161 -404.394324)
			(xy 215.7222 -404.37562) (xy 216.72804 -403.36978) (xy 216.73661 -403.361336) (xy 216.754789 -403.345571)
			(xy 216.764362 -403.338284) (xy 216.771497 -403.332545) (xy 216.781448 -403.31719) (xy 216.785335 -403.299311)
			(xy 216.782657 -403.281211) (xy 216.778586 -403.273006) (xy 216.763883 -403.244745) (xy 216.743053 -403.184544)
			(xy 216.732495 -403.121723) (xy 216.73185 -403.089872) (xy 216.732336 -403.062621) (xy 216.740092 -403.008673)
			(xy 216.755447 -402.956378) (xy 216.778089 -402.906801) (xy 216.807555 -402.860951) (xy 216.843246 -402.81976)
			(xy 216.884437 -402.784069) (xy 216.930287 -402.754603) (xy 216.979864 -402.731961) (xy 217.032159 -402.716606)
			(xy 217.086107 -402.70885) (xy 217.140609 -402.70885) (xy 217.194557 -402.716606) (xy 217.215795 -402.722842)
			(xy 219.703648 -402.722842) (xy 219.707719 -402.66722) (xy 219.719845 -402.612783) (xy 219.739768 -402.560692)
			(xy 219.767064 -402.512057) (xy 219.80115 -402.467914) (xy 219.841299 -402.429205) (xy 219.886657 -402.396754)
			(xy 219.936257 -402.371253) (xy 219.989041 -402.353246) (xy 220.043884 -402.343116) (xy 220.099618 -402.341079)
			(xy 220.155055 -402.347179) (xy 220.209012 -402.361285) (xy 220.260341 -402.383097) (xy 220.307947 -402.412151)
			(xy 220.350815 -402.447826) (xy 220.388032 -402.489363) (xy 220.418805 -402.535876) (xy 220.442477 -402.586373)
			(xy 220.458545 -402.63978) (xy 220.466665 -402.694956) (xy 220.467174 -402.722842) (xy 222.523048 -402.722842)
			(xy 222.527119 -402.66722) (xy 222.539245 -402.612783) (xy 222.559168 -402.560692) (xy 222.586464 -402.512057)
			(xy 222.62055 -402.467914) (xy 222.660699 -402.429205) (xy 222.706057 -402.396754) (xy 222.755657 -402.371253)
			(xy 222.808441 -402.353246) (xy 222.863284 -402.343116) (xy 222.919018 -402.341079) (xy 222.974455 -402.347179)
			(xy 223.028412 -402.361285) (xy 223.079741 -402.383097) (xy 223.127347 -402.412151) (xy 223.170215 -402.447826)
			(xy 223.207432 -402.489363) (xy 223.238205 -402.535876) (xy 223.261877 -402.586373) (xy 223.277945 -402.63978)
			(xy 223.286065 -402.694956) (xy 223.286574 -402.722842) (xy 223.286065 -402.750728) (xy 223.277945 -402.805904)
			(xy 223.261877 -402.859311) (xy 223.238205 -402.909808) (xy 223.207432 -402.956321) (xy 223.170215 -402.997858)
			(xy 223.127347 -403.033533) (xy 223.079741 -403.062587) (xy 223.028412 -403.084399) (xy 222.974455 -403.098505)
			(xy 222.919018 -403.104605) (xy 222.863284 -403.102568) (xy 222.808441 -403.092438) (xy 222.755657 -403.074431)
			(xy 222.706057 -403.04893) (xy 222.660699 -403.016479) (xy 222.62055 -402.97777) (xy 222.586464 -402.933627)
			(xy 222.559168 -402.884992) (xy 222.539245 -402.832901) (xy 222.527119 -402.778464) (xy 222.523048 -402.722842)
			(xy 220.467174 -402.722842) (xy 220.466665 -402.750728) (xy 220.458545 -402.805904) (xy 220.442477 -402.859311)
			(xy 220.418805 -402.909808) (xy 220.388032 -402.956321) (xy 220.350815 -402.997858) (xy 220.307947 -403.033533)
			(xy 220.260341 -403.062587) (xy 220.209012 -403.084399) (xy 220.155055 -403.098505) (xy 220.099618 -403.104605)
			(xy 220.043884 -403.102568) (xy 219.989041 -403.092438) (xy 219.936257 -403.074431) (xy 219.886657 -403.04893)
			(xy 219.841299 -403.016479) (xy 219.80115 -402.97777) (xy 219.767064 -402.933627) (xy 219.739768 -402.884992)
			(xy 219.719845 -402.832901) (xy 219.707719 -402.778464) (xy 219.703648 -402.722842) (xy 217.215795 -402.722842)
			(xy 217.246852 -402.731961) (xy 217.296429 -402.754603) (xy 217.342279 -402.784069) (xy 217.38347 -402.81976)
			(xy 217.419161 -402.860951) (xy 217.448627 -402.906801) (xy 217.471269 -402.956378) (xy 217.486624 -403.008673)
			(xy 217.49438 -403.062621) (xy 217.494866 -403.089872) (xy 217.494734 -403.106015) (xy 217.492062 -403.13819)
			(xy 217.489532 -403.154134) (xy 217.487558 -403.168753) (xy 217.491142 -403.19802) (xy 217.502934 -403.225045)
			(xy 217.521953 -403.247578) (xy 217.546615 -403.26374) (xy 217.574866 -403.272186) (xy 217.589608 -403.272752)
			(xy 218.236292 -403.272752) (xy 218.262272 -403.273251) (xy 218.313589 -403.281416) (xy 218.362994 -403.297513)
			(xy 218.40927 -403.321147) (xy 218.451275 -403.351734) (xy 218.469972 -403.36978) (xy 218.704414 -403.603968)
			(xy 218.716606 -403.607778) (xy 218.742047 -403.615984) (xy 218.790517 -403.638523) (xy 218.835367 -403.667607)
			(xy 218.875718 -403.702667) (xy 218.910781 -403.743017) (xy 218.939867 -403.787865) (xy 218.962409 -403.836335)
			(xy 218.970606 -403.861778) (xy 218.974416 -403.87397) (xy 219.126099 -404.025862) (xy 219.703648 -404.025862)
			(xy 219.707719 -403.97024) (xy 219.719845 -403.915803) (xy 219.739768 -403.863712) (xy 219.767064 -403.815077)
			(xy 219.80115 -403.770934) (xy 219.841299 -403.732225) (xy 219.886657 -403.699774) (xy 219.936257 -403.674273)
			(xy 219.989041 -403.656266) (xy 220.043884 -403.646136) (xy 220.099618 -403.644099) (xy 220.155055 -403.650199)
			(xy 220.209012 -403.664305) (xy 220.260341 -403.686117) (xy 220.307947 -403.715171) (xy 220.350815 -403.750846)
			(xy 220.388032 -403.792383) (xy 220.418805 -403.838896) (xy 220.442477 -403.889393) (xy 220.458545 -403.9428)
			(xy 220.466665 -403.997976) (xy 220.467174 -404.025862) (xy 221.126048 -404.025862) (xy 221.130119 -403.97024)
			(xy 221.142245 -403.915803) (xy 221.162168 -403.863712) (xy 221.189464 -403.815077) (xy 221.22355 -403.770934)
			(xy 221.263699 -403.732225) (xy 221.309057 -403.699774) (xy 221.358657 -403.674273) (xy 221.411441 -403.656266)
			(xy 221.466284 -403.646136) (xy 221.522018 -403.644099) (xy 221.577455 -403.650199) (xy 221.631412 -403.664305)
			(xy 221.682741 -403.686117) (xy 221.730347 -403.715171) (xy 221.773215 -403.750846) (xy 221.810432 -403.792383)
			(xy 221.841205 -403.838896) (xy 221.864877 -403.889393) (xy 221.880945 -403.9428) (xy 221.889065 -403.997976)
			(xy 221.889574 -404.025862) (xy 222.523048 -404.025862) (xy 222.527119 -403.97024) (xy 222.539245 -403.915803)
			(xy 222.559168 -403.863712) (xy 222.586464 -403.815077) (xy 222.62055 -403.770934) (xy 222.660699 -403.732225)
			(xy 222.706057 -403.699774) (xy 222.755657 -403.674273) (xy 222.808441 -403.656266) (xy 222.863284 -403.646136)
			(xy 222.919018 -403.644099) (xy 222.974455 -403.650199) (xy 223.028412 -403.664305) (xy 223.079741 -403.686117)
			(xy 223.127347 -403.715171) (xy 223.170215 -403.750846) (xy 223.207432 -403.792383) (xy 223.217382 -403.807422)
			(xy 225.33559 -403.807422) (xy 225.339661 -403.7518) (xy 225.351787 -403.697363) (xy 225.37171 -403.645272)
			(xy 225.399006 -403.596637) (xy 225.433092 -403.552494) (xy 225.473241 -403.513785) (xy 225.518599 -403.481334)
			(xy 225.568199 -403.455833) (xy 225.620983 -403.437826) (xy 225.675826 -403.427696) (xy 225.73156 -403.425659)
			(xy 225.786997 -403.431759) (xy 225.840954 -403.445865) (xy 225.892283 -403.467677) (xy 225.939889 -403.496731)
			(xy 225.982757 -403.532406) (xy 226.019974 -403.573943) (xy 226.050747 -403.620456) (xy 226.074419 -403.670953)
			(xy 226.090487 -403.72436) (xy 226.098607 -403.779536) (xy 226.099116 -403.807422) (xy 226.098607 -403.835308)
			(xy 226.090487 -403.890484) (xy 226.074419 -403.943891) (xy 226.050747 -403.994388) (xy 226.019974 -404.040901)
			(xy 225.982757 -404.082438) (xy 225.939889 -404.118113) (xy 225.892283 -404.147167) (xy 225.840954 -404.168979)
			(xy 225.786997 -404.183085) (xy 225.73156 -404.189185) (xy 225.675826 -404.187148) (xy 225.620983 -404.177018)
			(xy 225.568199 -404.159011) (xy 225.518599 -404.13351) (xy 225.473241 -404.101059) (xy 225.433092 -404.06235)
			(xy 225.399006 -404.018207) (xy 225.37171 -403.969572) (xy 225.351787 -403.917481) (xy 225.339661 -403.863044)
			(xy 225.33559 -403.807422) (xy 223.217382 -403.807422) (xy 223.238205 -403.838896) (xy 223.261877 -403.889393)
			(xy 223.277945 -403.9428) (xy 223.286065 -403.997976) (xy 223.286574 -404.025862) (xy 223.286065 -404.053748)
			(xy 223.277945 -404.108924) (xy 223.261877 -404.162331) (xy 223.238205 -404.212828) (xy 223.207432 -404.259341)
			(xy 223.170215 -404.300878) (xy 223.127347 -404.336553) (xy 223.079741 -404.365607) (xy 223.028412 -404.387419)
			(xy 222.974455 -404.401525) (xy 222.919018 -404.407625) (xy 222.863284 -404.405588) (xy 222.808441 -404.395458)
			(xy 222.755657 -404.377451) (xy 222.706057 -404.35195) (xy 222.660699 -404.319499) (xy 222.62055 -404.28079)
			(xy 222.586464 -404.236647) (xy 222.559168 -404.188012) (xy 222.539245 -404.135921) (xy 222.527119 -404.081484)
			(xy 222.523048 -404.025862) (xy 221.889574 -404.025862) (xy 221.889065 -404.053748) (xy 221.880945 -404.108924)
			(xy 221.864877 -404.162331) (xy 221.841205 -404.212828) (xy 221.810432 -404.259341) (xy 221.773215 -404.300878)
			(xy 221.730347 -404.336553) (xy 221.682741 -404.365607) (xy 221.631412 -404.387419) (xy 221.577455 -404.401525)
			(xy 221.522018 -404.407625) (xy 221.466284 -404.405588) (xy 221.411441 -404.395458) (xy 221.358657 -404.377451)
			(xy 221.309057 -404.35195) (xy 221.263699 -404.319499) (xy 221.22355 -404.28079) (xy 221.189464 -404.236647)
			(xy 221.162168 -404.188012) (xy 221.142245 -404.135921) (xy 221.130119 -404.081484) (xy 221.126048 -404.025862)
			(xy 220.467174 -404.025862) (xy 220.466665 -404.053748) (xy 220.458545 -404.108924) (xy 220.442477 -404.162331)
			(xy 220.418805 -404.212828) (xy 220.388032 -404.259341) (xy 220.350815 -404.300878) (xy 220.307947 -404.336553)
			(xy 220.260341 -404.365607) (xy 220.209012 -404.387419) (xy 220.155055 -404.401525) (xy 220.099618 -404.407625)
			(xy 220.043884 -404.405588) (xy 219.989041 -404.395458) (xy 219.936257 -404.377451) (xy 219.886657 -404.35195)
			(xy 219.841299 -404.319499) (xy 219.80115 -404.28079) (xy 219.767064 -404.236647) (xy 219.739768 -404.188012)
			(xy 219.719845 -404.135921) (xy 219.707719 -404.081484) (xy 219.703648 -404.025862) (xy 219.126099 -404.025862)
			(xy 219.15882 -404.058628) (xy 219.176836 -404.077349) (xy 219.207396 -404.119363) (xy 219.231019 -404.165635)
			(xy 219.247124 -404.215029) (xy 219.255316 -404.266332) (xy 219.255848 -404.292308) (xy 219.255848 -406.576014)
			(xy 219.595215 -406.576014) (xy 219.598942 -406.522764) (xy 219.610057 -406.470554) (xy 219.628341 -406.420404)
			(xy 219.653438 -406.373292) (xy 219.684857 -406.330138) (xy 219.721985 -406.291785) (xy 219.742766 -406.275032)
			(xy 219.754551 -406.265112) (xy 219.772073 -406.239795) (xy 219.781253 -406.210408) (xy 219.781257 -406.179619)
			(xy 219.772085 -406.150229) (xy 219.75457 -406.124908) (xy 219.742766 -406.115012) (xy 219.720281 -406.096823)
			(xy 219.680548 -406.054802) (xy 219.64761 -406.007266) (xy 219.622222 -405.955305) (xy 219.604966 -405.900107)
			(xy 219.596236 -405.842938) (xy 219.5957 -405.814022) (xy 219.596176 -405.786769) (xy 219.60393 -405.732818)
			(xy 219.619284 -405.68052) (xy 219.641924 -405.63094) (xy 219.671391 -405.585086) (xy 219.707083 -405.543893)
			(xy 219.748275 -405.508199) (xy 219.794127 -405.478731) (xy 219.843707 -405.456089) (xy 219.896005 -405.440733)
			(xy 219.949955 -405.432977) (xy 219.977208 -405.432514) (xy 220.006123 -405.433093) (xy 220.063291 -405.441809)
			(xy 220.118489 -405.459055) (xy 220.170451 -405.484435) (xy 220.217987 -405.517368) (xy 220.260006 -405.557099)
			(xy 220.278198 -405.57958) (xy 220.288095 -405.591385) (xy 220.313419 -405.608904) (xy 220.342812 -405.61808)
			(xy 220.373604 -405.61808) (xy 220.402997 -405.608904) (xy 220.428321 -405.591385) (xy 220.438218 -405.57958)
			(xy 220.454971 -405.558797) (xy 220.493325 -405.521667) (xy 220.536479 -405.490245) (xy 220.583593 -405.465146)
			(xy 220.633745 -405.44686) (xy 220.685956 -405.435743) (xy 220.739208 -405.432013) (xy 220.79246 -405.435743)
			(xy 220.844671 -405.44686) (xy 220.894823 -405.465146) (xy 220.941937 -405.490245) (xy 220.985091 -405.521667)
			(xy 221.023445 -405.558797) (xy 221.040198 -405.57958) (xy 221.050095 -405.591385) (xy 221.075419 -405.608904)
			(xy 221.104812 -405.61808) (xy 221.135604 -405.61808) (xy 221.164997 -405.608904) (xy 221.190321 -405.591385)
			(xy 221.200218 -405.57958) (xy 221.216971 -405.558797) (xy 221.255325 -405.521667) (xy 221.298479 -405.490245)
			(xy 221.345593 -405.465146) (xy 221.395745 -405.44686) (xy 221.447956 -405.435743) (xy 221.501208 -405.432013)
			(xy 221.55446 -405.435743) (xy 221.606671 -405.44686) (xy 221.656823 -405.465146) (xy 221.703937 -405.490245)
			(xy 221.747091 -405.521667) (xy 221.785445 -405.558797) (xy 221.802198 -405.57958) (xy 221.812095 -405.591385)
			(xy 221.837419 -405.608904) (xy 221.866812 -405.61808) (xy 221.897604 -405.61808) (xy 221.926997 -405.608904)
			(xy 221.952321 -405.591385) (xy 221.962218 -405.57958) (xy 221.978971 -405.558797) (xy 222.017325 -405.521667)
			(xy 222.060479 -405.490245) (xy 222.107593 -405.465146) (xy 222.157745 -405.44686) (xy 222.209956 -405.435743)
			(xy 222.263208 -405.432013) (xy 222.31646 -405.435743) (xy 222.368671 -405.44686) (xy 222.418823 -405.465146)
			(xy 222.465937 -405.490245) (xy 222.509091 -405.521667) (xy 222.547445 -405.558797) (xy 222.564198 -405.57958)
			(xy 222.574095 -405.591385) (xy 222.599419 -405.608904) (xy 222.628812 -405.61808) (xy 222.659604 -405.61808)
			(xy 222.688997 -405.608904) (xy 222.714321 -405.591385) (xy 222.724218 -405.57958) (xy 222.742394 -405.557084)
			(xy 222.784417 -405.51735) (xy 222.831956 -405.484413) (xy 222.88392 -405.459027) (xy 222.93912 -405.441774)
			(xy 222.996291 -405.433048) (xy 223.025208 -405.432514) (xy 223.052462 -405.432948) (xy 223.106415 -405.440707)
			(xy 223.158715 -405.456065) (xy 223.208297 -405.47871) (xy 223.254151 -405.508181) (xy 223.295344 -405.543877)
			(xy 223.331037 -405.585073) (xy 223.360505 -405.63093) (xy 223.383146 -405.680513) (xy 223.3985 -405.732814)
			(xy 223.406254 -405.786768) (xy 223.406716 -405.814022) (xy 223.406173 -405.842938) (xy 223.397454 -405.90011)
			(xy 223.380203 -405.95531) (xy 223.354816 -406.007272) (xy 223.321875 -406.054806) (xy 223.282135 -406.096822)
			(xy 223.25965 -406.115012) (xy 223.247819 -406.124883) (xy 223.230296 -406.150212) (xy 223.221119 -406.179613)
			(xy 223.221123 -406.210413) (xy 223.230308 -406.239812) (xy 223.247838 -406.265136) (xy 223.25965 -406.275032)
			(xy 223.280454 -406.29176) (xy 223.317584 -406.330116) (xy 223.349005 -406.373274) (xy 223.374103 -406.420391)
			(xy 223.392387 -406.470546) (xy 223.403502 -406.52276) (xy 223.40723 -406.576014) (xy 223.403499 -406.629267)
			(xy 223.39238 -406.68148) (xy 223.374092 -406.731634) (xy 223.34899 -406.778749) (xy 223.317567 -406.821904)
			(xy 223.280434 -406.860258) (xy 223.25965 -406.877012) (xy 223.247819 -406.886883) (xy 223.230296 -406.912212)
			(xy 223.221119 -406.941613) (xy 223.221123 -406.972413) (xy 223.230308 -407.001812) (xy 223.247838 -407.027136)
			(xy 223.25965 -407.037032) (xy 223.282159 -407.055192) (xy 223.321891 -407.09722) (xy 223.354825 -407.144762)
			(xy 223.380209 -407.196729) (xy 223.39746 -407.251931) (xy 223.406184 -407.309104) (xy 223.406716 -407.338022)
			(xy 223.406243 -407.365273) (xy 223.398483 -407.419221) (xy 223.383126 -407.471516) (xy 223.360483 -407.521092)
			(xy 223.331015 -407.566942) (xy 223.295322 -407.608132) (xy 223.254131 -407.643823) (xy 223.20828 -407.673289)
			(xy 223.158703 -407.695931) (xy 223.106407 -407.711286) (xy 223.052459 -407.719044) (xy 223.025208 -407.71953)
			(xy 222.99629 -407.719032) (xy 222.939117 -407.710303) (xy 222.883916 -407.693043) (xy 222.831954 -407.667647)
			(xy 222.784421 -407.634699) (xy 222.742406 -407.594952) (xy 222.724218 -407.572464) (xy 222.714321 -407.560659)
			(xy 222.688997 -407.54314) (xy 222.659604 -407.533964) (xy 222.628812 -407.533964) (xy 222.599419 -407.54314)
			(xy 222.574095 -407.560659) (xy 222.564198 -407.572464) (xy 222.547445 -407.593247) (xy 222.509091 -407.630377)
			(xy 222.465937 -407.661799) (xy 222.418823 -407.686898) (xy 222.368671 -407.705184) (xy 222.31646 -407.716301)
			(xy 222.263208 -407.720031) (xy 222.209956 -407.716301) (xy 222.157745 -407.705184) (xy 222.107593 -407.686898)
			(xy 222.060479 -407.661799) (xy 222.017325 -407.630377) (xy 221.978971 -407.593247) (xy 221.962218 -407.572464)
			(xy 221.952321 -407.560659) (xy 221.926997 -407.54314) (xy 221.897604 -407.533964) (xy 221.866812 -407.533964)
			(xy 221.837419 -407.54314) (xy 221.812095 -407.560659) (xy 221.802198 -407.572464) (xy 221.785445 -407.593247)
			(xy 221.747091 -407.630377) (xy 221.703937 -407.661799) (xy 221.656823 -407.686898) (xy 221.606671 -407.705184)
			(xy 221.55446 -407.716301) (xy 221.501208 -407.720031) (xy 221.447956 -407.716301) (xy 221.395745 -407.705184)
			(xy 221.345593 -407.686898) (xy 221.298479 -407.661799) (xy 221.255325 -407.630377) (xy 221.216971 -407.593247)
			(xy 221.200218 -407.572464) (xy 221.190321 -407.560659) (xy 221.164997 -407.54314) (xy 221.135604 -407.533964)
			(xy 221.104812 -407.533964) (xy 221.075419 -407.54314) (xy 221.050095 -407.560659) (xy 221.040198 -407.572464)
			(xy 221.023445 -407.593247) (xy 220.985091 -407.630377) (xy 220.941937 -407.661799) (xy 220.894823 -407.686898)
			(xy 220.844671 -407.705184) (xy 220.79246 -407.716301) (xy 220.739208 -407.720031) (xy 220.685956 -407.716301)
			(xy 220.633745 -407.705184) (xy 220.583593 -407.686898) (xy 220.536479 -407.661799) (xy 220.493325 -407.630377)
			(xy 220.454971 -407.593247) (xy 220.438218 -407.572464) (xy 220.428321 -407.560659) (xy 220.402997 -407.54314)
			(xy 220.373604 -407.533964) (xy 220.342812 -407.533964) (xy 220.313419 -407.54314) (xy 220.288095 -407.560659)
			(xy 220.278198 -407.572464) (xy 220.259999 -407.594941) (xy 220.217982 -407.634678) (xy 220.170449 -407.667619)
			(xy 220.118489 -407.693009) (xy 220.063293 -407.710266) (xy 220.006124 -407.718995) (xy 219.977208 -407.71953)
			(xy 219.949958 -407.719015) (xy 219.896012 -407.71126) (xy 219.84372 -407.695907) (xy 219.794144 -407.673268)
			(xy 219.748294 -407.643805) (xy 219.707105 -407.608117) (xy 219.671413 -407.56693) (xy 219.641946 -407.521083)
			(xy 219.619304 -407.471509) (xy 219.603946 -407.419217) (xy 219.596187 -407.365272) (xy 219.5957 -407.338022)
			(xy 219.596234 -407.309106) (xy 219.60496 -407.251935) (xy 219.622215 -407.196737) (xy 219.647603 -407.144775)
			(xy 219.680544 -407.097241) (xy 219.720282 -407.055223) (xy 219.742766 -407.037032) (xy 219.754551 -407.027112)
			(xy 219.772073 -407.001795) (xy 219.781253 -406.972408) (xy 219.781257 -406.941619) (xy 219.772085 -406.912229)
			(xy 219.75457 -406.886908) (xy 219.742766 -406.877012) (xy 219.722005 -406.860233) (xy 219.684874 -406.821883)
			(xy 219.653452 -406.778731) (xy 219.628352 -406.731621) (xy 219.610064 -406.681472) (xy 219.598946 -406.629263)
			(xy 219.595215 -406.576014) (xy 219.255848 -406.576014) (xy 219.255848 -407.2509) (xy 219.255348 -407.27688)
			(xy 219.247183 -407.328196) (xy 219.231084 -407.3776) (xy 219.20745 -407.423875) (xy 219.176862 -407.46588)
			(xy 219.15882 -407.48458) (xy 218.236935 -408.406652) (xy 218.834177 -408.406652) (xy 218.834177 -408.352148)
			(xy 218.841934 -408.2982) (xy 218.85729 -408.245904) (xy 218.879931 -408.196327) (xy 218.909398 -408.150476)
			(xy 218.945091 -408.109285) (xy 218.986282 -408.073594) (xy 219.032134 -408.044128) (xy 219.081712 -408.021487)
			(xy 219.134008 -408.006132) (xy 219.187956 -407.998377) (xy 219.215208 -407.997914) (xy 219.244123 -407.998493)
			(xy 219.301291 -408.007209) (xy 219.356489 -408.024455) (xy 219.408451 -408.049835) (xy 219.455987 -408.082768)
			(xy 219.498006 -408.122499) (xy 219.516198 -408.14498) (xy 219.526095 -408.156785) (xy 219.551419 -408.174304)
			(xy 219.580812 -408.18348) (xy 219.611604 -408.18348) (xy 219.640997 -408.174304) (xy 219.666321 -408.156785)
			(xy 219.676218 -408.14498) (xy 219.692971 -408.124197) (xy 219.731325 -408.087067) (xy 219.774479 -408.055645)
			(xy 219.821593 -408.030546) (xy 219.871745 -408.01226) (xy 219.923956 -408.001143) (xy 219.977208 -407.997413)
			(xy 220.03046 -408.001143) (xy 220.082671 -408.01226) (xy 220.132823 -408.030546) (xy 220.179937 -408.055645)
			(xy 220.223091 -408.087067) (xy 220.261445 -408.124197) (xy 220.278198 -408.14498) (xy 220.288095 -408.156785)
			(xy 220.313419 -408.174304) (xy 220.342812 -408.18348) (xy 220.373604 -408.18348) (xy 220.402997 -408.174304)
			(xy 220.428321 -408.156785) (xy 220.438218 -408.14498) (xy 220.454971 -408.124197) (xy 220.493325 -408.087067)
			(xy 220.536479 -408.055645) (xy 220.583593 -408.030546) (xy 220.633745 -408.01226) (xy 220.685956 -408.001143)
			(xy 220.739208 -407.997413) (xy 220.79246 -408.001143) (xy 220.844671 -408.01226) (xy 220.894823 -408.030546)
			(xy 220.941937 -408.055645) (xy 220.985091 -408.087067) (xy 221.023445 -408.124197) (xy 221.040198 -408.14498)
			(xy 221.050095 -408.156785) (xy 221.075419 -408.174304) (xy 221.104812 -408.18348) (xy 221.135604 -408.18348)
			(xy 221.164997 -408.174304) (xy 221.190321 -408.156785) (xy 221.200218 -408.14498) (xy 221.216971 -408.124197)
			(xy 221.255325 -408.087067) (xy 221.298479 -408.055645) (xy 221.345593 -408.030546) (xy 221.395745 -408.01226)
			(xy 221.447956 -408.001143) (xy 221.501208 -407.997413) (xy 221.55446 -408.001143) (xy 221.606671 -408.01226)
			(xy 221.656823 -408.030546) (xy 221.703937 -408.055645) (xy 221.747091 -408.087067) (xy 221.785445 -408.124197)
			(xy 221.802198 -408.14498) (xy 221.812095 -408.156785) (xy 221.837419 -408.174304) (xy 221.866812 -408.18348)
			(xy 221.897604 -408.18348) (xy 221.926997 -408.174304) (xy 221.952321 -408.156785) (xy 221.962218 -408.14498)
			(xy 221.978971 -408.124197) (xy 222.017325 -408.087067) (xy 222.060479 -408.055645) (xy 222.107593 -408.030546)
			(xy 222.157745 -408.01226) (xy 222.209956 -408.001143) (xy 222.263208 -407.997413) (xy 222.31646 -408.001143)
			(xy 222.368671 -408.01226) (xy 222.418823 -408.030546) (xy 222.465937 -408.055645) (xy 222.509091 -408.087067)
			(xy 222.547445 -408.124197) (xy 222.564198 -408.14498) (xy 222.574095 -408.156785) (xy 222.599419 -408.174304)
			(xy 222.628812 -408.18348) (xy 222.659604 -408.18348) (xy 222.688997 -408.174304) (xy 222.714321 -408.156785)
			(xy 222.724218 -408.14498) (xy 222.740971 -408.124197) (xy 222.779325 -408.087067) (xy 222.822479 -408.055645)
			(xy 222.869593 -408.030546) (xy 222.919745 -408.01226) (xy 222.971956 -408.001143) (xy 223.025208 -407.997413)
			(xy 223.07846 -408.001143) (xy 223.130671 -408.01226) (xy 223.180823 -408.030546) (xy 223.227937 -408.055645)
			(xy 223.271091 -408.087067) (xy 223.309445 -408.124197) (xy 223.326198 -408.14498) (xy 223.336095 -408.156785)
			(xy 223.361419 -408.174304) (xy 223.390812 -408.18348) (xy 223.421604 -408.18348) (xy 223.450997 -408.174304)
			(xy 223.476321 -408.156785) (xy 223.486218 -408.14498) (xy 223.504394 -408.122484) (xy 223.546417 -408.08275)
			(xy 223.593956 -408.049813) (xy 223.64592 -408.024427) (xy 223.70112 -408.007174) (xy 223.758291 -407.998448)
			(xy 223.787208 -407.997914) (xy 223.81446 -407.998356) (xy 223.86841 -408.006114) (xy 223.920707 -408.021471)
			(xy 223.970286 -408.044114) (xy 224.016138 -408.073582) (xy 224.05733 -408.109276) (xy 224.093023 -408.150468)
			(xy 224.12249 -408.196321) (xy 224.145132 -408.2459) (xy 224.160487 -408.298197) (xy 224.168244 -408.352148)
			(xy 224.168244 -408.406652) (xy 224.160487 -408.460603) (xy 224.145132 -408.5129) (xy 224.12249 -408.562479)
			(xy 224.093023 -408.608332) (xy 224.05733 -408.649524) (xy 224.016138 -408.685218) (xy 223.970286 -408.714686)
			(xy 223.920707 -408.737329) (xy 223.86841 -408.752686) (xy 223.81446 -408.760444) (xy 223.787208 -408.76093)
			(xy 223.75829 -408.760432) (xy 223.701117 -408.751703) (xy 223.645916 -408.734443) (xy 223.593954 -408.709047)
			(xy 223.546421 -408.676099) (xy 223.504406 -408.636352) (xy 223.486218 -408.613864) (xy 223.476321 -408.602059)
			(xy 223.450997 -408.58454) (xy 223.421604 -408.575364) (xy 223.390812 -408.575364) (xy 223.361419 -408.58454)
			(xy 223.336095 -408.602059) (xy 223.326198 -408.613864) (xy 223.309445 -408.634647) (xy 223.271091 -408.671777)
			(xy 223.227937 -408.703199) (xy 223.180823 -408.728298) (xy 223.130671 -408.746584) (xy 223.07846 -408.757701)
			(xy 223.025208 -408.761431) (xy 222.971956 -408.757701) (xy 222.919745 -408.746584) (xy 222.869593 -408.728298)
			(xy 222.822479 -408.703199) (xy 222.779325 -408.671777) (xy 222.740971 -408.634647) (xy 222.724218 -408.613864)
			(xy 222.714321 -408.602059) (xy 222.688997 -408.58454) (xy 222.659604 -408.575364) (xy 222.628812 -408.575364)
			(xy 222.599419 -408.58454) (xy 222.574095 -408.602059) (xy 222.564198 -408.613864) (xy 222.547445 -408.634647)
			(xy 222.509091 -408.671777) (xy 222.465937 -408.703199) (xy 222.418823 -408.728298) (xy 222.368671 -408.746584)
			(xy 222.31646 -408.757701) (xy 222.263208 -408.761431) (xy 222.209956 -408.757701) (xy 222.157745 -408.746584)
			(xy 222.107593 -408.728298) (xy 222.060479 -408.703199) (xy 222.017325 -408.671777) (xy 221.978971 -408.634647)
			(xy 221.962218 -408.613864) (xy 221.952321 -408.602059) (xy 221.926997 -408.58454) (xy 221.897604 -408.575364)
			(xy 221.866812 -408.575364) (xy 221.837419 -408.58454) (xy 221.812095 -408.602059) (xy 221.802198 -408.613864)
			(xy 221.785445 -408.634647) (xy 221.747091 -408.671777) (xy 221.703937 -408.703199) (xy 221.656823 -408.728298)
			(xy 221.606671 -408.746584) (xy 221.55446 -408.757701) (xy 221.501208 -408.761431) (xy 221.447956 -408.757701)
			(xy 221.395745 -408.746584) (xy 221.345593 -408.728298) (xy 221.298479 -408.703199) (xy 221.255325 -408.671777)
			(xy 221.216971 -408.634647) (xy 221.200218 -408.613864) (xy 221.190321 -408.602059) (xy 221.164997 -408.58454)
			(xy 221.135604 -408.575364) (xy 221.104812 -408.575364) (xy 221.075419 -408.58454) (xy 221.050095 -408.602059)
			(xy 221.040198 -408.613864) (xy 221.023445 -408.634647) (xy 220.985091 -408.671777) (xy 220.941937 -408.703199)
			(xy 220.894823 -408.728298) (xy 220.844671 -408.746584) (xy 220.79246 -408.757701) (xy 220.739208 -408.761431)
			(xy 220.685956 -408.757701) (xy 220.633745 -408.746584) (xy 220.583593 -408.728298) (xy 220.536479 -408.703199)
			(xy 220.493325 -408.671777) (xy 220.454971 -408.634647) (xy 220.438218 -408.613864) (xy 220.428321 -408.602059)
			(xy 220.402997 -408.58454) (xy 220.373604 -408.575364) (xy 220.342812 -408.575364) (xy 220.313419 -408.58454)
			(xy 220.288095 -408.602059) (xy 220.278198 -408.613864) (xy 220.261445 -408.634647) (xy 220.223091 -408.671777)
			(xy 220.179937 -408.703199) (xy 220.132823 -408.728298) (xy 220.082671 -408.746584) (xy 220.03046 -408.757701)
			(xy 219.977208 -408.761431) (xy 219.923956 -408.757701) (xy 219.871745 -408.746584) (xy 219.821593 -408.728298)
			(xy 219.774479 -408.703199) (xy 219.731325 -408.671777) (xy 219.692971 -408.634647) (xy 219.676218 -408.613864)
			(xy 219.666321 -408.602059) (xy 219.640997 -408.58454) (xy 219.611604 -408.575364) (xy 219.580812 -408.575364)
			(xy 219.551419 -408.58454) (xy 219.526095 -408.602059) (xy 219.516198 -408.613864) (xy 219.497999 -408.636341)
			(xy 219.455982 -408.676078) (xy 219.408449 -408.709019) (xy 219.356489 -408.734409) (xy 219.301293 -408.751666)
			(xy 219.244124 -408.760395) (xy 219.215208 -408.76093) (xy 219.187956 -408.760423) (xy 219.134008 -408.752668)
			(xy 219.081712 -408.737313) (xy 219.032134 -408.714672) (xy 218.986282 -408.685206) (xy 218.945091 -408.649515)
			(xy 218.909398 -408.608324) (xy 218.879931 -408.562473) (xy 218.85729 -408.512896) (xy 218.841934 -408.4606)
			(xy 218.834177 -408.406652) (xy 218.236935 -408.406652) (xy 217.907108 -408.736546) (xy 217.907108 -409.448052)
			(xy 218.072177 -409.448052) (xy 218.072177 -409.393548) (xy 218.079934 -409.3396) (xy 218.09529 -409.287304)
			(xy 218.117931 -409.237727) (xy 218.147398 -409.191876) (xy 218.183091 -409.150685) (xy 218.224282 -409.114994)
			(xy 218.270134 -409.085528) (xy 218.319712 -409.062887) (xy 218.372008 -409.047532) (xy 218.425956 -409.039777)
			(xy 218.453208 -409.039314) (xy 218.482123 -409.039893) (xy 218.539291 -409.048609) (xy 218.594489 -409.065855)
			(xy 218.646451 -409.091235) (xy 218.693987 -409.124168) (xy 218.736006 -409.163899) (xy 218.754198 -409.18638)
			(xy 218.764095 -409.198185) (xy 218.789419 -409.215704) (xy 218.818812 -409.22488) (xy 218.849604 -409.22488)
			(xy 218.878997 -409.215704) (xy 218.904321 -409.198185) (xy 218.914218 -409.18638) (xy 218.930971 -409.165597)
			(xy 218.969325 -409.128467) (xy 219.012479 -409.097045) (xy 219.059593 -409.071946) (xy 219.109745 -409.05366)
			(xy 219.161956 -409.042543) (xy 219.215208 -409.038813) (xy 219.26846 -409.042543) (xy 219.320671 -409.05366)
			(xy 219.370823 -409.071946) (xy 219.417937 -409.097045) (xy 219.461091 -409.128467) (xy 219.499445 -409.165597)
			(xy 219.516198 -409.18638) (xy 219.526095 -409.198185) (xy 219.551419 -409.215704) (xy 219.580812 -409.22488)
			(xy 219.611604 -409.22488) (xy 219.640997 -409.215704) (xy 219.666321 -409.198185) (xy 219.676218 -409.18638)
			(xy 219.692971 -409.165597) (xy 219.731325 -409.128467) (xy 219.774479 -409.097045) (xy 219.821593 -409.071946)
			(xy 219.871745 -409.05366) (xy 219.923956 -409.042543) (xy 219.977208 -409.038813) (xy 220.03046 -409.042543)
			(xy 220.082671 -409.05366) (xy 220.132823 -409.071946) (xy 220.179937 -409.097045) (xy 220.223091 -409.128467)
			(xy 220.261445 -409.165597) (xy 220.278198 -409.18638) (xy 220.288095 -409.198185) (xy 220.313419 -409.215704)
			(xy 220.342812 -409.22488) (xy 220.373604 -409.22488) (xy 220.402997 -409.215704) (xy 220.428321 -409.198185)
			(xy 220.438218 -409.18638) (xy 220.454971 -409.165597) (xy 220.493325 -409.128467) (xy 220.536479 -409.097045)
			(xy 220.583593 -409.071946) (xy 220.633745 -409.05366) (xy 220.685956 -409.042543) (xy 220.739208 -409.038813)
			(xy 220.79246 -409.042543) (xy 220.844671 -409.05366) (xy 220.894823 -409.071946) (xy 220.941937 -409.097045)
			(xy 220.985091 -409.128467) (xy 221.023445 -409.165597) (xy 221.040198 -409.18638) (xy 221.050095 -409.198185)
			(xy 221.075419 -409.215704) (xy 221.104812 -409.22488) (xy 221.135604 -409.22488) (xy 221.164997 -409.215704)
			(xy 221.190321 -409.198185) (xy 221.200218 -409.18638) (xy 221.216971 -409.165597) (xy 221.255325 -409.128467)
			(xy 221.298479 -409.097045) (xy 221.345593 -409.071946) (xy 221.395745 -409.05366) (xy 221.447956 -409.042543)
			(xy 221.501208 -409.038813) (xy 221.55446 -409.042543) (xy 221.606671 -409.05366) (xy 221.656823 -409.071946)
			(xy 221.703937 -409.097045) (xy 221.747091 -409.128467) (xy 221.785445 -409.165597) (xy 221.802198 -409.18638)
			(xy 221.812095 -409.198185) (xy 221.837419 -409.215704) (xy 221.866812 -409.22488) (xy 221.897604 -409.22488)
			(xy 221.926997 -409.215704) (xy 221.952321 -409.198185) (xy 221.962218 -409.18638) (xy 221.978971 -409.165597)
			(xy 222.017325 -409.128467) (xy 222.060479 -409.097045) (xy 222.107593 -409.071946) (xy 222.157745 -409.05366)
			(xy 222.209956 -409.042543) (xy 222.263208 -409.038813) (xy 222.31646 -409.042543) (xy 222.368671 -409.05366)
			(xy 222.418823 -409.071946) (xy 222.465937 -409.097045) (xy 222.509091 -409.128467) (xy 222.547445 -409.165597)
			(xy 222.564198 -409.18638) (xy 222.574095 -409.198185) (xy 222.599419 -409.215704) (xy 222.628812 -409.22488)
			(xy 222.659604 -409.22488) (xy 222.688997 -409.215704) (xy 222.714321 -409.198185) (xy 222.724218 -409.18638)
			(xy 222.740971 -409.165597) (xy 222.779325 -409.128467) (xy 222.822479 -409.097045) (xy 222.869593 -409.071946)
			(xy 222.919745 -409.05366) (xy 222.971956 -409.042543) (xy 223.025208 -409.038813) (xy 223.07846 -409.042543)
			(xy 223.130671 -409.05366) (xy 223.180823 -409.071946) (xy 223.227937 -409.097045) (xy 223.271091 -409.128467)
			(xy 223.309445 -409.165597) (xy 223.326198 -409.18638) (xy 223.336095 -409.198185) (xy 223.361419 -409.215704)
			(xy 223.390812 -409.22488) (xy 223.421604 -409.22488) (xy 223.450997 -409.215704) (xy 223.476321 -409.198185)
			(xy 223.486218 -409.18638) (xy 223.504394 -409.163884) (xy 223.546417 -409.12415) (xy 223.593956 -409.091213)
			(xy 223.64592 -409.065827) (xy 223.70112 -409.048574) (xy 223.758291 -409.039848) (xy 223.787208 -409.039314)
			(xy 223.81446 -409.039756) (xy 223.86841 -409.047514) (xy 223.920707 -409.062871) (xy 223.970286 -409.085514)
			(xy 224.016138 -409.114982) (xy 224.05733 -409.150676) (xy 224.093023 -409.191868) (xy 224.12249 -409.237721)
			(xy 224.145132 -409.2873) (xy 224.160487 -409.339597) (xy 224.168244 -409.393548) (xy 224.168244 -409.448052)
			(xy 224.160487 -409.502003) (xy 224.145132 -409.5543) (xy 224.12249 -409.603879) (xy 224.093023 -409.649732)
			(xy 224.05733 -409.690924) (xy 224.016138 -409.726618) (xy 223.970286 -409.756086) (xy 223.920707 -409.778729)
			(xy 223.86841 -409.794086) (xy 223.81446 -409.801844) (xy 223.787208 -409.80233) (xy 223.75829 -409.801832)
			(xy 223.701117 -409.793103) (xy 223.645916 -409.775843) (xy 223.593954 -409.750447) (xy 223.546421 -409.717499)
			(xy 223.504406 -409.677752) (xy 223.486218 -409.655264) (xy 223.476321 -409.643459) (xy 223.450997 -409.62594)
			(xy 223.421604 -409.616764) (xy 223.390812 -409.616764) (xy 223.361419 -409.62594) (xy 223.336095 -409.643459)
			(xy 223.326198 -409.655264) (xy 223.309445 -409.676047) (xy 223.271091 -409.713177) (xy 223.227937 -409.744599)
			(xy 223.180823 -409.769698) (xy 223.130671 -409.787984) (xy 223.07846 -409.799101) (xy 223.025208 -409.802831)
			(xy 222.971956 -409.799101) (xy 222.919745 -409.787984) (xy 222.869593 -409.769698) (xy 222.822479 -409.744599)
			(xy 222.779325 -409.713177) (xy 222.740971 -409.676047) (xy 222.724218 -409.655264) (xy 222.714321 -409.643459)
			(xy 222.688997 -409.62594) (xy 222.659604 -409.616764) (xy 222.628812 -409.616764) (xy 222.599419 -409.62594)
			(xy 222.574095 -409.643459) (xy 222.564198 -409.655264) (xy 222.547445 -409.676047) (xy 222.509091 -409.713177)
			(xy 222.465937 -409.744599) (xy 222.418823 -409.769698) (xy 222.368671 -409.787984) (xy 222.31646 -409.799101)
			(xy 222.263208 -409.802831) (xy 222.209956 -409.799101) (xy 222.157745 -409.787984) (xy 222.107593 -409.769698)
			(xy 222.060479 -409.744599) (xy 222.017325 -409.713177) (xy 221.978971 -409.676047) (xy 221.962218 -409.655264)
			(xy 221.952321 -409.643459) (xy 221.926997 -409.62594) (xy 221.897604 -409.616764) (xy 221.866812 -409.616764)
			(xy 221.837419 -409.62594) (xy 221.812095 -409.643459) (xy 221.802198 -409.655264) (xy 221.785445 -409.676047)
			(xy 221.747091 -409.713177) (xy 221.703937 -409.744599) (xy 221.656823 -409.769698) (xy 221.606671 -409.787984)
			(xy 221.55446 -409.799101) (xy 221.501208 -409.802831) (xy 221.447956 -409.799101) (xy 221.395745 -409.787984)
			(xy 221.345593 -409.769698) (xy 221.298479 -409.744599) (xy 221.255325 -409.713177) (xy 221.216971 -409.676047)
			(xy 221.200218 -409.655264) (xy 221.190321 -409.643459) (xy 221.164997 -409.62594) (xy 221.135604 -409.616764)
			(xy 221.104812 -409.616764) (xy 221.075419 -409.62594) (xy 221.050095 -409.643459) (xy 221.040198 -409.655264)
			(xy 221.023445 -409.676047) (xy 220.985091 -409.713177) (xy 220.941937 -409.744599) (xy 220.894823 -409.769698)
			(xy 220.844671 -409.787984) (xy 220.79246 -409.799101) (xy 220.739208 -409.802831) (xy 220.685956 -409.799101)
			(xy 220.633745 -409.787984) (xy 220.583593 -409.769698) (xy 220.536479 -409.744599) (xy 220.493325 -409.713177)
			(xy 220.454971 -409.676047) (xy 220.438218 -409.655264) (xy 220.428321 -409.643459) (xy 220.402997 -409.62594)
			(xy 220.373604 -409.616764) (xy 220.342812 -409.616764) (xy 220.313419 -409.62594) (xy 220.288095 -409.643459)
			(xy 220.278198 -409.655264) (xy 220.261445 -409.676047) (xy 220.223091 -409.713177) (xy 220.179937 -409.744599)
			(xy 220.132823 -409.769698) (xy 220.082671 -409.787984) (xy 220.03046 -409.799101) (xy 219.977208 -409.802831)
			(xy 219.923956 -409.799101) (xy 219.871745 -409.787984) (xy 219.821593 -409.769698) (xy 219.774479 -409.744599)
			(xy 219.731325 -409.713177) (xy 219.692971 -409.676047) (xy 219.676218 -409.655264) (xy 219.666321 -409.643459)
			(xy 219.640997 -409.62594) (xy 219.611604 -409.616764) (xy 219.580812 -409.616764) (xy 219.551419 -409.62594)
			(xy 219.526095 -409.643459) (xy 219.516198 -409.655264) (xy 219.499445 -409.676047) (xy 219.461091 -409.713177)
			(xy 219.417937 -409.744599) (xy 219.370823 -409.769698) (xy 219.320671 -409.787984) (xy 219.26846 -409.799101)
			(xy 219.215208 -409.802831) (xy 219.161956 -409.799101) (xy 219.109745 -409.787984) (xy 219.059593 -409.769698)
			(xy 219.012479 -409.744599) (xy 218.969325 -409.713177) (xy 218.930971 -409.676047) (xy 218.914218 -409.655264)
			(xy 218.904321 -409.643459) (xy 218.878997 -409.62594) (xy 218.849604 -409.616764) (xy 218.818812 -409.616764)
			(xy 218.789419 -409.62594) (xy 218.764095 -409.643459) (xy 218.754198 -409.655264) (xy 218.735999 -409.677741)
			(xy 218.693982 -409.717478) (xy 218.646449 -409.750419) (xy 218.594489 -409.775809) (xy 218.539293 -409.793066)
			(xy 218.482124 -409.801795) (xy 218.453208 -409.80233) (xy 218.425956 -409.801823) (xy 218.372008 -409.794068)
			(xy 218.319712 -409.778713) (xy 218.270134 -409.756072) (xy 218.224282 -409.726606) (xy 218.183091 -409.690915)
			(xy 218.147398 -409.649724) (xy 218.117931 -409.603873) (xy 218.09529 -409.554296) (xy 218.079934 -409.502)
			(xy 218.072177 -409.448052) (xy 217.907108 -409.448052) (xy 217.907108 -409.902914) (xy 217.982546 -409.978352)
			(xy 225.719894 -409.978352) (xy 226.006152 -409.692094) (xy 226.006152 -409.332938) (xy 226.005673 -409.318643)
			(xy 225.997755 -409.291171) (xy 225.982528 -409.266973) (xy 225.961187 -409.247947) (xy 225.935407 -409.235586)
			(xy 225.90721 -409.230859) (xy 225.878809 -409.234138) (xy 225.865436 -409.239212) (xy 225.84194 -409.248622)
			(xy 225.793088 -409.261863) (xy 225.742915 -409.268537) (xy 225.717608 -409.26893) (xy 225.690353 -409.268468)
			(xy 225.636398 -409.260711) (xy 225.584096 -409.245355) (xy 225.534512 -409.222712) (xy 225.488655 -409.193242)
			(xy 225.447459 -409.157546) (xy 225.411763 -409.116351) (xy 225.382292 -409.070495) (xy 225.359648 -409.020911)
			(xy 225.344291 -408.96861) (xy 225.336533 -408.914655) (xy 225.336533 -408.860145) (xy 225.344291 -408.80619)
			(xy 225.359648 -408.753889) (xy 225.382292 -408.704305) (xy 225.411763 -408.658449) (xy 225.447459 -408.617254)
			(xy 225.488655 -408.581558) (xy 225.534512 -408.552088) (xy 225.584096 -408.529445) (xy 225.636398 -408.514089)
			(xy 225.690353 -408.506332) (xy 225.717608 -408.505914) (xy 225.742916 -408.506308) (xy 225.793091 -408.51297)
			(xy 225.841942 -408.526215) (xy 225.865436 -408.535632) (xy 225.878806 -408.540681) (xy 225.907187 -408.543933)
			(xy 225.935358 -408.539192) (xy 225.961111 -408.52683) (xy 225.98243 -408.507815) (xy 225.997645 -408.483637)
			(xy 226.005563 -408.456189) (xy 226.006152 -408.441906) (xy 226.006152 -404.93696) (xy 226.006647 -404.910978)
			(xy 226.014805 -404.859658) (xy 226.030896 -404.810247) (xy 226.054525 -404.763966) (xy 226.085109 -404.721954)
			(xy 226.10318 -404.70328) (xy 227.452936 -403.353524) (xy 227.431346 -403.319234) (xy 227.417549 -403.296349)
			(xy 227.39579 -403.247543) (xy 227.381051 -403.196178) (xy 227.37362 -403.143261) (xy 227.37318 -403.116542)
			(xy 227.373666 -403.089291) (xy 227.381422 -403.035343) (xy 227.396777 -402.983048) (xy 227.419419 -402.933471)
			(xy 227.448885 -402.887621) (xy 227.484576 -402.84643) (xy 227.525767 -402.810739) (xy 227.571617 -402.781273)
			(xy 227.621194 -402.758631) (xy 227.673489 -402.743276) (xy 227.727437 -402.73552) (xy 227.781939 -402.73552)
			(xy 227.835887 -402.743276) (xy 227.888182 -402.758631) (xy 227.937759 -402.781273) (xy 227.983609 -402.810739)
			(xy 228.0248 -402.84643) (xy 228.060491 -402.887621) (xy 228.089957 -402.933471) (xy 228.112599 -402.983048)
			(xy 228.127954 -403.035343) (xy 228.13571 -403.089291) (xy 228.136196 -403.116542) (xy 228.136099 -403.127362)
			(xy 228.13483 -403.148965) (xy 228.133656 -403.159722) (xy 228.132535 -403.173977) (xy 228.137326 -403.202154)
			(xy 228.149733 -403.227902) (xy 228.168784 -403.249209) (xy 228.192989 -403.264407) (xy 228.220457 -403.272308)
			(xy 228.234748 -403.272752) (xy 228.904292 -403.272752) (xy 228.930272 -403.273251) (xy 228.981589 -403.281416)
			(xy 229.030994 -403.297513) (xy 229.07727 -403.321147) (xy 229.119275 -403.351734) (xy 229.137972 -403.36978)
			(xy 229.372414 -403.603968) (xy 229.384606 -403.607778) (xy 229.410346 -403.616098) (xy 229.459359 -403.63899)
			(xy 229.504647 -403.668575) (xy 229.545303 -403.704261) (xy 229.58051 -403.745331) (xy 229.609562 -403.790963)
			(xy 229.631879 -403.84024) (xy 229.64701 -403.892176) (xy 229.654655 -403.945728) (xy 229.655116 -403.972776)
			(xy 229.654654 -404.00003) (xy 229.650942 -404.025862) (xy 230.371648 -404.025862) (xy 230.375719 -403.97024)
			(xy 230.387845 -403.915803) (xy 230.407768 -403.863712) (xy 230.435064 -403.815077) (xy 230.46915 -403.770934)
			(xy 230.509299 -403.732225) (xy 230.554657 -403.699774) (xy 230.604257 -403.674273) (xy 230.657041 -403.656266)
			(xy 230.711884 -403.646136) (xy 230.767618 -403.644099) (xy 230.823055 -403.650199) (xy 230.877012 -403.664305)
			(xy 230.928341 -403.686117) (xy 230.975947 -403.715171) (xy 231.018815 -403.750846) (xy 231.056032 -403.792383)
			(xy 231.086805 -403.838896) (xy 231.110477 -403.889393) (xy 231.126545 -403.9428) (xy 231.134665 -403.997976)
			(xy 231.135174 -404.025862) (xy 231.794048 -404.025862) (xy 231.798119 -403.97024) (xy 231.810245 -403.915803)
			(xy 231.830168 -403.863712) (xy 231.857464 -403.815077) (xy 231.89155 -403.770934) (xy 231.931699 -403.732225)
			(xy 231.977057 -403.699774) (xy 232.026657 -403.674273) (xy 232.079441 -403.656266) (xy 232.134284 -403.646136)
			(xy 232.190018 -403.644099) (xy 232.245455 -403.650199) (xy 232.299412 -403.664305) (xy 232.350741 -403.686117)
			(xy 232.398347 -403.715171) (xy 232.441215 -403.750846) (xy 232.478432 -403.792383) (xy 232.509205 -403.838896)
			(xy 232.532877 -403.889393) (xy 232.548945 -403.9428) (xy 232.557065 -403.997976) (xy 232.557574 -404.025862)
			(xy 233.191048 -404.025862) (xy 233.195119 -403.97024) (xy 233.207245 -403.915803) (xy 233.227168 -403.863712)
			(xy 233.254464 -403.815077) (xy 233.28855 -403.770934) (xy 233.328699 -403.732225) (xy 233.374057 -403.699774)
			(xy 233.423657 -403.674273) (xy 233.476441 -403.656266) (xy 233.531284 -403.646136) (xy 233.587018 -403.644099)
			(xy 233.642455 -403.650199) (xy 233.696412 -403.664305) (xy 233.747741 -403.686117) (xy 233.780028 -403.705822)
			(xy 238.03559 -403.705822) (xy 238.039661 -403.6502) (xy 238.051787 -403.595763) (xy 238.07171 -403.543672)
			(xy 238.099006 -403.495037) (xy 238.133092 -403.450894) (xy 238.173241 -403.412185) (xy 238.218599 -403.379734)
			(xy 238.268199 -403.354233) (xy 238.320983 -403.336226) (xy 238.375826 -403.326096) (xy 238.43156 -403.324059)
			(xy 238.486997 -403.330159) (xy 238.540954 -403.344265) (xy 238.592283 -403.366077) (xy 238.639889 -403.395131)
			(xy 238.682757 -403.430806) (xy 238.719974 -403.472343) (xy 238.750747 -403.518856) (xy 238.774419 -403.569353)
			(xy 238.790487 -403.62276) (xy 238.798607 -403.677936) (xy 238.799116 -403.705822) (xy 238.798607 -403.733708)
			(xy 238.790487 -403.788884) (xy 238.774419 -403.842291) (xy 238.750747 -403.892788) (xy 238.719974 -403.939301)
			(xy 238.682757 -403.980838) (xy 238.639889 -404.016513) (xy 238.592283 -404.045567) (xy 238.540954 -404.067379)
			(xy 238.486997 -404.081485) (xy 238.43156 -404.087585) (xy 238.375826 -404.085548) (xy 238.320983 -404.075418)
			(xy 238.268199 -404.057411) (xy 238.218599 -404.03191) (xy 238.173241 -403.999459) (xy 238.133092 -403.96075)
			(xy 238.099006 -403.916607) (xy 238.07171 -403.867972) (xy 238.051787 -403.815881) (xy 238.039661 -403.761444)
			(xy 238.03559 -403.705822) (xy 233.780028 -403.705822) (xy 233.795347 -403.715171) (xy 233.838215 -403.750846)
			(xy 233.875432 -403.792383) (xy 233.906205 -403.838896) (xy 233.929877 -403.889393) (xy 233.945945 -403.9428)
			(xy 233.954065 -403.997976) (xy 233.954574 -404.025862) (xy 233.954065 -404.053748) (xy 233.945945 -404.108924)
			(xy 233.929877 -404.162331) (xy 233.906205 -404.212828) (xy 233.875432 -404.259341) (xy 233.838215 -404.300878)
			(xy 233.795347 -404.336553) (xy 233.747741 -404.365607) (xy 233.696412 -404.387419) (xy 233.642455 -404.401525)
			(xy 233.587018 -404.407625) (xy 233.531284 -404.405588) (xy 233.476441 -404.395458) (xy 233.423657 -404.377451)
			(xy 233.374057 -404.35195) (xy 233.328699 -404.319499) (xy 233.28855 -404.28079) (xy 233.254464 -404.236647)
			(xy 233.227168 -404.188012) (xy 233.207245 -404.135921) (xy 233.195119 -404.081484) (xy 233.191048 -404.025862)
			(xy 232.557574 -404.025862) (xy 232.557065 -404.053748) (xy 232.548945 -404.108924) (xy 232.532877 -404.162331)
			(xy 232.509205 -404.212828) (xy 232.478432 -404.259341) (xy 232.441215 -404.300878) (xy 232.398347 -404.336553)
			(xy 232.350741 -404.365607) (xy 232.299412 -404.387419) (xy 232.245455 -404.401525) (xy 232.190018 -404.407625)
			(xy 232.134284 -404.405588) (xy 232.079441 -404.395458) (xy 232.026657 -404.377451) (xy 231.977057 -404.35195)
			(xy 231.931699 -404.319499) (xy 231.89155 -404.28079) (xy 231.857464 -404.236647) (xy 231.830168 -404.188012)
			(xy 231.810245 -404.135921) (xy 231.798119 -404.081484) (xy 231.794048 -404.025862) (xy 231.135174 -404.025862)
			(xy 231.134665 -404.053748) (xy 231.126545 -404.108924) (xy 231.110477 -404.162331) (xy 231.086805 -404.212828)
			(xy 231.056032 -404.259341) (xy 231.018815 -404.300878) (xy 230.975947 -404.336553) (xy 230.928341 -404.365607)
			(xy 230.877012 -404.387419) (xy 230.823055 -404.401525) (xy 230.767618 -404.407625) (xy 230.711884 -404.405588)
			(xy 230.657041 -404.395458) (xy 230.604257 -404.377451) (xy 230.554657 -404.35195) (xy 230.509299 -404.319499)
			(xy 230.46915 -404.28079) (xy 230.435064 -404.236647) (xy 230.407768 -404.188012) (xy 230.387845 -404.135921)
			(xy 230.375719 -404.081484) (xy 230.371648 -404.025862) (xy 229.650942 -404.025862) (xy 229.6469 -404.053984)
			(xy 229.631546 -404.106285) (xy 229.608905 -404.155869) (xy 229.579438 -404.201726) (xy 229.543745 -404.242922)
			(xy 229.502551 -404.278619) (xy 229.456697 -404.30809) (xy 229.407115 -404.330735) (xy 229.354815 -404.346093)
			(xy 229.300862 -404.353852) (xy 229.273608 -404.354284) (xy 229.246561 -404.353813) (xy 229.193008 -404.346172)
			(xy 229.141072 -404.331043) (xy 229.091793 -404.308729) (xy 229.046162 -404.279677) (xy 229.005091 -404.244471)
			(xy 228.969407 -404.203816) (xy 228.939823 -404.158527) (xy 228.916933 -404.109513) (xy 228.90861 -404.083774)
			(xy 228.9048 -404.071582) (xy 228.767386 -403.934168) (xy 227.807266 -403.934168) (xy 226.667568 -405.073866)
			(xy 226.667568 -405.929084) (xy 226.668083 -405.944071) (xy 226.676753 -405.972762) (xy 226.69338 -405.997699)
			(xy 226.716532 -406.016734) (xy 226.744214 -406.028226) (xy 226.774039 -406.031186) (xy 226.80344 -406.025358)
			(xy 226.829881 -406.011244) (xy 226.840796 -406.000966) (xy 228.117146 -404.724616) (xy 228.120956 -404.712424)
			(xy 228.129275 -404.686681) (xy 228.152163 -404.637663) (xy 228.181746 -404.59237) (xy 228.217431 -404.55171)
			(xy 228.258501 -404.516498) (xy 228.304133 -404.48744) (xy 228.353412 -404.465119) (xy 228.40535 -404.449983)
			(xy 228.458905 -404.442335) (xy 228.485954 -404.441914) (xy 228.513208 -404.442374) (xy 228.567163 -404.450126)
			(xy 228.619465 -404.465478) (xy 228.66905 -404.488118) (xy 228.714907 -404.517586) (xy 228.756103 -404.55328)
			(xy 228.7918 -404.594474) (xy 228.82127 -404.640329) (xy 228.843913 -404.689912) (xy 228.859269 -404.742213)
			(xy 228.867024 -404.796168) (xy 228.867462 -404.823422) (xy 228.866989 -404.850468) (xy 228.859344 -404.904017)
			(xy 228.844212 -404.955949) (xy 228.821895 -405.005222) (xy 228.792842 -405.050849) (xy 228.757634 -405.091914)
			(xy 228.716978 -405.127594) (xy 228.67169 -405.157173) (xy 228.622678 -405.180057) (xy 228.596952 -405.18842)
			(xy 228.58476 -405.19223) (xy 227.160328 -406.616662) (xy 227.160328 -406.855422) (xy 227.36759 -406.855422)
			(xy 227.371661 -406.7998) (xy 227.383787 -406.745363) (xy 227.40371 -406.693272) (xy 227.431006 -406.644637)
			(xy 227.465092 -406.600494) (xy 227.505241 -406.561785) (xy 227.550599 -406.529334) (xy 227.600199 -406.503833)
			(xy 227.652983 -406.485826) (xy 227.707826 -406.475696) (xy 227.76356 -406.473659) (xy 227.818997 -406.479759)
			(xy 227.872954 -406.493865) (xy 227.924283 -406.515677) (xy 227.971889 -406.544731) (xy 228.009479 -406.576014)
			(xy 230.263215 -406.576014) (xy 230.266942 -406.522764) (xy 230.278057 -406.470554) (xy 230.296341 -406.420404)
			(xy 230.321438 -406.373292) (xy 230.352857 -406.330138) (xy 230.389985 -406.291785) (xy 230.410766 -406.275032)
			(xy 230.422551 -406.265112) (xy 230.440073 -406.239795) (xy 230.449253 -406.210408) (xy 230.449257 -406.179619)
			(xy 230.440085 -406.150229) (xy 230.42257 -406.124908) (xy 230.410766 -406.115012) (xy 230.388281 -406.096823)
			(xy 230.348548 -406.054802) (xy 230.31561 -406.007266) (xy 230.290222 -405.955305) (xy 230.272966 -405.900107)
			(xy 230.264236 -405.842938) (xy 230.2637 -405.814022) (xy 230.264176 -405.786769) (xy 230.27193 -405.732818)
			(xy 230.287284 -405.68052) (xy 230.309924 -405.63094) (xy 230.339391 -405.585086) (xy 230.375083 -405.543893)
			(xy 230.416275 -405.508199) (xy 230.462127 -405.478731) (xy 230.511707 -405.456089) (xy 230.564005 -405.440733)
			(xy 230.617955 -405.432977) (xy 230.645208 -405.432514) (xy 230.674123 -405.433093) (xy 230.731291 -405.441809)
			(xy 230.786489 -405.459055) (xy 230.838451 -405.484435) (xy 230.885987 -405.517368) (xy 230.928006 -405.557099)
			(xy 230.946198 -405.57958) (xy 230.956095 -405.591385) (xy 230.981419 -405.608904) (xy 231.010812 -405.61808)
			(xy 231.041604 -405.61808) (xy 231.070997 -405.608904) (xy 231.096321 -405.591385) (xy 231.106218 -405.57958)
			(xy 231.122971 -405.558797) (xy 231.161325 -405.521667) (xy 231.204479 -405.490245) (xy 231.251593 -405.465146)
			(xy 231.301745 -405.44686) (xy 231.353956 -405.435743) (xy 231.407208 -405.432013) (xy 231.46046 -405.435743)
			(xy 231.512671 -405.44686) (xy 231.562823 -405.465146) (xy 231.609937 -405.490245) (xy 231.653091 -405.521667)
			(xy 231.691445 -405.558797) (xy 231.708198 -405.57958) (xy 231.718095 -405.591385) (xy 231.743419 -405.608904)
			(xy 231.772812 -405.61808) (xy 231.803604 -405.61808) (xy 231.832997 -405.608904) (xy 231.858321 -405.591385)
			(xy 231.868218 -405.57958) (xy 231.884971 -405.558797) (xy 231.923325 -405.521667) (xy 231.966479 -405.490245)
			(xy 232.013593 -405.465146) (xy 232.063745 -405.44686) (xy 232.115956 -405.435743) (xy 232.169208 -405.432013)
			(xy 232.22246 -405.435743) (xy 232.274671 -405.44686) (xy 232.324823 -405.465146) (xy 232.371937 -405.490245)
			(xy 232.415091 -405.521667) (xy 232.453445 -405.558797) (xy 232.470198 -405.57958) (xy 232.480095 -405.591385)
			(xy 232.505419 -405.608904) (xy 232.534812 -405.61808) (xy 232.565604 -405.61808) (xy 232.594997 -405.608904)
			(xy 232.620321 -405.591385) (xy 232.630218 -405.57958) (xy 232.646971 -405.558797) (xy 232.685325 -405.521667)
			(xy 232.728479 -405.490245) (xy 232.775593 -405.465146) (xy 232.825745 -405.44686) (xy 232.877956 -405.435743)
			(xy 232.931208 -405.432013) (xy 232.98446 -405.435743) (xy 233.036671 -405.44686) (xy 233.086823 -405.465146)
			(xy 233.133937 -405.490245) (xy 233.177091 -405.521667) (xy 233.215445 -405.558797) (xy 233.232198 -405.57958)
			(xy 233.242095 -405.591385) (xy 233.267419 -405.608904) (xy 233.296812 -405.61808) (xy 233.327604 -405.61808)
			(xy 233.356997 -405.608904) (xy 233.382321 -405.591385) (xy 233.392218 -405.57958) (xy 233.410394 -405.557084)
			(xy 233.452417 -405.51735) (xy 233.499956 -405.484413) (xy 233.55192 -405.459027) (xy 233.60712 -405.441774)
			(xy 233.664291 -405.433048) (xy 233.693208 -405.432514) (xy 233.720462 -405.432948) (xy 233.774415 -405.440707)
			(xy 233.826715 -405.456065) (xy 233.876297 -405.47871) (xy 233.922151 -405.508181) (xy 233.963344 -405.543877)
			(xy 233.999037 -405.585073) (xy 234.028505 -405.63093) (xy 234.051146 -405.680513) (xy 234.0665 -405.732814)
			(xy 234.074254 -405.786768) (xy 234.074716 -405.814022) (xy 234.074173 -405.842938) (xy 234.065454 -405.90011)
			(xy 234.048203 -405.95531) (xy 234.022816 -406.007272) (xy 233.989875 -406.054806) (xy 233.950135 -406.096822)
			(xy 233.92765 -406.115012) (xy 233.915819 -406.124883) (xy 233.898296 -406.150212) (xy 233.889119 -406.179613)
			(xy 233.889123 -406.210413) (xy 233.898308 -406.239812) (xy 233.915838 -406.265136) (xy 233.92765 -406.275032)
			(xy 233.948454 -406.29176) (xy 233.985584 -406.330116) (xy 234.017005 -406.373274) (xy 234.042103 -406.420391)
			(xy 234.060387 -406.470546) (xy 234.071502 -406.52276) (xy 234.07523 -406.576014) (xy 234.071499 -406.629267)
			(xy 234.06038 -406.68148) (xy 234.042092 -406.731634) (xy 234.01699 -406.778749) (xy 233.985567 -406.821904)
			(xy 233.948434 -406.860258) (xy 233.92765 -406.877012) (xy 233.915819 -406.886883) (xy 233.898296 -406.912212)
			(xy 233.889119 -406.941613) (xy 233.889123 -406.972413) (xy 233.898308 -407.001812) (xy 233.915838 -407.027136)
			(xy 233.92765 -407.037032) (xy 233.950159 -407.055192) (xy 233.989891 -407.09722) (xy 234.022825 -407.144762)
			(xy 234.048209 -407.196729) (xy 234.06546 -407.251931) (xy 234.074184 -407.309104) (xy 234.074716 -407.338022)
			(xy 234.074243 -407.365273) (xy 234.066483 -407.419221) (xy 234.051126 -407.471516) (xy 234.028483 -407.521092)
			(xy 233.999015 -407.566942) (xy 233.963322 -407.608132) (xy 233.922131 -407.643823) (xy 233.87628 -407.673289)
			(xy 233.826703 -407.695931) (xy 233.774407 -407.711286) (xy 233.720459 -407.719044) (xy 233.693208 -407.71953)
			(xy 233.66429 -407.719032) (xy 233.607117 -407.710303) (xy 233.551916 -407.693043) (xy 233.499954 -407.667647)
			(xy 233.452421 -407.634699) (xy 233.410406 -407.594952) (xy 233.392218 -407.572464) (xy 233.382321 -407.560659)
			(xy 233.356997 -407.54314) (xy 233.327604 -407.533964) (xy 233.296812 -407.533964) (xy 233.267419 -407.54314)
			(xy 233.242095 -407.560659) (xy 233.232198 -407.572464) (xy 233.215445 -407.593247) (xy 233.177091 -407.630377)
			(xy 233.133937 -407.661799) (xy 233.086823 -407.686898) (xy 233.036671 -407.705184) (xy 232.98446 -407.716301)
			(xy 232.931208 -407.720031) (xy 232.877956 -407.716301) (xy 232.825745 -407.705184) (xy 232.775593 -407.686898)
			(xy 232.728479 -407.661799) (xy 232.685325 -407.630377) (xy 232.646971 -407.593247) (xy 232.630218 -407.572464)
			(xy 232.620321 -407.560659) (xy 232.594997 -407.54314) (xy 232.565604 -407.533964) (xy 232.534812 -407.533964)
			(xy 232.505419 -407.54314) (xy 232.480095 -407.560659) (xy 232.470198 -407.572464) (xy 232.453445 -407.593247)
			(xy 232.415091 -407.630377) (xy 232.371937 -407.661799) (xy 232.324823 -407.686898) (xy 232.274671 -407.705184)
			(xy 232.22246 -407.716301) (xy 232.169208 -407.720031) (xy 232.115956 -407.716301) (xy 232.063745 -407.705184)
			(xy 232.013593 -407.686898) (xy 231.966479 -407.661799) (xy 231.923325 -407.630377) (xy 231.884971 -407.593247)
			(xy 231.868218 -407.572464) (xy 231.858321 -407.560659) (xy 231.832997 -407.54314) (xy 231.803604 -407.533964)
			(xy 231.772812 -407.533964) (xy 231.743419 -407.54314) (xy 231.718095 -407.560659) (xy 231.708198 -407.572464)
			(xy 231.691445 -407.593247) (xy 231.653091 -407.630377) (xy 231.609937 -407.661799) (xy 231.562823 -407.686898)
			(xy 231.512671 -407.705184) (xy 231.46046 -407.716301) (xy 231.407208 -407.720031) (xy 231.353956 -407.716301)
			(xy 231.301745 -407.705184) (xy 231.251593 -407.686898) (xy 231.204479 -407.661799) (xy 231.161325 -407.630377)
			(xy 231.122971 -407.593247) (xy 231.106218 -407.572464) (xy 231.096321 -407.560659) (xy 231.070997 -407.54314)
			(xy 231.041604 -407.533964) (xy 231.010812 -407.533964) (xy 230.981419 -407.54314) (xy 230.956095 -407.560659)
			(xy 230.946198 -407.572464) (xy 230.927999 -407.594941) (xy 230.885982 -407.634678) (xy 230.838449 -407.667619)
			(xy 230.786489 -407.693009) (xy 230.731293 -407.710266) (xy 230.674124 -407.718995) (xy 230.645208 -407.71953)
			(xy 230.617958 -407.719015) (xy 230.564012 -407.71126) (xy 230.51172 -407.695907) (xy 230.462144 -407.673268)
			(xy 230.416294 -407.643805) (xy 230.375105 -407.608117) (xy 230.339413 -407.56693) (xy 230.309946 -407.521083)
			(xy 230.287304 -407.471509) (xy 230.271946 -407.419217) (xy 230.264187 -407.365272) (xy 230.2637 -407.338022)
			(xy 230.264234 -407.309106) (xy 230.27296 -407.251935) (xy 230.290215 -407.196737) (xy 230.315603 -407.144775)
			(xy 230.348544 -407.097241) (xy 230.388282 -407.055223) (xy 230.410766 -407.037032) (xy 230.422551 -407.027112)
			(xy 230.440073 -407.001795) (xy 230.449253 -406.972408) (xy 230.449257 -406.941619) (xy 230.440085 -406.912229)
			(xy 230.42257 -406.886908) (xy 230.410766 -406.877012) (xy 230.390005 -406.860233) (xy 230.352874 -406.821883)
			(xy 230.321452 -406.778731) (xy 230.296352 -406.731621) (xy 230.278064 -406.681472) (xy 230.266946 -406.629263)
			(xy 230.263215 -406.576014) (xy 228.009479 -406.576014) (xy 228.014757 -406.580406) (xy 228.051974 -406.621943)
			(xy 228.082747 -406.668456) (xy 228.106419 -406.718953) (xy 228.122487 -406.77236) (xy 228.130607 -406.827536)
			(xy 228.131116 -406.855422) (xy 228.130607 -406.883308) (xy 228.122487 -406.938484) (xy 228.106419 -406.991891)
			(xy 228.082747 -407.042388) (xy 228.051974 -407.088901) (xy 228.014757 -407.130438) (xy 227.971889 -407.166113)
			(xy 227.924283 -407.195167) (xy 227.872954 -407.216979) (xy 227.818997 -407.231085) (xy 227.76356 -407.237185)
			(xy 227.707826 -407.235148) (xy 227.652983 -407.225018) (xy 227.600199 -407.207011) (xy 227.550599 -407.18151)
			(xy 227.505241 -407.149059) (xy 227.465092 -407.11035) (xy 227.431006 -407.066207) (xy 227.40371 -407.017572)
			(xy 227.383787 -406.965481) (xy 227.371661 -406.911044) (xy 227.36759 -406.855422) (xy 227.160328 -406.855422)
			(xy 227.160328 -408.406652) (xy 229.502177 -408.406652) (xy 229.502177 -408.352148) (xy 229.509934 -408.2982)
			(xy 229.52529 -408.245904) (xy 229.547931 -408.196327) (xy 229.577398 -408.150476) (xy 229.613091 -408.109285)
			(xy 229.654282 -408.073594) (xy 229.700134 -408.044128) (xy 229.749712 -408.021487) (xy 229.802008 -408.006132)
			(xy 229.855956 -407.998377) (xy 229.883208 -407.997914) (xy 229.912123 -407.998493) (xy 229.969291 -408.007209)
			(xy 230.024489 -408.024455) (xy 230.076451 -408.049835) (xy 230.123987 -408.082768) (xy 230.166006 -408.122499)
			(xy 230.184198 -408.14498) (xy 230.194095 -408.156785) (xy 230.219419 -408.174304) (xy 230.248812 -408.18348)
			(xy 230.279604 -408.18348) (xy 230.308997 -408.174304) (xy 230.334321 -408.156785) (xy 230.344218 -408.14498)
			(xy 230.360971 -408.124197) (xy 230.399325 -408.087067) (xy 230.442479 -408.055645) (xy 230.489593 -408.030546)
			(xy 230.539745 -408.01226) (xy 230.591956 -408.001143) (xy 230.645208 -407.997413) (xy 230.69846 -408.001143)
			(xy 230.750671 -408.01226) (xy 230.800823 -408.030546) (xy 230.847937 -408.055645) (xy 230.891091 -408.087067)
			(xy 230.929445 -408.124197) (xy 230.946198 -408.14498) (xy 230.956095 -408.156785) (xy 230.981419 -408.174304)
			(xy 231.010812 -408.18348) (xy 231.041604 -408.18348) (xy 231.070997 -408.174304) (xy 231.096321 -408.156785)
			(xy 231.106218 -408.14498) (xy 231.122971 -408.124197) (xy 231.161325 -408.087067) (xy 231.204479 -408.055645)
			(xy 231.251593 -408.030546) (xy 231.301745 -408.01226) (xy 231.353956 -408.001143) (xy 231.407208 -407.997413)
			(xy 231.46046 -408.001143) (xy 231.512671 -408.01226) (xy 231.562823 -408.030546) (xy 231.609937 -408.055645)
			(xy 231.653091 -408.087067) (xy 231.691445 -408.124197) (xy 231.708198 -408.14498) (xy 231.718095 -408.156785)
			(xy 231.743419 -408.174304) (xy 231.772812 -408.18348) (xy 231.803604 -408.18348) (xy 231.832997 -408.174304)
			(xy 231.858321 -408.156785) (xy 231.868218 -408.14498) (xy 231.884971 -408.124197) (xy 231.923325 -408.087067)
			(xy 231.966479 -408.055645) (xy 232.013593 -408.030546) (xy 232.063745 -408.01226) (xy 232.115956 -408.001143)
			(xy 232.169208 -407.997413) (xy 232.22246 -408.001143) (xy 232.274671 -408.01226) (xy 232.324823 -408.030546)
			(xy 232.371937 -408.055645) (xy 232.415091 -408.087067) (xy 232.453445 -408.124197) (xy 232.470198 -408.14498)
			(xy 232.480095 -408.156785) (xy 232.505419 -408.174304) (xy 232.534812 -408.18348) (xy 232.565604 -408.18348)
			(xy 232.594997 -408.174304) (xy 232.620321 -408.156785) (xy 232.630218 -408.14498) (xy 232.646971 -408.124197)
			(xy 232.685325 -408.087067) (xy 232.728479 -408.055645) (xy 232.775593 -408.030546) (xy 232.825745 -408.01226)
			(xy 232.877956 -408.001143) (xy 232.931208 -407.997413) (xy 232.98446 -408.001143) (xy 233.036671 -408.01226)
			(xy 233.086823 -408.030546) (xy 233.133937 -408.055645) (xy 233.177091 -408.087067) (xy 233.215445 -408.124197)
			(xy 233.232198 -408.14498) (xy 233.242095 -408.156785) (xy 233.267419 -408.174304) (xy 233.296812 -408.18348)
			(xy 233.327604 -408.18348) (xy 233.356997 -408.174304) (xy 233.382321 -408.156785) (xy 233.392218 -408.14498)
			(xy 233.408971 -408.124197) (xy 233.447325 -408.087067) (xy 233.490479 -408.055645) (xy 233.537593 -408.030546)
			(xy 233.587745 -408.01226) (xy 233.639956 -408.001143) (xy 233.693208 -407.997413) (xy 233.74646 -408.001143)
			(xy 233.798671 -408.01226) (xy 233.848823 -408.030546) (xy 233.895937 -408.055645) (xy 233.939091 -408.087067)
			(xy 233.977445 -408.124197) (xy 233.994198 -408.14498) (xy 234.004095 -408.156785) (xy 234.029419 -408.174304)
			(xy 234.058812 -408.18348) (xy 234.089604 -408.18348) (xy 234.118997 -408.174304) (xy 234.144321 -408.156785)
			(xy 234.154218 -408.14498) (xy 234.172394 -408.122484) (xy 234.214417 -408.08275) (xy 234.261956 -408.049813)
			(xy 234.31392 -408.024427) (xy 234.36912 -408.007174) (xy 234.426291 -407.998448) (xy 234.455208 -407.997914)
			(xy 234.48246 -407.998356) (xy 234.53641 -408.006114) (xy 234.588707 -408.021471) (xy 234.638286 -408.044114)
			(xy 234.684138 -408.073582) (xy 234.72533 -408.109276) (xy 234.761023 -408.150468) (xy 234.79049 -408.196321)
			(xy 234.813132 -408.2459) (xy 234.828487 -408.298197) (xy 234.836244 -408.352148) (xy 234.836244 -408.406652)
			(xy 234.828487 -408.460603) (xy 234.813132 -408.5129) (xy 234.79049 -408.562479) (xy 234.761023 -408.608332)
			(xy 234.72533 -408.649524) (xy 234.684138 -408.685218) (xy 234.638286 -408.714686) (xy 234.588707 -408.737329)
			(xy 234.53641 -408.752686) (xy 234.48246 -408.760444) (xy 234.455208 -408.76093) (xy 234.42629 -408.760432)
			(xy 234.369117 -408.751703) (xy 234.313916 -408.734443) (xy 234.261954 -408.709047) (xy 234.214421 -408.676099)
			(xy 234.172406 -408.636352) (xy 234.154218 -408.613864) (xy 234.144321 -408.602059) (xy 234.118997 -408.58454)
			(xy 234.089604 -408.575364) (xy 234.058812 -408.575364) (xy 234.029419 -408.58454) (xy 234.004095 -408.602059)
			(xy 233.994198 -408.613864) (xy 233.977445 -408.634647) (xy 233.939091 -408.671777) (xy 233.895937 -408.703199)
			(xy 233.848823 -408.728298) (xy 233.798671 -408.746584) (xy 233.74646 -408.757701) (xy 233.693208 -408.761431)
			(xy 233.639956 -408.757701) (xy 233.587745 -408.746584) (xy 233.537593 -408.728298) (xy 233.490479 -408.703199)
			(xy 233.447325 -408.671777) (xy 233.408971 -408.634647) (xy 233.392218 -408.613864) (xy 233.382321 -408.602059)
			(xy 233.356997 -408.58454) (xy 233.327604 -408.575364) (xy 233.296812 -408.575364) (xy 233.267419 -408.58454)
			(xy 233.242095 -408.602059) (xy 233.232198 -408.613864) (xy 233.215445 -408.634647) (xy 233.177091 -408.671777)
			(xy 233.133937 -408.703199) (xy 233.086823 -408.728298) (xy 233.036671 -408.746584) (xy 232.98446 -408.757701)
			(xy 232.931208 -408.761431) (xy 232.877956 -408.757701) (xy 232.825745 -408.746584) (xy 232.775593 -408.728298)
			(xy 232.728479 -408.703199) (xy 232.685325 -408.671777) (xy 232.646971 -408.634647) (xy 232.630218 -408.613864)
			(xy 232.620321 -408.602059) (xy 232.594997 -408.58454) (xy 232.565604 -408.575364) (xy 232.534812 -408.575364)
			(xy 232.505419 -408.58454) (xy 232.480095 -408.602059) (xy 232.470198 -408.613864) (xy 232.453445 -408.634647)
			(xy 232.415091 -408.671777) (xy 232.371937 -408.703199) (xy 232.324823 -408.728298) (xy 232.274671 -408.746584)
			(xy 232.22246 -408.757701) (xy 232.169208 -408.761431) (xy 232.115956 -408.757701) (xy 232.063745 -408.746584)
			(xy 232.013593 -408.728298) (xy 231.966479 -408.703199) (xy 231.923325 -408.671777) (xy 231.884971 -408.634647)
			(xy 231.868218 -408.613864) (xy 231.858321 -408.602059) (xy 231.832997 -408.58454) (xy 231.803604 -408.575364)
			(xy 231.772812 -408.575364) (xy 231.743419 -408.58454) (xy 231.718095 -408.602059) (xy 231.708198 -408.613864)
			(xy 231.691445 -408.634647) (xy 231.653091 -408.671777) (xy 231.609937 -408.703199) (xy 231.562823 -408.728298)
			(xy 231.512671 -408.746584) (xy 231.46046 -408.757701) (xy 231.407208 -408.761431) (xy 231.353956 -408.757701)
			(xy 231.301745 -408.746584) (xy 231.251593 -408.728298) (xy 231.204479 -408.703199) (xy 231.161325 -408.671777)
			(xy 231.122971 -408.634647) (xy 231.106218 -408.613864) (xy 231.096321 -408.602059) (xy 231.070997 -408.58454)
			(xy 231.041604 -408.575364) (xy 231.010812 -408.575364) (xy 230.981419 -408.58454) (xy 230.956095 -408.602059)
			(xy 230.946198 -408.613864) (xy 230.929445 -408.634647) (xy 230.891091 -408.671777) (xy 230.847937 -408.703199)
			(xy 230.800823 -408.728298) (xy 230.750671 -408.746584) (xy 230.69846 -408.757701) (xy 230.645208 -408.761431)
			(xy 230.591956 -408.757701) (xy 230.539745 -408.746584) (xy 230.489593 -408.728298) (xy 230.442479 -408.703199)
			(xy 230.399325 -408.671777) (xy 230.360971 -408.634647) (xy 230.344218 -408.613864) (xy 230.334321 -408.602059)
			(xy 230.308997 -408.58454) (xy 230.279604 -408.575364) (xy 230.248812 -408.575364) (xy 230.219419 -408.58454)
			(xy 230.194095 -408.602059) (xy 230.184198 -408.613864) (xy 230.165999 -408.636341) (xy 230.123982 -408.676078)
			(xy 230.076449 -408.709019) (xy 230.024489 -408.734409) (xy 229.969293 -408.751666) (xy 229.912124 -408.760395)
			(xy 229.883208 -408.76093) (xy 229.855956 -408.760423) (xy 229.802008 -408.752668) (xy 229.749712 -408.737313)
			(xy 229.700134 -408.714672) (xy 229.654282 -408.685206) (xy 229.613091 -408.649515) (xy 229.577398 -408.608324)
			(xy 229.547931 -408.562473) (xy 229.52529 -408.512896) (xy 229.509934 -408.4606) (xy 229.502177 -408.406652)
			(xy 227.160328 -408.406652) (xy 227.160328 -409.448052) (xy 228.740177 -409.448052) (xy 228.740177 -409.393548)
			(xy 228.747934 -409.3396) (xy 228.76329 -409.287304) (xy 228.785931 -409.237727) (xy 228.815398 -409.191876)
			(xy 228.851091 -409.150685) (xy 228.892282 -409.114994) (xy 228.938134 -409.085528) (xy 228.987712 -409.062887)
			(xy 229.040008 -409.047532) (xy 229.093956 -409.039777) (xy 229.121208 -409.039314) (xy 229.150123 -409.039893)
			(xy 229.207291 -409.048609) (xy 229.262489 -409.065855) (xy 229.314451 -409.091235) (xy 229.361987 -409.124168)
			(xy 229.404006 -409.163899) (xy 229.422198 -409.18638) (xy 229.432095 -409.198185) (xy 229.457419 -409.215704)
			(xy 229.486812 -409.22488) (xy 229.517604 -409.22488) (xy 229.546997 -409.215704) (xy 229.572321 -409.198185)
			(xy 229.582218 -409.18638) (xy 229.598971 -409.165597) (xy 229.637325 -409.128467) (xy 229.680479 -409.097045)
			(xy 229.727593 -409.071946) (xy 229.777745 -409.05366) (xy 229.829956 -409.042543) (xy 229.883208 -409.038813)
			(xy 229.93646 -409.042543) (xy 229.988671 -409.05366) (xy 230.038823 -409.071946) (xy 230.085937 -409.097045)
			(xy 230.129091 -409.128467) (xy 230.167445 -409.165597) (xy 230.184198 -409.18638) (xy 230.194095 -409.198185)
			(xy 230.219419 -409.215704) (xy 230.248812 -409.22488) (xy 230.279604 -409.22488) (xy 230.308997 -409.215704)
			(xy 230.334321 -409.198185) (xy 230.344218 -409.18638) (xy 230.360971 -409.165597) (xy 230.399325 -409.128467)
			(xy 230.442479 -409.097045) (xy 230.489593 -409.071946) (xy 230.539745 -409.05366) (xy 230.591956 -409.042543)
			(xy 230.645208 -409.038813) (xy 230.69846 -409.042543) (xy 230.750671 -409.05366) (xy 230.800823 -409.071946)
			(xy 230.847937 -409.097045) (xy 230.891091 -409.128467) (xy 230.929445 -409.165597) (xy 230.946198 -409.18638)
			(xy 230.956095 -409.198185) (xy 230.981419 -409.215704) (xy 231.010812 -409.22488) (xy 231.041604 -409.22488)
			(xy 231.070997 -409.215704) (xy 231.096321 -409.198185) (xy 231.106218 -409.18638) (xy 231.122971 -409.165597)
			(xy 231.161325 -409.128467) (xy 231.204479 -409.097045) (xy 231.251593 -409.071946) (xy 231.301745 -409.05366)
			(xy 231.353956 -409.042543) (xy 231.407208 -409.038813) (xy 231.46046 -409.042543) (xy 231.512671 -409.05366)
			(xy 231.562823 -409.071946) (xy 231.609937 -409.097045) (xy 231.653091 -409.128467) (xy 231.691445 -409.165597)
			(xy 231.708198 -409.18638) (xy 231.718095 -409.198185) (xy 231.743419 -409.215704) (xy 231.772812 -409.22488)
			(xy 231.803604 -409.22488) (xy 231.832997 -409.215704) (xy 231.858321 -409.198185) (xy 231.868218 -409.18638)
			(xy 231.884971 -409.165597) (xy 231.923325 -409.128467) (xy 231.966479 -409.097045) (xy 232.013593 -409.071946)
			(xy 232.063745 -409.05366) (xy 232.115956 -409.042543) (xy 232.169208 -409.038813) (xy 232.22246 -409.042543)
			(xy 232.274671 -409.05366) (xy 232.324823 -409.071946) (xy 232.371937 -409.097045) (xy 232.415091 -409.128467)
			(xy 232.453445 -409.165597) (xy 232.470198 -409.18638) (xy 232.480095 -409.198185) (xy 232.505419 -409.215704)
			(xy 232.534812 -409.22488) (xy 232.565604 -409.22488) (xy 232.594997 -409.215704) (xy 232.620321 -409.198185)
			(xy 232.630218 -409.18638) (xy 232.646971 -409.165597) (xy 232.685325 -409.128467) (xy 232.728479 -409.097045)
			(xy 232.775593 -409.071946) (xy 232.825745 -409.05366) (xy 232.877956 -409.042543) (xy 232.931208 -409.038813)
			(xy 232.98446 -409.042543) (xy 233.036671 -409.05366) (xy 233.086823 -409.071946) (xy 233.133937 -409.097045)
			(xy 233.177091 -409.128467) (xy 233.215445 -409.165597) (xy 233.232198 -409.18638) (xy 233.242095 -409.198185)
			(xy 233.267419 -409.215704) (xy 233.296812 -409.22488) (xy 233.327604 -409.22488) (xy 233.356997 -409.215704)
			(xy 233.382321 -409.198185) (xy 233.392218 -409.18638) (xy 233.408971 -409.165597) (xy 233.447325 -409.128467)
			(xy 233.490479 -409.097045) (xy 233.537593 -409.071946) (xy 233.587745 -409.05366) (xy 233.639956 -409.042543)
			(xy 233.693208 -409.038813) (xy 233.74646 -409.042543) (xy 233.798671 -409.05366) (xy 233.848823 -409.071946)
			(xy 233.895937 -409.097045) (xy 233.939091 -409.128467) (xy 233.977445 -409.165597) (xy 233.994198 -409.18638)
			(xy 234.004095 -409.198185) (xy 234.029419 -409.215704) (xy 234.058812 -409.22488) (xy 234.089604 -409.22488)
			(xy 234.118997 -409.215704) (xy 234.144321 -409.198185) (xy 234.154218 -409.18638) (xy 234.172394 -409.163884)
			(xy 234.214417 -409.12415) (xy 234.261956 -409.091213) (xy 234.31392 -409.065827) (xy 234.36912 -409.048574)
			(xy 234.426291 -409.039848) (xy 234.455208 -409.039314) (xy 234.48246 -409.039756) (xy 234.53641 -409.047514)
			(xy 234.588707 -409.062871) (xy 234.638286 -409.085514) (xy 234.684138 -409.114982) (xy 234.72533 -409.150676)
			(xy 234.761023 -409.191868) (xy 234.79049 -409.237721) (xy 234.813132 -409.2873) (xy 234.828487 -409.339597)
			(xy 234.836244 -409.393548) (xy 234.836244 -409.448052) (xy 234.828487 -409.502003) (xy 234.813132 -409.5543)
			(xy 234.79049 -409.603879) (xy 234.761023 -409.649732) (xy 234.72533 -409.690924) (xy 234.684138 -409.726618)
			(xy 234.638286 -409.756086) (xy 234.588707 -409.778729) (xy 234.53641 -409.794086) (xy 234.48246 -409.801844)
			(xy 234.455208 -409.80233) (xy 234.42629 -409.801832) (xy 234.369117 -409.793103) (xy 234.313916 -409.775843)
			(xy 234.261954 -409.750447) (xy 234.214421 -409.717499) (xy 234.172406 -409.677752) (xy 234.154218 -409.655264)
			(xy 234.144321 -409.643459) (xy 234.118997 -409.62594) (xy 234.089604 -409.616764) (xy 234.058812 -409.616764)
			(xy 234.029419 -409.62594) (xy 234.004095 -409.643459) (xy 233.994198 -409.655264) (xy 233.977445 -409.676047)
			(xy 233.939091 -409.713177) (xy 233.895937 -409.744599) (xy 233.848823 -409.769698) (xy 233.798671 -409.787984)
			(xy 233.74646 -409.799101) (xy 233.693208 -409.802831) (xy 233.639956 -409.799101) (xy 233.587745 -409.787984)
			(xy 233.537593 -409.769698) (xy 233.490479 -409.744599) (xy 233.447325 -409.713177) (xy 233.408971 -409.676047)
			(xy 233.392218 -409.655264) (xy 233.382321 -409.643459) (xy 233.356997 -409.62594) (xy 233.327604 -409.616764)
			(xy 233.296812 -409.616764) (xy 233.267419 -409.62594) (xy 233.242095 -409.643459) (xy 233.232198 -409.655264)
			(xy 233.215445 -409.676047) (xy 233.177091 -409.713177) (xy 233.133937 -409.744599) (xy 233.086823 -409.769698)
			(xy 233.036671 -409.787984) (xy 232.98446 -409.799101) (xy 232.931208 -409.802831) (xy 232.877956 -409.799101)
			(xy 232.825745 -409.787984) (xy 232.775593 -409.769698) (xy 232.728479 -409.744599) (xy 232.685325 -409.713177)
			(xy 232.646971 -409.676047) (xy 232.630218 -409.655264) (xy 232.620321 -409.643459) (xy 232.594997 -409.62594)
			(xy 232.565604 -409.616764) (xy 232.534812 -409.616764) (xy 232.505419 -409.62594) (xy 232.480095 -409.643459)
			(xy 232.470198 -409.655264) (xy 232.453445 -409.676047) (xy 232.415091 -409.713177) (xy 232.371937 -409.744599)
			(xy 232.324823 -409.769698) (xy 232.274671 -409.787984) (xy 232.22246 -409.799101) (xy 232.169208 -409.802831)
			(xy 232.115956 -409.799101) (xy 232.063745 -409.787984) (xy 232.013593 -409.769698) (xy 231.966479 -409.744599)
			(xy 231.923325 -409.713177) (xy 231.884971 -409.676047) (xy 231.868218 -409.655264) (xy 231.858321 -409.643459)
			(xy 231.832997 -409.62594) (xy 231.803604 -409.616764) (xy 231.772812 -409.616764) (xy 231.743419 -409.62594)
			(xy 231.718095 -409.643459) (xy 231.708198 -409.655264) (xy 231.691445 -409.676047) (xy 231.653091 -409.713177)
			(xy 231.609937 -409.744599) (xy 231.562823 -409.769698) (xy 231.512671 -409.787984) (xy 231.46046 -409.799101)
			(xy 231.407208 -409.802831) (xy 231.353956 -409.799101) (xy 231.301745 -409.787984) (xy 231.251593 -409.769698)
			(xy 231.204479 -409.744599) (xy 231.161325 -409.713177) (xy 231.122971 -409.676047) (xy 231.106218 -409.655264)
			(xy 231.096321 -409.643459) (xy 231.070997 -409.62594) (xy 231.041604 -409.616764) (xy 231.010812 -409.616764)
			(xy 230.981419 -409.62594) (xy 230.956095 -409.643459) (xy 230.946198 -409.655264) (xy 230.929445 -409.676047)
			(xy 230.891091 -409.713177) (xy 230.847937 -409.744599) (xy 230.800823 -409.769698) (xy 230.750671 -409.787984)
			(xy 230.69846 -409.799101) (xy 230.645208 -409.802831) (xy 230.591956 -409.799101) (xy 230.539745 -409.787984)
			(xy 230.489593 -409.769698) (xy 230.442479 -409.744599) (xy 230.399325 -409.713177) (xy 230.360971 -409.676047)
			(xy 230.344218 -409.655264) (xy 230.334321 -409.643459) (xy 230.308997 -409.62594) (xy 230.279604 -409.616764)
			(xy 230.248812 -409.616764) (xy 230.219419 -409.62594) (xy 230.194095 -409.643459) (xy 230.184198 -409.655264)
			(xy 230.167445 -409.676047) (xy 230.129091 -409.713177) (xy 230.085937 -409.744599) (xy 230.038823 -409.769698)
			(xy 229.988671 -409.787984) (xy 229.93646 -409.799101) (xy 229.883208 -409.802831) (xy 229.829956 -409.799101)
			(xy 229.777745 -409.787984) (xy 229.727593 -409.769698) (xy 229.680479 -409.744599) (xy 229.637325 -409.713177)
			(xy 229.598971 -409.676047) (xy 229.582218 -409.655264) (xy 229.572321 -409.643459) (xy 229.546997 -409.62594)
			(xy 229.517604 -409.616764) (xy 229.486812 -409.616764) (xy 229.457419 -409.62594) (xy 229.432095 -409.643459)
			(xy 229.422198 -409.655264) (xy 229.403999 -409.677741) (xy 229.361982 -409.717478) (xy 229.314449 -409.750419)
			(xy 229.262489 -409.775809) (xy 229.207293 -409.793066) (xy 229.150124 -409.801795) (xy 229.121208 -409.80233)
			(xy 229.093956 -409.801823) (xy 229.040008 -409.794068) (xy 228.987712 -409.778713) (xy 228.938134 -409.756072)
			(xy 228.892282 -409.726606) (xy 228.851091 -409.690915) (xy 228.815398 -409.649724) (xy 228.785931 -409.603873)
			(xy 228.76329 -409.554296) (xy 228.747934 -409.502) (xy 228.740177 -409.448052) (xy 227.160328 -409.448052)
			(xy 227.160328 -410.49956) (xy 227.159831 -410.525541) (xy 227.151671 -410.57686) (xy 227.135576 -410.626267)
			(xy 227.111944 -410.672546) (xy 227.081358 -410.714554) (xy 227.0633 -410.73324) (xy 226.31146 -411.48508)
			(xy 226.29274 -411.503097) (xy 226.250727 -411.53366) (xy 226.204455 -411.557284) (xy 226.15506 -411.573389)
			(xy 226.103756 -411.58158) (xy 226.07778 -411.582108) (xy 217.06586 -411.582108) (xy 217.039878 -411.581613)
			(xy 216.988559 -411.573454) (xy 216.939149 -411.557361) (xy 216.89287 -411.53373) (xy 216.850861 -411.503144)
			(xy 216.83218 -411.48508) (xy 216.44864 -411.101794) (xy 215.99144 -411.55874) (xy 215.97272 -411.576757)
			(xy 215.930708 -411.607321) (xy 215.884435 -411.630945) (xy 215.835041 -411.647049) (xy 215.783736 -411.655238)
			(xy 215.75776 -411.655768) (xy 206.30642 -411.655768) (xy 206.280439 -411.65527) (xy 206.229121 -411.647107)
			(xy 206.179715 -411.631012) (xy 206.133436 -411.60738) (xy 206.091428 -411.576795) (xy 206.07274 -411.55874)
			(xy 205.55712 -411.043374) (xy 204.99578 -411.60446) (xy 204.977061 -411.622479) (xy 204.935049 -411.653046)
			(xy 204.888777 -411.676674) (xy 204.839382 -411.692784) (xy 204.788077 -411.700978) (xy 204.7621 -411.701488)
			(xy 196.82206 -411.701488) (xy 196.796078 -411.700993) (xy 196.744756 -411.692836) (xy 196.695345 -411.676746)
			(xy 196.649062 -411.653119) (xy 196.607047 -411.622538) (xy 196.58838 -411.60446) (xy 196.055488 -411.071822)
			(xy 195.418456 -411.7086) (xy 195.399735 -411.726616) (xy 195.357721 -411.757176) (xy 195.311449 -411.780798)
			(xy 195.262055 -411.796902) (xy 195.210752 -411.805091) (xy 195.184776 -411.805628) (xy 182.316882 -411.805628)
			(xy 182.010558 -412.111698) (xy 182.38724 -412.48838) (xy 183.016142 -412.48838) (xy 183.020213 -412.432758)
			(xy 183.032339 -412.378321) (xy 183.052262 -412.32623) (xy 183.079558 -412.277595) (xy 183.113644 -412.233452)
			(xy 183.153793 -412.194743) (xy 183.199151 -412.162292) (xy 183.248751 -412.136791) (xy 183.301535 -412.118784)
			(xy 183.356378 -412.108654) (xy 183.412112 -412.106617) (xy 183.467549 -412.112717) (xy 183.521506 -412.126823)
			(xy 183.572835 -412.148635) (xy 183.620441 -412.177689) (xy 183.663309 -412.213364) (xy 183.700526 -412.254901)
			(xy 183.731299 -412.301414) (xy 183.754971 -412.351911) (xy 183.771039 -412.405318) (xy 183.779159 -412.460494)
			(xy 183.779668 -412.48838) (xy 183.779159 -412.516266) (xy 183.771039 -412.571442) (xy 183.754971 -412.624849)
			(xy 183.731299 -412.675346) (xy 183.700526 -412.721859) (xy 183.663309 -412.763396) (xy 183.620441 -412.799071)
			(xy 183.572835 -412.828125) (xy 183.521506 -412.849937) (xy 183.467549 -412.864043) (xy 183.412112 -412.870143)
			(xy 183.356378 -412.868106) (xy 183.301535 -412.857976) (xy 183.248751 -412.839969) (xy 183.199151 -412.814468)
			(xy 183.153793 -412.782017) (xy 183.113644 -412.743308) (xy 183.079558 -412.699165) (xy 183.052262 -412.65053)
			(xy 183.032339 -412.598439) (xy 183.020213 -412.544002) (xy 183.016142 -412.48838) (xy 182.38724 -412.48838)
			(xy 183.57596 -413.6771) (xy 232.537 -413.6771)
		)
		(stroke
			(width 0)
			(type solid)
		)
		(fill yes)
		(layer "In13.Cu")
		(net "AGND_HSC")
	)
	(gr_poly
		(pts
			(xy 21.280374 -183.880506) (xy 21.295504 -183.879956) (xy 21.324437 -183.871092) (xy 21.349501 -183.854136)
			(xy 21.368491 -183.830576) (xy 21.379741 -183.802485) (xy 21.382261 -183.77233) (xy 21.37583 -183.742761)
			(xy 21.361013 -183.716376) (xy 21.350478 -183.7055) (xy 21.332196 -183.687432) (xy 21.300155 -183.647238)
			(xy 21.273796 -183.603109) (xy 21.253596 -183.555842) (xy 21.239921 -183.506293) (xy 21.233017 -183.455357)
			(xy 21.232622 -183.429656) (xy 21.233108 -183.402405) (xy 21.240864 -183.348457) (xy 21.256219 -183.296162)
			(xy 21.278861 -183.246585) (xy 21.308327 -183.200735) (xy 21.344018 -183.159544) (xy 21.385209 -183.123853)
			(xy 21.431059 -183.094387) (xy 21.480636 -183.071745) (xy 21.532931 -183.05639) (xy 21.586879 -183.048634)
			(xy 21.641381 -183.048634) (xy 21.695329 -183.05639) (xy 21.747624 -183.071745) (xy 21.797201 -183.094387)
			(xy 21.843051 -183.123853) (xy 21.884242 -183.159544) (xy 21.919933 -183.200735) (xy 21.944625 -183.239156)
			(xy 22.886922 -183.239156) (xy 22.890993 -183.183534) (xy 22.903119 -183.129097) (xy 22.923042 -183.077006)
			(xy 22.950338 -183.028371) (xy 22.984424 -182.984228) (xy 23.024573 -182.945519) (xy 23.069931 -182.913068)
			(xy 23.119531 -182.887567) (xy 23.172315 -182.86956) (xy 23.227158 -182.85943) (xy 23.282892 -182.857393)
			(xy 23.338329 -182.863493) (xy 23.392286 -182.877599) (xy 23.443615 -182.899411) (xy 23.491221 -182.928465)
			(xy 23.534089 -182.96414) (xy 23.571306 -183.005677) (xy 23.602079 -183.05219) (xy 23.625751 -183.102687)
			(xy 23.641819 -183.156094) (xy 23.649939 -183.21127) (xy 23.650448 -183.239156) (xy 23.649939 -183.267042)
			(xy 23.641819 -183.322218) (xy 23.639824 -183.32885) (xy 35.261795 -183.32885) (xy 35.261795 -183.27435)
			(xy 35.269552 -183.220404) (xy 35.284906 -183.168112) (xy 35.307547 -183.118536) (xy 35.337012 -183.072688)
			(xy 35.372702 -183.031499) (xy 35.413891 -182.995809) (xy 35.45974 -182.966345) (xy 35.509315 -182.943705)
			(xy 35.561608 -182.928351) (xy 35.615554 -182.920595) (xy 35.642804 -182.920132) (xy 35.670175 -182.920588)
			(xy 35.724355 -182.928407) (xy 35.776858 -182.943898) (xy 35.826605 -182.966742) (xy 35.872571 -182.996469)
			(xy 35.893502 -183.014112) (xy 35.90483 -183.023348) (xy 35.931387 -183.035524) (xy 35.960304 -183.039697)
			(xy 35.989221 -183.035524) (xy 36.015778 -183.023348) (xy 36.027106 -183.014112) (xy 36.048027 -182.996459)
			(xy 36.094002 -182.966748) (xy 36.143753 -182.943915) (xy 36.196256 -182.928427) (xy 36.250434 -182.920604)
			(xy 36.277804 -182.920132) (xy 36.305058 -182.920538) (xy 36.359011 -182.928296) (xy 36.411311 -182.943653)
			(xy 36.460893 -182.966297) (xy 36.506747 -182.995766) (xy 36.547941 -183.031462) (xy 36.583636 -183.072656)
			(xy 36.613105 -183.118511) (xy 36.635748 -183.168093) (xy 36.651105 -183.220393) (xy 36.658862 -183.274346)
			(xy 36.658862 -183.32885) (xy 40.544995 -183.32885) (xy 40.544995 -183.27435) (xy 40.552752 -183.220404)
			(xy 40.568106 -183.168112) (xy 40.590747 -183.118536) (xy 40.620212 -183.072688) (xy 40.655902 -183.031499)
			(xy 40.697091 -182.995809) (xy 40.74294 -182.966345) (xy 40.792515 -182.943705) (xy 40.844808 -182.928351)
			(xy 40.898754 -182.920595) (xy 40.926004 -182.920132) (xy 40.953375 -182.920588) (xy 41.007555 -182.928407)
			(xy 41.060058 -182.943898) (xy 41.109805 -182.966742) (xy 41.155771 -182.996469) (xy 41.176702 -183.014112)
			(xy 41.18803 -183.023348) (xy 41.214587 -183.035524) (xy 41.243504 -183.039697) (xy 41.272421 -183.035524)
			(xy 41.298978 -183.023348) (xy 41.310306 -183.014112) (xy 41.331227 -182.996459) (xy 41.377202 -182.966748)
			(xy 41.426953 -182.943915) (xy 41.479456 -182.928427) (xy 41.533634 -182.920604) (xy 41.561004 -182.920132)
			(xy 41.588258 -182.920538) (xy 41.642211 -182.928296) (xy 41.694511 -182.943653) (xy 41.744093 -182.966297)
			(xy 41.789947 -182.995766) (xy 41.831141 -183.031462) (xy 41.866836 -183.072656) (xy 41.896305 -183.118511)
			(xy 41.918948 -183.168093) (xy 41.934305 -183.220393) (xy 41.942062 -183.274346) (xy 41.942062 -183.328854)
			(xy 41.934305 -183.382807) (xy 41.918948 -183.435107) (xy 41.896305 -183.484689) (xy 41.866836 -183.530544)
			(xy 41.831141 -183.571738) (xy 41.789947 -183.607434) (xy 41.744093 -183.636903) (xy 41.694511 -183.659547)
			(xy 41.642211 -183.674904) (xy 41.588258 -183.682662) (xy 41.561004 -183.683148) (xy 41.533633 -183.682692)
			(xy 41.479453 -183.674874) (xy 41.42695 -183.659383) (xy 41.377203 -183.636539) (xy 41.331237 -183.606811)
			(xy 41.310306 -183.589168) (xy 41.298978 -183.579932) (xy 41.272421 -183.567756) (xy 41.243504 -183.563583)
			(xy 41.214587 -183.567756) (xy 41.18803 -183.579932) (xy 41.176702 -183.589168) (xy 41.155776 -183.606815)
			(xy 41.109802 -183.636526) (xy 41.060053 -183.659361) (xy 41.007551 -183.674851) (xy 40.953374 -183.682676)
			(xy 40.926004 -183.683148) (xy 40.898754 -183.682605) (xy 40.844808 -183.674849) (xy 40.792515 -183.659495)
			(xy 40.74294 -183.636855) (xy 40.697091 -183.607391) (xy 40.655902 -183.571701) (xy 40.620212 -183.530512)
			(xy 40.590747 -183.484664) (xy 40.568106 -183.435088) (xy 40.552752 -183.382796) (xy 40.544995 -183.32885)
			(xy 36.658862 -183.32885) (xy 36.658862 -183.328854) (xy 36.651105 -183.382807) (xy 36.635748 -183.435107)
			(xy 36.613105 -183.484689) (xy 36.583636 -183.530544) (xy 36.547941 -183.571738) (xy 36.506747 -183.607434)
			(xy 36.460893 -183.636903) (xy 36.411311 -183.659547) (xy 36.359011 -183.674904) (xy 36.305058 -183.682662)
			(xy 36.277804 -183.683148) (xy 36.250433 -183.682692) (xy 36.196253 -183.674874) (xy 36.14375 -183.659383)
			(xy 36.094003 -183.636539) (xy 36.048037 -183.606811) (xy 36.027106 -183.589168) (xy 36.015778 -183.579932)
			(xy 35.989221 -183.567756) (xy 35.960304 -183.563583) (xy 35.931387 -183.567756) (xy 35.90483 -183.579932)
			(xy 35.893502 -183.589168) (xy 35.872576 -183.606815) (xy 35.826602 -183.636526) (xy 35.776853 -183.659361)
			(xy 35.724351 -183.674851) (xy 35.670174 -183.682676) (xy 35.642804 -183.683148) (xy 35.615554 -183.682605)
			(xy 35.561608 -183.674849) (xy 35.509315 -183.659495) (xy 35.45974 -183.636855) (xy 35.413891 -183.607391)
			(xy 35.372702 -183.571701) (xy 35.337012 -183.530512) (xy 35.307547 -183.484664) (xy 35.284906 -183.435088)
			(xy 35.269552 -183.382796) (xy 35.261795 -183.32885) (xy 23.639824 -183.32885) (xy 23.625751 -183.375625)
			(xy 23.602079 -183.426122) (xy 23.571306 -183.472635) (xy 23.534089 -183.514172) (xy 23.491221 -183.549847)
			(xy 23.443615 -183.578901) (xy 23.392286 -183.600713) (xy 23.338329 -183.614819) (xy 23.282892 -183.620919)
			(xy 23.227158 -183.618882) (xy 23.172315 -183.608752) (xy 23.119531 -183.590745) (xy 23.069931 -183.565244)
			(xy 23.024573 -183.532793) (xy 22.984424 -183.494084) (xy 22.950338 -183.449941) (xy 22.923042 -183.401306)
			(xy 22.903119 -183.349215) (xy 22.890993 -183.294778) (xy 22.886922 -183.239156) (xy 21.944625 -183.239156)
			(xy 21.949399 -183.246585) (xy 21.972041 -183.296162) (xy 21.987396 -183.348457) (xy 21.995152 -183.402405)
			(xy 21.995638 -183.429656) (xy 21.995222 -183.455357) (xy 21.98833 -183.506296) (xy 21.974665 -183.555849)
			(xy 21.954473 -183.60312) (xy 21.928121 -183.647254) (xy 21.896085 -183.687452) (xy 21.877782 -183.7055)
			(xy 21.867237 -183.716352) (xy 21.852462 -183.742741) (xy 21.846062 -183.772299) (xy 21.848597 -183.802435)
			(xy 21.859844 -183.830509) (xy 21.878819 -183.854059) (xy 21.903857 -183.871022) (xy 21.932765 -183.879909)
			(xy 21.947886 -183.880506) (xy 57.26049 -183.880506) (xy 57.768998 -183.371998) (xy 57.77842 -183.361931)
			(xy 57.79199 -183.337941) (xy 57.798653 -183.311197) (xy 57.797923 -183.283645) (xy 57.789855 -183.25729)
			(xy 57.775034 -183.234052) (xy 57.754541 -183.215622) (xy 57.729867 -183.20334) (xy 57.71642 -183.200294)
			(xy 57.689291 -183.196176) (xy 57.636514 -183.181165) (xy 57.586432 -183.158746) (xy 57.54008 -183.129382)
			(xy 57.498415 -183.093677) (xy 57.462297 -183.05237) (xy 57.432471 -183.006313) (xy 57.409554 -182.956458)
			(xy 57.394019 -182.903832) (xy 57.386185 -182.849524) (xy 57.385712 -182.822088) (xy 57.386176 -182.794836)
			(xy 57.393935 -182.740888) (xy 57.409292 -182.688592) (xy 57.431935 -182.639015) (xy 57.461404 -182.593165)
			(xy 57.497098 -182.551975) (xy 57.538291 -182.516285) (xy 57.584143 -182.48682) (xy 57.633722 -182.464181)
			(xy 57.686019 -182.448828) (xy 57.739968 -182.441074) (xy 57.76722 -182.44058) (xy 57.794649 -182.441064)
			(xy 57.84894 -182.448934) (xy 57.901545 -182.464495) (xy 57.951381 -182.487426) (xy 57.997421 -182.517255)
			(xy 58.038717 -182.553368) (xy 58.074417 -182.59502) (xy 58.103788 -182.641354) (xy 58.126223 -182.691415)
			(xy 58.141261 -182.744172) (xy 58.145426 -182.771288) (xy 58.148489 -182.784728) (xy 58.160763 -182.809398)
			(xy 58.179187 -182.829888) (xy 58.20242 -182.844704) (xy 58.228768 -182.852768) (xy 58.256314 -182.853492)
			(xy 58.28305 -182.846824) (xy 58.307028 -182.833249) (xy 58.31713 -182.823866) (xy 60.407296 -180.733446)
			(xy 60.407296 -171.39031) (xy 60.464446 -171.333414) (xy 60.464446 -162.523678) (xy 60.430918 -162.511486)
			(xy 60.405445 -162.501741) (xy 60.357567 -162.475624) (xy 60.314231 -162.442512) (xy 60.27645 -162.40318)
			(xy 60.245108 -162.358548) (xy 60.220937 -162.309659) (xy 60.204503 -162.257656) (xy 60.19619 -162.203755)
			(xy 60.196192 -162.149218) (xy 60.204509 -162.095318) (xy 60.220947 -162.043316) (xy 60.245122 -161.994429)
			(xy 60.276467 -161.949799) (xy 60.314251 -161.91047) (xy 60.35759 -161.877361) (xy 60.405469 -161.851248)
			(xy 60.430918 -161.841434) (xy 60.464446 -161.829242) (xy 60.464446 -160.575498) (xy 60.430918 -160.563306)
			(xy 60.405441 -160.553564) (xy 60.357555 -160.527451) (xy 60.314213 -160.494339) (xy 60.276429 -160.455004)
			(xy 60.245086 -160.410366) (xy 60.220919 -160.36147) (xy 60.204492 -160.309459) (xy 60.196191 -160.255552)
			(xy 60.195714 -160.22828) (xy 60.196288 -160.199251) (xy 60.205704 -160.141962) (xy 60.224285 -160.086957)
			(xy 60.251537 -160.035693) (xy 60.286741 -159.989526) (xy 60.307474 -159.9692) (xy 60.316373 -159.959516)
			(xy 60.329351 -159.936652) (xy 60.33606 -159.911231) (xy 60.336057 -159.88494) (xy 60.32934 -159.859522)
			(xy 60.316356 -159.836661) (xy 60.307474 -159.82696) (xy 60.286749 -159.806626) (xy 60.251537 -159.760467)
			(xy 60.224282 -159.709205) (xy 60.205707 -159.654199) (xy 60.196305 -159.596909) (xy 60.195714 -159.56788)
			(xy 60.195812 -159.555137) (xy 60.197595 -159.529713) (xy 60.19927 -159.51708) (xy 60.203705 -159.489909)
			(xy 60.219851 -159.437277) (xy 60.243903 -159.387756) (xy 60.275287 -159.342526) (xy 60.313258 -159.302664)
			(xy 60.35691 -159.269119) (xy 60.405204 -159.242689) (xy 60.430918 -159.232854) (xy 60.464446 -159.220662)
			(xy 60.464446 -153.887678) (xy 60.430918 -153.875486) (xy 60.405445 -153.865741) (xy 60.357567 -153.839624)
			(xy 60.314231 -153.806512) (xy 60.27645 -153.76718) (xy 60.245108 -153.722548) (xy 60.220937 -153.673659)
			(xy 60.204503 -153.621656) (xy 60.19619 -153.567755) (xy 60.196192 -153.513218) (xy 60.204509 -153.459318)
			(xy 60.220947 -153.407316) (xy 60.245122 -153.358429) (xy 60.276467 -153.313799) (xy 60.314251 -153.27447)
			(xy 60.35759 -153.241361) (xy 60.405469 -153.215248) (xy 60.430918 -153.205434) (xy 60.464446 -153.193242)
			(xy 60.464446 -151.939498) (xy 60.430918 -151.927306) (xy 60.405441 -151.917564) (xy 60.357555 -151.891451)
			(xy 60.314213 -151.858339) (xy 60.276429 -151.819004) (xy 60.245086 -151.774366) (xy 60.220919 -151.72547)
			(xy 60.204492 -151.673459) (xy 60.196191 -151.619552) (xy 60.195714 -151.59228) (xy 60.196288 -151.563251)
			(xy 60.205704 -151.505962) (xy 60.224285 -151.450957) (xy 60.251537 -151.399693) (xy 60.286741 -151.353526)
			(xy 60.307474 -151.3332) (xy 60.316373 -151.323516) (xy 60.329351 -151.300652) (xy 60.33606 -151.275231)
			(xy 60.336057 -151.24894) (xy 60.32934 -151.223522) (xy 60.316356 -151.200661) (xy 60.307474 -151.19096)
			(xy 60.286749 -151.170626) (xy 60.251537 -151.124467) (xy 60.224282 -151.073205) (xy 60.205707 -151.018199)
			(xy 60.196305 -150.960909) (xy 60.195714 -150.93188) (xy 60.195812 -150.919137) (xy 60.197595 -150.893713)
			(xy 60.19927 -150.88108) (xy 60.203705 -150.853909) (xy 60.219851 -150.801277) (xy 60.243903 -150.751756)
			(xy 60.275287 -150.706526) (xy 60.313258 -150.666664) (xy 60.35691 -150.633119) (xy 60.405204 -150.606689)
			(xy 60.430918 -150.596854) (xy 60.464446 -150.584662) (xy 60.464446 -145.251678) (xy 60.430918 -145.239486)
			(xy 60.405445 -145.229741) (xy 60.357567 -145.203624) (xy 60.314231 -145.170512) (xy 60.27645 -145.13118)
			(xy 60.245108 -145.086548) (xy 60.220937 -145.037659) (xy 60.204503 -144.985656) (xy 60.19619 -144.931755)
			(xy 60.196192 -144.877218) (xy 60.204509 -144.823318) (xy 60.220947 -144.771316) (xy 60.245122 -144.722429)
			(xy 60.276467 -144.677799) (xy 60.314251 -144.63847) (xy 60.35759 -144.605361) (xy 60.405469 -144.579248)
			(xy 60.430918 -144.569434) (xy 60.464446 -144.557242) (xy 60.464446 -139.05865) (xy 46.332902 -124.92736)
			(xy 44.965366 -124.92736) (xy 43.302428 -126.590298) (xy 43.302428 -127.619506) (xy 46.656496 -127.619506)
			(xy 46.660567 -127.563884) (xy 46.672693 -127.509447) (xy 46.692616 -127.457356) (xy 46.719912 -127.408721)
			(xy 46.753998 -127.364578) (xy 46.794147 -127.325869) (xy 46.839505 -127.293418) (xy 46.889105 -127.267917)
			(xy 46.941889 -127.24991) (xy 46.996732 -127.23978) (xy 47.052466 -127.237743) (xy 47.107903 -127.243843)
			(xy 47.16186 -127.257949) (xy 47.213189 -127.279761) (xy 47.260795 -127.308815) (xy 47.303663 -127.34449)
			(xy 47.34088 -127.386027) (xy 47.371653 -127.43254) (xy 47.395325 -127.483037) (xy 47.411393 -127.536444)
			(xy 47.419513 -127.59162) (xy 47.420022 -127.619506) (xy 47.419513 -127.647392) (xy 47.411393 -127.702568)
			(xy 47.395325 -127.755975) (xy 47.371653 -127.806472) (xy 47.34088 -127.852985) (xy 47.303663 -127.894522)
			(xy 47.260795 -127.930197) (xy 47.213189 -127.959251) (xy 47.16186 -127.981063) (xy 47.107903 -127.995169)
			(xy 47.052466 -128.001269) (xy 46.996732 -127.999232) (xy 46.941889 -127.989102) (xy 46.889105 -127.971095)
			(xy 46.839505 -127.945594) (xy 46.794147 -127.913143) (xy 46.753998 -127.874434) (xy 46.719912 -127.830291)
			(xy 46.692616 -127.781656) (xy 46.672693 -127.729565) (xy 46.660567 -127.675128) (xy 46.656496 -127.619506)
			(xy 43.302428 -127.619506) (xy 43.302428 -131.313428) (xy 43.301871 -131.342402) (xy 43.292766 -131.399632)
			(xy 43.274817 -131.454731) (xy 43.248465 -131.506342) (xy 43.214362 -131.553193) (xy 43.194224 -131.574032)
			(xy 40.668956 -134.0993) (xy 40.648106 -134.119424) (xy 40.601255 -134.153523) (xy 40.549646 -134.179871)
			(xy 40.49455 -134.197819) (xy 40.437324 -134.206925) (xy 40.408352 -134.207504) (xy 38.547802 -134.207504)
			(xy 38.541706 -134.209028) (xy 38.519145 -134.214261) (xy 38.47317 -134.219865) (xy 38.450012 -134.220204)
			(xy 38.422759 -134.219741) (xy 38.368807 -134.211986) (xy 38.316508 -134.196631) (xy 38.266927 -134.17399)
			(xy 38.221073 -134.144522) (xy 38.17988 -134.108829) (xy 38.144185 -134.067636) (xy 38.114716 -134.021783)
			(xy 38.092073 -133.972203) (xy 38.076717 -133.919905) (xy 38.068959 -133.865953) (xy 38.068959 -133.811447)
			(xy 38.076717 -133.757495) (xy 38.092073 -133.705197) (xy 38.114716 -133.655617) (xy 38.144185 -133.609764)
			(xy 38.17988 -133.568571) (xy 38.221073 -133.532878) (xy 38.266927 -133.50341) (xy 38.316508 -133.480769)
			(xy 38.368807 -133.465414) (xy 38.422759 -133.457659) (xy 38.450012 -133.457188) (xy 38.47317 -133.457529)
			(xy 38.519144 -133.463134) (xy 38.541706 -133.468364) (xy 38.547802 -133.469888) (xy 40.255698 -133.469888)
			(xy 42.564812 -131.160774) (xy 42.564812 -126.437644) (xy 42.565372 -126.408671) (xy 42.574481 -126.351445)
			(xy 42.592435 -126.296349) (xy 42.618791 -126.244743) (xy 42.652899 -126.197898) (xy 42.673016 -126.17704)
			(xy 44.267628 -124.582174) (xy 44.274323 -124.574743) (xy 44.281913 -124.556259) (xy 44.28186 -124.536278)
			(xy 44.274174 -124.517834) (xy 44.260021 -124.503729) (xy 44.241551 -124.496105) (xy 44.23156 -124.49556)
			(xy 44.16933 -124.49556) (xy 42.001694 -126.663196) (xy 41.992085 -126.67461) (xy 41.979338 -126.701571)
			(xy 41.974918 -126.731064) (xy 41.979202 -126.760577) (xy 41.991824 -126.787596) (xy 42.01171 -126.80982)
			(xy 42.037166 -126.825356) (xy 42.051478 -126.829566) (xy 42.078309 -126.837128) (xy 42.129596 -126.858964)
			(xy 42.17716 -126.888031) (xy 42.219988 -126.923711) (xy 42.257167 -126.965244) (xy 42.287906 -127.011745)
			(xy 42.311552 -127.062224) (xy 42.327599 -127.115607) (xy 42.335707 -127.170757) (xy 42.336212 -127.198628)
			(xy 42.335724 -127.225878) (xy 42.327965 -127.279823) (xy 42.312607 -127.332115) (xy 42.289964 -127.381689)
			(xy 42.260497 -127.427536) (xy 42.224806 -127.468723) (xy 42.183616 -127.504412) (xy 42.137767 -127.533876)
			(xy 42.088192 -127.556515) (xy 42.035899 -127.57187) (xy 41.981954 -127.579626) (xy 41.954704 -127.580136)
			(xy 41.926833 -127.579629) (xy 41.871685 -127.571518) (xy 41.818304 -127.555469) (xy 41.767826 -127.531823)
			(xy 41.721327 -127.501084) (xy 41.679795 -127.463905) (xy 41.644115 -127.421079) (xy 41.615048 -127.373516)
			(xy 41.59321 -127.322231) (xy 41.585642 -127.295402) (xy 41.581372 -127.281112) (xy 41.565835 -127.255672)
			(xy 41.543619 -127.235796) (xy 41.516613 -127.223175) (xy 41.487114 -127.218882) (xy 41.45763 -127.223282)
			(xy 41.430671 -127.236002) (xy 41.419272 -127.245618) (xy 41.36517 -127.29972) (xy 41.330372 -127.334264)
			(xy 41.330372 -127.69469) (xy 41.331896 -127.705866) (xy 41.332658 -127.708406) (xy 41.337632 -127.730359)
			(xy 41.342985 -127.775053) (xy 41.343326 -127.79756) (xy 41.343326 -127.798322) (xy 41.34284 -127.825573)
			(xy 41.335084 -127.879521) (xy 41.319729 -127.931816) (xy 41.297087 -127.981393) (xy 41.267621 -128.027243)
			(xy 41.23193 -128.068434) (xy 41.190739 -128.104125) (xy 41.144889 -128.133591) (xy 41.095312 -128.156233)
			(xy 41.043017 -128.171588) (xy 40.989069 -128.179344) (xy 40.934567 -128.179344) (xy 40.880619 -128.171588)
			(xy 40.828324 -128.156233) (xy 40.778747 -128.133591) (xy 40.732897 -128.104125) (xy 40.691706 -128.068434)
			(xy 40.656015 -128.027243) (xy 40.626549 -127.981393) (xy 40.603907 -127.931816) (xy 40.588552 -127.879521)
			(xy 40.580796 -127.825573) (xy 40.58031 -127.798322) (xy 40.580693 -127.775031) (xy 40.586429 -127.728801)
			(xy 40.59174 -127.70612) (xy 40.593264 -127.700024) (xy 40.593264 -127.18161) (xy 40.593802 -127.152646)
			(xy 40.602863 -127.095432) (xy 40.620762 -127.04034) (xy 40.647061 -126.988726) (xy 40.68111 -126.941863)
			(xy 40.701214 -126.921006) (xy 43.384978 -124.236988) (xy 43.395168 -124.226007) (xy 43.409239 -124.199576)
			(xy 43.415043 -124.170201) (xy 43.412081 -124.140405) (xy 43.400608 -124.112748) (xy 43.381609 -124.089605)
			(xy 43.356715 -124.072965) (xy 43.328067 -124.064256) (xy 43.313096 -124.06376) (xy 41.012364 -124.06376)
			(xy 39.778178 -125.297946) (xy 41.053256 -125.297946) (xy 41.057329 -125.242287) (xy 41.069464 -125.187814)
			(xy 41.0894 -125.135688) (xy 41.116714 -125.08702) (xy 41.150822 -125.042848) (xy 41.190999 -125.004113)
			(xy 41.236387 -124.971641) (xy 41.286019 -124.946123) (xy 41.338839 -124.928104) (xy 41.393718 -124.917967)
			(xy 41.449489 -124.915929) (xy 41.504963 -124.922032) (xy 41.558956 -124.936148) (xy 41.610319 -124.957975)
			(xy 41.657957 -124.987048) (xy 41.700853 -125.022747) (xy 41.738095 -125.064311) (xy 41.768889 -125.110855)
			(xy 41.792577 -125.161386) (xy 41.808655 -125.214828) (xy 41.816781 -125.270042) (xy 41.81729 -125.297946)
			(xy 41.816781 -125.32585) (xy 41.808655 -125.381064) (xy 41.792577 -125.434506) (xy 41.768889 -125.485037)
			(xy 41.738095 -125.531581) (xy 41.700853 -125.573145) (xy 41.657957 -125.608844) (xy 41.610319 -125.637917)
			(xy 41.558956 -125.659744) (xy 41.504963 -125.67386) (xy 41.449489 -125.679963) (xy 41.393718 -125.677925)
			(xy 41.338839 -125.667788) (xy 41.286019 -125.649769) (xy 41.236387 -125.624251) (xy 41.190999 -125.591779)
			(xy 41.150822 -125.553044) (xy 41.116714 -125.508872) (xy 41.0894 -125.460204) (xy 41.069464 -125.408078)
			(xy 41.057329 -125.353605) (xy 41.053256 -125.297946) (xy 39.778178 -125.297946) (xy 39.05758 -126.018544)
			(xy 39.055548 -126.021846) (xy 39.04071 -126.045874) (xy 39.005066 -126.089673) (xy 38.963354 -126.127739)
			(xy 38.916486 -126.15924) (xy 38.865486 -126.183488) (xy 38.811469 -126.199953) (xy 38.755615 -126.208275)
			(xy 38.72738 -126.20879) (xy 38.699784 -126.208302) (xy 38.645168 -126.200349) (xy 38.592267 -126.184614)
			(xy 38.542184 -126.161424) (xy 38.495963 -126.131262) (xy 38.454569 -126.094757) (xy 38.418863 -126.052671)
			(xy 38.389592 -126.005881) (xy 38.367364 -125.955363) (xy 38.359588 -125.928882) (xy 38.354809 -125.916325)
			(xy 38.339708 -125.894115) (xy 38.319335 -125.876613) (xy 38.295102 -125.865033) (xy 38.268687 -125.860176)
			(xy 38.241919 -125.862379) (xy 38.216653 -125.871489) (xy 38.20541 -125.878844) (xy 38.181285 -125.894961)
			(xy 38.12919 -125.920495) (xy 38.073833 -125.937855) (xy 38.016486 -125.946642) (xy 37.987478 -125.94717)
			(xy 37.960231 -125.946682) (xy 37.906291 -125.938924) (xy 37.854004 -125.923569) (xy 37.804434 -125.900928)
			(xy 37.758591 -125.871465) (xy 37.717408 -125.835777) (xy 37.681722 -125.794591) (xy 37.652261 -125.748746)
			(xy 37.629624 -125.699176) (xy 37.614271 -125.646888) (xy 37.606516 -125.592947) (xy 37.606516 -125.538452)
			(xy 37.614271 -125.484512) (xy 37.629624 -125.432224) (xy 37.652261 -125.382654) (xy 37.681722 -125.336809)
			(xy 37.717408 -125.295623) (xy 37.758591 -125.259935) (xy 37.804434 -125.230472) (xy 37.854004 -125.207831)
			(xy 37.906291 -125.192476) (xy 37.960231 -125.184718) (xy 37.987478 -125.184154) (xy 38.015071 -125.184647)
			(xy 38.069679 -125.192606) (xy 38.122571 -125.208347) (xy 38.172645 -125.231543) (xy 38.218856 -125.261708)
			(xy 38.260241 -125.298215) (xy 38.295936 -125.340302) (xy 38.325197 -125.387091) (xy 38.347414 -125.437606)
			(xy 38.35527 -125.464062) (xy 38.360053 -125.476618) (xy 38.375158 -125.498828) (xy 38.395533 -125.51633)
			(xy 38.419766 -125.527913) (xy 38.446182 -125.532777) (xy 38.472952 -125.530583) (xy 38.498224 -125.521484)
			(xy 38.509448 -125.5141) (xy 38.511988 -125.512322) (xy 38.522402 -125.505464) (xy 38.530784 -125.500384)
			(xy 38.536118 -125.497082) (xy 40.599106 -123.434348) (xy 40.619955 -123.41422) (xy 40.666803 -123.380112)
			(xy 40.718411 -123.353755) (xy 40.773508 -123.335799) (xy 40.830736 -123.326685) (xy 40.85971 -123.326144)
			(xy 44.48683 -123.326144) (xy 44.501813 -123.325623) (xy 44.530494 -123.316945) (xy 44.555421 -123.300316)
			(xy 44.574448 -123.277167) (xy 44.585937 -123.249492) (xy 44.588899 -123.219674) (xy 44.583077 -123.19028)
			(xy 44.568975 -123.163841) (xy 44.558712 -123.152916) (xy 43.87977 -122.473974) (xy 25.159716 -122.473974)
			(xy 24.433324 -123.200414) (xy 29.125416 -123.200414) (xy 29.129487 -123.144792) (xy 29.141613 -123.090355)
			(xy 29.161536 -123.038264) (xy 29.188832 -122.989629) (xy 29.222918 -122.945486) (xy 29.263067 -122.906777)
			(xy 29.308425 -122.874326) (xy 29.358025 -122.848825) (xy 29.410809 -122.830818) (xy 29.465652 -122.820688)
			(xy 29.521386 -122.818651) (xy 29.576823 -122.824751) (xy 29.63078 -122.838857) (xy 29.682109 -122.860669)
			(xy 29.729715 -122.889723) (xy 29.772583 -122.925398) (xy 29.8098 -122.966935) (xy 29.840573 -123.013448)
			(xy 29.864245 -123.063945) (xy 29.880313 -123.117352) (xy 29.888433 -123.172528) (xy 29.888942 -123.200414)
			(xy 29.888433 -123.2283) (xy 29.880313 -123.283476) (xy 29.864245 -123.336883) (xy 29.840573 -123.38738)
			(xy 29.8098 -123.433893) (xy 29.772583 -123.47543) (xy 29.729715 -123.511105) (xy 29.682109 -123.540159)
			(xy 29.63078 -123.561971) (xy 29.576823 -123.576077) (xy 29.521386 -123.582177) (xy 29.465652 -123.58014)
			(xy 29.410809 -123.57001) (xy 29.358025 -123.552003) (xy 29.308425 -123.526502) (xy 29.263067 -123.494051)
			(xy 29.222918 -123.455342) (xy 29.188832 -123.411199) (xy 29.161536 -123.362564) (xy 29.141613 -123.310473)
			(xy 29.129487 -123.256036) (xy 29.125416 -123.200414) (xy 24.433324 -123.200414) (xy 23.730807 -123.902978)
			(xy 26.902408 -123.902978) (xy 26.906479 -123.847356) (xy 26.918605 -123.792919) (xy 26.938528 -123.740828)
			(xy 26.965824 -123.692193) (xy 26.99991 -123.64805) (xy 27.040059 -123.609341) (xy 27.085417 -123.57689)
			(xy 27.135017 -123.551389) (xy 27.187801 -123.533382) (xy 27.242644 -123.523252) (xy 27.298378 -123.521215)
			(xy 27.353815 -123.527315) (xy 27.407772 -123.541421) (xy 27.459101 -123.563233) (xy 27.506707 -123.592287)
			(xy 27.549575 -123.627962) (xy 27.552247 -123.630944) (xy 31.385762 -123.630944) (xy 31.389833 -123.575322)
			(xy 31.401959 -123.520885) (xy 31.421882 -123.468794) (xy 31.449178 -123.420159) (xy 31.483264 -123.376016)
			(xy 31.523413 -123.337307) (xy 31.568771 -123.304856) (xy 31.618371 -123.279355) (xy 31.671155 -123.261348)
			(xy 31.725998 -123.251218) (xy 31.781732 -123.249181) (xy 31.837169 -123.255281) (xy 31.891126 -123.269387)
			(xy 31.942455 -123.291199) (xy 31.990061 -123.320253) (xy 32.032929 -123.355928) (xy 32.070146 -123.397465)
			(xy 32.100919 -123.443978) (xy 32.124591 -123.494475) (xy 32.140659 -123.547882) (xy 32.148779 -123.603058)
			(xy 32.149288 -123.630944) (xy 32.148779 -123.65883) (xy 32.140659 -123.714006) (xy 32.124591 -123.767413)
			(xy 32.100919 -123.81791) (xy 32.070146 -123.864423) (xy 32.032929 -123.90596) (xy 32.031934 -123.906788)
			(xy 32.966912 -123.906788) (xy 32.970983 -123.851166) (xy 32.983109 -123.796729) (xy 33.003032 -123.744638)
			(xy 33.030328 -123.696003) (xy 33.064414 -123.65186) (xy 33.104563 -123.613151) (xy 33.149921 -123.5807)
			(xy 33.199521 -123.555199) (xy 33.252305 -123.537192) (xy 33.307148 -123.527062) (xy 33.362882 -123.525025)
			(xy 33.418319 -123.531125) (xy 33.472276 -123.545231) (xy 33.523605 -123.567043) (xy 33.571211 -123.596097)
			(xy 33.614079 -123.631772) (xy 33.651296 -123.673309) (xy 33.682069 -123.719822) (xy 33.705741 -123.770319)
			(xy 33.721809 -123.823726) (xy 33.729929 -123.878902) (xy 33.730118 -123.889262) (xy 33.909506 -123.889262)
			(xy 33.913577 -123.83364) (xy 33.925703 -123.779203) (xy 33.945626 -123.727112) (xy 33.972922 -123.678477)
			(xy 34.007008 -123.634334) (xy 34.047157 -123.595625) (xy 34.092515 -123.563174) (xy 34.142115 -123.537673)
			(xy 34.194899 -123.519666) (xy 34.249742 -123.509536) (xy 34.305476 -123.507499) (xy 34.360913 -123.513599)
			(xy 34.41487 -123.527705) (xy 34.466199 -123.549517) (xy 34.513805 -123.578571) (xy 34.556673 -123.614246)
			(xy 34.59389 -123.655783) (xy 34.624663 -123.702296) (xy 34.648335 -123.752793) (xy 34.664403 -123.8062)
			(xy 34.672523 -123.861376) (xy 34.673032 -123.889262) (xy 34.672523 -123.917148) (xy 34.664403 -123.972324)
			(xy 34.648335 -124.025731) (xy 34.624911 -124.075698) (xy 37.74643 -124.075698) (xy 37.750503 -124.020039)
			(xy 37.762638 -123.965566) (xy 37.782574 -123.91344) (xy 37.809888 -123.864772) (xy 37.843996 -123.8206)
			(xy 37.884173 -123.781865) (xy 37.929561 -123.749393) (xy 37.979193 -123.723875) (xy 38.032013 -123.705856)
			(xy 38.086892 -123.695719) (xy 38.142663 -123.693681) (xy 38.198137 -123.699784) (xy 38.25213 -123.7139)
			(xy 38.303493 -123.735727) (xy 38.351131 -123.7648) (xy 38.394027 -123.800499) (xy 38.431269 -123.842063)
			(xy 38.462063 -123.888607) (xy 38.485751 -123.939138) (xy 38.501829 -123.99258) (xy 38.509955 -124.047794)
			(xy 38.510464 -124.075698) (xy 38.509955 -124.103602) (xy 38.501829 -124.158816) (xy 38.485751 -124.212258)
			(xy 38.462063 -124.262789) (xy 38.431269 -124.309333) (xy 38.394027 -124.350897) (xy 38.351131 -124.386596)
			(xy 38.303493 -124.415669) (xy 38.25213 -124.437496) (xy 38.198137 -124.451612) (xy 38.142663 -124.457715)
			(xy 38.086892 -124.455677) (xy 38.032013 -124.44554) (xy 37.979193 -124.427521) (xy 37.929561 -124.402003)
			(xy 37.884173 -124.369531) (xy 37.843996 -124.330796) (xy 37.809888 -124.286624) (xy 37.782574 -124.237956)
			(xy 37.762638 -124.18583) (xy 37.750503 -124.131357) (xy 37.74643 -124.075698) (xy 34.624911 -124.075698)
			(xy 34.624663 -124.076228) (xy 34.59389 -124.122741) (xy 34.556673 -124.164278) (xy 34.513805 -124.199953)
			(xy 34.466199 -124.229007) (xy 34.41487 -124.250819) (xy 34.360913 -124.264925) (xy 34.305476 -124.271025)
			(xy 34.249742 -124.268988) (xy 34.194899 -124.258858) (xy 34.142115 -124.240851) (xy 34.092515 -124.21535)
			(xy 34.047157 -124.182899) (xy 34.007008 -124.14419) (xy 33.972922 -124.100047) (xy 33.945626 -124.051412)
			(xy 33.925703 -123.999321) (xy 33.913577 -123.944884) (xy 33.909506 -123.889262) (xy 33.730118 -123.889262)
			(xy 33.730438 -123.906788) (xy 33.729929 -123.934674) (xy 33.721809 -123.98985) (xy 33.705741 -124.043257)
			(xy 33.682069 -124.093754) (xy 33.651296 -124.140267) (xy 33.614079 -124.181804) (xy 33.571211 -124.217479)
			(xy 33.523605 -124.246533) (xy 33.472276 -124.268345) (xy 33.418319 -124.282451) (xy 33.362882 -124.288551)
			(xy 33.307148 -124.286514) (xy 33.252305 -124.276384) (xy 33.199521 -124.258377) (xy 33.149921 -124.232876)
			(xy 33.104563 -124.200425) (xy 33.064414 -124.161716) (xy 33.030328 -124.117573) (xy 33.003032 -124.068938)
			(xy 32.983109 -124.016847) (xy 32.970983 -123.96241) (xy 32.966912 -123.906788) (xy 32.031934 -123.906788)
			(xy 31.990061 -123.941635) (xy 31.942455 -123.970689) (xy 31.891126 -123.992501) (xy 31.837169 -124.006607)
			(xy 31.781732 -124.012707) (xy 31.725998 -124.01067) (xy 31.671155 -124.00054) (xy 31.618371 -123.982533)
			(xy 31.568771 -123.957032) (xy 31.523413 -123.924581) (xy 31.483264 -123.885872) (xy 31.449178 -123.841729)
			(xy 31.421882 -123.793094) (xy 31.401959 -123.741003) (xy 31.389833 -123.686566) (xy 31.385762 -123.630944)
			(xy 27.552247 -123.630944) (xy 27.586792 -123.669499) (xy 27.617565 -123.716012) (xy 27.641237 -123.766509)
			(xy 27.657305 -123.819916) (xy 27.665425 -123.875092) (xy 27.665934 -123.902978) (xy 27.665425 -123.930864)
			(xy 27.657305 -123.98604) (xy 27.641237 -124.039447) (xy 27.617565 -124.089944) (xy 27.586792 -124.136457)
			(xy 27.549575 -124.177994) (xy 27.506707 -124.213669) (xy 27.459101 -124.242723) (xy 27.407772 -124.264535)
			(xy 27.353815 -124.278641) (xy 27.298378 -124.284741) (xy 27.242644 -124.282704) (xy 27.187801 -124.272574)
			(xy 27.135017 -124.254567) (xy 27.085417 -124.229066) (xy 27.040059 -124.196615) (xy 26.99991 -124.157906)
			(xy 26.965824 -124.113763) (xy 26.938528 -124.065128) (xy 26.918605 -124.013037) (xy 26.906479 -123.9586)
			(xy 26.902408 -123.902978) (xy 23.730807 -123.902978) (xy 22.924919 -124.70892) (xy 26.256232 -124.70892)
			(xy 26.260303 -124.653298) (xy 26.272429 -124.598861) (xy 26.292352 -124.54677) (xy 26.319648 -124.498135)
			(xy 26.353734 -124.453992) (xy 26.393883 -124.415283) (xy 26.439241 -124.382832) (xy 26.488841 -124.357331)
			(xy 26.541625 -124.339324) (xy 26.596468 -124.329194) (xy 26.652202 -124.327157) (xy 26.707639 -124.333257)
			(xy 26.761596 -124.347363) (xy 26.812925 -124.369175) (xy 26.860531 -124.398229) (xy 26.903399 -124.433904)
			(xy 26.940616 -124.475441) (xy 26.971389 -124.521954) (xy 26.995061 -124.572451) (xy 27.011129 -124.625858)
			(xy 27.019249 -124.681034) (xy 27.019758 -124.70892) (xy 27.019249 -124.736806) (xy 27.011129 -124.791982)
			(xy 26.995061 -124.845389) (xy 26.971389 -124.895886) (xy 26.952414 -124.924566) (xy 31.371284 -124.924566)
			(xy 31.375355 -124.868944) (xy 31.387481 -124.814507) (xy 31.407404 -124.762416) (xy 31.4347 -124.713781)
			(xy 31.468786 -124.669638) (xy 31.508935 -124.630929) (xy 31.554293 -124.598478) (xy 31.603893 -124.572977)
			(xy 31.656677 -124.55497) (xy 31.71152 -124.54484) (xy 31.767254 -124.542803) (xy 31.822691 -124.548903)
			(xy 31.876648 -124.563009) (xy 31.927977 -124.584821) (xy 31.975583 -124.613875) (xy 32.018451 -124.64955)
			(xy 32.055668 -124.691087) (xy 32.086441 -124.7376) (xy 32.110113 -124.788097) (xy 32.126181 -124.841504)
			(xy 32.134301 -124.89668) (xy 32.13481 -124.924566) (xy 32.134301 -124.952452) (xy 32.126181 -125.007628)
			(xy 32.110113 -125.061035) (xy 32.086441 -125.111532) (xy 32.055668 -125.158045) (xy 32.018451 -125.199582)
			(xy 31.975583 -125.235257) (xy 31.927977 -125.264311) (xy 31.876648 -125.286123) (xy 31.822691 -125.300229)
			(xy 31.767254 -125.306329) (xy 31.71152 -125.304292) (xy 31.656677 -125.294162) (xy 31.603893 -125.276155)
			(xy 31.554293 -125.250654) (xy 31.508935 -125.218203) (xy 31.468786 -125.179494) (xy 31.4347 -125.135351)
			(xy 31.407404 -125.086716) (xy 31.387481 -125.034625) (xy 31.375355 -124.980188) (xy 31.371284 -124.924566)
			(xy 26.952414 -124.924566) (xy 26.940616 -124.942399) (xy 26.903399 -124.983936) (xy 26.860531 -125.019611)
			(xy 26.812925 -125.048665) (xy 26.761596 -125.070477) (xy 26.707639 -125.084583) (xy 26.652202 -125.090683)
			(xy 26.596468 -125.088646) (xy 26.541625 -125.078516) (xy 26.488841 -125.060509) (xy 26.439241 -125.035008)
			(xy 26.393883 -125.002557) (xy 26.353734 -124.963848) (xy 26.319648 -124.919705) (xy 26.292352 -124.87107)
			(xy 26.272429 -124.818979) (xy 26.260303 -124.764542) (xy 26.256232 -124.70892) (xy 22.924919 -124.70892)
			(xy 21.679641 -125.954282) (xy 31.145478 -125.954282) (xy 31.149549 -125.89866) (xy 31.161675 -125.844223)
			(xy 31.181598 -125.792132) (xy 31.208894 -125.743497) (xy 31.24298 -125.699354) (xy 31.283129 -125.660645)
			(xy 31.328487 -125.628194) (xy 31.378087 -125.602693) (xy 31.430871 -125.584686) (xy 31.485714 -125.574556)
			(xy 31.541448 -125.572519) (xy 31.596885 -125.578619) (xy 31.650842 -125.592725) (xy 31.702171 -125.614537)
			(xy 31.749777 -125.643591) (xy 31.792645 -125.679266) (xy 31.829862 -125.720803) (xy 31.860635 -125.767316)
			(xy 31.884307 -125.817813) (xy 31.900375 -125.87122) (xy 31.908495 -125.926396) (xy 31.909004 -125.954282)
			(xy 31.908495 -125.982168) (xy 31.900375 -126.037344) (xy 31.893881 -126.05893) (xy 33.07918 -126.05893)
			(xy 33.083251 -126.003308) (xy 33.095377 -125.948871) (xy 33.1153 -125.89678) (xy 33.142596 -125.848145)
			(xy 33.176682 -125.804002) (xy 33.216831 -125.765293) (xy 33.262189 -125.732842) (xy 33.311789 -125.707341)
			(xy 33.364573 -125.689334) (xy 33.419416 -125.679204) (xy 33.47515 -125.677167) (xy 33.530587 -125.683267)
			(xy 33.584544 -125.697373) (xy 33.635873 -125.719185) (xy 33.683479 -125.748239) (xy 33.726347 -125.783914)
			(xy 33.763564 -125.825451) (xy 33.794337 -125.871964) (xy 33.818009 -125.922461) (xy 33.834077 -125.975868)
			(xy 33.842197 -126.031044) (xy 33.842706 -126.05893) (xy 33.842197 -126.086816) (xy 33.834077 -126.141992)
			(xy 33.818009 -126.195399) (xy 33.794337 -126.245896) (xy 33.784437 -126.26086) (xy 34.41141 -126.26086)
			(xy 34.415481 -126.205238) (xy 34.427607 -126.150801) (xy 34.44753 -126.09871) (xy 34.474826 -126.050075)
			(xy 34.508912 -126.005932) (xy 34.549061 -125.967223) (xy 34.594419 -125.934772) (xy 34.644019 -125.909271)
			(xy 34.696803 -125.891264) (xy 34.751646 -125.881134) (xy 34.80738 -125.879097) (xy 34.862817 -125.885197)
			(xy 34.916774 -125.899303) (xy 34.968103 -125.921115) (xy 35.015709 -125.950169) (xy 35.058577 -125.985844)
			(xy 35.095794 -126.027381) (xy 35.126567 -126.073894) (xy 35.150239 -126.124391) (xy 35.166307 -126.177798)
			(xy 35.174427 -126.232974) (xy 35.174936 -126.26086) (xy 35.174427 -126.288746) (xy 35.166307 -126.343922)
			(xy 35.150239 -126.397329) (xy 35.126567 -126.447826) (xy 35.095794 -126.494339) (xy 35.058577 -126.535876)
			(xy 35.015709 -126.571551) (xy 34.968103 -126.600605) (xy 34.916774 -126.622417) (xy 34.862817 -126.636523)
			(xy 34.80738 -126.642623) (xy 34.751646 -126.640586) (xy 34.696803 -126.630456) (xy 34.644019 -126.612449)
			(xy 34.594419 -126.586948) (xy 34.549061 -126.554497) (xy 34.508912 -126.515788) (xy 34.474826 -126.471645)
			(xy 34.44753 -126.42301) (xy 34.427607 -126.370919) (xy 34.415481 -126.316482) (xy 34.41141 -126.26086)
			(xy 33.784437 -126.26086) (xy 33.763564 -126.292409) (xy 33.726347 -126.333946) (xy 33.683479 -126.369621)
			(xy 33.635873 -126.398675) (xy 33.584544 -126.420487) (xy 33.530587 -126.434593) (xy 33.47515 -126.440693)
			(xy 33.419416 -126.438656) (xy 33.364573 -126.428526) (xy 33.311789 -126.410519) (xy 33.262189 -126.385018)
			(xy 33.216831 -126.352567) (xy 33.176682 -126.313858) (xy 33.142596 -126.269715) (xy 33.1153 -126.22108)
			(xy 33.095377 -126.168989) (xy 33.083251 -126.114552) (xy 33.07918 -126.05893) (xy 31.893881 -126.05893)
			(xy 31.884307 -126.090751) (xy 31.860635 -126.141248) (xy 31.829862 -126.187761) (xy 31.792645 -126.229298)
			(xy 31.749777 -126.264973) (xy 31.702171 -126.294027) (xy 31.650842 -126.315839) (xy 31.596885 -126.329945)
			(xy 31.541448 -126.336045) (xy 31.485714 -126.334008) (xy 31.430871 -126.323878) (xy 31.378087 -126.305871)
			(xy 31.328487 -126.28037) (xy 31.283129 -126.247919) (xy 31.24298 -126.20921) (xy 31.208894 -126.165067)
			(xy 31.181598 -126.116432) (xy 31.161675 -126.064341) (xy 31.149549 -126.009904) (xy 31.145478 -125.954282)
			(xy 21.679641 -125.954282) (xy 21.361908 -126.272036) (xy 21.361908 -126.560834) (xy 27.732988 -126.560834)
			(xy 27.737059 -126.505212) (xy 27.749185 -126.450775) (xy 27.769108 -126.398684) (xy 27.796404 -126.350049)
			(xy 27.83049 -126.305906) (xy 27.870639 -126.267197) (xy 27.915997 -126.234746) (xy 27.965597 -126.209245)
			(xy 28.018381 -126.191238) (xy 28.073224 -126.181108) (xy 28.128958 -126.179071) (xy 28.184395 -126.185171)
			(xy 28.238352 -126.199277) (xy 28.289681 -126.221089) (xy 28.337287 -126.250143) (xy 28.380155 -126.285818)
			(xy 28.417372 -126.327355) (xy 28.448145 -126.373868) (xy 28.468635 -126.417578) (xy 29.186376 -126.417578)
			(xy 29.190447 -126.361956) (xy 29.202573 -126.307519) (xy 29.222496 -126.255428) (xy 29.249792 -126.206793)
			(xy 29.283878 -126.16265) (xy 29.324027 -126.123941) (xy 29.369385 -126.09149) (xy 29.418985 -126.065989)
			(xy 29.471769 -126.047982) (xy 29.526612 -126.037852) (xy 29.582346 -126.035815) (xy 29.637783 -126.041915)
			(xy 29.69174 -126.056021) (xy 29.743069 -126.077833) (xy 29.790675 -126.106887) (xy 29.833543 -126.142562)
			(xy 29.87076 -126.184099) (xy 29.901533 -126.230612) (xy 29.925205 -126.281109) (xy 29.941273 -126.334516)
			(xy 29.949393 -126.389692) (xy 29.949902 -126.417578) (xy 29.949393 -126.445464) (xy 29.941273 -126.50064)
			(xy 29.925205 -126.554047) (xy 29.901533 -126.604544) (xy 29.87076 -126.651057) (xy 29.833543 -126.692594)
			(xy 29.827359 -126.69774) (xy 35.487862 -126.69774) (xy 35.491933 -126.642118) (xy 35.504059 -126.587681)
			(xy 35.523982 -126.53559) (xy 35.551278 -126.486955) (xy 35.585364 -126.442812) (xy 35.625513 -126.404103)
			(xy 35.670871 -126.371652) (xy 35.720471 -126.346151) (xy 35.773255 -126.328144) (xy 35.828098 -126.318014)
			(xy 35.883832 -126.315977) (xy 35.939269 -126.322077) (xy 35.993226 -126.336183) (xy 36.044555 -126.357995)
			(xy 36.092161 -126.387049) (xy 36.135029 -126.422724) (xy 36.172246 -126.464261) (xy 36.203019 -126.510774)
			(xy 36.226691 -126.561271) (xy 36.242759 -126.614678) (xy 36.250879 -126.669854) (xy 36.251388 -126.69774)
			(xy 36.250879 -126.725626) (xy 36.242759 -126.780802) (xy 36.226691 -126.834209) (xy 36.203019 -126.884706)
			(xy 36.172246 -126.931219) (xy 36.135029 -126.972756) (xy 36.092161 -127.008431) (xy 36.044555 -127.037485)
			(xy 35.993226 -127.059297) (xy 35.939269 -127.073403) (xy 35.883832 -127.079503) (xy 35.828098 -127.077466)
			(xy 35.773255 -127.067336) (xy 35.720471 -127.049329) (xy 35.670871 -127.023828) (xy 35.625513 -126.991377)
			(xy 35.585364 -126.952668) (xy 35.551278 -126.908525) (xy 35.523982 -126.85989) (xy 35.504059 -126.807799)
			(xy 35.491933 -126.753362) (xy 35.487862 -126.69774) (xy 29.827359 -126.69774) (xy 29.790675 -126.728269)
			(xy 29.743069 -126.757323) (xy 29.69174 -126.779135) (xy 29.637783 -126.793241) (xy 29.582346 -126.799341)
			(xy 29.526612 -126.797304) (xy 29.471769 -126.787174) (xy 29.418985 -126.769167) (xy 29.369385 -126.743666)
			(xy 29.324027 -126.711215) (xy 29.283878 -126.672506) (xy 29.249792 -126.628363) (xy 29.222496 -126.579728)
			(xy 29.202573 -126.527637) (xy 29.190447 -126.4732) (xy 29.186376 -126.417578) (xy 28.468635 -126.417578)
			(xy 28.471817 -126.424365) (xy 28.487885 -126.477772) (xy 28.496005 -126.532948) (xy 28.496514 -126.560834)
			(xy 28.496005 -126.58872) (xy 28.487885 -126.643896) (xy 28.471817 -126.697303) (xy 28.448145 -126.7478)
			(xy 28.417372 -126.794313) (xy 28.380155 -126.83585) (xy 28.337287 -126.871525) (xy 28.289681 -126.900579)
			(xy 28.238352 -126.922391) (xy 28.184395 -126.936497) (xy 28.128958 -126.942597) (xy 28.073224 -126.94056)
			(xy 28.018381 -126.93043) (xy 27.965597 -126.912423) (xy 27.915997 -126.886922) (xy 27.870639 -126.854471)
			(xy 27.83049 -126.815762) (xy 27.796404 -126.771619) (xy 27.769108 -126.722984) (xy 27.749185 -126.670893)
			(xy 27.737059 -126.616456) (xy 27.732988 -126.560834) (xy 21.361908 -126.560834) (xy 21.361908 -127.966724)
			(xy 35.514532 -127.966724) (xy 35.518603 -127.911102) (xy 35.530729 -127.856665) (xy 35.550652 -127.804574)
			(xy 35.577948 -127.755939) (xy 35.612034 -127.711796) (xy 35.652183 -127.673087) (xy 35.697541 -127.640636)
			(xy 35.747141 -127.615135) (xy 35.799925 -127.597128) (xy 35.854768 -127.586998) (xy 35.910502 -127.584961)
			(xy 35.965939 -127.591061) (xy 36.019896 -127.605167) (xy 36.071225 -127.626979) (xy 36.118831 -127.656033)
			(xy 36.161699 -127.691708) (xy 36.198916 -127.733245) (xy 36.229689 -127.779758) (xy 36.253361 -127.830255)
			(xy 36.269429 -127.883662) (xy 36.277549 -127.938838) (xy 36.278058 -127.966724) (xy 36.277549 -127.99461)
			(xy 36.269429 -128.049786) (xy 36.253361 -128.103193) (xy 36.229689 -128.15369) (xy 36.198916 -128.200203)
			(xy 36.161699 -128.24174) (xy 36.118831 -128.277415) (xy 36.071225 -128.306469) (xy 36.019896 -128.328281)
			(xy 35.965939 -128.342387) (xy 35.910502 -128.348487) (xy 35.854768 -128.34645) (xy 35.799925 -128.33632)
			(xy 35.747141 -128.318313) (xy 35.697541 -128.292812) (xy 35.652183 -128.260361) (xy 35.612034 -128.221652)
			(xy 35.577948 -128.177509) (xy 35.550652 -128.128874) (xy 35.530729 -128.076783) (xy 35.518603 -128.022346)
			(xy 35.514532 -127.966724) (xy 21.361908 -127.966724) (xy 21.361908 -128.364996) (xy 25.623518 -128.364996)
			(xy 25.627589 -128.309374) (xy 25.639715 -128.254937) (xy 25.659638 -128.202846) (xy 25.686934 -128.154211)
			(xy 25.72102 -128.110068) (xy 25.761169 -128.071359) (xy 25.806527 -128.038908) (xy 25.856127 -128.013407)
			(xy 25.908911 -127.9954) (xy 25.963754 -127.98527) (xy 26.019488 -127.983233) (xy 26.074925 -127.989333)
			(xy 26.128882 -128.003439) (xy 26.180211 -128.025251) (xy 26.227817 -128.054305) (xy 26.270685 -128.08998)
			(xy 26.307902 -128.131517) (xy 26.338675 -128.17803) (xy 26.362347 -128.228527) (xy 26.378415 -128.281934)
			(xy 26.386535 -128.33711) (xy 26.387044 -128.364996) (xy 26.386547 -128.392219) (xy 27.67692 -128.392219)
			(xy 27.676924 -128.337725) (xy 27.684683 -128.283785) (xy 27.70004 -128.231499) (xy 27.722681 -128.18193)
			(xy 27.752145 -128.136088) (xy 27.787834 -128.094906) (xy 27.82902 -128.059221) (xy 27.874865 -128.029761)
			(xy 27.924436 -128.007126) (xy 27.976724 -127.991775) (xy 28.030665 -127.984021) (xy 28.085159 -127.984023)
			(xy 28.139099 -127.99178) (xy 28.191386 -128.007134) (xy 28.240956 -128.029773) (xy 28.286799 -128.059236)
			(xy 28.327983 -128.094923) (xy 28.363669 -128.136107) (xy 28.393131 -128.181951) (xy 28.415769 -128.231521)
			(xy 28.431122 -128.283809) (xy 28.438878 -128.337749) (xy 28.439364 -128.364996) (xy 28.439364 -128.365758)
			(xy 28.43888 -128.392273) (xy 28.431485 -128.444787) (xy 28.424632 -128.470406) (xy 28.421138 -128.484151)
			(xy 28.421089 -128.512502) (xy 28.428848 -128.539771) (xy 28.443814 -128.563849) (xy 28.464831 -128.582877)
			(xy 28.490274 -128.595383) (xy 28.518178 -128.600401) (xy 28.532328 -128.599438) (xy 28.56992 -128.59766)
			(xy 28.59717 -128.598159) (xy 28.651116 -128.605917) (xy 28.703408 -128.621274) (xy 28.752984 -128.643915)
			(xy 28.798832 -128.67338) (xy 28.840022 -128.70907) (xy 28.875713 -128.750258) (xy 28.90518 -128.796106)
			(xy 28.927822 -128.84568) (xy 28.94318 -128.897972) (xy 28.943221 -128.898257) (xy 34.774519 -128.898257)
			(xy 34.774519 -128.843743) (xy 34.782278 -128.789784) (xy 34.797637 -128.737479) (xy 34.820284 -128.687892)
			(xy 34.849757 -128.642033) (xy 34.885458 -128.600835) (xy 34.926658 -128.565138) (xy 34.97252 -128.535668)
			(xy 35.022109 -128.513025) (xy 35.074416 -128.497671) (xy 35.128375 -128.489917) (xy 35.155632 -128.489456)
			(xy 35.183235 -128.48994) (xy 35.237867 -128.497876) (xy 35.290784 -128.513608) (xy 35.340879 -128.536805)
			(xy 35.387106 -128.566983) (xy 35.428498 -128.603512) (xy 35.46419 -128.645628) (xy 35.479228 -128.66878)
			(xy 35.486745 -128.680134) (xy 35.506723 -128.698627) (xy 35.530881 -128.711177) (xy 35.557498 -128.716889)
			(xy 35.584678 -128.715357) (xy 35.610485 -128.70669) (xy 35.633079 -128.691506) (xy 35.642296 -128.68148)
			(xy 35.660491 -128.661057) (xy 35.701733 -128.625128) (xy 35.747683 -128.595458) (xy 35.7974 -128.572655)
			(xy 35.849864 -128.557185) (xy 35.904 -128.549366) (xy 35.931348 -128.548892) (xy 35.9586 -128.549333)
			(xy 36.01255 -128.557096) (xy 36.064845 -128.572457) (xy 36.114423 -128.595104) (xy 36.160273 -128.624575)
			(xy 36.201463 -128.660271) (xy 36.237153 -128.701466) (xy 36.255322 -128.72974) (xy 37.58387 -128.72974)
			(xy 37.587941 -128.674118) (xy 37.600067 -128.619681) (xy 37.61999 -128.56759) (xy 37.647286 -128.518955)
			(xy 37.681372 -128.474812) (xy 37.721521 -128.436103) (xy 37.766879 -128.403652) (xy 37.816479 -128.378151)
			(xy 37.869263 -128.360144) (xy 37.924106 -128.350014) (xy 37.97984 -128.347977) (xy 38.035277 -128.354077)
			(xy 38.089234 -128.368183) (xy 38.140563 -128.389995) (xy 38.188169 -128.419049) (xy 38.231037 -128.454724)
			(xy 38.268254 -128.496261) (xy 38.299027 -128.542774) (xy 38.322699 -128.593271) (xy 38.338767 -128.646678)
			(xy 38.346887 -128.701854) (xy 38.347396 -128.72974) (xy 38.346887 -128.757626) (xy 38.338767 -128.812802)
			(xy 38.322699 -128.866209) (xy 38.299027 -128.916706) (xy 38.268254 -128.963219) (xy 38.231037 -129.004756)
			(xy 38.188169 -129.040431) (xy 38.140563 -129.069485) (xy 38.089234 -129.091297) (xy 38.035277 -129.105403)
			(xy 37.97984 -129.111503) (xy 37.924106 -129.109466) (xy 37.869263 -129.099336) (xy 37.816479 -129.081329)
			(xy 37.766879 -129.055828) (xy 37.721521 -129.023377) (xy 37.681372 -128.984668) (xy 37.647286 -128.940525)
			(xy 37.61999 -128.89189) (xy 37.600067 -128.839799) (xy 37.587941 -128.785362) (xy 37.58387 -128.72974)
			(xy 36.255322 -128.72974) (xy 36.266619 -128.747319) (xy 36.289259 -128.7969) (xy 36.304614 -128.849197)
			(xy 36.31237 -128.903148) (xy 36.312856 -128.9304) (xy 36.312354 -128.959318) (xy 36.303624 -129.01649)
			(xy 36.286364 -129.07169) (xy 36.260969 -129.123652) (xy 36.228022 -129.171186) (xy 36.188277 -129.213201)
			(xy 36.16579 -129.23139) (xy 36.154505 -129.240742) (xy 36.137427 -129.264546) (xy 36.127817 -129.292223)
			(xy 36.12647 -129.321489) (xy 36.133495 -129.349931) (xy 36.148314 -129.375205) (xy 36.158678 -129.385568)
			(xy 36.177306 -129.403687) (xy 36.210021 -129.444059) (xy 36.236951 -129.4885) (xy 36.257598 -129.536186)
			(xy 36.262353 -129.553208) (xy 40.257982 -129.553208) (xy 40.262053 -129.497586) (xy 40.274179 -129.443149)
			(xy 40.294102 -129.391058) (xy 40.321398 -129.342423) (xy 40.355484 -129.29828) (xy 40.395633 -129.259571)
			(xy 40.440991 -129.22712) (xy 40.490591 -129.201619) (xy 40.543375 -129.183612) (xy 40.598218 -129.173482)
			(xy 40.653952 -129.171445) (xy 40.709389 -129.177545) (xy 40.763346 -129.191651) (xy 40.814675 -129.213463)
			(xy 40.862281 -129.242517) (xy 40.905149 -129.278192) (xy 40.942366 -129.319729) (xy 40.973139 -129.366242)
			(xy 40.996811 -129.416739) (xy 41.012879 -129.470146) (xy 41.020999 -129.525322) (xy 41.021508 -129.553208)
			(xy 41.020999 -129.581094) (xy 41.012879 -129.63627) (xy 40.996811 -129.689677) (xy 40.973139 -129.740174)
			(xy 40.942366 -129.786687) (xy 40.905149 -129.828224) (xy 40.862281 -129.863899) (xy 40.814675 -129.892953)
			(xy 40.763346 -129.914765) (xy 40.709389 -129.928871) (xy 40.653952 -129.934971) (xy 40.598218 -129.932934)
			(xy 40.543375 -129.922804) (xy 40.490591 -129.904797) (xy 40.440991 -129.879296) (xy 40.395633 -129.846845)
			(xy 40.355484 -129.808136) (xy 40.321398 -129.763993) (xy 40.294102 -129.715358) (xy 40.274179 -129.663267)
			(xy 40.262053 -129.60883) (xy 40.257982 -129.553208) (xy 36.262353 -129.553208) (xy 36.271578 -129.586234)
			(xy 36.278634 -129.637716) (xy 36.279074 -129.663698) (xy 36.278643 -129.690952) (xy 36.270885 -129.744906)
			(xy 36.255528 -129.797207) (xy 36.232883 -129.846789) (xy 36.203412 -129.892644) (xy 36.167715 -129.933837)
			(xy 36.126518 -129.969531) (xy 36.080661 -129.998998) (xy 36.031077 -130.021639) (xy 35.978775 -130.036992)
			(xy 35.92482 -130.044745) (xy 35.897566 -130.045206) (xy 35.868794 -130.044675) (xy 35.811906 -130.035999)
			(xy 35.784282 -130.027934) (xy 35.770239 -130.023972) (xy 35.741071 -130.023495) (xy 35.712955 -130.031276)
			(xy 35.688183 -130.046681) (xy 35.66877 -130.068456) (xy 35.656298 -130.094827) (xy 35.651782 -130.123647)
			(xy 35.653218 -130.13817) (xy 35.654756 -130.150495) (xy 35.656405 -130.17528) (xy 35.65652 -130.1877)
			(xy 35.656045 -130.214953) (xy 35.648288 -130.268904) (xy 35.632931 -130.321202) (xy 35.610289 -130.370783)
			(xy 35.58082 -130.416636) (xy 35.545126 -130.457829) (xy 35.503933 -130.493523) (xy 35.458079 -130.52299)
			(xy 35.408499 -130.545633) (xy 35.3562 -130.560988) (xy 35.302249 -130.568745) (xy 35.247743 -130.568744)
			(xy 35.193792 -130.560987) (xy 35.141494 -130.54563) (xy 35.091914 -130.522987) (xy 35.046061 -130.493518)
			(xy 35.004868 -130.457823) (xy 34.969175 -130.41663) (xy 34.939708 -130.370776) (xy 34.917066 -130.321195)
			(xy 34.901711 -130.268896) (xy 34.893955 -130.214945) (xy 34.893956 -130.160439) (xy 34.901714 -130.106488)
			(xy 34.917071 -130.05419) (xy 34.939715 -130.00461) (xy 34.969185 -129.958757) (xy 35.00488 -129.917565)
			(xy 35.046073 -129.881873) (xy 35.091928 -129.852406) (xy 35.141509 -129.829764) (xy 35.193807 -129.81441)
			(xy 35.247759 -129.806654) (xy 35.275012 -129.806192) (xy 35.303784 -129.806728) (xy 35.360672 -129.815401)
			(xy 35.388296 -129.823464) (xy 35.402345 -129.827403) (xy 35.431511 -129.827886) (xy 35.459625 -129.820109)
			(xy 35.484397 -129.804708) (xy 35.50381 -129.782936) (xy 35.516281 -129.756567) (xy 35.520797 -129.72775)
			(xy 35.51936 -129.713228) (xy 35.517822 -129.700903) (xy 35.516173 -129.676118) (xy 35.516058 -129.663698)
			(xy 35.516553 -129.63478) (xy 35.525284 -129.577607) (xy 35.542545 -129.522406) (xy 35.567941 -129.470444)
			(xy 35.600889 -129.422911) (xy 35.640636 -129.380897) (xy 35.663124 -129.362708) (xy 35.67441 -129.353358)
			(xy 35.691486 -129.329553) (xy 35.701094 -129.301876) (xy 35.702441 -129.27261) (xy 35.695417 -129.244168)
			(xy 35.680599 -129.218894) (xy 35.670236 -129.20853) (xy 35.65251 -129.191376) (xy 35.62117 -129.153283)
			(xy 35.607752 -129.132584) (xy 35.600137 -129.121302) (xy 35.580177 -129.102818) (xy 35.556041 -129.09027)
			(xy 35.529445 -129.084551) (xy 35.502284 -129.086069) (xy 35.47649 -129.094714) (xy 35.453901 -129.109872)
			(xy 35.444684 -129.119884) (xy 35.426492 -129.14031) (xy 35.38525 -129.176239) (xy 35.339299 -129.20591)
			(xy 35.289582 -129.228714) (xy 35.237117 -129.244183) (xy 35.182981 -129.251999) (xy 35.155632 -129.252472)
			(xy 35.128375 -129.252083) (xy 35.074416 -129.244329) (xy 35.022109 -129.228975) (xy 34.97252 -129.206332)
			(xy 34.926658 -129.176862) (xy 34.885458 -129.141165) (xy 34.849757 -129.099967) (xy 34.820284 -129.054108)
			(xy 34.797637 -129.004521) (xy 34.782278 -128.952216) (xy 34.774519 -128.898257) (xy 28.943221 -128.898257)
			(xy 28.95094 -128.951918) (xy 28.951428 -128.979168) (xy 28.950983 -129.006005) (xy 28.943447 -129.059147)
			(xy 28.928534 -129.110708) (xy 28.906538 -129.159668) (xy 28.877895 -129.20506) (xy 28.843169 -129.245987)
			(xy 28.823412 -129.264156) (xy 28.812991 -129.274041) (xy 28.797685 -129.298332) (xy 28.789743 -129.325924)
			(xy 28.789794 -129.354636) (xy 28.797834 -129.382199) (xy 28.813226 -129.406436) (xy 28.823666 -129.416302)
			(xy 28.843522 -129.434453) (xy 28.878376 -129.475433) (xy 28.907127 -129.520903) (xy 28.929204 -129.569962)
			(xy 28.94417 -129.621636) (xy 28.951729 -129.674899) (xy 28.95219 -129.701798) (xy 28.951704 -129.729049)
			(xy 28.943948 -129.782997) (xy 28.928593 -129.835292) (xy 28.905951 -129.884869) (xy 28.876485 -129.930719)
			(xy 28.840794 -129.97191) (xy 28.799603 -130.007601) (xy 28.753753 -130.037067) (xy 28.704176 -130.059709)
			(xy 28.651881 -130.075064) (xy 28.597933 -130.08282) (xy 28.543431 -130.08282) (xy 28.489483 -130.075064)
			(xy 28.437188 -130.059709) (xy 28.387611 -130.037067) (xy 28.341761 -130.007601) (xy 28.30057 -129.97191)
			(xy 28.264879 -129.930719) (xy 28.235413 -129.884869) (xy 28.212771 -129.835292) (xy 28.197416 -129.782997)
			(xy 28.18966 -129.729049) (xy 28.189174 -129.701798) (xy 28.189663 -129.674963) (xy 28.19719 -129.621822)
			(xy 28.212094 -129.570262) (xy 28.234082 -129.521302) (xy 28.262718 -129.475909) (xy 28.297436 -129.43498)
			(xy 28.31719 -129.41681) (xy 28.327545 -129.406861) (xy 28.342854 -129.382587) (xy 28.350803 -129.355013)
			(xy 28.350764 -129.326315) (xy 28.342741 -129.298762) (xy 28.327366 -129.27453) (xy 28.316936 -129.264664)
			(xy 28.297112 -129.246479) (xy 28.262256 -129.205507) (xy 28.233501 -129.160043) (xy 28.211418 -129.110991)
			(xy 28.196444 -129.059324) (xy 28.188878 -129.006065) (xy 28.188412 -128.979168) (xy 28.188412 -128.978406)
			(xy 28.18891 -128.951891) (xy 28.196296 -128.899378) (xy 28.203144 -128.873758) (xy 28.206593 -128.860001)
			(xy 28.206656 -128.831653) (xy 28.198909 -128.804385) (xy 28.183951 -128.780305) (xy 28.162938 -128.761277)
			(xy 28.137498 -128.748772) (xy 28.109597 -128.743759) (xy 28.095448 -128.744726) (xy 28.057856 -128.746504)
			(xy 28.030609 -128.745975) (xy 27.97667 -128.738213) (xy 27.924384 -128.722855) (xy 27.874816 -128.700212)
			(xy 27.828975 -128.670745) (xy 27.787794 -128.635055) (xy 27.752112 -128.593867) (xy 27.722654 -128.548021)
			(xy 27.70002 -128.498449) (xy 27.684671 -128.44616) (xy 27.67692 -128.392219) (xy 26.386547 -128.392219)
			(xy 26.386535 -128.392882) (xy 26.378415 -128.448058) (xy 26.362347 -128.501465) (xy 26.338675 -128.551962)
			(xy 26.307902 -128.598475) (xy 26.270685 -128.640012) (xy 26.227817 -128.675687) (xy 26.180211 -128.704741)
			(xy 26.128882 -128.726553) (xy 26.074925 -128.740659) (xy 26.019488 -128.746759) (xy 25.963754 -128.744722)
			(xy 25.908911 -128.734592) (xy 25.856127 -128.716585) (xy 25.806527 -128.691084) (xy 25.761169 -128.658633)
			(xy 25.72102 -128.619924) (xy 25.686934 -128.575781) (xy 25.659638 -128.527146) (xy 25.639715 -128.475055)
			(xy 25.627589 -128.420618) (xy 25.623518 -128.364996) (xy 21.361908 -128.364996) (xy 21.361908 -130.991153)
			(xy 24.961279 -130.991153) (xy 24.961279 -130.936647) (xy 24.969037 -130.882696) (xy 24.984394 -130.830398)
			(xy 25.007038 -130.780818) (xy 25.036508 -130.734966) (xy 25.072204 -130.693775) (xy 25.113399 -130.658083)
			(xy 25.159255 -130.628618) (xy 25.208837 -130.605979) (xy 25.261137 -130.590628) (xy 25.315089 -130.582876)
			(xy 25.342342 -130.582416) (xy 25.369076 -130.582883) (xy 25.422021 -130.590342) (xy 25.473405 -130.60512)
			(xy 25.522222 -130.626929) (xy 25.567516 -130.655342) (xy 25.608398 -130.689801) (xy 25.626568 -130.709416)
			(xy 26.975562 -130.709416) (xy 27.000557 -130.710077) (xy 27.049578 -130.719874) (xy 27.095749 -130.73904)
			(xy 27.137296 -130.76684) (xy 27.155394 -130.784092) (xy 27.252168 -130.880866) (xy 27.573222 -130.880866)
			(xy 27.577293 -130.825244) (xy 27.589419 -130.770807) (xy 27.609342 -130.718716) (xy 27.636638 -130.670081)
			(xy 27.670724 -130.625938) (xy 27.710873 -130.587229) (xy 27.756231 -130.554778) (xy 27.805831 -130.529277)
			(xy 27.858615 -130.51127) (xy 27.913458 -130.50114) (xy 27.969192 -130.499103) (xy 28.024629 -130.505203)
			(xy 28.078586 -130.519309) (xy 28.129915 -130.541121) (xy 28.177521 -130.570175) (xy 28.220389 -130.60585)
			(xy 28.257606 -130.647387) (xy 28.288379 -130.6939) (xy 28.312051 -130.744397) (xy 28.317269 -130.76174)
			(xy 37.59454 -130.76174) (xy 37.595112 -130.732636) (xy 37.60397 -130.675106) (xy 37.621457 -130.619587)
			(xy 37.647168 -130.567366) (xy 37.680507 -130.519651) (xy 37.720701 -130.477549) (xy 37.76682 -130.442035)
			(xy 37.817794 -130.413932) (xy 37.872443 -130.393892) (xy 37.900864 -130.387598) (xy 37.914157 -130.384444)
			(xy 37.938548 -130.372167) (xy 37.95881 -130.35386) (xy 37.973489 -130.330834) (xy 37.981534 -130.30474)
			(xy 37.982369 -130.277446) (xy 37.975935 -130.250908) (xy 37.969698 -130.238754) (xy 37.95827 -130.217443)
			(xy 37.940305 -130.172547) (xy 37.92817 -130.125737) (xy 37.922061 -130.077767) (xy 37.921692 -130.053588)
			(xy 37.921692 -130.053334) (xy 37.922178 -130.026083) (xy 37.929934 -129.972135) (xy 37.945289 -129.91984)
			(xy 37.967931 -129.870263) (xy 37.997397 -129.824413) (xy 38.033088 -129.783222) (xy 38.074279 -129.747531)
			(xy 38.120129 -129.718065) (xy 38.169706 -129.695423) (xy 38.222001 -129.680068) (xy 38.275949 -129.672312)
			(xy 38.330451 -129.672312) (xy 38.384399 -129.680068) (xy 38.436694 -129.695423) (xy 38.486271 -129.718065)
			(xy 38.532121 -129.747531) (xy 38.573312 -129.783222) (xy 38.609003 -129.824413) (xy 38.638469 -129.870263)
			(xy 38.661111 -129.91984) (xy 38.676466 -129.972135) (xy 38.684222 -130.026083) (xy 38.684708 -130.053334)
			(xy 38.684075 -130.082435) (xy 38.675221 -130.13996) (xy 38.65774 -130.195476) (xy 38.632037 -130.247695)
			(xy 38.598705 -130.295408) (xy 38.558519 -130.337511) (xy 38.512409 -130.373027) (xy 38.461443 -130.401133)
			(xy 38.406801 -130.421179) (xy 38.378384 -130.427476) (xy 38.365068 -130.430554) (xy 38.340661 -130.442834)
			(xy 38.320388 -130.461152) (xy 38.305705 -130.484193) (xy 38.297664 -130.510306) (xy 38.296843 -130.537616)
			(xy 38.3033 -130.564164) (xy 38.30955 -130.57632) (xy 38.320972 -130.597634) (xy 38.338938 -130.642529)
			(xy 38.351074 -130.689339) (xy 38.357186 -130.737308) (xy 38.357556 -130.761486) (xy 38.357556 -130.76174)
			(xy 38.35718 -130.782822) (xy 38.66718 -130.782822) (xy 38.671251 -130.7272) (xy 38.683377 -130.672763)
			(xy 38.7033 -130.620672) (xy 38.730596 -130.572037) (xy 38.764682 -130.527894) (xy 38.804831 -130.489185)
			(xy 38.850189 -130.456734) (xy 38.899789 -130.431233) (xy 38.952573 -130.413226) (xy 39.007416 -130.403096)
			(xy 39.06315 -130.401059) (xy 39.118587 -130.407159) (xy 39.172544 -130.421265) (xy 39.223873 -130.443077)
			(xy 39.271479 -130.472131) (xy 39.314347 -130.507806) (xy 39.351564 -130.549343) (xy 39.382337 -130.595856)
			(xy 39.406009 -130.646353) (xy 39.422077 -130.69976) (xy 39.430197 -130.754936) (xy 39.430706 -130.782822)
			(xy 39.430197 -130.810708) (xy 39.422077 -130.865884) (xy 39.406009 -130.919291) (xy 39.382337 -130.969788)
			(xy 39.351564 -131.016301) (xy 39.314347 -131.057838) (xy 39.271479 -131.093513) (xy 39.223873 -131.122567)
			(xy 39.172544 -131.144379) (xy 39.118587 -131.158485) (xy 39.06315 -131.164585) (xy 39.007416 -131.162548)
			(xy 38.952573 -131.152418) (xy 38.899789 -131.134411) (xy 38.850189 -131.10891) (xy 38.804831 -131.076459)
			(xy 38.764682 -131.03775) (xy 38.730596 -130.993607) (xy 38.7033 -130.944972) (xy 38.683377 -130.892881)
			(xy 38.671251 -130.838444) (xy 38.66718 -130.782822) (xy 38.35718 -130.782822) (xy 38.35707 -130.788991)
			(xy 38.349314 -130.842939) (xy 38.333959 -130.895234) (xy 38.311317 -130.944811) (xy 38.281851 -130.990661)
			(xy 38.24616 -131.031852) (xy 38.204969 -131.067543) (xy 38.159119 -131.097009) (xy 38.109542 -131.119651)
			(xy 38.057247 -131.135006) (xy 38.003299 -131.142762) (xy 37.948797 -131.142762) (xy 37.894849 -131.135006)
			(xy 37.842554 -131.119651) (xy 37.792977 -131.097009) (xy 37.747127 -131.067543) (xy 37.705936 -131.031852)
			(xy 37.670245 -130.990661) (xy 37.640779 -130.944811) (xy 37.618137 -130.895234) (xy 37.602782 -130.842939)
			(xy 37.595026 -130.788991) (xy 37.59454 -130.76174) (xy 28.317269 -130.76174) (xy 28.328119 -130.797804)
			(xy 28.336239 -130.85298) (xy 28.336748 -130.880866) (xy 28.336239 -130.908752) (xy 28.328119 -130.963928)
			(xy 28.312051 -131.017335) (xy 28.288379 -131.067832) (xy 28.257606 -131.114345) (xy 28.220389 -131.155882)
			(xy 28.192535 -131.179062) (xy 34.962844 -131.179062) (xy 34.966915 -131.12344) (xy 34.979041 -131.069003)
			(xy 34.998964 -131.016912) (xy 35.02626 -130.968277) (xy 35.060346 -130.924134) (xy 35.100495 -130.885425)
			(xy 35.145853 -130.852974) (xy 35.195453 -130.827473) (xy 35.248237 -130.809466) (xy 35.30308 -130.799336)
			(xy 35.358814 -130.797299) (xy 35.414251 -130.803399) (xy 35.468208 -130.817505) (xy 35.519537 -130.839317)
			(xy 35.567143 -130.868371) (xy 35.610011 -130.904046) (xy 35.647228 -130.945583) (xy 35.678001 -130.992096)
			(xy 35.701673 -131.042593) (xy 35.717741 -131.096) (xy 35.725861 -131.151176) (xy 35.72637 -131.179062)
			(xy 35.725861 -131.206948) (xy 35.717741 -131.262124) (xy 35.701673 -131.315531) (xy 35.678001 -131.366028)
			(xy 35.647228 -131.412541) (xy 35.610011 -131.454078) (xy 35.567143 -131.489753) (xy 35.519537 -131.518807)
			(xy 35.468208 -131.540619) (xy 35.414251 -131.554725) (xy 35.358814 -131.560825) (xy 35.30308 -131.558788)
			(xy 35.248237 -131.548658) (xy 35.195453 -131.530651) (xy 35.145853 -131.50515) (xy 35.100495 -131.472699)
			(xy 35.060346 -131.43399) (xy 35.02626 -131.389847) (xy 34.998964 -131.341212) (xy 34.979041 -131.289121)
			(xy 34.966915 -131.234684) (xy 34.962844 -131.179062) (xy 28.192535 -131.179062) (xy 28.177521 -131.191557)
			(xy 28.129915 -131.220611) (xy 28.078586 -131.242423) (xy 28.024629 -131.256529) (xy 27.969192 -131.262629)
			(xy 27.913458 -131.260592) (xy 27.858615 -131.250462) (xy 27.805831 -131.232455) (xy 27.756231 -131.206954)
			(xy 27.710873 -131.174503) (xy 27.670724 -131.135794) (xy 27.636638 -131.091651) (xy 27.609342 -131.043016)
			(xy 27.589419 -130.990925) (xy 27.577293 -130.936488) (xy 27.573222 -130.880866) (xy 27.252168 -130.880866)
			(xy 27.88793 -131.516628) (xy 27.905129 -131.534759) (xy 27.932875 -131.57631) (xy 27.951989 -131.622474)
			(xy 27.961737 -131.671478) (xy 27.962352 -131.69646) (xy 27.962352 -132.049774) (xy 37.591998 -132.049774)
			(xy 37.596069 -131.994152) (xy 37.608195 -131.939715) (xy 37.628118 -131.887624) (xy 37.655414 -131.838989)
			(xy 37.6895 -131.794846) (xy 37.729649 -131.756137) (xy 37.775007 -131.723686) (xy 37.824607 -131.698185)
			(xy 37.877391 -131.680178) (xy 37.932234 -131.670048) (xy 37.987968 -131.668011) (xy 38.043405 -131.674111)
			(xy 38.097362 -131.688217) (xy 38.148691 -131.710029) (xy 38.196297 -131.739083) (xy 38.239165 -131.774758)
			(xy 38.276382 -131.816295) (xy 38.307155 -131.862808) (xy 38.330827 -131.913305) (xy 38.346895 -131.966712)
			(xy 38.355015 -132.021888) (xy 38.355524 -132.049774) (xy 38.355015 -132.07766) (xy 38.346895 -132.132836)
			(xy 38.330827 -132.186243) (xy 38.307155 -132.23674) (xy 38.276382 -132.283253) (xy 38.239165 -132.32479)
			(xy 38.196297 -132.360465) (xy 38.148691 -132.389519) (xy 38.097362 -132.411331) (xy 38.043405 -132.425437)
			(xy 37.987968 -132.431537) (xy 37.932234 -132.4295) (xy 37.877391 -132.41937) (xy 37.824607 -132.401363)
			(xy 37.775007 -132.375862) (xy 37.729649 -132.343411) (xy 37.6895 -132.304702) (xy 37.655414 -132.260559)
			(xy 37.628118 -132.211924) (xy 37.608195 -132.159833) (xy 37.596069 -132.105396) (xy 37.591998 -132.049774)
			(xy 27.962352 -132.049774) (xy 27.962352 -132.532882) (xy 38.89832 -132.532882) (xy 38.902391 -132.47726)
			(xy 38.914517 -132.422823) (xy 38.93444 -132.370732) (xy 38.961736 -132.322097) (xy 38.995822 -132.277954)
			(xy 39.035971 -132.239245) (xy 39.081329 -132.206794) (xy 39.130929 -132.181293) (xy 39.183713 -132.163286)
			(xy 39.238556 -132.153156) (xy 39.29429 -132.151119) (xy 39.349727 -132.157219) (xy 39.403684 -132.171325)
			(xy 39.455013 -132.193137) (xy 39.502619 -132.222191) (xy 39.545487 -132.257866) (xy 39.582704 -132.299403)
			(xy 39.613477 -132.345916) (xy 39.637149 -132.396413) (xy 39.653217 -132.44982) (xy 39.661337 -132.504996)
			(xy 39.661846 -132.532882) (xy 39.661337 -132.560768) (xy 39.653217 -132.615944) (xy 39.637149 -132.669351)
			(xy 39.613477 -132.719848) (xy 39.582704 -132.766361) (xy 39.545487 -132.807898) (xy 39.502619 -132.843573)
			(xy 39.455013 -132.872627) (xy 39.403684 -132.894439) (xy 39.349727 -132.908545) (xy 39.29429 -132.914645)
			(xy 39.238556 -132.912608) (xy 39.183713 -132.902478) (xy 39.130929 -132.884471) (xy 39.081329 -132.85897)
			(xy 39.035971 -132.826519) (xy 38.995822 -132.78781) (xy 38.961736 -132.743667) (xy 38.93444 -132.695032)
			(xy 38.914517 -132.642941) (xy 38.902391 -132.588504) (xy 38.89832 -132.532882) (xy 27.962352 -132.532882)
			(xy 27.962352 -132.61213) (xy 28.42514 -133.074664) (xy 31.211012 -133.074664) (xy 31.236009 -133.075281)
			(xy 31.285033 -133.085089) (xy 31.331204 -133.104268) (xy 31.372749 -133.132082) (xy 31.390844 -133.14934)
			(xy 31.878778 -133.63702) (xy 35.700462 -133.63702) (xy 35.725457 -133.63768) (xy 35.774478 -133.647477)
			(xy 35.820649 -133.666644) (xy 35.862197 -133.694444) (xy 35.880294 -133.711696) (xy 39.226744 -137.058146)
			(xy 39.244005 -137.076237) (xy 39.271817 -137.117782) (xy 39.290989 -137.163955) (xy 39.300786 -137.212981)
			(xy 39.30142 -137.237978) (xy 39.30142 -144.48872) (xy 51.012924 -144.48872) (xy 51.012928 -144.434227)
			(xy 51.020687 -144.380288) (xy 51.036042 -144.328003) (xy 51.058683 -144.278435) (xy 51.088146 -144.232593)
			(xy 51.123834 -144.191411) (xy 51.165019 -144.155727) (xy 51.210863 -144.126267) (xy 51.260433 -144.103631)
			(xy 51.312719 -144.08828) (xy 51.366659 -144.080526) (xy 51.421152 -144.080526) (xy 51.475091 -144.088282)
			(xy 51.527377 -144.103635) (xy 51.576946 -144.126272) (xy 51.62279 -144.155734) (xy 51.663974 -144.191419)
			(xy 51.69966 -144.232602) (xy 51.729122 -144.278444) (xy 51.736434 -144.294455) (xy 53.058229 -144.294455)
			(xy 53.058229 -144.239945) (xy 53.065987 -144.185989) (xy 53.081345 -144.133686) (xy 53.10399 -144.084102)
			(xy 53.133461 -144.038245) (xy 53.169159 -143.997049) (xy 53.210356 -143.961353) (xy 53.256214 -143.931883)
			(xy 53.305799 -143.90924) (xy 53.358102 -143.893884) (xy 53.412059 -143.886128) (xy 53.439314 -143.885666)
			(xy 53.439822 -143.885666) (xy 53.472957 -143.886408) (xy 53.538223 -143.8979) (xy 53.569616 -143.908526)
			(xy 53.583198 -143.913028) (xy 53.611739 -143.914958) (xy 53.639697 -143.908906) (xy 53.664884 -143.895343)
			(xy 53.685327 -143.875334) (xy 53.699426 -143.850443) (xy 53.70322 -143.836644) (xy 53.710286 -143.809161)
			(xy 53.73138 -143.756484) (xy 53.760045 -143.707514) (xy 53.795649 -143.663332) (xy 53.837407 -143.624912)
			(xy 53.884396 -143.593104) (xy 53.93558 -143.568608) (xy 53.989828 -143.551967) (xy 54.045943 -143.543547)
			(xy 54.074314 -143.54302) (xy 54.101567 -143.543451) (xy 54.155517 -143.55121) (xy 54.207814 -143.566567)
			(xy 54.257393 -143.589211) (xy 54.303245 -143.618679) (xy 54.344436 -143.654374) (xy 54.380129 -143.695566)
			(xy 54.409596 -143.74142) (xy 54.432238 -143.790999) (xy 54.447593 -143.843297) (xy 54.45535 -143.897247)
			(xy 54.45535 -143.951753) (xy 54.447593 -144.005703) (xy 54.432238 -144.058001) (xy 54.409596 -144.10758)
			(xy 54.380129 -144.153434) (xy 54.344436 -144.194626) (xy 54.303245 -144.230321) (xy 54.257393 -144.259789)
			(xy 54.207814 -144.282433) (xy 54.155517 -144.29779) (xy 54.101567 -144.305549) (xy 54.074314 -144.306036)
			(xy 54.073806 -144.306036) (xy 54.040672 -144.305286) (xy 53.975406 -144.293799) (xy 53.944012 -144.283176)
			(xy 53.930421 -144.278704) (xy 53.901885 -144.276768) (xy 53.873929 -144.282814) (xy 53.848744 -144.296371)
			(xy 53.828301 -144.316375) (xy 53.814203 -144.341261) (xy 53.810408 -144.355058) (xy 53.803409 -144.38256)
			(xy 53.78231 -144.435241) (xy 53.753638 -144.484215) (xy 53.718025 -144.528399) (xy 53.676259 -144.566818)
			(xy 53.62926 -144.598624) (xy 53.578068 -144.623114) (xy 53.523811 -144.639749) (xy 53.467689 -144.64816)
			(xy 53.439314 -144.648682) (xy 53.412059 -144.648272) (xy 53.358102 -144.640516) (xy 53.305799 -144.62516)
			(xy 53.256214 -144.602517) (xy 53.210356 -144.573047) (xy 53.169159 -144.537351) (xy 53.133461 -144.496155)
			(xy 53.10399 -144.450298) (xy 53.081345 -144.400714) (xy 53.065987 -144.348411) (xy 53.058229 -144.294455)
			(xy 51.736434 -144.294455) (xy 51.751761 -144.328013) (xy 51.767116 -144.380299) (xy 51.774873 -144.434237)
			(xy 51.77536 -144.461484) (xy 51.77493 -144.486875) (xy 51.768173 -144.537207) (xy 51.761898 -144.561814)
			(xy 51.758525 -144.576472) (xy 51.759445 -144.606518) (xy 51.769069 -144.634996) (xy 51.786564 -144.65944)
			(xy 51.810415 -144.677736) (xy 51.838559 -144.688299) (xy 51.868558 -144.690215) (xy 51.88331 -144.68729)
			(xy 51.90484 -144.682535) (xy 51.948639 -144.677442) (xy 51.970686 -144.67713) (xy 51.97094 -144.67713)
			(xy 51.998187 -144.677621) (xy 52.052126 -144.685382) (xy 52.104412 -144.700739) (xy 52.153979 -144.723381)
			(xy 52.199821 -144.752847) (xy 52.241002 -144.788536) (xy 52.276686 -144.829723) (xy 52.306145 -144.875568)
			(xy 52.32878 -144.925139) (xy 52.34413 -144.977427) (xy 52.351883 -145.031367) (xy 52.351881 -145.085861)
			(xy 52.344124 -145.139801) (xy 52.32877 -145.192087) (xy 52.306131 -145.241657) (xy 52.276669 -145.2875)
			(xy 52.240982 -145.328684) (xy 52.199798 -145.36437) (xy 52.153955 -145.393832) (xy 52.104385 -145.416471)
			(xy 52.052099 -145.431824) (xy 51.998159 -145.439581) (xy 51.943665 -145.439583) (xy 51.889725 -145.431829)
			(xy 51.837437 -145.416479) (xy 51.787866 -145.393844) (xy 51.742021 -145.364384) (xy 51.700835 -145.328701)
			(xy 51.665146 -145.287519) (xy 51.63568 -145.241678) (xy 51.613039 -145.19211) (xy 51.597681 -145.139824)
			(xy 51.589921 -145.085885) (xy 51.589432 -145.058638) (xy 51.589867 -145.033247) (xy 51.596621 -144.982916)
			(xy 51.602894 -144.958308) (xy 51.606253 -144.943646) (xy 51.605338 -144.913601) (xy 51.595718 -144.885123)
			(xy 51.578225 -144.860677) (xy 51.554375 -144.842382) (xy 51.526232 -144.83182) (xy 51.496234 -144.829906)
			(xy 51.481482 -144.832832) (xy 51.459952 -144.837589) (xy 51.416153 -144.84268) (xy 51.394106 -144.842992)
			(xy 51.393852 -144.842992) (xy 51.366605 -144.84247) (xy 51.312667 -144.834709) (xy 51.260383 -144.81935)
			(xy 51.210816 -144.796707) (xy 51.164976 -144.767241) (xy 51.123796 -144.731551) (xy 51.088114 -144.690364)
			(xy 51.058657 -144.644518) (xy 51.036024 -144.594947) (xy 51.020675 -144.54266) (xy 51.012924 -144.48872)
			(xy 39.30142 -144.48872) (xy 39.30142 -146.75866) (xy 43.126914 -146.75866) (xy 43.127436 -146.729921)
			(xy 43.136063 -146.673095) (xy 43.153114 -146.618205) (xy 43.178206 -146.566493) (xy 43.210769 -146.51913)
			(xy 43.230038 -146.497802) (xy 43.240134 -146.486238) (xy 43.253567 -146.458655) (xy 43.258189 -146.428324)
			(xy 43.253582 -146.397991) (xy 43.240162 -146.370401) (xy 43.230038 -146.358864) (xy 43.21077 -146.337534)
			(xy 43.178203 -146.290173) (xy 43.15311 -146.238462) (xy 43.136059 -146.183572) (xy 43.127435 -146.126745)
			(xy 43.126914 -146.098006) (xy 43.12738 -146.070636) (xy 43.135197 -146.016457) (xy 43.150686 -145.963953)
			(xy 43.173528 -145.914206) (xy 43.203253 -145.86824) (xy 43.220894 -145.847308) (xy 43.230126 -145.835977)
			(xy 43.242304 -145.80942) (xy 43.246478 -145.780505) (xy 43.242307 -145.751588) (xy 43.23013 -145.725031)
			(xy 43.220894 -145.713704) (xy 43.203242 -145.692782) (xy 43.173533 -145.646806) (xy 43.150699 -145.597056)
			(xy 43.135211 -145.544553) (xy 43.127386 -145.490376) (xy 43.126914 -145.463006) (xy 43.127361 -145.435752)
			(xy 43.135118 -145.3818) (xy 43.150474 -145.3295) (xy 43.173117 -145.279919) (xy 43.202587 -145.234064)
			(xy 43.238282 -145.192871) (xy 43.279477 -145.157177) (xy 43.325333 -145.12771) (xy 43.374915 -145.105068)
			(xy 43.427215 -145.089714) (xy 43.481168 -145.08196) (xy 43.508422 -145.081498) (xy 43.535793 -145.081952)
			(xy 43.589972 -145.089773) (xy 43.642476 -145.105265) (xy 43.692222 -145.128109) (xy 43.738189 -145.157836)
			(xy 43.75912 -145.175478) (xy 43.770448 -145.184714) (xy 43.797005 -145.19689) (xy 43.825922 -145.201063)
			(xy 43.854839 -145.19689) (xy 43.881396 -145.184714) (xy 43.892724 -145.175478) (xy 43.913671 -145.157858)
			(xy 43.95964 -145.128144) (xy 44.009384 -145.105305) (xy 44.061881 -145.089809) (xy 44.116054 -145.081975)
			(xy 44.143422 -145.081498) (xy 44.172161 -145.082009) (xy 44.228989 -145.090635) (xy 44.28388 -145.107688)
			(xy 44.335592 -145.132782) (xy 44.382954 -145.16535) (xy 44.40428 -145.184622) (xy 44.415814 -145.194694)
			(xy 44.44336 -145.208036) (xy 44.473622 -145.212621) (xy 44.503884 -145.208036) (xy 44.53143 -145.194694)
			(xy 44.542964 -145.184622) (xy 44.564291 -145.165352) (xy 44.611654 -145.132787) (xy 44.663365 -145.107696)
			(xy 44.718256 -145.090646) (xy 44.775083 -145.082024) (xy 44.832561 -145.082024) (xy 44.889388 -145.090646)
			(xy 44.944279 -145.107696) (xy 44.99599 -145.132787) (xy 45.043353 -145.165352) (xy 45.06468 -145.184622)
			(xy 45.076214 -145.194694) (xy 45.10376 -145.208036) (xy 45.134022 -145.212621) (xy 45.164284 -145.208036)
			(xy 45.19183 -145.194694) (xy 45.203364 -145.184622) (xy 45.224691 -145.165352) (xy 45.272054 -145.132787)
			(xy 45.323765 -145.107696) (xy 45.378656 -145.090646) (xy 45.435483 -145.082024) (xy 45.492961 -145.082024)
			(xy 45.549788 -145.090646) (xy 45.604679 -145.107696) (xy 45.65639 -145.132787) (xy 45.703753 -145.165352)
			(xy 45.72508 -145.184622) (xy 45.736614 -145.194694) (xy 45.76416 -145.208036) (xy 45.794422 -145.212621)
			(xy 45.824684 -145.208036) (xy 45.85223 -145.194694) (xy 45.863764 -145.184622) (xy 45.885091 -145.165352)
			(xy 45.932454 -145.132787) (xy 45.984165 -145.107696) (xy 46.039056 -145.090646) (xy 46.095883 -145.082024)
			(xy 46.153361 -145.082024) (xy 46.210188 -145.090646) (xy 46.265079 -145.107696) (xy 46.31679 -145.132787)
			(xy 46.364153 -145.165352) (xy 46.38548 -145.184622) (xy 46.397014 -145.194694) (xy 46.42456 -145.208036)
			(xy 46.454822 -145.212621) (xy 46.485084 -145.208036) (xy 46.51263 -145.194694) (xy 46.524164 -145.184622)
			(xy 46.545491 -145.165352) (xy 46.592854 -145.132787) (xy 46.644565 -145.107696) (xy 46.699456 -145.090646)
			(xy 46.756283 -145.082024) (xy 46.813761 -145.082024) (xy 46.870588 -145.090646) (xy 46.925479 -145.107696)
			(xy 46.97719 -145.132787) (xy 47.024553 -145.165352) (xy 47.04588 -145.184622) (xy 47.057414 -145.194694)
			(xy 47.08496 -145.208036) (xy 47.115222 -145.212621) (xy 47.145484 -145.208036) (xy 47.17303 -145.194694)
			(xy 47.184564 -145.184622) (xy 47.20588 -145.165338) (xy 47.253245 -145.132774) (xy 47.30496 -145.107685)
			(xy 47.359853 -145.090637) (xy 47.416682 -145.082017) (xy 47.445422 -145.081498) (xy 47.472674 -145.081957)
			(xy 47.526623 -145.089717) (xy 47.578919 -145.105075) (xy 47.628496 -145.127719) (xy 47.674347 -145.157189)
			(xy 47.715537 -145.192883) (xy 47.751228 -145.234076) (xy 47.780694 -145.279928) (xy 47.803335 -145.329508)
			(xy 47.818689 -145.381804) (xy 47.826445 -145.435754) (xy 47.82693 -145.463006) (xy 47.826467 -145.489242)
			(xy 47.819271 -145.541217) (xy 47.805017 -145.591715) (xy 47.783973 -145.639781) (xy 47.756538 -145.684508)
			(xy 47.723228 -145.725051) (xy 47.704248 -145.743168) (xy 47.696871 -145.750692) (xy 47.688442 -145.769979)
			(xy 47.688444 -145.791029) (xy 47.696876 -145.810315) (xy 47.704248 -145.817844) (xy 47.725584 -145.83918)
			(xy 47.733113 -145.846552) (xy 47.752398 -145.854983) (xy 47.773446 -145.854983) (xy 47.792731 -145.846552)
			(xy 47.80026 -145.83918) (xy 47.818371 -145.820192) (xy 47.858911 -145.786874) (xy 47.903638 -145.759432)
			(xy 47.951706 -145.738384) (xy 48.002206 -145.724128) (xy 48.054185 -145.716934) (xy 48.080422 -145.716498)
			(xy 48.107674 -145.716957) (xy 48.161623 -145.724717) (xy 48.213919 -145.740075) (xy 48.263496 -145.762719)
			(xy 48.309347 -145.792189) (xy 48.350537 -145.827883) (xy 48.386228 -145.869076) (xy 48.400993 -145.892052)
			(xy 49.996289 -145.892052) (xy 49.996289 -145.837548) (xy 50.004047 -145.783598) (xy 50.019404 -145.731301)
			(xy 50.042047 -145.681722) (xy 50.071517 -145.635871) (xy 50.107212 -145.594681) (xy 50.148406 -145.55899)
			(xy 50.194261 -145.529526) (xy 50.243842 -145.506888) (xy 50.296141 -145.491537) (xy 50.350092 -145.483786)
			(xy 50.377344 -145.483326) (xy 50.407031 -145.483911) (xy 50.465689 -145.493102) (xy 50.522215 -145.511271)
			(xy 50.575243 -145.537978) (xy 50.623492 -145.57258) (xy 50.665798 -145.614239) (xy 50.683922 -145.637758)
			(xy 50.692348 -145.648365) (xy 50.713661 -145.665072) (xy 50.738615 -145.675591) (xy 50.765456 -145.679181)
			(xy 50.792297 -145.675591) (xy 50.817251 -145.665072) (xy 50.838564 -145.648365) (xy 50.84699 -145.637758)
			(xy 50.86512 -145.614243) (xy 50.907427 -145.572585) (xy 50.955675 -145.537982) (xy 51.008701 -145.511271)
			(xy 51.065225 -145.493095) (xy 51.123881 -145.483893) (xy 51.153568 -145.483326) (xy 51.180825 -145.483719)
			(xy 51.234784 -145.491473) (xy 51.28709 -145.506827) (xy 51.336679 -145.52947) (xy 51.38254 -145.55894)
			(xy 51.423741 -145.594637) (xy 51.459441 -145.635834) (xy 51.488915 -145.681693) (xy 51.511561 -145.73128)
			(xy 51.52692 -145.783585) (xy 51.534679 -145.837543) (xy 51.534679 -145.892057) (xy 51.52692 -145.946015)
			(xy 51.511561 -145.99832) (xy 51.488915 -146.047907) (xy 51.459441 -146.093766) (xy 51.423741 -146.134963)
			(xy 51.38254 -146.17066) (xy 51.336679 -146.20013) (xy 51.28709 -146.222773) (xy 51.234784 -146.238127)
			(xy 51.180825 -146.245881) (xy 51.153568 -146.246342) (xy 51.123881 -146.24576) (xy 51.065222 -146.23657)
			(xy 51.008695 -146.218402) (xy 50.955667 -146.191694) (xy 50.907418 -146.157091) (xy 50.865114 -146.11543)
			(xy 50.84699 -146.09191) (xy 50.838564 -146.081303) (xy 50.817251 -146.064596) (xy 50.792297 -146.054077)
			(xy 50.765456 -146.050487) (xy 50.738615 -146.054077) (xy 50.713661 -146.064596) (xy 50.692348 -146.081303)
			(xy 50.683922 -146.09191) (xy 50.665776 -146.115412) (xy 50.623474 -146.157073) (xy 50.575229 -146.191678)
			(xy 50.522206 -146.218392) (xy 50.465685 -146.23657) (xy 50.40703 -146.245774) (xy 50.377344 -146.246342)
			(xy 50.350092 -146.245814) (xy 50.296141 -146.238063) (xy 50.243842 -146.222712) (xy 50.194261 -146.200074)
			(xy 50.148406 -146.17061) (xy 50.107212 -146.134919) (xy 50.071517 -146.093729) (xy 50.042047 -146.047878)
			(xy 50.019404 -145.998299) (xy 50.004047 -145.946002) (xy 49.996289 -145.892052) (xy 48.400993 -145.892052)
			(xy 48.415694 -145.914928) (xy 48.438335 -145.964508) (xy 48.453689 -146.016804) (xy 48.461445 -146.070754)
			(xy 48.46193 -146.098006) (xy 48.461402 -146.126745) (xy 48.452779 -146.183571) (xy 48.43573 -146.238462)
			(xy 48.410639 -146.290174) (xy 48.378076 -146.337537) (xy 48.358806 -146.358864) (xy 48.348699 -146.3704)
			(xy 48.335361 -146.398008) (xy 48.330783 -146.428324) (xy 48.335375 -146.458639) (xy 48.348727 -146.48624)
			(xy 48.358806 -146.497802) (xy 48.378048 -146.519154) (xy 48.41062 -146.566508) (xy 48.435719 -146.618213)
			(xy 48.452776 -146.673099) (xy 48.461405 -146.729923) (xy 48.46193 -146.75866) (xy 48.461408 -146.785911)
			(xy 48.453657 -146.839859) (xy 48.438307 -146.892154) (xy 48.415671 -146.941732) (xy 48.386209 -146.987585)
			(xy 48.350521 -147.028777) (xy 48.309334 -147.064472) (xy 48.263487 -147.093941) (xy 48.213912 -147.116585)
			(xy 48.161619 -147.131943) (xy 48.107673 -147.139703) (xy 48.080422 -147.140168) (xy 48.053052 -147.139697)
			(xy 47.998873 -147.131881) (xy 47.946369 -147.116394) (xy 47.896622 -147.093553) (xy 47.850656 -147.063829)
			(xy 47.829724 -147.046188) (xy 47.818396 -147.036952) (xy 47.791839 -147.024776) (xy 47.762922 -147.020603)
			(xy 47.734005 -147.024776) (xy 47.707448 -147.036952) (xy 47.69612 -147.046188) (xy 47.67519 -147.063829)
			(xy 47.629217 -147.093541) (xy 47.579469 -147.116377) (xy 47.526968 -147.131867) (xy 47.472791 -147.139695)
			(xy 47.445422 -147.140168) (xy 47.416685 -147.139613) (xy 47.359859 -147.130995) (xy 47.30497 -147.113951)
			(xy 47.253257 -147.088867) (xy 47.205893 -147.05631) (xy 47.184564 -147.037044) (xy 47.17303 -147.026972)
			(xy 47.145484 -147.01363) (xy 47.115222 -147.009045) (xy 47.08496 -147.01363) (xy 47.057414 -147.026972)
			(xy 47.04588 -147.037044) (xy 47.024553 -147.056314) (xy 46.97719 -147.088879) (xy 46.925479 -147.11397)
			(xy 46.870588 -147.13102) (xy 46.813761 -147.139642) (xy 46.756283 -147.139642) (xy 46.699456 -147.13102)
			(xy 46.644565 -147.11397) (xy 46.592854 -147.088879) (xy 46.545491 -147.056314) (xy 46.524164 -147.037044)
			(xy 46.51263 -147.026972) (xy 46.485084 -147.01363) (xy 46.454822 -147.009045) (xy 46.42456 -147.01363)
			(xy 46.397014 -147.026972) (xy 46.38548 -147.037044) (xy 46.364153 -147.056314) (xy 46.31679 -147.088879)
			(xy 46.265079 -147.11397) (xy 46.210188 -147.13102) (xy 46.153361 -147.139642) (xy 46.095883 -147.139642)
			(xy 46.039056 -147.13102) (xy 45.984165 -147.11397) (xy 45.932454 -147.088879) (xy 45.885091 -147.056314)
			(xy 45.863764 -147.037044) (xy 45.85223 -147.026972) (xy 45.824684 -147.01363) (xy 45.794422 -147.009045)
			(xy 45.76416 -147.01363) (xy 45.736614 -147.026972) (xy 45.72508 -147.037044) (xy 45.703753 -147.056314)
			(xy 45.65639 -147.088879) (xy 45.604679 -147.11397) (xy 45.549788 -147.13102) (xy 45.492961 -147.139642)
			(xy 45.435483 -147.139642) (xy 45.378656 -147.13102) (xy 45.323765 -147.11397) (xy 45.272054 -147.088879)
			(xy 45.224691 -147.056314) (xy 45.203364 -147.037044) (xy 45.19183 -147.026972) (xy 45.164284 -147.01363)
			(xy 45.134022 -147.009045) (xy 45.10376 -147.01363) (xy 45.076214 -147.026972) (xy 45.06468 -147.037044)
			(xy 45.043353 -147.056314) (xy 44.99599 -147.088879) (xy 44.944279 -147.11397) (xy 44.889388 -147.13102)
			(xy 44.832561 -147.139642) (xy 44.775083 -147.139642) (xy 44.718256 -147.13102) (xy 44.663365 -147.11397)
			(xy 44.611654 -147.088879) (xy 44.564291 -147.056314) (xy 44.542964 -147.037044) (xy 44.53143 -147.026972)
			(xy 44.503884 -147.01363) (xy 44.473622 -147.009045) (xy 44.44336 -147.01363) (xy 44.415814 -147.026972)
			(xy 44.40428 -147.037044) (xy 44.382941 -147.056301) (xy 44.335583 -147.08887) (xy 44.283874 -147.113965)
			(xy 44.228986 -147.131019) (xy 44.17216 -147.139645) (xy 44.143422 -147.140168) (xy 44.116052 -147.139697)
			(xy 44.061873 -147.131881) (xy 44.009369 -147.116394) (xy 43.959622 -147.093553) (xy 43.913656 -147.063829)
			(xy 43.892724 -147.046188) (xy 43.881396 -147.036952) (xy 43.854839 -147.024776) (xy 43.825922 -147.020603)
			(xy 43.797005 -147.024776) (xy 43.770448 -147.036952) (xy 43.75912 -147.046188) (xy 43.73819 -147.063829)
			(xy 43.692217 -147.093541) (xy 43.642469 -147.116377) (xy 43.589968 -147.131867) (xy 43.535791 -147.139695)
			(xy 43.508422 -147.140168) (xy 43.481168 -147.139724) (xy 43.427214 -147.131969) (xy 43.374914 -147.116614)
			(xy 43.325331 -147.093971) (xy 43.279476 -147.064502) (xy 43.238282 -147.028806) (xy 43.202588 -146.98761)
			(xy 43.17312 -146.941753) (xy 43.15048 -146.89217) (xy 43.135127 -146.839868) (xy 43.127375 -146.785914)
			(xy 43.126914 -146.75866) (xy 39.30142 -146.75866) (xy 39.30142 -147.60702) (xy 48.240696 -147.60702)
			(xy 49.146968 -146.701002) (xy 49.165087 -146.68379) (xy 49.206642 -146.656044) (xy 49.252809 -146.636933)
			(xy 49.301817 -146.627191) (xy 49.3268 -146.62658) (xy 50.68189 -146.62658) (xy 50.700052 -146.606945)
			(xy 50.740922 -146.572443) (xy 50.78621 -146.543985) (xy 50.835026 -146.522129) (xy 50.886416 -146.507302)
			(xy 50.939373 -146.499795) (xy 50.966116 -146.499326) (xy 50.993371 -146.49974) (xy 51.047325 -146.5075)
			(xy 51.099626 -146.52286) (xy 51.149209 -146.545507) (xy 51.195063 -146.57498) (xy 51.236257 -146.610679)
			(xy 51.27195 -146.651877) (xy 51.301417 -146.697735) (xy 51.324058 -146.747321) (xy 51.339411 -146.799624)
			(xy 51.347163 -146.853579) (xy 51.347624 -146.880834) (xy 51.347624 -146.881088) (xy 51.347224 -146.906292)
			(xy 51.340585 -146.95626) (xy 51.327409 -147.004914) (xy 51.307926 -147.051404) (xy 51.295554 -147.073366)
			(xy 51.28846 -147.086303) (xy 51.281434 -147.114951) (xy 51.282888 -147.144412) (xy 51.292701 -147.172229)
			(xy 51.310054 -147.196081) (xy 51.3335 -147.21398) (xy 51.347116 -147.21967) (xy 51.373892 -147.230366)
			(xy 51.424134 -147.258654) (xy 51.469543 -147.294184) (xy 51.509085 -147.336146) (xy 51.541859 -147.383583)
			(xy 51.567117 -147.435414) (xy 51.584283 -147.490457) (xy 51.592966 -147.547457) (xy 51.593496 -147.576286)
			(xy 51.593032 -147.603539) (xy 51.585276 -147.657491) (xy 51.569921 -147.709789) (xy 51.54728 -147.75937)
			(xy 51.517812 -147.805224) (xy 51.482118 -147.846417) (xy 51.440925 -147.882111) (xy 51.395072 -147.911579)
			(xy 51.345491 -147.934221) (xy 51.293193 -147.949576) (xy 51.239241 -147.957331) (xy 51.211988 -147.957794)
			(xy 51.211734 -147.957794) (xy 51.181895 -147.957227) (xy 51.122949 -147.947906) (xy 51.094386 -147.939252)
			(xy 51.080457 -147.935302) (xy 51.051539 -147.934385) (xy 51.02353 -147.941636) (xy 50.998691 -147.956471)
			(xy 50.979026 -147.977693) (xy 50.966122 -148.003589) (xy 50.963068 -148.017738) (xy 50.957919 -148.043816)
			(xy 50.941346 -148.09432) (xy 50.917921 -148.142034) (xy 50.888096 -148.186032) (xy 50.852451 -148.225463)
			(xy 50.811676 -148.259561) (xy 50.76656 -148.287667) (xy 50.717979 -148.309236) (xy 50.666873 -148.323849)
			(xy 50.614233 -148.331225) (xy 50.587656 -148.331682) (xy 50.560405 -148.331245) (xy 50.506458 -148.323483)
			(xy 50.454165 -148.308123) (xy 50.40459 -148.285478) (xy 50.358742 -148.256008) (xy 50.317554 -148.220314)
			(xy 50.281865 -148.179123) (xy 50.252401 -148.133271) (xy 50.229762 -148.083693) (xy 50.214408 -148.031399)
			(xy 50.206652 -147.977451) (xy 50.206652 -147.922949) (xy 50.214408 -147.869001) (xy 50.229762 -147.816707)
			(xy 50.252401 -147.767129) (xy 50.281865 -147.721277) (xy 50.317554 -147.680086) (xy 50.358742 -147.644392)
			(xy 50.40459 -147.614922) (xy 50.454165 -147.592277) (xy 50.506458 -147.576917) (xy 50.560405 -147.569155)
			(xy 50.587656 -147.568666) (xy 50.58791 -147.568666) (xy 50.617749 -147.569247) (xy 50.676695 -147.578559)
			(xy 50.705258 -147.587208) (xy 50.719167 -147.591239) (xy 50.748099 -147.592148) (xy 50.776118 -147.584883)
			(xy 50.800963 -147.570032) (xy 50.820629 -147.548792) (xy 50.833527 -147.522879) (xy 50.836576 -147.508722)
			(xy 50.843165 -147.475884) (xy 50.866284 -147.413031) (xy 50.88255 -147.383754) (xy 50.889618 -147.370804)
			(xy 50.896647 -147.342161) (xy 50.895197 -147.312704) (xy 50.885389 -147.28489) (xy 50.868042 -147.261039)
			(xy 50.844601 -147.243141) (xy 50.830988 -147.23745) (xy 50.80273 -147.226094) (xy 50.749937 -147.195739)
			(xy 50.702636 -147.157383) (xy 50.68189 -147.135088) (xy 49.43221 -147.135088) (xy 48.525938 -148.04136)
			(xy 48.507856 -148.058632) (xy 48.466307 -148.086441) (xy 48.420132 -148.10561) (xy 48.371104 -148.115403)
			(xy 48.346106 -148.116036) (xy 39.30142 -148.116036) (xy 39.30142 -150.44547) (xy 50.99304 -150.44547)
			(xy 50.993427 -150.418214) (xy 51.001189 -150.364258) (xy 51.016552 -150.311956) (xy 51.039201 -150.262372)
			(xy 51.068677 -150.216517) (xy 51.104379 -150.175323) (xy 51.145579 -150.13963) (xy 51.191441 -150.110164)
			(xy 51.241029 -150.087524) (xy 51.293334 -150.072173) (xy 51.347292 -150.064422) (xy 51.374548 -150.063962)
			(xy 51.402122 -150.064442) (xy 51.456695 -150.072388) (xy 51.509556 -150.088109) (xy 51.559603 -150.111276)
			(xy 51.605792 -150.141408) (xy 51.647163 -150.177875) (xy 51.665378 -150.198582) (xy 51.675276 -150.20948)
			(xy 51.699926 -150.225555) (xy 51.728134 -150.233939) (xy 51.757562 -150.233939) (xy 51.78577 -150.225555)
			(xy 51.81042 -150.20948) (xy 51.820318 -150.198582) (xy 51.838512 -150.177855) (xy 51.879885 -150.141387)
			(xy 51.926079 -150.111257) (xy 51.97613 -150.088094) (xy 52.028995 -150.072381) (xy 52.083572 -150.064445)
			(xy 52.111148 -150.063962) (xy 52.137649 -150.064415) (xy 52.19014 -150.071762) (xy 52.241107 -150.086307)
			(xy 52.289569 -150.10777) (xy 52.334592 -150.135737) (xy 52.355242 -150.152354) (xy 52.367396 -150.161784)
			(xy 52.395794 -150.173573) (xy 52.426411 -150.176397) (xy 52.456486 -150.170003) (xy 52.483306 -150.154967)
			(xy 52.504451 -150.132645) (xy 52.511706 -150.11908) (xy 52.523817 -150.095395) (xy 52.553737 -150.051413)
			(xy 52.589605 -150.01213) (xy 52.630693 -149.978345) (xy 52.653184 -149.96414) (xy 52.665431 -149.956248)
			(xy 52.685104 -149.934769) (xy 52.697907 -149.908607) (xy 52.702796 -149.879894) (xy 52.699373 -149.850969)
			(xy 52.694078 -149.837394) (xy 52.684593 -149.814182) (xy 52.671241 -149.76585) (xy 52.664511 -149.716161)
			(xy 52.664106 -149.69109) (xy 52.66454 -149.666021) (xy 52.671286 -149.616338) (xy 52.684614 -149.568004)
			(xy 52.694078 -149.544786) (xy 52.699333 -149.531207) (xy 52.702713 -149.502299) (xy 52.697811 -149.47361)
			(xy 52.685024 -149.447464) (xy 52.665389 -149.42598) (xy 52.653184 -149.41804) (xy 52.630024 -149.403514)
			(xy 52.587899 -149.368668) (xy 52.551317 -149.328041) (xy 52.521063 -149.282506) (xy 52.497786 -149.233039)
			(xy 52.481986 -149.180703) (xy 52.474001 -149.126619) (xy 52.474003 -149.07195) (xy 52.481993 -149.017867)
			(xy 52.497797 -148.965532) (xy 52.521079 -148.916067) (xy 52.551336 -148.870534) (xy 52.587922 -148.829911)
			(xy 52.630049 -148.795068) (xy 52.653184 -148.7805) (xy 52.66539 -148.772551) (xy 52.685063 -148.751088)
			(xy 52.697871 -148.724941) (xy 52.702771 -148.696241) (xy 52.699363 -148.667326) (xy 52.694078 -148.653754)
			(xy 52.684581 -148.630547) (xy 52.671233 -148.582213) (xy 52.664508 -148.532522) (xy 52.664106 -148.50745)
			(xy 52.664627 -148.479565) (xy 52.672939 -148.424418) (xy 52.689377 -148.371126) (xy 52.713575 -148.32088)
			(xy 52.744991 -148.274801) (xy 52.782924 -148.233919) (xy 52.826526 -148.199147) (xy 52.874824 -148.171262)
			(xy 52.926739 -148.150887) (xy 52.98111 -148.138477) (xy 53.036724 -148.13431) (xy 53.092338 -148.138477)
			(xy 53.146709 -148.150887) (xy 53.198624 -148.171262) (xy 53.246922 -148.199147) (xy 53.290524 -148.233919)
			(xy 53.328457 -148.274801) (xy 53.359873 -148.32088) (xy 53.384071 -148.371126) (xy 53.400509 -148.424418)
			(xy 53.408821 -148.479565) (xy 53.409342 -148.50745) (xy 53.408875 -148.534782) (xy 53.400906 -148.588863)
			(xy 53.385118 -148.641198) (xy 53.36185 -148.690662) (xy 53.331601 -148.736195) (xy 53.295022 -148.776817)
			(xy 53.252897 -148.811655) (xy 53.229764 -148.82622) (xy 53.217537 -148.834138) (xy 53.19787 -148.855612)
			(xy 53.185068 -148.881767) (xy 53.180173 -148.910472) (xy 53.183584 -148.939392) (xy 53.18887 -148.952966)
			(xy 53.198345 -148.976181) (xy 53.211701 -149.024512) (xy 53.218435 -149.074199) (xy 53.218842 -149.09927)
			(xy 53.218431 -149.12434) (xy 53.211677 -149.174023) (xy 53.198339 -149.222357) (xy 53.18887 -149.245574)
			(xy 53.183624 -149.259151) (xy 53.180262 -149.288051) (xy 53.185173 -149.316729) (xy 53.197961 -149.342863)
			(xy 53.217591 -149.364338) (xy 53.229764 -149.37232) (xy 53.252885 -149.386903) (xy 53.295003 -149.421747)
			(xy 53.331579 -149.462369) (xy 53.361829 -149.507898) (xy 53.385103 -149.557358) (xy 53.400902 -149.609688)
			(xy 53.408888 -149.663764) (xy 53.408889 -149.718426) (xy 53.400905 -149.772502) (xy 53.385107 -149.824832)
			(xy 53.361834 -149.874292) (xy 53.331585 -149.919823) (xy 53.29501 -149.960446) (xy 53.252893 -149.995291)
			(xy 53.229764 -150.00986) (xy 53.217509 -150.017739) (xy 53.197842 -150.039225) (xy 53.185043 -150.06539)
			(xy 53.180156 -150.094104) (xy 53.183577 -150.12303) (xy 53.18887 -150.136606) (xy 53.198357 -150.159817)
			(xy 53.211708 -150.208149) (xy 53.218438 -150.257838) (xy 53.218842 -150.28291) (xy 53.21837 -150.309752)
			(xy 53.210665 -150.362881) (xy 53.195416 -150.414354) (xy 53.172938 -150.463106) (xy 53.143697 -150.508127)
			(xy 53.108298 -150.548487) (xy 53.067473 -150.583349) (xy 53.022069 -150.611993) (xy 52.973024 -150.633824)
			(xy 52.947316 -150.641558) (xy 52.932841 -150.646276) (xy 52.907286 -150.662788) (xy 52.887726 -150.686092)
			(xy 52.875894 -150.714122) (xy 52.87284 -150.744393) (xy 52.878835 -150.774222) (xy 52.885594 -150.787862)
			(xy 52.900228 -150.816008) (xy 52.920955 -150.875959) (xy 52.931453 -150.938517) (xy 52.932076 -150.970234)
			(xy 52.931855 -150.988253) (xy 52.928421 -151.024128) (xy 52.925218 -151.041862) (xy 52.922936 -151.057077)
			(xy 52.926453 -151.087622) (xy 52.938901 -151.115736) (xy 52.959153 -151.138871) (xy 52.985373 -151.154931)
			(xy 53.000148 -151.15921) (xy 53.027191 -151.166611) (xy 53.078917 -151.188241) (xy 53.126922 -151.217205)
			(xy 53.170174 -151.25288) (xy 53.207741 -151.294499) (xy 53.238815 -151.341165) (xy 53.262728 -151.391876)
			(xy 53.278965 -151.44554) (xy 53.287177 -151.501001) (xy 53.287676 -151.529034) (xy 53.287254 -151.556288)
			(xy 53.279492 -151.610239) (xy 53.264131 -151.662537) (xy 53.241483 -151.712117) (xy 53.21201 -151.757968)
			(xy 53.176312 -151.799159) (xy 53.135115 -151.83485) (xy 53.089259 -151.864315) (xy 53.039675 -151.886954)
			(xy 52.987375 -151.902306) (xy 52.933422 -151.910058) (xy 52.906168 -151.910542) (xy 52.878594 -151.91005)
			(xy 52.824022 -151.902105) (xy 52.771161 -151.886387) (xy 52.721115 -151.863222) (xy 52.674925 -151.833093)
			(xy 52.633554 -151.796628) (xy 52.615338 -151.775922) (xy 52.60544 -151.765024) (xy 52.58079 -151.748949)
			(xy 52.552582 -151.740565) (xy 52.523154 -151.740565) (xy 52.494946 -151.748949) (xy 52.470296 -151.765024)
			(xy 52.460398 -151.775922) (xy 52.442183 -151.796628) (xy 52.400812 -151.833093) (xy 52.354622 -151.86322)
			(xy 52.304575 -151.886383) (xy 52.251714 -151.902099) (xy 52.197142 -151.910039) (xy 52.141994 -151.910039)
			(xy 52.087422 -151.902099) (xy 52.034561 -151.886383) (xy 51.984514 -151.86322) (xy 51.938324 -151.833093)
			(xy 51.896953 -151.796628) (xy 51.878738 -151.775922) (xy 51.86884 -151.765024) (xy 51.84419 -151.748949)
			(xy 51.815982 -151.740565) (xy 51.786554 -151.740565) (xy 51.758346 -151.748949) (xy 51.733696 -151.765024)
			(xy 51.723798 -151.775922) (xy 51.705596 -151.796642) (xy 51.664225 -151.83311) (xy 51.618033 -151.863241)
			(xy 51.567983 -151.886405) (xy 51.515119 -151.90212) (xy 51.460543 -151.910058) (xy 51.432968 -151.910542)
			(xy 51.405718 -151.910052) (xy 51.351772 -151.902292) (xy 51.299479 -151.886935) (xy 51.249904 -151.864292)
			(xy 51.204055 -151.834826) (xy 51.162866 -151.799135) (xy 51.127175 -151.757946) (xy 51.097709 -151.712098)
			(xy 51.075066 -151.662523) (xy 51.059708 -151.61023) (xy 51.051948 -151.556284) (xy 51.05146 -151.529034)
			(xy 51.052043 -151.501181) (xy 51.060161 -151.44607) (xy 51.0762 -151.392722) (xy 51.09982 -151.342272)
			(xy 51.130519 -151.295788) (xy 51.167647 -151.254258) (xy 51.210414 -151.218563) (xy 51.257914 -151.189461)
			(xy 51.309138 -151.167569) (xy 51.33594 -151.159972) (xy 51.350063 -151.155719) (xy 51.375204 -151.14032)
			(xy 51.394916 -151.118396) (xy 51.407566 -151.091764) (xy 51.412104 -151.062632) (xy 51.410616 -151.047958)
			(xy 51.408945 -151.034942) (xy 51.407166 -151.008757) (xy 51.40706 -150.995634) (xy 51.407158 -150.981485)
			(xy 51.409189 -150.953262) (xy 51.411124 -150.939246) (xy 51.412683 -150.925896) (xy 51.409585 -150.899209)
			(xy 51.39962 -150.874259) (xy 51.38348 -150.852781) (xy 51.362288 -150.836267) (xy 51.337516 -150.825867)
			(xy 51.324256 -150.823676) (xy 51.297113 -150.81953) (xy 51.244287 -150.804561) (xy 51.194152 -150.782174)
			(xy 51.147744 -150.752832) (xy 51.106021 -150.717141) (xy 51.069844 -150.675838) (xy 51.039961 -150.629777)
			(xy 51.016989 -150.579907) (xy 51.001402 -150.52726) (xy 50.993522 -150.472923) (xy 50.99304 -150.44547)
			(xy 39.30142 -150.44547) (xy 39.30142 -151.644871) (xy 43.782962 -151.644871) (xy 43.786968 -151.589723)
			(xy 43.798892 -151.535731) (xy 43.818485 -151.484026) (xy 43.845337 -151.435691) (xy 43.878885 -151.391738)
			(xy 43.898312 -151.372062) (xy 43.907656 -151.362295) (xy 43.921334 -151.338994) (xy 43.928423 -151.312922)
			(xy 43.928426 -151.285903) (xy 43.921344 -151.259829) (xy 43.907671 -151.236525) (xy 43.898312 -151.226774)
			(xy 43.880473 -151.208774) (xy 43.849246 -151.16886) (xy 43.823579 -151.125162) (xy 43.803922 -151.078452)
			(xy 43.790624 -151.029549) (xy 43.783917 -150.979317) (xy 43.783504 -150.953978) (xy 43.783957 -150.926726)
			(xy 43.791717 -150.872776) (xy 43.807076 -150.82048) (xy 43.82972 -150.770902) (xy 43.85919 -150.725051)
			(xy 43.894885 -150.683861) (xy 43.936078 -150.64817) (xy 43.981932 -150.618704) (xy 44.031512 -150.596064)
			(xy 44.083809 -150.58071) (xy 44.13776 -150.572955) (xy 44.165012 -150.57247) (xy 44.194271 -150.573037)
			(xy 44.252103 -150.581981) (xy 44.307894 -150.599642) (xy 44.360337 -150.625607) (xy 44.408206 -150.659268)
			(xy 44.42968 -150.67915) (xy 44.439987 -150.688465) (xy 44.464413 -150.701673) (xy 44.491499 -150.707794)
			(xy 44.519231 -150.706373) (xy 44.545549 -150.697515) (xy 44.568497 -150.681879) (xy 44.577762 -150.67153)
			(xy 44.596006 -150.650711) (xy 44.637408 -150.613972) (xy 44.683688 -150.583606) (xy 44.733873 -150.560253)
			(xy 44.786908 -150.544404) (xy 44.841678 -150.536392) (xy 44.869354 -150.535894) (xy 44.896723 -150.536388)
			(xy 44.950901 -150.5442) (xy 45.003404 -150.559682) (xy 45.053151 -150.582518) (xy 45.099119 -150.612236)
			(xy 45.120052 -150.629874) (xy 45.13138 -150.63911) (xy 45.157937 -150.651286) (xy 45.186854 -150.655459)
			(xy 45.215771 -150.651286) (xy 45.242328 -150.63911) (xy 45.253656 -150.629874) (xy 45.274589 -150.612233)
			(xy 45.320557 -150.582509) (xy 45.370303 -150.559663) (xy 45.422805 -150.544167) (xy 45.476983 -150.536338)
			(xy 45.531725 -150.536338) (xy 45.585903 -150.544167) (xy 45.638405 -150.559663) (xy 45.688151 -150.582509)
			(xy 45.734119 -150.612233) (xy 45.755052 -150.629874) (xy 45.76638 -150.63911) (xy 45.792937 -150.651286)
			(xy 45.821854 -150.655459) (xy 45.850771 -150.651286) (xy 45.877328 -150.63911) (xy 45.888656 -150.629874)
			(xy 45.909589 -150.612233) (xy 45.955557 -150.582509) (xy 46.005303 -150.559663) (xy 46.057805 -150.544167)
			(xy 46.111983 -150.536338) (xy 46.166725 -150.536338) (xy 46.220903 -150.544167) (xy 46.273405 -150.559663)
			(xy 46.323151 -150.582509) (xy 46.369119 -150.612233) (xy 46.390052 -150.629874) (xy 46.40138 -150.63911)
			(xy 46.427937 -150.651286) (xy 46.456854 -150.655459) (xy 46.485771 -150.651286) (xy 46.512328 -150.63911)
			(xy 46.523656 -150.629874) (xy 46.54459 -150.612238) (xy 46.590563 -150.582527) (xy 46.64031 -150.55969)
			(xy 46.69281 -150.544199) (xy 46.746985 -150.536369) (xy 46.774354 -150.535894) (xy 46.804152 -150.536484)
			(xy 46.863022 -150.545758) (xy 46.919734 -150.56407) (xy 46.972911 -150.590976) (xy 47.021258 -150.625822)
			(xy 47.042832 -150.646384) (xy 47.054372 -150.657021) (xy 47.082273 -150.671355) (xy 47.113206 -150.676557)
			(xy 47.144261 -150.672139) (xy 47.172516 -150.658516) (xy 47.18431 -150.648162) (xy 47.205669 -150.628715)
			(xy 47.25316 -150.595835) (xy 47.305067 -150.570493) (xy 47.360201 -150.553269) (xy 47.417303 -150.544556)
			(xy 47.446184 -150.544022) (xy 47.473438 -150.54447) (xy 47.527391 -150.552226) (xy 47.579691 -150.567581)
			(xy 47.629273 -150.590224) (xy 47.675128 -150.619693) (xy 47.716321 -150.655389) (xy 47.752015 -150.696584)
			(xy 47.781483 -150.742439) (xy 47.804124 -150.792022) (xy 47.819477 -150.844323) (xy 47.827231 -150.898276)
			(xy 47.827692 -150.92553) (xy 47.827299 -150.950869) (xy 47.820586 -151.001101) (xy 47.807281 -151.050002)
			(xy 47.787619 -151.096711) (xy 47.761946 -151.140406) (xy 47.730715 -151.180317) (xy 47.712884 -151.198326)
			(xy 47.703553 -151.208104) (xy 47.689874 -151.231402) (xy 47.682784 -151.257471) (xy 47.682779 -151.284487)
			(xy 47.689858 -151.310559) (xy 47.703527 -151.333863) (xy 47.712884 -151.343614) (xy 47.732318 -151.363281)
			(xy 47.76586 -151.407234) (xy 47.792706 -151.455569) (xy 47.812293 -151.507273) (xy 47.824211 -151.561262)
			(xy 47.828212 -151.616407) (xy 47.824209 -151.671552) (xy 47.812289 -151.725541) (xy 47.7927 -151.777244)
			(xy 47.765852 -151.825578) (xy 47.732309 -151.86953) (xy 47.712884 -151.889206) (xy 47.703473 -151.898913)
			(xy 47.6898 -151.922231) (xy 47.68272 -151.948319) (xy 47.682729 -151.975351) (xy 47.689827 -152.001433)
			(xy 47.703516 -152.024742) (xy 47.712884 -152.034494) (xy 47.730707 -152.05251) (xy 47.761935 -152.09242)
			(xy 47.787605 -152.136114) (xy 47.807264 -152.182822) (xy 47.820566 -152.231722) (xy 47.827277 -152.281952)
			(xy 47.827692 -152.30729) (xy 47.827235 -152.334543) (xy 47.819479 -152.388495) (xy 47.804124 -152.440794)
			(xy 47.781481 -152.490375) (xy 47.752013 -152.536229) (xy 47.716318 -152.577423) (xy 47.675125 -152.613116)
			(xy 47.62927 -152.642584) (xy 47.579689 -152.665226) (xy 47.527389 -152.680581) (xy 47.473437 -152.688336)
			(xy 47.446184 -152.688798) (xy 47.416385 -152.688249) (xy 47.357513 -152.678966) (xy 47.300799 -152.660644)
			(xy 47.247624 -152.633728) (xy 47.199279 -152.598874) (xy 47.177706 -152.578308) (xy 47.166217 -152.567611)
			(xy 47.138297 -152.553284) (xy 47.107349 -152.548094) (xy 47.076284 -152.552527) (xy 47.048023 -152.566167)
			(xy 47.036228 -152.57653) (xy 47.014852 -152.595958) (xy 46.967366 -152.628841) (xy 46.915463 -152.654186)
			(xy 46.860333 -152.671415) (xy 46.803234 -152.680133) (xy 46.774354 -152.68067) (xy 46.746985 -152.68018)
			(xy 46.692806 -152.672369) (xy 46.640303 -152.656886) (xy 46.590556 -152.634049) (xy 46.544588 -152.604329)
			(xy 46.523656 -152.58669) (xy 46.512328 -152.577454) (xy 46.485771 -152.565278) (xy 46.456854 -152.561105)
			(xy 46.427937 -152.565278) (xy 46.40138 -152.577454) (xy 46.390052 -152.58669) (xy 46.369119 -152.604331)
			(xy 46.323151 -152.634055) (xy 46.273405 -152.656901) (xy 46.220903 -152.672397) (xy 46.166725 -152.680226)
			(xy 46.111983 -152.680226) (xy 46.057805 -152.672397) (xy 46.005303 -152.656901) (xy 45.955557 -152.634055)
			(xy 45.909589 -152.604331) (xy 45.888656 -152.58669) (xy 45.877328 -152.577454) (xy 45.850771 -152.565278)
			(xy 45.821854 -152.561105) (xy 45.792937 -152.565278) (xy 45.76638 -152.577454) (xy 45.755052 -152.58669)
			(xy 45.734119 -152.604331) (xy 45.688151 -152.634055) (xy 45.638405 -152.656901) (xy 45.585903 -152.672397)
			(xy 45.531725 -152.680226) (xy 45.476983 -152.680226) (xy 45.422805 -152.672397) (xy 45.370303 -152.656901)
			(xy 45.320557 -152.634055) (xy 45.274589 -152.604331) (xy 45.253656 -152.58669) (xy 45.242328 -152.577454)
			(xy 45.215771 -152.565278) (xy 45.186854 -152.561105) (xy 45.157937 -152.565278) (xy 45.13138 -152.577454)
			(xy 45.120052 -152.58669) (xy 45.09911 -152.604317) (xy 45.05314 -152.634031) (xy 45.003395 -152.656869)
			(xy 44.950897 -152.672363) (xy 44.896723 -152.680194) (xy 44.869354 -152.68067) (xy 44.840094 -152.680113)
			(xy 44.782263 -152.671165) (xy 44.726473 -152.653501) (xy 44.674029 -152.627534) (xy 44.62616 -152.593872)
			(xy 44.604686 -152.57399) (xy 44.594404 -152.564648) (xy 44.569969 -152.551451) (xy 44.542878 -152.545339)
			(xy 44.515144 -152.546766) (xy 44.488824 -152.555626) (xy 44.465872 -152.571261) (xy 44.456604 -152.58161)
			(xy 44.438387 -152.602453) (xy 44.396978 -152.639189) (xy 44.350692 -152.669551) (xy 44.300502 -152.692899)
			(xy 44.247463 -152.708743) (xy 44.19269 -152.71675) (xy 44.165012 -152.717246) (xy 44.137763 -152.716711)
			(xy 44.083819 -152.708957) (xy 44.031527 -152.693605) (xy 43.981953 -152.670968) (xy 43.936104 -152.641507)
			(xy 43.894915 -152.60582) (xy 43.859223 -152.564636) (xy 43.829756 -152.518791) (xy 43.807112 -152.469219)
			(xy 43.791754 -152.41693) (xy 43.783993 -152.362987) (xy 43.783504 -152.335738) (xy 43.783942 -152.3104)
			(xy 43.790646 -152.26017) (xy 43.803942 -152.21127) (xy 43.823596 -152.164561) (xy 43.849261 -152.120865)
			(xy 43.880485 -152.080952) (xy 43.898312 -152.062942) (xy 43.907675 -152.053192) (xy 43.921352 -152.029887)
			(xy 43.928439 -152.00381) (xy 43.928438 -151.976787) (xy 43.921351 -151.950711) (xy 43.907674 -151.927405)
			(xy 43.898312 -151.917654) (xy 43.878846 -151.898018) (xy 43.845305 -151.85406) (xy 43.818461 -151.805721)
			(xy 43.798875 -151.754012) (xy 43.786959 -151.700019) (xy 43.782962 -151.644871) (xy 39.30142 -151.644871)
			(xy 39.30142 -153.12472) (xy 51.012924 -153.12472) (xy 51.012928 -153.070227) (xy 51.020687 -153.016288)
			(xy 51.036042 -152.964003) (xy 51.058683 -152.914435) (xy 51.088146 -152.868593) (xy 51.123834 -152.827411)
			(xy 51.165019 -152.791727) (xy 51.210863 -152.762267) (xy 51.260433 -152.739631) (xy 51.312719 -152.72428)
			(xy 51.366659 -152.716526) (xy 51.421152 -152.716526) (xy 51.475091 -152.724282) (xy 51.527377 -152.739635)
			(xy 51.576946 -152.762272) (xy 51.62279 -152.791734) (xy 51.663974 -152.827419) (xy 51.69966 -152.868602)
			(xy 51.729122 -152.914444) (xy 51.736434 -152.930455) (xy 53.058229 -152.930455) (xy 53.058229 -152.875945)
			(xy 53.065987 -152.821989) (xy 53.081345 -152.769686) (xy 53.10399 -152.720102) (xy 53.133461 -152.674245)
			(xy 53.169159 -152.633049) (xy 53.210356 -152.597353) (xy 53.256214 -152.567883) (xy 53.305799 -152.54524)
			(xy 53.358102 -152.529884) (xy 53.412059 -152.522128) (xy 53.439314 -152.521666) (xy 53.466685 -152.522108)
			(xy 53.520866 -152.529929) (xy 53.57337 -152.545423) (xy 53.623117 -152.56827) (xy 53.669082 -152.598001)
			(xy 53.690012 -152.615646) (xy 53.70134 -152.624882) (xy 53.727897 -152.637058) (xy 53.756814 -152.641231)
			(xy 53.785731 -152.637058) (xy 53.812288 -152.624882) (xy 53.823616 -152.615646) (xy 53.844575 -152.59804)
			(xy 53.89054 -152.568322) (xy 53.94028 -152.545479) (xy 53.992775 -152.52998) (xy 54.046947 -152.522144)
			(xy 54.074314 -152.521666) (xy 54.101563 -152.522205) (xy 54.155505 -152.529963) (xy 54.207795 -152.545318)
			(xy 54.257367 -152.567958) (xy 54.303212 -152.597423) (xy 54.344398 -152.633112) (xy 54.380085 -152.674299)
			(xy 54.409548 -152.720146) (xy 54.432187 -152.769719) (xy 54.44754 -152.822009) (xy 54.455296 -152.875951)
			(xy 54.455296 -152.930449) (xy 54.44754 -152.984391) (xy 54.432187 -153.036681) (xy 54.409548 -153.086254)
			(xy 54.380085 -153.132101) (xy 54.344398 -153.173288) (xy 54.303212 -153.208977) (xy 54.257367 -153.238442)
			(xy 54.207795 -153.261082) (xy 54.155505 -153.276437) (xy 54.101563 -153.284195) (xy 54.074314 -153.284682)
			(xy 54.046944 -153.284212) (xy 53.992765 -153.276396) (xy 53.940262 -153.260908) (xy 53.890515 -153.238067)
			(xy 53.844548 -153.208343) (xy 53.823616 -153.190702) (xy 53.812288 -153.181466) (xy 53.785731 -153.16929)
			(xy 53.756814 -153.165117) (xy 53.727897 -153.16929) (xy 53.70134 -153.181466) (xy 53.690012 -153.190702)
			(xy 53.669086 -153.208349) (xy 53.623112 -153.23806) (xy 53.573363 -153.260894) (xy 53.520861 -153.276383)
			(xy 53.466684 -153.284209) (xy 53.439314 -153.284682) (xy 53.412059 -153.284272) (xy 53.358102 -153.276516)
			(xy 53.305799 -153.26116) (xy 53.256214 -153.238517) (xy 53.210356 -153.209047) (xy 53.169159 -153.173351)
			(xy 53.133461 -153.132155) (xy 53.10399 -153.086298) (xy 53.081345 -153.036714) (xy 53.065987 -152.984411)
			(xy 53.058229 -152.930455) (xy 51.736434 -152.930455) (xy 51.751761 -152.964013) (xy 51.767116 -153.016299)
			(xy 51.774873 -153.070237) (xy 51.77536 -153.097484) (xy 51.77493 -153.122875) (xy 51.768173 -153.173207)
			(xy 51.761898 -153.197814) (xy 51.758525 -153.212472) (xy 51.759445 -153.242518) (xy 51.769069 -153.270996)
			(xy 51.786564 -153.29544) (xy 51.810415 -153.313736) (xy 51.838559 -153.324299) (xy 51.868558 -153.326215)
			(xy 51.88331 -153.32329) (xy 51.90484 -153.318535) (xy 51.948639 -153.313442) (xy 51.970686 -153.31313)
			(xy 51.97094 -153.31313) (xy 51.998187 -153.313621) (xy 52.052126 -153.321382) (xy 52.104412 -153.336739)
			(xy 52.153979 -153.359381) (xy 52.199821 -153.388847) (xy 52.241002 -153.424536) (xy 52.276686 -153.465723)
			(xy 52.306145 -153.511568) (xy 52.32878 -153.561139) (xy 52.34413 -153.613427) (xy 52.351883 -153.667367)
			(xy 52.351881 -153.721861) (xy 52.344124 -153.775801) (xy 52.32877 -153.828087) (xy 52.306131 -153.877657)
			(xy 52.276669 -153.9235) (xy 52.240982 -153.964684) (xy 52.199798 -154.00037) (xy 52.153955 -154.029832)
			(xy 52.104385 -154.052471) (xy 52.052099 -154.067824) (xy 51.998159 -154.075581) (xy 51.943665 -154.075583)
			(xy 51.889725 -154.067829) (xy 51.837437 -154.052479) (xy 51.787866 -154.029844) (xy 51.742021 -154.000384)
			(xy 51.700835 -153.964701) (xy 51.665146 -153.923519) (xy 51.63568 -153.877678) (xy 51.613039 -153.82811)
			(xy 51.597681 -153.775824) (xy 51.589921 -153.721885) (xy 51.589432 -153.694638) (xy 51.589867 -153.669247)
			(xy 51.596621 -153.618916) (xy 51.602894 -153.594308) (xy 51.606253 -153.579646) (xy 51.605338 -153.549601)
			(xy 51.595718 -153.521123) (xy 51.578225 -153.496677) (xy 51.554375 -153.478382) (xy 51.526232 -153.46782)
			(xy 51.496234 -153.465906) (xy 51.481482 -153.468832) (xy 51.459952 -153.473589) (xy 51.416153 -153.47868)
			(xy 51.394106 -153.478992) (xy 51.393852 -153.478992) (xy 51.366605 -153.47847) (xy 51.312667 -153.470709)
			(xy 51.260383 -153.45535) (xy 51.210816 -153.432707) (xy 51.164976 -153.403241) (xy 51.123796 -153.367551)
			(xy 51.088114 -153.326364) (xy 51.058657 -153.280518) (xy 51.036024 -153.230947) (xy 51.020675 -153.17866)
			(xy 51.012924 -153.12472) (xy 39.30142 -153.12472) (xy 39.30142 -153.862532) (xy 39.966819 -154.528052)
			(xy 49.996289 -154.528052) (xy 49.996289 -154.473548) (xy 50.004047 -154.419598) (xy 50.019404 -154.367301)
			(xy 50.042047 -154.317722) (xy 50.071517 -154.271871) (xy 50.107212 -154.230681) (xy 50.148406 -154.19499)
			(xy 50.194261 -154.165526) (xy 50.243842 -154.142888) (xy 50.296141 -154.127537) (xy 50.350092 -154.119786)
			(xy 50.377344 -154.119326) (xy 50.407031 -154.119911) (xy 50.465689 -154.129102) (xy 50.522215 -154.147271)
			(xy 50.575243 -154.173978) (xy 50.623492 -154.20858) (xy 50.665798 -154.250239) (xy 50.683922 -154.273758)
			(xy 50.692348 -154.284365) (xy 50.713661 -154.301072) (xy 50.738615 -154.311591) (xy 50.765456 -154.315181)
			(xy 50.792297 -154.311591) (xy 50.817251 -154.301072) (xy 50.838564 -154.284365) (xy 50.84699 -154.273758)
			(xy 50.86512 -154.250243) (xy 50.907427 -154.208585) (xy 50.955675 -154.173982) (xy 51.008701 -154.147271)
			(xy 51.065225 -154.129095) (xy 51.123881 -154.119893) (xy 51.153568 -154.119326) (xy 51.180825 -154.119719)
			(xy 51.234784 -154.127473) (xy 51.28709 -154.142827) (xy 51.336679 -154.16547) (xy 51.38254 -154.19494)
			(xy 51.423741 -154.230637) (xy 51.459441 -154.271834) (xy 51.488915 -154.317693) (xy 51.511561 -154.36728)
			(xy 51.52692 -154.419585) (xy 51.534679 -154.473543) (xy 51.534679 -154.528057) (xy 51.52692 -154.582015)
			(xy 51.511561 -154.63432) (xy 51.488915 -154.683907) (xy 51.459441 -154.729766) (xy 51.423741 -154.770963)
			(xy 51.38254 -154.80666) (xy 51.336679 -154.83613) (xy 51.28709 -154.858773) (xy 51.234784 -154.874127)
			(xy 51.180825 -154.881881) (xy 51.153568 -154.882342) (xy 51.123881 -154.88176) (xy 51.065222 -154.87257)
			(xy 51.008695 -154.854402) (xy 50.955667 -154.827694) (xy 50.907418 -154.793091) (xy 50.865114 -154.75143)
			(xy 50.84699 -154.72791) (xy 50.838564 -154.717303) (xy 50.817251 -154.700596) (xy 50.792297 -154.690077)
			(xy 50.765456 -154.686487) (xy 50.738615 -154.690077) (xy 50.713661 -154.700596) (xy 50.692348 -154.717303)
			(xy 50.683922 -154.72791) (xy 50.665776 -154.751412) (xy 50.623474 -154.793073) (xy 50.575229 -154.827678)
			(xy 50.522206 -154.854392) (xy 50.465685 -154.87257) (xy 50.40703 -154.881774) (xy 50.377344 -154.882342)
			(xy 50.350092 -154.881814) (xy 50.296141 -154.874063) (xy 50.243842 -154.858712) (xy 50.194261 -154.836074)
			(xy 50.148406 -154.80661) (xy 50.107212 -154.770919) (xy 50.071517 -154.729729) (xy 50.042047 -154.683878)
			(xy 50.019404 -154.634299) (xy 50.004047 -154.582002) (xy 49.996289 -154.528052) (xy 39.966819 -154.528052)
			(xy 40.701214 -155.26258) (xy 50.68189 -155.26258) (xy 50.700052 -155.242945) (xy 50.740922 -155.208443)
			(xy 50.78621 -155.179985) (xy 50.835026 -155.158129) (xy 50.886416 -155.143302) (xy 50.939373 -155.135795)
			(xy 50.966116 -155.135326) (xy 50.993371 -155.13574) (xy 51.047325 -155.1435) (xy 51.099626 -155.15886)
			(xy 51.149209 -155.181507) (xy 51.195063 -155.21098) (xy 51.236257 -155.246679) (xy 51.27195 -155.287877)
			(xy 51.301417 -155.333735) (xy 51.324058 -155.383321) (xy 51.339411 -155.435624) (xy 51.347163 -155.489579)
			(xy 51.347624 -155.516834) (xy 51.347624 -155.517088) (xy 51.347224 -155.542292) (xy 51.340585 -155.59226)
			(xy 51.327409 -155.640914) (xy 51.307926 -155.687404) (xy 51.295554 -155.709366) (xy 51.28846 -155.722303)
			(xy 51.281434 -155.750951) (xy 51.282888 -155.780412) (xy 51.292701 -155.808229) (xy 51.310054 -155.832081)
			(xy 51.3335 -155.84998) (xy 51.347116 -155.85567) (xy 51.373892 -155.866366) (xy 51.424134 -155.894654)
			(xy 51.469543 -155.930184) (xy 51.509085 -155.972146) (xy 51.541859 -156.019583) (xy 51.567117 -156.071414)
			(xy 51.584283 -156.126457) (xy 51.592966 -156.183457) (xy 51.593496 -156.212286) (xy 51.593032 -156.239539)
			(xy 51.585276 -156.293491) (xy 51.569921 -156.345789) (xy 51.54728 -156.39537) (xy 51.517812 -156.441224)
			(xy 51.482118 -156.482417) (xy 51.440925 -156.518111) (xy 51.395072 -156.547579) (xy 51.345491 -156.570221)
			(xy 51.293193 -156.585576) (xy 51.239241 -156.593331) (xy 51.211988 -156.593794) (xy 51.211734 -156.593794)
			(xy 51.181895 -156.593227) (xy 51.122949 -156.583906) (xy 51.094386 -156.575252) (xy 51.080457 -156.571302)
			(xy 51.051539 -156.570385) (xy 51.02353 -156.577636) (xy 50.998691 -156.592471) (xy 50.979026 -156.613693)
			(xy 50.966122 -156.639589) (xy 50.963068 -156.653738) (xy 50.957919 -156.679816) (xy 50.941346 -156.73032)
			(xy 50.917921 -156.778034) (xy 50.888096 -156.822032) (xy 50.852451 -156.861463) (xy 50.811676 -156.895561)
			(xy 50.76656 -156.923667) (xy 50.717979 -156.945236) (xy 50.666873 -156.959849) (xy 50.614233 -156.967225)
			(xy 50.587656 -156.967682) (xy 50.560405 -156.967245) (xy 50.506458 -156.959483) (xy 50.454165 -156.944123)
			(xy 50.40459 -156.921478) (xy 50.358742 -156.892008) (xy 50.317554 -156.856314) (xy 50.281865 -156.815123)
			(xy 50.252401 -156.769271) (xy 50.229762 -156.719693) (xy 50.214408 -156.667399) (xy 50.206652 -156.613451)
			(xy 50.206652 -156.558949) (xy 50.214408 -156.505001) (xy 50.229762 -156.452707) (xy 50.252401 -156.403129)
			(xy 50.281865 -156.357277) (xy 50.317554 -156.316086) (xy 50.358742 -156.280392) (xy 50.40459 -156.250922)
			(xy 50.454165 -156.228277) (xy 50.506458 -156.212917) (xy 50.560405 -156.205155) (xy 50.587656 -156.204666)
			(xy 50.58791 -156.204666) (xy 50.617749 -156.205247) (xy 50.676695 -156.214559) (xy 50.705258 -156.223208)
			(xy 50.719167 -156.227239) (xy 50.748099 -156.228148) (xy 50.776118 -156.220883) (xy 50.800963 -156.206032)
			(xy 50.820629 -156.184792) (xy 50.833527 -156.158879) (xy 50.836576 -156.144722) (xy 50.843165 -156.111884)
			(xy 50.866284 -156.049031) (xy 50.88255 -156.019754) (xy 50.889618 -156.006804) (xy 50.896647 -155.978161)
			(xy 50.895197 -155.948704) (xy 50.885389 -155.92089) (xy 50.868042 -155.897039) (xy 50.844601 -155.879141)
			(xy 50.830988 -155.87345) (xy 50.80273 -155.862094) (xy 50.749937 -155.831739) (xy 50.702636 -155.793383)
			(xy 50.68189 -155.771088) (xy 40.595804 -155.771088) (xy 40.570822 -155.770445) (xy 40.521816 -155.76071)
			(xy 40.475647 -155.741611) (xy 40.434084 -155.713883) (xy 40.415972 -155.696666) (xy 38.86708 -154.147774)
			(xy 38.849815 -154.129686) (xy 38.822008 -154.088138) (xy 38.802837 -154.041965) (xy 38.79304 -153.992939)
			(xy 38.792404 -153.967942) (xy 38.792404 -137.343388) (xy 35.595052 -134.146036) (xy 31.773368 -134.146036)
			(xy 31.74837 -134.145431) (xy 31.699345 -134.135619) (xy 31.653175 -134.116436) (xy 31.61163 -134.08862)
			(xy 31.593536 -134.07136) (xy 31.105602 -133.58368) (xy 28.31973 -133.58368) (xy 28.294735 -133.583025)
			(xy 28.245713 -133.573226) (xy 28.199543 -133.554058) (xy 28.157995 -133.526256) (xy 28.139898 -133.509004)
			(xy 27.528266 -132.897372) (xy 27.511067 -132.879242) (xy 27.48332 -132.83769) (xy 27.464207 -132.791526)
			(xy 27.454459 -132.742522) (xy 27.453844 -132.71754) (xy 27.453844 -131.80187) (xy 26.870152 -131.218432)
			(xy 26.29916 -131.218432) (xy 26.285287 -131.218815) (xy 26.258569 -131.226293) (xy 26.234848 -131.240685)
			(xy 26.215876 -131.260931) (xy 26.203053 -131.285535) (xy 26.197325 -131.312683) (xy 26.199115 -131.340371)
			(xy 26.20829 -131.366555) (xy 26.215848 -131.378198) (xy 26.232215 -131.402398) (xy 26.258137 -131.454753)
			(xy 26.275758 -131.510452) (xy 26.284666 -131.56819) (xy 26.28519 -131.5974) (xy 26.284704 -131.624651)
			(xy 26.276948 -131.678599) (xy 26.261593 -131.730894) (xy 26.238951 -131.780471) (xy 26.209485 -131.826321)
			(xy 26.173794 -131.867512) (xy 26.132603 -131.903203) (xy 26.086753 -131.932669) (xy 26.037176 -131.955311)
			(xy 25.984881 -131.970666) (xy 25.930933 -131.978422) (xy 25.876431 -131.978422) (xy 25.822483 -131.970666)
			(xy 25.770188 -131.955311) (xy 25.720611 -131.932669) (xy 25.674761 -131.903203) (xy 25.63357 -131.867512)
			(xy 25.597879 -131.826321) (xy 25.568413 -131.780471) (xy 25.545771 -131.730894) (xy 25.530416 -131.678599)
			(xy 25.52266 -131.624651) (xy 25.522174 -131.5974) (xy 25.522829 -131.564741) (xy 25.533946 -131.500375)
			(xy 25.544272 -131.469384) (xy 25.548512 -131.456463) (xy 25.550554 -131.429351) (xy 25.545376 -131.40266)
			(xy 25.533345 -131.378277) (xy 25.515313 -131.357929) (xy 25.492555 -131.343053) (xy 25.46668 -131.334703)
			(xy 25.439519 -131.333468) (xy 25.426162 -131.336034) (xy 25.405486 -131.340428) (xy 25.363478 -131.345136)
			(xy 25.342342 -131.345432) (xy 25.315089 -131.344924) (xy 25.261137 -131.337172) (xy 25.208837 -131.321821)
			(xy 25.159255 -131.299182) (xy 25.113399 -131.269717) (xy 25.072204 -131.234025) (xy 25.036508 -131.192834)
			(xy 25.007038 -131.146982) (xy 24.984394 -131.097402) (xy 24.969037 -131.045104) (xy 24.961279 -130.991153)
			(xy 21.361908 -130.991153) (xy 21.361908 -132.264658) (xy 26.43708 -132.264658) (xy 26.441151 -132.209036)
			(xy 26.453277 -132.154599) (xy 26.4732 -132.102508) (xy 26.500496 -132.053873) (xy 26.534582 -132.00973)
			(xy 26.574731 -131.971021) (xy 26.620089 -131.93857) (xy 26.669689 -131.913069) (xy 26.722473 -131.895062)
			(xy 26.777316 -131.884932) (xy 26.83305 -131.882895) (xy 26.888487 -131.888995) (xy 26.942444 -131.903101)
			(xy 26.993773 -131.924913) (xy 27.041379 -131.953967) (xy 27.084247 -131.989642) (xy 27.121464 -132.031179)
			(xy 27.152237 -132.077692) (xy 27.175909 -132.128189) (xy 27.191977 -132.181596) (xy 27.200097 -132.236772)
			(xy 27.200606 -132.264658) (xy 27.200097 -132.292544) (xy 27.191977 -132.34772) (xy 27.175909 -132.401127)
			(xy 27.152237 -132.451624) (xy 27.121464 -132.498137) (xy 27.084247 -132.539674) (xy 27.041379 -132.575349)
			(xy 26.993773 -132.604403) (xy 26.942444 -132.626215) (xy 26.888487 -132.640321) (xy 26.83305 -132.646421)
			(xy 26.777316 -132.644384) (xy 26.722473 -132.634254) (xy 26.669689 -132.616247) (xy 26.620089 -132.590746)
			(xy 26.574731 -132.558295) (xy 26.534582 -132.519586) (xy 26.500496 -132.475443) (xy 26.4732 -132.426808)
			(xy 26.453277 -132.374717) (xy 26.441151 -132.32028) (xy 26.43708 -132.264658) (xy 21.361908 -132.264658)
			(xy 21.361908 -133.707454) (xy 24.988455 -133.707454) (xy 24.988455 -133.652946) (xy 24.996213 -133.598994)
			(xy 25.01157 -133.546694) (xy 25.034214 -133.497113) (xy 25.063684 -133.451259) (xy 25.09938 -133.410065)
			(xy 25.140575 -133.374372) (xy 25.18643 -133.344904) (xy 25.236013 -133.322263) (xy 25.288313 -133.306909)
			(xy 25.342266 -133.299154) (xy 25.36952 -133.298692) (xy 25.396254 -133.299149) (xy 25.449201 -133.306606)
			(xy 25.500586 -133.321385) (xy 25.549404 -133.343196) (xy 25.594697 -133.371611) (xy 25.635578 -133.406075)
			(xy 25.653746 -133.425692) (xy 26.026872 -133.425692) (xy 26.051868 -133.426326) (xy 26.100892 -133.436128)
			(xy 26.147063 -133.455302) (xy 26.188609 -133.483112) (xy 26.206704 -133.500368) (xy 26.893439 -134.187057)
			(xy 28.166707 -134.187057) (xy 28.166707 -134.132543) (xy 28.174466 -134.078583) (xy 28.189825 -134.026277)
			(xy 28.212472 -133.976689) (xy 28.241945 -133.930829) (xy 28.277646 -133.88963) (xy 28.318846 -133.853932)
			(xy 28.364708 -133.824461) (xy 28.414297 -133.801817) (xy 28.466605 -133.786461) (xy 28.520565 -133.778705)
			(xy 28.547822 -133.778244) (xy 28.5742 -133.778728) (xy 28.626454 -133.785982) (xy 28.677212 -133.800363)
			(xy 28.725505 -133.821597) (xy 28.770415 -133.84928) (xy 28.811084 -133.882882) (xy 28.846739 -133.921766)
			(xy 28.876699 -133.965189) (xy 28.888944 -133.988556) (xy 28.895646 -134.000915) (xy 28.914621 -134.021643)
			(xy 28.938535 -134.036405) (xy 28.965571 -134.044077) (xy 28.993673 -134.044077) (xy 29.020709 -134.036405)
			(xy 29.044623 -134.021643) (xy 29.063598 -134.000915) (xy 29.0703 -133.988556) (xy 29.082506 -133.965166)
			(xy 29.112475 -133.921743) (xy 29.148136 -133.88286) (xy 29.188811 -133.849256) (xy 29.233725 -133.821571)
			(xy 29.282022 -133.800334) (xy 29.332783 -133.785948) (xy 29.385042 -133.778688) (xy 29.411422 -133.778244)
			(xy 29.437962 -133.778742) (xy 29.490529 -133.786115) (xy 29.541566 -133.800702) (xy 29.59009 -133.822221)
			(xy 29.635162 -133.850258) (xy 29.675915 -133.884271) (xy 29.71156 -133.923603) (xy 29.741411 -133.967495)
			(xy 29.75356 -133.991096) (xy 29.760607 -134.004333) (xy 29.781101 -134.026212) (xy 29.807058 -134.04121)
			(xy 29.836249 -134.048038) (xy 29.866165 -134.04611) (xy 29.894238 -134.035592) (xy 29.906468 -134.02691)
			(xy 29.931543 -134.008577) (xy 29.986405 -133.979453) (xy 30.045259 -133.9596) (xy 30.106552 -133.949541)
			(xy 30.137608 -133.948932) (xy 30.164862 -133.949338) (xy 30.218814 -133.957097) (xy 30.271114 -133.972454)
			(xy 30.320695 -133.995098) (xy 30.366549 -134.024568) (xy 30.407743 -134.060263) (xy 30.443437 -134.101457)
			(xy 30.472906 -134.147312) (xy 30.495549 -134.196894) (xy 30.510905 -134.249194) (xy 30.518662 -134.303146)
			(xy 30.518662 -134.357654) (xy 30.510905 -134.411606) (xy 30.495549 -134.463906) (xy 30.472906 -134.513488)
			(xy 30.443437 -134.559343) (xy 30.407743 -134.600537) (xy 30.366549 -134.636232) (xy 30.320695 -134.665702)
			(xy 30.271114 -134.688346) (xy 30.218814 -134.703703) (xy 30.164862 -134.711462) (xy 30.137608 -134.711948)
			(xy 30.111066 -134.711513) (xy 30.058496 -134.70413) (xy 30.007457 -134.689533) (xy 29.958933 -134.668005)
			(xy 29.913861 -134.639959) (xy 29.873109 -134.605939) (xy 29.837466 -134.566599) (xy 29.807618 -134.5227)
			(xy 29.79547 -134.499096) (xy 29.788388 -134.48588) (xy 29.767901 -134.464005) (xy 29.741952 -134.449007)
			(xy 29.71277 -134.442176) (xy 29.68286 -134.444097) (xy 29.654792 -134.454606) (xy 29.642562 -134.463282)
			(xy 29.617477 -134.4816) (xy 29.562619 -134.510728) (xy 29.503768 -134.530585) (xy 29.442477 -134.540648)
			(xy 29.411422 -134.54126) (xy 29.38504 -134.540875) (xy 29.332779 -134.533611) (xy 29.282017 -134.519218)
			(xy 29.23372 -134.497972) (xy 29.18881 -134.470275) (xy 29.148143 -134.436658) (xy 29.112493 -134.39776)
			(xy 29.082541 -134.354322) (xy 29.0703 -134.330948) (xy 29.063598 -134.318589) (xy 29.044623 -134.297861)
			(xy 29.020709 -134.283099) (xy 28.993673 -134.275427) (xy 28.965571 -134.275427) (xy 28.938535 -134.283099)
			(xy 28.914621 -134.297861) (xy 28.895646 -134.318589) (xy 28.888944 -134.330948) (xy 28.876706 -134.35432)
			(xy 28.846742 -134.397742) (xy 28.811085 -134.436626) (xy 28.770415 -134.470231) (xy 28.725505 -134.497917)
			(xy 28.677213 -134.519158) (xy 28.626456 -134.533548) (xy 28.574201 -134.540813) (xy 28.547822 -134.54126)
			(xy 28.520565 -134.540895) (xy 28.466605 -134.533139) (xy 28.414297 -134.517783) (xy 28.364708 -134.495139)
			(xy 28.318847 -134.465668) (xy 28.277646 -134.42997) (xy 28.241945 -134.388771) (xy 28.212472 -134.342911)
			(xy 28.189825 -134.293323) (xy 28.174466 -134.241017) (xy 28.166707 -134.187057) (xy 26.893439 -134.187057)
			(xy 27.847004 -135.140557) (xy 32.578423 -135.140557) (xy 32.578423 -135.086043) (xy 32.586182 -135.032083)
			(xy 32.601542 -134.979777) (xy 32.62419 -134.930189) (xy 32.653665 -134.88433) (xy 32.689366 -134.843133)
			(xy 32.730568 -134.807436) (xy 32.776431 -134.777967) (xy 32.826022 -134.755325) (xy 32.87833 -134.739972)
			(xy 32.932291 -134.73222) (xy 32.959548 -134.73176) (xy 32.98633 -134.732183) (xy 33.039367 -134.739689)
			(xy 33.090834 -134.754533) (xy 33.139722 -134.776423) (xy 33.185071 -134.804931) (xy 33.225992 -134.839496)
			(xy 33.26168 -134.87944) (xy 33.291437 -134.92398) (xy 33.303464 -134.947914) (xy 33.309986 -134.960369)
			(xy 33.328576 -134.98144) (xy 33.352213 -134.996636) (xy 33.379101 -135.004802) (xy 33.407196 -135.005317)
			(xy 33.434365 -134.998143) (xy 33.458543 -134.983824) (xy 33.477894 -134.963448) (xy 33.48482 -134.951216)
			(xy 33.497242 -134.928438) (xy 33.527358 -134.886189) (xy 33.562922 -134.848411) (xy 33.603278 -134.815801)
			(xy 33.647681 -134.788962) (xy 33.695312 -134.768389) (xy 33.745292 -134.75446) (xy 33.796698 -134.747434)
			(xy 33.82264 -134.747) (xy 33.84989 -134.747473) (xy 33.903834 -134.755234) (xy 33.956126 -134.770593)
			(xy 34.005699 -134.793237) (xy 34.051545 -134.822705) (xy 34.092731 -134.858397) (xy 34.128419 -134.899587)
			(xy 34.157883 -134.945436) (xy 34.180521 -134.995012) (xy 34.195875 -135.047305) (xy 34.20363 -135.10125)
			(xy 34.20363 -135.15575) (xy 34.195875 -135.209695) (xy 34.180521 -135.261988) (xy 34.157883 -135.311564)
			(xy 34.128419 -135.357413) (xy 34.092731 -135.398603) (xy 34.051545 -135.434295) (xy 34.005699 -135.463763)
			(xy 33.956126 -135.486407) (xy 33.903834 -135.501766) (xy 33.84989 -135.509527) (xy 33.82264 -135.510016)
			(xy 33.795859 -135.509561) (xy 33.742826 -135.502055) (xy 33.691361 -135.487213) (xy 33.642475 -135.465326)
			(xy 33.597127 -135.436823) (xy 33.556206 -135.402264) (xy 33.520515 -135.362326) (xy 33.490754 -135.317793)
			(xy 33.478724 -135.293862) (xy 33.472219 -135.281399) (xy 33.453623 -135.260331) (xy 33.429984 -135.245139)
			(xy 33.403095 -135.236976) (xy 33.374999 -135.236462) (xy 33.347829 -135.243636) (xy 33.32365 -135.257954)
			(xy 33.304296 -135.278328) (xy 33.297368 -135.29056) (xy 33.284913 -135.313319) (xy 33.254798 -135.355564)
			(xy 33.219236 -135.393339) (xy 33.178885 -135.425948) (xy 33.134487 -135.452788) (xy 33.086863 -135.473366)
			(xy 33.036889 -135.487301) (xy 32.985488 -135.494337) (xy 32.959548 -135.494776) (xy 32.932291 -135.49438)
			(xy 32.87833 -135.486628) (xy 32.826022 -135.471275) (xy 32.776431 -135.448633) (xy 32.730568 -135.419164)
			(xy 32.689366 -135.383467) (xy 32.653665 -135.34227) (xy 32.62419 -135.296411) (xy 32.601542 -135.246823)
			(xy 32.586182 -135.194517) (xy 32.578423 -135.140557) (xy 27.847004 -135.140557) (xy 29.95803 -137.25144)
			(xy 31.0007 -137.25144) (xy 31.025696 -137.252071) (xy 31.074719 -137.261876) (xy 31.11809 -137.279888)
			(xy 33.298892 -137.279888) (xy 33.299358 -137.253509) (xy 33.306612 -137.201253) (xy 33.320994 -137.150494)
			(xy 33.34223 -137.102199) (xy 33.369914 -137.057289) (xy 33.403521 -137.01662) (xy 33.442408 -136.980967)
			(xy 33.485835 -136.95101) (xy 33.509204 -136.938766) (xy 33.521569 -136.932079) (xy 33.542292 -136.913098)
			(xy 33.557047 -136.889181) (xy 33.564715 -136.862146) (xy 33.564714 -136.834044) (xy 33.557043 -136.807009)
			(xy 33.542285 -136.783094) (xy 33.52156 -136.764115) (xy 33.509204 -136.75741) (xy 33.48583 -136.745175)
			(xy 33.442405 -136.715213) (xy 33.403519 -136.679557) (xy 33.369913 -136.638886) (xy 33.342226 -136.593976)
			(xy 33.320987 -136.545682) (xy 33.306599 -136.494923) (xy 33.299336 -136.442667) (xy 33.298892 -136.416288)
			(xy 33.299378 -136.389037) (xy 33.307134 -136.335089) (xy 33.322489 -136.282794) (xy 33.345131 -136.233217)
			(xy 33.374597 -136.187367) (xy 33.410288 -136.146176) (xy 33.451479 -136.110485) (xy 33.497329 -136.081019)
			(xy 33.546906 -136.058377) (xy 33.599201 -136.043022) (xy 33.653149 -136.035266) (xy 33.707651 -136.035266)
			(xy 33.761599 -136.043022) (xy 33.813894 -136.058377) (xy 33.863471 -136.081019) (xy 33.909321 -136.110485)
			(xy 33.950512 -136.146176) (xy 33.986203 -136.187367) (xy 34.015669 -136.233217) (xy 34.038311 -136.282794)
			(xy 34.053666 -136.335089) (xy 34.061422 -136.389037) (xy 34.061908 -136.416288) (xy 34.061505 -136.442669)
			(xy 34.05424 -136.494928) (xy 34.039849 -136.545689) (xy 34.018604 -136.593984) (xy 33.99091 -136.638893)
			(xy 33.957296 -136.679561) (xy 33.918402 -136.715212) (xy 33.874968 -136.745168) (xy 33.851596 -136.75741)
			(xy 33.839252 -136.764132) (xy 33.818532 -136.783108) (xy 33.803777 -136.807018) (xy 33.796107 -136.834047)
			(xy 33.796106 -136.862143) (xy 33.803772 -136.889173) (xy 33.818525 -136.913084) (xy 33.839243 -136.932062)
			(xy 33.851596 -136.938766) (xy 33.87496 -136.951019) (xy 33.918385 -136.980979) (xy 33.957271 -137.016632)
			(xy 33.990878 -137.0573) (xy 34.018565 -137.102207) (xy 34.039807 -137.150499) (xy 34.054197 -137.201255)
			(xy 34.061462 -137.25351) (xy 34.061908 -137.279888) (xy 34.061422 -137.307139) (xy 34.053666 -137.361087)
			(xy 34.038311 -137.413382) (xy 34.015669 -137.462959) (xy 33.986203 -137.508809) (xy 33.950512 -137.55)
			(xy 33.909321 -137.585691) (xy 33.863471 -137.615157) (xy 33.813894 -137.637799) (xy 33.761599 -137.653154)
			(xy 33.707651 -137.66091) (xy 33.653149 -137.66091) (xy 33.599201 -137.653154) (xy 33.546906 -137.637799)
			(xy 33.497329 -137.615157) (xy 33.451479 -137.585691) (xy 33.410288 -137.55) (xy 33.374597 -137.508809)
			(xy 33.345131 -137.462959) (xy 33.322489 -137.413382) (xy 33.307134 -137.361087) (xy 33.299378 -137.307139)
			(xy 33.298892 -137.279888) (xy 31.11809 -137.279888) (xy 31.12089 -137.281051) (xy 31.162436 -137.30886)
			(xy 31.180532 -137.326116) (xy 38.025832 -144.171416) (xy 38.043077 -144.189522) (xy 38.070892 -144.231062)
			(xy 38.090069 -144.27723) (xy 38.099871 -144.326252) (xy 38.100508 -144.351248) (xy 38.100508 -159.08147)
			(xy 50.99304 -159.08147) (xy 50.993427 -159.054214) (xy 51.001189 -159.000258) (xy 51.016552 -158.947956)
			(xy 51.039201 -158.898372) (xy 51.068677 -158.852517) (xy 51.104379 -158.811323) (xy 51.145579 -158.77563)
			(xy 51.191441 -158.746164) (xy 51.241029 -158.723524) (xy 51.293334 -158.708173) (xy 51.347292 -158.700422)
			(xy 51.374548 -158.699962) (xy 51.402122 -158.700442) (xy 51.456695 -158.708388) (xy 51.509556 -158.724109)
			(xy 51.559603 -158.747276) (xy 51.605792 -158.777408) (xy 51.647163 -158.813875) (xy 51.665378 -158.834582)
			(xy 51.675276 -158.84548) (xy 51.699926 -158.861555) (xy 51.728134 -158.869939) (xy 51.757562 -158.869939)
			(xy 51.78577 -158.861555) (xy 51.81042 -158.84548) (xy 51.820318 -158.834582) (xy 51.838512 -158.813855)
			(xy 51.879885 -158.777387) (xy 51.926079 -158.747257) (xy 51.97613 -158.724094) (xy 52.028995 -158.708381)
			(xy 52.083572 -158.700445) (xy 52.111148 -158.699962) (xy 52.137649 -158.700415) (xy 52.19014 -158.707762)
			(xy 52.241107 -158.722307) (xy 52.289569 -158.74377) (xy 52.334592 -158.771737) (xy 52.355242 -158.788354)
			(xy 52.367396 -158.797784) (xy 52.395794 -158.809573) (xy 52.426411 -158.812397) (xy 52.456486 -158.806003)
			(xy 52.483306 -158.790967) (xy 52.504451 -158.768645) (xy 52.511706 -158.75508) (xy 52.523817 -158.731395)
			(xy 52.553737 -158.687413) (xy 52.589605 -158.64813) (xy 52.630693 -158.614345) (xy 52.653184 -158.60014)
			(xy 52.665431 -158.592248) (xy 52.685104 -158.570769) (xy 52.697907 -158.544607) (xy 52.702796 -158.515894)
			(xy 52.699373 -158.486969) (xy 52.694078 -158.473394) (xy 52.684593 -158.450182) (xy 52.671241 -158.40185)
			(xy 52.664511 -158.352161) (xy 52.664106 -158.32709) (xy 52.66454 -158.302021) (xy 52.671286 -158.252338)
			(xy 52.684614 -158.204004) (xy 52.694078 -158.180786) (xy 52.699333 -158.167207) (xy 52.702713 -158.138299)
			(xy 52.697811 -158.10961) (xy 52.685024 -158.083464) (xy 52.665389 -158.06198) (xy 52.653184 -158.05404)
			(xy 52.630024 -158.039514) (xy 52.587899 -158.004668) (xy 52.551317 -157.964041) (xy 52.521063 -157.918506)
			(xy 52.497786 -157.869039) (xy 52.481986 -157.816703) (xy 52.474001 -157.762619) (xy 52.474003 -157.70795)
			(xy 52.481993 -157.653867) (xy 52.497797 -157.601532) (xy 52.521079 -157.552067) (xy 52.551336 -157.506534)
			(xy 52.587922 -157.465911) (xy 52.630049 -157.431068) (xy 52.653184 -157.4165) (xy 52.66539 -157.408551)
			(xy 52.685063 -157.387088) (xy 52.697871 -157.360941) (xy 52.702771 -157.332241) (xy 52.699363 -157.303326)
			(xy 52.694078 -157.289754) (xy 52.684581 -157.266547) (xy 52.671233 -157.218213) (xy 52.664508 -157.168522)
			(xy 52.664106 -157.14345) (xy 52.664627 -157.115565) (xy 52.672939 -157.060418) (xy 52.689377 -157.007126)
			(xy 52.713575 -156.95688) (xy 52.744991 -156.910801) (xy 52.782924 -156.869919) (xy 52.826526 -156.835147)
			(xy 52.874824 -156.807262) (xy 52.926739 -156.786887) (xy 52.98111 -156.774477) (xy 53.036724 -156.77031)
			(xy 53.092338 -156.774477) (xy 53.146709 -156.786887) (xy 53.198624 -156.807262) (xy 53.246922 -156.835147)
			(xy 53.290524 -156.869919) (xy 53.328457 -156.910801) (xy 53.359873 -156.95688) (xy 53.384071 -157.007126)
			(xy 53.400509 -157.060418) (xy 53.408821 -157.115565) (xy 53.409342 -157.14345) (xy 53.408875 -157.170782)
			(xy 53.400906 -157.224863) (xy 53.385118 -157.277198) (xy 53.36185 -157.326662) (xy 53.331601 -157.372195)
			(xy 53.295022 -157.412817) (xy 53.252897 -157.447655) (xy 53.229764 -157.46222) (xy 53.217537 -157.470138)
			(xy 53.19787 -157.491612) (xy 53.185068 -157.517767) (xy 53.180173 -157.546472) (xy 53.183584 -157.575392)
			(xy 53.18887 -157.588966) (xy 53.198345 -157.612181) (xy 53.211701 -157.660512) (xy 53.218435 -157.710199)
			(xy 53.218842 -157.73527) (xy 53.218431 -157.76034) (xy 53.211677 -157.810023) (xy 53.198339 -157.858357)
			(xy 53.18887 -157.881574) (xy 53.183624 -157.895151) (xy 53.180262 -157.924051) (xy 53.185173 -157.952729)
			(xy 53.197961 -157.978863) (xy 53.217591 -158.000338) (xy 53.229764 -158.00832) (xy 53.252885 -158.022903)
			(xy 53.295003 -158.057747) (xy 53.331579 -158.098369) (xy 53.361829 -158.143898) (xy 53.385103 -158.193358)
			(xy 53.400902 -158.245688) (xy 53.408888 -158.299764) (xy 53.408889 -158.354426) (xy 53.400905 -158.408502)
			(xy 53.385107 -158.460832) (xy 53.361834 -158.510292) (xy 53.331585 -158.555823) (xy 53.29501 -158.596446)
			(xy 53.252893 -158.631291) (xy 53.229764 -158.64586) (xy 53.217509 -158.653739) (xy 53.197842 -158.675225)
			(xy 53.185043 -158.70139) (xy 53.180156 -158.730104) (xy 53.183577 -158.75903) (xy 53.18887 -158.772606)
			(xy 53.198357 -158.795817) (xy 53.211708 -158.844149) (xy 53.218438 -158.893838) (xy 53.218842 -158.91891)
			(xy 53.21837 -158.945752) (xy 53.210665 -158.998881) (xy 53.195416 -159.050354) (xy 53.172938 -159.099106)
			(xy 53.143697 -159.144127) (xy 53.108298 -159.184487) (xy 53.067473 -159.219349) (xy 53.022069 -159.247993)
			(xy 52.973024 -159.269824) (xy 52.947316 -159.277558) (xy 52.932841 -159.282276) (xy 52.907286 -159.298788)
			(xy 52.887726 -159.322092) (xy 52.875894 -159.350122) (xy 52.87284 -159.380393) (xy 52.878835 -159.410222)
			(xy 52.885594 -159.423862) (xy 52.900228 -159.452008) (xy 52.920955 -159.511959) (xy 52.931453 -159.574517)
			(xy 52.932076 -159.606234) (xy 52.931855 -159.624253) (xy 52.928421 -159.660128) (xy 52.925218 -159.677862)
			(xy 52.922936 -159.693077) (xy 52.926453 -159.723622) (xy 52.938901 -159.751736) (xy 52.959153 -159.774871)
			(xy 52.985373 -159.790931) (xy 53.000148 -159.79521) (xy 53.027191 -159.802611) (xy 53.078917 -159.824241)
			(xy 53.126922 -159.853205) (xy 53.170174 -159.88888) (xy 53.207741 -159.930499) (xy 53.238815 -159.977165)
			(xy 53.262728 -160.027876) (xy 53.278965 -160.08154) (xy 53.287177 -160.137001) (xy 53.287676 -160.165034)
			(xy 53.287254 -160.192288) (xy 53.279492 -160.246239) (xy 53.264131 -160.298537) (xy 53.241483 -160.348117)
			(xy 53.21201 -160.393968) (xy 53.176312 -160.435159) (xy 53.135115 -160.47085) (xy 53.089259 -160.500315)
			(xy 53.039675 -160.522954) (xy 52.987375 -160.538306) (xy 52.933422 -160.546058) (xy 52.906168 -160.546542)
			(xy 52.878594 -160.54605) (xy 52.824022 -160.538105) (xy 52.771161 -160.522387) (xy 52.721115 -160.499222)
			(xy 52.674925 -160.469093) (xy 52.633554 -160.432628) (xy 52.615338 -160.411922) (xy 52.60544 -160.401024)
			(xy 52.58079 -160.384949) (xy 52.552582 -160.376565) (xy 52.523154 -160.376565) (xy 52.494946 -160.384949)
			(xy 52.470296 -160.401024) (xy 52.460398 -160.411922) (xy 52.442183 -160.432628) (xy 52.400812 -160.469093)
			(xy 52.354622 -160.49922) (xy 52.304575 -160.522383) (xy 52.251714 -160.538099) (xy 52.197142 -160.546039)
			(xy 52.141994 -160.546039) (xy 52.087422 -160.538099) (xy 52.034561 -160.522383) (xy 51.984514 -160.49922)
			(xy 51.938324 -160.469093) (xy 51.896953 -160.432628) (xy 51.878738 -160.411922) (xy 51.86884 -160.401024)
			(xy 51.84419 -160.384949) (xy 51.815982 -160.376565) (xy 51.786554 -160.376565) (xy 51.758346 -160.384949)
			(xy 51.733696 -160.401024) (xy 51.723798 -160.411922) (xy 51.705596 -160.432642) (xy 51.664225 -160.46911)
			(xy 51.618033 -160.499241) (xy 51.567983 -160.522405) (xy 51.515119 -160.53812) (xy 51.460543 -160.546058)
			(xy 51.432968 -160.546542) (xy 51.405718 -160.546052) (xy 51.351772 -160.538292) (xy 51.299479 -160.522935)
			(xy 51.249904 -160.500292) (xy 51.204055 -160.470826) (xy 51.162866 -160.435135) (xy 51.127175 -160.393946)
			(xy 51.097709 -160.348098) (xy 51.075066 -160.298523) (xy 51.059708 -160.24623) (xy 51.051948 -160.192284)
			(xy 51.05146 -160.165034) (xy 51.052043 -160.137181) (xy 51.060161 -160.08207) (xy 51.0762 -160.028722)
			(xy 51.09982 -159.978272) (xy 51.130519 -159.931788) (xy 51.167647 -159.890258) (xy 51.210414 -159.854563)
			(xy 51.257914 -159.825461) (xy 51.309138 -159.803569) (xy 51.33594 -159.795972) (xy 51.350063 -159.791719)
			(xy 51.375204 -159.77632) (xy 51.394916 -159.754396) (xy 51.407566 -159.727764) (xy 51.412104 -159.698632)
			(xy 51.410616 -159.683958) (xy 51.408945 -159.670942) (xy 51.407166 -159.644757) (xy 51.40706 -159.631634)
			(xy 51.407158 -159.617485) (xy 51.409189 -159.589262) (xy 51.411124 -159.575246) (xy 51.412683 -159.561896)
			(xy 51.409585 -159.535209) (xy 51.39962 -159.510259) (xy 51.38348 -159.488781) (xy 51.362288 -159.472267)
			(xy 51.337516 -159.461867) (xy 51.324256 -159.459676) (xy 51.297113 -159.45553) (xy 51.244287 -159.440561)
			(xy 51.194152 -159.418174) (xy 51.147744 -159.388832) (xy 51.106021 -159.353141) (xy 51.069844 -159.311838)
			(xy 51.039961 -159.265777) (xy 51.016989 -159.215907) (xy 51.001402 -159.16326) (xy 50.993522 -159.108923)
			(xy 50.99304 -159.08147) (xy 38.100508 -159.08147) (xy 38.100508 -161.891218) (xy 43.505377 -161.891218)
			(xy 43.509413 -161.807771) (xy 43.521485 -161.725103) (xy 43.541478 -161.643986) (xy 43.569207 -161.565177)
			(xy 43.604413 -161.489412) (xy 43.646767 -161.417399) (xy 43.695873 -161.34981) (xy 43.751274 -161.287276)
			(xy 43.812451 -161.230381) (xy 43.878834 -161.179655) (xy 43.949802 -161.135574) (xy 44.024694 -161.098548)
			(xy 44.10281 -161.068922) (xy 44.18342 -161.046974) (xy 44.265772 -161.032909) (xy 44.349098 -161.026857)
			(xy 44.432618 -161.028876) (xy 44.515554 -161.038946) (xy 44.59713 -161.056974) (xy 44.676586 -161.082791)
			(xy 44.753179 -161.116156) (xy 44.826195 -161.156757) (xy 44.894951 -161.204216) (xy 44.958805 -161.258089)
			(xy 45.017162 -161.317874) (xy 45.069477 -161.383011) (xy 45.11526 -161.452894) (xy 45.154085 -161.526869)
			(xy 45.18559 -161.604246) (xy 45.209479 -161.684303) (xy 45.224439 -161.76072) (xy 51.012924 -161.76072)
			(xy 51.012928 -161.706227) (xy 51.020687 -161.652288) (xy 51.036042 -161.600003) (xy 51.058683 -161.550435)
			(xy 51.088146 -161.504593) (xy 51.123834 -161.463411) (xy 51.165019 -161.427727) (xy 51.210863 -161.398267)
			(xy 51.260433 -161.375631) (xy 51.312719 -161.36028) (xy 51.366659 -161.352526) (xy 51.421152 -161.352526)
			(xy 51.475091 -161.360282) (xy 51.527377 -161.375635) (xy 51.576946 -161.398272) (xy 51.62279 -161.427734)
			(xy 51.663974 -161.463419) (xy 51.69966 -161.504602) (xy 51.729122 -161.550444) (xy 51.736434 -161.566455)
			(xy 53.058229 -161.566455) (xy 53.058229 -161.511945) (xy 53.065987 -161.457989) (xy 53.081345 -161.405686)
			(xy 53.10399 -161.356102) (xy 53.133461 -161.310245) (xy 53.169159 -161.269049) (xy 53.210356 -161.233353)
			(xy 53.256214 -161.203883) (xy 53.305799 -161.18124) (xy 53.358102 -161.165884) (xy 53.412059 -161.158128)
			(xy 53.439314 -161.157666) (xy 53.466685 -161.158108) (xy 53.520866 -161.165929) (xy 53.57337 -161.181423)
			(xy 53.623117 -161.20427) (xy 53.669082 -161.234001) (xy 53.690012 -161.251646) (xy 53.70134 -161.260882)
			(xy 53.727897 -161.273058) (xy 53.756814 -161.277231) (xy 53.785731 -161.273058) (xy 53.812288 -161.260882)
			(xy 53.823616 -161.251646) (xy 53.844575 -161.23404) (xy 53.89054 -161.204322) (xy 53.94028 -161.181479)
			(xy 53.992775 -161.16598) (xy 54.046947 -161.158144) (xy 54.074314 -161.157666) (xy 54.101563 -161.158205)
			(xy 54.155505 -161.165963) (xy 54.207795 -161.181318) (xy 54.257367 -161.203958) (xy 54.303212 -161.233423)
			(xy 54.344398 -161.269112) (xy 54.380085 -161.310299) (xy 54.409548 -161.356146) (xy 54.432187 -161.405719)
			(xy 54.44754 -161.458009) (xy 54.455296 -161.511951) (xy 54.455296 -161.566449) (xy 54.44754 -161.620391)
			(xy 54.432187 -161.672681) (xy 54.409548 -161.722254) (xy 54.380085 -161.768101) (xy 54.344398 -161.809288)
			(xy 54.303212 -161.844977) (xy 54.257367 -161.874442) (xy 54.207795 -161.897082) (xy 54.155505 -161.912437)
			(xy 54.101563 -161.920195) (xy 54.074314 -161.920682) (xy 54.046944 -161.920212) (xy 53.992765 -161.912396)
			(xy 53.940262 -161.896908) (xy 53.890515 -161.874067) (xy 53.844548 -161.844343) (xy 53.823616 -161.826702)
			(xy 53.812288 -161.817466) (xy 53.785731 -161.80529) (xy 53.756814 -161.801117) (xy 53.727897 -161.80529)
			(xy 53.70134 -161.817466) (xy 53.690012 -161.826702) (xy 53.669086 -161.844349) (xy 53.623112 -161.87406)
			(xy 53.573363 -161.896894) (xy 53.520861 -161.912383) (xy 53.466684 -161.920209) (xy 53.439314 -161.920682)
			(xy 53.412059 -161.920272) (xy 53.358102 -161.912516) (xy 53.305799 -161.89716) (xy 53.256214 -161.874517)
			(xy 53.210356 -161.845047) (xy 53.169159 -161.809351) (xy 53.133461 -161.768155) (xy 53.10399 -161.722298)
			(xy 53.081345 -161.672714) (xy 53.065987 -161.620411) (xy 53.058229 -161.566455) (xy 51.736434 -161.566455)
			(xy 51.751761 -161.600013) (xy 51.767116 -161.652299) (xy 51.774873 -161.706237) (xy 51.77536 -161.733484)
			(xy 51.77493 -161.758875) (xy 51.768173 -161.809207) (xy 51.761898 -161.833814) (xy 51.758525 -161.848472)
			(xy 51.759445 -161.878518) (xy 51.769069 -161.906996) (xy 51.786564 -161.93144) (xy 51.810415 -161.949736)
			(xy 51.838559 -161.960299) (xy 51.868558 -161.962215) (xy 51.88331 -161.95929) (xy 51.90484 -161.954535)
			(xy 51.948639 -161.949442) (xy 51.970686 -161.94913) (xy 51.97094 -161.94913) (xy 51.998187 -161.949621)
			(xy 52.052126 -161.957382) (xy 52.104412 -161.972739) (xy 52.153979 -161.995381) (xy 52.199821 -162.024847)
			(xy 52.241002 -162.060536) (xy 52.276686 -162.101723) (xy 52.306145 -162.147568) (xy 52.32878 -162.197139)
			(xy 52.34413 -162.249427) (xy 52.351883 -162.303367) (xy 52.351881 -162.357861) (xy 52.344124 -162.411801)
			(xy 52.32877 -162.464087) (xy 52.306131 -162.513657) (xy 52.276669 -162.5595) (xy 52.240982 -162.600684)
			(xy 52.199798 -162.63637) (xy 52.153955 -162.665832) (xy 52.104385 -162.688471) (xy 52.052099 -162.703824)
			(xy 51.998159 -162.711581) (xy 51.943665 -162.711583) (xy 51.889725 -162.703829) (xy 51.837437 -162.688479)
			(xy 51.787866 -162.665844) (xy 51.742021 -162.636384) (xy 51.700835 -162.600701) (xy 51.665146 -162.559519)
			(xy 51.63568 -162.513678) (xy 51.613039 -162.46411) (xy 51.597681 -162.411824) (xy 51.589921 -162.357885)
			(xy 51.589432 -162.330638) (xy 51.589867 -162.305247) (xy 51.596621 -162.254916) (xy 51.602894 -162.230308)
			(xy 51.606253 -162.215646) (xy 51.605338 -162.185601) (xy 51.595718 -162.157123) (xy 51.578225 -162.132677)
			(xy 51.554375 -162.114382) (xy 51.526232 -162.10382) (xy 51.496234 -162.101906) (xy 51.481482 -162.104832)
			(xy 51.459952 -162.109589) (xy 51.416153 -162.11468) (xy 51.394106 -162.114992) (xy 51.393852 -162.114992)
			(xy 51.366605 -162.11447) (xy 51.312667 -162.106709) (xy 51.260383 -162.09135) (xy 51.210816 -162.068707)
			(xy 51.164976 -162.039241) (xy 51.123796 -162.003551) (xy 51.088114 -161.962364) (xy 51.058657 -161.916518)
			(xy 51.036024 -161.866947) (xy 51.020675 -161.81466) (xy 51.012924 -161.76072) (xy 45.224439 -161.76072)
			(xy 45.22553 -161.766291) (xy 45.233593 -161.849446) (xy 45.234098 -161.891218) (xy 45.233593 -161.93299)
			(xy 45.22553 -162.016145) (xy 45.209479 -162.098133) (xy 45.18559 -162.17819) (xy 45.154085 -162.255567)
			(xy 45.11526 -162.329542) (xy 45.069477 -162.399425) (xy 45.017162 -162.464562) (xy 44.958805 -162.524347)
			(xy 44.894951 -162.57822) (xy 44.826195 -162.625679) (xy 44.753179 -162.66628) (xy 44.676586 -162.699645)
			(xy 44.59713 -162.725462) (xy 44.515554 -162.74349) (xy 44.432618 -162.75356) (xy 44.349098 -162.755579)
			(xy 44.265772 -162.749527) (xy 44.18342 -162.735462) (xy 44.10281 -162.713514) (xy 44.024694 -162.683888)
			(xy 43.949802 -162.646862) (xy 43.878834 -162.602781) (xy 43.812451 -162.552055) (xy 43.751274 -162.49516)
			(xy 43.695873 -162.432626) (xy 43.646767 -162.365037) (xy 43.604413 -162.293024) (xy 43.569207 -162.217259)
			(xy 43.541478 -162.13845) (xy 43.521485 -162.057333) (xy 43.509413 -161.974665) (xy 43.505377 -161.891218)
			(xy 38.100508 -161.891218) (xy 38.100508 -163.164052) (xy 49.996289 -163.164052) (xy 49.996289 -163.109548)
			(xy 50.004047 -163.055598) (xy 50.019404 -163.003301) (xy 50.042047 -162.953722) (xy 50.071517 -162.907871)
			(xy 50.107212 -162.866681) (xy 50.148406 -162.83099) (xy 50.194261 -162.801526) (xy 50.243842 -162.778888)
			(xy 50.296141 -162.763537) (xy 50.350092 -162.755786) (xy 50.377344 -162.755326) (xy 50.407031 -162.755911)
			(xy 50.465689 -162.765102) (xy 50.522215 -162.783271) (xy 50.575243 -162.809978) (xy 50.623492 -162.84458)
			(xy 50.665798 -162.886239) (xy 50.683922 -162.909758) (xy 50.692348 -162.920365) (xy 50.713661 -162.937072)
			(xy 50.738615 -162.947591) (xy 50.765456 -162.951181) (xy 50.792297 -162.947591) (xy 50.817251 -162.937072)
			(xy 50.838564 -162.920365) (xy 50.84699 -162.909758) (xy 50.86512 -162.886243) (xy 50.907427 -162.844585)
			(xy 50.955675 -162.809982) (xy 51.008701 -162.783271) (xy 51.065225 -162.765095) (xy 51.123881 -162.755893)
			(xy 51.153568 -162.755326) (xy 51.180825 -162.755719) (xy 51.234784 -162.763473) (xy 51.28709 -162.778827)
			(xy 51.336679 -162.80147) (xy 51.38254 -162.83094) (xy 51.423741 -162.866637) (xy 51.459441 -162.907834)
			(xy 51.488915 -162.953693) (xy 51.511561 -163.00328) (xy 51.52692 -163.055585) (xy 51.534679 -163.109543)
			(xy 51.534679 -163.164057) (xy 51.52692 -163.218015) (xy 51.511561 -163.27032) (xy 51.488915 -163.319907)
			(xy 51.459441 -163.365766) (xy 51.423741 -163.406963) (xy 51.38254 -163.44266) (xy 51.336679 -163.47213)
			(xy 51.28709 -163.494773) (xy 51.234784 -163.510127) (xy 51.180825 -163.517881) (xy 51.153568 -163.518342)
			(xy 51.123881 -163.51776) (xy 51.065222 -163.50857) (xy 51.008695 -163.490402) (xy 50.955667 -163.463694)
			(xy 50.907418 -163.429091) (xy 50.865114 -163.38743) (xy 50.84699 -163.36391) (xy 50.838564 -163.353303)
			(xy 50.817251 -163.336596) (xy 50.792297 -163.326077) (xy 50.765456 -163.322487) (xy 50.738615 -163.326077)
			(xy 50.713661 -163.336596) (xy 50.692348 -163.353303) (xy 50.683922 -163.36391) (xy 50.665776 -163.387412)
			(xy 50.623474 -163.429073) (xy 50.575229 -163.463678) (xy 50.522206 -163.490392) (xy 50.465685 -163.50857)
			(xy 50.40703 -163.517774) (xy 50.377344 -163.518342) (xy 50.350092 -163.517814) (xy 50.296141 -163.510063)
			(xy 50.243842 -163.494712) (xy 50.194261 -163.472074) (xy 50.148406 -163.44261) (xy 50.107212 -163.406919)
			(xy 50.071517 -163.365729) (xy 50.042047 -163.319878) (xy 50.019404 -163.270299) (xy 50.004047 -163.218002)
			(xy 49.996289 -163.164052) (xy 38.100508 -163.164052) (xy 38.100508 -164.433688) (xy 43.480986 -164.433688)
			(xy 43.480986 -164.348992) (xy 43.489037 -164.264678) (xy 43.505066 -164.181512) (xy 43.528927 -164.100245)
			(xy 43.560406 -164.021615) (xy 43.599217 -163.946334) (xy 43.645007 -163.875082) (xy 43.697363 -163.808506)
			(xy 43.755811 -163.747208) (xy 43.819821 -163.691743) (xy 43.888813 -163.642614) (xy 43.962163 -163.600265)
			(xy 44.039206 -163.565081) (xy 44.119245 -163.537379) (xy 44.201554 -163.517411) (xy 44.285389 -163.505358)
			(xy 44.36999 -163.501328) (xy 44.454591 -163.505358) (xy 44.538426 -163.517411) (xy 44.620735 -163.537379)
			(xy 44.700774 -163.565081) (xy 44.777817 -163.600265) (xy 44.851167 -163.642614) (xy 44.920159 -163.691743)
			(xy 44.984169 -163.747208) (xy 45.042617 -163.808506) (xy 45.094973 -163.875082) (xy 45.140763 -163.946334)
			(xy 45.179574 -164.021615) (xy 45.211053 -164.100245) (xy 45.234914 -164.181512) (xy 45.250943 -164.264678)
			(xy 45.258994 -164.348992) (xy 45.259498 -164.39134) (xy 45.258994 -164.433688) (xy 45.250943 -164.518002)
			(xy 45.234914 -164.601168) (xy 45.211053 -164.682435) (xy 45.179574 -164.761065) (xy 45.140763 -164.836346)
			(xy 45.094973 -164.907598) (xy 45.042617 -164.974174) (xy 44.984169 -165.035472) (xy 44.920159 -165.090937)
			(xy 44.851167 -165.140066) (xy 44.777817 -165.182415) (xy 44.700774 -165.217599) (xy 44.620735 -165.245301)
			(xy 44.603629 -165.249451) (xy 50.206652 -165.249451) (xy 50.206652 -165.194949) (xy 50.214408 -165.141001)
			(xy 50.229762 -165.088707) (xy 50.252401 -165.039129) (xy 50.281865 -164.993277) (xy 50.317554 -164.952086)
			(xy 50.358742 -164.916392) (xy 50.40459 -164.886922) (xy 50.454165 -164.864277) (xy 50.506458 -164.848917)
			(xy 50.560405 -164.841155) (xy 50.587656 -164.840666) (xy 50.58791 -164.840666) (xy 50.617749 -164.841247)
			(xy 50.676695 -164.850559) (xy 50.705258 -164.859208) (xy 50.719167 -164.863239) (xy 50.748099 -164.864148)
			(xy 50.776118 -164.856883) (xy 50.800963 -164.842032) (xy 50.820629 -164.820792) (xy 50.833527 -164.794879)
			(xy 50.836576 -164.780722) (xy 50.843165 -164.747884) (xy 50.866284 -164.685031) (xy 50.88255 -164.655754)
			(xy 50.889618 -164.642804) (xy 50.896647 -164.614161) (xy 50.895197 -164.584704) (xy 50.885389 -164.55689)
			(xy 50.868042 -164.533039) (xy 50.844601 -164.515141) (xy 50.830988 -164.50945) (xy 50.80422 -164.498735)
			(xy 50.753979 -164.47045) (xy 50.70857 -164.434922) (xy 50.669027 -164.392963) (xy 50.636253 -164.345528)
			(xy 50.610993 -164.2937) (xy 50.593825 -164.23866) (xy 50.585139 -164.181662) (xy 50.584608 -164.152834)
			(xy 50.585094 -164.125583) (xy 50.59285 -164.071635) (xy 50.608205 -164.01934) (xy 50.630847 -163.969763)
			(xy 50.660313 -163.923913) (xy 50.696004 -163.882722) (xy 50.737195 -163.847031) (xy 50.783045 -163.817565)
			(xy 50.832622 -163.794923) (xy 50.884917 -163.779568) (xy 50.938865 -163.771812) (xy 50.993367 -163.771812)
			(xy 51.047315 -163.779568) (xy 51.09961 -163.794923) (xy 51.149187 -163.817565) (xy 51.195037 -163.847031)
			(xy 51.236228 -163.882722) (xy 51.271919 -163.923913) (xy 51.301385 -163.969763) (xy 51.324027 -164.01934)
			(xy 51.339382 -164.071635) (xy 51.347138 -164.125583) (xy 51.347624 -164.152834) (xy 51.347624 -164.153088)
			(xy 51.347224 -164.178292) (xy 51.340585 -164.22826) (xy 51.327409 -164.276914) (xy 51.307926 -164.323404)
			(xy 51.295554 -164.345366) (xy 51.28846 -164.358303) (xy 51.281434 -164.386951) (xy 51.282888 -164.416412)
			(xy 51.292701 -164.444229) (xy 51.310054 -164.468081) (xy 51.3335 -164.48598) (xy 51.347116 -164.49167)
			(xy 51.373892 -164.502366) (xy 51.424134 -164.530654) (xy 51.469543 -164.566184) (xy 51.509085 -164.608146)
			(xy 51.541859 -164.655583) (xy 51.567117 -164.707414) (xy 51.584283 -164.762457) (xy 51.592966 -164.819457)
			(xy 51.593496 -164.848286) (xy 51.593032 -164.875539) (xy 51.585276 -164.929491) (xy 51.569921 -164.981789)
			(xy 51.54728 -165.03137) (xy 51.517812 -165.077224) (xy 51.482118 -165.118417) (xy 51.440925 -165.154111)
			(xy 51.395072 -165.183579) (xy 51.345491 -165.206221) (xy 51.293193 -165.221576) (xy 51.239241 -165.229331)
			(xy 51.211988 -165.229794) (xy 51.211734 -165.229794) (xy 51.181895 -165.229227) (xy 51.122949 -165.219906)
			(xy 51.094386 -165.211252) (xy 51.080457 -165.207302) (xy 51.051539 -165.206385) (xy 51.02353 -165.213636)
			(xy 50.998691 -165.228471) (xy 50.979026 -165.249693) (xy 50.966122 -165.275589) (xy 50.963068 -165.289738)
			(xy 50.957919 -165.315816) (xy 50.941346 -165.36632) (xy 50.917921 -165.414034) (xy 50.888096 -165.458032)
			(xy 50.852451 -165.497463) (xy 50.811676 -165.531561) (xy 50.76656 -165.559667) (xy 50.717979 -165.581236)
			(xy 50.666873 -165.595849) (xy 50.614233 -165.603225) (xy 50.587656 -165.603682) (xy 50.560405 -165.603245)
			(xy 50.506458 -165.595483) (xy 50.454165 -165.580123) (xy 50.40459 -165.557478) (xy 50.358742 -165.528008)
			(xy 50.317554 -165.492314) (xy 50.281865 -165.451123) (xy 50.252401 -165.405271) (xy 50.229762 -165.355693)
			(xy 50.214408 -165.303399) (xy 50.206652 -165.249451) (xy 44.603629 -165.249451) (xy 44.538426 -165.265269)
			(xy 44.454591 -165.277322) (xy 44.36999 -165.281353) (xy 44.285389 -165.277322) (xy 44.201554 -165.265269)
			(xy 44.119245 -165.245301) (xy 44.039206 -165.217599) (xy 43.962163 -165.182415) (xy 43.888813 -165.140066)
			(xy 43.819821 -165.090937) (xy 43.755811 -165.035472) (xy 43.697363 -164.974174) (xy 43.645007 -164.907598)
			(xy 43.599217 -164.836346) (xy 43.560406 -164.761065) (xy 43.528927 -164.682435) (xy 43.505066 -164.601168)
			(xy 43.489037 -164.518002) (xy 43.480986 -164.433688) (xy 38.100508 -164.433688) (xy 38.100508 -167.71747)
			(xy 50.99304 -167.71747) (xy 50.993427 -167.690214) (xy 51.001189 -167.636258) (xy 51.016552 -167.583956)
			(xy 51.039201 -167.534372) (xy 51.068677 -167.488517) (xy 51.104379 -167.447323) (xy 51.145579 -167.41163)
			(xy 51.191441 -167.382164) (xy 51.241029 -167.359524) (xy 51.293334 -167.344173) (xy 51.347292 -167.336422)
			(xy 51.374548 -167.335962) (xy 51.402122 -167.336442) (xy 51.456695 -167.344388) (xy 51.509556 -167.360109)
			(xy 51.559603 -167.383276) (xy 51.605792 -167.413408) (xy 51.647163 -167.449875) (xy 51.665378 -167.470582)
			(xy 51.675276 -167.48148) (xy 51.699926 -167.497555) (xy 51.728134 -167.505939) (xy 51.757562 -167.505939)
			(xy 51.78577 -167.497555) (xy 51.81042 -167.48148) (xy 51.820318 -167.470582) (xy 51.838512 -167.449855)
			(xy 51.879885 -167.413387) (xy 51.926079 -167.383257) (xy 51.97613 -167.360094) (xy 52.028995 -167.344381)
			(xy 52.083572 -167.336445) (xy 52.111148 -167.335962) (xy 52.137649 -167.336415) (xy 52.19014 -167.343762)
			(xy 52.241107 -167.358307) (xy 52.289569 -167.37977) (xy 52.334592 -167.407737) (xy 52.355242 -167.424354)
			(xy 52.367396 -167.433784) (xy 52.395794 -167.445573) (xy 52.426411 -167.448397) (xy 52.456486 -167.442003)
			(xy 52.483306 -167.426967) (xy 52.504451 -167.404645) (xy 52.511706 -167.39108) (xy 52.523817 -167.367395)
			(xy 52.553737 -167.323413) (xy 52.589605 -167.28413) (xy 52.630693 -167.250345) (xy 52.653184 -167.23614)
			(xy 52.665431 -167.228248) (xy 52.685104 -167.206769) (xy 52.697907 -167.180607) (xy 52.702796 -167.151894)
			(xy 52.699373 -167.122969) (xy 52.694078 -167.109394) (xy 52.684593 -167.086182) (xy 52.671241 -167.03785)
			(xy 52.664511 -166.988161) (xy 52.664106 -166.96309) (xy 52.66454 -166.938021) (xy 52.671286 -166.888338)
			(xy 52.684614 -166.840004) (xy 52.694078 -166.816786) (xy 52.699333 -166.803207) (xy 52.702713 -166.774299)
			(xy 52.697811 -166.74561) (xy 52.685024 -166.719464) (xy 52.665389 -166.69798) (xy 52.653184 -166.69004)
			(xy 52.630024 -166.675514) (xy 52.587899 -166.640668) (xy 52.551317 -166.600041) (xy 52.521063 -166.554506)
			(xy 52.497786 -166.505039) (xy 52.481986 -166.452703) (xy 52.474001 -166.398619) (xy 52.474003 -166.34395)
			(xy 52.481993 -166.289867) (xy 52.497797 -166.237532) (xy 52.521079 -166.188067) (xy 52.551336 -166.142534)
			(xy 52.587922 -166.101911) (xy 52.630049 -166.067068) (xy 52.653184 -166.0525) (xy 52.66539 -166.044551)
			(xy 52.685063 -166.023088) (xy 52.697871 -165.996941) (xy 52.702771 -165.968241) (xy 52.699363 -165.939326)
			(xy 52.694078 -165.925754) (xy 52.684581 -165.902547) (xy 52.671233 -165.854213) (xy 52.664508 -165.804522)
			(xy 52.664106 -165.77945) (xy 52.664627 -165.751565) (xy 52.672939 -165.696418) (xy 52.689377 -165.643126)
			(xy 52.713575 -165.59288) (xy 52.744991 -165.546801) (xy 52.782924 -165.505919) (xy 52.826526 -165.471147)
			(xy 52.874824 -165.443262) (xy 52.926739 -165.422887) (xy 52.98111 -165.410477) (xy 53.036724 -165.40631)
			(xy 53.092338 -165.410477) (xy 53.146709 -165.422887) (xy 53.198624 -165.443262) (xy 53.246922 -165.471147)
			(xy 53.290524 -165.505919) (xy 53.328457 -165.546801) (xy 53.359873 -165.59288) (xy 53.384071 -165.643126)
			(xy 53.400509 -165.696418) (xy 53.408821 -165.751565) (xy 53.409342 -165.77945) (xy 53.408875 -165.806782)
			(xy 53.400906 -165.860863) (xy 53.385118 -165.913198) (xy 53.36185 -165.962662) (xy 53.331601 -166.008195)
			(xy 53.295022 -166.048817) (xy 53.252897 -166.083655) (xy 53.229764 -166.09822) (xy 53.217537 -166.106138)
			(xy 53.19787 -166.127612) (xy 53.185068 -166.153767) (xy 53.180173 -166.182472) (xy 53.183584 -166.211392)
			(xy 53.18887 -166.224966) (xy 53.198345 -166.248181) (xy 53.211701 -166.296512) (xy 53.218435 -166.346199)
			(xy 53.218842 -166.37127) (xy 53.218431 -166.39634) (xy 53.211677 -166.446023) (xy 53.198339 -166.494357)
			(xy 53.18887 -166.517574) (xy 53.183624 -166.531151) (xy 53.180262 -166.560051) (xy 53.185173 -166.588729)
			(xy 53.197961 -166.614863) (xy 53.217591 -166.636338) (xy 53.229764 -166.64432) (xy 53.252885 -166.658903)
			(xy 53.295003 -166.693747) (xy 53.331579 -166.734369) (xy 53.361829 -166.779898) (xy 53.385103 -166.829358)
			(xy 53.400902 -166.881688) (xy 53.408888 -166.935764) (xy 53.408889 -166.990426) (xy 53.400905 -167.044502)
			(xy 53.385107 -167.096832) (xy 53.361834 -167.146292) (xy 53.331585 -167.191823) (xy 53.29501 -167.232446)
			(xy 53.252893 -167.267291) (xy 53.229764 -167.28186) (xy 53.217509 -167.289739) (xy 53.197842 -167.311225)
			(xy 53.185043 -167.33739) (xy 53.180156 -167.366104) (xy 53.183577 -167.39503) (xy 53.18887 -167.408606)
			(xy 53.198357 -167.431817) (xy 53.211708 -167.480149) (xy 53.218438 -167.529838) (xy 53.218842 -167.55491)
			(xy 53.21837 -167.581752) (xy 53.210665 -167.634881) (xy 53.195416 -167.686354) (xy 53.172938 -167.735106)
			(xy 53.143697 -167.780127) (xy 53.108298 -167.820487) (xy 53.067473 -167.855349) (xy 53.022069 -167.883993)
			(xy 52.973024 -167.905824) (xy 52.947316 -167.913558) (xy 52.932841 -167.918276) (xy 52.907286 -167.934788)
			(xy 52.887726 -167.958092) (xy 52.875894 -167.986122) (xy 52.87284 -168.016393) (xy 52.878835 -168.046222)
			(xy 52.885594 -168.059862) (xy 52.900228 -168.088008) (xy 52.920955 -168.147959) (xy 52.931453 -168.210517)
			(xy 52.932076 -168.242234) (xy 52.931855 -168.260253) (xy 52.928421 -168.296128) (xy 52.925218 -168.313862)
			(xy 52.922936 -168.329077) (xy 52.926453 -168.359622) (xy 52.938901 -168.387736) (xy 52.959153 -168.410871)
			(xy 52.985373 -168.426931) (xy 53.000148 -168.43121) (xy 53.027191 -168.438611) (xy 53.078917 -168.460241)
			(xy 53.126922 -168.489205) (xy 53.170174 -168.52488) (xy 53.207741 -168.566499) (xy 53.238815 -168.613165)
			(xy 53.262728 -168.663876) (xy 53.278965 -168.71754) (xy 53.287177 -168.773001) (xy 53.287676 -168.801034)
			(xy 53.287254 -168.828288) (xy 53.279492 -168.882239) (xy 53.264131 -168.934537) (xy 53.241483 -168.984117)
			(xy 53.21201 -169.029968) (xy 53.176312 -169.071159) (xy 53.135115 -169.10685) (xy 53.089259 -169.136315)
			(xy 53.039675 -169.158954) (xy 52.987375 -169.174306) (xy 52.933422 -169.182058) (xy 52.906168 -169.182542)
			(xy 52.878594 -169.18205) (xy 52.824022 -169.174105) (xy 52.771161 -169.158387) (xy 52.721115 -169.135222)
			(xy 52.674925 -169.105093) (xy 52.633554 -169.068628) (xy 52.615338 -169.047922) (xy 52.60544 -169.037024)
			(xy 52.58079 -169.020949) (xy 52.552582 -169.012565) (xy 52.523154 -169.012565) (xy 52.494946 -169.020949)
			(xy 52.470296 -169.037024) (xy 52.460398 -169.047922) (xy 52.442183 -169.068628) (xy 52.400812 -169.105093)
			(xy 52.354622 -169.13522) (xy 52.304575 -169.158383) (xy 52.251714 -169.174099) (xy 52.197142 -169.182039)
			(xy 52.141994 -169.182039) (xy 52.087422 -169.174099) (xy 52.034561 -169.158383) (xy 51.984514 -169.13522)
			(xy 51.938324 -169.105093) (xy 51.896953 -169.068628) (xy 51.878738 -169.047922) (xy 51.86884 -169.037024)
			(xy 51.84419 -169.020949) (xy 51.815982 -169.012565) (xy 51.786554 -169.012565) (xy 51.758346 -169.020949)
			(xy 51.733696 -169.037024) (xy 51.723798 -169.047922) (xy 51.705596 -169.068642) (xy 51.664225 -169.10511)
			(xy 51.618033 -169.135241) (xy 51.567983 -169.158405) (xy 51.515119 -169.17412) (xy 51.460543 -169.182058)
			(xy 51.432968 -169.182542) (xy 51.405718 -169.182052) (xy 51.351772 -169.174292) (xy 51.299479 -169.158935)
			(xy 51.249904 -169.136292) (xy 51.204055 -169.106826) (xy 51.162866 -169.071135) (xy 51.127175 -169.029946)
			(xy 51.097709 -168.984098) (xy 51.075066 -168.934523) (xy 51.059708 -168.88223) (xy 51.051948 -168.828284)
			(xy 51.05146 -168.801034) (xy 51.052043 -168.773181) (xy 51.060161 -168.71807) (xy 51.0762 -168.664722)
			(xy 51.09982 -168.614272) (xy 51.130519 -168.567788) (xy 51.167647 -168.526258) (xy 51.210414 -168.490563)
			(xy 51.257914 -168.461461) (xy 51.309138 -168.439569) (xy 51.33594 -168.431972) (xy 51.350063 -168.427719)
			(xy 51.375204 -168.41232) (xy 51.394916 -168.390396) (xy 51.407566 -168.363764) (xy 51.412104 -168.334632)
			(xy 51.410616 -168.319958) (xy 51.408945 -168.306942) (xy 51.407166 -168.280757) (xy 51.40706 -168.267634)
			(xy 51.407158 -168.253485) (xy 51.409189 -168.225262) (xy 51.411124 -168.211246) (xy 51.412683 -168.197896)
			(xy 51.409585 -168.171209) (xy 51.39962 -168.146259) (xy 51.38348 -168.124781) (xy 51.362288 -168.108267)
			(xy 51.337516 -168.097867) (xy 51.324256 -168.095676) (xy 51.297113 -168.09153) (xy 51.244287 -168.076561)
			(xy 51.194152 -168.054174) (xy 51.147744 -168.024832) (xy 51.106021 -167.989141) (xy 51.069844 -167.947838)
			(xy 51.039961 -167.901777) (xy 51.016989 -167.851907) (xy 51.001402 -167.79926) (xy 50.993522 -167.744923)
			(xy 50.99304 -167.71747) (xy 38.100508 -167.71747) (xy 38.100508 -168.238678) (xy 39.663624 -169.801794)
			(xy 43.431209 -169.801794) (xy 43.435245 -169.718347) (xy 43.447317 -169.635679) (xy 43.46731 -169.554562)
			(xy 43.495039 -169.475753) (xy 43.530245 -169.399988) (xy 43.572599 -169.327975) (xy 43.621705 -169.260386)
			(xy 43.677106 -169.197852) (xy 43.738283 -169.140957) (xy 43.804666 -169.090231) (xy 43.875634 -169.04615)
			(xy 43.950526 -169.009124) (xy 44.028642 -168.979498) (xy 44.109252 -168.95755) (xy 44.191604 -168.943485)
			(xy 44.27493 -168.937433) (xy 44.35845 -168.939452) (xy 44.441386 -168.949522) (xy 44.522962 -168.96755)
			(xy 44.602418 -168.993367) (xy 44.679011 -169.026732) (xy 44.752027 -169.067333) (xy 44.820783 -169.114792)
			(xy 44.884637 -169.168665) (xy 44.942994 -169.22845) (xy 44.995309 -169.293587) (xy 45.041092 -169.36347)
			(xy 45.079917 -169.437445) (xy 45.111422 -169.514822) (xy 45.135311 -169.594879) (xy 45.151362 -169.676867)
			(xy 45.159425 -169.760022) (xy 45.15993 -169.801794) (xy 45.159425 -169.843566) (xy 45.151362 -169.926721)
			(xy 45.135311 -170.008709) (xy 45.111422 -170.088766) (xy 45.079917 -170.166143) (xy 45.041092 -170.240118)
			(xy 44.995309 -170.310001) (xy 44.942994 -170.375138) (xy 44.884637 -170.434923) (xy 44.820783 -170.488796)
			(xy 44.752027 -170.536255) (xy 44.679011 -170.576856) (xy 44.602418 -170.610221) (xy 44.522962 -170.636038)
			(xy 44.441386 -170.654066) (xy 44.35845 -170.664136) (xy 44.27493 -170.666155) (xy 44.191604 -170.660103)
			(xy 44.109252 -170.646038) (xy 44.028642 -170.62409) (xy 43.950526 -170.594464) (xy 43.875634 -170.557438)
			(xy 43.804666 -170.513357) (xy 43.738283 -170.462631) (xy 43.677106 -170.405736) (xy 43.621705 -170.343202)
			(xy 43.572599 -170.275613) (xy 43.530245 -170.2036) (xy 43.495039 -170.127835) (xy 43.46731 -170.049026)
			(xy 43.447317 -169.967909) (xy 43.435245 -169.885241) (xy 43.431209 -169.801794) (xy 39.663624 -169.801794)
			(xy 40.717978 -170.856148) (xy 50.017172 -170.856148) (xy 50.017649 -170.828574) (xy 50.025597 -170.774002)
			(xy 50.041318 -170.721142) (xy 50.064486 -170.671096) (xy 50.094617 -170.624907) (xy 50.131084 -170.583538)
			(xy 50.173128 -170.54785) (xy 50.196242 -170.532806) (xy 50.208147 -170.524733) (xy 50.227333 -170.503326)
			(xy 50.239787 -170.477417) (xy 50.244521 -170.449062) (xy 50.24116 -170.420513) (xy 50.229971 -170.394033)
			(xy 50.21184 -170.371725) (xy 50.200306 -170.363134) (xy 50.178981 -170.347755) (xy 50.140292 -170.312157)
			(xy 50.10686 -170.27158) (xy 50.079321 -170.226795) (xy 50.058196 -170.178651) (xy 50.043886 -170.128062)
			(xy 50.036663 -170.075985) (xy 50.036222 -170.049698) (xy 50.036708 -170.022447) (xy 50.044464 -169.968499)
			(xy 50.059819 -169.916204) (xy 50.082461 -169.866627) (xy 50.111927 -169.820777) (xy 50.147618 -169.779586)
			(xy 50.188809 -169.743895) (xy 50.234659 -169.714429) (xy 50.284236 -169.691787) (xy 50.336531 -169.676432)
			(xy 50.390479 -169.668676) (xy 50.444981 -169.668676) (xy 50.498929 -169.676432) (xy 50.551224 -169.691787)
			(xy 50.600801 -169.714429) (xy 50.646651 -169.743895) (xy 50.687842 -169.779586) (xy 50.723533 -169.820777)
			(xy 50.752999 -169.866627) (xy 50.775641 -169.916204) (xy 50.790996 -169.968499) (xy 50.798752 -170.022447)
			(xy 50.799238 -170.049698) (xy 50.798792 -170.077273) (xy 50.790838 -170.131847) (xy 50.775111 -170.184707)
			(xy 50.751938 -170.234752) (xy 50.721802 -170.280941) (xy 50.685331 -170.32231) (xy 50.643284 -170.357997)
			(xy 50.620168 -170.37304) (xy 50.608219 -170.381053) (xy 50.58903 -170.402473) (xy 50.576576 -170.428395)
			(xy 50.571846 -170.456762) (xy 50.575216 -170.485322) (xy 50.586418 -170.51181) (xy 50.599378 -170.527747)
			(xy 52.354526 -170.527747) (xy 52.354526 -170.473253) (xy 52.362281 -170.419314) (xy 52.377633 -170.367027)
			(xy 52.40027 -170.317458) (xy 52.429731 -170.271614) (xy 52.465416 -170.23043) (xy 52.506598 -170.194743)
			(xy 52.55244 -170.16528) (xy 52.602009 -170.14264) (xy 52.654294 -170.127285) (xy 52.708233 -170.119528)
			(xy 52.73548 -170.11904) (xy 52.765603 -170.119626) (xy 52.825098 -170.129104) (xy 52.882366 -170.147811)
			(xy 52.935983 -170.175284) (xy 52.984619 -170.210839) (xy 53.006244 -170.231816) (xy 53.015966 -170.241034)
			(xy 53.039128 -170.254479) (xy 53.064989 -170.261441) (xy 53.091771 -170.261441) (xy 53.117632 -170.254479)
			(xy 53.140794 -170.241034) (xy 53.150516 -170.231816) (xy 53.172113 -170.210806) (xy 53.220749 -170.175241)
			(xy 53.274373 -170.147766) (xy 53.331649 -170.129065) (xy 53.391154 -170.119603) (xy 53.42128 -170.11904)
			(xy 53.448537 -170.119406) (xy 53.502497 -170.127161) (xy 53.554804 -170.142517) (xy 53.604393 -170.165162)
			(xy 53.650254 -170.194633) (xy 53.691455 -170.230331) (xy 53.727155 -170.27153) (xy 53.756629 -170.317389)
			(xy 53.779276 -170.366977) (xy 53.794635 -170.419283) (xy 53.802393 -170.473243) (xy 53.802393 -170.527757)
			(xy 53.794635 -170.581717) (xy 53.779276 -170.634023) (xy 53.756629 -170.683611) (xy 53.727155 -170.72947)
			(xy 53.691455 -170.770669) (xy 53.650254 -170.806367) (xy 53.604393 -170.835838) (xy 53.554804 -170.858483)
			(xy 53.502497 -170.873839) (xy 53.448537 -170.881594) (xy 53.42128 -170.882056) (xy 53.391156 -170.881496)
			(xy 53.331659 -170.872012) (xy 53.274391 -170.853299) (xy 53.220775 -170.82582) (xy 53.172141 -170.79026)
			(xy 53.150516 -170.76928) (xy 53.140794 -170.760062) (xy 53.117632 -170.746617) (xy 53.091771 -170.739655)
			(xy 53.064989 -170.739655) (xy 53.039128 -170.746617) (xy 53.015966 -170.760062) (xy 53.006244 -170.76928)
			(xy 52.98462 -170.790261) (xy 52.935991 -170.82583) (xy 52.882375 -170.85331) (xy 52.825104 -170.872018)
			(xy 52.765604 -170.881488) (xy 52.73548 -170.882056) (xy 52.708233 -170.881472) (xy 52.654294 -170.873715)
			(xy 52.602009 -170.85836) (xy 52.55244 -170.83572) (xy 52.506598 -170.806257) (xy 52.465416 -170.77057)
			(xy 52.429731 -170.729386) (xy 52.40027 -170.683542) (xy 52.377633 -170.633973) (xy 52.362281 -170.581686)
			(xy 52.354526 -170.527747) (xy 50.599378 -170.527747) (xy 50.604562 -170.534121) (xy 50.616104 -170.542712)
			(xy 50.637453 -170.558059) (xy 50.676141 -170.593663) (xy 50.709571 -170.634245) (xy 50.737107 -170.679036)
			(xy 50.758228 -170.727185) (xy 50.772533 -170.777779) (xy 50.779751 -170.829859) (xy 50.780188 -170.856148)
			(xy 50.779702 -170.883399) (xy 50.771946 -170.937347) (xy 50.756591 -170.989642) (xy 50.733949 -171.039219)
			(xy 50.704483 -171.085069) (xy 50.668792 -171.12626) (xy 50.627601 -171.161951) (xy 50.581751 -171.191417)
			(xy 50.532174 -171.214059) (xy 50.479879 -171.229414) (xy 50.425931 -171.23717) (xy 50.371429 -171.23717)
			(xy 50.317481 -171.229414) (xy 50.265186 -171.214059) (xy 50.215609 -171.191417) (xy 50.169759 -171.161951)
			(xy 50.128568 -171.12626) (xy 50.092877 -171.085069) (xy 50.063411 -171.039219) (xy 50.040769 -170.989642)
			(xy 50.025414 -170.937347) (xy 50.017658 -170.883399) (xy 50.017172 -170.856148) (xy 40.717978 -170.856148)
			(xy 42.206094 -172.344264) (xy 43.406818 -172.344264) (xy 43.406818 -172.259568) (xy 43.414869 -172.175254)
			(xy 43.430898 -172.092088) (xy 43.454759 -172.010821) (xy 43.486238 -171.932191) (xy 43.525049 -171.85691)
			(xy 43.570839 -171.785658) (xy 43.623195 -171.719082) (xy 43.681643 -171.657784) (xy 43.745653 -171.602319)
			(xy 43.814645 -171.55319) (xy 43.887995 -171.510841) (xy 43.965038 -171.475657) (xy 44.045077 -171.447955)
			(xy 44.127386 -171.427987) (xy 44.211221 -171.415934) (xy 44.295822 -171.411904) (xy 44.380423 -171.415934)
			(xy 44.464258 -171.427987) (xy 44.546567 -171.447955) (xy 44.626606 -171.475657) (xy 44.703649 -171.510841)
			(xy 44.776999 -171.55319) (xy 44.845991 -171.602319) (xy 44.910001 -171.657784) (xy 44.968449 -171.719082)
			(xy 45.020805 -171.785658) (xy 45.066595 -171.85691) (xy 45.105406 -171.932191) (xy 45.136885 -172.010821)
			(xy 45.160746 -172.092088) (xy 45.176775 -172.175254) (xy 45.184826 -172.259568) (xy 45.185173 -172.288752)
			(xy 48.725285 -172.288752) (xy 48.725285 -172.234248) (xy 48.733042 -172.180299) (xy 48.748399 -172.128003)
			(xy 48.771041 -172.078425) (xy 48.80051 -172.032574) (xy 48.836204 -171.991384) (xy 48.877396 -171.955693)
			(xy 48.923249 -171.926228) (xy 48.972829 -171.903589) (xy 49.025126 -171.888236) (xy 49.079076 -171.880483)
			(xy 49.106328 -171.880022) (xy 49.136703 -171.88062) (xy 49.196685 -171.89025) (xy 49.254384 -171.909263)
			(xy 49.308341 -171.937178) (xy 49.357193 -171.97329) (xy 49.37887 -171.994576) (xy 49.388621 -172.003887)
			(xy 49.411894 -172.017482) (xy 49.437911 -172.024524) (xy 49.464863 -172.024524) (xy 49.49088 -172.017482)
			(xy 49.514153 -172.003887) (xy 49.523904 -171.994576) (xy 49.54556 -171.973266) (xy 49.594415 -171.937152)
			(xy 49.648377 -171.909238) (xy 49.706081 -171.890229) (xy 49.766069 -171.880607) (xy 49.796446 -171.880022)
			(xy 49.823697 -171.880451) (xy 49.877644 -171.888213) (xy 49.929938 -171.903574) (xy 49.979513 -171.926219)
			(xy 50.025361 -171.955689) (xy 50.066549 -171.991383) (xy 50.102238 -172.032576) (xy 50.131703 -172.078428)
			(xy 50.154342 -172.128006) (xy 50.169696 -172.180301) (xy 50.177452 -172.234249) (xy 50.177452 -172.288751)
			(xy 50.169696 -172.342699) (xy 50.154342 -172.394994) (xy 50.131703 -172.444572) (xy 50.102238 -172.490424)
			(xy 50.066549 -172.531617) (xy 50.025361 -172.567311) (xy 49.979513 -172.596781) (xy 49.929938 -172.619426)
			(xy 49.877644 -172.634787) (xy 49.823697 -172.642549) (xy 49.796446 -172.643038) (xy 49.76607 -172.642468)
			(xy 49.706086 -172.632833) (xy 49.648386 -172.613814) (xy 49.59443 -172.585893) (xy 49.545579 -172.549774)
			(xy 49.523904 -172.528484) (xy 49.514176 -172.519126) (xy 49.490915 -172.50545) (xy 49.464879 -172.498363)
			(xy 49.437895 -172.498363) (xy 49.411859 -172.50545) (xy 49.388598 -172.519126) (xy 49.37887 -172.528484)
			(xy 49.357174 -172.549751) (xy 49.30833 -172.585872) (xy 49.254379 -172.613795) (xy 49.196683 -172.632814)
			(xy 49.136703 -172.642447) (xy 49.106328 -172.643038) (xy 49.079076 -172.642517) (xy 49.025126 -172.634764)
			(xy 48.972829 -172.619411) (xy 48.923249 -172.596772) (xy 48.877396 -172.567307) (xy 48.836204 -172.531616)
			(xy 48.80051 -172.490426) (xy 48.771041 -172.444575) (xy 48.748399 -172.394997) (xy 48.733042 -172.342701)
			(xy 48.725285 -172.288752) (xy 45.185173 -172.288752) (xy 45.18533 -172.301916) (xy 45.184826 -172.344264)
			(xy 45.176775 -172.428578) (xy 45.160746 -172.511744) (xy 45.136885 -172.593011) (xy 45.105406 -172.671641)
			(xy 45.066595 -172.746922) (xy 45.020805 -172.818174) (xy 44.968449 -172.88475) (xy 44.910001 -172.946048)
			(xy 44.845991 -173.001513) (xy 44.776999 -173.050642) (xy 44.703649 -173.092991) (xy 44.626606 -173.128175)
			(xy 44.546567 -173.155877) (xy 44.464258 -173.175845) (xy 44.380423 -173.187898) (xy 44.295822 -173.191929)
			(xy 44.211221 -173.187898) (xy 44.127386 -173.175845) (xy 44.045077 -173.155877) (xy 43.965038 -173.128175)
			(xy 43.887995 -173.092991) (xy 43.814645 -173.050642) (xy 43.745653 -173.001513) (xy 43.681643 -172.946048)
			(xy 43.623195 -172.88475) (xy 43.570839 -172.818174) (xy 43.525049 -172.746922) (xy 43.486238 -172.671641)
			(xy 43.454759 -172.593011) (xy 43.430898 -172.511744) (xy 43.414869 -172.428578) (xy 43.406818 -172.344264)
			(xy 42.206094 -172.344264) (xy 43.57497 -173.71314) (xy 46.76267 -173.71314) (xy 47.427388 -173.048676)
			(xy 47.445491 -173.031429) (xy 47.487034 -173.003618) (xy 47.533203 -172.984443) (xy 47.582225 -172.97464)
			(xy 47.60722 -172.974) (xy 50.17643 -172.974) (xy 50.550064 -172.600366) (xy 50.550064 -172.367194)
			(xy 50.530465 -172.349008) (xy 50.496007 -172.308126) (xy 50.467592 -172.262836) (xy 50.445778 -172.214023)
			(xy 50.43099 -172.162642) (xy 50.423518 -172.109701) (xy 50.423064 -172.082968) (xy 50.42355 -172.055717)
			(xy 50.431306 -172.001769) (xy 50.446661 -171.949474) (xy 50.469303 -171.899897) (xy 50.498769 -171.854047)
			(xy 50.53446 -171.812856) (xy 50.575651 -171.777165) (xy 50.621501 -171.747699) (xy 50.671078 -171.725057)
			(xy 50.723373 -171.709702) (xy 50.777321 -171.701946) (xy 50.831823 -171.701946) (xy 50.885771 -171.709702)
			(xy 50.938066 -171.725057) (xy 50.987643 -171.747699) (xy 51.033493 -171.777165) (xy 51.074684 -171.812856)
			(xy 51.110375 -171.854047) (xy 51.139841 -171.899897) (xy 51.162483 -171.949474) (xy 51.177838 -172.001769)
			(xy 51.185594 -172.055717) (xy 51.18608 -172.082968) (xy 51.185632 -172.109702) (xy 51.17817 -172.162648)
			(xy 51.163387 -172.214033) (xy 51.141575 -172.26285) (xy 51.113159 -172.308143) (xy 51.078697 -172.349025)
			(xy 51.05908 -172.367194) (xy 51.05908 -172.705776) (xy 51.058429 -172.730771) (xy 51.048629 -172.779793)
			(xy 51.02946 -172.825964) (xy 51.001657 -172.867511) (xy 50.984404 -172.885608) (xy 50.461672 -173.40834)
			(xy 50.443573 -173.425592) (xy 50.40203 -173.453406) (xy 50.35586 -173.472581) (xy 50.306836 -173.48238)
			(xy 50.28184 -173.483016) (xy 47.71263 -173.483016) (xy 47.047912 -174.14748) (xy 47.029802 -174.16472)
			(xy 46.988262 -174.192534) (xy 46.942096 -174.211712) (xy 46.893075 -174.221516) (xy 46.86808 -174.222156)
			(xy 43.46956 -174.222156) (xy 43.444565 -174.22149) (xy 43.395544 -174.211696) (xy 43.349373 -174.192531)
			(xy 43.307825 -174.164732) (xy 43.289728 -174.14748) (xy 37.666168 -168.52392) (xy 37.64894 -168.505799)
			(xy 37.621121 -168.464264) (xy 37.60194 -168.418101) (xy 37.592133 -168.369082) (xy 37.591492 -168.344088)
			(xy 37.591492 -144.456658) (xy 30.89529 -137.760456) (xy 29.85262 -137.760456) (xy 29.827624 -137.759814)
			(xy 29.778602 -137.750012) (xy 29.732431 -137.730841) (xy 29.690884 -137.703035) (xy 29.672788 -137.68578)
			(xy 25.921462 -133.934708) (xy 25.653746 -133.934708) (xy 25.635578 -133.954325) (xy 25.594693 -133.988783)
			(xy 25.549399 -134.017195) (xy 25.500582 -134.039007) (xy 25.449198 -134.053791) (xy 25.396254 -134.061258)
			(xy 25.36952 -134.061708) (xy 25.342266 -134.061246) (xy 25.288313 -134.053491) (xy 25.236013 -134.038137)
			(xy 25.18643 -134.015496) (xy 25.140575 -133.986028) (xy 25.09938 -133.950335) (xy 25.063684 -133.909141)
			(xy 25.034214 -133.863287) (xy 25.01157 -133.813706) (xy 24.996213 -133.761406) (xy 24.988455 -133.707454)
			(xy 21.361908 -133.707454) (xy 21.361908 -134.911084) (xy 36.808664 -150.358094) (xy 36.815268 -150.364698)
			(xy 36.916614 -150.466044) (xy 36.916614 -150.61057) (xy 36.916868 -150.618698) (xy 36.916868 -157.45333)
			(xy 36.916614 -157.461458) (xy 36.916614 -157.605984) (xy 36.815268 -157.70733) (xy 36.808664 -157.713934)
			(xy 36.182554 -158.340298) (xy 35.547808 -158.975044) (xy 35.547808 -169.203878) (xy 35.547554 -169.212006)
			(xy 35.547554 -169.356532) (xy 35.446208 -169.457878) (xy 35.439604 -169.464482) (xy 32.715454 -172.188632)
			(xy 32.70885 -172.195236) (xy 32.607504 -172.296582) (xy 32.461962 -172.296582) (xy 32.45485 -172.296836)
			(xy 22.829774 -172.296836) (xy 22.31644 -172.81017) (xy 21.713444 -173.412912) (xy 21.713444 -174.323502)
			(xy 21.713861 -174.336982) (xy 21.720922 -174.363) (xy 21.734552 -174.386261) (xy 21.753797 -174.40514)
			(xy 21.777316 -174.41832) (xy 21.803465 -174.424879) (xy 21.83042 -174.424362) (xy 21.843492 -174.421038)
			(xy 21.869588 -174.413929) (xy 21.923129 -174.406278) (xy 21.950172 -174.405798) (xy 21.979952 -174.406367)
			(xy 22.038791 -174.415611) (xy 22.09548 -174.43388) (xy 22.148645 -174.46073) (xy 22.196995 -174.495511)
			(xy 22.239358 -174.537377) (xy 22.257512 -174.560992) (xy 22.27229 -174.581033) (xy 22.297083 -174.624216)
			(xy 22.316055 -174.670255) (xy 22.328882 -174.71837) (xy 22.335348 -174.767743) (xy 22.335744 -174.79264)
			(xy 22.335255 -174.819907) (xy 22.327488 -174.873885) (xy 22.314795 -174.9171) (xy 25.556462 -174.9171)
			(xy 25.560533 -174.861478) (xy 25.572659 -174.807041) (xy 25.592582 -174.75495) (xy 25.619878 -174.706315)
			(xy 25.653964 -174.662172) (xy 25.694113 -174.623463) (xy 25.739471 -174.591012) (xy 25.789071 -174.565511)
			(xy 25.841855 -174.547504) (xy 25.896698 -174.537374) (xy 25.952432 -174.535337) (xy 26.001635 -174.540751)
			(xy 48.944772 -174.540751) (xy 48.944772 -174.486249) (xy 48.952528 -174.432302) (xy 48.967883 -174.380008)
			(xy 48.990523 -174.330431) (xy 49.019988 -174.28458) (xy 49.055678 -174.24339) (xy 49.096867 -174.207698)
			(xy 49.142717 -174.178231) (xy 49.192293 -174.155588) (xy 49.244586 -174.140231) (xy 49.298533 -174.132473)
			(xy 49.325784 -174.131986) (xy 49.350659 -174.132354) (xy 49.399986 -174.138825) (xy 49.448052 -174.151659)
			(xy 49.494039 -174.170637) (xy 49.537167 -174.195438) (xy 49.557178 -174.210218) (xy 49.569675 -174.219055)
			(xy 49.598406 -174.229566) (xy 49.62896 -174.231114) (xy 49.658606 -174.223559) (xy 49.684693 -174.207578)
			(xy 49.704889 -174.184599) (xy 49.71161 -174.170848) (xy 49.723254 -174.14601) (xy 49.752631 -174.099682)
			(xy 49.788337 -174.058036) (xy 49.829637 -174.021931) (xy 49.875681 -173.99211) (xy 49.925519 -173.969188)
			(xy 49.978125 -173.953636) (xy 50.032416 -173.945775) (xy 50.059844 -173.945296) (xy 50.087093 -173.945777)
			(xy 50.141037 -173.953538) (xy 50.193327 -173.968898) (xy 50.242899 -173.991541) (xy 50.288745 -174.021009)
			(xy 50.32993 -174.056701) (xy 50.365617 -174.097891) (xy 50.39508 -174.143739) (xy 50.417718 -174.193314)
			(xy 50.433071 -174.245606) (xy 50.440826 -174.29955) (xy 50.440826 -174.35405) (xy 50.433071 -174.407994)
			(xy 50.417718 -174.460286) (xy 50.39508 -174.509861) (xy 50.365617 -174.555709) (xy 50.32993 -174.596899)
			(xy 50.288745 -174.632591) (xy 50.242899 -174.662059) (xy 50.193327 -174.684702) (xy 50.141037 -174.700062)
			(xy 50.087093 -174.707823) (xy 50.059844 -174.708312) (xy 50.03497 -174.707929) (xy 49.985643 -174.701462)
			(xy 49.937577 -174.688631) (xy 49.89159 -174.669656) (xy 49.848462 -174.644859) (xy 49.82845 -174.63008)
			(xy 49.815931 -174.621277) (xy 49.787208 -174.610762) (xy 49.75666 -174.60921) (xy 49.72702 -174.616758)
			(xy 49.700935 -174.632732) (xy 49.68074 -174.655703) (xy 49.674018 -174.66945) (xy 49.662351 -174.694277)
			(xy 49.632977 -174.740604) (xy 49.597274 -174.78225) (xy 49.555977 -174.818355) (xy 49.509937 -174.848178)
			(xy 49.460103 -174.871102) (xy 49.407499 -174.886657) (xy 49.353211 -174.894521) (xy 49.325784 -174.895002)
			(xy 49.298533 -174.894527) (xy 49.244586 -174.886769) (xy 49.192293 -174.871412) (xy 49.142717 -174.848769)
			(xy 49.096867 -174.819302) (xy 49.055678 -174.78361) (xy 49.019988 -174.74242) (xy 48.990523 -174.696569)
			(xy 48.967883 -174.646992) (xy 48.952528 -174.594698) (xy 48.944772 -174.540751) (xy 26.001635 -174.540751)
			(xy 26.007869 -174.541437) (xy 26.061826 -174.555543) (xy 26.113155 -174.577355) (xy 26.160761 -174.606409)
			(xy 26.203629 -174.642084) (xy 26.240846 -174.683621) (xy 26.271619 -174.730134) (xy 26.295291 -174.780631)
			(xy 26.311359 -174.834038) (xy 26.319479 -174.889214) (xy 26.319988 -174.9171) (xy 26.319479 -174.944986)
			(xy 26.311359 -175.000162) (xy 26.295291 -175.053569) (xy 26.271619 -175.104066) (xy 26.240846 -175.150579)
			(xy 26.203629 -175.192116) (xy 26.160761 -175.227791) (xy 26.113155 -175.256845) (xy 26.061826 -175.278657)
			(xy 26.007869 -175.292763) (xy 25.952432 -175.298863) (xy 25.896698 -175.296826) (xy 25.841855 -175.286696)
			(xy 25.789071 -175.268689) (xy 25.739471 -175.243188) (xy 25.694113 -175.210737) (xy 25.653964 -175.172028)
			(xy 25.619878 -175.127885) (xy 25.592582 -175.07925) (xy 25.572659 -175.027159) (xy 25.560533 -174.972722)
			(xy 25.556462 -174.9171) (xy 22.314795 -174.9171) (xy 22.312119 -174.926209) (xy 22.289461 -174.975813)
			(xy 22.259973 -175.021688) (xy 22.224258 -175.062899) (xy 22.183041 -175.098608) (xy 22.137162 -175.128089)
			(xy 22.087555 -175.15074) (xy 22.035229 -175.166101) (xy 21.981249 -175.173859) (xy 21.953982 -175.174402)
			(xy 21.953474 -175.174402) (xy 21.919393 -175.173625) (xy 21.852319 -175.161481) (xy 21.820124 -175.150272)
			(xy 21.806382 -175.15003) (xy 21.779568 -175.156015) (xy 21.755323 -175.168937) (xy 21.735405 -175.187859)
			(xy 21.721257 -175.21141) (xy 21.713905 -175.237882) (xy 21.713444 -175.251618) (xy 21.713444 -175.83404)
			(xy 23.37714 -175.83404) (xy 23.381229 -175.778158) (xy 23.393412 -175.723468) (xy 23.413428 -175.671134)
			(xy 23.440851 -175.622272) (xy 23.475096 -175.577924) (xy 23.515432 -175.539034) (xy 23.561002 -175.506432)
			(xy 23.610833 -175.480813) (xy 23.663863 -175.462721) (xy 23.718961 -175.452544) (xy 23.774955 -175.450498)
			(xy 23.83065 -175.456626) (xy 23.884859 -175.470798) (xy 23.936427 -175.492712) (xy 23.984255 -175.521901)
			(xy 24.027323 -175.557742) (xy 24.064713 -175.599472) (xy 24.095629 -175.646202) (xy 24.119412 -175.696935)
			(xy 24.135554 -175.750591) (xy 24.141855 -175.7934) (xy 25.541222 -175.7934) (xy 25.545293 -175.737778)
			(xy 25.557419 -175.683341) (xy 25.577342 -175.63125) (xy 25.604638 -175.582615) (xy 25.638724 -175.538472)
			(xy 25.678873 -175.499763) (xy 25.724231 -175.467312) (xy 25.773831 -175.441811) (xy 25.826615 -175.423804)
			(xy 25.881458 -175.413674) (xy 25.937192 -175.411637) (xy 25.992629 -175.417737) (xy 26.046586 -175.431843)
			(xy 26.097915 -175.453655) (xy 26.145521 -175.482709) (xy 26.156993 -175.492256) (xy 35.295733 -175.492256)
			(xy 35.295733 -175.437744) (xy 35.303491 -175.383786) (xy 35.31885 -175.331482) (xy 35.341497 -175.281896)
			(xy 35.370971 -175.236039) (xy 35.406671 -175.194842) (xy 35.447871 -175.159147) (xy 35.493731 -175.129678)
			(xy 35.54332 -175.107036) (xy 35.595625 -175.091683) (xy 35.649584 -175.08393) (xy 35.67684 -175.08347)
			(xy 35.70421 -175.083954) (xy 35.758389 -175.091765) (xy 35.810892 -175.107249) (xy 35.86064 -175.130087)
			(xy 35.906607 -175.159809) (xy 35.927538 -175.17745) (xy 35.938866 -175.186686) (xy 35.965423 -175.198862)
			(xy 35.99434 -175.203035) (xy 36.023257 -175.198862) (xy 36.049814 -175.186686) (xy 36.061142 -175.17745)
			(xy 36.082092 -175.159832) (xy 36.128059 -175.130116) (xy 36.177802 -175.107275) (xy 36.230299 -175.091779)
			(xy 36.284472 -175.083946) (xy 36.31184 -175.08347) (xy 36.339088 -175.084003) (xy 36.393028 -175.091764)
			(xy 36.445315 -175.107121) (xy 36.494884 -175.129763) (xy 36.540727 -175.159229) (xy 36.58191 -175.194918)
			(xy 36.617595 -175.236105) (xy 36.633929 -175.261524) (xy 51.230528 -175.261524) (xy 51.234599 -175.205902)
			(xy 51.246725 -175.151465) (xy 51.266648 -175.099374) (xy 51.293944 -175.050739) (xy 51.32803 -175.006596)
			(xy 51.368179 -174.967887) (xy 51.413537 -174.935436) (xy 51.463137 -174.909935) (xy 51.515921 -174.891928)
			(xy 51.570764 -174.881798) (xy 51.626498 -174.879761) (xy 51.681935 -174.885861) (xy 51.735892 -174.899967)
			(xy 51.787221 -174.921779) (xy 51.834827 -174.950833) (xy 51.877695 -174.986508) (xy 51.914912 -175.028045)
			(xy 51.945685 -175.074558) (xy 51.969357 -175.125055) (xy 51.985425 -175.178462) (xy 51.993545 -175.233638)
			(xy 51.994054 -175.261524) (xy 51.993957 -175.266858) (xy 52.228748 -175.266858) (xy 52.232819 -175.211236)
			(xy 52.244945 -175.156799) (xy 52.264868 -175.104708) (xy 52.292164 -175.056073) (xy 52.32625 -175.01193)
			(xy 52.366399 -174.973221) (xy 52.411757 -174.94077) (xy 52.461357 -174.915269) (xy 52.514141 -174.897262)
			(xy 52.568984 -174.887132) (xy 52.624718 -174.885095) (xy 52.680155 -174.891195) (xy 52.734112 -174.905301)
			(xy 52.785441 -174.927113) (xy 52.833047 -174.956167) (xy 52.875915 -174.991842) (xy 52.913132 -175.033379)
			(xy 52.943905 -175.079892) (xy 52.967577 -175.130389) (xy 52.983645 -175.183796) (xy 52.991765 -175.238972)
			(xy 52.992274 -175.266858) (xy 52.991765 -175.294744) (xy 52.983645 -175.34992) (xy 52.967577 -175.403327)
			(xy 52.943905 -175.453824) (xy 52.913132 -175.500337) (xy 52.875915 -175.541874) (xy 52.833047 -175.577549)
			(xy 52.785441 -175.606603) (xy 52.734112 -175.628415) (xy 52.680155 -175.642521) (xy 52.624718 -175.648621)
			(xy 52.568984 -175.646584) (xy 52.514141 -175.636454) (xy 52.461357 -175.618447) (xy 52.411757 -175.592946)
			(xy 52.366399 -175.560495) (xy 52.32625 -175.521786) (xy 52.292164 -175.477643) (xy 52.264868 -175.429008)
			(xy 52.244945 -175.376917) (xy 52.232819 -175.32248) (xy 52.228748 -175.266858) (xy 51.993957 -175.266858)
			(xy 51.993545 -175.28941) (xy 51.985425 -175.344586) (xy 51.969357 -175.397993) (xy 51.945685 -175.44849)
			(xy 51.914912 -175.495003) (xy 51.877695 -175.53654) (xy 51.834827 -175.572215) (xy 51.787221 -175.601269)
			(xy 51.735892 -175.623081) (xy 51.681935 -175.637187) (xy 51.626498 -175.643287) (xy 51.570764 -175.64125)
			(xy 51.515921 -175.63112) (xy 51.463137 -175.613113) (xy 51.413537 -175.587612) (xy 51.368179 -175.555161)
			(xy 51.32803 -175.516452) (xy 51.293944 -175.472309) (xy 51.266648 -175.423674) (xy 51.246725 -175.371583)
			(xy 51.234599 -175.317146) (xy 51.230528 -175.261524) (xy 36.633929 -175.261524) (xy 36.647056 -175.281951)
			(xy 36.669693 -175.331523) (xy 36.685045 -175.383811) (xy 36.6928 -175.437752) (xy 36.6928 -175.492248)
			(xy 36.685045 -175.546189) (xy 36.669693 -175.598477) (xy 36.647056 -175.648049) (xy 36.617595 -175.693895)
			(xy 36.58191 -175.735082) (xy 36.540727 -175.770771) (xy 36.494884 -175.800237) (xy 36.445315 -175.822879)
			(xy 36.393028 -175.838236) (xy 36.339088 -175.845997) (xy 36.31184 -175.846486) (xy 36.28447 -175.846)
			(xy 36.230292 -175.838187) (xy 36.177789 -175.822703) (xy 36.128042 -175.799866) (xy 36.082074 -175.770145)
			(xy 36.061142 -175.752506) (xy 36.049814 -175.74327) (xy 36.023257 -175.731094) (xy 35.99434 -175.726921)
			(xy 35.965423 -175.731094) (xy 35.938866 -175.74327) (xy 35.927538 -175.752506) (xy 35.906603 -175.770142)
			(xy 35.860631 -175.799854) (xy 35.810884 -175.82269) (xy 35.758384 -175.838182) (xy 35.704209 -175.846011)
			(xy 35.67684 -175.846486) (xy 35.649584 -175.84607) (xy 35.595625 -175.838317) (xy 35.54332 -175.822964)
			(xy 35.493731 -175.800322) (xy 35.447871 -175.770853) (xy 35.406671 -175.735158) (xy 35.370971 -175.693961)
			(xy 35.341497 -175.648104) (xy 35.31885 -175.598518) (xy 35.303491 -175.546214) (xy 35.295733 -175.492256)
			(xy 26.156993 -175.492256) (xy 26.188389 -175.518384) (xy 26.225606 -175.559921) (xy 26.256379 -175.606434)
			(xy 26.280051 -175.656931) (xy 26.296119 -175.710338) (xy 26.304239 -175.765514) (xy 26.304748 -175.7934)
			(xy 26.304239 -175.821286) (xy 26.296119 -175.876462) (xy 26.280051 -175.929869) (xy 26.256379 -175.980366)
			(xy 26.225606 -176.026879) (xy 26.188389 -176.068416) (xy 26.145521 -176.104091) (xy 26.097915 -176.133145)
			(xy 26.046586 -176.154957) (xy 25.992629 -176.169063) (xy 25.937192 -176.175163) (xy 25.881458 -176.173126)
			(xy 25.826615 -176.162996) (xy 25.773831 -176.144989) (xy 25.724231 -176.119488) (xy 25.678873 -176.087037)
			(xy 25.638724 -176.048328) (xy 25.604638 -176.004185) (xy 25.577342 -175.95555) (xy 25.557419 -175.903459)
			(xy 25.545293 -175.849022) (xy 25.541222 -175.7934) (xy 24.141855 -175.7934) (xy 24.143713 -175.806025)
			(xy 24.144224 -175.83404) (xy 24.143713 -175.862055) (xy 24.135554 -175.917489) (xy 24.119412 -175.971145)
			(xy 24.095629 -176.021878) (xy 24.064713 -176.068608) (xy 24.027323 -176.110338) (xy 23.984255 -176.146179)
			(xy 23.936427 -176.175368) (xy 23.923164 -176.181004) (xy 51.225448 -176.181004) (xy 51.229519 -176.125382)
			(xy 51.241645 -176.070945) (xy 51.261568 -176.018854) (xy 51.288864 -175.970219) (xy 51.32295 -175.926076)
			(xy 51.363099 -175.887367) (xy 51.408457 -175.854916) (xy 51.458057 -175.829415) (xy 51.510841 -175.811408)
			(xy 51.565684 -175.801278) (xy 51.621418 -175.799241) (xy 51.676855 -175.805341) (xy 51.730812 -175.819447)
			(xy 51.782141 -175.841259) (xy 51.829747 -175.870313) (xy 51.872615 -175.905988) (xy 51.909832 -175.947525)
			(xy 51.940605 -175.994038) (xy 51.964277 -176.044535) (xy 51.980345 -176.097942) (xy 51.988465 -176.153118)
			(xy 51.988974 -176.181004) (xy 51.988928 -176.183544) (xy 52.231542 -176.183544) (xy 52.235613 -176.127922)
			(xy 52.247739 -176.073485) (xy 52.267662 -176.021394) (xy 52.294958 -175.972759) (xy 52.329044 -175.928616)
			(xy 52.369193 -175.889907) (xy 52.414551 -175.857456) (xy 52.464151 -175.831955) (xy 52.516935 -175.813948)
			(xy 52.571778 -175.803818) (xy 52.627512 -175.801781) (xy 52.682949 -175.807881) (xy 52.736906 -175.821987)
			(xy 52.788235 -175.843799) (xy 52.835841 -175.872853) (xy 52.878709 -175.908528) (xy 52.915926 -175.950065)
			(xy 52.946699 -175.996578) (xy 52.970371 -176.047075) (xy 52.986439 -176.100482) (xy 52.994559 -176.155658)
			(xy 52.995068 -176.183544) (xy 52.994559 -176.21143) (xy 52.986439 -176.266606) (xy 52.970371 -176.320013)
			(xy 52.946699 -176.37051) (xy 52.915926 -176.417023) (xy 52.878709 -176.45856) (xy 52.835841 -176.494235)
			(xy 52.788235 -176.523289) (xy 52.736906 -176.545101) (xy 52.682949 -176.559207) (xy 52.627512 -176.565307)
			(xy 52.571778 -176.56327) (xy 52.516935 -176.55314) (xy 52.464151 -176.535133) (xy 52.414551 -176.509632)
			(xy 52.369193 -176.477181) (xy 52.329044 -176.438472) (xy 52.294958 -176.394329) (xy 52.267662 -176.345694)
			(xy 52.247739 -176.293603) (xy 52.235613 -176.239166) (xy 52.231542 -176.183544) (xy 51.988928 -176.183544)
			(xy 51.988465 -176.20889) (xy 51.980345 -176.264066) (xy 51.964277 -176.317473) (xy 51.940605 -176.36797)
			(xy 51.909832 -176.414483) (xy 51.872615 -176.45602) (xy 51.829747 -176.491695) (xy 51.782141 -176.520749)
			(xy 51.730812 -176.542561) (xy 51.676855 -176.556667) (xy 51.621418 -176.562767) (xy 51.565684 -176.56073)
			(xy 51.510841 -176.5506) (xy 51.458057 -176.532593) (xy 51.408457 -176.507092) (xy 51.363099 -176.474641)
			(xy 51.32295 -176.435932) (xy 51.288864 -176.391789) (xy 51.261568 -176.343154) (xy 51.241645 -176.291063)
			(xy 51.229519 -176.236626) (xy 51.225448 -176.181004) (xy 23.923164 -176.181004) (xy 23.884859 -176.197282)
			(xy 23.83065 -176.211454) (xy 23.774955 -176.217582) (xy 23.718961 -176.215536) (xy 23.663863 -176.205359)
			(xy 23.610833 -176.187267) (xy 23.561002 -176.161648) (xy 23.515432 -176.129046) (xy 23.475096 -176.090156)
			(xy 23.440851 -176.045808) (xy 23.413428 -175.996946) (xy 23.393412 -175.944612) (xy 23.381229 -175.889922)
			(xy 23.37714 -175.83404) (xy 21.713444 -175.83404) (xy 21.713444 -177.087784) (xy 21.714714 -177.096166)
			(xy 21.715476 -177.09896) (xy 21.716772 -177.104548) (xy 25.632662 -177.104548) (xy 25.636733 -177.048926)
			(xy 25.648859 -176.994489) (xy 25.668782 -176.942398) (xy 25.696078 -176.893763) (xy 25.730164 -176.84962)
			(xy 25.770313 -176.810911) (xy 25.815671 -176.77846) (xy 25.865271 -176.752959) (xy 25.918055 -176.734952)
			(xy 25.972898 -176.724822) (xy 26.028632 -176.722785) (xy 26.084069 -176.728885) (xy 26.138026 -176.742991)
			(xy 26.189355 -176.764803) (xy 26.236961 -176.793857) (xy 26.279829 -176.829532) (xy 26.317046 -176.871069)
			(xy 26.347819 -176.917582) (xy 26.353804 -176.930349) (xy 49.335704 -176.930349) (xy 49.335704 -176.875851)
			(xy 49.34346 -176.821908) (xy 49.358813 -176.769618) (xy 49.381452 -176.720045) (xy 49.410916 -176.674198)
			(xy 49.446604 -176.633011) (xy 49.48779 -176.597322) (xy 49.533636 -176.567857) (xy 49.583208 -176.545217)
			(xy 49.635498 -176.529862) (xy 49.689441 -176.522105) (xy 49.71669 -176.521618) (xy 49.74406 -176.522086)
			(xy 49.798239 -176.529902) (xy 49.850743 -176.545391) (xy 49.90049 -176.568232) (xy 49.946456 -176.597957)
			(xy 49.967388 -176.615598) (xy 49.978716 -176.624834) (xy 50.005273 -176.63701) (xy 50.03419 -176.641183)
			(xy 50.063107 -176.63701) (xy 50.089664 -176.624834) (xy 50.100992 -176.615598) (xy 50.121925 -176.597957)
			(xy 50.167893 -176.568233) (xy 50.217639 -176.545387) (xy 50.270141 -176.529891) (xy 50.324319 -176.522062)
			(xy 50.379061 -176.522062) (xy 50.433239 -176.529891) (xy 50.485741 -176.545387) (xy 50.535487 -176.568233)
			(xy 50.581455 -176.597957) (xy 50.602388 -176.615598) (xy 50.613716 -176.624834) (xy 50.640273 -176.63701)
			(xy 50.66919 -176.641183) (xy 50.698107 -176.63701) (xy 50.724664 -176.624834) (xy 50.735992 -176.615598)
			(xy 50.756916 -176.597949) (xy 50.802891 -176.568239) (xy 50.852641 -176.545405) (xy 50.905143 -176.529916)
			(xy 50.95932 -176.52209) (xy 50.98669 -176.521618) (xy 51.013944 -176.522065) (xy 51.067897 -176.529821)
			(xy 51.120196 -176.545177) (xy 51.169778 -176.56782) (xy 51.215633 -176.59729) (xy 51.256826 -176.632985)
			(xy 51.29252 -176.67418) (xy 51.321987 -176.720036) (xy 51.344629 -176.769619) (xy 51.359982 -176.821919)
			(xy 51.367736 -176.875872) (xy 51.368198 -176.903126) (xy 51.367748 -176.930497) (xy 51.359926 -176.984677)
			(xy 51.344433 -177.03718) (xy 51.321588 -177.086926) (xy 51.291861 -177.132893) (xy 51.274218 -177.153824)
			(xy 51.264955 -177.165132) (xy 51.252778 -177.191696) (xy 51.24861 -177.22062) (xy 51.252789 -177.249541)
			(xy 51.264976 -177.276101) (xy 51.274218 -177.287428) (xy 51.29184 -177.308374) (xy 51.321553 -177.354343)
			(xy 51.344392 -177.404087) (xy 51.359888 -177.456585) (xy 51.367721 -177.510758) (xy 51.368198 -177.538126)
			(xy 51.367746 -177.565378) (xy 51.359986 -177.619328) (xy 51.344627 -177.671624) (xy 51.321982 -177.721202)
			(xy 51.292512 -177.767053) (xy 51.256817 -177.808243) (xy 51.215624 -177.843934) (xy 51.16977 -177.873399)
			(xy 51.12019 -177.89604) (xy 51.067893 -177.911394) (xy 51.013942 -177.919149) (xy 50.98669 -177.919634)
			(xy 50.959319 -177.91919) (xy 50.905138 -177.911369) (xy 50.852634 -177.895876) (xy 50.802888 -177.873029)
			(xy 50.756922 -177.843298) (xy 50.735992 -177.825654) (xy 50.724664 -177.816418) (xy 50.698107 -177.804242)
			(xy 50.66919 -177.800069) (xy 50.640273 -177.804242) (xy 50.613716 -177.816418) (xy 50.602388 -177.825654)
			(xy 50.581428 -177.843258) (xy 50.535463 -177.872977) (xy 50.485723 -177.89582) (xy 50.433228 -177.911319)
			(xy 50.379057 -177.919156) (xy 50.35169 -177.919634) (xy 50.32444 -177.919132) (xy 50.270494 -177.911374)
			(xy 50.218201 -177.896019) (xy 50.168626 -177.873379) (xy 50.122776 -177.843914) (xy 50.081587 -177.808224)
			(xy 50.045896 -177.767036) (xy 50.016429 -177.721189) (xy 49.993786 -177.671614) (xy 49.978429 -177.619322)
			(xy 49.97067 -177.565376) (xy 49.970182 -177.538126) (xy 49.970663 -177.511891) (xy 49.977854 -177.459916)
			(xy 49.992105 -177.409419) (xy 50.013145 -177.361352) (xy 50.040578 -177.316625) (xy 50.073885 -177.276082)
			(xy 50.092864 -177.257964) (xy 50.100207 -177.250412) (xy 50.108638 -177.231137) (xy 50.108646 -177.210098)
			(xy 50.100228 -177.190817) (xy 50.092864 -177.183288) (xy 50.071528 -177.161952) (xy 50.063999 -177.15458)
			(xy 50.044714 -177.146149) (xy 50.023666 -177.146149) (xy 50.004381 -177.15458) (xy 49.996852 -177.161952)
			(xy 49.978741 -177.180941) (xy 49.938201 -177.214257) (xy 49.893474 -177.241698) (xy 49.845406 -177.262746)
			(xy 49.794905 -177.277002) (xy 49.742927 -177.284197) (xy 49.71669 -177.284634) (xy 49.689441 -177.284095)
			(xy 49.635498 -177.276338) (xy 49.583208 -177.260983) (xy 49.533636 -177.238343) (xy 49.48779 -177.208878)
			(xy 49.446604 -177.173189) (xy 49.410916 -177.132002) (xy 49.381452 -177.086155) (xy 49.358813 -177.036582)
			(xy 49.34346 -176.984292) (xy 49.335704 -176.930349) (xy 26.353804 -176.930349) (xy 26.371491 -176.968079)
			(xy 26.387559 -177.021486) (xy 26.395679 -177.076662) (xy 26.396188 -177.104548) (xy 26.395679 -177.132434)
			(xy 26.387559 -177.18761) (xy 26.371491 -177.241017) (xy 26.347819 -177.291514) (xy 26.317046 -177.338027)
			(xy 26.279829 -177.379564) (xy 26.236961 -177.415239) (xy 26.189355 -177.444293) (xy 26.138026 -177.466105)
			(xy 26.084069 -177.480211) (xy 26.028632 -177.486311) (xy 25.972898 -177.484274) (xy 25.918055 -177.474144)
			(xy 25.865271 -177.456137) (xy 25.815671 -177.430636) (xy 25.770313 -177.398185) (xy 25.730164 -177.359476)
			(xy 25.696078 -177.315333) (xy 25.668782 -177.266698) (xy 25.648859 -177.214607) (xy 25.636733 -177.16017)
			(xy 25.632662 -177.104548) (xy 21.716772 -177.104548) (xy 21.72071 -177.121521) (xy 21.726318 -177.167496)
			(xy 21.726652 -177.190654) (xy 21.726652 -177.191416) (xy 21.726294 -177.215098) (xy 21.720433 -177.262097)
			(xy 21.714968 -177.285142) (xy 21.713444 -177.291238) (xy 21.713444 -177.34407) (xy 21.676106 -177.381408)
			(xy 21.672804 -177.386996) (xy 21.656096 -177.413743) (xy 21.615331 -177.461856) (xy 21.567214 -177.502616)
			(xy 21.54047 -177.51933) (xy 21.534882 -177.522632) (xy 21.497544 -177.55997) (xy 21.450046 -177.55997)
			(xy 21.439632 -177.56124) (xy 21.436584 -177.562002) (xy 21.414022 -177.567233) (xy 21.368047 -177.572833)
			(xy 21.34489 -177.573178) (xy 21.321208 -177.57282) (xy 21.274209 -177.566959) (xy 21.251164 -177.561494)
			(xy 21.245068 -177.55997) (xy 21.192236 -177.55997) (xy 21.154898 -177.522632) (xy 21.14931 -177.51933)
			(xy 21.122562 -177.502623) (xy 21.074446 -177.46186) (xy 21.033682 -177.413745) (xy 21.016976 -177.386996)
			(xy 21.013674 -177.381408) (xy 20.976336 -177.34407) (xy 20.976336 -177.296572) (xy 20.975066 -177.286158)
			(xy 20.974304 -177.28311) (xy 20.969072 -177.260549) (xy 20.963468 -177.214574) (xy 20.963128 -177.191416)
			(xy 20.96337 -177.167486) (xy 20.969098 -177.119974) (xy 20.974558 -177.096674) (xy 20.976336 -177.090578)
			(xy 20.976336 -175.631094) (xy 20.975212 -175.617162) (xy 20.966328 -175.590672) (xy 20.950601 -175.567578)
			(xy 20.929207 -175.549607) (xy 20.903745 -175.538104) (xy 20.876119 -175.533927) (xy 20.848394 -175.537389)
			(xy 20.835366 -175.542448) (xy 20.799044 -175.57877) (xy 20.7518 -175.57877) (xy 20.740878 -175.58004)
			(xy 20.737576 -175.580802) (xy 20.715137 -175.585995) (xy 20.669419 -175.591594) (xy 20.64639 -175.591978)
			(xy 20.622971 -175.591621) (xy 20.576485 -175.585889) (xy 20.55368 -175.580548) (xy 20.547584 -175.57877)
			(xy 20.493736 -175.57877) (xy 20.455636 -175.54067) (xy 20.450302 -175.537368) (xy 20.423842 -175.520781)
			(xy 20.376225 -175.480381) (xy 20.335824 -175.432765) (xy 20.319238 -175.406304) (xy 20.315936 -175.40097)
			(xy 20.277836 -175.36287) (xy 20.277836 -175.315372) (xy 20.276312 -175.302926) (xy 20.275296 -175.299878)
			(xy 20.27029 -175.277802) (xy 20.264937 -175.23285) (xy 20.264628 -175.210216) (xy 20.264628 -175.20285)
			(xy 20.26539 -175.189642) (xy 20.266612 -175.171537) (xy 20.272081 -175.13566) (xy 20.276312 -175.118014)
			(xy 20.277836 -175.111918) (xy 20.277836 -173.040294) (xy 20.379182 -172.938948) (xy 20.385786 -172.932344)
			(xy 22.082506 -171.235624) (xy 22.08911 -171.22902) (xy 22.190456 -171.127674) (xy 22.335998 -171.127674)
			(xy 22.34311 -171.12742) (xy 30.841696 -171.12742) (xy 30.901386 -170.97502) (xy 30.875732 -170.951398)
			(xy 30.856637 -170.933239) (xy 30.823118 -170.892581) (xy 30.795503 -170.847704) (xy 30.774315 -170.799458)
			(xy 30.759957 -170.748758) (xy 30.752701 -170.696567) (xy 30.752288 -170.67022) (xy 30.752774 -170.642951)
			(xy 30.760536 -170.588967) (xy 30.775901 -170.536637) (xy 30.798558 -170.487027) (xy 30.828044 -170.441146)
			(xy 30.863759 -170.399929) (xy 30.904976 -170.364214) (xy 30.950857 -170.334728) (xy 31.000467 -170.312071)
			(xy 31.052797 -170.296706) (xy 31.106781 -170.288944) (xy 31.161319 -170.288944) (xy 31.215303 -170.296706)
			(xy 31.267633 -170.312071) (xy 31.317243 -170.334728) (xy 31.363124 -170.364214) (xy 31.404341 -170.399929)
			(xy 31.440056 -170.441146) (xy 31.469542 -170.487027) (xy 31.492199 -170.536637) (xy 31.507564 -170.588967)
			(xy 31.515326 -170.642951) (xy 31.515812 -170.67022) (xy 31.515368 -170.696565) (xy 31.508122 -170.748755)
			(xy 31.49377 -170.799454) (xy 31.472585 -170.847698) (xy 31.444969 -170.892572) (xy 31.411446 -170.933223)
			(xy 31.392368 -170.951398) (xy 31.366714 -170.97502) (xy 31.426404 -171.12742) (xy 32.123126 -171.12742)
			(xy 34.378392 -168.872154) (xy 34.378392 -161.473896) (xy 34.377972 -161.45997) (xy 34.370464 -161.433148)
			(xy 34.355982 -161.409357) (xy 34.335605 -161.39037) (xy 34.310852 -161.377602) (xy 34.283568 -161.372004)
			(xy 34.255787 -161.373995) (xy 34.22958 -161.383425) (xy 34.2069 -161.399592) (xy 34.197798 -161.410142)
			(xy 34.17958 -161.43194) (xy 34.13779 -161.47042) (xy 34.090755 -161.502275) (xy 34.039514 -161.526801)
			(xy 33.985203 -161.543456) (xy 33.929022 -161.55187) (xy 33.900618 -161.552382) (xy 33.873365 -161.55192)
			(xy 33.819414 -161.544165) (xy 33.767115 -161.52881) (xy 33.717534 -161.506168) (xy 33.671681 -161.4767)
			(xy 33.630488 -161.441006) (xy 33.594795 -161.399813) (xy 33.565328 -161.353959) (xy 33.542687 -161.304378)
			(xy 33.527333 -161.252079) (xy 33.51958 -161.198127) (xy 33.51911 -161.170874) (xy 33.518856 -161.170874)
			(xy 33.519358 -161.142301) (xy 33.527868 -161.085792) (xy 33.544708 -161.031183) (xy 33.569501 -160.979696)
			(xy 33.601694 -160.932481) (xy 33.640567 -160.890593) (xy 33.685251 -160.85497) (xy 33.734747 -160.826407)
			(xy 33.761172 -160.815528) (xy 33.783872 -160.807024) (xy 33.830879 -160.795177) (xy 33.854898 -160.791906)
			(xy 33.869884 -160.790382) (xy 33.900618 -160.789112) (xy 33.92952 -160.789645) (xy 33.986664 -160.79836)
			(xy 34.041842 -160.815587) (xy 34.093794 -160.840933) (xy 34.141332 -160.87382) (xy 34.18337 -160.913495)
			(xy 34.201608 -160.935924) (xy 34.211051 -160.945691) (xy 34.233961 -160.960276) (xy 34.259906 -160.968299)
			(xy 34.28705 -160.969191) (xy 34.313466 -160.96289) (xy 34.337284 -160.949841) (xy 34.356815 -160.93097)
			(xy 34.370674 -160.907615) (xy 34.377879 -160.88143) (xy 34.378392 -160.867852) (xy 34.378392 -158.64332)
			(xy 34.378646 -158.635192) (xy 34.378646 -158.490666) (xy 34.479992 -158.38932) (xy 34.486596 -158.382716)
			(xy 35.112706 -157.756352) (xy 35.747452 -157.121606) (xy 35.747452 -150.950422) (xy 20.300696 -135.503412)
			(xy 20.294092 -135.496808) (xy 20.192746 -135.395462) (xy 20.192746 -135.250936) (xy 20.192492 -135.242808)
			(xy 20.192492 -127.686308) (xy 20.191975 -127.671326) (xy 20.183306 -127.642646) (xy 20.166681 -127.617719)
			(xy 20.143534 -127.598693) (xy 20.115861 -127.587209) (xy 20.086044 -127.584255) (xy 20.056655 -127.590087)
			(xy 20.030226 -127.604201) (xy 20.019264 -127.614426) (xy 19.25447 -128.37922) (xy 19.25447 -152.530556)
			(xy 20.489871 -153.766012) (xy 24.445731 -153.766012) (xy 24.449724 -153.556271) (xy 24.4617 -153.346834)
			(xy 24.481641 -153.138005) (xy 24.509518 -152.930086) (xy 24.54529 -152.723379) (xy 24.588905 -152.518184)
			(xy 24.640301 -152.314799) (xy 24.699403 -152.113517) (xy 24.766125 -151.914631) (xy 24.84037 -151.71843)
			(xy 24.92203 -151.525198) (xy 25.010988 -151.335214) (xy 25.107115 -151.148755) (xy 25.21027 -150.966091)
			(xy 25.320305 -150.787486) (xy 25.437059 -150.6132) (xy 25.560364 -150.443485) (xy 25.690041 -150.278587)
			(xy 25.825902 -150.118746) (xy 25.967749 -149.964193) (xy 26.115378 -149.815153) (xy 26.268573 -149.67184)
			(xy 26.427114 -149.534464) (xy 26.590769 -149.403223) (xy 26.759303 -149.278308) (xy 26.932469 -149.1599)
			(xy 27.110019 -149.04817) (xy 27.291693 -148.94328) (xy 27.477228 -148.845383) (xy 27.666356 -148.754621)
			(xy 27.858803 -148.671124) (xy 28.054288 -148.595014) (xy 28.25253 -148.526402) (xy 28.45324 -148.465387)
			(xy 28.656127 -148.412058) (xy 28.860897 -148.366491) (xy 29.067254 -148.328752) (xy 29.274898 -148.298898)
			(xy 29.483528 -148.27697) (xy 29.692841 -148.263001) (xy 29.902535 -148.25701) (xy 30.112304 -148.259007)
			(xy 30.321846 -148.268989) (xy 30.530856 -148.286941) (xy 30.73903 -148.312837) (xy 30.946068 -148.346639)
			(xy 31.151669 -148.388299) (xy 31.355535 -148.437757) (xy 31.55737 -148.49494) (xy 31.756882 -148.559765)
			(xy 31.953781 -148.632139) (xy 32.147782 -148.711956) (xy 32.338604 -148.799102) (xy 32.52597 -148.893449)
			(xy 32.709608 -148.99486) (xy 32.889252 -149.10319) (xy 33.064642 -149.21828) (xy 33.235523 -149.339964)
			(xy 33.401647 -149.468065) (xy 33.562774 -149.602398) (xy 33.718671 -149.742767) (xy 33.86911 -149.88897)
			(xy 34.013874 -150.040794) (xy 34.152753 -150.19802) (xy 34.285546 -150.360419) (xy 34.41206 -150.527755)
			(xy 34.532112 -150.699787) (xy 34.645527 -150.876264) (xy 34.752141 -151.056932) (xy 34.8518 -151.241527)
			(xy 34.944359 -151.429782) (xy 35.029684 -151.621425) (xy 35.107651 -151.816177) (xy 35.178147 -152.013757)
			(xy 35.24107 -152.213876) (xy 35.296329 -152.416247) (xy 35.343843 -152.620574) (xy 35.383544 -152.826562)
			(xy 35.415374 -153.033913) (xy 35.439287 -153.242324) (xy 35.455248 -153.451495) (xy 35.463235 -153.661122)
			(xy 35.463734 -153.766012) (xy 35.463235 -153.870902) (xy 35.455248 -154.080529) (xy 35.439287 -154.2897)
			(xy 35.415374 -154.498111) (xy 35.383544 -154.705462) (xy 35.343843 -154.91145) (xy 35.296329 -155.115777)
			(xy 35.24107 -155.318148) (xy 35.178147 -155.518267) (xy 35.107651 -155.715847) (xy 35.029684 -155.910599)
			(xy 34.944359 -156.102242) (xy 34.8518 -156.290497) (xy 34.752141 -156.475092) (xy 34.645527 -156.65576)
			(xy 34.532112 -156.832237) (xy 34.41206 -157.004269) (xy 34.285546 -157.171605) (xy 34.152753 -157.334004)
			(xy 34.013874 -157.49123) (xy 33.86911 -157.643054) (xy 33.718671 -157.789257) (xy 33.562774 -157.929626)
			(xy 33.401647 -158.063959) (xy 33.235523 -158.19206) (xy 33.064642 -158.313744) (xy 32.889252 -158.428834)
			(xy 32.709608 -158.537164) (xy 32.52597 -158.638575) (xy 32.338604 -158.732922) (xy 32.147782 -158.820068)
			(xy 31.953781 -158.899885) (xy 31.756882 -158.972259) (xy 31.55737 -159.037084) (xy 31.355535 -159.094267)
			(xy 31.151669 -159.143725) (xy 30.946068 -159.185385) (xy 30.73903 -159.219187) (xy 30.530856 -159.245083)
			(xy 30.321846 -159.263035) (xy 30.112304 -159.273017) (xy 29.902535 -159.275014) (xy 29.692841 -159.269023)
			(xy 29.483528 -159.255054) (xy 29.274898 -159.233126) (xy 29.067254 -159.203272) (xy 28.860897 -159.165533)
			(xy 28.656127 -159.119966) (xy 28.45324 -159.066637) (xy 28.25253 -159.005622) (xy 28.054288 -158.93701)
			(xy 27.858803 -158.8609) (xy 27.666356 -158.777403) (xy 27.477228 -158.686641) (xy 27.291693 -158.588744)
			(xy 27.110019 -158.483854) (xy 26.932469 -158.372124) (xy 26.759303 -158.253716) (xy 26.590769 -158.128801)
			(xy 26.427114 -157.99756) (xy 26.268573 -157.860184) (xy 26.115378 -157.716871) (xy 25.967749 -157.567831)
			(xy 25.825902 -157.413278) (xy 25.690041 -157.253437) (xy 25.560364 -157.088539) (xy 25.437059 -156.918824)
			(xy 25.320305 -156.744538) (xy 25.21027 -156.565933) (xy 25.107115 -156.383269) (xy 25.010988 -156.19681)
			(xy 24.92203 -156.006826) (xy 24.84037 -155.813594) (xy 24.766125 -155.617393) (xy 24.699403 -155.418507)
			(xy 24.640301 -155.217225) (xy 24.588905 -155.01384) (xy 24.54529 -154.808645) (xy 24.509518 -154.601938)
			(xy 24.481641 -154.394019) (xy 24.4617 -154.18519) (xy 24.449724 -153.975753) (xy 24.445731 -153.766012)
			(xy 20.489871 -153.766012) (xy 24.911304 -158.187644) (xy 24.931428 -158.208495) (xy 24.965526 -158.255345)
			(xy 24.991874 -158.306954) (xy 25.009822 -158.36205) (xy 25.018928 -158.419276) (xy 25.019508 -158.448248)
			(xy 25.019508 -161.154364) (xy 25.594308 -161.154364) (xy 25.598379 -161.098742) (xy 25.610505 -161.044305)
			(xy 25.630428 -160.992214) (xy 25.657724 -160.943579) (xy 25.69181 -160.899436) (xy 25.731959 -160.860727)
			(xy 25.777317 -160.828276) (xy 25.826917 -160.802775) (xy 25.879701 -160.784768) (xy 25.934544 -160.774638)
			(xy 25.990278 -160.772601) (xy 26.045715 -160.778701) (xy 26.099672 -160.792807) (xy 26.151001 -160.814619)
			(xy 26.198607 -160.843673) (xy 26.241475 -160.879348) (xy 26.278692 -160.920885) (xy 26.309465 -160.967398)
			(xy 26.309713 -160.967928) (xy 26.570432 -160.967928) (xy 26.570946 -160.940755) (xy 26.578642 -160.886956)
			(xy 26.593896 -160.834795) (xy 26.6164 -160.785326) (xy 26.645697 -160.739553) (xy 26.681194 -160.698402)
			(xy 26.722173 -160.662705) (xy 26.767804 -160.633187) (xy 26.817163 -160.610444) (xy 26.86925 -160.594938)
			(xy 26.89606 -160.590484) (xy 26.90991 -160.587923) (xy 26.935569 -160.576339) (xy 26.957091 -160.558192)
			(xy 26.972845 -160.53486) (xy 26.981632 -160.508114) (xy 26.982786 -160.479985) (xy 26.97622 -160.45261)
			(xy 26.96972 -160.440116) (xy 26.958096 -160.418623) (xy 26.939779 -160.373325) (xy 26.927382 -160.326061)
			(xy 26.921109 -160.277603) (xy 26.920698 -160.253172) (xy 26.920698 -160.252918) (xy 26.921172 -160.225665)
			(xy 26.928927 -160.171714) (xy 26.944281 -160.119416) (xy 26.966922 -160.069836) (xy 26.996388 -160.023982)
			(xy 27.032081 -159.982789) (xy 27.073273 -159.947096) (xy 27.119125 -159.917627) (xy 27.168705 -159.894985)
			(xy 27.221003 -159.879629) (xy 27.274953 -159.871873) (xy 27.302206 -159.87141) (xy 27.329163 -159.871906)
			(xy 27.38254 -159.879496) (xy 27.434317 -159.894525) (xy 27.483463 -159.916692) (xy 27.528999 -159.945556)
			(xy 27.570019 -159.980543) (xy 27.58821 -160.000442) (xy 27.5982 -160.011136) (xy 27.622961 -160.026717)
			(xy 27.651124 -160.034637) (xy 27.680377 -160.034246) (xy 27.708318 -160.025576) (xy 27.732653 -160.009339)
			(xy 27.742388 -159.99841) (xy 27.760611 -159.977409) (xy 27.802113 -159.940408) (xy 27.848545 -159.909821)
			(xy 27.898924 -159.886295) (xy 27.952183 -159.870329) (xy 28.007195 -159.86226) (xy 28.034996 -159.861758)
			(xy 28.062246 -159.862281) (xy 28.11619 -159.870036) (xy 28.168482 -159.885389) (xy 28.218057 -159.908028)
			(xy 28.263906 -159.93749) (xy 28.305095 -159.973178) (xy 28.340787 -160.014364) (xy 28.370254 -160.060209)
			(xy 28.392897 -160.109782) (xy 28.408255 -160.162073) (xy 28.416016 -160.216016) (xy 28.416504 -160.243266)
			(xy 28.41498 -160.278064) (xy 28.414165 -160.293081) (xy 28.420272 -160.322513) (xy 28.434692 -160.348886)
			(xy 28.456174 -160.369911) (xy 28.482851 -160.383762) (xy 28.49753 -160.38703) (xy 28.526432 -160.392984)
			(xy 28.582076 -160.412623) (xy 28.634041 -160.440578) (xy 28.681095 -160.476185) (xy 28.702 -160.497012)
			(xy 28.713208 -160.507706) (xy 28.740419 -160.522471) (xy 28.770798 -160.528431) (xy 28.801571 -160.525042)
			(xy 28.829926 -160.512612) (xy 28.841954 -160.502854) (xy 28.862882 -160.485154) (xy 28.908886 -160.455355)
			(xy 28.958685 -160.432455) (xy 29.011251 -160.416926) (xy 29.0655 -160.409088) (xy 29.092906 -160.40862)
			(xy 29.09316 -160.40862) (xy 29.122313 -160.409181) (xy 29.179938 -160.41806) (xy 29.235541 -160.435603)
			(xy 29.287829 -160.4614) (xy 29.335584 -160.494852) (xy 29.377693 -160.535179) (xy 29.413177 -160.581443)
			(xy 29.427678 -160.60674) (xy 29.435187 -160.619327) (xy 29.455948 -160.639992) (xy 29.481718 -160.653918)
			(xy 29.510381 -160.659958) (xy 29.53958 -160.657617) (xy 29.566914 -160.647087) (xy 29.590137 -160.629234)
			(xy 29.599128 -160.617662) (xy 29.61455 -160.596998) (xy 29.650085 -160.559636) (xy 29.690329 -160.5274)
			(xy 29.734547 -160.500876) (xy 29.781933 -160.480549) (xy 29.831626 -160.466789) (xy 29.882719 -160.459845)
			(xy 29.9085 -160.45942) (xy 29.934856 -160.459881) (xy 29.987065 -160.467149) (xy 30.037778 -160.481532)
			(xy 30.086028 -160.502757) (xy 30.130899 -160.53042) (xy 30.171536 -160.563994) (xy 30.189678 -160.583118)
			(xy 30.198948 -160.592739) (xy 30.221445 -160.607141) (xy 30.246909 -160.615206) (xy 30.273594 -160.616381)
			(xy 30.299669 -160.610586) (xy 30.323344 -160.598219) (xy 30.333442 -160.589468) (xy 30.354685 -160.570621)
			(xy 30.4017 -160.53877) (xy 30.452918 -160.514243) (xy 30.507207 -160.497582) (xy 30.563366 -160.489155)
			(xy 30.59176 -160.48863) (xy 30.619017 -160.489014) (xy 30.672978 -160.496767) (xy 30.725286 -160.512121)
			(xy 30.774876 -160.534764) (xy 30.820739 -160.564234) (xy 30.861941 -160.599931) (xy 30.897642 -160.641129)
			(xy 30.927117 -160.686989) (xy 30.949765 -160.736576) (xy 30.965124 -160.788883) (xy 30.972883 -160.842843)
			(xy 30.972883 -160.897357) (xy 30.965124 -160.951317) (xy 30.949765 -161.003624) (xy 30.927117 -161.053211)
			(xy 30.897642 -161.099071) (xy 30.861941 -161.140269) (xy 30.820739 -161.175966) (xy 30.774876 -161.205436)
			(xy 30.725286 -161.228079) (xy 30.672978 -161.243433) (xy 30.619017 -161.251186) (xy 30.59176 -161.251646)
			(xy 30.565402 -161.251223) (xy 30.513191 -161.243949) (xy 30.462478 -161.229559) (xy 30.414227 -161.208327)
			(xy 30.369357 -161.180657) (xy 30.328723 -161.147075) (xy 30.310582 -161.127948) (xy 30.301256 -161.118382)
			(xy 30.278778 -161.103969) (xy 30.253326 -161.095892) (xy 30.22665 -161.094705) (xy 30.200582 -161.100491)
			(xy 30.176913 -161.112851) (xy 30.166818 -161.121598) (xy 30.145586 -161.140458) (xy 30.098569 -161.172308)
			(xy 30.047348 -161.196834) (xy 29.993056 -161.213491) (xy 29.936895 -161.221913) (xy 29.9085 -161.222436)
			(xy 29.879345 -161.22193) (xy 29.821716 -161.213043) (xy 29.76611 -161.195493) (xy 29.713822 -161.169687)
			(xy 29.666068 -161.136226) (xy 29.62396 -161.09589) (xy 29.58848 -161.049617) (xy 29.573982 -161.024316)
			(xy 29.566526 -161.011692) (xy 29.545759 -160.991013) (xy 29.519977 -160.977081) (xy 29.491299 -160.971041)
			(xy 29.462087 -160.973391) (xy 29.434744 -160.983937) (xy 29.41152 -161.001811) (xy 29.402532 -161.013394)
			(xy 29.387061 -161.03402) (xy 29.351535 -161.071385) (xy 29.311301 -161.103626) (xy 29.267092 -161.130155)
			(xy 29.219712 -161.150488) (xy 29.170026 -161.164256) (xy 29.118939 -161.171207) (xy 29.09316 -161.171636)
			(xy 29.067638 -161.171269) (xy 29.017049 -161.164468) (xy 28.967819 -161.15098) (xy 28.920828 -161.131046)
			(xy 28.876916 -161.105023) (xy 28.836868 -161.073374) (xy 28.81884 -161.055304) (xy 28.807683 -161.044552)
			(xy 28.780455 -161.02979) (xy 28.750059 -161.02384) (xy 28.719275 -161.027244) (xy 28.690915 -161.039693)
			(xy 28.678886 -161.049462) (xy 28.657945 -161.067146) (xy 28.611944 -161.096946) (xy 28.562148 -161.119849)
			(xy 28.509585 -161.135382) (xy 28.455339 -161.143225) (xy 28.427934 -161.143696) (xy 28.42768 -161.143696)
			(xy 28.400428 -161.143241) (xy 28.346478 -161.135481) (xy 28.294182 -161.120123) (xy 28.244604 -161.097479)
			(xy 28.198753 -161.068009) (xy 28.157563 -161.032314) (xy 28.121872 -160.991121) (xy 28.092406 -160.945268)
			(xy 28.069766 -160.895688) (xy 28.054412 -160.84339) (xy 28.046657 -160.78944) (xy 28.046172 -160.762188)
			(xy 28.047696 -160.72739) (xy 28.048492 -160.712374) (xy 28.042378 -160.682951) (xy 28.027959 -160.656584)
			(xy 28.006486 -160.635559) (xy 27.97982 -160.6217) (xy 27.965146 -160.618424) (xy 27.94033 -160.613351)
			(xy 27.892202 -160.597564) (xy 27.846588 -160.575544) (xy 27.804291 -160.54768) (xy 27.766054 -160.514462)
			(xy 27.748992 -160.495742) (xy 27.738999 -160.485052) (xy 27.714238 -160.469473) (xy 27.686077 -160.461554)
			(xy 27.656825 -160.461945) (xy 27.628885 -160.470613) (xy 27.604549 -160.486847) (xy 27.594814 -160.497774)
			(xy 27.576613 -160.51873) (xy 27.535206 -160.555693) (xy 27.48888 -160.586264) (xy 27.438613 -160.6098)
			(xy 27.385466 -160.625802) (xy 27.358086 -160.630362) (xy 27.344215 -160.632826) (xy 27.318551 -160.644429)
			(xy 27.297027 -160.662594) (xy 27.281276 -160.685943) (xy 27.272494 -160.712704) (xy 27.271346 -160.740845)
			(xy 27.277921 -160.768232) (xy 27.284426 -160.78073) (xy 27.296071 -160.802211) (xy 27.314383 -160.847515)
			(xy 27.326773 -160.894782) (xy 27.33304 -160.943242) (xy 27.333448 -160.967674) (xy 27.333448 -160.967928)
			(xy 27.332962 -160.995179) (xy 27.325206 -161.049127) (xy 27.309851 -161.101422) (xy 27.287209 -161.150999)
			(xy 27.257743 -161.196849) (xy 27.222052 -161.23804) (xy 27.180861 -161.273731) (xy 27.135011 -161.303197)
			(xy 27.085434 -161.325839) (xy 27.033139 -161.341194) (xy 26.979191 -161.34895) (xy 26.924689 -161.34895)
			(xy 26.870741 -161.341194) (xy 26.818446 -161.325839) (xy 26.768869 -161.303197) (xy 26.723019 -161.273731)
			(xy 26.681828 -161.23804) (xy 26.646137 -161.196849) (xy 26.616671 -161.150999) (xy 26.594029 -161.101422)
			(xy 26.578674 -161.049127) (xy 26.570918 -160.995179) (xy 26.570432 -160.967928) (xy 26.309713 -160.967928)
			(xy 26.333137 -161.017895) (xy 26.349205 -161.071302) (xy 26.357325 -161.126478) (xy 26.357834 -161.154364)
			(xy 26.357325 -161.18225) (xy 26.349205 -161.237426) (xy 26.333137 -161.290833) (xy 26.309465 -161.34133)
			(xy 26.278692 -161.387843) (xy 26.241475 -161.42938) (xy 26.198607 -161.465055) (xy 26.151001 -161.494109)
			(xy 26.099672 -161.515921) (xy 26.045715 -161.530027) (xy 25.990278 -161.536127) (xy 25.934544 -161.53409)
			(xy 25.879701 -161.52396) (xy 25.826917 -161.505953) (xy 25.777317 -161.480452) (xy 25.731959 -161.448001)
			(xy 25.69181 -161.409292) (xy 25.657724 -161.365149) (xy 25.630428 -161.316514) (xy 25.610505 -161.264423)
			(xy 25.598379 -161.209986) (xy 25.594308 -161.154364) (xy 25.019508 -161.154364) (xy 25.019508 -162.067748)
			(xy 30.453582 -162.067748) (xy 30.457653 -162.012126) (xy 30.469779 -161.957689) (xy 30.489702 -161.905598)
			(xy 30.516998 -161.856963) (xy 30.551084 -161.81282) (xy 30.591233 -161.774111) (xy 30.636591 -161.74166)
			(xy 30.686191 -161.716159) (xy 30.738975 -161.698152) (xy 30.793818 -161.688022) (xy 30.849552 -161.685985)
			(xy 30.904989 -161.692085) (xy 30.958946 -161.706191) (xy 31.010275 -161.728003) (xy 31.057881 -161.757057)
			(xy 31.100749 -161.792732) (xy 31.137966 -161.834269) (xy 31.168739 -161.880782) (xy 31.192411 -161.931279)
			(xy 31.208479 -161.984686) (xy 31.216599 -162.039862) (xy 31.217108 -162.067748) (xy 31.216599 -162.095634)
			(xy 31.208479 -162.15081) (xy 31.192411 -162.204217) (xy 31.168739 -162.254714) (xy 31.137966 -162.301227)
			(xy 31.100749 -162.342764) (xy 31.057881 -162.378439) (xy 31.010275 -162.407493) (xy 30.958946 -162.429305)
			(xy 30.904989 -162.443411) (xy 30.849552 -162.449511) (xy 30.793818 -162.447474) (xy 30.738975 -162.437344)
			(xy 30.686191 -162.419337) (xy 30.636591 -162.393836) (xy 30.591233 -162.361385) (xy 30.551084 -162.322676)
			(xy 30.516998 -162.278533) (xy 30.489702 -162.229898) (xy 30.469779 -162.177807) (xy 30.457653 -162.12337)
			(xy 30.453582 -162.067748) (xy 25.019508 -162.067748) (xy 25.019508 -162.586162) (xy 33.079942 -162.586162)
			(xy 33.084013 -162.53054) (xy 33.096139 -162.476103) (xy 33.116062 -162.424012) (xy 33.143358 -162.375377)
			(xy 33.177444 -162.331234) (xy 33.217593 -162.292525) (xy 33.262951 -162.260074) (xy 33.312551 -162.234573)
			(xy 33.365335 -162.216566) (xy 33.420178 -162.206436) (xy 33.475912 -162.204399) (xy 33.531349 -162.210499)
			(xy 33.585306 -162.224605) (xy 33.636635 -162.246417) (xy 33.684241 -162.275471) (xy 33.727109 -162.311146)
			(xy 33.764326 -162.352683) (xy 33.795099 -162.399196) (xy 33.818771 -162.449693) (xy 33.834839 -162.5031)
			(xy 33.842959 -162.558276) (xy 33.843468 -162.586162) (xy 33.842959 -162.614048) (xy 33.834839 -162.669224)
			(xy 33.818771 -162.722631) (xy 33.795099 -162.773128) (xy 33.764326 -162.819641) (xy 33.727109 -162.861178)
			(xy 33.684241 -162.896853) (xy 33.636635 -162.925907) (xy 33.585306 -162.947719) (xy 33.531349 -162.961825)
			(xy 33.475912 -162.967925) (xy 33.420178 -162.965888) (xy 33.365335 -162.955758) (xy 33.312551 -162.937751)
			(xy 33.262951 -162.91225) (xy 33.217593 -162.879799) (xy 33.177444 -162.84109) (xy 33.143358 -162.796947)
			(xy 33.116062 -162.748312) (xy 33.096139 -162.696221) (xy 33.084013 -162.641784) (xy 33.079942 -162.586162)
			(xy 25.019508 -162.586162) (xy 25.019508 -163.617402) (xy 31.594042 -163.617402) (xy 31.598113 -163.56178)
			(xy 31.610239 -163.507343) (xy 31.630162 -163.455252) (xy 31.657458 -163.406617) (xy 31.691544 -163.362474)
			(xy 31.731693 -163.323765) (xy 31.777051 -163.291314) (xy 31.826651 -163.265813) (xy 31.879435 -163.247806)
			(xy 31.934278 -163.237676) (xy 31.990012 -163.235639) (xy 32.045449 -163.241739) (xy 32.099406 -163.255845)
			(xy 32.150735 -163.277657) (xy 32.198341 -163.306711) (xy 32.241209 -163.342386) (xy 32.278426 -163.383923)
			(xy 32.309199 -163.430436) (xy 32.332871 -163.480933) (xy 32.348939 -163.53434) (xy 32.357059 -163.589516)
			(xy 32.357568 -163.617402) (xy 32.357059 -163.645288) (xy 32.348939 -163.700464) (xy 32.332871 -163.753871)
			(xy 32.309199 -163.804368) (xy 32.278426 -163.850881) (xy 32.241209 -163.892418) (xy 32.198341 -163.928093)
			(xy 32.150735 -163.957147) (xy 32.099406 -163.978959) (xy 32.045449 -163.993065) (xy 31.990012 -163.999165)
			(xy 31.934278 -163.997128) (xy 31.879435 -163.986998) (xy 31.826651 -163.968991) (xy 31.777051 -163.94349)
			(xy 31.731693 -163.911039) (xy 31.691544 -163.87233) (xy 31.657458 -163.828187) (xy 31.630162 -163.779552)
			(xy 31.610239 -163.727461) (xy 31.598113 -163.673024) (xy 31.594042 -163.617402) (xy 25.019508 -163.617402)
			(xy 25.019508 -164.302694) (xy 33.044382 -164.302694) (xy 33.048453 -164.247072) (xy 33.060579 -164.192635)
			(xy 33.080502 -164.140544) (xy 33.107798 -164.091909) (xy 33.141884 -164.047766) (xy 33.182033 -164.009057)
			(xy 33.227391 -163.976606) (xy 33.276991 -163.951105) (xy 33.329775 -163.933098) (xy 33.384618 -163.922968)
			(xy 33.440352 -163.920931) (xy 33.495789 -163.927031) (xy 33.549746 -163.941137) (xy 33.601075 -163.962949)
			(xy 33.648681 -163.992003) (xy 33.691549 -164.027678) (xy 33.728766 -164.069215) (xy 33.759539 -164.115728)
			(xy 33.783211 -164.166225) (xy 33.799279 -164.219632) (xy 33.807399 -164.274808) (xy 33.807908 -164.302694)
			(xy 33.807399 -164.33058) (xy 33.799279 -164.385756) (xy 33.783211 -164.439163) (xy 33.759539 -164.48966)
			(xy 33.728766 -164.536173) (xy 33.691549 -164.57771) (xy 33.648681 -164.613385) (xy 33.601075 -164.642439)
			(xy 33.549746 -164.664251) (xy 33.495789 -164.678357) (xy 33.440352 -164.684457) (xy 33.384618 -164.68242)
			(xy 33.329775 -164.67229) (xy 33.276991 -164.654283) (xy 33.227391 -164.628782) (xy 33.182033 -164.596331)
			(xy 33.141884 -164.557622) (xy 33.107798 -164.513479) (xy 33.080502 -164.464844) (xy 33.060579 -164.412753)
			(xy 33.048453 -164.358316) (xy 33.044382 -164.302694) (xy 25.019508 -164.302694) (xy 25.019508 -164.700712)
			(xy 25.018952 -164.729687) (xy 25.009849 -164.786917) (xy 24.991901 -164.842017) (xy 24.96555 -164.893629)
			(xy 24.931446 -164.94048) (xy 24.911304 -164.961316) (xy 24.281516 -165.591236) (xy 30.677612 -165.591236)
			(xy 30.678089 -165.563983) (xy 30.685841 -165.510032) (xy 30.701194 -165.457733) (xy 30.723834 -165.408151)
			(xy 30.7533 -165.362297) (xy 30.788992 -165.321104) (xy 30.830184 -165.285409) (xy 30.876037 -165.255941)
			(xy 30.925618 -165.2333) (xy 30.977916 -165.217945) (xy 31.031867 -165.21019) (xy 31.05912 -165.209728)
			(xy 31.074876 -165.20987) (xy 31.106285 -165.21241) (xy 31.121858 -165.214808) (xy 31.136247 -165.216682)
			(xy 31.165042 -165.213223) (xy 31.191699 -165.2018) (xy 31.214065 -165.183337) (xy 31.230331 -165.159326)
			(xy 31.239182 -165.131707) (xy 31.239903 -165.102714) (xy 31.236666 -165.08857) (xy 31.230726 -165.064625)
			(xy 31.224354 -165.015702) (xy 31.223966 -164.991034) (xy 31.223966 -164.99078) (xy 31.224477 -164.963529)
			(xy 31.232236 -164.909581) (xy 31.247594 -164.857286) (xy 31.270238 -164.80771) (xy 31.299707 -164.76186)
			(xy 31.335401 -164.720672) (xy 31.376594 -164.684982) (xy 31.422447 -164.655518) (xy 31.472026 -164.63288)
			(xy 31.524322 -164.617527) (xy 31.57827 -164.609774) (xy 31.632773 -164.609777) (xy 31.686721 -164.617537)
			(xy 31.739016 -164.632895) (xy 31.788592 -164.655539) (xy 31.834441 -164.685009) (xy 31.87563 -164.720703)
			(xy 31.911319 -164.761896) (xy 31.940783 -164.807748) (xy 31.963421 -164.857327) (xy 31.978773 -164.909624)
			(xy 31.986526 -164.963572) (xy 31.986523 -165.018075) (xy 31.978763 -165.072023) (xy 31.963404 -165.124318)
			(xy 31.94076 -165.173894) (xy 31.91129 -165.219743) (xy 31.875596 -165.260931) (xy 31.834403 -165.29662)
			(xy 31.78855 -165.326084) (xy 31.738971 -165.348722) (xy 31.686674 -165.364074) (xy 31.632726 -165.371827)
			(xy 31.605474 -165.372288) (xy 31.589718 -165.372146) (xy 31.558309 -165.369606) (xy 31.542736 -165.367208)
			(xy 31.528349 -165.365308) (xy 31.49955 -165.368769) (xy 31.472889 -165.380195) (xy 31.450522 -165.398663)
			(xy 31.434256 -165.422679) (xy 31.425406 -165.450303) (xy 31.424689 -165.4793) (xy 31.427928 -165.493446)
			(xy 31.433885 -165.517453) (xy 31.440254 -165.566504) (xy 31.440628 -165.591236) (xy 31.440072 -165.62106)
			(xy 31.430817 -165.679986) (xy 31.412508 -165.736754) (xy 31.385589 -165.789982) (xy 31.350717 -165.838374)
			(xy 31.330138 -165.859968) (xy 31.320921 -165.869896) (xy 31.307608 -165.893478) (xy 31.300954 -165.919729)
			(xy 31.301426 -165.946805) (xy 31.308991 -165.972808) (xy 31.323119 -165.995911) (xy 31.332678 -166.00551)
			(xy 31.351326 -166.023609) (xy 31.384039 -166.063986) (xy 31.410967 -166.108431) (xy 31.43161 -166.15612)
			(xy 31.445586 -166.206172) (xy 31.452637 -166.257657) (xy 31.453074 -166.28364) (xy 31.452588 -166.310891)
			(xy 31.444832 -166.364839) (xy 31.429477 -166.417134) (xy 31.406835 -166.466711) (xy 31.377369 -166.512561)
			(xy 31.341678 -166.553752) (xy 31.300487 -166.589443) (xy 31.254637 -166.618909) (xy 31.20506 -166.641551)
			(xy 31.152765 -166.656906) (xy 31.098817 -166.664662) (xy 31.044315 -166.664662) (xy 30.990367 -166.656906)
			(xy 30.938072 -166.641551) (xy 30.888495 -166.618909) (xy 30.842645 -166.589443) (xy 30.801454 -166.553752)
			(xy 30.765763 -166.512561) (xy 30.736297 -166.466711) (xy 30.713655 -166.417134) (xy 30.6983 -166.364839)
			(xy 30.690544 -166.310891) (xy 30.690058 -166.28364) (xy 30.690058 -166.283386) (xy 30.690621 -166.253587)
			(xy 30.699903 -166.194717) (xy 30.718222 -166.138004) (xy 30.745134 -166.084828) (xy 30.779984 -166.036482)
			(xy 30.800548 -166.014908) (xy 30.809791 -166.005002) (xy 30.823104 -165.981413) (xy 30.829756 -165.955157)
			(xy 30.829279 -165.928075) (xy 30.821707 -165.902069) (xy 30.807572 -165.878964) (xy 30.798008 -165.869366)
			(xy 30.779346 -165.851282) (xy 30.746635 -165.810901) (xy 30.719709 -165.766453) (xy 30.699069 -165.71876)
			(xy 30.685095 -165.668707) (xy 30.678047 -165.61722) (xy 30.677612 -165.591236) (xy 24.281516 -165.591236)
			(xy 23.697184 -166.17569) (xy 23.697184 -166.25316) (xy 23.932132 -166.25316) (xy 23.936203 -166.197538)
			(xy 23.948329 -166.143101) (xy 23.968252 -166.09101) (xy 23.995548 -166.042375) (xy 24.029634 -165.998232)
			(xy 24.069783 -165.959523) (xy 24.115141 -165.927072) (xy 24.164741 -165.901571) (xy 24.217525 -165.883564)
			(xy 24.272368 -165.873434) (xy 24.328102 -165.871397) (xy 24.383539 -165.877497) (xy 24.437496 -165.891603)
			(xy 24.488825 -165.913415) (xy 24.536431 -165.942469) (xy 24.579299 -165.978144) (xy 24.616516 -166.019681)
			(xy 24.647289 -166.066194) (xy 24.670961 -166.116691) (xy 24.687029 -166.170098) (xy 24.695149 -166.225274)
			(xy 24.695658 -166.25316) (xy 24.695149 -166.281046) (xy 24.687029 -166.336222) (xy 24.670961 -166.389629)
			(xy 24.647289 -166.440126) (xy 24.616516 -166.486639) (xy 24.579299 -166.528176) (xy 24.536431 -166.563851)
			(xy 24.488825 -166.592905) (xy 24.437496 -166.614717) (xy 24.383539 -166.628823) (xy 24.328102 -166.634923)
			(xy 24.272368 -166.632886) (xy 24.217525 -166.622756) (xy 24.164741 -166.604749) (xy 24.115141 -166.579248)
			(xy 24.069783 -166.546797) (xy 24.029634 -166.508088) (xy 23.995548 -166.463945) (xy 23.968252 -166.41531)
			(xy 23.948329 -166.363219) (xy 23.936203 -166.308782) (xy 23.932132 -166.25316) (xy 23.697184 -166.25316)
			(xy 23.697184 -166.835836) (xy 23.696626 -166.86481) (xy 23.687519 -166.922037) (xy 23.669568 -166.977135)
			(xy 23.643213 -167.028743) (xy 23.609106 -167.07559) (xy 23.58898 -167.09644) (xy 23.141486 -167.543988)
			(xy 23.966422 -167.543988) (xy 23.970493 -167.488366) (xy 23.982619 -167.433929) (xy 24.002542 -167.381838)
			(xy 24.029838 -167.333203) (xy 24.063924 -167.28906) (xy 24.104073 -167.250351) (xy 24.149431 -167.2179)
			(xy 24.199031 -167.192399) (xy 24.251815 -167.174392) (xy 24.306658 -167.164262) (xy 24.362392 -167.162225)
			(xy 24.417829 -167.168325) (xy 24.471786 -167.182431) (xy 24.523115 -167.204243) (xy 24.570721 -167.233297)
			(xy 24.613589 -167.268972) (xy 24.650806 -167.310509) (xy 24.681579 -167.357022) (xy 24.705251 -167.407519)
			(xy 24.721319 -167.460926) (xy 24.729439 -167.516102) (xy 24.729948 -167.543988) (xy 24.729439 -167.571874)
			(xy 24.721319 -167.62705) (xy 24.705251 -167.680457) (xy 24.681579 -167.730954) (xy 24.650806 -167.777467)
			(xy 24.613589 -167.819004) (xy 24.570721 -167.854679) (xy 24.523115 -167.883733) (xy 24.471786 -167.905545)
			(xy 24.417829 -167.919651) (xy 24.362392 -167.925751) (xy 24.306658 -167.923714) (xy 24.251815 -167.913584)
			(xy 24.199031 -167.895577) (xy 24.149431 -167.870076) (xy 24.104073 -167.837625) (xy 24.063924 -167.798916)
			(xy 24.029838 -167.754773) (xy 24.002542 -167.706138) (xy 23.982619 -167.654047) (xy 23.970493 -167.59961)
			(xy 23.966422 -167.543988) (xy 23.141486 -167.543988) (xy 22.558626 -168.126918) (xy 26.807412 -168.126918)
			(xy 26.811483 -168.071296) (xy 26.823609 -168.016859) (xy 26.843532 -167.964768) (xy 26.870828 -167.916133)
			(xy 26.904914 -167.87199) (xy 26.945063 -167.833281) (xy 26.990421 -167.80083) (xy 27.040021 -167.775329)
			(xy 27.092805 -167.757322) (xy 27.147648 -167.747192) (xy 27.203382 -167.745155) (xy 27.258819 -167.751255)
			(xy 27.312776 -167.765361) (xy 27.364105 -167.787173) (xy 27.411711 -167.816227) (xy 27.454579 -167.851902)
			(xy 27.491796 -167.893439) (xy 27.522569 -167.939952) (xy 27.545203 -167.988234) (xy 29.594808 -167.988234)
			(xy 29.598879 -167.932612) (xy 29.611005 -167.878175) (xy 29.630928 -167.826084) (xy 29.658224 -167.777449)
			(xy 29.69231 -167.733306) (xy 29.732459 -167.694597) (xy 29.777817 -167.662146) (xy 29.827417 -167.636645)
			(xy 29.880201 -167.618638) (xy 29.935044 -167.608508) (xy 29.990778 -167.606471) (xy 30.046215 -167.612571)
			(xy 30.100172 -167.626677) (xy 30.151501 -167.648489) (xy 30.199107 -167.677543) (xy 30.241975 -167.713218)
			(xy 30.279192 -167.754755) (xy 30.309965 -167.801268) (xy 30.333637 -167.851765) (xy 30.349705 -167.905172)
			(xy 30.357825 -167.960348) (xy 30.358334 -167.988234) (xy 30.357825 -168.01612) (xy 30.349705 -168.071296)
			(xy 30.333637 -168.124703) (xy 30.309965 -168.1752) (xy 30.279192 -168.221713) (xy 30.241975 -168.26325)
			(xy 30.199107 -168.298925) (xy 30.151501 -168.327979) (xy 30.100172 -168.349791) (xy 30.046215 -168.363897)
			(xy 29.990778 -168.369997) (xy 29.935044 -168.36796) (xy 29.880201 -168.35783) (xy 29.827417 -168.339823)
			(xy 29.777817 -168.314322) (xy 29.732459 -168.281871) (xy 29.69231 -168.243162) (xy 29.658224 -168.199019)
			(xy 29.630928 -168.150384) (xy 29.611005 -168.098293) (xy 29.598879 -168.043856) (xy 29.594808 -167.988234)
			(xy 27.545203 -167.988234) (xy 27.546241 -167.990449) (xy 27.562309 -168.043856) (xy 27.570429 -168.099032)
			(xy 27.570938 -168.126918) (xy 27.570429 -168.154804) (xy 27.562309 -168.20998) (xy 27.546241 -168.263387)
			(xy 27.522569 -168.313884) (xy 27.491796 -168.360397) (xy 27.454579 -168.401934) (xy 27.411711 -168.437609)
			(xy 27.364105 -168.466663) (xy 27.312776 -168.488475) (xy 27.258819 -168.502581) (xy 27.203382 -168.508681)
			(xy 27.147648 -168.506644) (xy 27.092805 -168.496514) (xy 27.040021 -168.478507) (xy 26.990421 -168.453006)
			(xy 26.945063 -168.420555) (xy 26.904914 -168.381846) (xy 26.870828 -168.337703) (xy 26.843532 -168.289068)
			(xy 26.823609 -168.236977) (xy 26.811483 -168.18254) (xy 26.807412 -168.126918) (xy 22.558626 -168.126918)
			(xy 22.097671 -168.587928) (xy 24.769316 -168.587928) (xy 24.773387 -168.532306) (xy 24.785513 -168.477869)
			(xy 24.805436 -168.425778) (xy 24.832732 -168.377143) (xy 24.866818 -168.333) (xy 24.906967 -168.294291)
			(xy 24.952325 -168.26184) (xy 25.001925 -168.236339) (xy 25.054709 -168.218332) (xy 25.109552 -168.208202)
			(xy 25.165286 -168.206165) (xy 25.220723 -168.212265) (xy 25.27468 -168.226371) (xy 25.326009 -168.248183)
			(xy 25.373615 -168.277237) (xy 25.416483 -168.312912) (xy 25.4537 -168.354449) (xy 25.484473 -168.400962)
			(xy 25.508145 -168.451459) (xy 25.524213 -168.504866) (xy 25.532333 -168.560042) (xy 25.532842 -168.587928)
			(xy 25.532333 -168.615814) (xy 25.524213 -168.67099) (xy 25.508145 -168.724397) (xy 25.484473 -168.774894)
			(xy 25.4537 -168.821407) (xy 25.416483 -168.862944) (xy 25.373615 -168.898619) (xy 25.326009 -168.927673)
			(xy 25.27468 -168.949485) (xy 25.220723 -168.963591) (xy 25.165286 -168.969691) (xy 25.109552 -168.967654)
			(xy 25.054709 -168.957524) (xy 25.001925 -168.939517) (xy 24.952325 -168.914016) (xy 24.906967 -168.881565)
			(xy 24.866818 -168.842856) (xy 24.832732 -168.798713) (xy 24.805436 -168.750078) (xy 24.785513 -168.697987)
			(xy 24.773387 -168.64355) (xy 24.769316 -168.587928) (xy 22.097671 -168.587928) (xy 21.5877 -169.09796)
			(xy 32.975802 -169.09796) (xy 32.979873 -169.042338) (xy 32.991999 -168.987901) (xy 33.011922 -168.93581)
			(xy 33.039218 -168.887175) (xy 33.073304 -168.843032) (xy 33.113453 -168.804323) (xy 33.158811 -168.771872)
			(xy 33.208411 -168.746371) (xy 33.261195 -168.728364) (xy 33.316038 -168.718234) (xy 33.371772 -168.716197)
			(xy 33.427209 -168.722297) (xy 33.481166 -168.736403) (xy 33.532495 -168.758215) (xy 33.580101 -168.787269)
			(xy 33.622969 -168.822944) (xy 33.660186 -168.864481) (xy 33.690959 -168.910994) (xy 33.714631 -168.961491)
			(xy 33.730699 -169.014898) (xy 33.738819 -169.070074) (xy 33.739328 -169.09796) (xy 33.738819 -169.125846)
			(xy 33.730699 -169.181022) (xy 33.714631 -169.234429) (xy 33.690959 -169.284926) (xy 33.660186 -169.331439)
			(xy 33.622969 -169.372976) (xy 33.580101 -169.408651) (xy 33.532495 -169.437705) (xy 33.481166 -169.459517)
			(xy 33.427209 -169.473623) (xy 33.371772 -169.479723) (xy 33.316038 -169.477686) (xy 33.261195 -169.467556)
			(xy 33.208411 -169.449549) (xy 33.158811 -169.424048) (xy 33.113453 -169.391597) (xy 33.073304 -169.352888)
			(xy 33.039218 -169.308745) (xy 33.011922 -169.26011) (xy 32.991999 -169.208019) (xy 32.979873 -169.153582)
			(xy 32.975802 -169.09796) (xy 21.5877 -169.09796) (xy 21.4757 -169.209974) (xy 21.472398 -169.215308)
			(xy 21.457508 -169.239098) (xy 21.421846 -169.282433) (xy 21.380222 -169.320078) (xy 21.333533 -169.35122)
			(xy 21.282786 -169.375189) (xy 21.229076 -169.391465) (xy 21.173561 -169.3997) (xy 21.1455 -169.40022)
			(xy 21.118248 -169.399734) (xy 21.0643 -169.391978) (xy 21.012005 -169.376623) (xy 20.962427 -169.353982)
			(xy 20.916575 -169.324516) (xy 20.875384 -169.288824) (xy 20.839691 -169.247634) (xy 20.810224 -169.201784)
			(xy 20.787581 -169.152207) (xy 20.772225 -169.099912) (xy 20.764467 -169.045964) (xy 20.763992 -169.018712)
			(xy 20.764353 -168.993916) (xy 20.770721 -168.944737) (xy 20.776692 -168.920668) (xy 20.786344 -168.884854)
			(xy 20.704556 -168.832276) (xy 20.682458 -168.854374) (xy 20.671536 -168.871138) (xy 20.656376 -168.893688)
			(xy 20.620689 -168.934659) (xy 20.57955 -168.970153) (xy 20.533792 -168.999452) (xy 20.484339 -169.021963)
			(xy 20.432194 -169.03723) (xy 20.378409 -169.044944) (xy 20.351242 -169.045382) (xy 20.323988 -169.044922)
			(xy 20.270034 -169.037169) (xy 20.217732 -169.021817) (xy 20.168149 -168.999176) (xy 20.122292 -168.969709)
			(xy 20.081097 -168.934015) (xy 20.045401 -168.892821) (xy 20.015932 -168.846965) (xy 19.993289 -168.797383)
			(xy 19.977934 -168.745082) (xy 19.97018 -168.691128) (xy 19.969734 -168.663874) (xy 19.970227 -168.635809)
			(xy 19.978443 -168.580283) (xy 19.99471 -168.526562) (xy 20.018676 -168.475805) (xy 20.049823 -168.429109)
			(xy 20.087477 -168.387483) (xy 20.130827 -168.351826) (xy 20.154646 -168.336976) (xy 20.15998 -168.333674)
			(xy 20.565872 -167.927528) (xy 20.575601 -167.916146) (xy 20.588598 -167.889188) (xy 20.593261 -167.859625)
			(xy 20.59178 -167.844724) (xy 20.58935 -167.830849) (xy 20.577937 -167.805108) (xy 20.559945 -167.783448)
			(xy 20.536735 -167.767505) (xy 20.510061 -167.758485) (xy 20.496022 -167.757348) (xy 20.484846 -167.757348)
			(xy 20.47367 -167.758872) (xy 20.47113 -167.759634) (xy 20.449177 -167.764603) (xy 20.404482 -167.769948)
			(xy 20.381976 -167.770302) (xy 20.381214 -167.770302) (xy 20.353961 -167.76984) (xy 20.300009 -167.762084)
			(xy 20.247711 -167.74673) (xy 20.19813 -167.724088) (xy 20.152275 -167.694621) (xy 20.111082 -167.658928)
			(xy 20.075387 -167.617736) (xy 20.045918 -167.571883) (xy 20.023275 -167.522302) (xy 20.007919 -167.470004)
			(xy 20.000161 -167.416053) (xy 20.000161 -167.361547) (xy 20.007919 -167.307596) (xy 20.023275 -167.255298)
			(xy 20.045918 -167.205717) (xy 20.075387 -167.159864) (xy 20.111082 -167.118672) (xy 20.152275 -167.082979)
			(xy 20.19813 -167.053512) (xy 20.247711 -167.03087) (xy 20.300009 -167.015516) (xy 20.353961 -167.00776)
			(xy 20.381214 -167.007286) (xy 20.404506 -167.007665) (xy 20.450737 -167.013393) (xy 20.473416 -167.018716)
			(xy 20.479512 -167.02024) (xy 20.594066 -167.02024) (xy 20.607177 -167.019185) (xy 20.632237 -167.011229)
			(xy 20.654431 -166.997131) (xy 20.672284 -166.977828) (xy 20.68461 -166.954602) (xy 20.690588 -166.928998)
			(xy 20.690586 -166.915846) (xy 20.690586 -166.906194) (xy 20.691091 -166.878458) (xy 20.699136 -166.823571)
			(xy 20.715041 -166.770427) (xy 20.738471 -166.720145) (xy 20.768932 -166.673784) (xy 20.805784 -166.632321)
			(xy 20.848249 -166.596628) (xy 20.895433 -166.567458) (xy 20.946343 -166.545425) (xy 20.999906 -166.530994)
			(xy 21.02739 -166.527226) (xy 21.051774 -166.524432) (xy 21.072094 -166.524432) (xy 21.098191 -166.524878)
			(xy 21.149894 -166.532029) (xy 21.200141 -166.546156) (xy 21.22424 -166.556182) (xy 21.248755 -166.567339)
			(xy 21.294643 -166.59554) (xy 21.336106 -166.629918) (xy 21.372319 -166.669788) (xy 21.387816 -166.691818)
			(xy 21.3967 -166.702627) (xy 21.419142 -166.71932) (xy 21.44527 -166.729299) (xy 21.473126 -166.731815)
			(xy 21.50062 -166.72668) (xy 21.52569 -166.714279) (xy 21.536406 -166.70528) (xy 21.754084 -166.487348)
			(xy 21.754084 -163.560252) (xy 21.754643 -163.531279) (xy 21.763751 -163.474051) (xy 21.781703 -163.418954)
			(xy 21.808056 -163.367346) (xy 21.842162 -163.320498) (xy 21.862288 -163.299648) (xy 23.367492 -161.79419)
			(xy 23.367492 -158.981648) (xy 22.773132 -158.387288) (xy 22.76217 -158.377047) (xy 22.735746 -158.362874)
			(xy 22.706346 -158.356984) (xy 22.676502 -158.359886) (xy 22.648786 -158.371328) (xy 22.625587 -158.390324)
			(xy 22.608904 -158.415239) (xy 22.600173 -158.443924) (xy 22.59965 -158.458916) (xy 22.59965 -159.107378)
			(xy 22.600114 -159.120649) (xy 22.607027 -159.146277) (xy 22.620314 -159.169256) (xy 22.639076 -159.188034)
			(xy 22.662044 -159.20134) (xy 22.687666 -159.208274) (xy 22.71421 -159.208369) (xy 22.727158 -159.205422)
			(xy 22.750801 -159.199616) (xy 22.799082 -159.193371) (xy 22.823424 -159.192976) (xy 22.824186 -159.192976)
			(xy 22.851441 -159.193438) (xy 22.905395 -159.201194) (xy 22.957697 -159.216549) (xy 23.007281 -159.239192)
			(xy 23.053138 -159.268661) (xy 23.094334 -159.304356) (xy 23.130031 -159.345551) (xy 23.159502 -159.391406)
			(xy 23.182146 -159.44099) (xy 23.197503 -159.493291) (xy 23.205261 -159.547245) (xy 23.205261 -159.601755)
			(xy 23.197503 -159.655709) (xy 23.182146 -159.70801) (xy 23.159502 -159.757594) (xy 23.130031 -159.803449)
			(xy 23.094334 -159.844644) (xy 23.053138 -159.880339) (xy 23.007281 -159.909808) (xy 22.957697 -159.932451)
			(xy 22.905395 -159.947806) (xy 22.851441 -159.955562) (xy 22.824186 -159.955992) (xy 22.823424 -159.955992)
			(xy 22.799084 -159.955571) (xy 22.750806 -159.949323) (xy 22.727158 -159.943546) (xy 22.714207 -159.940569)
			(xy 22.687644 -159.940641) (xy 22.661999 -159.947565) (xy 22.639009 -159.960872) (xy 22.620232 -159.979661)
			(xy 22.60694 -160.00266) (xy 22.600032 -160.028309) (xy 22.59965 -160.04159) (xy 22.59965 -162.349434)
			(xy 21.312378 -163.636706) (xy 21.301812 -163.648048) (xy 21.28747 -163.675513) (xy 21.282005 -163.706011)
			(xy 21.28592 -163.736746) (xy 21.298854 -163.764901) (xy 21.319621 -163.787894) (xy 21.332698 -163.796218)
			(xy 21.359383 -163.810018) (xy 21.409108 -163.843731) (xy 21.453846 -163.883827) (xy 21.492783 -163.929578)
			(xy 21.52521 -163.980151) (xy 21.550539 -164.034627) (xy 21.568308 -164.092015) (xy 21.578196 -164.151272)
			(xy 21.579586 -164.181282) (xy 21.57984 -164.19195) (xy 21.57984 -164.194744) (xy 21.579361 -164.223879)
			(xy 21.57175 -164.28165) (xy 21.556665 -164.337934) (xy 21.534363 -164.391767) (xy 21.505226 -164.442229)
			(xy 21.469752 -164.488457) (xy 21.428548 -164.52966) (xy 21.382319 -164.565132) (xy 21.331856 -164.594268)
			(xy 21.278022 -164.616569) (xy 21.221738 -164.631653) (xy 21.163967 -164.639262) (xy 21.134832 -164.639752)
			(xy 20.309586 -164.639752) (xy 19.816064 -165.13302) (xy 19.805879 -165.144004) (xy 19.791818 -165.170437)
			(xy 19.78602 -165.199811) (xy 19.788984 -165.229604) (xy 19.800455 -165.25726) (xy 19.819448 -165.280404)
			(xy 19.844334 -165.297051) (xy 19.872977 -165.305772) (xy 19.887946 -165.306248) (xy 21.12391 -165.306248)
			(xy 21.154314 -165.306767) (xy 21.214556 -165.315047) (xy 21.27311 -165.331453) (xy 21.328884 -165.355679)
			(xy 21.38084 -165.387274) (xy 21.428009 -165.425649) (xy 21.469514 -165.47009) (xy 21.504581 -165.519769)
			(xy 21.532557 -165.57376) (xy 21.55292 -165.631057) (xy 21.565292 -165.690593) (xy 21.569442 -165.75126)
			(xy 21.565292 -165.811927) (xy 21.55292 -165.871463) (xy 21.532557 -165.92876) (xy 21.504581 -165.982751)
			(xy 21.469514 -166.03243) (xy 21.428009 -166.076871) (xy 21.38084 -166.115246) (xy 21.328884 -166.146841)
			(xy 21.27311 -166.171067) (xy 21.214556 -166.187473) (xy 21.154314 -166.195753) (xy 21.12391 -166.196264)
			(xy 18.821146 -166.196264) (xy 15.674086 -169.343324) (xy 15.674086 -169.624756) (xy 18.555968 -169.624756)
			(xy 18.560039 -169.569134) (xy 18.572165 -169.514697) (xy 18.592088 -169.462606) (xy 18.619384 -169.413971)
			(xy 18.65347 -169.369828) (xy 18.693619 -169.331119) (xy 18.738977 -169.298668) (xy 18.788577 -169.273167)
			(xy 18.841361 -169.25516) (xy 18.896204 -169.24503) (xy 18.951938 -169.242993) (xy 19.007375 -169.249093)
			(xy 19.061332 -169.263199) (xy 19.112661 -169.285011) (xy 19.160267 -169.314065) (xy 19.203135 -169.34974)
			(xy 19.240352 -169.391277) (xy 19.271125 -169.43779) (xy 19.294797 -169.488287) (xy 19.310865 -169.541694)
			(xy 19.318985 -169.59687) (xy 19.319494 -169.624756) (xy 19.318985 -169.652642) (xy 19.318641 -169.654982)
			(xy 19.972272 -169.654982) (xy 19.976343 -169.59936) (xy 19.988469 -169.544923) (xy 20.008392 -169.492832)
			(xy 20.035688 -169.444197) (xy 20.069774 -169.400054) (xy 20.109923 -169.361345) (xy 20.155281 -169.328894)
			(xy 20.204881 -169.303393) (xy 20.257665 -169.285386) (xy 20.312508 -169.275256) (xy 20.368242 -169.273219)
			(xy 20.423679 -169.279319) (xy 20.477636 -169.293425) (xy 20.528965 -169.315237) (xy 20.576571 -169.344291)
			(xy 20.619439 -169.379966) (xy 20.656656 -169.421503) (xy 20.687429 -169.468016) (xy 20.711101 -169.518513)
			(xy 20.727169 -169.57192) (xy 20.735289 -169.627096) (xy 20.735798 -169.654982) (xy 20.735289 -169.682868)
			(xy 20.727169 -169.738044) (xy 20.711101 -169.791451) (xy 20.687429 -169.841948) (xy 20.681898 -169.850308)
			(xy 21.073362 -169.850308) (xy 21.077433 -169.794686) (xy 21.089559 -169.740249) (xy 21.109482 -169.688158)
			(xy 21.136778 -169.639523) (xy 21.170864 -169.59538) (xy 21.211013 -169.556671) (xy 21.256371 -169.52422)
			(xy 21.305971 -169.498719) (xy 21.358755 -169.480712) (xy 21.413598 -169.470582) (xy 21.469332 -169.468545)
			(xy 21.524769 -169.474645) (xy 21.572365 -169.487088) (xy 25.88082 -169.487088) (xy 25.884891 -169.431466)
			(xy 25.897017 -169.377029) (xy 25.91694 -169.324938) (xy 25.944236 -169.276303) (xy 25.978322 -169.23216)
			(xy 26.018471 -169.193451) (xy 26.063829 -169.161) (xy 26.113429 -169.135499) (xy 26.166213 -169.117492)
			(xy 26.221056 -169.107362) (xy 26.27679 -169.105325) (xy 26.332227 -169.111425) (xy 26.386184 -169.125531)
			(xy 26.437513 -169.147343) (xy 26.485119 -169.176397) (xy 26.527987 -169.212072) (xy 26.565204 -169.253609)
			(xy 26.595977 -169.300122) (xy 26.619649 -169.350619) (xy 26.635717 -169.404026) (xy 26.643837 -169.459202)
			(xy 26.644346 -169.487088) (xy 26.643837 -169.514974) (xy 26.635717 -169.57015) (xy 26.619649 -169.623557)
			(xy 26.595977 -169.674054) (xy 26.565204 -169.720567) (xy 26.527987 -169.762104) (xy 26.485119 -169.797779)
			(xy 26.437513 -169.826833) (xy 26.386184 -169.848645) (xy 26.332227 -169.862751) (xy 26.27679 -169.868851)
			(xy 26.221056 -169.866814) (xy 26.166213 -169.856684) (xy 26.113429 -169.838677) (xy 26.063829 -169.813176)
			(xy 26.018471 -169.780725) (xy 25.978322 -169.742016) (xy 25.944236 -169.697873) (xy 25.91694 -169.649238)
			(xy 25.897017 -169.597147) (xy 25.884891 -169.54271) (xy 25.88082 -169.487088) (xy 21.572365 -169.487088)
			(xy 21.578726 -169.488751) (xy 21.630055 -169.510563) (xy 21.677661 -169.539617) (xy 21.720529 -169.575292)
			(xy 21.757746 -169.616829) (xy 21.788519 -169.663342) (xy 21.812191 -169.713839) (xy 21.828259 -169.767246)
			(xy 21.836379 -169.822422) (xy 21.836888 -169.850308) (xy 21.836379 -169.878194) (xy 21.828259 -169.93337)
			(xy 21.812191 -169.986777) (xy 21.788519 -170.037274) (xy 21.757746 -170.083787) (xy 21.720529 -170.125324)
			(xy 21.677661 -170.160999) (xy 21.630055 -170.190053) (xy 21.578726 -170.211865) (xy 21.524769 -170.225971)
			(xy 21.469332 -170.232071) (xy 21.413598 -170.230034) (xy 21.358755 -170.219904) (xy 21.305971 -170.201897)
			(xy 21.256371 -170.176396) (xy 21.211013 -170.143945) (xy 21.170864 -170.105236) (xy 21.136778 -170.061093)
			(xy 21.109482 -170.012458) (xy 21.089559 -169.960367) (xy 21.077433 -169.90593) (xy 21.073362 -169.850308)
			(xy 20.681898 -169.850308) (xy 20.656656 -169.888461) (xy 20.619439 -169.929998) (xy 20.576571 -169.965673)
			(xy 20.528965 -169.994727) (xy 20.477636 -170.016539) (xy 20.423679 -170.030645) (xy 20.368242 -170.036745)
			(xy 20.312508 -170.034708) (xy 20.257665 -170.024578) (xy 20.204881 -170.006571) (xy 20.155281 -169.98107)
			(xy 20.109923 -169.948619) (xy 20.069774 -169.90991) (xy 20.035688 -169.865767) (xy 20.008392 -169.817132)
			(xy 19.988469 -169.765041) (xy 19.976343 -169.710604) (xy 19.972272 -169.654982) (xy 19.318641 -169.654982)
			(xy 19.310865 -169.707818) (xy 19.294797 -169.761225) (xy 19.271125 -169.811722) (xy 19.240352 -169.858235)
			(xy 19.203135 -169.899772) (xy 19.160267 -169.935447) (xy 19.112661 -169.964501) (xy 19.061332 -169.986313)
			(xy 19.007375 -170.000419) (xy 18.951938 -170.006519) (xy 18.896204 -170.004482) (xy 18.841361 -169.994352)
			(xy 18.788577 -169.976345) (xy 18.738977 -169.950844) (xy 18.693619 -169.918393) (xy 18.65347 -169.879684)
			(xy 18.619384 -169.835541) (xy 18.592088 -169.786906) (xy 18.572165 -169.734815) (xy 18.560039 -169.680378)
			(xy 18.555968 -169.624756) (xy 15.674086 -169.624756) (xy 15.674086 -177.745644) (xy 24.330912 -177.745644)
			(xy 24.334983 -177.690022) (xy 24.347109 -177.635585) (xy 24.367032 -177.583494) (xy 24.394328 -177.534859)
			(xy 24.428414 -177.490716) (xy 24.468563 -177.452007) (xy 24.513921 -177.419556) (xy 24.563521 -177.394055)
			(xy 24.616305 -177.376048) (xy 24.671148 -177.365918) (xy 24.726882 -177.363881) (xy 24.782319 -177.369981)
			(xy 24.836276 -177.384087) (xy 24.887605 -177.405899) (xy 24.935211 -177.434953) (xy 24.978079 -177.470628)
			(xy 25.015296 -177.512165) (xy 25.023956 -177.525254) (xy 35.243449 -177.525254) (xy 35.243449 -177.470746)
			(xy 35.251207 -177.416793) (xy 35.266564 -177.364493) (xy 35.289208 -177.314911) (xy 35.318678 -177.269056)
			(xy 35.354374 -177.227863) (xy 35.395569 -177.192168) (xy 35.441425 -177.1627) (xy 35.491008 -177.140058)
			(xy 35.543308 -177.124704) (xy 35.597262 -177.116948) (xy 35.624516 -177.116486) (xy 35.651886 -177.116946)
			(xy 35.706066 -177.124766) (xy 35.758569 -177.140257) (xy 35.808315 -177.163099) (xy 35.854282 -177.192825)
			(xy 35.875214 -177.210466) (xy 35.886542 -177.219702) (xy 35.913099 -177.231878) (xy 35.942016 -177.236051)
			(xy 35.970933 -177.231878) (xy 35.99749 -177.219702) (xy 36.008818 -177.210466) (xy 36.029766 -177.192847)
			(xy 36.075735 -177.163133) (xy 36.125478 -177.140294) (xy 36.177975 -177.124798) (xy 36.232148 -177.116964)
			(xy 36.259516 -177.116486) (xy 36.286766 -177.116985) (xy 36.340711 -177.124743) (xy 36.393003 -177.140099)
			(xy 36.442578 -177.162741) (xy 36.488425 -177.192207) (xy 36.529613 -177.227898) (xy 36.565302 -177.269087)
			(xy 36.594767 -177.314936) (xy 36.617406 -177.364512) (xy 36.63276 -177.416804) (xy 36.640516 -177.47075)
			(xy 36.640516 -177.52525) (xy 36.63276 -177.579196) (xy 36.617406 -177.631488) (xy 36.594767 -177.681064)
			(xy 36.565302 -177.726913) (xy 36.529613 -177.768102) (xy 36.488425 -177.803793) (xy 36.442578 -177.833259)
			(xy 36.393003 -177.855901) (xy 36.340711 -177.871257) (xy 36.286766 -177.879015) (xy 36.259516 -177.879502)
			(xy 36.232146 -177.879026) (xy 36.177967 -177.871211) (xy 36.125464 -177.855724) (xy 36.075717 -177.832884)
			(xy 36.02975 -177.803162) (xy 36.008818 -177.785522) (xy 35.99749 -177.776286) (xy 35.970933 -177.76411)
			(xy 35.942016 -177.759937) (xy 35.913099 -177.76411) (xy 35.886542 -177.776286) (xy 35.875214 -177.785522)
			(xy 35.85429 -177.803171) (xy 35.808315 -177.832881) (xy 35.758565 -177.855715) (xy 35.706063 -177.871203)
			(xy 35.651886 -177.879029) (xy 35.624516 -177.879502) (xy 35.597262 -177.879052) (xy 35.543308 -177.871296)
			(xy 35.491008 -177.855942) (xy 35.441425 -177.8333) (xy 35.395569 -177.803832) (xy 35.354374 -177.768137)
			(xy 35.318678 -177.726944) (xy 35.289208 -177.681089) (xy 35.266564 -177.631507) (xy 35.251207 -177.579207)
			(xy 35.243449 -177.525254) (xy 25.023956 -177.525254) (xy 25.046069 -177.558678) (xy 25.069741 -177.609175)
			(xy 25.085809 -177.662582) (xy 25.093929 -177.717758) (xy 25.094438 -177.745644) (xy 25.093929 -177.77353)
			(xy 25.085809 -177.828706) (xy 25.069741 -177.882113) (xy 25.046069 -177.93261) (xy 25.015296 -177.979123)
			(xy 24.978079 -178.02066) (xy 24.935211 -178.056335) (xy 24.887605 -178.085389) (xy 24.836276 -178.107201)
			(xy 24.782319 -178.121307) (xy 24.726882 -178.127407) (xy 24.671148 -178.12537) (xy 24.616305 -178.11524)
			(xy 24.563521 -178.097233) (xy 24.513921 -178.071732) (xy 24.468563 -178.039281) (xy 24.428414 -178.000572)
			(xy 24.394328 -177.956429) (xy 24.367032 -177.907794) (xy 24.347109 -177.855703) (xy 24.334983 -177.801266)
			(xy 24.330912 -177.745644) (xy 15.674086 -177.745644) (xy 15.674086 -178.265328) (xy 19.450302 -178.265328)
			(xy 19.454373 -178.209706) (xy 19.466499 -178.155269) (xy 19.486422 -178.103178) (xy 19.513718 -178.054543)
			(xy 19.547804 -178.0104) (xy 19.587953 -177.971691) (xy 19.633311 -177.93924) (xy 19.682911 -177.913739)
			(xy 19.735695 -177.895732) (xy 19.790538 -177.885602) (xy 19.846272 -177.883565) (xy 19.901709 -177.889665)
			(xy 19.955666 -177.903771) (xy 20.006995 -177.925583) (xy 20.054601 -177.954637) (xy 20.097469 -177.990312)
			(xy 20.134686 -178.031849) (xy 20.165459 -178.078362) (xy 20.189131 -178.128859) (xy 20.205199 -178.182266)
			(xy 20.213319 -178.237442) (xy 20.213828 -178.265328) (xy 20.213319 -178.293214) (xy 20.205199 -178.34839)
			(xy 20.189131 -178.401797) (xy 20.165459 -178.452294) (xy 20.134686 -178.498807) (xy 20.097469 -178.540344)
			(xy 20.054601 -178.576019) (xy 20.006995 -178.605073) (xy 19.955666 -178.626885) (xy 19.901709 -178.640991)
			(xy 19.846272 -178.647091) (xy 19.790538 -178.645054) (xy 19.735695 -178.634924) (xy 19.682911 -178.616917)
			(xy 19.633311 -178.591416) (xy 19.587953 -178.558965) (xy 19.547804 -178.520256) (xy 19.513718 -178.476113)
			(xy 19.486422 -178.427478) (xy 19.466499 -178.375387) (xy 19.454373 -178.32095) (xy 19.450302 -178.265328)
			(xy 15.674086 -178.265328) (xy 15.674086 -179.105814) (xy 20.700998 -179.105814) (xy 20.705069 -179.050192)
			(xy 20.717195 -178.995755) (xy 20.737118 -178.943664) (xy 20.764414 -178.895029) (xy 20.7985 -178.850886)
			(xy 20.838649 -178.812177) (xy 20.884007 -178.779726) (xy 20.933607 -178.754225) (xy 20.986391 -178.736218)
			(xy 21.041234 -178.726088) (xy 21.096968 -178.724051) (xy 21.152405 -178.730151) (xy 21.206362 -178.744257)
			(xy 21.257691 -178.766069) (xy 21.305297 -178.795123) (xy 21.348165 -178.830798) (xy 21.385382 -178.872335)
			(xy 21.416155 -178.918848) (xy 21.439827 -178.969345) (xy 21.455895 -179.022752) (xy 21.464015 -179.077928)
			(xy 21.464524 -179.105814) (xy 21.464015 -179.1337) (xy 21.455895 -179.188876) (xy 21.439827 -179.242283)
			(xy 21.416155 -179.29278) (xy 21.385382 -179.339293) (xy 21.348165 -179.38083) (xy 21.305297 -179.416505)
			(xy 21.257691 -179.445559) (xy 21.206362 -179.467371) (xy 21.152405 -179.481477) (xy 21.096968 -179.487577)
			(xy 21.041234 -179.48554) (xy 20.986391 -179.47541) (xy 20.933607 -179.457403) (xy 20.884007 -179.431902)
			(xy 20.838649 -179.399451) (xy 20.7985 -179.360742) (xy 20.764414 -179.316599) (xy 20.737118 -179.267964)
			(xy 20.717195 -179.215873) (xy 20.705069 -179.161436) (xy 20.700998 -179.105814) (xy 15.674086 -179.105814)
			(xy 15.674086 -179.563354) (xy 35.249545 -179.563354) (xy 35.249545 -179.508846) (xy 35.257302 -179.454892)
			(xy 35.272659 -179.402592) (xy 35.295303 -179.35301) (xy 35.324773 -179.307155) (xy 35.360469 -179.265961)
			(xy 35.401665 -179.230266) (xy 35.44752 -179.200798) (xy 35.497103 -179.178155) (xy 35.549404 -179.1628)
			(xy 35.603358 -179.155044) (xy 35.630612 -179.154582) (xy 35.657983 -179.155021) (xy 35.712164 -179.162842)
			(xy 35.764669 -179.178337) (xy 35.814415 -179.201185) (xy 35.86038 -179.230917) (xy 35.88131 -179.248562)
			(xy 35.892638 -179.257798) (xy 35.919195 -179.269974) (xy 35.948112 -179.274147) (xy 35.977029 -179.269974)
			(xy 36.003586 -179.257798) (xy 36.014914 -179.248562) (xy 36.035863 -179.230943) (xy 36.081831 -179.20123)
			(xy 36.131575 -179.17839) (xy 36.184072 -179.162894) (xy 36.238244 -179.155059) (xy 36.265612 -179.154582)
			(xy 36.292862 -179.155089) (xy 36.346807 -179.162847) (xy 36.399099 -179.178203) (xy 36.448673 -179.200844)
			(xy 36.494521 -179.23031) (xy 36.535708 -179.266) (xy 36.571398 -179.307189) (xy 36.600862 -179.353037)
			(xy 36.623502 -179.402612) (xy 36.638856 -179.454905) (xy 36.646612 -179.50885) (xy 36.646612 -179.56335)
			(xy 36.646611 -179.563354) (xy 40.532745 -179.563354) (xy 40.532745 -179.508846) (xy 40.540502 -179.454892)
			(xy 40.555859 -179.402592) (xy 40.578503 -179.35301) (xy 40.607973 -179.307155) (xy 40.643669 -179.265961)
			(xy 40.684865 -179.230266) (xy 40.73072 -179.200798) (xy 40.780303 -179.178155) (xy 40.832604 -179.1628)
			(xy 40.886558 -179.155044) (xy 40.913812 -179.154582) (xy 40.941183 -179.155021) (xy 40.995364 -179.162842)
			(xy 41.047869 -179.178337) (xy 41.097615 -179.201185) (xy 41.14358 -179.230917) (xy 41.16451 -179.248562)
			(xy 41.175838 -179.257798) (xy 41.202395 -179.269974) (xy 41.231312 -179.274147) (xy 41.260229 -179.269974)
			(xy 41.286786 -179.257798) (xy 41.298114 -179.248562) (xy 41.319063 -179.230943) (xy 41.365031 -179.20123)
			(xy 41.414775 -179.17839) (xy 41.467272 -179.162894) (xy 41.521444 -179.155059) (xy 41.548812 -179.154582)
			(xy 41.576062 -179.155089) (xy 41.630007 -179.162847) (xy 41.682299 -179.178203) (xy 41.731873 -179.200844)
			(xy 41.777721 -179.23031) (xy 41.818908 -179.266) (xy 41.854598 -179.307189) (xy 41.884062 -179.353037)
			(xy 41.906702 -179.402612) (xy 41.922056 -179.454905) (xy 41.929812 -179.50885) (xy 41.929812 -179.56335)
			(xy 41.922056 -179.617295) (xy 41.906702 -179.669588) (xy 41.884062 -179.719163) (xy 41.854598 -179.765011)
			(xy 41.818908 -179.8062) (xy 41.777721 -179.84189) (xy 41.731873 -179.871356) (xy 41.682299 -179.893997)
			(xy 41.630007 -179.909353) (xy 41.576062 -179.917111) (xy 41.548812 -179.917598) (xy 41.521442 -179.917125)
			(xy 41.467263 -179.909309) (xy 41.41476 -179.893822) (xy 41.365013 -179.870981) (xy 41.319046 -179.841258)
			(xy 41.298114 -179.823618) (xy 41.286786 -179.814382) (xy 41.260229 -179.802206) (xy 41.231312 -179.798033)
			(xy 41.202395 -179.802206) (xy 41.175838 -179.814382) (xy 41.16451 -179.823618) (xy 41.143587 -179.841269)
			(xy 41.097612 -179.870978) (xy 41.047862 -179.893812) (xy 40.995359 -179.9093) (xy 40.941182 -179.917125)
			(xy 40.913812 -179.917598) (xy 40.886558 -179.917156) (xy 40.832604 -179.9094) (xy 40.780303 -179.894045)
			(xy 40.73072 -179.871402) (xy 40.684865 -179.841934) (xy 40.643669 -179.806239) (xy 40.607973 -179.765045)
			(xy 40.578503 -179.71919) (xy 40.555859 -179.669608) (xy 40.540502 -179.617308) (xy 40.532745 -179.563354)
			(xy 36.646611 -179.563354) (xy 36.638856 -179.617295) (xy 36.623502 -179.669588) (xy 36.600862 -179.719163)
			(xy 36.571398 -179.765011) (xy 36.535708 -179.8062) (xy 36.494521 -179.84189) (xy 36.448673 -179.871356)
			(xy 36.399099 -179.893997) (xy 36.346807 -179.909353) (xy 36.292862 -179.917111) (xy 36.265612 -179.917598)
			(xy 36.238242 -179.917125) (xy 36.184063 -179.909309) (xy 36.13156 -179.893822) (xy 36.081813 -179.870981)
			(xy 36.035846 -179.841258) (xy 36.014914 -179.823618) (xy 36.003586 -179.814382) (xy 35.977029 -179.802206)
			(xy 35.948112 -179.798033) (xy 35.919195 -179.802206) (xy 35.892638 -179.814382) (xy 35.88131 -179.823618)
			(xy 35.860387 -179.841269) (xy 35.814412 -179.870978) (xy 35.764662 -179.893812) (xy 35.712159 -179.9093)
			(xy 35.657982 -179.917125) (xy 35.630612 -179.917598) (xy 35.603358 -179.917156) (xy 35.549404 -179.9094)
			(xy 35.497103 -179.894045) (xy 35.44752 -179.871402) (xy 35.401665 -179.841934) (xy 35.360469 -179.806239)
			(xy 35.324773 -179.765045) (xy 35.295303 -179.71919) (xy 35.272659 -179.669608) (xy 35.257302 -179.617308)
			(xy 35.249545 -179.563354) (xy 15.674086 -179.563354) (xy 15.674086 -181.176422) (xy 56.742582 -181.176422)
			(xy 56.746653 -181.1208) (xy 56.758779 -181.066363) (xy 56.778702 -181.014272) (xy 56.805998 -180.965637)
			(xy 56.840084 -180.921494) (xy 56.880233 -180.882785) (xy 56.925591 -180.850334) (xy 56.975191 -180.824833)
			(xy 57.027975 -180.806826) (xy 57.082818 -180.796696) (xy 57.138552 -180.794659) (xy 57.193989 -180.800759)
			(xy 57.247946 -180.814865) (xy 57.299275 -180.836677) (xy 57.346881 -180.865731) (xy 57.389749 -180.901406)
			(xy 57.426966 -180.942943) (xy 57.457739 -180.989456) (xy 57.481411 -181.039953) (xy 57.497479 -181.09336)
			(xy 57.505599 -181.148536) (xy 57.506108 -181.176422) (xy 57.505599 -181.204308) (xy 57.497479 -181.259484)
			(xy 57.481411 -181.312891) (xy 57.457739 -181.363388) (xy 57.426966 -181.409901) (xy 57.389749 -181.451438)
			(xy 57.346881 -181.487113) (xy 57.299275 -181.516167) (xy 57.247946 -181.537979) (xy 57.193989 -181.552085)
			(xy 57.138552 -181.558185) (xy 57.082818 -181.556148) (xy 57.027975 -181.546018) (xy 56.975191 -181.528011)
			(xy 56.925591 -181.50251) (xy 56.880233 -181.470059) (xy 56.840084 -181.43135) (xy 56.805998 -181.387207)
			(xy 56.778702 -181.338572) (xy 56.758779 -181.286481) (xy 56.746653 -181.232044) (xy 56.742582 -181.176422)
			(xy 15.674086 -181.176422) (xy 15.674086 -181.954932) (xy 23.963628 -181.954932) (xy 23.967699 -181.89931)
			(xy 23.979825 -181.844873) (xy 23.999748 -181.792782) (xy 24.027044 -181.744147) (xy 24.06113 -181.700004)
			(xy 24.101279 -181.661295) (xy 24.146637 -181.628844) (xy 24.196237 -181.603343) (xy 24.249021 -181.585336)
			(xy 24.303864 -181.575206) (xy 24.359598 -181.573169) (xy 24.415035 -181.579269) (xy 24.468992 -181.593375)
			(xy 24.520321 -181.615187) (xy 24.567927 -181.644241) (xy 24.610795 -181.679916) (xy 24.648012 -181.721453)
			(xy 24.678785 -181.767966) (xy 24.702457 -181.818463) (xy 24.718525 -181.87187) (xy 24.726645 -181.927046)
			(xy 24.727154 -181.954932) (xy 24.726645 -181.982818) (xy 24.718525 -182.037994) (xy 24.702457 -182.091401)
			(xy 24.678785 -182.141898) (xy 24.648012 -182.188411) (xy 24.610795 -182.229948) (xy 24.567927 -182.265623)
			(xy 24.520321 -182.294677) (xy 24.468992 -182.316489) (xy 24.415035 -182.330595) (xy 24.359598 -182.336695)
			(xy 24.303864 -182.334658) (xy 24.249021 -182.324528) (xy 24.196237 -182.306521) (xy 24.146637 -182.28102)
			(xy 24.101279 -182.248569) (xy 24.06113 -182.20986) (xy 24.027044 -182.165717) (xy 23.999748 -182.117082)
			(xy 23.979825 -182.064991) (xy 23.967699 -182.010554) (xy 23.963628 -181.954932) (xy 15.674086 -181.954932)
			(xy 15.674086 -182.090314) (xy 17.464278 -183.880506)
		)
		(stroke
			(width 0)
			(type solid)
		)
		(fill yes)
		(layer "In13.Cu")
		(net "GND")
	)
	(gr_poly
		(pts
			(xy 419.291262 -100.466398) (xy 419.306429 -100.465857) (xy 419.335432 -100.456974) (xy 419.360538 -100.439952)
			(xy 419.379527 -100.416299) (xy 419.390718 -100.388106) (xy 419.393121 -100.357869) (xy 419.390322 -100.342954)
			(xy 419.386154 -100.322636) (xy 419.3817 -100.281397) (xy 419.381432 -100.260658) (xy 419.381918 -100.233407)
			(xy 419.389674 -100.179459) (xy 419.405029 -100.127164) (xy 419.427671 -100.077587) (xy 419.457137 -100.031737)
			(xy 419.492828 -99.990546) (xy 419.534019 -99.954855) (xy 419.579869 -99.925389) (xy 419.629446 -99.902747)
			(xy 419.681741 -99.887392) (xy 419.735689 -99.879636) (xy 419.790191 -99.879636) (xy 419.844139 -99.887392)
			(xy 419.896434 -99.902747) (xy 419.946011 -99.925389) (xy 419.991861 -99.954855) (xy 420.033052 -99.990546)
			(xy 420.068743 -100.031737) (xy 420.098209 -100.077587) (xy 420.120851 -100.127164) (xy 420.136206 -100.179459)
			(xy 420.143962 -100.233407) (xy 420.144448 -100.260658) (xy 420.144201 -100.281398) (xy 420.139741 -100.322638)
			(xy 420.135558 -100.342954) (xy 420.132859 -100.357861) (xy 420.135331 -100.388039) (xy 420.146539 -100.416167)
			(xy 420.1655 -100.439775) (xy 420.190546 -100.456789) (xy 420.21948 -100.465715) (xy 420.234618 -100.466398)
			(xy 421.069262 -100.466398) (xy 421.084429 -100.465857) (xy 421.113432 -100.456974) (xy 421.138538 -100.439952)
			(xy 421.157527 -100.416299) (xy 421.168718 -100.388106) (xy 421.171121 -100.357869) (xy 421.168322 -100.342954)
			(xy 421.164154 -100.322636) (xy 421.1597 -100.281397) (xy 421.159432 -100.260658) (xy 421.159918 -100.233407)
			(xy 421.167674 -100.179459) (xy 421.183029 -100.127164) (xy 421.205671 -100.077587) (xy 421.235137 -100.031737)
			(xy 421.270828 -99.990546) (xy 421.312019 -99.954855) (xy 421.357869 -99.925389) (xy 421.407446 -99.902747)
			(xy 421.459741 -99.887392) (xy 421.513689 -99.879636) (xy 421.568191 -99.879636) (xy 421.622139 -99.887392)
			(xy 421.674434 -99.902747) (xy 421.724011 -99.925389) (xy 421.769861 -99.954855) (xy 421.811052 -99.990546)
			(xy 421.846743 -100.031737) (xy 421.876209 -100.077587) (xy 421.898851 -100.127164) (xy 421.914206 -100.179459)
			(xy 421.921962 -100.233407) (xy 421.922448 -100.260658) (xy 421.922201 -100.281398) (xy 421.917741 -100.322638)
			(xy 421.913558 -100.342954) (xy 421.910859 -100.357861) (xy 421.913331 -100.388039) (xy 421.924539 -100.416167)
			(xy 421.9435 -100.439775) (xy 421.968546 -100.456789) (xy 421.99748 -100.465715) (xy 422.012618 -100.466398)
			(xy 422.085262 -100.466398) (xy 422.100429 -100.465857) (xy 422.129432 -100.456974) (xy 422.154538 -100.439952)
			(xy 422.173527 -100.416299) (xy 422.184718 -100.388106) (xy 422.187121 -100.357869) (xy 422.184322 -100.342954)
			(xy 422.180154 -100.322636) (xy 422.1757 -100.281397) (xy 422.175432 -100.260658) (xy 422.175918 -100.233407)
			(xy 422.183674 -100.179459) (xy 422.199029 -100.127164) (xy 422.221671 -100.077587) (xy 422.251137 -100.031737)
			(xy 422.286828 -99.990546) (xy 422.328019 -99.954855) (xy 422.373869 -99.925389) (xy 422.423446 -99.902747)
			(xy 422.475741 -99.887392) (xy 422.529689 -99.879636) (xy 422.584191 -99.879636) (xy 422.638139 -99.887392)
			(xy 422.690434 -99.902747) (xy 422.740011 -99.925389) (xy 422.785861 -99.954855) (xy 422.827052 -99.990546)
			(xy 422.862743 -100.031737) (xy 422.892209 -100.077587) (xy 422.914851 -100.127164) (xy 422.930206 -100.179459)
			(xy 422.937962 -100.233407) (xy 422.938448 -100.260658) (xy 422.938201 -100.281398) (xy 422.933741 -100.322638)
			(xy 422.929558 -100.342954) (xy 422.926859 -100.357861) (xy 422.929331 -100.388039) (xy 422.940539 -100.416167)
			(xy 422.9595 -100.439775) (xy 422.984546 -100.456789) (xy 423.01348 -100.465715) (xy 423.028618 -100.466398)
			(xy 437.287924 -100.466398) (xy 439.390282 -98.36404) (xy 439.390282 -96.336104) (xy 439.389803 -96.321837)
			(xy 439.381909 -96.294417) (xy 439.366735 -96.270252) (xy 439.345466 -96.25123) (xy 439.319765 -96.238836)
			(xy 439.291637 -96.234038) (xy 439.26328 -96.23721) (xy 439.236908 -96.248106) (xy 439.225436 -96.256602)
			(xy 439.205124 -96.272215) (xy 439.161109 -96.298433) (xy 439.11398 -96.318521) (xy 439.064586 -96.332118)
			(xy 439.013816 -96.338978) (xy 438.9882 -96.339406) (xy 438.960949 -96.33892) (xy 438.907001 -96.331164)
			(xy 438.854707 -96.315809) (xy 438.80513 -96.293168) (xy 438.75928 -96.263702) (xy 438.71809 -96.22801)
			(xy 438.682398 -96.18682) (xy 438.652932 -96.14097) (xy 438.630291 -96.091393) (xy 438.614936 -96.039099)
			(xy 438.60718 -95.985151) (xy 438.60718 -95.930649) (xy 438.614936 -95.876701) (xy 438.630291 -95.824407)
			(xy 438.652932 -95.77483) (xy 438.682398 -95.72898) (xy 438.71809 -95.68779) (xy 438.75928 -95.652098)
			(xy 438.80513 -95.622632) (xy 438.854707 -95.599991) (xy 438.907001 -95.584636) (xy 438.960949 -95.57688)
			(xy 438.9882 -95.57639) (xy 439.013816 -95.576805) (xy 439.064587 -95.583667) (xy 439.113981 -95.597267)
			(xy 439.161109 -95.61736) (xy 439.205121 -95.643584) (xy 439.225436 -95.659194) (xy 439.2369 -95.667704)
			(xy 439.263275 -95.678602) (xy 439.291637 -95.681776) (xy 439.319769 -95.676977) (xy 439.345475 -95.664581)
			(xy 439.366746 -95.645555) (xy 439.381922 -95.621386) (xy 439.389817 -95.593961) (xy 439.390282 -95.579692)
			(xy 439.390282 -52.099972) (xy 441.985654 -49.504854) (xy 441.959238 -49.469548) (xy 441.950765 -49.458004)
			(xy 441.935383 -49.433847) (xy 441.928504 -49.421288) (xy 441.922842 -49.411837) (xy 441.905297 -49.39855)
			(xy 441.8838 -49.393833) (xy 441.862303 -49.39855) (xy 441.844758 -49.411837) (xy 441.839096 -49.421288)
			(xy 441.824703 -49.44694) (xy 441.789255 -49.493875) (xy 441.747029 -49.53482) (xy 441.699024 -49.568805)
			(xy 441.646375 -49.595028) (xy 441.590328 -49.612867) (xy 441.532209 -49.621902) (xy 441.5028 -49.622456)
			(xy 441.475545 -49.62197) (xy 441.421591 -49.614213) (xy 441.369289 -49.598856) (xy 441.319706 -49.576212)
			(xy 441.27385 -49.546742) (xy 441.232654 -49.511046) (xy 441.196958 -49.46985) (xy 441.167488 -49.423994)
			(xy 441.144844 -49.374411) (xy 441.129487 -49.322109) (xy 441.12173 -49.268155) (xy 441.12173 -49.213645)
			(xy 441.129487 -49.159691) (xy 441.144844 -49.107389) (xy 441.167488 -49.057806) (xy 441.196958 -49.01195)
			(xy 441.232654 -48.970754) (xy 441.27385 -48.935058) (xy 441.319706 -48.905588) (xy 441.369289 -48.882944)
			(xy 441.421591 -48.867587) (xy 441.475545 -48.85983) (xy 441.5028 -48.85944) (xy 441.531716 -48.859974)
			(xy 441.588886 -48.868702) (xy 441.644085 -48.885957) (xy 441.696047 -48.911345) (xy 441.743583 -48.944284)
			(xy 441.785603 -48.984019) (xy 441.80379 -49.006506) (xy 441.813687 -49.018311) (xy 441.839011 -49.03583)
			(xy 441.868404 -49.045006) (xy 441.899196 -49.045006) (xy 441.928589 -49.03583) (xy 441.953913 -49.018311)
			(xy 441.96381 -49.006506) (xy 441.981999 -48.984019) (xy 442.024015 -48.944275) (xy 442.071548 -48.911328)
			(xy 442.12351 -48.885933) (xy 442.17871 -48.868673) (xy 442.235882 -48.859943) (xy 442.2648 -48.85944)
			(xy 442.295452 -48.860029) (xy 442.355972 -48.869799) (xy 442.414147 -48.889134) (xy 442.468474 -48.917535)
			(xy 442.4934 -48.935386) (xy 442.528706 -48.961802) (xy 442.757052 -48.733456) (xy 444.311786 -48.733456)
			(xy 444.325282 -48.733027) (xy 444.351325 -48.725934) (xy 444.374601 -48.712267) (xy 444.393483 -48.692979)
			(xy 444.406654 -48.669419) (xy 444.413192 -48.643231) (xy 444.412643 -48.616245) (xy 444.409322 -48.603154)
			(xy 444.402077 -48.576887) (xy 444.394304 -48.522956) (xy 444.393828 -48.495712) (xy 444.394314 -48.468461)
			(xy 444.40207 -48.414513) (xy 444.417425 -48.362218) (xy 444.440067 -48.312641) (xy 444.469533 -48.266791)
			(xy 444.505224 -48.2256) (xy 444.546415 -48.189909) (xy 444.592265 -48.160443) (xy 444.641842 -48.137801)
			(xy 444.694137 -48.122446) (xy 444.748085 -48.11469) (xy 444.802587 -48.11469) (xy 444.856535 -48.122446)
			(xy 444.90883 -48.137801) (xy 444.958407 -48.160443) (xy 445.004257 -48.189909) (xy 445.045448 -48.2256)
			(xy 445.081139 -48.266791) (xy 445.110605 -48.312641) (xy 445.133247 -48.362218) (xy 445.148602 -48.414513)
			(xy 445.156358 -48.468461) (xy 445.156844 -48.495712) (xy 445.15634 -48.522954) (xy 445.148566 -48.576881)
			(xy 445.14135 -48.603154) (xy 445.137931 -48.616232) (xy 445.137354 -48.643248) (xy 445.143886 -48.669469)
			(xy 445.157069 -48.693057) (xy 445.17598 -48.71236) (xy 445.199293 -48.726024) (xy 445.225375 -48.733092)
			(xy 445.238886 -48.733456) (xy 446.070228 -48.733456) (xy 446.634616 -48.169068) (xy 458.98435 -48.169068)
			(xy 459.97622 -49.160938) (xy 463.93354 -49.160938) (xy 465.25815 -50.485548) (xy 467.85022 -50.485548)
			(xy 468.46998 -49.865788) (xy 468.46998 -48.336708) (xy 467.7537 -47.620428) (xy 465.93252 -47.620428)
			(xy 463.68208 -45.369988) (xy 463.68208 -42.964608) (xy 463.644488 -42.954448) (xy 463.617825 -42.946779)
			(xy 463.566888 -42.924792) (xy 463.519674 -42.895656) (xy 463.47718 -42.859986) (xy 463.440304 -42.818536)
			(xy 463.409822 -42.77218) (xy 463.386379 -42.721896) (xy 463.370469 -42.668747) (xy 463.362428 -42.613852)
			(xy 463.362427 -42.558372) (xy 463.370464 -42.503478) (xy 463.38637 -42.450327) (xy 463.40981 -42.400042)
			(xy 463.440288 -42.353684) (xy 463.477163 -42.312231) (xy 463.519654 -42.276559) (xy 463.566865 -42.24742)
			(xy 463.617801 -42.225429) (xy 463.644488 -42.217848) (xy 463.68208 -42.207688) (xy 463.68208 -38.587172)
			(xy 461.10271 -36.007802) (xy 440.98718 -36.007802) (xy 439.390282 -34.410904) (xy 439.390282 -30.477714)
			(xy 439.38973 -30.462566) (xy 439.380857 -30.433598) (xy 439.363886 -30.408501) (xy 439.340306 -30.389479)
			(xy 439.312187 -30.378201) (xy 439.281997 -30.375657) (xy 439.267092 -30.3784) (xy 439.247146 -30.382453)
			(xy 439.206672 -30.386779) (xy 439.18632 -30.387036) (xy 439.159064 -30.386574) (xy 439.105107 -30.378819)
			(xy 439.052803 -30.363464) (xy 439.003217 -30.340821) (xy 438.957358 -30.311351) (xy 438.916159 -30.275655)
			(xy 438.880461 -30.234458) (xy 438.850989 -30.188601) (xy 438.828343 -30.139016) (xy 438.812985 -30.086712)
			(xy 438.805227 -30.032756) (xy 438.805227 -29.978244) (xy 438.812985 -29.924288) (xy 438.828343 -29.871984)
			(xy 438.850989 -29.822399) (xy 438.880461 -29.776542) (xy 438.916159 -29.735345) (xy 438.957358 -29.699649)
			(xy 439.003217 -29.670179) (xy 439.052803 -29.647536) (xy 439.105107 -29.632181) (xy 439.159064 -29.624426)
			(xy 439.18632 -29.62402) (xy 439.206671 -29.624291) (xy 439.247144 -29.628614) (xy 439.267092 -29.632656)
			(xy 439.282009 -29.635335) (xy 439.312195 -29.632816) (xy 439.340316 -29.621555) (xy 439.363898 -29.602544)
			(xy 439.380868 -29.577452) (xy 439.389734 -29.548488) (xy 439.390282 -29.533342) (xy 439.390282 -29.142436)
			(xy 439.389819 -29.129162) (xy 439.382909 -29.103527) (xy 439.369623 -29.080539) (xy 439.35086 -29.061754)
			(xy 439.32789 -29.04844) (xy 439.302263 -29.041497) (xy 439.275713 -29.041396) (xy 439.262774 -29.044392)
			(xy 439.238947 -29.050247) (xy 439.190279 -29.056485) (xy 439.165746 -29.056838) (xy 439.138489 -29.056378)
			(xy 439.084529 -29.048626) (xy 439.032221 -29.033273) (xy 438.982631 -29.010631) (xy 438.936769 -28.981162)
			(xy 438.895567 -28.945465) (xy 438.859866 -28.904268) (xy 438.830391 -28.858409) (xy 438.807743 -28.808822)
			(xy 438.792384 -28.756516) (xy 438.784625 -28.702557) (xy 438.784625 -28.648043) (xy 438.792384 -28.594084)
			(xy 438.807743 -28.541778) (xy 438.830391 -28.492191) (xy 438.859866 -28.446332) (xy 438.895567 -28.405135)
			(xy 438.936769 -28.369438) (xy 438.982631 -28.339969) (xy 439.032221 -28.317327) (xy 439.084529 -28.301974)
			(xy 439.138489 -28.294222) (xy 439.165746 -28.293822) (xy 439.190277 -28.294202) (xy 439.238942 -28.30044)
			(xy 439.262774 -28.306268) (xy 439.275723 -28.309241) (xy 439.302281 -28.309161) (xy 439.327919 -28.302233)
			(xy 439.350902 -28.288926) (xy 439.369674 -28.270139) (xy 439.382964 -28.247146) (xy 439.389872 -28.221502)
			(xy 439.390282 -28.208224) (xy 439.390282 -19.694144) (xy 439.368306 -19.675925) (xy 439.329492 -19.634069)
			(xy 439.297346 -19.586898) (xy 439.272586 -19.535464) (xy 439.255764 -19.480917) (xy 439.247256 -19.424471)
			(xy 439.247252 -19.367389) (xy 439.255751 -19.310942) (xy 439.272564 -19.256391) (xy 439.297316 -19.204954)
			(xy 439.329454 -19.157778) (xy 439.368262 -19.115916) (xy 439.390282 -19.097752) (xy 439.390282 -16.170656)
			(xy 439.389865 -16.157506) (xy 439.383136 -16.132081) (xy 439.370138 -16.109217) (xy 439.351731 -16.090431)
			(xy 439.329136 -16.07697) (xy 439.303853 -16.069725) (xy 439.290714 -16.069056) (xy 439.262521 -16.068003)
			(xy 439.206892 -16.058619) (xy 439.15325 -16.041148) (xy 439.102764 -16.015969) (xy 439.056536 -15.983633)
			(xy 439.015572 -15.944844) (xy 438.980764 -15.900446) (xy 438.952872 -15.851408) (xy 438.932503 -15.798798)
			(xy 438.920102 -15.743763) (xy 438.915938 -15.687501) (xy 438.920101 -15.631239) (xy 438.932503 -15.576204)
			(xy 438.952871 -15.523594) (xy 438.980763 -15.474555) (xy 439.01557 -15.430158) (xy 439.056534 -15.391368)
			(xy 439.102763 -15.359031) (xy 439.153248 -15.333853) (xy 439.20689 -15.316382) (xy 439.26252 -15.306997)
			(xy 439.290714 -15.30604) (xy 439.303854 -15.305366) (xy 439.329144 -15.298137) (xy 439.351744 -15.284681)
			(xy 439.370152 -15.265894) (xy 439.383143 -15.243023) (xy 439.389854 -15.217591) (xy 439.390282 -15.20444)
			(xy 439.390282 -15.124684) (xy 439.415936 -15.09903) (xy 439.425237 -15.089148) (xy 439.438711 -15.065604)
			(xy 439.445497 -15.039339) (xy 439.445115 -15.012214) (xy 439.437591 -14.986151) (xy 439.423459 -14.962996)
			(xy 439.403719 -14.944389) (xy 439.37977 -14.931648) (xy 439.353308 -14.925676) (xy 439.339736 -14.925802)
			(xy 439.32348 -14.926056) (xy 439.296223 -14.925592) (xy 439.242265 -14.917831) (xy 439.189961 -14.902469)
			(xy 439.140375 -14.879821) (xy 439.094517 -14.850346) (xy 439.053321 -14.814644) (xy 439.017625 -14.773443)
			(xy 438.988156 -14.727582) (xy 438.965513 -14.677993) (xy 438.950159 -14.625687) (xy 438.942405 -14.571727)
			(xy 438.942409 -14.517214) (xy 438.950171 -14.463256) (xy 438.965534 -14.410952) (xy 438.988184 -14.361367)
			(xy 439.01766 -14.31551) (xy 439.053362 -14.274314) (xy 439.094564 -14.238619) (xy 439.140426 -14.209151)
			(xy 439.190016 -14.18651) (xy 439.242323 -14.171157) (xy 439.296282 -14.163404) (xy 439.350795 -14.16341)
			(xy 439.404753 -14.171173) (xy 439.457057 -14.186537) (xy 439.506642 -14.209188) (xy 439.552498 -14.238666)
			(xy 439.593692 -14.274369) (xy 439.629387 -14.315572) (xy 439.658853 -14.361435) (xy 439.681493 -14.411024)
			(xy 439.696845 -14.463332) (xy 439.704596 -14.517291) (xy 439.704988 -14.544548) (xy 439.704734 -14.560804)
			(xy 439.704599 -14.57436) (xy 439.710641 -14.600777) (xy 439.723417 -14.624675) (xy 439.742029 -14.644372)
			(xy 439.765166 -14.658481) (xy 439.791198 -14.666008) (xy 439.818294 -14.666424) (xy 439.844546 -14.659699)
			(xy 439.868105 -14.646307) (xy 439.877962 -14.637004) (xy 442.768482 -11.746484) (xy 451.367398 -11.746484)
			(xy 451.428866 -11.807952) (xy 452.227188 -11.807952) (xy 453.271382 -10.763758) (xy 453.271382 -7.754112)
			(xy 452.65721 -7.13994) (xy 449.120006 -7.13994) (xy 449.099259 -7.156848) (xy 449.053928 -7.185299)
			(xy 449.005068 -7.207141) (xy 448.953635 -7.221944) (xy 448.90064 -7.229419) (xy 448.84712 -7.229419)
			(xy 448.794125 -7.221944) (xy 448.742692 -7.207141) (xy 448.693832 -7.185299) (xy 448.648501 -7.156848)
			(xy 448.627754 -7.13994) (xy 447.642234 -7.13994) (xy 447.627057 -7.140507) (xy 447.598043 -7.14943)
			(xy 447.572924 -7.166472) (xy 447.553908 -7.190132) (xy 447.54267 -7.21833) (xy 447.540888 -7.233412)
			(xy 447.538282 -7.260404) (xy 447.526408 -7.313314) (xy 447.507159 -7.364008) (xy 447.480925 -7.411466)
			(xy 447.448234 -7.45473) (xy 447.409745 -7.492927) (xy 447.366234 -7.525288) (xy 447.318578 -7.551161)
			(xy 447.267738 -7.570023) (xy 447.214739 -7.581495) (xy 447.16065 -7.585344) (xy 447.106561 -7.581495)
			(xy 447.053562 -7.570023) (xy 447.002722 -7.551161) (xy 446.955066 -7.525288) (xy 446.911555 -7.492927)
			(xy 446.873066 -7.45473) (xy 446.840375 -7.411466) (xy 446.814141 -7.364008) (xy 446.794892 -7.313314)
			(xy 446.783018 -7.260404) (xy 446.780412 -7.233412) (xy 446.778643 -7.218323) (xy 446.767431 -7.190105)
			(xy 446.748416 -7.166432) (xy 446.723282 -7.149397) (xy 446.694249 -7.140507) (xy 446.679066 -7.13994)
			(xy 445.842136 -7.13994) (xy 445.826959 -7.140507) (xy 445.797945 -7.14943) (xy 445.772825 -7.166471)
			(xy 445.753809 -7.190131) (xy 445.74257 -7.218329) (xy 445.74079 -7.233412) (xy 445.738184 -7.260404)
			(xy 445.72631 -7.313314) (xy 445.707061 -7.364008) (xy 445.680827 -7.411466) (xy 445.648136 -7.45473)
			(xy 445.609647 -7.492927) (xy 445.566136 -7.525288) (xy 445.51848 -7.551161) (xy 445.46764 -7.570023)
			(xy 445.414641 -7.581495) (xy 445.360552 -7.585344) (xy 445.306463 -7.581495) (xy 445.253464 -7.570023)
			(xy 445.202624 -7.551161) (xy 445.154968 -7.525288) (xy 445.111457 -7.492927) (xy 445.072968 -7.45473)
			(xy 445.040277 -7.411466) (xy 445.014043 -7.364008) (xy 444.994794 -7.313314) (xy 444.98292 -7.260404)
			(xy 444.980314 -7.233412) (xy 444.978545 -7.218323) (xy 444.967333 -7.190105) (xy 444.948319 -7.166432)
			(xy 444.923184 -7.149396) (xy 444.894151 -7.140505) (xy 444.878968 -7.13994) (xy 440.393328 -7.13994)
			(xy 440.389264 -7.186422) (xy 440.386282 -7.214575) (xy 440.373062 -7.269622) (xy 440.351851 -7.32211)
			(xy 440.323116 -7.370887) (xy 440.287487 -7.414881) (xy 440.245747 -7.453126) (xy 440.198812 -7.484782)
			(xy 440.147715 -7.509153) (xy 440.093576 -7.525703) (xy 440.037586 -7.534071) (xy 439.980974 -7.534071)
			(xy 439.924984 -7.525703) (xy 439.870845 -7.509153) (xy 439.819748 -7.484782) (xy 439.772813 -7.453126)
			(xy 439.731073 -7.414881) (xy 439.695444 -7.370887) (xy 439.666709 -7.32211) (xy 439.645498 -7.269622)
			(xy 439.632278 -7.214575) (xy 439.629296 -7.186422) (xy 439.625232 -7.13994) (xy 439.504328 -7.13994)
			(xy 439.500264 -7.186422) (xy 439.497282 -7.214575) (xy 439.484062 -7.269622) (xy 439.462851 -7.32211)
			(xy 439.434116 -7.370887) (xy 439.398487 -7.414881) (xy 439.356747 -7.453126) (xy 439.309812 -7.484782)
			(xy 439.258715 -7.509153) (xy 439.204576 -7.525703) (xy 439.148586 -7.534071) (xy 439.091974 -7.534071)
			(xy 439.035984 -7.525703) (xy 438.981845 -7.509153) (xy 438.930748 -7.484782) (xy 438.883813 -7.453126)
			(xy 438.842073 -7.414881) (xy 438.806444 -7.370887) (xy 438.777709 -7.32211) (xy 438.756498 -7.269622)
			(xy 438.743278 -7.214575) (xy 438.740296 -7.186422) (xy 438.736232 -7.13994) (xy 438.615328 -7.13994)
			(xy 438.611264 -7.186422) (xy 438.608282 -7.214575) (xy 438.595062 -7.269622) (xy 438.573851 -7.32211)
			(xy 438.545116 -7.370887) (xy 438.509487 -7.414881) (xy 438.467747 -7.453126) (xy 438.420812 -7.484782)
			(xy 438.369715 -7.509153) (xy 438.315576 -7.525703) (xy 438.259586 -7.534071) (xy 438.202974 -7.534071)
			(xy 438.146984 -7.525703) (xy 438.092845 -7.509153) (xy 438.041748 -7.484782) (xy 437.994813 -7.453126)
			(xy 437.953073 -7.414881) (xy 437.917444 -7.370887) (xy 437.888709 -7.32211) (xy 437.867498 -7.269622)
			(xy 437.854278 -7.214575) (xy 437.851296 -7.186422) (xy 437.847232 -7.13994) (xy 433.64912 -7.13994)
			(xy 433.633679 -7.140464) (xy 433.6042 -7.149662) (xy 433.57882 -7.167254) (xy 433.559861 -7.191629)
			(xy 433.549057 -7.220558) (xy 433.547774 -7.235952) (xy 433.545785 -7.263446) (xy 433.534887 -7.317482)
			(xy 433.516327 -7.369387) (xy 433.490491 -7.418082) (xy 433.457917 -7.462551) (xy 433.419283 -7.501871)
			(xy 433.375393 -7.535222) (xy 433.327161 -7.56191) (xy 433.27559 -7.58138) (xy 433.221754 -7.593227)
			(xy 433.166774 -7.597203) (xy 433.111794 -7.593227) (xy 433.057958 -7.58138) (xy 433.006387 -7.56191)
			(xy 432.958155 -7.535222) (xy 432.914265 -7.501871) (xy 432.875631 -7.462551) (xy 432.843057 -7.418082)
			(xy 432.817221 -7.369387) (xy 432.798661 -7.317482) (xy 432.787763 -7.263446) (xy 432.785774 -7.235952)
			(xy 432.784383 -7.220577) (xy 432.773566 -7.191677) (xy 432.754628 -7.167314) (xy 432.729291 -7.149701)
			(xy 432.699856 -7.140439) (xy 432.684428 -7.13994) (xy 431.849276 -7.13994) (xy 431.833839 -7.14047)
			(xy 431.804372 -7.149676) (xy 431.779003 -7.16727) (xy 431.760054 -7.191642) (xy 431.749256 -7.220565)
			(xy 431.74793 -7.235952) (xy 431.745941 -7.263446) (xy 431.735043 -7.317482) (xy 431.716483 -7.369387)
			(xy 431.690647 -7.418082) (xy 431.658073 -7.462551) (xy 431.619439 -7.501871) (xy 431.575549 -7.535222)
			(xy 431.527317 -7.56191) (xy 431.475746 -7.58138) (xy 431.42191 -7.593227) (xy 431.36693 -7.597203)
			(xy 431.31195 -7.593227) (xy 431.258114 -7.58138) (xy 431.206543 -7.56191) (xy 431.158311 -7.535222)
			(xy 431.114421 -7.501871) (xy 431.075787 -7.462551) (xy 431.043213 -7.418082) (xy 431.017377 -7.369387)
			(xy 430.998817 -7.317482) (xy 430.987919 -7.263446) (xy 430.98593 -7.235952) (xy 430.984538 -7.220579)
			(xy 430.97372 -7.191685) (xy 430.954781 -7.16733) (xy 430.929443 -7.149727) (xy 430.900009 -7.140477)
			(xy 430.884584 -7.13994) (xy 430.546002 -7.13994) (xy 428.957994 -8.727948) (xy 443.539372 -8.727948)
			(xy 443.539849 -8.700578) (xy 443.547661 -8.646399) (xy 443.563147 -8.593895) (xy 443.585987 -8.544148)
			(xy 443.615711 -8.498181) (xy 443.633352 -8.47725) (xy 443.642538 -8.465886) (xy 443.654715 -8.439341)
			(xy 443.658895 -8.410436) (xy 443.654736 -8.381529) (xy 443.642578 -8.354975) (xy 443.633352 -8.343646)
			(xy 443.615729 -8.322701) (xy 443.586013 -8.276732) (xy 443.563173 -8.226988) (xy 443.547678 -8.17449)
			(xy 443.539847 -8.120316) (xy 443.539372 -8.092948) (xy 443.539858 -8.065697) (xy 443.547614 -8.011749)
			(xy 443.562969 -7.959454) (xy 443.585611 -7.909877) (xy 443.615077 -7.864027) (xy 443.650768 -7.822836)
			(xy 443.691959 -7.787145) (xy 443.737809 -7.757679) (xy 443.787386 -7.735037) (xy 443.839681 -7.719682)
			(xy 443.893629 -7.711926) (xy 443.948131 -7.711926) (xy 444.002079 -7.719682) (xy 444.054374 -7.735037)
			(xy 444.103951 -7.757679) (xy 444.149801 -7.787145) (xy 444.190992 -7.822836) (xy 444.226683 -7.864027)
			(xy 444.256149 -7.909877) (xy 444.278791 -7.959454) (xy 444.294146 -8.011749) (xy 444.301902 -8.065697)
			(xy 444.302388 -8.092948) (xy 444.301894 -8.120317) (xy 444.294084 -8.174495) (xy 444.278601 -8.226998)
			(xy 444.255766 -8.276746) (xy 444.226047 -8.322714) (xy 444.208408 -8.343646) (xy 444.199124 -8.354938)
			(xy 444.186952 -8.381509) (xy 444.182788 -8.410436) (xy 444.186972 -8.439361) (xy 444.199164 -8.465923)
			(xy 444.208408 -8.47725) (xy 444.226038 -8.498189) (xy 444.255751 -8.54416) (xy 444.278589 -8.593906)
			(xy 444.294082 -8.646405) (xy 444.301913 -8.700579) (xy 444.302388 -8.727948) (xy 444.301967 -8.753495)
			(xy 444.295163 -8.804135) (xy 444.281657 -8.853412) (xy 444.261691 -8.900443) (xy 444.235622 -8.944387)
			(xy 444.220092 -8.964676) (xy 444.211 -8.976959) (xy 444.199976 -9.005447) (xy 444.197856 -9.035921)
			(xy 444.204832 -9.065662) (xy 444.220279 -9.092016) (xy 444.242821 -9.112632) (xy 444.256414 -9.119616)
			(xy 444.280602 -9.131507) (xy 444.325621 -9.161142) (xy 444.366022 -9.196818) (xy 444.400999 -9.237826)
			(xy 444.429856 -9.283348) (xy 444.452019 -9.332478) (xy 444.467047 -9.384239) (xy 444.47464 -9.437599)
			(xy 444.475108 -9.464548) (xy 444.475108 -9.467088) (xy 444.475521 -9.481546) (xy 444.483456 -9.509348)
			(xy 444.498865 -9.533811) (xy 444.520512 -9.552975) (xy 444.546663 -9.565305) (xy 444.575221 -9.569811)
			(xy 444.603897 -9.566134) (xy 444.617348 -9.560814) (xy 444.641592 -9.550672) (xy 444.692173 -9.536408)
			(xy 444.744233 -9.529229) (xy 444.77051 -9.52881) (xy 444.79776 -9.529289) (xy 444.851705 -9.537046)
			(xy 444.903997 -9.552402) (xy 444.953572 -9.575043) (xy 444.967397 -9.583928) (xy 449.172582 -9.583928)
			(xy 449.176653 -9.528306) (xy 449.188779 -9.473869) (xy 449.208702 -9.421778) (xy 449.235998 -9.373143)
			(xy 449.270084 -9.329) (xy 449.310233 -9.290291) (xy 449.355591 -9.25784) (xy 449.405191 -9.232339)
			(xy 449.457975 -9.214332) (xy 449.512818 -9.204202) (xy 449.568552 -9.202165) (xy 449.623989 -9.208265)
			(xy 449.677946 -9.222371) (xy 449.729275 -9.244183) (xy 449.776881 -9.273237) (xy 449.819749 -9.308912)
			(xy 449.856966 -9.350449) (xy 449.887739 -9.396962) (xy 449.911411 -9.447459) (xy 449.927479 -9.500866)
			(xy 449.935599 -9.556042) (xy 449.936108 -9.583928) (xy 449.935599 -9.611814) (xy 449.927479 -9.66699)
			(xy 449.911411 -9.720397) (xy 449.887739 -9.770894) (xy 449.856966 -9.817407) (xy 449.819749 -9.858944)
			(xy 449.776881 -9.894619) (xy 449.729275 -9.923673) (xy 449.677946 -9.945485) (xy 449.623989 -9.959591)
			(xy 449.568552 -9.965691) (xy 449.512818 -9.963654) (xy 449.457975 -9.953524) (xy 449.405191 -9.935517)
			(xy 449.355591 -9.910016) (xy 449.310233 -9.877565) (xy 449.270084 -9.838856) (xy 449.235998 -9.794713)
			(xy 449.208702 -9.746078) (xy 449.188779 -9.693987) (xy 449.176653 -9.63955) (xy 449.172582 -9.583928)
			(xy 444.967397 -9.583928) (xy 444.99942 -9.604509) (xy 445.040608 -9.6402) (xy 445.076297 -9.681389)
			(xy 445.105762 -9.727237) (xy 445.128402 -9.776813) (xy 445.143756 -9.829105) (xy 445.151512 -9.883051)
			(xy 445.151512 -9.937551) (xy 445.143756 -9.991496) (xy 445.128401 -10.043789) (xy 445.105761 -10.093364)
			(xy 445.076297 -10.139213) (xy 445.040607 -10.180401) (xy 444.999419 -10.216092) (xy 444.953571 -10.245557)
			(xy 444.903996 -10.268198) (xy 444.851704 -10.283554) (xy 444.797759 -10.291311) (xy 444.743259 -10.291312)
			(xy 444.689313 -10.283558) (xy 444.63702 -10.268205) (xy 444.587444 -10.245566) (xy 444.541595 -10.216102)
			(xy 444.500405 -10.180414) (xy 444.464714 -10.139226) (xy 444.435247 -10.093379) (xy 444.412605 -10.043805)
			(xy 444.397248 -9.991513) (xy 444.38949 -9.937568) (xy 444.389002 -9.910318) (xy 444.389002 -9.907778)
			(xy 444.388602 -9.89332) (xy 444.38066 -9.865521) (xy 444.365247 -9.841061) (xy 444.343598 -9.821899)
			(xy 444.317448 -9.80957) (xy 444.28889 -9.805062) (xy 444.260214 -9.808735) (xy 444.246762 -9.814052)
			(xy 444.222516 -9.824189) (xy 444.171936 -9.838455) (xy 444.119877 -9.845636) (xy 444.0936 -9.846056)
			(xy 444.066351 -9.845522) (xy 444.012407 -9.837767) (xy 443.960116 -9.822414) (xy 443.910542 -9.799777)
			(xy 443.864694 -9.770315) (xy 443.823505 -9.734629) (xy 443.787814 -9.693444) (xy 443.758346 -9.6476)
			(xy 443.735702 -9.598029) (xy 443.720343 -9.54574) (xy 443.712581 -9.491797) (xy 443.712092 -9.464548)
			(xy 443.712515 -9.439001) (xy 443.719319 -9.388362) (xy 443.732825 -9.339085) (xy 443.752791 -9.292053)
			(xy 443.778858 -9.248109) (xy 443.794388 -9.22782) (xy 443.803492 -9.215545) (xy 443.814519 -9.187053)
			(xy 443.816638 -9.156576) (xy 443.809661 -9.126833) (xy 443.794209 -9.100478) (xy 443.771662 -9.079862)
			(xy 443.758066 -9.07288) (xy 443.733895 -9.060955) (xy 443.688873 -9.031328) (xy 443.648469 -8.995659)
			(xy 443.613489 -8.954657) (xy 443.584628 -8.909139) (xy 443.562463 -8.860012) (xy 443.547434 -8.808254)
			(xy 443.53984 -8.754896) (xy 443.539372 -8.727948) (xy 428.957994 -8.727948) (xy 428.641764 -9.044178)
			(xy 428.161196 -9.044178) (xy 428.147276 -9.044597) (xy 428.120465 -9.052096) (xy 428.096679 -9.066561)
			(xy 428.077688 -9.086918) (xy 428.064905 -9.111649) (xy 428.059282 -9.138915) (xy 428.061237 -9.166686)
			(xy 428.070625 -9.192895) (xy 428.078392 -9.204452) (xy 428.094924 -9.228764) (xy 428.121113 -9.281401)
			(xy 428.138922 -9.337431) (xy 428.147932 -9.395528) (xy 428.148496 -9.424924) (xy 428.147994 -9.452693)
			(xy 428.139937 -9.507643) (xy 428.123998 -9.560844) (xy 428.100513 -9.611172) (xy 428.069979 -9.657563)
			(xy 428.033041 -9.699036) (xy 428.012098 -9.717278) (xy 428.00112 -9.727184) (xy 427.984914 -9.751902)
			(xy 427.976457 -9.780223) (xy 427.976458 -9.80978) (xy 427.984915 -9.838101) (xy 428.001121 -9.862818)
			(xy 428.012098 -9.872726) (xy 428.033058 -9.89095) (xy 428.069999 -9.932426) (xy 428.100534 -9.97882)
			(xy 428.12402 -10.029151) (xy 428.139959 -10.082356) (xy 428.148016 -10.137309) (xy 428.148496 -10.16508)
			(xy 429.185324 -10.16508) (xy 429.185798 -10.137309) (xy 429.193854 -10.082355) (xy 429.209795 -10.02915)
			(xy 429.233282 -9.978818) (xy 429.263819 -9.932425) (xy 429.300761 -9.89095) (xy 429.321722 -9.872726)
			(xy 429.332697 -9.862817) (xy 429.3489 -9.838099) (xy 429.357356 -9.809779) (xy 429.357356 -9.780224)
			(xy 429.348901 -9.751903) (xy 429.332698 -9.727185) (xy 429.321722 -9.717278) (xy 429.300783 -9.699032)
			(xy 429.263844 -9.65756) (xy 429.233308 -9.61117) (xy 429.209823 -9.560843) (xy 429.193883 -9.507642)
			(xy 429.185826 -9.452693) (xy 429.185324 -9.424924) (xy 429.18581 -9.397673) (xy 429.193566 -9.343725)
			(xy 429.208921 -9.29143) (xy 429.231563 -9.241853) (xy 429.261029 -9.196003) (xy 429.29672 -9.154812)
			(xy 429.337911 -9.119121) (xy 429.383761 -9.089655) (xy 429.433338 -9.067013) (xy 429.485633 -9.051658)
			(xy 429.539581 -9.043902) (xy 429.594083 -9.043902) (xy 429.648031 -9.051658) (xy 429.700326 -9.067013)
			(xy 429.749903 -9.089655) (xy 429.795753 -9.119121) (xy 429.836944 -9.154812) (xy 429.872635 -9.196003)
			(xy 429.902101 -9.241853) (xy 429.924743 -9.29143) (xy 429.940098 -9.343725) (xy 429.947854 -9.397673)
			(xy 429.94834 -9.424924) (xy 429.947847 -9.452694) (xy 429.939791 -9.507646) (xy 429.923853 -9.56085)
			(xy 429.90037 -9.611181) (xy 429.869837 -9.657575) (xy 429.832901 -9.699053) (xy 429.811942 -9.717278)
			(xy 429.800966 -9.727185) (xy 429.784769 -9.751904) (xy 429.776317 -9.780224) (xy 429.776317 -9.809778)
			(xy 429.78477 -9.838098) (xy 429.800968 -9.862817) (xy 429.811942 -9.872726) (xy 429.832896 -9.890955)
			(xy 429.869832 -9.932432) (xy 429.900363 -9.978826) (xy 429.923846 -10.029156) (xy 429.939783 -10.082359)
			(xy 429.947838 -10.137311) (xy 429.948129 -10.153396) (xy 430.865788 -10.153396) (xy 430.866327 -10.125256)
			(xy 430.874601 -10.069587) (xy 430.890968 -10.01574) (xy 430.915073 -9.964883) (xy 430.946393 -9.918123)
			(xy 430.984246 -9.876475) (xy 431.02781 -9.840843) (xy 431.051716 -9.82599) (xy 431.064173 -9.818024)
			(xy 431.084145 -9.796233) (xy 431.097057 -9.769643) (xy 431.101832 -9.740472) (xy 431.09807 -9.711153)
			(xy 431.086087 -9.684132) (xy 431.076862 -9.672574) (xy 431.059704 -9.651764) (xy 431.030809 -9.606223)
			(xy 431.008607 -9.55707) (xy 430.993541 -9.505283) (xy 430.985909 -9.451891) (xy 430.985422 -9.424924)
			(xy 430.985908 -9.397673) (xy 430.993664 -9.343725) (xy 431.009019 -9.29143) (xy 431.031661 -9.241853)
			(xy 431.061127 -9.196003) (xy 431.096818 -9.154812) (xy 431.138009 -9.119121) (xy 431.183859 -9.089655)
			(xy 431.233436 -9.067013) (xy 431.285731 -9.051658) (xy 431.339679 -9.043902) (xy 431.394181 -9.043902)
			(xy 431.448129 -9.051658) (xy 431.500424 -9.067013) (xy 431.550001 -9.089655) (xy 431.595851 -9.119121)
			(xy 431.637042 -9.154812) (xy 431.672733 -9.196003) (xy 431.702199 -9.241853) (xy 431.724841 -9.29143)
			(xy 431.740196 -9.343725) (xy 431.747952 -9.397673) (xy 431.748438 -9.424924) (xy 432.784756 -9.424924)
			(xy 432.788827 -9.369302) (xy 432.800953 -9.314865) (xy 432.820876 -9.262774) (xy 432.848172 -9.214139)
			(xy 432.882258 -9.169996) (xy 432.922407 -9.131287) (xy 432.967765 -9.098836) (xy 433.017365 -9.073335)
			(xy 433.070149 -9.055328) (xy 433.124992 -9.045198) (xy 433.180726 -9.043161) (xy 433.236163 -9.049261)
			(xy 433.29012 -9.063367) (xy 433.341449 -9.085179) (xy 433.389055 -9.114233) (xy 433.431923 -9.149908)
			(xy 433.46914 -9.191445) (xy 433.499913 -9.237958) (xy 433.523585 -9.288455) (xy 433.539653 -9.341862)
			(xy 433.547773 -9.397038) (xy 433.548282 -9.424924) (xy 433.548022 -9.439148) (xy 435.106062 -9.439148)
			(xy 435.110133 -9.383526) (xy 435.122259 -9.329089) (xy 435.142182 -9.276998) (xy 435.169478 -9.228363)
			(xy 435.203564 -9.18422) (xy 435.243713 -9.145511) (xy 435.289071 -9.11306) (xy 435.338671 -9.087559)
			(xy 435.391455 -9.069552) (xy 435.446298 -9.059422) (xy 435.502032 -9.057385) (xy 435.557469 -9.063485)
			(xy 435.611426 -9.077591) (xy 435.662755 -9.099403) (xy 435.710361 -9.128457) (xy 435.753229 -9.164132)
			(xy 435.790446 -9.205669) (xy 435.821219 -9.252182) (xy 435.844891 -9.302679) (xy 435.860959 -9.356086)
			(xy 435.869079 -9.411262) (xy 435.869588 -9.439148) (xy 435.869079 -9.467034) (xy 435.860959 -9.52221)
			(xy 435.844891 -9.575617) (xy 435.821219 -9.626114) (xy 435.790446 -9.672627) (xy 435.753229 -9.714164)
			(xy 435.710361 -9.749839) (xy 435.662755 -9.778893) (xy 435.611426 -9.800705) (xy 435.557469 -9.814811)
			(xy 435.502032 -9.820911) (xy 435.446298 -9.818874) (xy 435.391455 -9.808744) (xy 435.338671 -9.790737)
			(xy 435.289071 -9.765236) (xy 435.243713 -9.732785) (xy 435.203564 -9.694076) (xy 435.169478 -9.649933)
			(xy 435.142182 -9.601298) (xy 435.122259 -9.549207) (xy 435.110133 -9.49477) (xy 435.106062 -9.439148)
			(xy 433.548022 -9.439148) (xy 433.547773 -9.45281) (xy 433.539653 -9.507986) (xy 433.523585 -9.561393)
			(xy 433.499913 -9.61189) (xy 433.46914 -9.658403) (xy 433.431923 -9.69994) (xy 433.389055 -9.735615)
			(xy 433.341449 -9.764669) (xy 433.29012 -9.786481) (xy 433.236163 -9.800587) (xy 433.180726 -9.806687)
			(xy 433.124992 -9.80465) (xy 433.070149 -9.79452) (xy 433.017365 -9.776513) (xy 432.967765 -9.751012)
			(xy 432.922407 -9.718561) (xy 432.882258 -9.679852) (xy 432.848172 -9.635709) (xy 432.820876 -9.587074)
			(xy 432.800953 -9.534983) (xy 432.788827 -9.480546) (xy 432.784756 -9.424924) (xy 431.748438 -9.424924)
			(xy 431.74795 -9.453066) (xy 431.739672 -9.508739) (xy 431.723298 -9.562589) (xy 431.699185 -9.613447)
			(xy 431.667857 -9.660207) (xy 431.629995 -9.701853) (xy 431.586421 -9.73748) (xy 431.56251 -9.75233)
			(xy 431.550121 -9.760393) (xy 431.530147 -9.782159) (xy 431.517228 -9.808726) (xy 431.512442 -9.837877)
			(xy 431.516186 -9.86718) (xy 431.52815 -9.894191) (xy 431.537364 -9.905746) (xy 431.554535 -9.926545)
			(xy 431.583427 -9.97209) (xy 431.605626 -10.021246) (xy 431.62069 -10.073035) (xy 431.628319 -10.126429)
			(xy 431.628804 -10.153396) (xy 431.628318 -10.180647) (xy 431.620562 -10.234595) (xy 431.605207 -10.28689)
			(xy 431.582565 -10.336467) (xy 431.553099 -10.382317) (xy 431.517408 -10.423508) (xy 431.476217 -10.459199)
			(xy 431.430367 -10.488665) (xy 431.38079 -10.511307) (xy 431.328495 -10.526662) (xy 431.274547 -10.534418)
			(xy 431.220045 -10.534418) (xy 431.166097 -10.526662) (xy 431.113802 -10.511307) (xy 431.064225 -10.488665)
			(xy 431.018375 -10.459199) (xy 430.977184 -10.423508) (xy 430.941493 -10.382317) (xy 430.912027 -10.336467)
			(xy 430.889385 -10.28689) (xy 430.87403 -10.234595) (xy 430.866274 -10.180647) (xy 430.865788 -10.153396)
			(xy 429.948129 -10.153396) (xy 429.94834 -10.16508) (xy 429.947854 -10.192331) (xy 429.940098 -10.246279)
			(xy 429.924743 -10.298574) (xy 429.902101 -10.348151) (xy 429.872635 -10.394001) (xy 429.836944 -10.435192)
			(xy 429.795753 -10.470883) (xy 429.749903 -10.500349) (xy 429.700326 -10.522991) (xy 429.648031 -10.538346)
			(xy 429.594083 -10.546102) (xy 429.539581 -10.546102) (xy 429.485633 -10.538346) (xy 429.433338 -10.522991)
			(xy 429.383761 -10.500349) (xy 429.337911 -10.470883) (xy 429.29672 -10.435192) (xy 429.261029 -10.394001)
			(xy 429.231563 -10.348151) (xy 429.208921 -10.298574) (xy 429.193566 -10.246279) (xy 429.18581 -10.192331)
			(xy 429.185324 -10.16508) (xy 428.148496 -10.16508) (xy 428.14801 -10.192331) (xy 428.140254 -10.246279)
			(xy 428.124899 -10.298574) (xy 428.102257 -10.348151) (xy 428.072791 -10.394001) (xy 428.0371 -10.435192)
			(xy 427.995909 -10.470883) (xy 427.950059 -10.500349) (xy 427.900482 -10.522991) (xy 427.848187 -10.538346)
			(xy 427.794239 -10.546102) (xy 427.739737 -10.546102) (xy 427.685789 -10.538346) (xy 427.633494 -10.522991)
			(xy 427.583917 -10.500349) (xy 427.538067 -10.470883) (xy 427.496876 -10.435192) (xy 427.461185 -10.394001)
			(xy 427.431719 -10.348151) (xy 427.409077 -10.298574) (xy 427.393722 -10.246279) (xy 427.385966 -10.192331)
			(xy 427.38548 -10.16508) (xy 427.385982 -10.137311) (xy 427.394037 -10.08236) (xy 427.409975 -10.029157)
			(xy 427.433458 -9.978828) (xy 427.463991 -9.932435) (xy 427.500928 -9.89096) (xy 427.521878 -9.872726)
			(xy 427.53285 -9.862816) (xy 427.549045 -9.838096) (xy 427.557496 -9.809778) (xy 427.557496 -9.780225)
			(xy 427.549046 -9.751906) (xy 427.532852 -9.727186) (xy 427.521878 -9.717278) (xy 427.500918 -9.699053)
			(xy 427.46398 -9.657577) (xy 427.433446 -9.611183) (xy 427.409961 -9.560852) (xy 427.394022 -9.507647)
			(xy 427.385966 -9.452694) (xy 427.38548 -9.424924) (xy 427.38602 -9.395527) (xy 427.395032 -9.337426)
			(xy 427.412845 -9.281395) (xy 427.43904 -9.228758) (xy 427.455584 -9.204452) (xy 427.463263 -9.192858)
			(xy 427.472602 -9.166675) (xy 427.474529 -9.138943) (xy 427.468901 -9.111719) (xy 427.456136 -9.087024)
			(xy 427.43718 -9.06669) (xy 427.413441 -9.052225) (xy 427.386679 -9.044703) (xy 427.37278 -9.044178)
			(xy 426.361098 -9.044178) (xy 426.347178 -9.044596) (xy 426.320366 -9.052095) (xy 426.29658 -9.066561)
			(xy 426.277588 -9.086917) (xy 426.264805 -9.111649) (xy 426.259182 -9.138915) (xy 426.261137 -9.166686)
			(xy 426.270526 -9.192896) (xy 426.278294 -9.204452) (xy 426.294826 -9.228764) (xy 426.321015 -9.281401)
			(xy 426.338824 -9.337431) (xy 426.347834 -9.395528) (xy 426.348398 -9.424924) (xy 426.347896 -9.452693)
			(xy 426.339839 -9.507643) (xy 426.3239 -9.560845) (xy 426.300416 -9.611173) (xy 426.269882 -9.657563)
			(xy 426.232944 -9.699037) (xy 426.212 -9.717278) (xy 426.201022 -9.727184) (xy 426.184815 -9.751902)
			(xy 426.176358 -9.780223) (xy 426.176359 -9.80978) (xy 426.184816 -9.838101) (xy 426.201023 -9.862818)
			(xy 426.212 -9.872726) (xy 426.23296 -9.89095) (xy 426.2699 -9.932426) (xy 426.300436 -9.97882) (xy 426.323921 -10.029151)
			(xy 426.339861 -10.082356) (xy 426.347917 -10.137309) (xy 426.348398 -10.16508) (xy 426.347912 -10.192331)
			(xy 426.340156 -10.246279) (xy 426.324801 -10.298574) (xy 426.302159 -10.348151) (xy 426.272693 -10.394001)
			(xy 426.237002 -10.435192) (xy 426.195811 -10.470883) (xy 426.149961 -10.500349) (xy 426.100384 -10.522991)
			(xy 426.048089 -10.538346) (xy 425.994141 -10.546102) (xy 425.939639 -10.546102) (xy 425.885691 -10.538346)
			(xy 425.833396 -10.522991) (xy 425.783819 -10.500349) (xy 425.737969 -10.470883) (xy 425.696778 -10.435192)
			(xy 425.661087 -10.394001) (xy 425.631621 -10.348151) (xy 425.608979 -10.298574) (xy 425.593624 -10.246279)
			(xy 425.585868 -10.192331) (xy 425.585382 -10.16508) (xy 425.585884 -10.137311) (xy 425.593939 -10.08236)
			(xy 425.609877 -10.029157) (xy 425.633361 -9.978828) (xy 425.663893 -9.932436) (xy 425.70083 -9.89096)
			(xy 425.72178 -9.872726) (xy 425.732752 -9.862816) (xy 425.748947 -9.838096) (xy 425.757397 -9.809778)
			(xy 425.757398 -9.780225) (xy 425.748948 -9.751906) (xy 425.732754 -9.727186) (xy 425.72178 -9.717278)
			(xy 425.70082 -9.699053) (xy 425.663882 -9.657577) (xy 425.633348 -9.611183) (xy 425.609863 -9.560852)
			(xy 425.593924 -9.507647) (xy 425.585867 -9.452694) (xy 425.585382 -9.424924) (xy 425.585922 -9.395527)
			(xy 425.594934 -9.337426) (xy 425.612747 -9.281395) (xy 425.638942 -9.228758) (xy 425.655486 -9.204452)
			(xy 425.663165 -9.192858) (xy 425.672503 -9.166675) (xy 425.67443 -9.138942) (xy 425.668802 -9.111719)
			(xy 425.656037 -9.087024) (xy 425.637082 -9.066689) (xy 425.613343 -9.052224) (xy 425.586581 -9.044701)
			(xy 425.572682 -9.044178) (xy 424.561 -9.044178) (xy 424.547079 -9.044596) (xy 424.520268 -9.052094)
			(xy 424.496481 -9.06656) (xy 424.477488 -9.086917) (xy 424.464705 -9.111649) (xy 424.459082 -9.138915)
			(xy 424.461037 -9.166687) (xy 424.470426 -9.192896) (xy 424.478196 -9.204452) (xy 424.494728 -9.228764)
			(xy 424.520917 -9.281401) (xy 424.538726 -9.337431) (xy 424.547735 -9.395528) (xy 424.5483 -9.424924)
			(xy 424.547798 -9.452693) (xy 424.539741 -9.507643) (xy 424.523802 -9.560845) (xy 424.500318 -9.611173)
			(xy 424.469784 -9.657564) (xy 424.432846 -9.699037) (xy 424.411902 -9.717278) (xy 424.400923 -9.727184)
			(xy 424.384717 -9.751901) (xy 424.37626 -9.780223) (xy 424.37626 -9.80978) (xy 424.384718 -9.838101)
			(xy 424.400925 -9.862818) (xy 424.411902 -9.872726) (xy 424.432862 -9.89095) (xy 424.469802 -9.932426)
			(xy 424.500337 -9.97882) (xy 424.523823 -10.029151) (xy 424.539762 -10.082356) (xy 424.547818 -10.13731)
			(xy 424.5483 -10.16508) (xy 424.547814 -10.192331) (xy 424.540058 -10.246279) (xy 424.524703 -10.298574)
			(xy 424.502061 -10.348151) (xy 424.472595 -10.394001) (xy 424.436904 -10.435192) (xy 424.395713 -10.470883)
			(xy 424.349863 -10.500349) (xy 424.300286 -10.522991) (xy 424.247991 -10.538346) (xy 424.194043 -10.546102)
			(xy 424.139541 -10.546102) (xy 424.085593 -10.538346) (xy 424.033298 -10.522991) (xy 423.983721 -10.500349)
			(xy 423.937871 -10.470883) (xy 423.89668 -10.435192) (xy 423.860989 -10.394001) (xy 423.831523 -10.348151)
			(xy 423.808881 -10.298574) (xy 423.793526 -10.246279) (xy 423.78577 -10.192331) (xy 423.785284 -10.16508)
			(xy 423.785786 -10.137311) (xy 423.793842 -10.08236) (xy 423.80978 -10.029158) (xy 423.833263 -9.978829)
			(xy 423.863796 -9.932436) (xy 423.900733 -9.890961) (xy 423.921682 -9.872726) (xy 423.932654 -9.862816)
			(xy 423.948848 -9.838096) (xy 423.957298 -9.809777) (xy 423.957299 -9.780225) (xy 423.948849 -9.751906)
			(xy 423.932655 -9.727186) (xy 423.921682 -9.717278) (xy 423.900722 -9.699054) (xy 423.863784 -9.657577)
			(xy 423.833249 -9.611183) (xy 423.809764 -9.560852) (xy 423.793825 -9.507648) (xy 423.785768 -9.452694)
			(xy 423.785284 -9.424924) (xy 423.785824 -9.395527) (xy 423.794836 -9.337427) (xy 423.812649 -9.281395)
			(xy 423.838844 -9.228758) (xy 423.855388 -9.204452) (xy 423.863067 -9.192858) (xy 423.872405 -9.166674)
			(xy 423.874332 -9.138942) (xy 423.868704 -9.111718) (xy 423.855939 -9.087023) (xy 423.836984 -9.066689)
			(xy 423.813245 -9.052223) (xy 423.786483 -9.0447) (xy 423.772584 -9.044178) (xy 421.455596 -9.044178)
			(xy 420.501572 -9.998202) (xy 420.513256 -10.028936) (xy 420.521218 -10.050741) (xy 420.532406 -10.095794)
			(xy 420.538054 -10.14187) (xy 420.538402 -10.16508) (xy 420.53794 -10.192334) (xy 420.530185 -10.246286)
			(xy 420.514831 -10.298586) (xy 420.49219 -10.348169) (xy 420.462722 -10.394024) (xy 420.427028 -10.435218)
			(xy 420.385835 -10.470914) (xy 420.339981 -10.500383) (xy 420.290399 -10.523026) (xy 420.2381 -10.538382)
			(xy 420.184148 -10.546139) (xy 420.156894 -10.546588) (xy 420.133683 -10.546248) (xy 420.087603 -10.540614)
			(xy 420.04255 -10.529419) (xy 420.02075 -10.521442) (xy 419.990016 -10.509758) (xy 419.249606 -11.250168)
			(xy 440.572652 -11.250168) (xy 440.573087 -11.222796) (xy 440.58091 -11.168616) (xy 440.596406 -11.116112)
			(xy 440.619255 -11.066365) (xy 440.648987 -11.0204) (xy 440.666632 -10.99947) (xy 440.675897 -10.988165)
			(xy 440.688067 -10.961598) (xy 440.692232 -10.932676) (xy 440.688053 -10.903755) (xy 440.675871 -10.877195)
			(xy 440.666632 -10.865866) (xy 440.649015 -10.844916) (xy 440.619299 -10.798948) (xy 440.596458 -10.749206)
			(xy 440.580962 -10.696709) (xy 440.573129 -10.642536) (xy 440.572652 -10.615168) (xy 440.573138 -10.587917)
			(xy 440.580894 -10.533969) (xy 440.596249 -10.481674) (xy 440.618891 -10.432097) (xy 440.648357 -10.386247)
			(xy 440.684048 -10.345056) (xy 440.725239 -10.309365) (xy 440.771089 -10.279899) (xy 440.820666 -10.257257)
			(xy 440.872961 -10.241902) (xy 440.926909 -10.234146) (xy 440.981411 -10.234146) (xy 441.035359 -10.241902)
			(xy 441.087654 -10.257257) (xy 441.137231 -10.279899) (xy 441.183081 -10.309365) (xy 441.224272 -10.345056)
			(xy 441.259963 -10.386247) (xy 441.289429 -10.432097) (xy 441.312071 -10.481674) (xy 441.327426 -10.533969)
			(xy 441.335182 -10.587917) (xy 441.335668 -10.615168) (xy 441.335191 -10.642538) (xy 441.327377 -10.696717)
			(xy 441.311891 -10.74922) (xy 441.289051 -10.798967) (xy 441.259329 -10.844934) (xy 441.241688 -10.865866)
			(xy 441.232483 -10.877217) (xy 441.220303 -10.903766) (xy 441.216125 -10.932676) (xy 441.220289 -10.961587)
			(xy 441.232457 -10.988143) (xy 441.241688 -10.99947) (xy 441.259325 -11.020404) (xy 441.289037 -11.066376)
			(xy 441.311874 -11.116123) (xy 441.327365 -11.168623) (xy 441.335194 -11.222799) (xy 441.335668 -11.250168)
			(xy 441.335182 -11.277419) (xy 441.327426 -11.331367) (xy 441.312071 -11.383662) (xy 441.289429 -11.433239)
			(xy 441.259963 -11.479089) (xy 441.224272 -11.52028) (xy 441.183081 -11.555971) (xy 441.137231 -11.585437)
			(xy 441.087654 -11.608079) (xy 441.035359 -11.623434) (xy 440.981411 -11.63119) (xy 440.926909 -11.63119)
			(xy 440.872961 -11.623434) (xy 440.820666 -11.608079) (xy 440.771089 -11.585437) (xy 440.725239 -11.555971)
			(xy 440.684048 -11.52028) (xy 440.648357 -11.479089) (xy 440.618891 -11.433239) (xy 440.596249 -11.383662)
			(xy 440.580894 -11.331367) (xy 440.573138 -11.277419) (xy 440.572652 -11.250168) (xy 419.249606 -11.250168)
			(xy 418.579554 -11.92022) (xy 418.569703 -11.930775) (xy 418.555812 -11.956071) (xy 418.549551 -11.984242)
			(xy 418.551417 -12.01304) (xy 418.561263 -12.040167) (xy 418.578303 -12.063458) (xy 418.58946 -12.07262)
			(xy 418.612195 -12.090788) (xy 418.652408 -12.132855) (xy 418.685759 -12.180546) (xy 418.711471 -12.232753)
			(xy 418.728948 -12.288262) (xy 418.737783 -12.345782) (xy 418.738304 -12.37488) (xy 419.774876 -12.37488)
			(xy 419.778947 -12.319258) (xy 419.791073 -12.264821) (xy 419.810996 -12.21273) (xy 419.838292 -12.164095)
			(xy 419.872378 -12.119952) (xy 419.912527 -12.081243) (xy 419.957885 -12.048792) (xy 420.007485 -12.023291)
			(xy 420.060269 -12.005284) (xy 420.115112 -11.995154) (xy 420.170846 -11.993117) (xy 420.226283 -11.999217)
			(xy 420.28024 -12.013323) (xy 420.331569 -12.035135) (xy 420.379175 -12.064189) (xy 420.422043 -12.099864)
			(xy 420.45926 -12.141401) (xy 420.490033 -12.187914) (xy 420.513705 -12.238411) (xy 420.529773 -12.291818)
			(xy 420.537893 -12.346994) (xy 420.538402 -12.37488) (xy 423.784774 -12.37488) (xy 423.788845 -12.319258)
			(xy 423.800971 -12.264821) (xy 423.820894 -12.21273) (xy 423.84819 -12.164095) (xy 423.882276 -12.119952)
			(xy 423.922425 -12.081243) (xy 423.967783 -12.048792) (xy 424.017383 -12.023291) (xy 424.070167 -12.005284)
			(xy 424.12501 -11.995154) (xy 424.180744 -11.993117) (xy 424.236181 -11.999217) (xy 424.290138 -12.013323)
			(xy 424.341467 -12.035135) (xy 424.389073 -12.064189) (xy 424.431941 -12.099864) (xy 424.469158 -12.141401)
			(xy 424.499931 -12.187914) (xy 424.523603 -12.238411) (xy 424.539671 -12.291818) (xy 424.547791 -12.346994)
			(xy 424.5483 -12.37488) (xy 425.584872 -12.37488) (xy 425.588943 -12.319258) (xy 425.601069 -12.264821)
			(xy 425.620992 -12.21273) (xy 425.648288 -12.164095) (xy 425.682374 -12.119952) (xy 425.722523 -12.081243)
			(xy 425.767881 -12.048792) (xy 425.817481 -12.023291) (xy 425.870265 -12.005284) (xy 425.925108 -11.995154)
			(xy 425.980842 -11.993117) (xy 426.036279 -11.999217) (xy 426.090236 -12.013323) (xy 426.141565 -12.035135)
			(xy 426.189171 -12.064189) (xy 426.232039 -12.099864) (xy 426.269256 -12.141401) (xy 426.300029 -12.187914)
			(xy 426.323701 -12.238411) (xy 426.339769 -12.291818) (xy 426.347889 -12.346994) (xy 426.348398 -12.37488)
			(xy 427.38497 -12.37488) (xy 427.389041 -12.319258) (xy 427.401167 -12.264821) (xy 427.42109 -12.21273)
			(xy 427.448386 -12.164095) (xy 427.482472 -12.119952) (xy 427.522621 -12.081243) (xy 427.567979 -12.048792)
			(xy 427.617579 -12.023291) (xy 427.670363 -12.005284) (xy 427.725206 -11.995154) (xy 427.78094 -11.993117)
			(xy 427.836377 -11.999217) (xy 427.890334 -12.013323) (xy 427.941663 -12.035135) (xy 427.989269 -12.064189)
			(xy 428.032137 -12.099864) (xy 428.069354 -12.141401) (xy 428.100127 -12.187914) (xy 428.123799 -12.238411)
			(xy 428.139867 -12.291818) (xy 428.147987 -12.346994) (xy 428.148496 -12.37488) (xy 429.184814 -12.37488)
			(xy 429.188885 -12.319258) (xy 429.201011 -12.264821) (xy 429.220934 -12.21273) (xy 429.24823 -12.164095)
			(xy 429.282316 -12.119952) (xy 429.322465 -12.081243) (xy 429.367823 -12.048792) (xy 429.417423 -12.023291)
			(xy 429.470207 -12.005284) (xy 429.52505 -11.995154) (xy 429.580784 -11.993117) (xy 429.636221 -11.999217)
			(xy 429.690178 -12.013323) (xy 429.741507 -12.035135) (xy 429.789113 -12.064189) (xy 429.831981 -12.099864)
			(xy 429.869198 -12.141401) (xy 429.899971 -12.187914) (xy 429.923643 -12.238411) (xy 429.939711 -12.291818)
			(xy 429.947831 -12.346994) (xy 429.94834 -12.37488) (xy 430.985422 -12.37488) (xy 430.985908 -12.347629)
			(xy 430.993664 -12.293681) (xy 431.009019 -12.241386) (xy 431.031661 -12.191809) (xy 431.061127 -12.145959)
			(xy 431.096818 -12.104768) (xy 431.138009 -12.069077) (xy 431.183859 -12.039611) (xy 431.233436 -12.016969)
			(xy 431.285731 -12.001614) (xy 431.339679 -11.993858) (xy 431.394181 -11.993858) (xy 431.448129 -12.001614)
			(xy 431.500424 -12.016969) (xy 431.550001 -12.039611) (xy 431.595851 -12.069077) (xy 431.637042 -12.104768)
			(xy 431.672733 -12.145959) (xy 431.702199 -12.191809) (xy 431.724841 -12.241386) (xy 431.740196 -12.293681)
			(xy 431.747952 -12.347629) (xy 431.748438 -12.37488) (xy 431.748302 -12.388198) (xy 431.746396 -12.414765)
			(xy 431.744628 -12.427966) (xy 431.743738 -12.437249) (xy 431.747858 -12.455418) (xy 431.758205 -12.470911)
			(xy 431.773411 -12.481675) (xy 431.791461 -12.486287) (xy 431.800762 -12.485624) (xy 431.811329 -12.484473)
			(xy 431.832551 -12.4832) (xy 431.84318 -12.483084) (xy 432.70678 -12.483084) (xy 432.73472 -12.484354)
			(xy 432.746097 -12.484542) (xy 432.767255 -12.476251) (xy 432.782804 -12.45968) (xy 432.789734 -12.438038)
			(xy 432.788822 -12.426696) (xy 432.787168 -12.413806) (xy 432.785386 -12.387876) (xy 432.785266 -12.37488)
			(xy 432.785752 -12.347629) (xy 432.793508 -12.293681) (xy 432.808863 -12.241386) (xy 432.831505 -12.191809)
			(xy 432.860971 -12.145959) (xy 432.896662 -12.104768) (xy 432.937853 -12.069077) (xy 432.983703 -12.039611)
			(xy 433.03328 -12.016969) (xy 433.085575 -12.001614) (xy 433.139523 -11.993858) (xy 433.194025 -11.993858)
			(xy 433.247973 -12.001614) (xy 433.300268 -12.016969) (xy 433.349845 -12.039611) (xy 433.395695 -12.069077)
			(xy 433.436886 -12.104768) (xy 433.472577 -12.145959) (xy 433.502043 -12.191809) (xy 433.524685 -12.241386)
			(xy 433.54004 -12.293681) (xy 433.547796 -12.347629) (xy 433.548282 -12.37488) (xy 433.547768 -12.401293)
			(xy 433.540469 -12.453613) (xy 433.526022 -12.504425) (xy 433.504703 -12.552758) (xy 433.476919 -12.597688)
			(xy 433.443202 -12.638355) (xy 433.414088 -12.664948) (xy 438.205372 -12.664948) (xy 438.205858 -12.637697)
			(xy 438.213614 -12.583749) (xy 438.228969 -12.531454) (xy 438.251611 -12.481877) (xy 438.281077 -12.436027)
			(xy 438.316768 -12.394836) (xy 438.357959 -12.359145) (xy 438.403809 -12.329679) (xy 438.453386 -12.307037)
			(xy 438.505681 -12.291682) (xy 438.559629 -12.283926) (xy 438.614131 -12.283926) (xy 438.668079 -12.291682)
			(xy 438.720374 -12.307037) (xy 438.769951 -12.329679) (xy 438.815801 -12.359145) (xy 438.856992 -12.394836)
			(xy 438.892683 -12.436027) (xy 438.922149 -12.481877) (xy 438.944791 -12.531454) (xy 438.960146 -12.583749)
			(xy 438.967902 -12.637697) (xy 438.968388 -12.664948) (xy 438.967964 -12.690593) (xy 438.961083 -12.741419)
			(xy 438.947453 -12.790864) (xy 438.927319 -12.838036) (xy 438.91454 -12.860274) (xy 438.907618 -12.872927)
			(xy 438.900413 -12.900841) (xy 438.901281 -12.929657) (xy 438.910152 -12.957086) (xy 438.926322 -12.980953)
			(xy 438.948508 -12.999362) (xy 438.96153 -13.005562) (xy 438.986071 -13.016649) (xy 439.032034 -13.044706)
			(xy 439.073586 -13.078958) (xy 439.092086 -13.098526) (xy 439.099707 -13.106115) (xy 439.119419 -13.114661)
			(xy 439.140902 -13.114378) (xy 439.160382 -13.105316) (xy 439.167778 -13.09751) (xy 439.194194 -13.070332)
			(xy 439.203502 -13.06083) (xy 439.217398 -13.038163) (xy 439.224981 -13.012681) (xy 439.225739 -12.986105)
			(xy 439.219622 -12.960231) (xy 439.207042 -12.936809) (xy 439.198258 -12.926822) (xy 439.178816 -12.905471)
			(xy 439.145988 -12.857963) (xy 439.120702 -12.806049) (xy 439.103534 -12.750914) (xy 439.094878 -12.693821)
			(xy 439.094372 -12.664948) (xy 439.094858 -12.637697) (xy 439.102614 -12.583749) (xy 439.117969 -12.531454)
			(xy 439.140611 -12.481877) (xy 439.170077 -12.436027) (xy 439.205768 -12.394836) (xy 439.246959 -12.359145)
			(xy 439.292809 -12.329679) (xy 439.342386 -12.307037) (xy 439.394681 -12.291682) (xy 439.448629 -12.283926)
			(xy 439.503131 -12.283926) (xy 439.557079 -12.291682) (xy 439.609374 -12.307037) (xy 439.658951 -12.329679)
			(xy 439.704801 -12.359145) (xy 439.745992 -12.394836) (xy 439.781683 -12.436027) (xy 439.811149 -12.481877)
			(xy 439.833791 -12.531454) (xy 439.849146 -12.583749) (xy 439.856902 -12.637697) (xy 439.857388 -12.664948)
			(xy 439.856965 -12.690612) (xy 439.850096 -12.741479) (xy 439.83646 -12.790963) (xy 439.816306 -12.838169)
			(xy 439.789998 -12.882242) (xy 439.758011 -12.922385) (xy 439.720926 -12.957871) (xy 439.700416 -12.973304)
			(xy 439.693112 -12.979079) (xy 439.682951 -12.994664) (xy 439.679045 -13.012855) (xy 439.681915 -13.031237)
			(xy 439.691178 -13.047372) (xy 439.69813 -13.053568) (xy 439.716164 -13.06957) (xy 439.726064 -13.078327)
			(xy 439.749337 -13.090839) (xy 439.77504 -13.096968) (xy 439.801455 -13.096304) (xy 439.826817 -13.088892)
			(xy 439.849433 -13.075226) (xy 439.858912 -13.066014) (xy 439.87615 -13.048606) (xy 439.914312 -13.017884)
			(xy 439.956091 -12.992298) (xy 439.978292 -12.98194) (xy 439.99075 -12.975857) (xy 440.012091 -12.958181)
			(xy 440.027903 -12.935423) (xy 440.037022 -12.909256) (xy 440.038781 -12.881601) (xy 440.033049 -12.854489)
			(xy 440.02706 -12.841986) (xy 440.013332 -12.814514) (xy 439.99388 -12.756265) (xy 439.984006 -12.695653)
			(xy 439.983372 -12.664948) (xy 439.983858 -12.637697) (xy 439.991614 -12.583749) (xy 440.006969 -12.531454)
			(xy 440.029611 -12.481877) (xy 440.059077 -12.436027) (xy 440.094768 -12.394836) (xy 440.135959 -12.359145)
			(xy 440.181809 -12.329679) (xy 440.231386 -12.307037) (xy 440.283681 -12.291682) (xy 440.337629 -12.283926)
			(xy 440.392131 -12.283926) (xy 440.446079 -12.291682) (xy 440.498374 -12.307037) (xy 440.547951 -12.329679)
			(xy 440.593801 -12.359145) (xy 440.634992 -12.394836) (xy 440.670683 -12.436027) (xy 440.700149 -12.481877)
			(xy 440.722791 -12.531454) (xy 440.738146 -12.583749) (xy 440.745902 -12.637697) (xy 440.746388 -12.664948)
			(xy 440.745889 -12.69241) (xy 440.737999 -12.746765) (xy 440.722403 -12.799429) (xy 440.699423 -12.849316)
			(xy 440.669534 -12.895395) (xy 440.633351 -12.936717) (xy 440.591621 -12.972429) (xy 440.545205 -13.001794)
			(xy 440.520328 -13.013436) (xy 440.507888 -13.019553) (xy 440.486546 -13.037221) (xy 440.470733 -13.059971)
			(xy 440.46161 -13.086131) (xy 440.459847 -13.113781) (xy 440.465574 -13.140889) (xy 440.47156 -13.15339)
			(xy 440.485281 -13.180866) (xy 440.504735 -13.239113) (xy 440.514612 -13.299723) (xy 440.515248 -13.330428)
			(xy 440.514748 -13.357678) (xy 440.506989 -13.411623) (xy 440.491632 -13.463915) (xy 440.468991 -13.51349)
			(xy 440.439525 -13.559338) (xy 440.403836 -13.600527) (xy 440.362648 -13.636218) (xy 440.316801 -13.665685)
			(xy 440.267227 -13.688328) (xy 440.214935 -13.703687) (xy 440.16099 -13.711448) (xy 440.13374 -13.711936)
			(xy 440.105036 -13.711419) (xy 440.048276 -13.702822) (xy 439.993445 -13.685816) (xy 439.941782 -13.660785)
			(xy 439.894453 -13.628295) (xy 439.873136 -13.609066) (xy 439.863239 -13.600305) (xy 439.839966 -13.587788)
			(xy 439.814261 -13.581657) (xy 439.787844 -13.582321) (xy 439.762481 -13.589737) (xy 439.739866 -13.603407)
			(xy 439.730388 -13.612622) (xy 439.712331 -13.630757) (xy 439.672245 -13.662568) (xy 439.62827 -13.688739)
			(xy 439.581192 -13.708802) (xy 439.531856 -13.722397) (xy 439.481147 -13.729281) (xy 439.45556 -13.729716)
			(xy 439.428096 -13.729261) (xy 439.373733 -13.721394) (xy 439.32106 -13.705815) (xy 439.271165 -13.682846)
			(xy 439.225078 -13.652961) (xy 439.2041 -13.635228) (xy 439.192533 -13.625861) (xy 439.165452 -13.613555)
			(xy 439.135976 -13.609556) (xy 439.106595 -13.614202) (xy 439.079791 -13.627099) (xy 439.068464 -13.636752)
			(xy 439.047247 -13.655576) (xy 439.000259 -13.687344) (xy 438.949085 -13.711805) (xy 438.894854 -13.728418)
			(xy 438.83876 -13.736817) (xy 438.8104 -13.737336) (xy 438.78315 -13.736822) (xy 438.729205 -13.729067)
			(xy 438.676912 -13.713713) (xy 438.627337 -13.691074) (xy 438.581488 -13.66161) (xy 438.540298 -13.625922)
			(xy 438.504607 -13.584735) (xy 438.47514 -13.538888) (xy 438.452497 -13.489314) (xy 438.437139 -13.437023)
			(xy 438.42938 -13.383078) (xy 438.428892 -13.355828) (xy 438.429308 -13.330183) (xy 438.436192 -13.279357)
			(xy 438.449824 -13.229912) (xy 438.46996 -13.18274) (xy 438.48274 -13.160502) (xy 438.4897 -13.147867)
			(xy 438.496902 -13.119946) (xy 438.49603 -13.091123) (xy 438.487152 -13.063689) (xy 438.470972 -13.03982)
			(xy 438.448777 -13.021413) (xy 438.43575 -13.015214) (xy 438.410451 -13.003789) (xy 438.363205 -12.974648)
			(xy 438.320682 -12.938967) (xy 438.28378 -12.897498) (xy 438.253279 -12.851119) (xy 438.229823 -12.800808)
			(xy 438.213907 -12.747628) (xy 438.205868 -12.692703) (xy 438.205372 -12.664948) (xy 433.414088 -12.664948)
			(xy 433.404198 -12.673982) (xy 433.360651 -12.703887) (xy 433.313395 -12.727498) (xy 433.263333 -12.744363)
			(xy 433.211423 -12.754161) (xy 433.185062 -12.75588) (xy 433.169444 -12.757248) (xy 433.140082 -12.768183)
			(xy 433.115397 -12.787481) (xy 433.097699 -12.813336) (xy 433.088642 -12.843331) (xy 433.088288 -12.859004)
			(xy 433.088288 -12.864846) (xy 433.087819 -12.892104) (xy 433.080059 -12.946064) (xy 433.064702 -12.998372)
			(xy 433.042061 -13.047964) (xy 433.012596 -13.093831) (xy 432.976907 -13.135041) (xy 432.935719 -13.170755)
			(xy 432.88987 -13.200248) (xy 432.840292 -13.22292) (xy 432.787993 -13.238309) (xy 432.734037 -13.246103)
			(xy 432.70678 -13.246608) (xy 431.84318 -13.246608) (xy 431.815915 -13.246163) (xy 431.761941 -13.238397)
			(xy 431.709623 -13.223025) (xy 431.660025 -13.200362) (xy 431.61416 -13.170868) (xy 431.572961 -13.135145)
			(xy 431.537267 -13.09392) (xy 431.507807 -13.048034) (xy 431.485179 -12.99842) (xy 431.469845 -12.946091)
			(xy 431.462117 -12.892111) (xy 431.461672 -12.864846) (xy 431.461672 -12.859258) (xy 431.461481 -12.845927)
			(xy 431.454901 -12.820096) (xy 431.441858 -12.79685) (xy 431.423244 -12.777771) (xy 431.400325 -12.764161)
			(xy 431.374664 -12.756947) (xy 431.361342 -12.756388) (xy 431.334351 -12.755568) (xy 431.281009 -12.747163)
			(xy 431.229384 -12.731321) (xy 431.180509 -12.708359) (xy 431.135359 -12.678736) (xy 431.094836 -12.643043)
			(xy 431.05975 -12.601994) (xy 431.030802 -12.556408) (xy 431.00857 -12.507196) (xy 430.993499 -12.455342)
			(xy 430.985888 -12.40188) (xy 430.985422 -12.37488) (xy 429.94834 -12.37488) (xy 429.947831 -12.402766)
			(xy 429.939711 -12.457942) (xy 429.923643 -12.511349) (xy 429.899971 -12.561846) (xy 429.869198 -12.608359)
			(xy 429.831981 -12.649896) (xy 429.789113 -12.685571) (xy 429.741507 -12.714625) (xy 429.690178 -12.736437)
			(xy 429.636221 -12.750543) (xy 429.580784 -12.756643) (xy 429.52505 -12.754606) (xy 429.470207 -12.744476)
			(xy 429.417423 -12.726469) (xy 429.367823 -12.700968) (xy 429.322465 -12.668517) (xy 429.282316 -12.629808)
			(xy 429.24823 -12.585665) (xy 429.220934 -12.53703) (xy 429.201011 -12.484939) (xy 429.188885 -12.430502)
			(xy 429.184814 -12.37488) (xy 428.148496 -12.37488) (xy 428.147987 -12.402766) (xy 428.139867 -12.457942)
			(xy 428.123799 -12.511349) (xy 428.100127 -12.561846) (xy 428.069354 -12.608359) (xy 428.032137 -12.649896)
			(xy 427.989269 -12.685571) (xy 427.941663 -12.714625) (xy 427.890334 -12.736437) (xy 427.836377 -12.750543)
			(xy 427.78094 -12.756643) (xy 427.725206 -12.754606) (xy 427.670363 -12.744476) (xy 427.617579 -12.726469)
			(xy 427.567979 -12.700968) (xy 427.522621 -12.668517) (xy 427.482472 -12.629808) (xy 427.448386 -12.585665)
			(xy 427.42109 -12.53703) (xy 427.401167 -12.484939) (xy 427.389041 -12.430502) (xy 427.38497 -12.37488)
			(xy 426.348398 -12.37488) (xy 426.347889 -12.402766) (xy 426.339769 -12.457942) (xy 426.323701 -12.511349)
			(xy 426.300029 -12.561846) (xy 426.269256 -12.608359) (xy 426.232039 -12.649896) (xy 426.189171 -12.685571)
			(xy 426.141565 -12.714625) (xy 426.090236 -12.736437) (xy 426.036279 -12.750543) (xy 425.980842 -12.756643)
			(xy 425.925108 -12.754606) (xy 425.870265 -12.744476) (xy 425.817481 -12.726469) (xy 425.767881 -12.700968)
			(xy 425.722523 -12.668517) (xy 425.682374 -12.629808) (xy 425.648288 -12.585665) (xy 425.620992 -12.53703)
			(xy 425.601069 -12.484939) (xy 425.588943 -12.430502) (xy 425.584872 -12.37488) (xy 424.5483 -12.37488)
			(xy 424.547791 -12.402766) (xy 424.539671 -12.457942) (xy 424.523603 -12.511349) (xy 424.499931 -12.561846)
			(xy 424.469158 -12.608359) (xy 424.431941 -12.649896) (xy 424.389073 -12.685571) (xy 424.341467 -12.714625)
			(xy 424.290138 -12.736437) (xy 424.236181 -12.750543) (xy 424.180744 -12.756643) (xy 424.12501 -12.754606)
			(xy 424.070167 -12.744476) (xy 424.017383 -12.726469) (xy 423.967783 -12.700968) (xy 423.922425 -12.668517)
			(xy 423.882276 -12.629808) (xy 423.84819 -12.585665) (xy 423.820894 -12.53703) (xy 423.800971 -12.484939)
			(xy 423.788845 -12.430502) (xy 423.784774 -12.37488) (xy 420.538402 -12.37488) (xy 420.537893 -12.402766)
			(xy 420.529773 -12.457942) (xy 420.513705 -12.511349) (xy 420.490033 -12.561846) (xy 420.45926 -12.608359)
			(xy 420.422043 -12.649896) (xy 420.379175 -12.685571) (xy 420.331569 -12.714625) (xy 420.28024 -12.736437)
			(xy 420.226283 -12.750543) (xy 420.170846 -12.756643) (xy 420.115112 -12.754606) (xy 420.060269 -12.744476)
			(xy 420.007485 -12.726469) (xy 419.957885 -12.700968) (xy 419.912527 -12.668517) (xy 419.872378 -12.629808)
			(xy 419.838292 -12.585665) (xy 419.810996 -12.53703) (xy 419.791073 -12.484939) (xy 419.778947 -12.430502)
			(xy 419.774876 -12.37488) (xy 418.738304 -12.37488) (xy 418.737842 -12.402134) (xy 418.730087 -12.456087)
			(xy 418.714733 -12.508387) (xy 418.692092 -12.557969) (xy 418.662624 -12.603824) (xy 418.62693 -12.645019)
			(xy 418.585737 -12.680714) (xy 418.539883 -12.710184) (xy 418.490302 -12.732827) (xy 418.438002 -12.748184)
			(xy 418.38405 -12.755941) (xy 418.356796 -12.756388) (xy 418.3277 -12.755839) (xy 418.270183 -12.746998)
			(xy 418.214677 -12.729522) (xy 418.16247 -12.703817) (xy 418.114774 -12.67048) (xy 418.072696 -12.630284)
			(xy 418.054536 -12.607544) (xy 418.045338 -12.596426) (xy 418.022053 -12.579408) (xy 417.99494 -12.569574)
			(xy 417.966159 -12.567707) (xy 417.938003 -12.573956) (xy 417.912714 -12.587822) (xy 417.902136 -12.597638)
			(xy 417.156138 -13.343636) (xy 417.156138 -17.243044) (xy 417.156656 -17.257692) (xy 417.165041 -17.285766)
			(xy 417.181052 -17.310304) (xy 417.203369 -17.329286) (xy 417.230158 -17.341152) (xy 417.259213 -17.344925)
			(xy 417.288144 -17.340293) (xy 417.314569 -17.327639) (xy 417.32581 -17.318228) (xy 417.346963 -17.299813)
			(xy 417.393653 -17.268743) (xy 417.444385 -17.244837) (xy 417.498067 -17.228607) (xy 417.553547 -17.220403)
			(xy 417.581588 -17.21993) (xy 417.591448 -17.219995) (xy 417.611143 -17.221013) (xy 417.620958 -17.221962)
			(xy 417.635474 -17.223036) (xy 417.664101 -17.217828) (xy 417.690097 -17.204758) (xy 417.71135 -17.184886)
			(xy 417.726135 -17.159826) (xy 417.733252 -17.131613) (xy 417.732122 -17.102538) (xy 417.727892 -17.088612)
			(xy 417.718637 -17.059182) (xy 417.708682 -16.998299) (xy 417.70808 -16.967454) (xy 417.708566 -16.940203)
			(xy 417.716322 -16.886255) (xy 417.731677 -16.83396) (xy 417.754319 -16.784383) (xy 417.783785 -16.738533)
			(xy 417.819476 -16.697342) (xy 417.860667 -16.661651) (xy 417.906517 -16.632185) (xy 417.956094 -16.609543)
			(xy 418.008389 -16.594188) (xy 418.062337 -16.586432) (xy 418.116839 -16.586432) (xy 418.170787 -16.594188)
			(xy 418.223082 -16.609543) (xy 418.272659 -16.632185) (xy 418.318509 -16.661651) (xy 418.3597 -16.697342)
			(xy 418.395391 -16.738533) (xy 418.424857 -16.784383) (xy 418.447499 -16.83396) (xy 418.462854 -16.886255)
			(xy 418.47061 -16.940203) (xy 418.471096 -16.967454) (xy 418.470513 -16.997758) (xy 418.460944 -17.057606)
			(xy 418.452046 -17.08658) (xy 418.44822 -17.099752) (xy 418.446959 -17.127141) (xy 418.45303 -17.153879)
			(xy 418.465994 -17.178038) (xy 418.484917 -17.197879) (xy 418.508437 -17.211971) (xy 418.534857 -17.219299)
			(xy 418.548566 -17.219676) (xy 418.889434 -17.219676) (xy 418.903143 -17.219236) (xy 418.929575 -17.211947)
			(xy 418.953108 -17.197877) (xy 418.972041 -17.178045) (xy 418.985004 -17.153885) (xy 418.99106 -17.127144)
			(xy 418.989771 -17.099756) (xy 418.985954 -17.08658) (xy 418.977046 -17.057608) (xy 418.967479 -16.997759)
			(xy 418.966904 -16.967454) (xy 418.96739 -16.940203) (xy 418.975146 -16.886255) (xy 418.990501 -16.83396)
			(xy 419.013143 -16.784383) (xy 419.042609 -16.738533) (xy 419.0783 -16.697342) (xy 419.119491 -16.661651)
			(xy 419.165341 -16.632185) (xy 419.214918 -16.609543) (xy 419.267213 -16.594188) (xy 419.321161 -16.586432)
			(xy 419.375663 -16.586432) (xy 419.429611 -16.594188) (xy 419.481906 -16.609543) (xy 419.531483 -16.632185)
			(xy 419.577333 -16.661651) (xy 419.618524 -16.697342) (xy 419.654215 -16.738533) (xy 419.683681 -16.784383)
			(xy 419.706323 -16.83396) (xy 419.721678 -16.886255) (xy 419.729434 -16.940203) (xy 419.72992 -16.967454)
			(xy 419.729302 -16.998298) (xy 419.719342 -17.059176) (xy 419.710108 -17.088612) (xy 419.705997 -17.102548)
			(xy 419.704923 -17.131569) (xy 419.712058 -17.15972) (xy 419.726828 -17.184725) (xy 419.748038 -17.204562)
			(xy 419.773973 -17.21763) (xy 419.802537 -17.22287) (xy 419.817042 -17.221962) (xy 419.826856 -17.221007)
			(xy 419.846551 -17.21999) (xy 419.856412 -17.21993) (xy 419.88366 -17.220417) (xy 419.937601 -17.228174)
			(xy 419.989889 -17.243529) (xy 420.03946 -17.266168) (xy 420.085304 -17.295632) (xy 420.126489 -17.33132)
			(xy 420.162175 -17.372506) (xy 420.191637 -17.418351) (xy 420.214275 -17.467922) (xy 420.229628 -17.520211)
			(xy 420.237384 -17.574152) (xy 420.237384 -17.628648) (xy 422.788616 -17.628648) (xy 422.788616 -17.574152)
			(xy 422.796372 -17.520211) (xy 422.811725 -17.467922) (xy 422.834363 -17.418351) (xy 422.863825 -17.372506)
			(xy 422.899511 -17.33132) (xy 422.940696 -17.295632) (xy 422.98654 -17.266168) (xy 423.036111 -17.243529)
			(xy 423.088399 -17.228174) (xy 423.14234 -17.220417) (xy 423.169588 -17.21993) (xy 423.179449 -17.21999)
			(xy 423.199144 -17.221007) (xy 423.208958 -17.221962) (xy 423.223463 -17.22287) (xy 423.252027 -17.21763)
			(xy 423.277962 -17.204562) (xy 423.299172 -17.184725) (xy 423.313942 -17.15972) (xy 423.321077 -17.131569)
			(xy 423.320003 -17.102548) (xy 423.315892 -17.088612) (xy 423.306658 -17.059176) (xy 423.296698 -16.998298)
			(xy 423.29608 -16.967454) (xy 423.296566 -16.940203) (xy 423.304322 -16.886255) (xy 423.319677 -16.83396)
			(xy 423.342319 -16.784383) (xy 423.371785 -16.738533) (xy 423.407476 -16.697342) (xy 423.448667 -16.661651)
			(xy 423.494517 -16.632185) (xy 423.544094 -16.609543) (xy 423.596389 -16.594188) (xy 423.650337 -16.586432)
			(xy 423.704839 -16.586432) (xy 423.758787 -16.594188) (xy 423.811082 -16.609543) (xy 423.860659 -16.632185)
			(xy 423.906509 -16.661651) (xy 423.9477 -16.697342) (xy 423.983391 -16.738533) (xy 424.012857 -16.784383)
			(xy 424.035499 -16.83396) (xy 424.050854 -16.886255) (xy 424.05861 -16.940203) (xy 424.059096 -16.967454)
			(xy 424.058521 -16.997759) (xy 424.048954 -17.057608) (xy 424.040046 -17.08658) (xy 424.036229 -17.099756)
			(xy 424.03494 -17.127144) (xy 424.040996 -17.153885) (xy 424.053959 -17.178045) (xy 424.072892 -17.197877)
			(xy 424.096425 -17.211947) (xy 424.122857 -17.219236) (xy 424.136566 -17.219676) (xy 424.477434 -17.219676)
			(xy 424.491143 -17.219299) (xy 424.517563 -17.211971) (xy 424.541083 -17.197879) (xy 424.560006 -17.178038)
			(xy 424.57297 -17.153879) (xy 424.579041 -17.127141) (xy 424.57778 -17.099752) (xy 424.573954 -17.08658)
			(xy 424.565056 -17.057606) (xy 424.555487 -16.997758) (xy 424.554904 -16.967454) (xy 424.55539 -16.940203)
			(xy 424.563146 -16.886255) (xy 424.578501 -16.83396) (xy 424.601143 -16.784383) (xy 424.630609 -16.738533)
			(xy 424.6663 -16.697342) (xy 424.707491 -16.661651) (xy 424.753341 -16.632185) (xy 424.802918 -16.609543)
			(xy 424.855213 -16.594188) (xy 424.909161 -16.586432) (xy 424.963663 -16.586432) (xy 425.017611 -16.594188)
			(xy 425.069906 -16.609543) (xy 425.119483 -16.632185) (xy 425.165333 -16.661651) (xy 425.206524 -16.697342)
			(xy 425.242215 -16.738533) (xy 425.271681 -16.784383) (xy 425.294323 -16.83396) (xy 425.309678 -16.886255)
			(xy 425.317434 -16.940203) (xy 425.31792 -16.967454) (xy 425.317318 -16.998299) (xy 425.307363 -17.059182)
			(xy 425.298108 -17.088612) (xy 425.293878 -17.102538) (xy 425.292748 -17.131613) (xy 425.299865 -17.159826)
			(xy 425.31465 -17.184886) (xy 425.335903 -17.204758) (xy 425.361899 -17.217828) (xy 425.390526 -17.223036)
			(xy 425.405042 -17.221962) (xy 425.414857 -17.221013) (xy 425.434552 -17.219995) (xy 425.444412 -17.21993)
			(xy 425.471665 -17.220341) (xy 425.525617 -17.228099) (xy 425.577916 -17.243457) (xy 425.627496 -17.266101)
			(xy 425.67335 -17.295571) (xy 425.714543 -17.331266) (xy 425.750237 -17.37246) (xy 425.779705 -17.418314)
			(xy 425.802347 -17.467896) (xy 425.817703 -17.520195) (xy 425.82546 -17.574147) (xy 425.82546 -17.628651)
			(xy 428.410593 -17.628651) (xy 428.410593 -17.574149) (xy 428.41835 -17.520201) (xy 428.433706 -17.467907)
			(xy 428.456348 -17.41833) (xy 428.485815 -17.37248) (xy 428.521508 -17.331291) (xy 428.562699 -17.295601)
			(xy 428.608551 -17.266136) (xy 428.658129 -17.243497) (xy 428.710425 -17.228145) (xy 428.764373 -17.220392)
			(xy 428.791624 -17.21993) (xy 428.801485 -17.219995) (xy 428.821179 -17.221008) (xy 428.830994 -17.221962)
			(xy 428.845496 -17.222903) (xy 428.874062 -17.217654) (xy 428.899997 -17.204579) (xy 428.921206 -17.184736)
			(xy 428.935975 -17.159728) (xy 428.943111 -17.131574) (xy 428.942038 -17.10255) (xy 428.937928 -17.088612)
			(xy 428.928695 -17.059176) (xy 428.918734 -16.998298) (xy 428.918116 -16.967454) (xy 428.918602 -16.940203)
			(xy 428.926358 -16.886255) (xy 428.941713 -16.83396) (xy 428.964355 -16.784383) (xy 428.993821 -16.738533)
			(xy 429.029512 -16.697342) (xy 429.070703 -16.661651) (xy 429.116553 -16.632185) (xy 429.16613 -16.609543)
			(xy 429.218425 -16.594188) (xy 429.272373 -16.586432) (xy 429.326875 -16.586432) (xy 429.380823 -16.594188)
			(xy 429.433118 -16.609543) (xy 429.482695 -16.632185) (xy 429.528545 -16.661651) (xy 429.569736 -16.697342)
			(xy 429.605427 -16.738533) (xy 429.634893 -16.784383) (xy 429.657535 -16.83396) (xy 429.67289 -16.886255)
			(xy 429.680646 -16.940203) (xy 429.681132 -16.967454) (xy 429.680555 -16.997759) (xy 429.670989 -17.057608)
			(xy 429.662082 -17.08658) (xy 429.658327 -17.09977) (xy 429.65704 -17.127146) (xy 429.663092 -17.153875)
			(xy 429.676046 -17.178027) (xy 429.694965 -17.197856) (xy 429.718483 -17.211928) (xy 429.744899 -17.219228)
			(xy 429.758602 -17.219676) (xy 430.09947 -17.219676) (xy 430.113177 -17.219246) (xy 430.139597 -17.211933)
			(xy 430.163118 -17.197852) (xy 430.182044 -17.17802) (xy 430.195009 -17.153867) (xy 430.20108 -17.127134)
			(xy 430.199817 -17.099749) (xy 430.19599 -17.08658) (xy 430.18709 -17.057607) (xy 430.177523 -16.997758)
			(xy 430.17694 -16.967454) (xy 430.177426 -16.940203) (xy 430.185182 -16.886255) (xy 430.200537 -16.83396)
			(xy 430.223179 -16.784383) (xy 430.252645 -16.738533) (xy 430.288336 -16.697342) (xy 430.329527 -16.661651)
			(xy 430.375377 -16.632185) (xy 430.424954 -16.609543) (xy 430.477249 -16.594188) (xy 430.531197 -16.586432)
			(xy 430.585699 -16.586432) (xy 430.639647 -16.594188) (xy 430.691942 -16.609543) (xy 430.741519 -16.632185)
			(xy 430.787369 -16.661651) (xy 430.82856 -16.697342) (xy 430.864251 -16.738533) (xy 430.893717 -16.784383)
			(xy 430.916359 -16.83396) (xy 430.931714 -16.886255) (xy 430.93947 -16.940203) (xy 430.939956 -16.967454)
			(xy 430.939352 -16.998299) (xy 430.929398 -17.059181) (xy 430.920144 -17.088612) (xy 430.915875 -17.10253)
			(xy 430.914744 -17.131612) (xy 430.921863 -17.159832) (xy 430.936655 -17.184898) (xy 430.957917 -17.204772)
			(xy 430.983922 -17.21784) (xy 431.012558 -17.223041) (xy 431.027078 -17.221962) (xy 431.036893 -17.22101)
			(xy 431.056588 -17.219995) (xy 431.066448 -17.21993) (xy 431.0937 -17.220343) (xy 431.147648 -17.228106)
			(xy 431.199942 -17.243467) (xy 431.249518 -17.266113) (xy 431.283177 -17.287748) (xy 435.704232 -17.287748)
			(xy 435.708303 -17.232126) (xy 435.720429 -17.177689) (xy 435.740352 -17.125598) (xy 435.767648 -17.076963)
			(xy 435.801734 -17.03282) (xy 435.841883 -16.994111) (xy 435.887241 -16.96166) (xy 435.936841 -16.936159)
			(xy 435.989625 -16.918152) (xy 436.044468 -16.908022) (xy 436.100202 -16.905985) (xy 436.155639 -16.912085)
			(xy 436.209596 -16.926191) (xy 436.260925 -16.948003) (xy 436.308531 -16.977057) (xy 436.351399 -17.012732)
			(xy 436.388616 -17.054269) (xy 436.419389 -17.100782) (xy 436.443061 -17.151279) (xy 436.459129 -17.204686)
			(xy 436.467249 -17.259862) (xy 436.467758 -17.287748) (xy 436.725312 -17.287748) (xy 436.729383 -17.232126)
			(xy 436.741509 -17.177689) (xy 436.761432 -17.125598) (xy 436.788728 -17.076963) (xy 436.822814 -17.03282)
			(xy 436.862963 -16.994111) (xy 436.908321 -16.96166) (xy 436.957921 -16.936159) (xy 437.010705 -16.918152)
			(xy 437.065548 -16.908022) (xy 437.121282 -16.905985) (xy 437.176719 -16.912085) (xy 437.230676 -16.926191)
			(xy 437.282005 -16.948003) (xy 437.329611 -16.977057) (xy 437.372479 -17.012732) (xy 437.409696 -17.054269)
			(xy 437.440469 -17.100782) (xy 437.464141 -17.151279) (xy 437.480209 -17.204686) (xy 437.488329 -17.259862)
			(xy 437.488374 -17.262348) (xy 437.849262 -17.262348) (xy 437.853333 -17.206726) (xy 437.865459 -17.152289)
			(xy 437.885382 -17.100198) (xy 437.912678 -17.051563) (xy 437.946764 -17.00742) (xy 437.986913 -16.968711)
			(xy 438.032271 -16.93626) (xy 438.081871 -16.910759) (xy 438.134655 -16.892752) (xy 438.189498 -16.882622)
			(xy 438.245232 -16.880585) (xy 438.300669 -16.886685) (xy 438.354626 -16.900791) (xy 438.405955 -16.922603)
			(xy 438.453561 -16.951657) (xy 438.496429 -16.987332) (xy 438.533646 -17.028869) (xy 438.564419 -17.075382)
			(xy 438.588091 -17.125879) (xy 438.604159 -17.179286) (xy 438.612279 -17.234462) (xy 438.612788 -17.262348)
			(xy 438.612279 -17.290234) (xy 438.604159 -17.34541) (xy 438.588091 -17.398817) (xy 438.564419 -17.449314)
			(xy 438.533646 -17.495827) (xy 438.496429 -17.537364) (xy 438.453561 -17.573039) (xy 438.405955 -17.602093)
			(xy 438.354626 -17.623905) (xy 438.300669 -17.638011) (xy 438.245232 -17.644111) (xy 438.189498 -17.642074)
			(xy 438.134655 -17.631944) (xy 438.081871 -17.613937) (xy 438.032271 -17.588436) (xy 437.986913 -17.555985)
			(xy 437.946764 -17.517276) (xy 437.912678 -17.473133) (xy 437.885382 -17.424498) (xy 437.865459 -17.372407)
			(xy 437.853333 -17.31797) (xy 437.849262 -17.262348) (xy 437.488374 -17.262348) (xy 437.488838 -17.287748)
			(xy 437.488329 -17.315634) (xy 437.480209 -17.37081) (xy 437.464141 -17.424217) (xy 437.440469 -17.474714)
			(xy 437.409696 -17.521227) (xy 437.372479 -17.562764) (xy 437.329611 -17.598439) (xy 437.282005 -17.627493)
			(xy 437.230676 -17.649305) (xy 437.176719 -17.663411) (xy 437.121282 -17.669511) (xy 437.065548 -17.667474)
			(xy 437.010705 -17.657344) (xy 436.957921 -17.639337) (xy 436.908321 -17.613836) (xy 436.862963 -17.581385)
			(xy 436.822814 -17.542676) (xy 436.788728 -17.498533) (xy 436.761432 -17.449898) (xy 436.741509 -17.397807)
			(xy 436.729383 -17.34337) (xy 436.725312 -17.287748) (xy 436.467758 -17.287748) (xy 436.467249 -17.315634)
			(xy 436.459129 -17.37081) (xy 436.443061 -17.424217) (xy 436.419389 -17.474714) (xy 436.388616 -17.521227)
			(xy 436.351399 -17.562764) (xy 436.308531 -17.598439) (xy 436.260925 -17.627493) (xy 436.209596 -17.649305)
			(xy 436.155639 -17.663411) (xy 436.100202 -17.669511) (xy 436.044468 -17.667474) (xy 435.989625 -17.657344)
			(xy 435.936841 -17.639337) (xy 435.887241 -17.613836) (xy 435.841883 -17.581385) (xy 435.801734 -17.542676)
			(xy 435.767648 -17.498533) (xy 435.740352 -17.449898) (xy 435.720429 -17.397807) (xy 435.708303 -17.34337)
			(xy 435.704232 -17.287748) (xy 431.283177 -17.287748) (xy 431.295367 -17.295583) (xy 431.336555 -17.331279)
			(xy 431.372245 -17.372472) (xy 431.40171 -17.418324) (xy 431.42435 -17.467903) (xy 431.439704 -17.520199)
			(xy 431.44746 -17.574148) (xy 431.44746 -17.628652) (xy 431.439704 -17.682601) (xy 431.42435 -17.734897)
			(xy 431.40171 -17.784476) (xy 431.372245 -17.830328) (xy 431.336555 -17.871521) (xy 431.295367 -17.907217)
			(xy 431.249518 -17.936687) (xy 431.199942 -17.959333) (xy 431.147648 -17.974694) (xy 431.0937 -17.982457)
			(xy 431.066448 -17.982946) (xy 431.056587 -17.982884) (xy 431.036892 -17.981868) (xy 431.027078 -17.980914)
			(xy 431.012578 -17.979847) (xy 430.983994 -17.985107) (xy 430.958044 -17.998199) (xy 430.936828 -18.018064)
			(xy 430.922059 -18.043097) (xy 430.914932 -18.071274) (xy 430.916023 -18.100319) (xy 430.920144 -18.114264)
			(xy 430.929396 -18.143694) (xy 430.939345 -18.204577) (xy 430.939956 -18.235422) (xy 430.93947 -18.262673)
			(xy 430.931714 -18.316621) (xy 430.916359 -18.368916) (xy 430.893717 -18.418493) (xy 430.864251 -18.464343)
			(xy 430.82856 -18.505534) (xy 430.787369 -18.541225) (xy 430.741519 -18.570691) (xy 430.691942 -18.593333)
			(xy 430.639647 -18.608688) (xy 430.585699 -18.616444) (xy 430.531197 -18.616444) (xy 430.477249 -18.608688)
			(xy 430.424954 -18.593333) (xy 430.375377 -18.570691) (xy 430.329527 -18.541225) (xy 430.288336 -18.505534)
			(xy 430.252645 -18.464343) (xy 430.223179 -18.418493) (xy 430.200537 -18.368916) (xy 430.185182 -18.316621)
			(xy 430.177426 -18.262673) (xy 430.17694 -18.235422) (xy 430.177508 -18.205117) (xy 430.18708 -18.145267)
			(xy 430.19599 -18.116296) (xy 430.1998 -18.10312) (xy 430.201082 -18.075735) (xy 430.195023 -18.048998)
			(xy 430.182061 -18.024842) (xy 430.163132 -18.005011) (xy 430.139604 -17.99094) (xy 430.113178 -17.983644)
			(xy 430.09947 -17.9832) (xy 429.758602 -17.9832) (xy 429.744897 -17.983638) (xy 429.718482 -17.990955)
			(xy 429.694965 -18.005037) (xy 429.676042 -18.024867) (xy 429.663076 -18.049017) (xy 429.657003 -18.075746)
			(xy 429.658259 -18.103127) (xy 429.662082 -18.116296) (xy 429.670976 -18.145271) (xy 429.680547 -18.205118)
			(xy 429.681132 -18.235422) (xy 429.680646 -18.262673) (xy 429.67289 -18.316621) (xy 429.657535 -18.368916)
			(xy 429.634893 -18.418493) (xy 429.605427 -18.464343) (xy 429.569736 -18.505534) (xy 429.528545 -18.541225)
			(xy 429.482695 -18.570691) (xy 429.433118 -18.593333) (xy 429.380823 -18.608688) (xy 429.326875 -18.616444)
			(xy 429.272373 -18.616444) (xy 429.218425 -18.608688) (xy 429.16613 -18.593333) (xy 429.116553 -18.570691)
			(xy 429.070703 -18.541225) (xy 429.029512 -18.505534) (xy 428.993821 -18.464343) (xy 428.964355 -18.418493)
			(xy 428.941713 -18.368916) (xy 428.926358 -18.316621) (xy 428.918602 -18.262673) (xy 428.918116 -18.235422)
			(xy 428.918711 -18.204576) (xy 428.928671 -18.143694) (xy 428.937928 -18.114264) (xy 428.942147 -18.100337)
			(xy 428.94327 -18.071266) (xy 428.936151 -18.043059) (xy 428.921367 -18.018003) (xy 428.900118 -17.998133)
			(xy 428.874129 -17.98506) (xy 428.845508 -17.979846) (xy 428.830994 -17.980914) (xy 428.82118 -17.981868)
			(xy 428.801485 -17.982882) (xy 428.791624 -17.982946) (xy 428.764373 -17.982408) (xy 428.710425 -17.974655)
			(xy 428.658129 -17.959303) (xy 428.608551 -17.936664) (xy 428.562699 -17.907199) (xy 428.521508 -17.871509)
			(xy 428.485815 -17.83032) (xy 428.456348 -17.78447) (xy 428.433706 -17.734893) (xy 428.41835 -17.682599)
			(xy 428.410593 -17.628651) (xy 425.82546 -17.628651) (xy 425.82546 -17.628653) (xy 425.817703 -17.682605)
			(xy 425.802347 -17.734904) (xy 425.779705 -17.784486) (xy 425.750237 -17.83034) (xy 425.714543 -17.871534)
			(xy 425.67335 -17.907229) (xy 425.627496 -17.936699) (xy 425.577916 -17.959343) (xy 425.525617 -17.974701)
			(xy 425.471665 -17.982459) (xy 425.444412 -17.982946) (xy 425.434551 -17.982887) (xy 425.414856 -17.981869)
			(xy 425.405042 -17.980914) (xy 425.390539 -17.979906) (xy 425.361957 -17.985151) (xy 425.336007 -17.99823)
			(xy 425.314789 -18.018085) (xy 425.30002 -18.043111) (xy 425.292893 -18.071283) (xy 425.293985 -18.100322)
			(xy 425.298108 -18.114264) (xy 425.307359 -18.143695) (xy 425.317308 -18.204577) (xy 425.31792 -18.235422)
			(xy 425.317434 -18.262673) (xy 425.309678 -18.316621) (xy 425.294323 -18.368916) (xy 425.271681 -18.418493)
			(xy 425.242215 -18.464343) (xy 425.206524 -18.505534) (xy 425.165333 -18.541225) (xy 425.119483 -18.570691)
			(xy 425.069906 -18.593333) (xy 425.017611 -18.608688) (xy 424.963663 -18.616444) (xy 424.909161 -18.616444)
			(xy 424.855213 -18.608688) (xy 424.802918 -18.593333) (xy 424.753341 -18.570691) (xy 424.707491 -18.541225)
			(xy 424.6663 -18.505534) (xy 424.630609 -18.464343) (xy 424.601143 -18.418493) (xy 424.578501 -18.368916)
			(xy 424.563146 -18.316621) (xy 424.55539 -18.262673) (xy 424.554904 -18.235422) (xy 424.555473 -18.205117)
			(xy 424.565044 -18.145268) (xy 424.573954 -18.116296) (xy 424.577798 -18.103128) (xy 424.579082 -18.075736)
			(xy 424.573021 -18.048993) (xy 424.560054 -18.024832) (xy 424.541117 -18.004999) (xy 424.51758 -17.990929)
			(xy 424.491145 -17.98364) (xy 424.477434 -17.9832) (xy 424.136566 -17.9832) (xy 424.12286 -17.983608)
			(xy 424.096444 -17.990934) (xy 424.072928 -18.005022) (xy 424.054006 -18.024857) (xy 424.041042 -18.04901)
			(xy 424.034968 -18.075742) (xy 424.036223 -18.103126) (xy 424.040046 -18.116296) (xy 424.048939 -18.145272)
			(xy 424.058511 -18.205118) (xy 424.059096 -18.235422) (xy 424.05861 -18.262673) (xy 424.050854 -18.316621)
			(xy 424.035499 -18.368916) (xy 424.012857 -18.418493) (xy 423.983391 -18.464343) (xy 423.9477 -18.505534)
			(xy 423.906509 -18.541225) (xy 423.860659 -18.570691) (xy 423.811082 -18.593333) (xy 423.758787 -18.608688)
			(xy 423.704839 -18.616444) (xy 423.650337 -18.616444) (xy 423.596389 -18.608688) (xy 423.544094 -18.593333)
			(xy 423.494517 -18.570691) (xy 423.448667 -18.541225) (xy 423.407476 -18.505534) (xy 423.371785 -18.464343)
			(xy 423.342319 -18.418493) (xy 423.319677 -18.368916) (xy 423.304322 -18.316621) (xy 423.296566 -18.262673)
			(xy 423.29608 -18.235422) (xy 423.296677 -18.204576) (xy 423.306636 -18.143694) (xy 423.315892 -18.114264)
			(xy 423.32015 -18.100345) (xy 423.321274 -18.071267) (xy 423.314152 -18.043052) (xy 423.299362 -18.017991)
			(xy 423.278105 -17.998119) (xy 423.252106 -17.985048) (xy 423.223476 -17.979841) (xy 423.208958 -17.980914)
			(xy 423.199143 -17.981863) (xy 423.179448 -17.982881) (xy 423.169588 -17.982946) (xy 423.14234 -17.982383)
			(xy 423.088399 -17.974626) (xy 423.036111 -17.959271) (xy 422.98654 -17.936632) (xy 422.940696 -17.907168)
			(xy 422.899511 -17.87148) (xy 422.863825 -17.830294) (xy 422.834363 -17.784449) (xy 422.811725 -17.734878)
			(xy 422.796372 -17.682589) (xy 422.788616 -17.628648) (xy 420.237384 -17.628648) (xy 420.229628 -17.682589)
			(xy 420.214275 -17.734878) (xy 420.191637 -17.784449) (xy 420.162175 -17.830294) (xy 420.126489 -17.87148)
			(xy 420.085304 -17.907168) (xy 420.03946 -17.936632) (xy 419.989889 -17.959271) (xy 419.937601 -17.974626)
			(xy 419.88366 -17.982383) (xy 419.856412 -17.982946) (xy 419.846552 -17.982881) (xy 419.826857 -17.981863)
			(xy 419.817042 -17.980914) (xy 419.802524 -17.979841) (xy 419.773894 -17.985048) (xy 419.747895 -17.998119)
			(xy 419.726638 -18.017991) (xy 419.711848 -18.043052) (xy 419.704726 -18.071267) (xy 419.70585 -18.100345)
			(xy 419.710108 -18.114264) (xy 419.719364 -18.143694) (xy 419.729323 -18.204576) (xy 419.72992 -18.235422)
			(xy 419.729434 -18.262673) (xy 419.721678 -18.316621) (xy 419.706323 -18.368916) (xy 419.683681 -18.418493)
			(xy 419.654215 -18.464343) (xy 419.618524 -18.505534) (xy 419.577333 -18.541225) (xy 419.531483 -18.570691)
			(xy 419.481906 -18.593333) (xy 419.429611 -18.608688) (xy 419.375663 -18.616444) (xy 419.321161 -18.616444)
			(xy 419.267213 -18.608688) (xy 419.214918 -18.593333) (xy 419.165341 -18.570691) (xy 419.119491 -18.541225)
			(xy 419.0783 -18.505534) (xy 419.042609 -18.464343) (xy 419.013143 -18.418493) (xy 418.990501 -18.368916)
			(xy 418.975146 -18.316621) (xy 418.96739 -18.262673) (xy 418.966904 -18.235422) (xy 418.967489 -18.205118)
			(xy 418.977061 -18.145272) (xy 418.985954 -18.116296) (xy 418.989777 -18.103126) (xy 418.991032 -18.075742)
			(xy 418.984958 -18.04901) (xy 418.971994 -18.024857) (xy 418.953072 -18.005022) (xy 418.929556 -17.990934)
			(xy 418.90314 -17.983608) (xy 418.889434 -17.9832) (xy 418.548566 -17.9832) (xy 418.534855 -17.98364)
			(xy 418.50842 -17.990929) (xy 418.484883 -18.004999) (xy 418.465946 -18.024832) (xy 418.452979 -18.048993)
			(xy 418.446918 -18.075736) (xy 418.448202 -18.103128) (xy 418.452046 -18.116296) (xy 418.460956 -18.145268)
			(xy 418.470527 -18.205117) (xy 418.471096 -18.235422) (xy 418.47061 -18.262673) (xy 418.462854 -18.316621)
			(xy 418.447499 -18.368916) (xy 418.424857 -18.418493) (xy 418.395391 -18.464343) (xy 418.3597 -18.505534)
			(xy 418.318509 -18.541225) (xy 418.272659 -18.570691) (xy 418.223082 -18.593333) (xy 418.170787 -18.608688)
			(xy 418.116839 -18.616444) (xy 418.062337 -18.616444) (xy 418.008389 -18.608688) (xy 417.956094 -18.593333)
			(xy 417.906517 -18.570691) (xy 417.860667 -18.541225) (xy 417.819476 -18.505534) (xy 417.783785 -18.464343)
			(xy 417.754319 -18.418493) (xy 417.731677 -18.368916) (xy 417.716322 -18.316621) (xy 417.708566 -18.262673)
			(xy 417.70808 -18.235422) (xy 417.708692 -18.204577) (xy 417.718641 -18.143695) (xy 417.727892 -18.114264)
			(xy 417.732015 -18.100322) (xy 417.733107 -18.071283) (xy 417.72598 -18.043111) (xy 417.711211 -18.018085)
			(xy 417.689993 -17.99823) (xy 417.664043 -17.985151) (xy 417.635461 -17.979906) (xy 417.620958 -17.980914)
			(xy 417.611144 -17.981869) (xy 417.591449 -17.982887) (xy 417.581588 -17.982946) (xy 417.553543 -17.982477)
			(xy 417.498051 -17.974311) (xy 417.444356 -17.958098) (xy 417.393618 -17.93419) (xy 417.346933 -17.903102)
			(xy 417.32581 -17.884648) (xy 417.314605 -17.875184) (xy 417.288161 -17.862524) (xy 417.259211 -17.857891)
			(xy 417.230137 -17.861666) (xy 417.20333 -17.873539) (xy 417.180996 -17.892532) (xy 417.164971 -17.917084)
			(xy 417.156575 -17.945174) (xy 417.156138 -17.959832) (xy 417.156138 -18.753836) (xy 417.18992 -18.765774)
			(xy 417.21578 -18.775476) (xy 417.264618 -18.80127) (xy 417.309228 -18.833834) (xy 417.348677 -18.872489)
			(xy 417.382143 -18.916427) (xy 417.408925 -18.96473) (xy 417.428465 -19.016389) (xy 417.440353 -19.070326)
			(xy 417.444343 -19.125413) (xy 417.442369 -19.152648) (xy 419.994616 -19.152648) (xy 419.994616 -19.098152)
			(xy 420.002372 -19.044211) (xy 420.017725 -18.991922) (xy 420.040363 -18.942351) (xy 420.069825 -18.896506)
			(xy 420.105511 -18.85532) (xy 420.146696 -18.819632) (xy 420.19254 -18.790168) (xy 420.242111 -18.767529)
			(xy 420.294399 -18.752174) (xy 420.34834 -18.744417) (xy 420.375588 -18.74393) (xy 420.385449 -18.74399)
			(xy 420.405144 -18.745007) (xy 420.414958 -18.745962) (xy 420.429463 -18.74687) (xy 420.458027 -18.74163)
			(xy 420.483962 -18.728562) (xy 420.505172 -18.708725) (xy 420.519942 -18.68372) (xy 420.527077 -18.655569)
			(xy 420.526003 -18.626548) (xy 420.521892 -18.612612) (xy 420.512658 -18.583176) (xy 420.502698 -18.522298)
			(xy 420.50208 -18.491454) (xy 420.502566 -18.464203) (xy 420.510322 -18.410255) (xy 420.525677 -18.35796)
			(xy 420.548319 -18.308383) (xy 420.577785 -18.262533) (xy 420.613476 -18.221342) (xy 420.654667 -18.185651)
			(xy 420.700517 -18.156185) (xy 420.750094 -18.133543) (xy 420.802389 -18.118188) (xy 420.856337 -18.110432)
			(xy 420.910839 -18.110432) (xy 420.964787 -18.118188) (xy 421.017082 -18.133543) (xy 421.066659 -18.156185)
			(xy 421.112509 -18.185651) (xy 421.1537 -18.221342) (xy 421.189391 -18.262533) (xy 421.218857 -18.308383)
			(xy 421.241499 -18.35796) (xy 421.256854 -18.410255) (xy 421.26461 -18.464203) (xy 421.265096 -18.491454)
			(xy 421.264521 -18.521759) (xy 421.254954 -18.581608) (xy 421.246046 -18.61058) (xy 421.242229 -18.623756)
			(xy 421.24094 -18.651144) (xy 421.246996 -18.677885) (xy 421.259959 -18.702045) (xy 421.278892 -18.721877)
			(xy 421.302425 -18.735947) (xy 421.328857 -18.743236) (xy 421.342566 -18.743676) (xy 421.683434 -18.743676)
			(xy 421.697143 -18.743299) (xy 421.723563 -18.735971) (xy 421.747083 -18.721879) (xy 421.766006 -18.702038)
			(xy 421.77897 -18.677879) (xy 421.785041 -18.651141) (xy 421.78378 -18.623752) (xy 421.779954 -18.61058)
			(xy 421.771056 -18.581606) (xy 421.761487 -18.521758) (xy 421.760904 -18.491454) (xy 421.76139 -18.464203)
			(xy 421.769146 -18.410255) (xy 421.784501 -18.35796) (xy 421.807143 -18.308383) (xy 421.836609 -18.262533)
			(xy 421.8723 -18.221342) (xy 421.913491 -18.185651) (xy 421.959341 -18.156185) (xy 422.008918 -18.133543)
			(xy 422.061213 -18.118188) (xy 422.115161 -18.110432) (xy 422.169663 -18.110432) (xy 422.223611 -18.118188)
			(xy 422.275906 -18.133543) (xy 422.325483 -18.156185) (xy 422.371333 -18.185651) (xy 422.412524 -18.221342)
			(xy 422.448215 -18.262533) (xy 422.477681 -18.308383) (xy 422.500323 -18.35796) (xy 422.515678 -18.410255)
			(xy 422.523434 -18.464203) (xy 422.52392 -18.491454) (xy 422.523318 -18.522299) (xy 422.513363 -18.583182)
			(xy 422.504108 -18.612612) (xy 422.499878 -18.626538) (xy 422.498748 -18.655613) (xy 422.505865 -18.683826)
			(xy 422.52065 -18.708886) (xy 422.541903 -18.728758) (xy 422.567899 -18.741828) (xy 422.596526 -18.747036)
			(xy 422.611042 -18.745962) (xy 422.620857 -18.745013) (xy 422.640552 -18.743995) (xy 422.650412 -18.74393)
			(xy 422.677665 -18.744341) (xy 422.731617 -18.752099) (xy 422.783916 -18.767457) (xy 422.833496 -18.790101)
			(xy 422.87935 -18.819571) (xy 422.920543 -18.855266) (xy 422.956237 -18.89646) (xy 422.985705 -18.942314)
			(xy 423.008347 -18.991896) (xy 423.023703 -19.044195) (xy 423.03146 -19.098147) (xy 423.03146 -19.152651)
			(xy 425.616593 -19.152651) (xy 425.616593 -19.098149) (xy 425.62435 -19.044201) (xy 425.639706 -18.991907)
			(xy 425.662348 -18.94233) (xy 425.691815 -18.89648) (xy 425.727508 -18.855291) (xy 425.768699 -18.819601)
			(xy 425.814551 -18.790136) (xy 425.864129 -18.767497) (xy 425.916425 -18.752145) (xy 425.970373 -18.744392)
			(xy 425.997624 -18.74393) (xy 426.007485 -18.743995) (xy 426.027179 -18.745008) (xy 426.036994 -18.745962)
			(xy 426.051496 -18.746903) (xy 426.080062 -18.741654) (xy 426.105997 -18.728579) (xy 426.127206 -18.708736)
			(xy 426.141975 -18.683728) (xy 426.149111 -18.655574) (xy 426.148038 -18.62655) (xy 426.143928 -18.612612)
			(xy 426.134695 -18.583176) (xy 426.124734 -18.522298) (xy 426.124116 -18.491454) (xy 426.124602 -18.464203)
			(xy 426.132358 -18.410255) (xy 426.147713 -18.35796) (xy 426.170355 -18.308383) (xy 426.199821 -18.262533)
			(xy 426.235512 -18.221342) (xy 426.276703 -18.185651) (xy 426.322553 -18.156185) (xy 426.37213 -18.133543)
			(xy 426.424425 -18.118188) (xy 426.478373 -18.110432) (xy 426.532875 -18.110432) (xy 426.586823 -18.118188)
			(xy 426.639118 -18.133543) (xy 426.688695 -18.156185) (xy 426.734545 -18.185651) (xy 426.775736 -18.221342)
			(xy 426.811427 -18.262533) (xy 426.840893 -18.308383) (xy 426.863535 -18.35796) (xy 426.87889 -18.410255)
			(xy 426.886646 -18.464203) (xy 426.887132 -18.491454) (xy 426.886555 -18.521759) (xy 426.876989 -18.581608)
			(xy 426.868082 -18.61058) (xy 426.864327 -18.62377) (xy 426.86304 -18.651146) (xy 426.869092 -18.677875)
			(xy 426.882046 -18.702027) (xy 426.900965 -18.721856) (xy 426.924483 -18.735928) (xy 426.950899 -18.743228)
			(xy 426.964602 -18.743676) (xy 427.30547 -18.743676) (xy 427.319177 -18.743246) (xy 427.345597 -18.735933)
			(xy 427.369118 -18.721852) (xy 427.388044 -18.70202) (xy 427.401009 -18.677867) (xy 427.40708 -18.651134)
			(xy 427.405817 -18.623749) (xy 427.40199 -18.61058) (xy 427.39309 -18.581607) (xy 427.383523 -18.521758)
			(xy 427.38294 -18.491454) (xy 427.383426 -18.464203) (xy 427.391182 -18.410255) (xy 427.406537 -18.35796)
			(xy 427.429179 -18.308383) (xy 427.458645 -18.262533) (xy 427.494336 -18.221342) (xy 427.535527 -18.185651)
			(xy 427.581377 -18.156185) (xy 427.630954 -18.133543) (xy 427.683249 -18.118188) (xy 427.737197 -18.110432)
			(xy 427.791699 -18.110432) (xy 427.845647 -18.118188) (xy 427.897942 -18.133543) (xy 427.947519 -18.156185)
			(xy 427.993369 -18.185651) (xy 428.03456 -18.221342) (xy 428.070251 -18.262533) (xy 428.099717 -18.308383)
			(xy 428.122359 -18.35796) (xy 428.137714 -18.410255) (xy 428.14547 -18.464203) (xy 428.145956 -18.491454)
			(xy 428.145352 -18.522299) (xy 428.135398 -18.583181) (xy 428.126144 -18.612612) (xy 428.121875 -18.62653)
			(xy 428.120744 -18.655612) (xy 428.127863 -18.683832) (xy 428.142655 -18.708898) (xy 428.163917 -18.728772)
			(xy 428.189922 -18.74184) (xy 428.218558 -18.747041) (xy 428.233078 -18.745962) (xy 428.242893 -18.74501)
			(xy 428.262588 -18.743995) (xy 428.272448 -18.74393) (xy 428.2997 -18.744343) (xy 428.353648 -18.752106)
			(xy 428.405942 -18.767467) (xy 428.455518 -18.790113) (xy 428.501367 -18.819583) (xy 428.542555 -18.855279)
			(xy 428.578245 -18.896472) (xy 428.60771 -18.942324) (xy 428.63035 -18.991903) (xy 428.645704 -19.044199)
			(xy 428.65346 -19.098148) (xy 428.65346 -19.152651) (xy 431.204593 -19.152651) (xy 431.204593 -19.098149)
			(xy 431.21235 -19.044201) (xy 431.227706 -18.991907) (xy 431.250348 -18.94233) (xy 431.279815 -18.89648)
			(xy 431.315508 -18.855291) (xy 431.356699 -18.819601) (xy 431.402551 -18.790136) (xy 431.452129 -18.767497)
			(xy 431.504425 -18.752145) (xy 431.558373 -18.744392) (xy 431.585624 -18.74393) (xy 431.595485 -18.743995)
			(xy 431.615179 -18.745008) (xy 431.624994 -18.745962) (xy 431.639496 -18.746903) (xy 431.668062 -18.741654)
			(xy 431.693997 -18.728579) (xy 431.715206 -18.708736) (xy 431.729975 -18.683728) (xy 431.737111 -18.655574)
			(xy 431.736038 -18.62655) (xy 431.731928 -18.612612) (xy 431.722695 -18.583176) (xy 431.712734 -18.522298)
			(xy 431.712116 -18.491454) (xy 431.712602 -18.464203) (xy 431.720358 -18.410255) (xy 431.735713 -18.35796)
			(xy 431.758355 -18.308383) (xy 431.787821 -18.262533) (xy 431.823512 -18.221342) (xy 431.864703 -18.185651)
			(xy 431.910553 -18.156185) (xy 431.96013 -18.133543) (xy 432.012425 -18.118188) (xy 432.066373 -18.110432)
			(xy 432.120875 -18.110432) (xy 432.174823 -18.118188) (xy 432.227118 -18.133543) (xy 432.276695 -18.156185)
			(xy 432.322545 -18.185651) (xy 432.363736 -18.221342) (xy 432.399427 -18.262533) (xy 432.428893 -18.308383)
			(xy 432.451535 -18.35796) (xy 432.46689 -18.410255) (xy 432.474646 -18.464203) (xy 432.475132 -18.491454)
			(xy 432.474555 -18.521759) (xy 432.464989 -18.581608) (xy 432.456082 -18.61058) (xy 432.452327 -18.62377)
			(xy 432.45104 -18.651146) (xy 432.457092 -18.677875) (xy 432.470046 -18.702027) (xy 432.488965 -18.721856)
			(xy 432.512483 -18.735928) (xy 432.538899 -18.743228) (xy 432.552602 -18.743676) (xy 432.89347 -18.743676)
			(xy 432.907177 -18.743246) (xy 432.933597 -18.735933) (xy 432.957118 -18.721852) (xy 432.976044 -18.70202)
			(xy 432.989009 -18.677867) (xy 432.99508 -18.651134) (xy 432.993817 -18.623749) (xy 432.98999 -18.61058)
			(xy 432.98109 -18.581607) (xy 432.971523 -18.521758) (xy 432.97094 -18.491454) (xy 432.971426 -18.464203)
			(xy 432.979182 -18.410255) (xy 432.994537 -18.35796) (xy 433.017179 -18.308383) (xy 433.046645 -18.262533)
			(xy 433.082336 -18.221342) (xy 433.123527 -18.185651) (xy 433.169377 -18.156185) (xy 433.218954 -18.133543)
			(xy 433.271249 -18.118188) (xy 433.325197 -18.110432) (xy 433.379699 -18.110432) (xy 433.433647 -18.118188)
			(xy 433.485942 -18.133543) (xy 433.535519 -18.156185) (xy 433.581369 -18.185651) (xy 433.62256 -18.221342)
			(xy 433.658251 -18.262533) (xy 433.687717 -18.308383) (xy 433.710359 -18.35796) (xy 433.725714 -18.410255)
			(xy 433.73347 -18.464203) (xy 433.733956 -18.491454) (xy 433.733352 -18.522299) (xy 433.723398 -18.583181)
			(xy 433.714144 -18.612612) (xy 433.709875 -18.62653) (xy 433.708744 -18.655612) (xy 433.715863 -18.683832)
			(xy 433.730655 -18.708898) (xy 433.751917 -18.728772) (xy 433.777922 -18.74184) (xy 433.806558 -18.747041)
			(xy 433.821078 -18.745962) (xy 433.830893 -18.74501) (xy 433.850588 -18.743995) (xy 433.860448 -18.74393)
			(xy 433.8877 -18.744343) (xy 433.941648 -18.752106) (xy 433.993942 -18.767467) (xy 434.043518 -18.790113)
			(xy 434.089367 -18.819583) (xy 434.130555 -18.855279) (xy 434.166245 -18.896472) (xy 434.19571 -18.942324)
			(xy 434.21835 -18.991903) (xy 434.233704 -19.044199) (xy 434.24146 -19.098148) (xy 434.24146 -19.152652)
			(xy 434.233704 -19.206601) (xy 434.21835 -19.258897) (xy 434.19571 -19.308476) (xy 434.166245 -19.354328)
			(xy 434.130555 -19.395521) (xy 434.089367 -19.431217) (xy 434.043518 -19.460687) (xy 433.993942 -19.483333)
			(xy 433.941648 -19.498694) (xy 433.8877 -19.506457) (xy 433.860448 -19.506946) (xy 433.850587 -19.506884)
			(xy 433.830892 -19.505868) (xy 433.821078 -19.504914) (xy 433.806578 -19.503847) (xy 433.777994 -19.509107)
			(xy 433.752044 -19.522199) (xy 433.730828 -19.542064) (xy 433.716059 -19.567097) (xy 433.708932 -19.595274)
			(xy 433.710023 -19.624319) (xy 433.714144 -19.638264) (xy 433.723396 -19.667694) (xy 433.733345 -19.728577)
			(xy 433.733956 -19.759422) (xy 433.73347 -19.786673) (xy 433.725714 -19.840621) (xy 433.710359 -19.892916)
			(xy 433.687717 -19.942493) (xy 433.658251 -19.988343) (xy 433.62256 -20.029534) (xy 433.581369 -20.065225)
			(xy 433.535519 -20.094691) (xy 433.485942 -20.117333) (xy 433.433647 -20.132688) (xy 433.379699 -20.140444)
			(xy 433.325197 -20.140444) (xy 433.271249 -20.132688) (xy 433.218954 -20.117333) (xy 433.169377 -20.094691)
			(xy 433.123527 -20.065225) (xy 433.082336 -20.029534) (xy 433.046645 -19.988343) (xy 433.017179 -19.942493)
			(xy 432.994537 -19.892916) (xy 432.979182 -19.840621) (xy 432.971426 -19.786673) (xy 432.97094 -19.759422)
			(xy 432.971508 -19.729117) (xy 432.98108 -19.669267) (xy 432.98999 -19.640296) (xy 432.9938 -19.62712)
			(xy 432.995082 -19.599735) (xy 432.989023 -19.572998) (xy 432.976061 -19.548842) (xy 432.957132 -19.529011)
			(xy 432.933604 -19.51494) (xy 432.907178 -19.507644) (xy 432.89347 -19.5072) (xy 432.552602 -19.5072)
			(xy 432.538897 -19.507638) (xy 432.512482 -19.514955) (xy 432.488965 -19.529037) (xy 432.470042 -19.548867)
			(xy 432.457076 -19.573017) (xy 432.451003 -19.599746) (xy 432.452259 -19.627127) (xy 432.456082 -19.640296)
			(xy 432.464976 -19.669271) (xy 432.474547 -19.729118) (xy 432.475132 -19.759422) (xy 432.474646 -19.786673)
			(xy 432.46689 -19.840621) (xy 432.451535 -19.892916) (xy 432.428893 -19.942493) (xy 432.399427 -19.988343)
			(xy 432.363736 -20.029534) (xy 432.322545 -20.065225) (xy 432.276695 -20.094691) (xy 432.227118 -20.117333)
			(xy 432.174823 -20.132688) (xy 432.120875 -20.140444) (xy 432.066373 -20.140444) (xy 432.012425 -20.132688)
			(xy 431.96013 -20.117333) (xy 431.910553 -20.094691) (xy 431.864703 -20.065225) (xy 431.823512 -20.029534)
			(xy 431.787821 -19.988343) (xy 431.758355 -19.942493) (xy 431.735713 -19.892916) (xy 431.720358 -19.840621)
			(xy 431.712602 -19.786673) (xy 431.712116 -19.759422) (xy 431.712711 -19.728576) (xy 431.722671 -19.667694)
			(xy 431.731928 -19.638264) (xy 431.736147 -19.624337) (xy 431.73727 -19.595266) (xy 431.730151 -19.567059)
			(xy 431.715367 -19.542003) (xy 431.694118 -19.522133) (xy 431.668129 -19.50906) (xy 431.639508 -19.503846)
			(xy 431.624994 -19.504914) (xy 431.61518 -19.505868) (xy 431.595485 -19.506882) (xy 431.585624 -19.506946)
			(xy 431.558373 -19.506408) (xy 431.504425 -19.498655) (xy 431.452129 -19.483303) (xy 431.402551 -19.460664)
			(xy 431.356699 -19.431199) (xy 431.315508 -19.395509) (xy 431.279815 -19.35432) (xy 431.250348 -19.30847)
			(xy 431.227706 -19.258893) (xy 431.21235 -19.206599) (xy 431.204593 -19.152651) (xy 428.65346 -19.152651)
			(xy 428.65346 -19.152652) (xy 428.645704 -19.206601) (xy 428.63035 -19.258897) (xy 428.60771 -19.308476)
			(xy 428.578245 -19.354328) (xy 428.542555 -19.395521) (xy 428.501367 -19.431217) (xy 428.455518 -19.460687)
			(xy 428.405942 -19.483333) (xy 428.353648 -19.498694) (xy 428.2997 -19.506457) (xy 428.272448 -19.506946)
			(xy 428.262587 -19.506884) (xy 428.242892 -19.505868) (xy 428.233078 -19.504914) (xy 428.218578 -19.503847)
			(xy 428.189994 -19.509107) (xy 428.164044 -19.522199) (xy 428.142828 -19.542064) (xy 428.128059 -19.567097)
			(xy 428.120932 -19.595274) (xy 428.122023 -19.624319) (xy 428.126144 -19.638264) (xy 428.135396 -19.667694)
			(xy 428.145345 -19.728577) (xy 428.145956 -19.759422) (xy 428.14547 -19.786673) (xy 428.137714 -19.840621)
			(xy 428.122359 -19.892916) (xy 428.099717 -19.942493) (xy 428.070251 -19.988343) (xy 428.03456 -20.029534)
			(xy 427.993369 -20.065225) (xy 427.947519 -20.094691) (xy 427.897942 -20.117333) (xy 427.845647 -20.132688)
			(xy 427.791699 -20.140444) (xy 427.737197 -20.140444) (xy 427.683249 -20.132688) (xy 427.630954 -20.117333)
			(xy 427.581377 -20.094691) (xy 427.535527 -20.065225) (xy 427.494336 -20.029534) (xy 427.458645 -19.988343)
			(xy 427.429179 -19.942493) (xy 427.406537 -19.892916) (xy 427.391182 -19.840621) (xy 427.383426 -19.786673)
			(xy 427.38294 -19.759422) (xy 427.383508 -19.729117) (xy 427.39308 -19.669267) (xy 427.40199 -19.640296)
			(xy 427.4058 -19.62712) (xy 427.407082 -19.599735) (xy 427.401023 -19.572998) (xy 427.388061 -19.548842)
			(xy 427.369132 -19.529011) (xy 427.345604 -19.51494) (xy 427.319178 -19.507644) (xy 427.30547 -19.5072)
			(xy 426.964602 -19.5072) (xy 426.950897 -19.507638) (xy 426.924482 -19.514955) (xy 426.900965 -19.529037)
			(xy 426.882042 -19.548867) (xy 426.869076 -19.573017) (xy 426.863003 -19.599746) (xy 426.864259 -19.627127)
			(xy 426.868082 -19.640296) (xy 426.876976 -19.669271) (xy 426.886547 -19.729118) (xy 426.887132 -19.759422)
			(xy 426.886646 -19.786673) (xy 426.87889 -19.840621) (xy 426.863535 -19.892916) (xy 426.840893 -19.942493)
			(xy 426.811427 -19.988343) (xy 426.775736 -20.029534) (xy 426.734545 -20.065225) (xy 426.688695 -20.094691)
			(xy 426.639118 -20.117333) (xy 426.586823 -20.132688) (xy 426.532875 -20.140444) (xy 426.478373 -20.140444)
			(xy 426.424425 -20.132688) (xy 426.37213 -20.117333) (xy 426.322553 -20.094691) (xy 426.276703 -20.065225)
			(xy 426.235512 -20.029534) (xy 426.199821 -19.988343) (xy 426.170355 -19.942493) (xy 426.147713 -19.892916)
			(xy 426.132358 -19.840621) (xy 426.124602 -19.786673) (xy 426.124116 -19.759422) (xy 426.124711 -19.728576)
			(xy 426.134671 -19.667694) (xy 426.143928 -19.638264) (xy 426.148147 -19.624337) (xy 426.14927 -19.595266)
			(xy 426.142151 -19.567059) (xy 426.127367 -19.542003) (xy 426.106118 -19.522133) (xy 426.080129 -19.50906)
			(xy 426.051508 -19.503846) (xy 426.036994 -19.504914) (xy 426.02718 -19.505868) (xy 426.007485 -19.506882)
			(xy 425.997624 -19.506946) (xy 425.970373 -19.506408) (xy 425.916425 -19.498655) (xy 425.864129 -19.483303)
			(xy 425.814551 -19.460664) (xy 425.768699 -19.431199) (xy 425.727508 -19.395509) (xy 425.691815 -19.35432)
			(xy 425.662348 -19.30847) (xy 425.639706 -19.258893) (xy 425.62435 -19.206599) (xy 425.616593 -19.152651)
			(xy 423.03146 -19.152651) (xy 423.03146 -19.152653) (xy 423.023703 -19.206605) (xy 423.008347 -19.258904)
			(xy 422.985705 -19.308486) (xy 422.956237 -19.35434) (xy 422.920543 -19.395534) (xy 422.87935 -19.431229)
			(xy 422.833496 -19.460699) (xy 422.783916 -19.483343) (xy 422.731617 -19.498701) (xy 422.677665 -19.506459)
			(xy 422.650412 -19.506946) (xy 422.640551 -19.506887) (xy 422.620856 -19.505869) (xy 422.611042 -19.504914)
			(xy 422.596539 -19.503906) (xy 422.567957 -19.509151) (xy 422.542007 -19.52223) (xy 422.520789 -19.542085)
			(xy 422.50602 -19.567111) (xy 422.498893 -19.595283) (xy 422.499985 -19.624322) (xy 422.504108 -19.638264)
			(xy 422.513359 -19.667695) (xy 422.523308 -19.728577) (xy 422.52392 -19.759422) (xy 422.523434 -19.786673)
			(xy 422.515678 -19.840621) (xy 422.500323 -19.892916) (xy 422.477681 -19.942493) (xy 422.448215 -19.988343)
			(xy 422.412524 -20.029534) (xy 422.371333 -20.065225) (xy 422.325483 -20.094691) (xy 422.275906 -20.117333)
			(xy 422.223611 -20.132688) (xy 422.169663 -20.140444) (xy 422.115161 -20.140444) (xy 422.061213 -20.132688)
			(xy 422.008918 -20.117333) (xy 421.959341 -20.094691) (xy 421.913491 -20.065225) (xy 421.8723 -20.029534)
			(xy 421.836609 -19.988343) (xy 421.807143 -19.942493) (xy 421.784501 -19.892916) (xy 421.769146 -19.840621)
			(xy 421.76139 -19.786673) (xy 421.760904 -19.759422) (xy 421.761473 -19.729117) (xy 421.771044 -19.669268)
			(xy 421.779954 -19.640296) (xy 421.783798 -19.627128) (xy 421.785082 -19.599736) (xy 421.779021 -19.572993)
			(xy 421.766054 -19.548832) (xy 421.747117 -19.528999) (xy 421.72358 -19.514929) (xy 421.697145 -19.50764)
			(xy 421.683434 -19.5072) (xy 421.342566 -19.5072) (xy 421.32886 -19.507608) (xy 421.302444 -19.514934)
			(xy 421.278928 -19.529022) (xy 421.260006 -19.548857) (xy 421.247042 -19.57301) (xy 421.240968 -19.599742)
			(xy 421.242223 -19.627126) (xy 421.246046 -19.640296) (xy 421.254939 -19.669272) (xy 421.264511 -19.729118)
			(xy 421.265096 -19.759422) (xy 421.26461 -19.786673) (xy 421.256854 -19.840621) (xy 421.241499 -19.892916)
			(xy 421.218857 -19.942493) (xy 421.189391 -19.988343) (xy 421.1537 -20.029534) (xy 421.112509 -20.065225)
			(xy 421.066659 -20.094691) (xy 421.017082 -20.117333) (xy 420.964787 -20.132688) (xy 420.910839 -20.140444)
			(xy 420.856337 -20.140444) (xy 420.802389 -20.132688) (xy 420.750094 -20.117333) (xy 420.700517 -20.094691)
			(xy 420.654667 -20.065225) (xy 420.613476 -20.029534) (xy 420.577785 -19.988343) (xy 420.548319 -19.942493)
			(xy 420.525677 -19.892916) (xy 420.510322 -19.840621) (xy 420.502566 -19.786673) (xy 420.50208 -19.759422)
			(xy 420.502677 -19.728576) (xy 420.512636 -19.667694) (xy 420.521892 -19.638264) (xy 420.52615 -19.624345)
			(xy 420.527274 -19.595267) (xy 420.520152 -19.567052) (xy 420.505362 -19.541991) (xy 420.484105 -19.522119)
			(xy 420.458106 -19.509048) (xy 420.429476 -19.503841) (xy 420.414958 -19.504914) (xy 420.405143 -19.505863)
			(xy 420.385448 -19.506881) (xy 420.375588 -19.506946) (xy 420.34834 -19.506383) (xy 420.294399 -19.498626)
			(xy 420.242111 -19.483271) (xy 420.19254 -19.460632) (xy 420.146696 -19.431168) (xy 420.105511 -19.39548)
			(xy 420.069825 -19.354294) (xy 420.040363 -19.308449) (xy 420.017725 -19.258878) (xy 420.002372 -19.206589)
			(xy 419.994616 -19.152648) (xy 417.442369 -19.152648) (xy 417.44035 -19.180499) (xy 417.428457 -19.234435)
			(xy 417.408915 -19.286093) (xy 417.382129 -19.334394) (xy 417.348661 -19.37833) (xy 417.309208 -19.416982)
			(xy 417.264596 -19.449543) (xy 417.215756 -19.475334) (xy 417.18992 -19.485102) (xy 417.156138 -19.49704)
			(xy 417.156138 -20.869148) (xy 434.191662 -20.869148) (xy 434.195733 -20.813526) (xy 434.207859 -20.759089)
			(xy 434.227782 -20.706998) (xy 434.255078 -20.658363) (xy 434.289164 -20.61422) (xy 434.329313 -20.575511)
			(xy 434.374671 -20.54306) (xy 434.424271 -20.517559) (xy 434.477055 -20.499552) (xy 434.531898 -20.489422)
			(xy 434.587632 -20.487385) (xy 434.643069 -20.493485) (xy 434.697026 -20.507591) (xy 434.748355 -20.529403)
			(xy 434.795961 -20.558457) (xy 434.838829 -20.594132) (xy 434.876046 -20.635669) (xy 434.906819 -20.682182)
			(xy 434.930491 -20.732679) (xy 434.946559 -20.786086) (xy 434.954679 -20.841262) (xy 434.955188 -20.869148)
			(xy 434.954679 -20.897034) (xy 434.946559 -20.95221) (xy 434.930491 -21.005617) (xy 434.906819 -21.056114)
			(xy 434.876046 -21.102627) (xy 434.838829 -21.144164) (xy 434.795961 -21.179839) (xy 434.748355 -21.208893)
			(xy 434.697026 -21.230705) (xy 434.643069 -21.244811) (xy 434.587632 -21.250911) (xy 434.531898 -21.248874)
			(xy 434.477055 -21.238744) (xy 434.424271 -21.220737) (xy 434.374671 -21.195236) (xy 434.329313 -21.162785)
			(xy 434.289164 -21.124076) (xy 434.255078 -21.079933) (xy 434.227782 -21.031298) (xy 434.207859 -20.979207)
			(xy 434.195733 -20.92477) (xy 434.191662 -20.869148) (xy 417.156138 -20.869148) (xy 417.156138 -23.689818)
			(xy 437.315354 -23.689818) (xy 437.319425 -23.634196) (xy 437.331551 -23.579759) (xy 437.351474 -23.527668)
			(xy 437.37877 -23.479033) (xy 437.412856 -23.43489) (xy 437.453005 -23.396181) (xy 437.498363 -23.36373)
			(xy 437.547963 -23.338229) (xy 437.600747 -23.320222) (xy 437.65559 -23.310092) (xy 437.711324 -23.308055)
			(xy 437.766761 -23.314155) (xy 437.820718 -23.328261) (xy 437.872047 -23.350073) (xy 437.919653 -23.379127)
			(xy 437.962521 -23.414802) (xy 437.999738 -23.456339) (xy 438.030511 -23.502852) (xy 438.054183 -23.553349)
			(xy 438.070251 -23.606756) (xy 438.078371 -23.661932) (xy 438.07888 -23.689818) (xy 438.078371 -23.717704)
			(xy 438.070251 -23.77288) (xy 438.054183 -23.826287) (xy 438.030511 -23.876784) (xy 437.999738 -23.923297)
			(xy 437.962521 -23.964834) (xy 437.919653 -24.000509) (xy 437.872047 -24.029563) (xy 437.820718 -24.051375)
			(xy 437.766761 -24.065481) (xy 437.711324 -24.071581) (xy 437.65559 -24.069544) (xy 437.600747 -24.059414)
			(xy 437.547963 -24.041407) (xy 437.498363 -24.015906) (xy 437.453005 -23.983455) (xy 437.412856 -23.944746)
			(xy 437.37877 -23.900603) (xy 437.351474 -23.851968) (xy 437.331551 -23.799877) (xy 437.319425 -23.74544)
			(xy 437.315354 -23.689818) (xy 417.156138 -23.689818) (xy 417.156138 -24.494998) (xy 430.389282 -24.494998)
			(xy 430.393353 -24.439376) (xy 430.405479 -24.384939) (xy 430.425402 -24.332848) (xy 430.452698 -24.284213)
			(xy 430.486784 -24.24007) (xy 430.526933 -24.201361) (xy 430.572291 -24.16891) (xy 430.621891 -24.143409)
			(xy 430.674675 -24.125402) (xy 430.729518 -24.115272) (xy 430.785252 -24.113235) (xy 430.840689 -24.119335)
			(xy 430.894646 -24.133441) (xy 430.945975 -24.155253) (xy 430.993581 -24.184307) (xy 431.036449 -24.219982)
			(xy 431.073666 -24.261519) (xy 431.104439 -24.308032) (xy 431.128111 -24.358529) (xy 431.144179 -24.411936)
			(xy 431.152299 -24.467112) (xy 431.152808 -24.494998) (xy 431.152299 -24.522884) (xy 431.144179 -24.57806)
			(xy 431.128111 -24.631467) (xy 431.104439 -24.681964) (xy 431.073666 -24.728477) (xy 431.036449 -24.770014)
			(xy 430.993581 -24.805689) (xy 430.945975 -24.834743) (xy 430.894646 -24.856555) (xy 430.840689 -24.870661)
			(xy 430.785252 -24.876761) (xy 430.729518 -24.874724) (xy 430.674675 -24.864594) (xy 430.621891 -24.846587)
			(xy 430.572291 -24.821086) (xy 430.526933 -24.788635) (xy 430.486784 -24.749926) (xy 430.452698 -24.705783)
			(xy 430.425402 -24.657148) (xy 430.405479 -24.605057) (xy 430.393353 -24.55062) (xy 430.389282 -24.494998)
			(xy 417.156138 -24.494998) (xy 417.156138 -25.176988) (xy 433.449982 -25.176988) (xy 433.454053 -25.121366)
			(xy 433.466179 -25.066929) (xy 433.486102 -25.014838) (xy 433.513398 -24.966203) (xy 433.547484 -24.92206)
			(xy 433.587633 -24.883351) (xy 433.632991 -24.8509) (xy 433.682591 -24.825399) (xy 433.735375 -24.807392)
			(xy 433.790218 -24.797262) (xy 433.845952 -24.795225) (xy 433.901389 -24.801325) (xy 433.955346 -24.815431)
			(xy 434.006675 -24.837243) (xy 434.054281 -24.866297) (xy 434.097149 -24.901972) (xy 434.134366 -24.943509)
			(xy 434.165139 -24.990022) (xy 434.188811 -25.040519) (xy 434.204879 -25.093926) (xy 434.212999 -25.149102)
			(xy 434.213508 -25.176988) (xy 434.212999 -25.204874) (xy 434.204879 -25.26005) (xy 434.188811 -25.313457)
			(xy 434.165139 -25.363954) (xy 434.134366 -25.410467) (xy 434.097149 -25.452004) (xy 434.054281 -25.487679)
			(xy 434.006675 -25.516733) (xy 433.955346 -25.538545) (xy 433.901389 -25.552651) (xy 433.845952 -25.558751)
			(xy 433.790218 -25.556714) (xy 433.735375 -25.546584) (xy 433.682591 -25.528577) (xy 433.632991 -25.503076)
			(xy 433.587633 -25.470625) (xy 433.547484 -25.431916) (xy 433.513398 -25.387773) (xy 433.486102 -25.339138)
			(xy 433.466179 -25.287047) (xy 433.454053 -25.23261) (xy 433.449982 -25.176988) (xy 417.156138 -25.176988)
			(xy 417.156138 -25.823418) (xy 437.264554 -25.823418) (xy 437.268625 -25.767796) (xy 437.280751 -25.713359)
			(xy 437.300674 -25.661268) (xy 437.32797 -25.612633) (xy 437.362056 -25.56849) (xy 437.402205 -25.529781)
			(xy 437.447563 -25.49733) (xy 437.497163 -25.471829) (xy 437.549947 -25.453822) (xy 437.60479 -25.443692)
			(xy 437.660524 -25.441655) (xy 437.715961 -25.447755) (xy 437.769918 -25.461861) (xy 437.821247 -25.483673)
			(xy 437.868853 -25.512727) (xy 437.911721 -25.548402) (xy 437.948938 -25.589939) (xy 437.979711 -25.636452)
			(xy 438.003383 -25.686949) (xy 438.019451 -25.740356) (xy 438.027571 -25.795532) (xy 438.02808 -25.823418)
			(xy 438.027571 -25.851304) (xy 438.020461 -25.899618) (xy 438.255154 -25.899618) (xy 438.259225 -25.843996)
			(xy 438.271351 -25.789559) (xy 438.291274 -25.737468) (xy 438.31857 -25.688833) (xy 438.352656 -25.64469)
			(xy 438.392805 -25.605981) (xy 438.438163 -25.57353) (xy 438.487763 -25.548029) (xy 438.540547 -25.530022)
			(xy 438.59539 -25.519892) (xy 438.651124 -25.517855) (xy 438.706561 -25.523955) (xy 438.760518 -25.538061)
			(xy 438.811847 -25.559873) (xy 438.859453 -25.588927) (xy 438.902321 -25.624602) (xy 438.939538 -25.666139)
			(xy 438.970311 -25.712652) (xy 438.993983 -25.763149) (xy 439.010051 -25.816556) (xy 439.018171 -25.871732)
			(xy 439.01868 -25.899618) (xy 439.018171 -25.927504) (xy 439.010051 -25.98268) (xy 438.993983 -26.036087)
			(xy 438.970311 -26.086584) (xy 438.939538 -26.133097) (xy 438.902321 -26.174634) (xy 438.859453 -26.210309)
			(xy 438.811847 -26.239363) (xy 438.760518 -26.261175) (xy 438.706561 -26.275281) (xy 438.651124 -26.281381)
			(xy 438.59539 -26.279344) (xy 438.540547 -26.269214) (xy 438.487763 -26.251207) (xy 438.438163 -26.225706)
			(xy 438.392805 -26.193255) (xy 438.352656 -26.154546) (xy 438.31857 -26.110403) (xy 438.291274 -26.061768)
			(xy 438.271351 -26.009677) (xy 438.259225 -25.95524) (xy 438.255154 -25.899618) (xy 438.020461 -25.899618)
			(xy 438.019451 -25.90648) (xy 438.003383 -25.959887) (xy 437.979711 -26.010384) (xy 437.948938 -26.056897)
			(xy 437.911721 -26.098434) (xy 437.868853 -26.134109) (xy 437.821247 -26.163163) (xy 437.769918 -26.184975)
			(xy 437.715961 -26.199081) (xy 437.660524 -26.205181) (xy 437.60479 -26.203144) (xy 437.549947 -26.193014)
			(xy 437.497163 -26.175007) (xy 437.447563 -26.149506) (xy 437.402205 -26.117055) (xy 437.362056 -26.078346)
			(xy 437.32797 -26.034203) (xy 437.300674 -25.985568) (xy 437.280751 -25.933477) (xy 437.268625 -25.87904)
			(xy 437.264554 -25.823418) (xy 417.156138 -25.823418) (xy 417.156138 -28.412948) (xy 434.648862 -28.412948)
			(xy 434.652933 -28.357326) (xy 434.665059 -28.302889) (xy 434.684982 -28.250798) (xy 434.712278 -28.202163)
			(xy 434.746364 -28.15802) (xy 434.786513 -28.119311) (xy 434.831871 -28.08686) (xy 434.881471 -28.061359)
			(xy 434.934255 -28.043352) (xy 434.989098 -28.033222) (xy 435.044832 -28.031185) (xy 435.100269 -28.037285)
			(xy 435.154226 -28.051391) (xy 435.205555 -28.073203) (xy 435.253161 -28.102257) (xy 435.296029 -28.137932)
			(xy 435.333246 -28.179469) (xy 435.364019 -28.225982) (xy 435.387691 -28.276479) (xy 435.403759 -28.329886)
			(xy 435.411879 -28.385062) (xy 435.412388 -28.412948) (xy 435.411879 -28.440834) (xy 435.403759 -28.49601)
			(xy 435.387691 -28.549417) (xy 435.364019 -28.599914) (xy 435.352438 -28.617418) (xy 436.483504 -28.617418)
			(xy 436.487575 -28.561796) (xy 436.499701 -28.507359) (xy 436.519624 -28.455268) (xy 436.54692 -28.406633)
			(xy 436.581006 -28.36249) (xy 436.621155 -28.323781) (xy 436.666513 -28.29133) (xy 436.716113 -28.265829)
			(xy 436.768897 -28.247822) (xy 436.82374 -28.237692) (xy 436.879474 -28.235655) (xy 436.934911 -28.241755)
			(xy 436.988868 -28.255861) (xy 437.040197 -28.277673) (xy 437.087803 -28.306727) (xy 437.130671 -28.342402)
			(xy 437.167888 -28.383939) (xy 437.198661 -28.430452) (xy 437.222333 -28.480949) (xy 437.238401 -28.534356)
			(xy 437.246521 -28.589532) (xy 437.24703 -28.617418) (xy 437.246521 -28.645304) (xy 437.238401 -28.70048)
			(xy 437.222333 -28.753887) (xy 437.198661 -28.804384) (xy 437.167888 -28.850897) (xy 437.130671 -28.892434)
			(xy 437.087803 -28.928109) (xy 437.040197 -28.957163) (xy 436.988868 -28.978975) (xy 436.934911 -28.993081)
			(xy 436.879474 -28.999181) (xy 436.82374 -28.997144) (xy 436.768897 -28.987014) (xy 436.716113 -28.969007)
			(xy 436.666513 -28.943506) (xy 436.621155 -28.911055) (xy 436.581006 -28.872346) (xy 436.54692 -28.828203)
			(xy 436.519624 -28.779568) (xy 436.499701 -28.727477) (xy 436.487575 -28.67304) (xy 436.483504 -28.617418)
			(xy 435.352438 -28.617418) (xy 435.333246 -28.646427) (xy 435.296029 -28.687964) (xy 435.253161 -28.723639)
			(xy 435.205555 -28.752693) (xy 435.154226 -28.774505) (xy 435.100269 -28.788611) (xy 435.044832 -28.794711)
			(xy 434.989098 -28.792674) (xy 434.934255 -28.782544) (xy 434.881471 -28.764537) (xy 434.831871 -28.739036)
			(xy 434.786513 -28.706585) (xy 434.746364 -28.667876) (xy 434.712278 -28.623733) (xy 434.684982 -28.575098)
			(xy 434.665059 -28.523007) (xy 434.652933 -28.46857) (xy 434.648862 -28.412948) (xy 417.156138 -28.412948)
			(xy 417.156138 -29.379926) (xy 425.72738 -29.379926) (xy 425.731346 -29.295395) (xy 425.743211 -29.211608)
			(xy 425.762869 -29.129299) (xy 425.790149 -29.049193) (xy 425.82481 -28.971994) (xy 425.866548 -28.898379)
			(xy 425.914995 -28.828996) (xy 425.969727 -28.764455) (xy 426.030263 -28.705323) (xy 426.096069 -28.652119)
			(xy 426.166569 -28.605311) (xy 426.241141 -28.56531) (xy 426.319132 -28.532468) (xy 426.399856 -28.507074)
			(xy 426.482603 -28.489351) (xy 426.566645 -28.479453) (xy 426.651246 -28.47747) (xy 426.73566 -28.483417)
			(xy 426.819147 -28.497242) (xy 426.900972 -28.518825) (xy 426.980416 -28.547975) (xy 427.056782 -28.584436)
			(xy 427.129398 -28.627888) (xy 427.197626 -28.677949) (xy 427.260866 -28.734179) (xy 427.318563 -28.796084)
			(xy 427.37021 -28.86312) (xy 427.415352 -28.934697) (xy 427.453594 -29.010187) (xy 427.484598 -29.088926)
			(xy 427.508093 -29.170223) (xy 427.523872 -29.253362) (xy 427.531796 -29.337614) (xy 427.532292 -29.379926)
			(xy 428.26738 -29.379926) (xy 428.271346 -29.295395) (xy 428.283211 -29.211608) (xy 428.302869 -29.129299)
			(xy 428.330149 -29.049193) (xy 428.36481 -28.971994) (xy 428.406548 -28.898379) (xy 428.454995 -28.828996)
			(xy 428.509727 -28.764455) (xy 428.570263 -28.705323) (xy 428.636069 -28.652119) (xy 428.706569 -28.605311)
			(xy 428.781141 -28.56531) (xy 428.859132 -28.532468) (xy 428.939856 -28.507074) (xy 429.022603 -28.489351)
			(xy 429.106645 -28.479453) (xy 429.191246 -28.47747) (xy 429.27566 -28.483417) (xy 429.359147 -28.497242)
			(xy 429.440972 -28.518825) (xy 429.520416 -28.547975) (xy 429.596782 -28.584436) (xy 429.669398 -28.627888)
			(xy 429.737626 -28.677949) (xy 429.800866 -28.734179) (xy 429.858563 -28.796084) (xy 429.91021 -28.86312)
			(xy 429.955352 -28.934697) (xy 429.993594 -29.010187) (xy 430.024598 -29.088926) (xy 430.048093 -29.170223)
			(xy 430.063872 -29.253362) (xy 430.071796 -29.337614) (xy 430.072292 -29.379926) (xy 430.071796 -29.422238)
			(xy 430.063872 -29.50649) (xy 430.048093 -29.589629) (xy 430.024598 -29.670926) (xy 429.993594 -29.749665)
			(xy 429.955352 -29.825155) (xy 429.91021 -29.896732) (xy 429.879226 -29.936948) (xy 434.598062 -29.936948)
			(xy 434.602133 -29.881326) (xy 434.614259 -29.826889) (xy 434.634182 -29.774798) (xy 434.661478 -29.726163)
			(xy 434.695564 -29.68202) (xy 434.735713 -29.643311) (xy 434.781071 -29.61086) (xy 434.830671 -29.585359)
			(xy 434.883455 -29.567352) (xy 434.938298 -29.557222) (xy 434.994032 -29.555185) (xy 435.049469 -29.561285)
			(xy 435.103426 -29.575391) (xy 435.154755 -29.597203) (xy 435.202361 -29.626257) (xy 435.210966 -29.633418)
			(xy 436.483504 -29.633418) (xy 436.487575 -29.577796) (xy 436.499701 -29.523359) (xy 436.519624 -29.471268)
			(xy 436.54692 -29.422633) (xy 436.581006 -29.37849) (xy 436.621155 -29.339781) (xy 436.666513 -29.30733)
			(xy 436.716113 -29.281829) (xy 436.768897 -29.263822) (xy 436.82374 -29.253692) (xy 436.879474 -29.251655)
			(xy 436.934911 -29.257755) (xy 436.988868 -29.271861) (xy 437.040197 -29.293673) (xy 437.087803 -29.322727)
			(xy 437.130671 -29.358402) (xy 437.167888 -29.399939) (xy 437.198661 -29.446452) (xy 437.222333 -29.496949)
			(xy 437.238401 -29.550356) (xy 437.246521 -29.605532) (xy 437.24703 -29.633418) (xy 437.246521 -29.661304)
			(xy 437.238401 -29.71648) (xy 437.222333 -29.769887) (xy 437.198661 -29.820384) (xy 437.167888 -29.866897)
			(xy 437.130671 -29.908434) (xy 437.087803 -29.944109) (xy 437.040197 -29.973163) (xy 436.988868 -29.994975)
			(xy 436.934911 -30.009081) (xy 436.879474 -30.015181) (xy 436.82374 -30.013144) (xy 436.768897 -30.003014)
			(xy 436.716113 -29.985007) (xy 436.666513 -29.959506) (xy 436.621155 -29.927055) (xy 436.581006 -29.888346)
			(xy 436.54692 -29.844203) (xy 436.519624 -29.795568) (xy 436.499701 -29.743477) (xy 436.487575 -29.68904)
			(xy 436.483504 -29.633418) (xy 435.210966 -29.633418) (xy 435.245229 -29.661932) (xy 435.282446 -29.703469)
			(xy 435.313219 -29.749982) (xy 435.336891 -29.800479) (xy 435.352959 -29.853886) (xy 435.361079 -29.909062)
			(xy 435.361588 -29.936948) (xy 435.361079 -29.964834) (xy 435.352959 -30.02001) (xy 435.336891 -30.073417)
			(xy 435.313219 -30.123914) (xy 435.282446 -30.170427) (xy 435.245229 -30.211964) (xy 435.202361 -30.247639)
			(xy 435.154755 -30.276693) (xy 435.103426 -30.298505) (xy 435.049469 -30.312611) (xy 434.994032 -30.318711)
			(xy 434.938298 -30.316674) (xy 434.883455 -30.306544) (xy 434.830671 -30.288537) (xy 434.781071 -30.263036)
			(xy 434.735713 -30.230585) (xy 434.695564 -30.191876) (xy 434.661478 -30.147733) (xy 434.634182 -30.099098)
			(xy 434.614259 -30.047007) (xy 434.602133 -29.99257) (xy 434.598062 -29.936948) (xy 429.879226 -29.936948)
			(xy 429.858563 -29.963768) (xy 429.800866 -30.025673) (xy 429.737626 -30.081903) (xy 429.669398 -30.131964)
			(xy 429.596782 -30.175416) (xy 429.520416 -30.211877) (xy 429.440972 -30.241027) (xy 429.359147 -30.26261)
			(xy 429.27566 -30.276435) (xy 429.191246 -30.282382) (xy 429.106645 -30.280399) (xy 429.022603 -30.270501)
			(xy 428.939856 -30.252778) (xy 428.859132 -30.227384) (xy 428.781141 -30.194542) (xy 428.706569 -30.154541)
			(xy 428.636069 -30.107733) (xy 428.570263 -30.054529) (xy 428.509727 -29.995397) (xy 428.454995 -29.930856)
			(xy 428.406548 -29.861473) (xy 428.36481 -29.787858) (xy 428.330149 -29.710659) (xy 428.302869 -29.630553)
			(xy 428.283211 -29.548244) (xy 428.271346 -29.464457) (xy 428.26738 -29.379926) (xy 427.532292 -29.379926)
			(xy 427.531796 -29.422238) (xy 427.523872 -29.50649) (xy 427.508093 -29.589629) (xy 427.484598 -29.670926)
			(xy 427.453594 -29.749665) (xy 427.415352 -29.825155) (xy 427.37021 -29.896732) (xy 427.318563 -29.963768)
			(xy 427.260866 -30.025673) (xy 427.197626 -30.081903) (xy 427.129398 -30.131964) (xy 427.056782 -30.175416)
			(xy 426.980416 -30.211877) (xy 426.900972 -30.241027) (xy 426.819147 -30.26261) (xy 426.73566 -30.276435)
			(xy 426.651246 -30.282382) (xy 426.566645 -30.280399) (xy 426.482603 -30.270501) (xy 426.399856 -30.252778)
			(xy 426.319132 -30.227384) (xy 426.241141 -30.194542) (xy 426.166569 -30.154541) (xy 426.096069 -30.107733)
			(xy 426.030263 -30.054529) (xy 425.969727 -29.995397) (xy 425.914995 -29.930856) (xy 425.866548 -29.861473)
			(xy 425.82481 -29.787858) (xy 425.790149 -29.710659) (xy 425.762869 -29.630553) (xy 425.743211 -29.548244)
			(xy 425.731346 -29.464457) (xy 425.72738 -29.379926) (xy 417.156138 -29.379926) (xy 417.156138 -31.919926)
			(xy 425.72738 -31.919926) (xy 425.731346 -31.835395) (xy 425.743211 -31.751608) (xy 425.762869 -31.669299)
			(xy 425.790149 -31.589193) (xy 425.82481 -31.511994) (xy 425.866548 -31.438379) (xy 425.914995 -31.368996)
			(xy 425.969727 -31.304455) (xy 426.030263 -31.245323) (xy 426.096069 -31.192119) (xy 426.166569 -31.145311)
			(xy 426.241141 -31.10531) (xy 426.319132 -31.072468) (xy 426.399856 -31.047074) (xy 426.482603 -31.029351)
			(xy 426.566645 -31.019453) (xy 426.651246 -31.01747) (xy 426.73566 -31.023417) (xy 426.819147 -31.037242)
			(xy 426.900972 -31.058825) (xy 426.980416 -31.087975) (xy 427.056782 -31.124436) (xy 427.129398 -31.167888)
			(xy 427.197626 -31.217949) (xy 427.260866 -31.274179) (xy 427.318563 -31.336084) (xy 427.37021 -31.40312)
			(xy 427.415352 -31.474697) (xy 427.453594 -31.550187) (xy 427.484598 -31.628926) (xy 427.508093 -31.710223)
			(xy 427.523872 -31.793362) (xy 427.531796 -31.877614) (xy 427.532292 -31.919926) (xy 428.26738 -31.919926)
			(xy 428.271346 -31.835395) (xy 428.283211 -31.751608) (xy 428.302869 -31.669299) (xy 428.330149 -31.589193)
			(xy 428.36481 -31.511994) (xy 428.406548 -31.438379) (xy 428.454995 -31.368996) (xy 428.509727 -31.304455)
			(xy 428.570263 -31.245323) (xy 428.636069 -31.192119) (xy 428.706569 -31.145311) (xy 428.781141 -31.10531)
			(xy 428.859132 -31.072468) (xy 428.939856 -31.047074) (xy 429.022603 -31.029351) (xy 429.106645 -31.019453)
			(xy 429.191246 -31.01747) (xy 429.27566 -31.023417) (xy 429.359147 -31.037242) (xy 429.440972 -31.058825)
			(xy 429.520416 -31.087975) (xy 429.596782 -31.124436) (xy 429.669398 -31.167888) (xy 429.737626 -31.217949)
			(xy 429.800866 -31.274179) (xy 429.858563 -31.336084) (xy 429.91021 -31.40312) (xy 429.955352 -31.474697)
			(xy 429.993594 -31.550187) (xy 430.024598 -31.628926) (xy 430.048093 -31.710223) (xy 430.063872 -31.793362)
			(xy 430.071796 -31.877614) (xy 430.072292 -31.919926) (xy 430.071796 -31.962238) (xy 430.063872 -32.04649)
			(xy 430.048093 -32.129629) (xy 430.024598 -32.210926) (xy 429.993594 -32.289665) (xy 429.955352 -32.365155)
			(xy 429.91021 -32.436732) (xy 429.858563 -32.503768) (xy 429.800866 -32.565673) (xy 429.737626 -32.621903)
			(xy 429.669398 -32.671964) (xy 429.596782 -32.715416) (xy 429.520416 -32.751877) (xy 429.440972 -32.781027)
			(xy 429.359147 -32.80261) (xy 429.27566 -32.816435) (xy 429.191246 -32.822382) (xy 429.106645 -32.820399)
			(xy 429.022603 -32.810501) (xy 428.939856 -32.792778) (xy 428.859132 -32.767384) (xy 428.781141 -32.734542)
			(xy 428.706569 -32.694541) (xy 428.636069 -32.647733) (xy 428.570263 -32.594529) (xy 428.509727 -32.535397)
			(xy 428.454995 -32.470856) (xy 428.406548 -32.401473) (xy 428.36481 -32.327858) (xy 428.330149 -32.250659)
			(xy 428.302869 -32.170553) (xy 428.283211 -32.088244) (xy 428.271346 -32.004457) (xy 428.26738 -31.919926)
			(xy 427.532292 -31.919926) (xy 427.531796 -31.962238) (xy 427.523872 -32.04649) (xy 427.508093 -32.129629)
			(xy 427.484598 -32.210926) (xy 427.453594 -32.289665) (xy 427.415352 -32.365155) (xy 427.37021 -32.436732)
			(xy 427.318563 -32.503768) (xy 427.260866 -32.565673) (xy 427.197626 -32.621903) (xy 427.129398 -32.671964)
			(xy 427.056782 -32.715416) (xy 426.980416 -32.751877) (xy 426.900972 -32.781027) (xy 426.819147 -32.80261)
			(xy 426.73566 -32.816435) (xy 426.651246 -32.822382) (xy 426.566645 -32.820399) (xy 426.482603 -32.810501)
			(xy 426.399856 -32.792778) (xy 426.319132 -32.767384) (xy 426.241141 -32.734542) (xy 426.166569 -32.694541)
			(xy 426.096069 -32.647733) (xy 426.030263 -32.594529) (xy 425.969727 -32.535397) (xy 425.914995 -32.470856)
			(xy 425.866548 -32.401473) (xy 425.82481 -32.327858) (xy 425.790149 -32.250659) (xy 425.762869 -32.170553)
			(xy 425.743211 -32.088244) (xy 425.731346 -32.004457) (xy 425.72738 -31.919926) (xy 417.156138 -31.919926)
			(xy 417.156138 -33.238948) (xy 434.826154 -33.238948) (xy 434.830225 -33.183326) (xy 434.842351 -33.128889)
			(xy 434.862274 -33.076798) (xy 434.88957 -33.028163) (xy 434.923656 -32.98402) (xy 434.963805 -32.945311)
			(xy 435.009163 -32.91286) (xy 435.058763 -32.887359) (xy 435.111547 -32.869352) (xy 435.16639 -32.859222)
			(xy 435.222124 -32.857185) (xy 435.277561 -32.863285) (xy 435.331518 -32.877391) (xy 435.382847 -32.899203)
			(xy 435.430453 -32.928257) (xy 435.473321 -32.963932) (xy 435.510538 -33.005469) (xy 435.541311 -33.051982)
			(xy 435.564983 -33.102479) (xy 435.581051 -33.155886) (xy 435.589171 -33.211062) (xy 435.58968 -33.238948)
			(xy 435.589171 -33.266834) (xy 435.581051 -33.32201) (xy 435.564983 -33.375417) (xy 435.541311 -33.425914)
			(xy 435.510538 -33.472427) (xy 435.473321 -33.513964) (xy 435.430453 -33.549639) (xy 435.382847 -33.578693)
			(xy 435.331518 -33.600505) (xy 435.277561 -33.614611) (xy 435.222124 -33.620711) (xy 435.16639 -33.618674)
			(xy 435.111547 -33.608544) (xy 435.058763 -33.590537) (xy 435.009163 -33.565036) (xy 434.963805 -33.532585)
			(xy 434.923656 -33.493876) (xy 434.88957 -33.449733) (xy 434.862274 -33.401098) (xy 434.842351 -33.349007)
			(xy 434.830225 -33.29457) (xy 434.826154 -33.238948) (xy 417.156138 -33.238948) (xy 417.156138 -34.459926)
			(xy 425.72738 -34.459926) (xy 425.731346 -34.375395) (xy 425.743211 -34.291608) (xy 425.762869 -34.209299)
			(xy 425.790149 -34.129193) (xy 425.82481 -34.051994) (xy 425.866548 -33.978379) (xy 425.914995 -33.908996)
			(xy 425.969727 -33.844455) (xy 426.030263 -33.785323) (xy 426.096069 -33.732119) (xy 426.166569 -33.685311)
			(xy 426.241141 -33.64531) (xy 426.319132 -33.612468) (xy 426.399856 -33.587074) (xy 426.482603 -33.569351)
			(xy 426.566645 -33.559453) (xy 426.651246 -33.55747) (xy 426.73566 -33.563417) (xy 426.819147 -33.577242)
			(xy 426.900972 -33.598825) (xy 426.980416 -33.627975) (xy 427.056782 -33.664436) (xy 427.129398 -33.707888)
			(xy 427.197626 -33.757949) (xy 427.260866 -33.814179) (xy 427.318563 -33.876084) (xy 427.37021 -33.94312)
			(xy 427.415352 -34.014697) (xy 427.453594 -34.090187) (xy 427.484598 -34.168926) (xy 427.508093 -34.250223)
			(xy 427.523872 -34.333362) (xy 427.531796 -34.417614) (xy 427.532292 -34.459926) (xy 428.26738 -34.459926)
			(xy 428.271346 -34.375395) (xy 428.283211 -34.291608) (xy 428.302869 -34.209299) (xy 428.330149 -34.129193)
			(xy 428.36481 -34.051994) (xy 428.406548 -33.978379) (xy 428.454995 -33.908996) (xy 428.509727 -33.844455)
			(xy 428.570263 -33.785323) (xy 428.636069 -33.732119) (xy 428.706569 -33.685311) (xy 428.781141 -33.64531)
			(xy 428.859132 -33.612468) (xy 428.939856 -33.587074) (xy 429.022603 -33.569351) (xy 429.106645 -33.559453)
			(xy 429.191246 -33.55747) (xy 429.27566 -33.563417) (xy 429.359147 -33.577242) (xy 429.440972 -33.598825)
			(xy 429.520416 -33.627975) (xy 429.596782 -33.664436) (xy 429.669398 -33.707888) (xy 429.737626 -33.757949)
			(xy 429.800866 -33.814179) (xy 429.858563 -33.876084) (xy 429.91021 -33.94312) (xy 429.955352 -34.014697)
			(xy 429.993594 -34.090187) (xy 430.024598 -34.168926) (xy 430.048093 -34.250223) (xy 430.063872 -34.333362)
			(xy 430.067605 -34.373058) (xy 435.842154 -34.373058) (xy 435.846225 -34.317436) (xy 435.858351 -34.262999)
			(xy 435.878274 -34.210908) (xy 435.90557 -34.162273) (xy 435.939656 -34.11813) (xy 435.979805 -34.079421)
			(xy 436.025163 -34.04697) (xy 436.074763 -34.021469) (xy 436.127547 -34.003462) (xy 436.18239 -33.993332)
			(xy 436.238124 -33.991295) (xy 436.293561 -33.997395) (xy 436.347518 -34.011501) (xy 436.398847 -34.033313)
			(xy 436.446453 -34.062367) (xy 436.489321 -34.098042) (xy 436.526538 -34.139579) (xy 436.557311 -34.186092)
			(xy 436.580983 -34.236589) (xy 436.597051 -34.289996) (xy 436.605171 -34.345172) (xy 436.60568 -34.373058)
			(xy 436.858154 -34.373058) (xy 436.862225 -34.317436) (xy 436.874351 -34.262999) (xy 436.894274 -34.210908)
			(xy 436.92157 -34.162273) (xy 436.955656 -34.11813) (xy 436.995805 -34.079421) (xy 437.041163 -34.04697)
			(xy 437.090763 -34.021469) (xy 437.143547 -34.003462) (xy 437.19839 -33.993332) (xy 437.254124 -33.991295)
			(xy 437.309561 -33.997395) (xy 437.363518 -34.011501) (xy 437.414847 -34.033313) (xy 437.462453 -34.062367)
			(xy 437.505321 -34.098042) (xy 437.542538 -34.139579) (xy 437.573311 -34.186092) (xy 437.596983 -34.236589)
			(xy 437.613051 -34.289996) (xy 437.621171 -34.345172) (xy 437.62168 -34.373058) (xy 437.621171 -34.400944)
			(xy 437.613051 -34.45612) (xy 437.596983 -34.509527) (xy 437.573311 -34.560024) (xy 437.542538 -34.606537)
			(xy 437.505321 -34.648074) (xy 437.462453 -34.683749) (xy 437.414847 -34.712803) (xy 437.363518 -34.734615)
			(xy 437.309561 -34.748721) (xy 437.254124 -34.754821) (xy 437.19839 -34.752784) (xy 437.143547 -34.742654)
			(xy 437.090763 -34.724647) (xy 437.041163 -34.699146) (xy 436.995805 -34.666695) (xy 436.955656 -34.627986)
			(xy 436.92157 -34.583843) (xy 436.894274 -34.535208) (xy 436.874351 -34.483117) (xy 436.862225 -34.42868)
			(xy 436.858154 -34.373058) (xy 436.60568 -34.373058) (xy 436.605171 -34.400944) (xy 436.597051 -34.45612)
			(xy 436.580983 -34.509527) (xy 436.557311 -34.560024) (xy 436.526538 -34.606537) (xy 436.489321 -34.648074)
			(xy 436.446453 -34.683749) (xy 436.398847 -34.712803) (xy 436.347518 -34.734615) (xy 436.293561 -34.748721)
			(xy 436.238124 -34.754821) (xy 436.18239 -34.752784) (xy 436.127547 -34.742654) (xy 436.074763 -34.724647)
			(xy 436.025163 -34.699146) (xy 435.979805 -34.666695) (xy 435.939656 -34.627986) (xy 435.90557 -34.583843)
			(xy 435.878274 -34.535208) (xy 435.858351 -34.483117) (xy 435.846225 -34.42868) (xy 435.842154 -34.373058)
			(xy 430.067605 -34.373058) (xy 430.071796 -34.417614) (xy 430.072292 -34.459926) (xy 430.071796 -34.502238)
			(xy 430.063872 -34.58649) (xy 430.048093 -34.669629) (xy 430.024598 -34.750926) (xy 429.993594 -34.829665)
			(xy 429.955352 -34.905155) (xy 429.91021 -34.976732) (xy 429.858563 -35.043768) (xy 429.800866 -35.105673)
			(xy 429.737626 -35.161903) (xy 429.669398 -35.211964) (xy 429.596782 -35.255416) (xy 429.520416 -35.291877)
			(xy 429.440972 -35.321027) (xy 429.359147 -35.34261) (xy 429.27566 -35.356435) (xy 429.191246 -35.362382)
			(xy 429.106645 -35.360399) (xy 429.022603 -35.350501) (xy 428.939856 -35.332778) (xy 428.859132 -35.307384)
			(xy 428.781141 -35.274542) (xy 428.706569 -35.234541) (xy 428.636069 -35.187733) (xy 428.570263 -35.134529)
			(xy 428.509727 -35.075397) (xy 428.454995 -35.010856) (xy 428.406548 -34.941473) (xy 428.36481 -34.867858)
			(xy 428.330149 -34.790659) (xy 428.302869 -34.710553) (xy 428.283211 -34.628244) (xy 428.271346 -34.544457)
			(xy 428.26738 -34.459926) (xy 427.532292 -34.459926) (xy 427.531796 -34.502238) (xy 427.523872 -34.58649)
			(xy 427.508093 -34.669629) (xy 427.484598 -34.750926) (xy 427.453594 -34.829665) (xy 427.415352 -34.905155)
			(xy 427.37021 -34.976732) (xy 427.318563 -35.043768) (xy 427.260866 -35.105673) (xy 427.197626 -35.161903)
			(xy 427.129398 -35.211964) (xy 427.056782 -35.255416) (xy 426.980416 -35.291877) (xy 426.900972 -35.321027)
			(xy 426.819147 -35.34261) (xy 426.73566 -35.356435) (xy 426.651246 -35.362382) (xy 426.566645 -35.360399)
			(xy 426.482603 -35.350501) (xy 426.399856 -35.332778) (xy 426.319132 -35.307384) (xy 426.241141 -35.274542)
			(xy 426.166569 -35.234541) (xy 426.096069 -35.187733) (xy 426.030263 -35.134529) (xy 425.969727 -35.075397)
			(xy 425.914995 -35.010856) (xy 425.866548 -34.941473) (xy 425.82481 -34.867858) (xy 425.790149 -34.790659)
			(xy 425.762869 -34.710553) (xy 425.743211 -34.628244) (xy 425.731346 -34.544457) (xy 425.72738 -34.459926)
			(xy 417.156138 -34.459926) (xy 417.156138 -35.6108) (xy 434.389782 -35.6108) (xy 434.393853 -35.555178)
			(xy 434.405979 -35.500741) (xy 434.425902 -35.44865) (xy 434.453198 -35.400015) (xy 434.487284 -35.355872)
			(xy 434.527433 -35.317163) (xy 434.572791 -35.284712) (xy 434.622391 -35.259211) (xy 434.675175 -35.241204)
			(xy 434.730018 -35.231074) (xy 434.785752 -35.229037) (xy 434.841189 -35.235137) (xy 434.895146 -35.249243)
			(xy 434.946475 -35.271055) (xy 434.994081 -35.300109) (xy 435.036949 -35.335784) (xy 435.074166 -35.377321)
			(xy 435.104939 -35.423834) (xy 435.128611 -35.474331) (xy 435.144679 -35.527738) (xy 435.152799 -35.582914)
			(xy 435.153308 -35.6108) (xy 435.152799 -35.638686) (xy 435.144679 -35.693862) (xy 435.128611 -35.747269)
			(xy 435.104939 -35.797766) (xy 435.074166 -35.844279) (xy 435.036949 -35.885816) (xy 434.994081 -35.921491)
			(xy 434.946475 -35.950545) (xy 434.895146 -35.972357) (xy 434.841189 -35.986463) (xy 434.785752 -35.992563)
			(xy 434.730018 -35.990526) (xy 434.675175 -35.980396) (xy 434.622391 -35.962389) (xy 434.572791 -35.936888)
			(xy 434.527433 -35.904437) (xy 434.487284 -35.865728) (xy 434.453198 -35.821585) (xy 434.425902 -35.77295)
			(xy 434.405979 -35.720859) (xy 434.393853 -35.666422) (xy 434.389782 -35.6108) (xy 417.156138 -35.6108)
			(xy 417.156138 -36.999926) (xy 425.72738 -36.999926) (xy 425.731346 -36.915395) (xy 425.743211 -36.831608)
			(xy 425.762869 -36.749299) (xy 425.790149 -36.669193) (xy 425.82481 -36.591994) (xy 425.866548 -36.518379)
			(xy 425.914995 -36.448996) (xy 425.969727 -36.384455) (xy 426.030263 -36.325323) (xy 426.096069 -36.272119)
			(xy 426.166569 -36.225311) (xy 426.241141 -36.18531) (xy 426.319132 -36.152468) (xy 426.399856 -36.127074)
			(xy 426.482603 -36.109351) (xy 426.566645 -36.099453) (xy 426.651246 -36.09747) (xy 426.73566 -36.103417)
			(xy 426.819147 -36.117242) (xy 426.900972 -36.138825) (xy 426.980416 -36.167975) (xy 427.056782 -36.204436)
			(xy 427.129398 -36.247888) (xy 427.197626 -36.297949) (xy 427.260866 -36.354179) (xy 427.318563 -36.416084)
			(xy 427.37021 -36.48312) (xy 427.415352 -36.554697) (xy 427.453594 -36.630187) (xy 427.484598 -36.708926)
			(xy 427.508093 -36.790223) (xy 427.523872 -36.873362) (xy 427.531796 -36.957614) (xy 427.532292 -36.999926)
			(xy 428.26738 -36.999926) (xy 428.271346 -36.915395) (xy 428.283211 -36.831608) (xy 428.302869 -36.749299)
			(xy 428.330149 -36.669193) (xy 428.36481 -36.591994) (xy 428.406548 -36.518379) (xy 428.454995 -36.448996)
			(xy 428.509727 -36.384455) (xy 428.570263 -36.325323) (xy 428.636069 -36.272119) (xy 428.706569 -36.225311)
			(xy 428.781141 -36.18531) (xy 428.859132 -36.152468) (xy 428.939856 -36.127074) (xy 429.022603 -36.109351)
			(xy 429.106645 -36.099453) (xy 429.191246 -36.09747) (xy 429.27566 -36.103417) (xy 429.359147 -36.117242)
			(xy 429.440972 -36.138825) (xy 429.520416 -36.167975) (xy 429.596782 -36.204436) (xy 429.669398 -36.247888)
			(xy 429.737626 -36.297949) (xy 429.741822 -36.30168) (xy 435.098442 -36.30168) (xy 435.102513 -36.246058)
			(xy 435.114639 -36.191621) (xy 435.134562 -36.13953) (xy 435.161858 -36.090895) (xy 435.195944 -36.046752)
			(xy 435.236093 -36.008043) (xy 435.281451 -35.975592) (xy 435.331051 -35.950091) (xy 435.383835 -35.932084)
			(xy 435.438678 -35.921954) (xy 435.494412 -35.919917) (xy 435.549849 -35.926017) (xy 435.603806 -35.940123)
			(xy 435.655135 -35.961935) (xy 435.702741 -35.990989) (xy 435.745609 -36.026664) (xy 435.782826 -36.068201)
			(xy 435.813599 -36.114714) (xy 435.837271 -36.165211) (xy 435.853339 -36.218618) (xy 435.861459 -36.273794)
			(xy 435.861968 -36.30168) (xy 435.861459 -36.329566) (xy 435.853339 -36.384742) (xy 435.837271 -36.438149)
			(xy 435.813599 -36.488646) (xy 435.782826 -36.535159) (xy 435.768536 -36.551108) (xy 459.081122 -36.551108)
			(xy 459.085193 -36.495486) (xy 459.097319 -36.441049) (xy 459.117242 -36.388958) (xy 459.144538 -36.340323)
			(xy 459.178624 -36.29618) (xy 459.218773 -36.257471) (xy 459.264131 -36.22502) (xy 459.313731 -36.199519)
			(xy 459.366515 -36.181512) (xy 459.421358 -36.171382) (xy 459.477092 -36.169345) (xy 459.532529 -36.175445)
			(xy 459.586486 -36.189551) (xy 459.637815 -36.211363) (xy 459.685421 -36.240417) (xy 459.728289 -36.276092)
			(xy 459.765506 -36.317629) (xy 459.796279 -36.364142) (xy 459.819951 -36.414639) (xy 459.836019 -36.468046)
			(xy 459.844139 -36.523222) (xy 459.844648 -36.551108) (xy 459.844139 -36.578994) (xy 459.836019 -36.63417)
			(xy 459.819951 -36.687577) (xy 459.796279 -36.738074) (xy 459.765506 -36.784587) (xy 459.728289 -36.826124)
			(xy 459.685421 -36.861799) (xy 459.637815 -36.890853) (xy 459.586486 -36.912665) (xy 459.532529 -36.926771)
			(xy 459.477092 -36.932871) (xy 459.421358 -36.930834) (xy 459.366515 -36.920704) (xy 459.313731 -36.902697)
			(xy 459.264131 -36.877196) (xy 459.218773 -36.844745) (xy 459.178624 -36.806036) (xy 459.144538 -36.761893)
			(xy 459.117242 -36.713258) (xy 459.097319 -36.661167) (xy 459.085193 -36.60673) (xy 459.081122 -36.551108)
			(xy 435.768536 -36.551108) (xy 435.745609 -36.576696) (xy 435.702741 -36.612371) (xy 435.655135 -36.641425)
			(xy 435.603806 -36.663237) (xy 435.549849 -36.677343) (xy 435.494412 -36.683443) (xy 435.438678 -36.681406)
			(xy 435.383835 -36.671276) (xy 435.331051 -36.653269) (xy 435.281451 -36.627768) (xy 435.236093 -36.595317)
			(xy 435.195944 -36.556608) (xy 435.161858 -36.512465) (xy 435.134562 -36.46383) (xy 435.114639 -36.411739)
			(xy 435.102513 -36.357302) (xy 435.098442 -36.30168) (xy 429.741822 -36.30168) (xy 429.800866 -36.354179)
			(xy 429.858563 -36.416084) (xy 429.91021 -36.48312) (xy 429.955352 -36.554697) (xy 429.993594 -36.630187)
			(xy 430.024598 -36.708926) (xy 430.048093 -36.790223) (xy 430.063872 -36.873362) (xy 430.071796 -36.957614)
			(xy 430.072292 -36.999926) (xy 430.071796 -37.042238) (xy 430.063872 -37.12649) (xy 430.048093 -37.209629)
			(xy 430.024598 -37.290926) (xy 429.993594 -37.369665) (xy 429.955352 -37.445155) (xy 429.91021 -37.516732)
			(xy 429.858563 -37.583768) (xy 429.800866 -37.645673) (xy 429.737626 -37.701903) (xy 429.669398 -37.751964)
			(xy 429.596782 -37.795416) (xy 429.538715 -37.82314) (xy 435.771542 -37.82314) (xy 435.775613 -37.767518)
			(xy 435.787739 -37.713081) (xy 435.807662 -37.66099) (xy 435.834958 -37.612355) (xy 435.869044 -37.568212)
			(xy 435.909193 -37.529503) (xy 435.954551 -37.497052) (xy 436.004151 -37.471551) (xy 436.056935 -37.453544)
			(xy 436.111778 -37.443414) (xy 436.167512 -37.441377) (xy 436.222949 -37.447477) (xy 436.276906 -37.461583)
			(xy 436.328235 -37.483395) (xy 436.375841 -37.512449) (xy 436.418709 -37.548124) (xy 436.455926 -37.589661)
			(xy 436.486699 -37.636174) (xy 436.510371 -37.686671) (xy 436.526439 -37.740078) (xy 436.534559 -37.795254)
			(xy 436.535068 -37.82314) (xy 436.534559 -37.851026) (xy 436.531486 -37.871908) (xy 437.430162 -37.871908)
			(xy 437.434233 -37.816286) (xy 437.446359 -37.761849) (xy 437.466282 -37.709758) (xy 437.493578 -37.661123)
			(xy 437.527664 -37.61698) (xy 437.567813 -37.578271) (xy 437.613171 -37.54582) (xy 437.662771 -37.520319)
			(xy 437.715555 -37.502312) (xy 437.770398 -37.492182) (xy 437.826132 -37.490145) (xy 437.881569 -37.496245)
			(xy 437.926342 -37.50795) (xy 443.729103 -37.50795) (xy 443.729103 -37.45345) (xy 443.73686 -37.399505)
			(xy 443.752214 -37.347213) (xy 443.774854 -37.297638) (xy 443.80432 -37.251791) (xy 443.84001 -37.210603)
			(xy 443.881199 -37.174914) (xy 443.927047 -37.14545) (xy 443.976622 -37.122811) (xy 444.028915 -37.107457)
			(xy 444.08286 -37.099703) (xy 444.11011 -37.09924) (xy 444.135871 -37.099647) (xy 444.186925 -37.106578)
			(xy 444.236583 -37.120311) (xy 444.283942 -37.140599) (xy 444.328143 -37.167071) (xy 444.368383 -37.199248)
			(xy 444.386462 -37.217604) (xy 444.39626 -37.227225) (xy 444.419813 -37.241321) (xy 444.446271 -37.248633)
			(xy 444.473719 -37.248633) (xy 444.500177 -37.241321) (xy 444.52373 -37.227225) (xy 444.533528 -37.217604)
			(xy 444.551605 -37.199246) (xy 444.591847 -37.167076) (xy 444.63605 -37.140609) (xy 444.68341 -37.120326)
			(xy 444.733067 -37.106594) (xy 444.78412 -37.099664) (xy 444.80988 -37.09924) (xy 444.837137 -37.099606)
			(xy 444.891097 -37.107361) (xy 444.943404 -37.122717) (xy 444.992993 -37.145362) (xy 445.038854 -37.174833)
			(xy 445.080055 -37.210531) (xy 445.115755 -37.25173) (xy 445.145229 -37.297589) (xy 445.167876 -37.347177)
			(xy 445.183235 -37.399483) (xy 445.190993 -37.453443) (xy 445.190993 -37.507957) (xy 445.183235 -37.561917)
			(xy 445.167876 -37.614223) (xy 445.145229 -37.663811) (xy 445.115755 -37.70967) (xy 445.080055 -37.750869)
			(xy 445.038854 -37.786567) (xy 444.992993 -37.816038) (xy 444.943404 -37.838683) (xy 444.891097 -37.854039)
			(xy 444.837137 -37.861794) (xy 444.80988 -37.862256) (xy 444.784121 -37.861791) (xy 444.73307 -37.854872)
			(xy 444.683413 -37.84115) (xy 444.636053 -37.820873) (xy 444.59185 -37.794411) (xy 444.551609 -37.762244)
			(xy 444.533528 -37.743892) (xy 444.523754 -37.734223) (xy 444.500213 -37.720044) (xy 444.473736 -37.712686)
			(xy 444.446254 -37.712686) (xy 444.419777 -37.720044) (xy 444.396236 -37.734223) (xy 444.386462 -37.743892)
			(xy 444.368389 -37.762254) (xy 444.328146 -37.794424) (xy 444.283942 -37.82089) (xy 444.236582 -37.841173)
			(xy 444.186924 -37.854904) (xy 444.135871 -37.861832) (xy 444.11011 -37.862256) (xy 444.08286 -37.861697)
			(xy 444.028915 -37.853943) (xy 443.976622 -37.838589) (xy 443.927047 -37.81595) (xy 443.881199 -37.786486)
			(xy 443.84001 -37.750797) (xy 443.80432 -37.709609) (xy 443.774854 -37.663762) (xy 443.752214 -37.614187)
			(xy 443.73686 -37.561895) (xy 443.729103 -37.50795) (xy 437.926342 -37.50795) (xy 437.935526 -37.510351)
			(xy 437.986855 -37.532163) (xy 438.034461 -37.561217) (xy 438.077329 -37.596892) (xy 438.114546 -37.638429)
			(xy 438.145319 -37.684942) (xy 438.168991 -37.735439) (xy 438.185059 -37.788846) (xy 438.193179 -37.844022)
			(xy 438.193688 -37.871908) (xy 438.193179 -37.899794) (xy 438.185059 -37.95497) (xy 438.168991 -38.008377)
			(xy 438.145319 -38.058874) (xy 438.114546 -38.105387) (xy 438.077329 -38.146924) (xy 438.034461 -38.182599)
			(xy 437.986855 -38.211653) (xy 437.935526 -38.233465) (xy 437.881569 -38.247571) (xy 437.826132 -38.253671)
			(xy 437.770398 -38.251634) (xy 437.715555 -38.241504) (xy 437.662771 -38.223497) (xy 437.613171 -38.197996)
			(xy 437.567813 -38.165545) (xy 437.527664 -38.126836) (xy 437.493578 -38.082693) (xy 437.466282 -38.034058)
			(xy 437.446359 -37.981967) (xy 437.434233 -37.92753) (xy 437.430162 -37.871908) (xy 436.531486 -37.871908)
			(xy 436.526439 -37.906202) (xy 436.510371 -37.959609) (xy 436.486699 -38.010106) (xy 436.455926 -38.056619)
			(xy 436.418709 -38.098156) (xy 436.375841 -38.133831) (xy 436.328235 -38.162885) (xy 436.276906 -38.184697)
			(xy 436.222949 -38.198803) (xy 436.167512 -38.204903) (xy 436.111778 -38.202866) (xy 436.056935 -38.192736)
			(xy 436.004151 -38.174729) (xy 435.954551 -38.149228) (xy 435.909193 -38.116777) (xy 435.869044 -38.078068)
			(xy 435.834958 -38.033925) (xy 435.807662 -37.98529) (xy 435.787739 -37.933199) (xy 435.775613 -37.878762)
			(xy 435.771542 -37.82314) (xy 429.538715 -37.82314) (xy 429.520416 -37.831877) (xy 429.440972 -37.861027)
			(xy 429.359147 -37.88261) (xy 429.27566 -37.896435) (xy 429.191246 -37.902382) (xy 429.106645 -37.900399)
			(xy 429.022603 -37.890501) (xy 428.939856 -37.872778) (xy 428.859132 -37.847384) (xy 428.781141 -37.814542)
			(xy 428.706569 -37.774541) (xy 428.636069 -37.727733) (xy 428.570263 -37.674529) (xy 428.509727 -37.615397)
			(xy 428.454995 -37.550856) (xy 428.406548 -37.481473) (xy 428.36481 -37.407858) (xy 428.330149 -37.330659)
			(xy 428.302869 -37.250553) (xy 428.283211 -37.168244) (xy 428.271346 -37.084457) (xy 428.26738 -36.999926)
			(xy 427.532292 -36.999926) (xy 427.531796 -37.042238) (xy 427.523872 -37.12649) (xy 427.508093 -37.209629)
			(xy 427.484598 -37.290926) (xy 427.453594 -37.369665) (xy 427.415352 -37.445155) (xy 427.37021 -37.516732)
			(xy 427.318563 -37.583768) (xy 427.260866 -37.645673) (xy 427.197626 -37.701903) (xy 427.129398 -37.751964)
			(xy 427.056782 -37.795416) (xy 426.980416 -37.831877) (xy 426.900972 -37.861027) (xy 426.819147 -37.88261)
			(xy 426.73566 -37.896435) (xy 426.651246 -37.902382) (xy 426.566645 -37.900399) (xy 426.482603 -37.890501)
			(xy 426.399856 -37.872778) (xy 426.319132 -37.847384) (xy 426.241141 -37.814542) (xy 426.166569 -37.774541)
			(xy 426.096069 -37.727733) (xy 426.030263 -37.674529) (xy 425.969727 -37.615397) (xy 425.914995 -37.550856)
			(xy 425.866548 -37.481473) (xy 425.82481 -37.407858) (xy 425.790149 -37.330659) (xy 425.762869 -37.250553)
			(xy 425.743211 -37.168244) (xy 425.731346 -37.084457) (xy 425.72738 -36.999926) (xy 417.156138 -36.999926)
			(xy 417.156138 -38.47315) (xy 439.233303 -38.47315) (xy 439.233303 -38.41865) (xy 439.24106 -38.364705)
			(xy 439.256414 -38.312413) (xy 439.279054 -38.262838) (xy 439.30852 -38.216991) (xy 439.34421 -38.175803)
			(xy 439.385399 -38.140114) (xy 439.431247 -38.11065) (xy 439.480822 -38.088011) (xy 439.533115 -38.072657)
			(xy 439.58706 -38.064903) (xy 439.61431 -38.06444) (xy 439.640981 -38.064852) (xy 439.693806 -38.072273)
			(xy 439.74508 -38.086982) (xy 439.793805 -38.108692) (xy 439.839029 -38.13698) (xy 439.87987 -38.171294)
			(xy 439.915532 -38.210965) (xy 439.930794 -38.232842) (xy 439.93915 -38.244325) (xy 439.960933 -38.26253)
			(xy 439.986881 -38.274046) (xy 440.014995 -38.277985) (xy 440.043109 -38.274046) (xy 440.069057 -38.26253)
			(xy 440.09084 -38.244325) (xy 440.099196 -38.232842) (xy 440.114455 -38.210965) (xy 440.150129 -38.171312)
			(xy 440.190976 -38.137011) (xy 440.236201 -38.108733) (xy 440.284923 -38.087026) (xy 440.336192 -38.072315)
			(xy 440.389011 -38.064886) (xy 440.41568 -38.06444) (xy 440.442937 -38.064806) (xy 440.496897 -38.072561)
			(xy 440.549204 -38.087917) (xy 440.598793 -38.110562) (xy 440.644654 -38.140033) (xy 440.685855 -38.175731)
			(xy 440.721555 -38.21693) (xy 440.751029 -38.262789) (xy 440.773676 -38.312377) (xy 440.789035 -38.364683)
			(xy 440.796793 -38.418643) (xy 440.796793 -38.473147) (xy 441.203126 -38.473147) (xy 441.203126 -38.418653)
			(xy 441.210881 -38.364714) (xy 441.226233 -38.312427) (xy 441.24887 -38.262858) (xy 441.278331 -38.217014)
			(xy 441.314016 -38.17583) (xy 441.355198 -38.140143) (xy 441.40104 -38.11068) (xy 441.450609 -38.08804)
			(xy 441.502894 -38.072685) (xy 441.556833 -38.064928) (xy 441.58408 -38.06444) (xy 441.611202 -38.06494)
			(xy 441.664901 -38.072614) (xy 441.716969 -38.087824) (xy 441.766354 -38.110263) (xy 441.812059 -38.139477)
			(xy 441.85316 -38.174876) (xy 441.871354 -38.194996) (xy 441.880514 -38.204826) (xy 441.902822 -38.219777)
			(xy 441.928263 -38.228381) (xy 441.955068 -38.230039) (xy 441.981375 -38.224636) (xy 442.005356 -38.212547)
			(xy 442.015626 -38.203886) (xy 442.036735 -38.185619) (xy 442.083271 -38.154791) (xy 442.133803 -38.131073)
			(xy 442.187252 -38.114974) (xy 442.242477 -38.106837) (xy 442.270388 -38.10635) (xy 442.297638 -38.106896)
			(xy 442.351585 -38.114651) (xy 442.403878 -38.130004) (xy 442.453454 -38.152644) (xy 442.499304 -38.182108)
			(xy 442.540494 -38.217798) (xy 442.576185 -38.258986) (xy 442.595458 -38.288976) (xy 452.814434 -38.288976)
			(xy 452.818505 -38.233354) (xy 452.830631 -38.178917) (xy 452.850554 -38.126826) (xy 452.87785 -38.078191)
			(xy 452.911936 -38.034048) (xy 452.952085 -37.995339) (xy 452.997443 -37.962888) (xy 453.047043 -37.937387)
			(xy 453.099827 -37.91938) (xy 453.15467 -37.90925) (xy 453.210404 -37.907213) (xy 453.265841 -37.913313)
			(xy 453.319798 -37.927419) (xy 453.371127 -37.949231) (xy 453.418733 -37.978285) (xy 453.461601 -38.01396)
			(xy 453.498818 -38.055497) (xy 453.529591 -38.10201) (xy 453.553263 -38.152507) (xy 453.569331 -38.205914)
			(xy 453.577451 -38.26109) (xy 453.57796 -38.288976) (xy 453.577451 -38.316862) (xy 453.569331 -38.372038)
			(xy 453.553263 -38.425445) (xy 453.529591 -38.475942) (xy 453.498818 -38.522455) (xy 453.461601 -38.563992)
			(xy 453.418733 -38.599667) (xy 453.371127 -38.628721) (xy 453.319798 -38.650533) (xy 453.265841 -38.664639)
			(xy 453.210404 -38.670739) (xy 453.15467 -38.668702) (xy 453.099827 -38.658572) (xy 453.047043 -38.640565)
			(xy 452.997443 -38.615064) (xy 452.952085 -38.582613) (xy 452.911936 -38.543904) (xy 452.87785 -38.499761)
			(xy 452.850554 -38.451126) (xy 452.830631 -38.399035) (xy 452.818505 -38.344598) (xy 452.814434 -38.288976)
			(xy 442.595458 -38.288976) (xy 442.60565 -38.304835) (xy 442.628291 -38.354411) (xy 442.643646 -38.406704)
			(xy 442.651403 -38.46065) (xy 442.651403 -38.51515) (xy 442.643646 -38.569096) (xy 442.628291 -38.621389)
			(xy 442.60565 -38.670965) (xy 442.576185 -38.716814) (xy 442.540494 -38.758002) (xy 442.499304 -38.793692)
			(xy 442.453454 -38.823156) (xy 442.403878 -38.845796) (xy 442.351585 -38.861149) (xy 442.297638 -38.868904)
			(xy 442.270388 -38.869366) (xy 442.243265 -38.868886) (xy 442.189566 -38.861208) (xy 442.137498 -38.845994)
			(xy 442.088112 -38.823551) (xy 442.042408 -38.794334) (xy 442.001307 -38.758932) (xy 441.983114 -38.73881)
			(xy 441.973985 -38.72895) (xy 441.951668 -38.713998) (xy 441.926219 -38.705398) (xy 441.899408 -38.703745)
			(xy 441.873096 -38.709156) (xy 441.849112 -38.721254) (xy 441.838842 -38.72992) (xy 441.817746 -38.748203)
			(xy 441.771207 -38.779029) (xy 441.720671 -38.802743) (xy 441.667219 -38.818838) (xy 441.611992 -38.826971)
			(xy 441.58408 -38.827456) (xy 441.556833 -38.826872) (xy 441.502894 -38.819115) (xy 441.450609 -38.80376)
			(xy 441.40104 -38.78112) (xy 441.355198 -38.751657) (xy 441.314016 -38.71597) (xy 441.278331 -38.674786)
			(xy 441.24887 -38.628942) (xy 441.226233 -38.579373) (xy 441.210881 -38.527086) (xy 441.203126 -38.473147)
			(xy 440.796793 -38.473147) (xy 440.796793 -38.473157) (xy 440.789035 -38.527117) (xy 440.773676 -38.579423)
			(xy 440.751029 -38.629011) (xy 440.721555 -38.67487) (xy 440.685855 -38.716069) (xy 440.644654 -38.751767)
			(xy 440.598793 -38.781238) (xy 440.549204 -38.803883) (xy 440.496897 -38.819239) (xy 440.442937 -38.826994)
			(xy 440.41568 -38.827456) (xy 440.389008 -38.827053) (xy 440.336184 -38.819631) (xy 440.284909 -38.804921)
			(xy 440.236184 -38.783209) (xy 440.19096 -38.754919) (xy 440.150119 -38.720604) (xy 440.114458 -38.680932)
			(xy 440.099196 -38.659054) (xy 440.090869 -38.647526) (xy 440.069108 -38.629236) (xy 440.043144 -38.617662)
			(xy 440.014995 -38.613701) (xy 439.986846 -38.617662) (xy 439.960882 -38.629236) (xy 439.939121 -38.647526)
			(xy 439.930794 -38.659054) (xy 439.91554 -38.680934) (xy 439.879866 -38.720588) (xy 439.839018 -38.754888)
			(xy 439.793792 -38.783167) (xy 439.745069 -38.804873) (xy 439.693799 -38.819583) (xy 439.64098 -38.827011)
			(xy 439.61431 -38.827456) (xy 439.58706 -38.826897) (xy 439.533115 -38.819143) (xy 439.480822 -38.803789)
			(xy 439.431247 -38.78115) (xy 439.385399 -38.751686) (xy 439.34421 -38.715997) (xy 439.30852 -38.674809)
			(xy 439.279054 -38.628962) (xy 439.256414 -38.579387) (xy 439.24106 -38.527095) (xy 439.233303 -38.47315)
			(xy 417.156138 -38.47315) (xy 417.156138 -39.539926) (xy 425.72738 -39.539926) (xy 425.731346 -39.455395)
			(xy 425.743211 -39.371608) (xy 425.762869 -39.289299) (xy 425.790149 -39.209193) (xy 425.82481 -39.131994)
			(xy 425.866548 -39.058379) (xy 425.914995 -38.988996) (xy 425.969727 -38.924455) (xy 426.030263 -38.865323)
			(xy 426.096069 -38.812119) (xy 426.166569 -38.765311) (xy 426.241141 -38.72531) (xy 426.319132 -38.692468)
			(xy 426.399856 -38.667074) (xy 426.482603 -38.649351) (xy 426.566645 -38.639453) (xy 426.651246 -38.63747)
			(xy 426.73566 -38.643417) (xy 426.819147 -38.657242) (xy 426.900972 -38.678825) (xy 426.980416 -38.707975)
			(xy 427.056782 -38.744436) (xy 427.129398 -38.787888) (xy 427.197626 -38.837949) (xy 427.260866 -38.894179)
			(xy 427.318563 -38.956084) (xy 427.37021 -39.02312) (xy 427.415352 -39.094697) (xy 427.453594 -39.170187)
			(xy 427.484598 -39.248926) (xy 427.508093 -39.330223) (xy 427.523872 -39.413362) (xy 427.531796 -39.497614)
			(xy 427.532292 -39.539926) (xy 428.26738 -39.539926) (xy 428.271346 -39.455395) (xy 428.283211 -39.371608)
			(xy 428.302869 -39.289299) (xy 428.330149 -39.209193) (xy 428.36481 -39.131994) (xy 428.406548 -39.058379)
			(xy 428.454995 -38.988996) (xy 428.509727 -38.924455) (xy 428.570263 -38.865323) (xy 428.636069 -38.812119)
			(xy 428.706569 -38.765311) (xy 428.781141 -38.72531) (xy 428.859132 -38.692468) (xy 428.939856 -38.667074)
			(xy 429.022603 -38.649351) (xy 429.106645 -38.639453) (xy 429.191246 -38.63747) (xy 429.27566 -38.643417)
			(xy 429.359147 -38.657242) (xy 429.440972 -38.678825) (xy 429.520416 -38.707975) (xy 429.596782 -38.744436)
			(xy 429.669398 -38.787888) (xy 429.737626 -38.837949) (xy 429.800866 -38.894179) (xy 429.809225 -38.903148)
			(xy 451.819262 -38.903148) (xy 451.823333 -38.847526) (xy 451.835459 -38.793089) (xy 451.855382 -38.740998)
			(xy 451.882678 -38.692363) (xy 451.916764 -38.64822) (xy 451.956913 -38.609511) (xy 452.002271 -38.57706)
			(xy 452.051871 -38.551559) (xy 452.104655 -38.533552) (xy 452.159498 -38.523422) (xy 452.215232 -38.521385)
			(xy 452.270669 -38.527485) (xy 452.324626 -38.541591) (xy 452.375955 -38.563403) (xy 452.423561 -38.592457)
			(xy 452.466429 -38.628132) (xy 452.503646 -38.669669) (xy 452.534419 -38.716182) (xy 452.558091 -38.766679)
			(xy 452.574159 -38.820086) (xy 452.582279 -38.875262) (xy 452.582788 -38.903148) (xy 452.582279 -38.931034)
			(xy 452.574159 -38.98621) (xy 452.558091 -39.039617) (xy 452.534419 -39.090114) (xy 452.503646 -39.136627)
			(xy 452.490453 -39.151351) (xy 457.635583 -39.151351) (xy 457.635583 -39.096849) (xy 457.64334 -39.042901)
			(xy 457.658695 -38.990606) (xy 457.681337 -38.941029) (xy 457.710804 -38.895179) (xy 457.746496 -38.853989)
			(xy 457.787687 -38.818298) (xy 457.833538 -38.788832) (xy 457.883115 -38.766192) (xy 457.935411 -38.750838)
			(xy 457.989359 -38.743083) (xy 458.01661 -38.74262) (xy 458.043215 -38.743052) (xy 458.095909 -38.750436)
			(xy 458.147065 -38.765072) (xy 458.195691 -38.786678) (xy 458.240841 -38.814832) (xy 458.281639 -38.848989)
			(xy 458.317294 -38.888485) (xy 458.332586 -38.91026) (xy 458.34092 -38.92174) (xy 458.362664 -38.939944)
			(xy 458.388577 -38.951462) (xy 458.41666 -38.955402) (xy 458.444743 -38.951462) (xy 458.470656 -38.939944)
			(xy 458.4924 -38.92174) (xy 458.500734 -38.91026) (xy 458.516836 -38.887355) (xy 458.554639 -38.846056)
			(xy 458.598077 -38.810732) (xy 458.646216 -38.782144) (xy 458.67193 -38.771068) (xy 458.685302 -38.765069)
			(xy 458.708126 -38.746699) (xy 458.724798 -38.722608) (xy 458.73395 -38.694776) (xy 458.734829 -38.665491)
			(xy 458.727362 -38.637161) (xy 458.712164 -38.612113) (xy 458.701648 -38.601904) (xy 458.682278 -38.583713)
			(xy 458.648222 -38.542923) (xy 458.620152 -38.497806) (xy 458.598608 -38.449232) (xy 458.584008 -38.39814)
			(xy 458.576634 -38.345517) (xy 458.576172 -38.318948) (xy 458.576658 -38.291697) (xy 458.584414 -38.237749)
			(xy 458.599769 -38.185454) (xy 458.622411 -38.135877) (xy 458.651877 -38.090027) (xy 458.687568 -38.048836)
			(xy 458.728759 -38.013145) (xy 458.774609 -37.983679) (xy 458.824186 -37.961037) (xy 458.876481 -37.945682)
			(xy 458.930429 -37.937926) (xy 458.984931 -37.937926) (xy 459.038879 -37.945682) (xy 459.091174 -37.961037)
			(xy 459.140751 -37.983679) (xy 459.186601 -38.013145) (xy 459.227792 -38.048836) (xy 459.263483 -38.090027)
			(xy 459.292949 -38.135877) (xy 459.315591 -38.185454) (xy 459.330946 -38.237749) (xy 459.338702 -38.291697)
			(xy 459.339188 -38.318948) (xy 459.338658 -38.347136) (xy 459.330347 -38.402897) (xy 459.313929 -38.456831)
			(xy 459.289759 -38.507764) (xy 459.258364 -38.55459) (xy 459.220426 -38.596291) (xy 459.176768 -38.631962)
			(xy 459.128341 -38.660826) (xy 459.10246 -38.672008) (xy 459.089105 -38.678039) (xy 459.066286 -38.696405)
			(xy 459.049615 -38.72049) (xy 459.040463 -38.748314) (xy 459.03958 -38.777592) (xy 459.04704 -38.805918)
			(xy 459.06223 -38.830963) (xy 459.072742 -38.841172) (xy 459.092147 -38.859327) (xy 459.1262 -38.900124)
			(xy 459.154266 -38.945249) (xy 459.175804 -38.993831) (xy 459.190396 -39.044929) (xy 459.197761 -39.097557)
			(xy 459.198218 -39.124128) (xy 459.197748 -39.151379) (xy 459.189988 -39.205327) (xy 459.17463 -39.257622)
			(xy 459.151986 -39.307198) (xy 459.122518 -39.353048) (xy 459.086825 -39.394238) (xy 459.045634 -39.429929)
			(xy 458.999783 -39.459395) (xy 458.95359 -39.48049) (xy 460.205072 -39.48049) (xy 460.209143 -39.424868)
			(xy 460.221269 -39.370431) (xy 460.241192 -39.31834) (xy 460.268488 -39.269705) (xy 460.302574 -39.225562)
			(xy 460.342723 -39.186853) (xy 460.388081 -39.154402) (xy 460.437681 -39.128901) (xy 460.490465 -39.110894)
			(xy 460.545308 -39.100764) (xy 460.601042 -39.098727) (xy 460.656479 -39.104827) (xy 460.710436 -39.118933)
			(xy 460.761765 -39.140745) (xy 460.809371 -39.169799) (xy 460.852239 -39.205474) (xy 460.889456 -39.247011)
			(xy 460.920229 -39.293524) (xy 460.943901 -39.344021) (xy 460.959969 -39.397428) (xy 460.968089 -39.452604)
			(xy 460.968598 -39.48049) (xy 460.968089 -39.508376) (xy 460.959969 -39.563552) (xy 460.943901 -39.616959)
			(xy 460.920229 -39.667456) (xy 460.889456 -39.713969) (xy 460.852239 -39.755506) (xy 460.809371 -39.791181)
			(xy 460.761765 -39.820235) (xy 460.710436 -39.842047) (xy 460.656479 -39.856153) (xy 460.601042 -39.862253)
			(xy 460.545308 -39.860216) (xy 460.490465 -39.850086) (xy 460.437681 -39.832079) (xy 460.388081 -39.806578)
			(xy 460.342723 -39.774127) (xy 460.302574 -39.735418) (xy 460.268488 -39.691275) (xy 460.241192 -39.64264)
			(xy 460.221269 -39.590549) (xy 460.209143 -39.536112) (xy 460.205072 -39.48049) (xy 458.95359 -39.48049)
			(xy 458.950205 -39.482036) (xy 458.89791 -39.497392) (xy 458.843962 -39.50515) (xy 458.81671 -39.505636)
			(xy 458.790105 -39.505208) (xy 458.73741 -39.497826) (xy 458.686252 -39.48319) (xy 458.637626 -39.461585)
			(xy 458.592476 -39.43343) (xy 458.551678 -39.399271) (xy 458.516025 -39.359772) (xy 458.500734 -39.337996)
			(xy 458.4924 -39.326516) (xy 458.470656 -39.308312) (xy 458.444743 -39.296794) (xy 458.41666 -39.292854)
			(xy 458.388577 -39.296794) (xy 458.362664 -39.308312) (xy 458.34092 -39.326516) (xy 458.332586 -39.337996)
			(xy 458.317323 -39.35979) (xy 458.28165 -39.399267) (xy 458.240841 -39.433407) (xy 458.195685 -39.461549)
			(xy 458.147059 -39.483148) (xy 458.095905 -39.497784) (xy 458.043214 -39.505174) (xy 458.01661 -39.505636)
			(xy 457.989359 -39.505117) (xy 457.935411 -39.497362) (xy 457.883115 -39.482008) (xy 457.833538 -39.459368)
			(xy 457.787687 -39.429902) (xy 457.746496 -39.394211) (xy 457.710804 -39.353021) (xy 457.681337 -39.307171)
			(xy 457.658695 -39.257594) (xy 457.64334 -39.205299) (xy 457.635583 -39.151351) (xy 452.490453 -39.151351)
			(xy 452.466429 -39.178164) (xy 452.423561 -39.213839) (xy 452.375955 -39.242893) (xy 452.324626 -39.264705)
			(xy 452.270669 -39.278811) (xy 452.215232 -39.284911) (xy 452.159498 -39.282874) (xy 452.104655 -39.272744)
			(xy 452.051871 -39.254737) (xy 452.002271 -39.229236) (xy 451.956913 -39.196785) (xy 451.916764 -39.158076)
			(xy 451.882678 -39.113933) (xy 451.855382 -39.065298) (xy 451.835459 -39.013207) (xy 451.823333 -38.95877)
			(xy 451.819262 -38.903148) (xy 429.809225 -38.903148) (xy 429.858563 -38.956084) (xy 429.91021 -39.02312)
			(xy 429.955352 -39.094697) (xy 429.993594 -39.170187) (xy 430.024598 -39.248926) (xy 430.044173 -39.31666)
			(xy 435.019702 -39.31666) (xy 435.023773 -39.261038) (xy 435.035899 -39.206601) (xy 435.055822 -39.15451)
			(xy 435.083118 -39.105875) (xy 435.117204 -39.061732) (xy 435.157353 -39.023023) (xy 435.202711 -38.990572)
			(xy 435.252311 -38.965071) (xy 435.305095 -38.947064) (xy 435.359938 -38.936934) (xy 435.415672 -38.934897)
			(xy 435.471109 -38.940997) (xy 435.525066 -38.955103) (xy 435.576395 -38.976915) (xy 435.624001 -39.005969)
			(xy 435.666869 -39.041644) (xy 435.704086 -39.083181) (xy 435.734859 -39.129694) (xy 435.758531 -39.180191)
			(xy 435.774599 -39.233598) (xy 435.782719 -39.288774) (xy 435.783228 -39.31666) (xy 435.782719 -39.344546)
			(xy 435.774599 -39.399722) (xy 435.758531 -39.453129) (xy 435.734859 -39.503626) (xy 435.704086 -39.550139)
			(xy 435.666869 -39.591676) (xy 435.624001 -39.627351) (xy 435.576395 -39.656405) (xy 435.525066 -39.678217)
			(xy 435.471109 -39.692323) (xy 435.415672 -39.698423) (xy 435.359938 -39.696386) (xy 435.305095 -39.686256)
			(xy 435.252311 -39.668249) (xy 435.202711 -39.642748) (xy 435.157353 -39.610297) (xy 435.117204 -39.571588)
			(xy 435.083118 -39.527445) (xy 435.055822 -39.47881) (xy 435.035899 -39.426719) (xy 435.023773 -39.372282)
			(xy 435.019702 -39.31666) (xy 430.044173 -39.31666) (xy 430.048093 -39.330223) (xy 430.063872 -39.413362)
			(xy 430.071796 -39.497614) (xy 430.072292 -39.539926) (xy 430.071796 -39.582238) (xy 430.063872 -39.66649)
			(xy 430.048093 -39.749629) (xy 430.024598 -39.830926) (xy 429.993594 -39.909665) (xy 429.955352 -39.985155)
			(xy 429.91021 -40.056732) (xy 429.858563 -40.123768) (xy 429.800866 -40.185673) (xy 429.737626 -40.241903)
			(xy 429.669398 -40.291964) (xy 429.596782 -40.335416) (xy 429.520416 -40.371877) (xy 429.454236 -40.39616)
			(xy 436.017922 -40.39616) (xy 436.021993 -40.340538) (xy 436.034119 -40.286101) (xy 436.054042 -40.23401)
			(xy 436.081338 -40.185375) (xy 436.115424 -40.141232) (xy 436.155573 -40.102523) (xy 436.200931 -40.070072)
			(xy 436.250531 -40.044571) (xy 436.303315 -40.026564) (xy 436.358158 -40.016434) (xy 436.413892 -40.014397)
			(xy 436.469329 -40.020497) (xy 436.523286 -40.034603) (xy 436.574615 -40.056415) (xy 436.622221 -40.085469)
			(xy 436.665089 -40.121144) (xy 436.702306 -40.162681) (xy 436.733079 -40.209194) (xy 436.756751 -40.259691)
			(xy 436.772819 -40.313098) (xy 436.778613 -40.352472) (xy 462.789014 -40.352472) (xy 462.793085 -40.29685)
			(xy 462.805211 -40.242413) (xy 462.825134 -40.190322) (xy 462.85243 -40.141687) (xy 462.886516 -40.097544)
			(xy 462.926665 -40.058835) (xy 462.972023 -40.026384) (xy 463.021623 -40.000883) (xy 463.074407 -39.982876)
			(xy 463.12925 -39.972746) (xy 463.184984 -39.970709) (xy 463.240421 -39.976809) (xy 463.294378 -39.990915)
			(xy 463.345707 -40.012727) (xy 463.393313 -40.041781) (xy 463.436181 -40.077456) (xy 463.473398 -40.118993)
			(xy 463.504171 -40.165506) (xy 463.527843 -40.216003) (xy 463.543911 -40.26941) (xy 463.552031 -40.324586)
			(xy 463.55254 -40.352472) (xy 463.552031 -40.380358) (xy 463.543911 -40.435534) (xy 463.527843 -40.488941)
			(xy 463.504171 -40.539438) (xy 463.473398 -40.585951) (xy 463.436181 -40.627488) (xy 463.393313 -40.663163)
			(xy 463.345707 -40.692217) (xy 463.294378 -40.714029) (xy 463.240421 -40.728135) (xy 463.184984 -40.734235)
			(xy 463.12925 -40.732198) (xy 463.074407 -40.722068) (xy 463.021623 -40.704061) (xy 462.972023 -40.67856)
			(xy 462.926665 -40.646109) (xy 462.886516 -40.6074) (xy 462.85243 -40.563257) (xy 462.825134 -40.514622)
			(xy 462.805211 -40.462531) (xy 462.793085 -40.408094) (xy 462.789014 -40.352472) (xy 436.778613 -40.352472)
			(xy 436.780939 -40.368274) (xy 436.781448 -40.39616) (xy 436.780939 -40.424046) (xy 436.772819 -40.479222)
			(xy 436.756751 -40.532629) (xy 436.733079 -40.583126) (xy 436.702306 -40.629639) (xy 436.665089 -40.671176)
			(xy 436.622221 -40.706851) (xy 436.574615 -40.735905) (xy 436.523286 -40.757717) (xy 436.469329 -40.771823)
			(xy 436.413892 -40.777923) (xy 436.358158 -40.775886) (xy 436.303315 -40.765756) (xy 436.250531 -40.747749)
			(xy 436.200931 -40.722248) (xy 436.155573 -40.689797) (xy 436.115424 -40.651088) (xy 436.081338 -40.606945)
			(xy 436.054042 -40.55831) (xy 436.034119 -40.506219) (xy 436.021993 -40.451782) (xy 436.017922 -40.39616)
			(xy 429.454236 -40.39616) (xy 429.440972 -40.401027) (xy 429.359147 -40.42261) (xy 429.27566 -40.436435)
			(xy 429.191246 -40.442382) (xy 429.106645 -40.440399) (xy 429.022603 -40.430501) (xy 428.939856 -40.412778)
			(xy 428.859132 -40.387384) (xy 428.781141 -40.354542) (xy 428.706569 -40.314541) (xy 428.636069 -40.267733)
			(xy 428.570263 -40.214529) (xy 428.509727 -40.155397) (xy 428.454995 -40.090856) (xy 428.406548 -40.021473)
			(xy 428.36481 -39.947858) (xy 428.330149 -39.870659) (xy 428.302869 -39.790553) (xy 428.283211 -39.708244)
			(xy 428.271346 -39.624457) (xy 428.26738 -39.539926) (xy 427.532292 -39.539926) (xy 427.531796 -39.582238)
			(xy 427.523872 -39.66649) (xy 427.508093 -39.749629) (xy 427.484598 -39.830926) (xy 427.453594 -39.909665)
			(xy 427.415352 -39.985155) (xy 427.37021 -40.056732) (xy 427.318563 -40.123768) (xy 427.260866 -40.185673)
			(xy 427.197626 -40.241903) (xy 427.129398 -40.291964) (xy 427.056782 -40.335416) (xy 426.980416 -40.371877)
			(xy 426.900972 -40.401027) (xy 426.819147 -40.42261) (xy 426.73566 -40.436435) (xy 426.651246 -40.442382)
			(xy 426.566645 -40.440399) (xy 426.482603 -40.430501) (xy 426.399856 -40.412778) (xy 426.319132 -40.387384)
			(xy 426.241141 -40.354542) (xy 426.166569 -40.314541) (xy 426.096069 -40.267733) (xy 426.030263 -40.214529)
			(xy 425.969727 -40.155397) (xy 425.914995 -40.090856) (xy 425.866548 -40.021473) (xy 425.82481 -39.947858)
			(xy 425.790149 -39.870659) (xy 425.762869 -39.790553) (xy 425.743211 -39.708244) (xy 425.731346 -39.624457)
			(xy 425.72738 -39.539926) (xy 417.156138 -39.539926) (xy 417.156138 -42.079926) (xy 425.72738 -42.079926)
			(xy 425.731346 -41.995395) (xy 425.743211 -41.911608) (xy 425.762869 -41.829299) (xy 425.790149 -41.749193)
			(xy 425.82481 -41.671994) (xy 425.866548 -41.598379) (xy 425.914995 -41.528996) (xy 425.969727 -41.464455)
			(xy 426.030263 -41.405323) (xy 426.096069 -41.352119) (xy 426.166569 -41.305311) (xy 426.241141 -41.26531)
			(xy 426.319132 -41.232468) (xy 426.399856 -41.207074) (xy 426.482603 -41.189351) (xy 426.566645 -41.179453)
			(xy 426.651246 -41.17747) (xy 426.73566 -41.183417) (xy 426.819147 -41.197242) (xy 426.900972 -41.218825)
			(xy 426.980416 -41.247975) (xy 427.056782 -41.284436) (xy 427.129398 -41.327888) (xy 427.197626 -41.377949)
			(xy 427.260866 -41.434179) (xy 427.318563 -41.496084) (xy 427.37021 -41.56312) (xy 427.415352 -41.634697)
			(xy 427.453594 -41.710187) (xy 427.484598 -41.788926) (xy 427.508093 -41.870223) (xy 427.523872 -41.953362)
			(xy 427.531796 -42.037614) (xy 427.532292 -42.079926) (xy 428.26738 -42.079926) (xy 428.271346 -41.995395)
			(xy 428.283211 -41.911608) (xy 428.302869 -41.829299) (xy 428.330149 -41.749193) (xy 428.36481 -41.671994)
			(xy 428.406548 -41.598379) (xy 428.454995 -41.528996) (xy 428.509727 -41.464455) (xy 428.570263 -41.405323)
			(xy 428.636069 -41.352119) (xy 428.706569 -41.305311) (xy 428.781141 -41.26531) (xy 428.859132 -41.232468)
			(xy 428.939856 -41.207074) (xy 429.022603 -41.189351) (xy 429.106645 -41.179453) (xy 429.191246 -41.17747)
			(xy 429.27566 -41.183417) (xy 429.359147 -41.197242) (xy 429.440972 -41.218825) (xy 429.520416 -41.247975)
			(xy 429.596782 -41.284436) (xy 429.669398 -41.327888) (xy 429.737626 -41.377949) (xy 429.750392 -41.3893)
			(xy 436.378602 -41.3893) (xy 436.382673 -41.333678) (xy 436.394799 -41.279241) (xy 436.414722 -41.22715)
			(xy 436.442018 -41.178515) (xy 436.476104 -41.134372) (xy 436.516253 -41.095663) (xy 436.561611 -41.063212)
			(xy 436.611211 -41.037711) (xy 436.663995 -41.019704) (xy 436.718838 -41.009574) (xy 436.774572 -41.007537)
			(xy 436.816132 -41.01211) (xy 456.138278 -41.01211) (xy 456.142349 -40.956488) (xy 456.154475 -40.902051)
			(xy 456.174398 -40.84996) (xy 456.201694 -40.801325) (xy 456.23578 -40.757182) (xy 456.275929 -40.718473)
			(xy 456.321287 -40.686022) (xy 456.370887 -40.660521) (xy 456.423671 -40.642514) (xy 456.478514 -40.632384)
			(xy 456.534248 -40.630347) (xy 456.589685 -40.636447) (xy 456.643642 -40.650553) (xy 456.694971 -40.672365)
			(xy 456.742577 -40.701419) (xy 456.785445 -40.737094) (xy 456.822662 -40.778631) (xy 456.853435 -40.825144)
			(xy 456.877107 -40.875641) (xy 456.893175 -40.929048) (xy 456.901295 -40.984224) (xy 456.901804 -41.01211)
			(xy 456.901295 -41.039996) (xy 456.893175 -41.095172) (xy 456.877107 -41.148579) (xy 456.853435 -41.199076)
			(xy 456.822662 -41.245589) (xy 456.785445 -41.287126) (xy 456.742577 -41.322801) (xy 456.694971 -41.351855)
			(xy 456.643642 -41.373667) (xy 456.589685 -41.387773) (xy 456.534248 -41.393873) (xy 456.478514 -41.391836)
			(xy 456.423671 -41.381706) (xy 456.370887 -41.363699) (xy 456.321287 -41.338198) (xy 456.275929 -41.305747)
			(xy 456.23578 -41.267038) (xy 456.201694 -41.222895) (xy 456.174398 -41.17426) (xy 456.154475 -41.122169)
			(xy 456.142349 -41.067732) (xy 456.138278 -41.01211) (xy 436.816132 -41.01211) (xy 436.830009 -41.013637)
			(xy 436.883966 -41.027743) (xy 436.935295 -41.049555) (xy 436.982901 -41.078609) (xy 437.025769 -41.114284)
			(xy 437.062986 -41.155821) (xy 437.093759 -41.202334) (xy 437.117431 -41.252831) (xy 437.133499 -41.306238)
			(xy 437.141619 -41.361414) (xy 437.142128 -41.3893) (xy 437.141619 -41.417186) (xy 437.133499 -41.472362)
			(xy 437.117431 -41.525769) (xy 437.093759 -41.576266) (xy 437.062986 -41.622779) (xy 437.036406 -41.652444)
			(xy 459.570072 -41.652444) (xy 459.574143 -41.596822) (xy 459.586269 -41.542385) (xy 459.606192 -41.490294)
			(xy 459.633488 -41.441659) (xy 459.667574 -41.397516) (xy 459.707723 -41.358807) (xy 459.753081 -41.326356)
			(xy 459.802681 -41.300855) (xy 459.855465 -41.282848) (xy 459.910308 -41.272718) (xy 459.966042 -41.270681)
			(xy 460.021479 -41.276781) (xy 460.075436 -41.290887) (xy 460.126765 -41.312699) (xy 460.174371 -41.341753)
			(xy 460.217239 -41.377428) (xy 460.254456 -41.418965) (xy 460.285229 -41.465478) (xy 460.308901 -41.515975)
			(xy 460.324969 -41.569382) (xy 460.333089 -41.624558) (xy 460.333598 -41.652444) (xy 460.333089 -41.68033)
			(xy 460.324969 -41.735506) (xy 460.308901 -41.788913) (xy 460.285229 -41.83941) (xy 460.254456 -41.885923)
			(xy 460.217239 -41.92746) (xy 460.174371 -41.963135) (xy 460.126765 -41.992189) (xy 460.075436 -42.014001)
			(xy 460.021479 -42.028107) (xy 459.966042 -42.034207) (xy 459.910308 -42.03217) (xy 459.855465 -42.02204)
			(xy 459.802681 -42.004033) (xy 459.753081 -41.978532) (xy 459.707723 -41.946081) (xy 459.667574 -41.907372)
			(xy 459.633488 -41.863229) (xy 459.606192 -41.814594) (xy 459.586269 -41.762503) (xy 459.574143 -41.708066)
			(xy 459.570072 -41.652444) (xy 437.036406 -41.652444) (xy 437.025769 -41.664316) (xy 436.982901 -41.699991)
			(xy 436.935295 -41.729045) (xy 436.883966 -41.750857) (xy 436.830009 -41.764963) (xy 436.774572 -41.771063)
			(xy 436.718838 -41.769026) (xy 436.663995 -41.758896) (xy 436.611211 -41.740889) (xy 436.561611 -41.715388)
			(xy 436.516253 -41.682937) (xy 436.476104 -41.644228) (xy 436.442018 -41.600085) (xy 436.414722 -41.55145)
			(xy 436.394799 -41.499359) (xy 436.382673 -41.444922) (xy 436.378602 -41.3893) (xy 429.750392 -41.3893)
			(xy 429.800866 -41.434179) (xy 429.858563 -41.496084) (xy 429.91021 -41.56312) (xy 429.955352 -41.634697)
			(xy 429.993594 -41.710187) (xy 430.024598 -41.788926) (xy 430.048093 -41.870223) (xy 430.063872 -41.953362)
			(xy 430.071796 -42.037614) (xy 430.072292 -42.079926) (xy 430.071796 -42.122238) (xy 430.070042 -42.140886)
			(xy 435.893208 -42.140886) (xy 435.897279 -42.085264) (xy 435.909405 -42.030827) (xy 435.929328 -41.978736)
			(xy 435.956624 -41.930101) (xy 435.99071 -41.885958) (xy 436.030859 -41.847249) (xy 436.076217 -41.814798)
			(xy 436.125817 -41.789297) (xy 436.178601 -41.77129) (xy 436.233444 -41.76116) (xy 436.289178 -41.759123)
			(xy 436.344615 -41.765223) (xy 436.398572 -41.779329) (xy 436.449901 -41.801141) (xy 436.497507 -41.830195)
			(xy 436.540375 -41.86587) (xy 436.577592 -41.907407) (xy 436.608365 -41.95392) (xy 436.632037 -42.004417)
			(xy 436.648105 -42.057824) (xy 436.656225 -42.113) (xy 436.656734 -42.140886) (xy 436.656225 -42.168772)
			(xy 436.648105 -42.223948) (xy 436.632037 -42.277355) (xy 436.608365 -42.327852) (xy 436.577592 -42.374365)
			(xy 436.569902 -42.382948) (xy 447.530472 -42.382948) (xy 447.534543 -42.327326) (xy 447.546669 -42.272889)
			(xy 447.566592 -42.220798) (xy 447.593888 -42.172163) (xy 447.627974 -42.12802) (xy 447.668123 -42.089311)
			(xy 447.713481 -42.05686) (xy 447.763081 -42.031359) (xy 447.815865 -42.013352) (xy 447.870708 -42.003222)
			(xy 447.926442 -42.001185) (xy 447.981879 -42.007285) (xy 448.035836 -42.021391) (xy 448.087165 -42.043203)
			(xy 448.134771 -42.072257) (xy 448.177639 -42.107932) (xy 448.214856 -42.149469) (xy 448.245629 -42.195982)
			(xy 448.261595 -42.23004) (xy 448.812664 -42.23004) (xy 448.816735 -42.174418) (xy 448.828861 -42.119981)
			(xy 448.848784 -42.06789) (xy 448.87608 -42.019255) (xy 448.910166 -41.975112) (xy 448.950315 -41.936403)
			(xy 448.995673 -41.903952) (xy 449.045273 -41.878451) (xy 449.098057 -41.860444) (xy 449.1529 -41.850314)
			(xy 449.208634 -41.848277) (xy 449.264071 -41.854377) (xy 449.318028 -41.868483) (xy 449.369357 -41.890295)
			(xy 449.416963 -41.919349) (xy 449.459831 -41.955024) (xy 449.497048 -41.996561) (xy 449.527821 -42.043074)
			(xy 449.551493 -42.093571) (xy 449.567561 -42.146978) (xy 449.575681 -42.202154) (xy 449.57619 -42.23004)
			(xy 449.575681 -42.257926) (xy 449.567561 -42.313102) (xy 449.551493 -42.366509) (xy 449.527821 -42.417006)
			(xy 449.497048 -42.463519) (xy 449.459831 -42.505056) (xy 449.444796 -42.517568) (xy 450.455282 -42.517568)
			(xy 450.459353 -42.461946) (xy 450.471479 -42.407509) (xy 450.491402 -42.355418) (xy 450.518698 -42.306783)
			(xy 450.552784 -42.26264) (xy 450.592933 -42.223931) (xy 450.638291 -42.19148) (xy 450.687891 -42.165979)
			(xy 450.740675 -42.147972) (xy 450.795518 -42.137842) (xy 450.851252 -42.135805) (xy 450.906689 -42.141905)
			(xy 450.960646 -42.156011) (xy 451.011975 -42.177823) (xy 451.059581 -42.206877) (xy 451.102449 -42.242552)
			(xy 451.139666 -42.284089) (xy 451.170439 -42.330602) (xy 451.194111 -42.381099) (xy 451.210179 -42.434506)
			(xy 451.218299 -42.489682) (xy 451.218808 -42.517568) (xy 451.218299 -42.545454) (xy 451.210179 -42.60063)
			(xy 451.194111 -42.654037) (xy 451.170439 -42.704534) (xy 451.139666 -42.751047) (xy 451.102449 -42.792584)
			(xy 451.059581 -42.828259) (xy 451.011975 -42.857313) (xy 450.960646 -42.879125) (xy 450.906689 -42.893231)
			(xy 450.851252 -42.899331) (xy 450.795518 -42.897294) (xy 450.740675 -42.887164) (xy 450.687891 -42.869157)
			(xy 450.638291 -42.843656) (xy 450.592933 -42.811205) (xy 450.552784 -42.772496) (xy 450.518698 -42.728353)
			(xy 450.491402 -42.679718) (xy 450.471479 -42.627627) (xy 450.459353 -42.57319) (xy 450.455282 -42.517568)
			(xy 449.444796 -42.517568) (xy 449.416963 -42.540731) (xy 449.369357 -42.569785) (xy 449.318028 -42.591597)
			(xy 449.264071 -42.605703) (xy 449.208634 -42.611803) (xy 449.1529 -42.609766) (xy 449.098057 -42.599636)
			(xy 449.045273 -42.581629) (xy 448.995673 -42.556128) (xy 448.950315 -42.523677) (xy 448.910166 -42.484968)
			(xy 448.87608 -42.440825) (xy 448.848784 -42.39219) (xy 448.828861 -42.340099) (xy 448.816735 -42.285662)
			(xy 448.812664 -42.23004) (xy 448.261595 -42.23004) (xy 448.269301 -42.246479) (xy 448.285369 -42.299886)
			(xy 448.293489 -42.355062) (xy 448.293998 -42.382948) (xy 448.293489 -42.410834) (xy 448.285369 -42.46601)
			(xy 448.269301 -42.519417) (xy 448.245629 -42.569914) (xy 448.214856 -42.616427) (xy 448.177639 -42.657964)
			(xy 448.134771 -42.693639) (xy 448.087165 -42.722693) (xy 448.035836 -42.744505) (xy 447.981879 -42.758611)
			(xy 447.926442 -42.764711) (xy 447.870708 -42.762674) (xy 447.815865 -42.752544) (xy 447.763081 -42.734537)
			(xy 447.713481 -42.709036) (xy 447.668123 -42.676585) (xy 447.627974 -42.637876) (xy 447.593888 -42.593733)
			(xy 447.566592 -42.545098) (xy 447.546669 -42.493007) (xy 447.534543 -42.43857) (xy 447.530472 -42.382948)
			(xy 436.569902 -42.382948) (xy 436.540375 -42.415902) (xy 436.497507 -42.451577) (xy 436.449901 -42.480631)
			(xy 436.398572 -42.502443) (xy 436.344615 -42.516549) (xy 436.289178 -42.522649) (xy 436.233444 -42.520612)
			(xy 436.178601 -42.510482) (xy 436.125817 -42.492475) (xy 436.076217 -42.466974) (xy 436.030859 -42.434523)
			(xy 435.99071 -42.395814) (xy 435.956624 -42.351671) (xy 435.929328 -42.303036) (xy 435.909405 -42.250945)
			(xy 435.897279 -42.196508) (xy 435.893208 -42.140886) (xy 430.070042 -42.140886) (xy 430.063872 -42.20649)
			(xy 430.048093 -42.289629) (xy 430.024598 -42.370926) (xy 429.993594 -42.449665) (xy 429.955352 -42.525155)
			(xy 429.91021 -42.596732) (xy 429.858563 -42.663768) (xy 429.800866 -42.725673) (xy 429.737626 -42.781903)
			(xy 429.669398 -42.831964) (xy 429.596782 -42.875416) (xy 429.520416 -42.911877) (xy 429.440972 -42.941027)
			(xy 429.359147 -42.96261) (xy 429.27566 -42.976435) (xy 429.191246 -42.982382) (xy 429.106645 -42.980399)
			(xy 429.022603 -42.970501) (xy 428.939856 -42.952778) (xy 428.859132 -42.927384) (xy 428.781141 -42.894542)
			(xy 428.706569 -42.854541) (xy 428.636069 -42.807733) (xy 428.570263 -42.754529) (xy 428.509727 -42.695397)
			(xy 428.454995 -42.630856) (xy 428.406548 -42.561473) (xy 428.36481 -42.487858) (xy 428.330149 -42.410659)
			(xy 428.302869 -42.330553) (xy 428.283211 -42.248244) (xy 428.271346 -42.164457) (xy 428.26738 -42.079926)
			(xy 427.532292 -42.079926) (xy 427.531796 -42.122238) (xy 427.523872 -42.20649) (xy 427.508093 -42.289629)
			(xy 427.484598 -42.370926) (xy 427.453594 -42.449665) (xy 427.415352 -42.525155) (xy 427.37021 -42.596732)
			(xy 427.318563 -42.663768) (xy 427.260866 -42.725673) (xy 427.197626 -42.781903) (xy 427.129398 -42.831964)
			(xy 427.056782 -42.875416) (xy 426.980416 -42.911877) (xy 426.900972 -42.941027) (xy 426.819147 -42.96261)
			(xy 426.73566 -42.976435) (xy 426.651246 -42.982382) (xy 426.566645 -42.980399) (xy 426.482603 -42.970501)
			(xy 426.399856 -42.952778) (xy 426.319132 -42.927384) (xy 426.241141 -42.894542) (xy 426.166569 -42.854541)
			(xy 426.096069 -42.807733) (xy 426.030263 -42.754529) (xy 425.969727 -42.695397) (xy 425.914995 -42.630856)
			(xy 425.866548 -42.561473) (xy 425.82481 -42.487858) (xy 425.790149 -42.410659) (xy 425.762869 -42.330553)
			(xy 425.743211 -42.248244) (xy 425.731346 -42.164457) (xy 425.72738 -42.079926) (xy 417.156138 -42.079926)
			(xy 417.156138 -43.144948) (xy 438.611262 -43.144948) (xy 438.615333 -43.089326) (xy 438.627459 -43.034889)
			(xy 438.647382 -42.982798) (xy 438.674678 -42.934163) (xy 438.708764 -42.89002) (xy 438.748913 -42.851311)
			(xy 438.794271 -42.81886) (xy 438.843871 -42.793359) (xy 438.896655 -42.775352) (xy 438.951498 -42.765222)
			(xy 439.007232 -42.763185) (xy 439.062669 -42.769285) (xy 439.116626 -42.783391) (xy 439.167955 -42.805203)
			(xy 439.215561 -42.834257) (xy 439.258429 -42.869932) (xy 439.295646 -42.911469) (xy 439.326419 -42.957982)
			(xy 439.350091 -43.008479) (xy 439.366159 -43.061886) (xy 439.374279 -43.117062) (xy 439.374788 -43.144948)
			(xy 439.374279 -43.172834) (xy 439.366159 -43.22801) (xy 439.350091 -43.281417) (xy 439.326419 -43.331914)
			(xy 439.295646 -43.378427) (xy 439.258429 -43.419964) (xy 439.215561 -43.455639) (xy 439.167955 -43.484693)
			(xy 439.116626 -43.506505) (xy 439.062669 -43.520611) (xy 439.007232 -43.526711) (xy 438.951498 -43.524674)
			(xy 438.896655 -43.514544) (xy 438.843871 -43.496537) (xy 438.794271 -43.471036) (xy 438.748913 -43.438585)
			(xy 438.708764 -43.399876) (xy 438.674678 -43.355733) (xy 438.647382 -43.307098) (xy 438.627459 -43.255007)
			(xy 438.615333 -43.20057) (xy 438.611262 -43.144948) (xy 417.156138 -43.144948) (xy 417.156138 -44.619926)
			(xy 425.72738 -44.619926) (xy 425.731346 -44.535395) (xy 425.743211 -44.451608) (xy 425.762869 -44.369299)
			(xy 425.790149 -44.289193) (xy 425.82481 -44.211994) (xy 425.866548 -44.138379) (xy 425.914995 -44.068996)
			(xy 425.969727 -44.004455) (xy 426.030263 -43.945323) (xy 426.096069 -43.892119) (xy 426.166569 -43.845311)
			(xy 426.241141 -43.80531) (xy 426.319132 -43.772468) (xy 426.399856 -43.747074) (xy 426.482603 -43.729351)
			(xy 426.566645 -43.719453) (xy 426.651246 -43.71747) (xy 426.73566 -43.723417) (xy 426.819147 -43.737242)
			(xy 426.900972 -43.758825) (xy 426.980416 -43.787975) (xy 427.056782 -43.824436) (xy 427.129398 -43.867888)
			(xy 427.197626 -43.917949) (xy 427.260866 -43.974179) (xy 427.318563 -44.036084) (xy 427.37021 -44.10312)
			(xy 427.415352 -44.174697) (xy 427.453594 -44.250187) (xy 427.484598 -44.328926) (xy 427.508093 -44.410223)
			(xy 427.523872 -44.493362) (xy 427.531796 -44.577614) (xy 427.532292 -44.619926) (xy 428.26738 -44.619926)
			(xy 428.271346 -44.535395) (xy 428.283211 -44.451608) (xy 428.302869 -44.369299) (xy 428.330149 -44.289193)
			(xy 428.36481 -44.211994) (xy 428.406548 -44.138379) (xy 428.454995 -44.068996) (xy 428.509727 -44.004455)
			(xy 428.570263 -43.945323) (xy 428.636069 -43.892119) (xy 428.706569 -43.845311) (xy 428.781141 -43.80531)
			(xy 428.859132 -43.772468) (xy 428.939856 -43.747074) (xy 429.022603 -43.729351) (xy 429.106645 -43.719453)
			(xy 429.191246 -43.71747) (xy 429.27566 -43.723417) (xy 429.359147 -43.737242) (xy 429.440972 -43.758825)
			(xy 429.520416 -43.787975) (xy 429.596782 -43.824436) (xy 429.669398 -43.867888) (xy 429.737626 -43.917949)
			(xy 429.785243 -43.960288) (xy 437.282842 -43.960288) (xy 437.286913 -43.904666) (xy 437.299039 -43.850229)
			(xy 437.318962 -43.798138) (xy 437.346258 -43.749503) (xy 437.380344 -43.70536) (xy 437.420493 -43.666651)
			(xy 437.465851 -43.6342) (xy 437.515451 -43.608699) (xy 437.568235 -43.590692) (xy 437.623078 -43.580562)
			(xy 437.678812 -43.578525) (xy 437.734249 -43.584625) (xy 437.788206 -43.598731) (xy 437.839535 -43.620543)
			(xy 437.883631 -43.647455) (xy 443.507037 -43.647455) (xy 443.507037 -43.592945) (xy 443.514795 -43.53899)
			(xy 443.530152 -43.486689) (xy 443.552797 -43.437105) (xy 443.582267 -43.391249) (xy 443.617964 -43.350054)
			(xy 443.659161 -43.314359) (xy 443.705018 -43.28489) (xy 443.754602 -43.262247) (xy 443.806904 -43.246892)
			(xy 443.860859 -43.239136) (xy 443.888114 -43.238674) (xy 443.9166 -43.239208) (xy 443.972939 -43.247682)
			(xy 444.027392 -43.26444) (xy 444.078747 -43.289109) (xy 444.125863 -43.321141) (xy 444.167691 -43.359823)
			(xy 444.203302 -43.404295) (xy 444.21806 -43.428666) (xy 444.225243 -43.440168) (xy 444.24457 -43.459179)
			(xy 444.268218 -43.472436) (xy 444.294519 -43.479005) (xy 444.321623 -43.478424) (xy 444.347619 -43.470733)
			(xy 444.370676 -43.456474) (xy 444.38917 -43.436652) (xy 444.39586 -43.424856) (xy 444.408301 -43.402089)
			(xy 444.438418 -43.359843) (xy 444.47398 -43.322067) (xy 444.514334 -43.289459) (xy 444.558733 -43.262619)
			(xy 444.60636 -43.242043) (xy 444.656336 -43.22811) (xy 444.707739 -43.221077) (xy 444.73368 -43.22064)
			(xy 444.760099 -43.221102) (xy 444.812433 -43.228384) (xy 444.863259 -43.242826) (xy 444.911604 -43.264149)
			(xy 444.956539 -43.291946) (xy 444.997204 -43.325683) (xy 445.03282 -43.364714) (xy 445.048132 -43.386248)
			(xy 445.056826 -43.397905) (xy 445.079389 -43.416226) (xy 445.106196 -43.427457) (xy 445.13508 -43.430691)
			(xy 445.163707 -43.425667) (xy 445.189764 -43.412791) (xy 445.211144 -43.393103) (xy 445.219074 -43.380914)
			(xy 445.233972 -43.357049) (xy 445.269622 -43.31353) (xy 445.311276 -43.275718) (xy 445.358033 -43.244435)
			(xy 445.408877 -43.220357) (xy 445.462705 -43.204009) (xy 445.518352 -43.195744) (xy 445.54648 -43.19524)
			(xy 445.573737 -43.195606) (xy 445.627697 -43.203361) (xy 445.680004 -43.218717) (xy 445.729593 -43.241362)
			(xy 445.775454 -43.270833) (xy 445.816655 -43.306531) (xy 445.852355 -43.34773) (xy 445.881829 -43.393589)
			(xy 445.904476 -43.443177) (xy 445.919835 -43.495483) (xy 445.927593 -43.549443) (xy 445.927593 -43.603957)
			(xy 445.926758 -43.609768) (xy 451.610982 -43.609768) (xy 451.615053 -43.554146) (xy 451.627179 -43.499709)
			(xy 451.647102 -43.447618) (xy 451.674398 -43.398983) (xy 451.708484 -43.35484) (xy 451.748633 -43.316131)
			(xy 451.793991 -43.28368) (xy 451.843591 -43.258179) (xy 451.896375 -43.240172) (xy 451.951218 -43.230042)
			(xy 452.006952 -43.228005) (xy 452.062389 -43.234105) (xy 452.116346 -43.248211) (xy 452.167675 -43.270023)
			(xy 452.215281 -43.299077) (xy 452.258149 -43.334752) (xy 452.295366 -43.376289) (xy 452.326139 -43.422802)
			(xy 452.349811 -43.473299) (xy 452.365879 -43.526706) (xy 452.373999 -43.581882) (xy 452.374508 -43.609768)
			(xy 452.373999 -43.637654) (xy 452.365879 -43.69283) (xy 452.349811 -43.746237) (xy 452.326139 -43.796734)
			(xy 452.295366 -43.843247) (xy 452.258149 -43.884784) (xy 452.215281 -43.920459) (xy 452.167675 -43.949513)
			(xy 452.116346 -43.971325) (xy 452.062389 -43.985431) (xy 452.006952 -43.991531) (xy 451.951218 -43.989494)
			(xy 451.896375 -43.979364) (xy 451.843591 -43.961357) (xy 451.793991 -43.935856) (xy 451.748633 -43.903405)
			(xy 451.708484 -43.864696) (xy 451.674398 -43.820553) (xy 451.647102 -43.771918) (xy 451.627179 -43.719827)
			(xy 451.615053 -43.66539) (xy 451.610982 -43.609768) (xy 445.926758 -43.609768) (xy 445.919835 -43.657917)
			(xy 445.904476 -43.710223) (xy 445.881829 -43.759811) (xy 445.852355 -43.80567) (xy 445.816655 -43.846869)
			(xy 445.775454 -43.882567) (xy 445.729593 -43.912038) (xy 445.680004 -43.934683) (xy 445.627697 -43.950039)
			(xy 445.573737 -43.957794) (xy 445.54648 -43.958256) (xy 445.52006 -43.957826) (xy 445.467724 -43.950538)
			(xy 445.416897 -43.936091) (xy 445.368553 -43.914763) (xy 445.323618 -43.886961) (xy 445.282953 -43.853219)
			(xy 445.24734 -43.814184) (xy 445.232028 -43.792648) (xy 445.223383 -43.780951) (xy 445.200809 -43.76263)
			(xy 445.173991 -43.751402) (xy 445.145097 -43.748173) (xy 445.116462 -43.753204) (xy 445.0904 -43.76609)
			(xy 445.069016 -43.785788) (xy 445.061086 -43.797982) (xy 445.046214 -43.821864) (xy 445.01056 -43.865384)
			(xy 444.968901 -43.903194) (xy 444.92214 -43.934476) (xy 444.871292 -43.95855) (xy 444.817459 -43.974895)
			(xy 444.76181 -43.983155) (xy 444.73368 -43.983656) (xy 444.705194 -43.983112) (xy 444.648856 -43.974638)
			(xy 444.594405 -43.95788) (xy 444.54305 -43.933213) (xy 444.495935 -43.901183) (xy 444.454106 -43.862503)
			(xy 444.418493 -43.818034) (xy 444.403734 -43.793664) (xy 444.396562 -43.782152) (xy 444.377235 -43.763136)
			(xy 444.353585 -43.749874) (xy 444.32728 -43.743303) (xy 444.300172 -43.743886) (xy 444.274173 -43.75158)
			(xy 444.251115 -43.765845) (xy 444.232622 -43.785674) (xy 444.225934 -43.797474) (xy 444.213467 -43.820227)
			(xy 444.183358 -43.862476) (xy 444.1478 -43.900254) (xy 444.107451 -43.932866) (xy 444.063054 -43.959708)
			(xy 444.01543 -43.980286) (xy 443.965456 -43.99422) (xy 443.914054 -44.001253) (xy 443.888114 -44.00169)
			(xy 443.860859 -44.001264) (xy 443.806904 -43.993508) (xy 443.754602 -43.978153) (xy 443.705018 -43.95551)
			(xy 443.659161 -43.926041) (xy 443.617964 -43.890346) (xy 443.582267 -43.849151) (xy 443.552797 -43.803295)
			(xy 443.530152 -43.753711) (xy 443.514795 -43.70141) (xy 443.507037 -43.647455) (xy 437.883631 -43.647455)
			(xy 437.887141 -43.649597) (xy 437.930009 -43.685272) (xy 437.967226 -43.726809) (xy 437.997999 -43.773322)
			(xy 438.021671 -43.823819) (xy 438.037739 -43.877226) (xy 438.045859 -43.932402) (xy 438.046368 -43.960288)
			(xy 438.045859 -43.988174) (xy 438.037739 -44.04335) (xy 438.021671 -44.096757) (xy 437.997999 -44.147254)
			(xy 437.967226 -44.193767) (xy 437.930009 -44.235304) (xy 437.887141 -44.270979) (xy 437.839535 -44.300033)
			(xy 437.788206 -44.321845) (xy 437.734249 -44.335951) (xy 437.678812 -44.342051) (xy 437.623078 -44.340014)
			(xy 437.568235 -44.329884) (xy 437.515451 -44.311877) (xy 437.465851 -44.286376) (xy 437.420493 -44.253925)
			(xy 437.380344 -44.215216) (xy 437.346258 -44.171073) (xy 437.318962 -44.122438) (xy 437.299039 -44.070347)
			(xy 437.286913 -44.01591) (xy 437.282842 -43.960288) (xy 429.785243 -43.960288) (xy 429.800866 -43.974179)
			(xy 429.858563 -44.036084) (xy 429.91021 -44.10312) (xy 429.955352 -44.174697) (xy 429.993594 -44.250187)
			(xy 430.024598 -44.328926) (xy 430.048093 -44.410223) (xy 430.054196 -44.44238) (xy 435.807102 -44.44238)
			(xy 435.811173 -44.386758) (xy 435.823299 -44.332321) (xy 435.843222 -44.28023) (xy 435.870518 -44.231595)
			(xy 435.904604 -44.187452) (xy 435.944753 -44.148743) (xy 435.990111 -44.116292) (xy 436.039711 -44.090791)
			(xy 436.092495 -44.072784) (xy 436.147338 -44.062654) (xy 436.203072 -44.060617) (xy 436.258509 -44.066717)
			(xy 436.312466 -44.080823) (xy 436.363795 -44.102635) (xy 436.411401 -44.131689) (xy 436.454269 -44.167364)
			(xy 436.491486 -44.208901) (xy 436.522259 -44.255414) (xy 436.545931 -44.305911) (xy 436.557721 -44.345098)
			(xy 448.512182 -44.345098) (xy 448.516253 -44.289476) (xy 448.528379 -44.235039) (xy 448.548302 -44.182948)
			(xy 448.575598 -44.134313) (xy 448.609684 -44.09017) (xy 448.649833 -44.051461) (xy 448.695191 -44.01901)
			(xy 448.744791 -43.993509) (xy 448.797575 -43.975502) (xy 448.852418 -43.965372) (xy 448.908152 -43.963335)
			(xy 448.963589 -43.969435) (xy 449.017546 -43.983541) (xy 449.068875 -44.005353) (xy 449.116481 -44.034407)
			(xy 449.159349 -44.070082) (xy 449.196566 -44.111619) (xy 449.227339 -44.158132) (xy 449.251011 -44.208629)
			(xy 449.267079 -44.262036) (xy 449.275199 -44.317212) (xy 449.275708 -44.345098) (xy 449.275199 -44.372984)
			(xy 449.267079 -44.42816) (xy 449.251011 -44.481567) (xy 449.227339 -44.532064) (xy 449.196566 -44.578577)
			(xy 449.159349 -44.620114) (xy 449.116481 -44.655789) (xy 449.068875 -44.684843) (xy 449.017546 -44.706655)
			(xy 448.963589 -44.720761) (xy 448.908152 -44.726861) (xy 448.852418 -44.724824) (xy 448.797575 -44.714694)
			(xy 448.744791 -44.696687) (xy 448.695191 -44.671186) (xy 448.649833 -44.638735) (xy 448.609684 -44.600026)
			(xy 448.575598 -44.555883) (xy 448.548302 -44.507248) (xy 448.528379 -44.455157) (xy 448.516253 -44.40072)
			(xy 448.512182 -44.345098) (xy 436.557721 -44.345098) (xy 436.561999 -44.359318) (xy 436.570119 -44.414494)
			(xy 436.570628 -44.44238) (xy 436.570119 -44.470266) (xy 436.561999 -44.525442) (xy 436.545931 -44.578849)
			(xy 436.522259 -44.629346) (xy 436.491486 -44.675859) (xy 436.454269 -44.717396) (xy 436.411401 -44.753071)
			(xy 436.363795 -44.782125) (xy 436.312466 -44.803937) (xy 436.258509 -44.818043) (xy 436.203072 -44.824143)
			(xy 436.147338 -44.822106) (xy 436.092495 -44.811976) (xy 436.039711 -44.793969) (xy 435.990111 -44.768468)
			(xy 435.944753 -44.736017) (xy 435.904604 -44.697308) (xy 435.870518 -44.653165) (xy 435.843222 -44.60453)
			(xy 435.823299 -44.552439) (xy 435.811173 -44.498002) (xy 435.807102 -44.44238) (xy 430.054196 -44.44238)
			(xy 430.063872 -44.493362) (xy 430.071796 -44.577614) (xy 430.072292 -44.619926) (xy 430.071796 -44.662238)
			(xy 430.063872 -44.74649) (xy 430.048093 -44.829629) (xy 430.024598 -44.910926) (xy 429.998861 -44.976288)
			(xy 437.282842 -44.976288) (xy 437.286913 -44.920666) (xy 437.299039 -44.866229) (xy 437.318962 -44.814138)
			(xy 437.346258 -44.765503) (xy 437.380344 -44.72136) (xy 437.420493 -44.682651) (xy 437.465851 -44.6502)
			(xy 437.515451 -44.624699) (xy 437.568235 -44.606692) (xy 437.623078 -44.596562) (xy 437.678812 -44.594525)
			(xy 437.734249 -44.600625) (xy 437.788206 -44.614731) (xy 437.839535 -44.636543) (xy 437.887141 -44.665597)
			(xy 437.930009 -44.701272) (xy 437.967226 -44.742809) (xy 437.997999 -44.789322) (xy 438.021671 -44.839819)
			(xy 438.037739 -44.893226) (xy 438.045859 -44.948402) (xy 438.046368 -44.976288) (xy 438.04602 -44.995338)
			(xy 440.935362 -44.995338) (xy 440.939433 -44.939716) (xy 440.951559 -44.885279) (xy 440.971482 -44.833188)
			(xy 440.998778 -44.784553) (xy 441.032864 -44.74041) (xy 441.073013 -44.701701) (xy 441.118371 -44.66925)
			(xy 441.167971 -44.643749) (xy 441.220755 -44.625742) (xy 441.275598 -44.615612) (xy 441.331332 -44.613575)
			(xy 441.386769 -44.619675) (xy 441.440726 -44.633781) (xy 441.492055 -44.655593) (xy 441.539661 -44.684647)
			(xy 441.582529 -44.720322) (xy 441.619746 -44.761859) (xy 441.650519 -44.808372) (xy 441.674191 -44.858869)
			(xy 441.690259 -44.912276) (xy 441.698379 -44.967452) (xy 441.698888 -44.995338) (xy 441.698379 -45.023224)
			(xy 441.690259 -45.0784) (xy 441.674191 -45.131807) (xy 441.671218 -45.13815) (xy 451.820286 -45.13815)
			(xy 451.820286 -45.08365) (xy 451.828042 -45.029705) (xy 451.843395 -44.977413) (xy 451.866035 -44.927838)
			(xy 451.895498 -44.88199) (xy 451.931187 -44.840801) (xy 451.972374 -44.80511) (xy 452.018221 -44.775644)
			(xy 452.067795 -44.753002) (xy 452.120086 -44.737646) (xy 452.17403 -44.729887) (xy 452.20128 -44.7294)
			(xy 452.220855 -44.729693) (xy 452.259793 -44.733761) (xy 452.279004 -44.737528) (xy 452.293033 -44.739944)
			(xy 452.32141 -44.737831) (xy 452.348106 -44.727979) (xy 452.371054 -44.711154) (xy 452.388477 -44.688656)
			(xy 452.399026 -44.662228) (xy 452.400924 -44.64812) (xy 452.404191 -44.620263) (xy 452.417964 -44.56589)
			(xy 452.439551 -44.514121) (xy 452.468489 -44.466072) (xy 452.504152 -44.42278) (xy 452.545772 -44.385178)
			(xy 452.59245 -44.354078) (xy 452.64318 -44.33015) (xy 452.696868 -44.31391) (xy 452.752355 -44.305709)
			(xy 452.7804 -44.30522) (xy 452.807653 -44.30565) (xy 452.861605 -44.313407) (xy 452.913904 -44.328763)
			(xy 452.963484 -44.351406) (xy 453.009338 -44.380874) (xy 453.050531 -44.416569) (xy 453.086226 -44.457762)
			(xy 453.115694 -44.503616) (xy 453.138337 -44.553196) (xy 453.153693 -44.605495) (xy 453.16145 -44.659447)
			(xy 453.16145 -44.713953) (xy 453.153693 -44.767905) (xy 453.138337 -44.820204) (xy 453.115694 -44.869784)
			(xy 453.086226 -44.915638) (xy 453.050531 -44.956831) (xy 453.009338 -44.992526) (xy 452.963484 -45.021994)
			(xy 452.960673 -45.023278) (xy 460.202532 -45.023278) (xy 460.206603 -44.967656) (xy 460.218729 -44.913219)
			(xy 460.238652 -44.861128) (xy 460.265948 -44.812493) (xy 460.300034 -44.76835) (xy 460.340183 -44.729641)
			(xy 460.385541 -44.69719) (xy 460.435141 -44.671689) (xy 460.487925 -44.653682) (xy 460.542768 -44.643552)
			(xy 460.598502 -44.641515) (xy 460.653939 -44.647615) (xy 460.707896 -44.661721) (xy 460.759225 -44.683533)
			(xy 460.806831 -44.712587) (xy 460.849699 -44.748262) (xy 460.886916 -44.789799) (xy 460.917689 -44.836312)
			(xy 460.941361 -44.886809) (xy 460.957429 -44.940216) (xy 460.965549 -44.995392) (xy 460.965993 -45.019722)
			(xy 461.882488 -45.019722) (xy 461.886559 -44.9641) (xy 461.898685 -44.909663) (xy 461.918608 -44.857572)
			(xy 461.945904 -44.808937) (xy 461.97999 -44.764794) (xy 462.020139 -44.726085) (xy 462.065497 -44.693634)
			(xy 462.115097 -44.668133) (xy 462.167881 -44.650126) (xy 462.222724 -44.639996) (xy 462.278458 -44.637959)
			(xy 462.333895 -44.644059) (xy 462.387852 -44.658165) (xy 462.439181 -44.679977) (xy 462.486787 -44.709031)
			(xy 462.529655 -44.744706) (xy 462.566872 -44.786243) (xy 462.597645 -44.832756) (xy 462.621317 -44.883253)
			(xy 462.637385 -44.93666) (xy 462.645505 -44.991836) (xy 462.646014 -45.019722) (xy 462.645505 -45.047608)
			(xy 462.637385 -45.102784) (xy 462.621317 -45.156191) (xy 462.597645 -45.206688) (xy 462.566872 -45.253201)
			(xy 462.529655 -45.294738) (xy 462.486787 -45.330413) (xy 462.439181 -45.359467) (xy 462.387852 -45.381279)
			(xy 462.333895 -45.395385) (xy 462.278458 -45.401485) (xy 462.222724 -45.399448) (xy 462.167881 -45.389318)
			(xy 462.115097 -45.371311) (xy 462.065497 -45.34581) (xy 462.020139 -45.313359) (xy 461.97999 -45.27465)
			(xy 461.945904 -45.230507) (xy 461.918608 -45.181872) (xy 461.898685 -45.129781) (xy 461.886559 -45.075344)
			(xy 461.882488 -45.019722) (xy 460.965993 -45.019722) (xy 460.966058 -45.023278) (xy 460.965549 -45.051164)
			(xy 460.957429 -45.10634) (xy 460.941361 -45.159747) (xy 460.917689 -45.210244) (xy 460.886916 -45.256757)
			(xy 460.849699 -45.298294) (xy 460.806831 -45.333969) (xy 460.759225 -45.363023) (xy 460.707896 -45.384835)
			(xy 460.653939 -45.398941) (xy 460.598502 -45.405041) (xy 460.542768 -45.403004) (xy 460.487925 -45.392874)
			(xy 460.435141 -45.374867) (xy 460.385541 -45.349366) (xy 460.340183 -45.316915) (xy 460.300034 -45.278206)
			(xy 460.265948 -45.234063) (xy 460.238652 -45.185428) (xy 460.218729 -45.133337) (xy 460.206603 -45.0789)
			(xy 460.202532 -45.023278) (xy 452.960673 -45.023278) (xy 452.913904 -45.044637) (xy 452.861605 -45.059993)
			(xy 452.807653 -45.06775) (xy 452.7804 -45.068236) (xy 452.760825 -45.067948) (xy 452.721887 -45.063877)
			(xy 452.702676 -45.060108) (xy 452.688643 -45.057728) (xy 452.660275 -45.059846) (xy 452.633588 -45.069694)
			(xy 452.610644 -45.086512) (xy 452.59322 -45.108998) (xy 452.582662 -45.135413) (xy 452.580756 -45.149516)
			(xy 452.577441 -45.177366) (xy 452.563667 -45.231733) (xy 452.542081 -45.283497) (xy 452.513146 -45.331541)
			(xy 452.477488 -45.374831) (xy 452.435875 -45.412432) (xy 452.389205 -45.443533) (xy 452.338483 -45.467465)
			(xy 452.284803 -45.483712) (xy 452.229322 -45.491922) (xy 452.20128 -45.492416) (xy 452.17403 -45.491913)
			(xy 452.120086 -45.484154) (xy 452.067795 -45.468798) (xy 452.018221 -45.446156) (xy 451.972374 -45.41669)
			(xy 451.931187 -45.380999) (xy 451.895498 -45.33981) (xy 451.866035 -45.293962) (xy 451.843395 -45.244387)
			(xy 451.828042 -45.192095) (xy 451.820286 -45.13815) (xy 441.671218 -45.13815) (xy 441.650519 -45.182304)
			(xy 441.619746 -45.228817) (xy 441.582529 -45.270354) (xy 441.539661 -45.306029) (xy 441.492055 -45.335083)
			(xy 441.440726 -45.356895) (xy 441.386769 -45.371001) (xy 441.331332 -45.377101) (xy 441.275598 -45.375064)
			(xy 441.220755 -45.364934) (xy 441.167971 -45.346927) (xy 441.118371 -45.321426) (xy 441.073013 -45.288975)
			(xy 441.032864 -45.250266) (xy 440.998778 -45.206123) (xy 440.971482 -45.157488) (xy 440.951559 -45.105397)
			(xy 440.939433 -45.05096) (xy 440.935362 -44.995338) (xy 438.04602 -44.995338) (xy 438.045859 -45.004174)
			(xy 438.037739 -45.05935) (xy 438.021671 -45.112757) (xy 437.997999 -45.163254) (xy 437.967226 -45.209767)
			(xy 437.930009 -45.251304) (xy 437.887141 -45.286979) (xy 437.839535 -45.316033) (xy 437.788206 -45.337845)
			(xy 437.734249 -45.351951) (xy 437.678812 -45.358051) (xy 437.623078 -45.356014) (xy 437.568235 -45.345884)
			(xy 437.515451 -45.327877) (xy 437.465851 -45.302376) (xy 437.420493 -45.269925) (xy 437.380344 -45.231216)
			(xy 437.346258 -45.187073) (xy 437.318962 -45.138438) (xy 437.299039 -45.086347) (xy 437.286913 -45.03191)
			(xy 437.282842 -44.976288) (xy 429.998861 -44.976288) (xy 429.993594 -44.989665) (xy 429.955352 -45.065155)
			(xy 429.91021 -45.136732) (xy 429.858563 -45.203768) (xy 429.800866 -45.265673) (xy 429.737626 -45.321903)
			(xy 429.669398 -45.371964) (xy 429.596782 -45.415416) (xy 429.520416 -45.451877) (xy 429.440972 -45.481027)
			(xy 429.359147 -45.50261) (xy 429.27566 -45.516435) (xy 429.191246 -45.522382) (xy 429.106645 -45.520399)
			(xy 429.022603 -45.510501) (xy 428.939856 -45.492778) (xy 428.859132 -45.467384) (xy 428.781141 -45.434542)
			(xy 428.706569 -45.394541) (xy 428.636069 -45.347733) (xy 428.570263 -45.294529) (xy 428.509727 -45.235397)
			(xy 428.454995 -45.170856) (xy 428.406548 -45.101473) (xy 428.36481 -45.027858) (xy 428.330149 -44.950659)
			(xy 428.302869 -44.870553) (xy 428.283211 -44.788244) (xy 428.271346 -44.704457) (xy 428.26738 -44.619926)
			(xy 427.532292 -44.619926) (xy 427.531796 -44.662238) (xy 427.523872 -44.74649) (xy 427.508093 -44.829629)
			(xy 427.484598 -44.910926) (xy 427.453594 -44.989665) (xy 427.415352 -45.065155) (xy 427.37021 -45.136732)
			(xy 427.318563 -45.203768) (xy 427.260866 -45.265673) (xy 427.197626 -45.321903) (xy 427.129398 -45.371964)
			(xy 427.056782 -45.415416) (xy 426.980416 -45.451877) (xy 426.900972 -45.481027) (xy 426.819147 -45.50261)
			(xy 426.73566 -45.516435) (xy 426.651246 -45.522382) (xy 426.566645 -45.520399) (xy 426.482603 -45.510501)
			(xy 426.399856 -45.492778) (xy 426.319132 -45.467384) (xy 426.241141 -45.434542) (xy 426.166569 -45.394541)
			(xy 426.096069 -45.347733) (xy 426.030263 -45.294529) (xy 425.969727 -45.235397) (xy 425.914995 -45.170856)
			(xy 425.866548 -45.101473) (xy 425.82481 -45.027858) (xy 425.790149 -44.950659) (xy 425.762869 -44.870553)
			(xy 425.743211 -44.788244) (xy 425.731346 -44.704457) (xy 425.72738 -44.619926) (xy 417.156138 -44.619926)
			(xy 417.156138 -45.936408) (xy 423.315382 -45.936408) (xy 423.319453 -45.880786) (xy 423.331579 -45.826349)
			(xy 423.351502 -45.774258) (xy 423.378798 -45.725623) (xy 423.412884 -45.68148) (xy 423.453033 -45.642771)
			(xy 423.498391 -45.61032) (xy 423.547991 -45.584819) (xy 423.600775 -45.566812) (xy 423.655618 -45.556682)
			(xy 423.711352 -45.554645) (xy 423.766789 -45.560745) (xy 423.820746 -45.574851) (xy 423.872075 -45.596663)
			(xy 423.919681 -45.625717) (xy 423.962549 -45.661392) (xy 423.999766 -45.702929) (xy 424.030539 -45.749442)
			(xy 424.054211 -45.799939) (xy 424.070279 -45.853346) (xy 424.078399 -45.908522) (xy 424.078908 -45.936408)
			(xy 424.078399 -45.964294) (xy 424.070279 -46.01947) (xy 424.054211 -46.072877) (xy 424.030539 -46.123374)
			(xy 423.999766 -46.169887) (xy 423.962549 -46.211424) (xy 423.919681 -46.247099) (xy 423.872075 -46.276153)
			(xy 423.820746 -46.297965) (xy 423.766789 -46.312071) (xy 423.711352 -46.318171) (xy 423.655618 -46.316134)
			(xy 423.600775 -46.306004) (xy 423.547991 -46.287997) (xy 423.498391 -46.262496) (xy 423.453033 -46.230045)
			(xy 423.412884 -46.191336) (xy 423.378798 -46.147193) (xy 423.351502 -46.098558) (xy 423.331579 -46.046467)
			(xy 423.319453 -45.99203) (xy 423.315382 -45.936408) (xy 417.156138 -45.936408) (xy 417.156138 -47.0408)
			(xy 437.320942 -47.0408) (xy 437.325013 -46.985178) (xy 437.337139 -46.930741) (xy 437.357062 -46.87865)
			(xy 437.384358 -46.830015) (xy 437.418444 -46.785872) (xy 437.458593 -46.747163) (xy 437.503951 -46.714712)
			(xy 437.553551 -46.689211) (xy 437.606335 -46.671204) (xy 437.661178 -46.661074) (xy 437.716912 -46.659037)
			(xy 437.772349 -46.665137) (xy 437.826306 -46.679243) (xy 437.877635 -46.701055) (xy 437.925241 -46.730109)
			(xy 437.968109 -46.765784) (xy 438.005326 -46.807321) (xy 438.036099 -46.853834) (xy 438.059771 -46.904331)
			(xy 438.067031 -46.928461) (xy 440.272687 -46.928461) (xy 440.280442 -46.874516) (xy 440.295794 -46.822223)
			(xy 440.318433 -46.772647) (xy 440.347896 -46.726798) (xy 440.383584 -46.685608) (xy 440.424771 -46.649916)
			(xy 440.470618 -46.620449) (xy 440.520192 -46.597806) (xy 440.572483 -46.582449) (xy 440.626428 -46.57469)
			(xy 440.653678 -46.574202) (xy 440.678543 -46.57457) (xy 440.727854 -46.581012) (xy 440.775911 -46.593803)
			(xy 440.8219 -46.612727) (xy 440.84367 -46.624748) (xy 440.85562 -46.63113) (xy 440.881845 -46.637891)
			(xy 440.908926 -46.63752) (xy 440.934957 -46.630043) (xy 440.958107 -46.615987) (xy 440.976748 -46.596339)
			(xy 440.989568 -46.572482) (xy 440.995665 -46.546094) (xy 440.995562 -46.532546) (xy 440.995308 -46.517306)
			(xy 440.995771 -46.490054) (xy 441.003527 -46.436106) (xy 441.018881 -46.38381) (xy 441.041522 -46.334232)
			(xy 441.070988 -46.288381) (xy 441.106679 -46.24719) (xy 441.147869 -46.211497) (xy 441.193719 -46.182029)
			(xy 441.243296 -46.159387) (xy 441.295591 -46.14403) (xy 441.349539 -46.136272) (xy 441.404042 -46.136271)
			(xy 441.457991 -46.144026) (xy 441.510286 -46.15938) (xy 441.559865 -46.18202) (xy 441.605716 -46.211486)
			(xy 441.646908 -46.247176) (xy 441.682601 -46.288366) (xy 441.689839 -46.299628) (xy 448.136772 -46.299628)
			(xy 448.13726 -46.271631) (xy 448.145449 -46.216238) (xy 448.161639 -46.162635) (xy 448.185485 -46.111971)
			(xy 448.216474 -46.065333) (xy 448.253943 -46.023721) (xy 448.275202 -46.005496) (xy 448.286212 -45.995817)
			(xy 448.302594 -45.971518) (xy 448.311411 -45.94357) (xy 448.311938 -45.91427) (xy 448.304132 -45.886023)
			(xy 448.288634 -45.861151) (xy 448.277996 -45.851064) (xy 448.258184 -45.832867) (xy 448.223324 -45.791898)
			(xy 448.194566 -45.746438) (xy 448.17248 -45.697388) (xy 448.157505 -45.645722) (xy 448.149938 -45.592464)
			(xy 448.149472 -45.565568) (xy 448.149958 -45.538317) (xy 448.157714 -45.484369) (xy 448.173069 -45.432074)
			(xy 448.195711 -45.382497) (xy 448.225177 -45.336647) (xy 448.260868 -45.295456) (xy 448.302059 -45.259765)
			(xy 448.347909 -45.230299) (xy 448.397486 -45.207657) (xy 448.449781 -45.192302) (xy 448.503729 -45.184546)
			(xy 448.558231 -45.184546) (xy 448.612179 -45.192302) (xy 448.664474 -45.207657) (xy 448.714051 -45.230299)
			(xy 448.759901 -45.259765) (xy 448.801092 -45.295456) (xy 448.836783 -45.336647) (xy 448.866249 -45.382497)
			(xy 448.888891 -45.432074) (xy 448.904246 -45.484369) (xy 448.912002 -45.538317) (xy 448.912488 -45.565568)
			(xy 448.911975 -45.593564) (xy 448.903789 -45.648955) (xy 448.887602 -45.702557) (xy 448.86376 -45.75322)
			(xy 448.832776 -45.799859) (xy 448.795314 -45.841473) (xy 448.774058 -45.8597) (xy 448.763048 -45.869382)
			(xy 448.746656 -45.893677) (xy 448.737833 -45.921626) (xy 448.737305 -45.950929) (xy 448.745115 -45.979177)
			(xy 448.760621 -46.004048) (xy 448.771264 -46.014132) (xy 448.791086 -46.032319) (xy 448.825942 -46.073291)
			(xy 448.854698 -46.118754) (xy 448.876781 -46.167805) (xy 448.891755 -46.219473) (xy 448.899322 -46.272731)
			(xy 448.899788 -46.299628) (xy 448.899302 -46.326879) (xy 448.891546 -46.380827) (xy 448.876191 -46.433122)
			(xy 448.853549 -46.482699) (xy 448.824083 -46.528549) (xy 448.788392 -46.56974) (xy 448.747201 -46.605431)
			(xy 448.701351 -46.634897) (xy 448.651774 -46.657539) (xy 448.599479 -46.672894) (xy 448.545531 -46.68065)
			(xy 448.491029 -46.68065) (xy 448.437081 -46.672894) (xy 448.384786 -46.657539) (xy 448.335209 -46.634897)
			(xy 448.289359 -46.605431) (xy 448.248168 -46.56974) (xy 448.212477 -46.528549) (xy 448.183011 -46.482699)
			(xy 448.160369 -46.433122) (xy 448.145014 -46.380827) (xy 448.137258 -46.326879) (xy 448.136772 -46.299628)
			(xy 441.689839 -46.299628) (xy 441.712069 -46.334216) (xy 441.734712 -46.383793) (xy 441.750069 -46.436088)
			(xy 441.757827 -46.490036) (xy 441.757829 -46.544539) (xy 441.750074 -46.598487) (xy 441.734721 -46.650783)
			(xy 441.712081 -46.700362) (xy 441.682616 -46.746214) (xy 441.646926 -46.787406) (xy 441.605737 -46.823099)
			(xy 441.559887 -46.852568) (xy 441.51031 -46.875211) (xy 441.458015 -46.890568) (xy 441.404068 -46.898327)
			(xy 441.376816 -46.898814) (xy 441.351951 -46.898447) (xy 441.30264 -46.892004) (xy 441.254583 -46.879212)
			(xy 441.208594 -46.860289) (xy 441.186824 -46.848268) (xy 441.174884 -46.841865) (xy 441.148655 -46.835102)
			(xy 441.12157 -46.835474) (xy 441.095535 -46.842953) (xy 441.072383 -46.857013) (xy 441.053741 -46.876665)
			(xy 441.040922 -46.900527) (xy 441.034827 -46.92692) (xy 441.034932 -46.94047) (xy 441.035186 -46.95571)
			(xy 441.034711 -46.98296) (xy 441.026954 -47.036905) (xy 441.011598 -47.089197) (xy 440.988957 -47.138772)
			(xy 440.959491 -47.18462) (xy 440.923801 -47.225807) (xy 440.882612 -47.261497) (xy 440.836764 -47.290962)
			(xy 440.787188 -47.313601) (xy 440.734896 -47.328956) (xy 440.680951 -47.336712) (xy 440.626451 -47.336712)
			(xy 440.572505 -47.328956) (xy 440.520213 -47.313602) (xy 440.470638 -47.290962) (xy 440.424789 -47.261498)
			(xy 440.3836 -47.225808) (xy 440.347909 -47.184621) (xy 440.318444 -47.138773) (xy 440.295802 -47.089198)
			(xy 440.280447 -47.036906) (xy 440.272689 -46.982961) (xy 440.272687 -46.928461) (xy 438.067031 -46.928461)
			(xy 438.075839 -46.957738) (xy 438.083959 -47.012914) (xy 438.084468 -47.0408) (xy 438.083959 -47.068686)
			(xy 438.075839 -47.123862) (xy 438.059771 -47.177269) (xy 438.036099 -47.227766) (xy 438.005326 -47.274279)
			(xy 437.968109 -47.315816) (xy 437.925241 -47.351491) (xy 437.877635 -47.380545) (xy 437.826306 -47.402357)
			(xy 437.772349 -47.416463) (xy 437.716912 -47.422563) (xy 437.661178 -47.420526) (xy 437.606335 -47.410396)
			(xy 437.553551 -47.392389) (xy 437.503951 -47.366888) (xy 437.458593 -47.334437) (xy 437.418444 -47.295728)
			(xy 437.384358 -47.251585) (xy 437.357062 -47.20295) (xy 437.337139 -47.150859) (xy 437.325013 -47.096422)
			(xy 437.320942 -47.0408) (xy 417.156138 -47.0408) (xy 417.156138 -47.545498) (xy 423.223688 -47.545498)
			(xy 423.227759 -47.489876) (xy 423.239885 -47.435439) (xy 423.259808 -47.383348) (xy 423.287104 -47.334713)
			(xy 423.32119 -47.29057) (xy 423.361339 -47.251861) (xy 423.406697 -47.21941) (xy 423.456297 -47.193909)
			(xy 423.509081 -47.175902) (xy 423.563924 -47.165772) (xy 423.619658 -47.163735) (xy 423.675095 -47.169835)
			(xy 423.729052 -47.183941) (xy 423.780381 -47.205753) (xy 423.827987 -47.234807) (xy 423.870855 -47.270482)
			(xy 423.908072 -47.312019) (xy 423.938845 -47.358532) (xy 423.962517 -47.409029) (xy 423.978585 -47.462436)
			(xy 423.986705 -47.517612) (xy 423.987214 -47.545498) (xy 423.986705 -47.573384) (xy 423.978585 -47.62856)
			(xy 423.962517 -47.681967) (xy 423.938845 -47.732464) (xy 423.908072 -47.778977) (xy 423.870855 -47.820514)
			(xy 423.827987 -47.856189) (xy 423.780381 -47.885243) (xy 423.729052 -47.907055) (xy 423.675095 -47.921161)
			(xy 423.619658 -47.927261) (xy 423.563924 -47.925224) (xy 423.509081 -47.915094) (xy 423.456297 -47.897087)
			(xy 423.406697 -47.871586) (xy 423.361339 -47.839135) (xy 423.32119 -47.800426) (xy 423.287104 -47.756283)
			(xy 423.259808 -47.707648) (xy 423.239885 -47.655557) (xy 423.227759 -47.60112) (xy 423.223688 -47.545498)
			(xy 417.156138 -47.545498) (xy 417.156138 -48.578008) (xy 436.577232 -48.578008) (xy 436.577787 -48.549327)
			(xy 436.586396 -48.492615) (xy 436.603391 -48.437828) (xy 436.62839 -48.3862) (xy 436.66083 -48.338892)
			(xy 436.699982 -48.296969) (xy 436.744964 -48.261374) (xy 436.794764 -48.232907) (xy 436.848262 -48.212211)
			(xy 436.904254 -48.199749) (xy 436.932832 -48.197262) (xy 436.947352 -48.195752) (xy 436.974693 -48.18556)
			(xy 436.998039 -48.168055) (xy 437.015484 -48.144666) (xy 437.025607 -48.117298) (xy 437.027066 -48.102774)
			(xy 437.029521 -48.074186) (xy 437.041948 -48.018171) (xy 437.062623 -47.964649) (xy 437.091079 -47.914826)
			(xy 437.126675 -47.869826) (xy 437.168609 -47.830663) (xy 437.215933 -47.798221) (xy 437.267582 -47.773231)
			(xy 437.322391 -47.756258) (xy 437.379123 -47.747683) (xy 437.407812 -47.747174) (xy 437.435063 -47.747667)
			(xy 437.489009 -47.755424) (xy 437.541303 -47.77078) (xy 437.590879 -47.793421) (xy 437.636728 -47.822887)
			(xy 437.677918 -47.858578) (xy 437.713609 -47.899767) (xy 437.743076 -47.945616) (xy 437.765718 -47.995192)
			(xy 437.781074 -48.047485) (xy 437.788833 -48.101431) (xy 437.78932 -48.128682) (xy 437.7888 -48.157365)
			(xy 437.780192 -48.214081) (xy 437.763195 -48.268871) (xy 437.738194 -48.320502) (xy 437.70575 -48.367812)
			(xy 437.666594 -48.409736) (xy 437.621606 -48.445331) (xy 437.5718 -48.473795) (xy 437.518297 -48.494488)
			(xy 437.4623 -48.506944) (xy 437.43372 -48.509428) (xy 437.419197 -48.510909) (xy 437.391856 -48.521112)
			(xy 437.368513 -48.538625) (xy 437.351069 -48.56202) (xy 437.340946 -48.58939) (xy 437.339486 -48.603916)
			(xy 437.336971 -48.632497) (xy 437.324548 -48.688507) (xy 437.303878 -48.742026) (xy 437.275428 -48.791846)
			(xy 437.239838 -48.836845) (xy 437.197912 -48.876008) (xy 437.150595 -48.908451) (xy 437.098954 -48.933444)
			(xy 437.044152 -48.950422) (xy 436.987426 -48.959004) (xy 436.95874 -48.959516) (xy 436.931488 -48.959008)
			(xy 436.87754 -48.951256) (xy 436.825243 -48.935906) (xy 436.775664 -48.913268) (xy 436.729811 -48.883805)
			(xy 436.688618 -48.848116) (xy 436.652924 -48.806928) (xy 436.623455 -48.761079) (xy 436.600811 -48.711502)
			(xy 436.585454 -48.659207) (xy 436.577696 -48.605259) (xy 436.577232 -48.578008) (xy 417.156138 -48.578008)
			(xy 417.156138 -49.09566) (xy 422.957242 -49.09566) (xy 422.961313 -49.040038) (xy 422.973439 -48.985601)
			(xy 422.993362 -48.93351) (xy 423.020658 -48.884875) (xy 423.054744 -48.840732) (xy 423.094893 -48.802023)
			(xy 423.140251 -48.769572) (xy 423.189851 -48.744071) (xy 423.242635 -48.726064) (xy 423.297478 -48.715934)
			(xy 423.353212 -48.713897) (xy 423.408649 -48.719997) (xy 423.462606 -48.734103) (xy 423.513935 -48.755915)
			(xy 423.561541 -48.784969) (xy 423.604409 -48.820644) (xy 423.641626 -48.862181) (xy 423.672399 -48.908694)
			(xy 423.696071 -48.959191) (xy 423.712139 -49.012598) (xy 423.720259 -49.067774) (xy 423.720768 -49.09566)
			(xy 423.720259 -49.123546) (xy 423.712139 -49.178722) (xy 423.696071 -49.232129) (xy 423.672399 -49.282626)
			(xy 423.641626 -49.329139) (xy 423.604409 -49.370676) (xy 423.561541 -49.406351) (xy 423.513935 -49.435405)
			(xy 423.462606 -49.457217) (xy 423.408649 -49.471323) (xy 423.353212 -49.477423) (xy 423.297478 -49.475386)
			(xy 423.242635 -49.465256) (xy 423.189851 -49.447249) (xy 423.140251 -49.421748) (xy 423.094893 -49.389297)
			(xy 423.054744 -49.350588) (xy 423.020658 -49.306445) (xy 422.993362 -49.25781) (xy 422.973439 -49.205719)
			(xy 422.961313 -49.151282) (xy 422.957242 -49.09566) (xy 417.156138 -49.09566) (xy 417.156138 -50.94732)
			(xy 423.297602 -50.94732) (xy 423.301673 -50.891698) (xy 423.313799 -50.837261) (xy 423.333722 -50.78517)
			(xy 423.361018 -50.736535) (xy 423.395104 -50.692392) (xy 423.435253 -50.653683) (xy 423.480611 -50.621232)
			(xy 423.530211 -50.595731) (xy 423.582995 -50.577724) (xy 423.637838 -50.567594) (xy 423.693572 -50.565557)
			(xy 423.749009 -50.571657) (xy 423.802966 -50.585763) (xy 423.854295 -50.607575) (xy 423.901901 -50.636629)
			(xy 423.944769 -50.672304) (xy 423.981986 -50.713841) (xy 424.012759 -50.760354) (xy 424.036431 -50.810851)
			(xy 424.052499 -50.864258) (xy 424.060619 -50.919434) (xy 424.061128 -50.94732) (xy 424.060619 -50.975206)
			(xy 424.052499 -51.030382) (xy 424.036431 -51.083789) (xy 424.012759 -51.134286) (xy 423.981986 -51.180799)
			(xy 423.944769 -51.222336) (xy 423.901901 -51.258011) (xy 423.854295 -51.287065) (xy 423.802966 -51.308877)
			(xy 423.749009 -51.322983) (xy 423.693572 -51.329083) (xy 423.637838 -51.327046) (xy 423.582995 -51.316916)
			(xy 423.530211 -51.298909) (xy 423.480611 -51.273408) (xy 423.435253 -51.240957) (xy 423.395104 -51.202248)
			(xy 423.361018 -51.158105) (xy 423.333722 -51.10947) (xy 423.313799 -51.057379) (xy 423.301673 -51.002942)
			(xy 423.297602 -50.94732) (xy 417.156138 -50.94732) (xy 417.156138 -52.10048) (xy 430.840132 -52.10048)
			(xy 430.844203 -52.044858) (xy 430.856329 -51.990421) (xy 430.876252 -51.93833) (xy 430.903548 -51.889695)
			(xy 430.937634 -51.845552) (xy 430.977783 -51.806843) (xy 431.023141 -51.774392) (xy 431.072741 -51.748891)
			(xy 431.125525 -51.730884) (xy 431.180368 -51.720754) (xy 431.236102 -51.718717) (xy 431.291539 -51.724817)
			(xy 431.345496 -51.738923) (xy 431.396825 -51.760735) (xy 431.444431 -51.789789) (xy 431.487299 -51.825464)
			(xy 431.524516 -51.867001) (xy 431.555289 -51.913514) (xy 431.578961 -51.964011) (xy 431.594037 -52.01412)
			(xy 432.050442 -52.01412) (xy 432.054513 -51.958498) (xy 432.066639 -51.904061) (xy 432.086562 -51.85197)
			(xy 432.113858 -51.803335) (xy 432.147944 -51.759192) (xy 432.188093 -51.720483) (xy 432.233451 -51.688032)
			(xy 432.283051 -51.662531) (xy 432.335835 -51.644524) (xy 432.390678 -51.634394) (xy 432.446412 -51.632357)
			(xy 432.501849 -51.638457) (xy 432.555806 -51.652563) (xy 432.607135 -51.674375) (xy 432.654741 -51.703429)
			(xy 432.697609 -51.739104) (xy 432.734826 -51.780641) (xy 432.765599 -51.827154) (xy 432.789271 -51.877651)
			(xy 432.805339 -51.931058) (xy 432.813459 -51.986234) (xy 432.813968 -52.01412) (xy 432.813459 -52.042006)
			(xy 432.805339 -52.097182) (xy 432.789271 -52.150589) (xy 432.765599 -52.201086) (xy 432.734826 -52.247599)
			(xy 432.697609 -52.289136) (xy 432.654741 -52.324811) (xy 432.607135 -52.353865) (xy 432.555806 -52.375677)
			(xy 432.501849 -52.389783) (xy 432.446412 -52.395883) (xy 432.390678 -52.393846) (xy 432.335835 -52.383716)
			(xy 432.283051 -52.365709) (xy 432.233451 -52.340208) (xy 432.188093 -52.307757) (xy 432.147944 -52.269048)
			(xy 432.113858 -52.224905) (xy 432.086562 -52.17627) (xy 432.066639 -52.124179) (xy 432.054513 -52.069742)
			(xy 432.050442 -52.01412) (xy 431.594037 -52.01412) (xy 431.595029 -52.017418) (xy 431.603149 -52.072594)
			(xy 431.603658 -52.10048) (xy 431.603149 -52.128366) (xy 431.595029 -52.183542) (xy 431.578961 -52.236949)
			(xy 431.555289 -52.287446) (xy 431.524516 -52.333959) (xy 431.487299 -52.375496) (xy 431.444431 -52.411171)
			(xy 431.396825 -52.440225) (xy 431.345496 -52.462037) (xy 431.291539 -52.476143) (xy 431.236102 -52.482243)
			(xy 431.180368 -52.480206) (xy 431.125525 -52.470076) (xy 431.072741 -52.452069) (xy 431.023141 -52.426568)
			(xy 430.977783 -52.394117) (xy 430.937634 -52.355408) (xy 430.903548 -52.311265) (xy 430.876252 -52.26263)
			(xy 430.856329 -52.210539) (xy 430.844203 -52.156102) (xy 430.840132 -52.10048) (xy 417.156138 -52.10048)
			(xy 417.156138 -54.534816) (xy 429.758856 -54.534816) (xy 429.759318 -54.507445) (xy 429.767135 -54.453266)
			(xy 429.782624 -54.400762) (xy 429.805467 -54.351015) (xy 429.835194 -54.305049) (xy 429.852836 -54.284118)
			(xy 429.862055 -54.272778) (xy 429.874229 -54.246224) (xy 429.878403 -54.217312) (xy 429.874236 -54.188399)
			(xy 429.862068 -54.161842) (xy 429.852836 -54.150514) (xy 429.835196 -54.129583) (xy 429.805483 -54.08361)
			(xy 429.782646 -54.033863) (xy 429.767156 -53.981362) (xy 429.759329 -53.927185) (xy 429.758856 -53.899816)
			(xy 429.759435 -53.869693) (xy 429.768914 -53.810197) (xy 429.787623 -53.752929) (xy 429.815097 -53.699312)
			(xy 429.850654 -53.650677) (xy 429.871632 -53.629052) (xy 429.880834 -53.619316) (xy 429.89428 -53.596158)
			(xy 429.901244 -53.570301) (xy 429.901247 -53.543522) (xy 429.894288 -53.517663) (xy 429.880847 -53.494502)
			(xy 429.871632 -53.48478) (xy 429.850671 -53.463138) (xy 429.815099 -53.414514) (xy 429.787614 -53.360902)
			(xy 429.768902 -53.303636) (xy 429.759426 -53.244139) (xy 429.758856 -53.214016) (xy 429.759393 -53.186767)
			(xy 429.767146 -53.132823) (xy 429.782498 -53.080531) (xy 429.805134 -53.030957) (xy 429.834596 -52.985108)
			(xy 429.870282 -52.943918) (xy 429.911466 -52.908227) (xy 429.957311 -52.878759) (xy 430.006883 -52.856116)
			(xy 430.059172 -52.840757) (xy 430.113115 -52.832997) (xy 430.140364 -52.832508) (xy 430.166824 -52.832931)
			(xy 430.219233 -52.840271) (xy 430.270124 -52.854787) (xy 430.318518 -52.876201) (xy 430.363487 -52.904102)
			(xy 430.404166 -52.937952) (xy 430.422304 -52.957222) (xy 430.433109 -52.968182) (xy 430.459663 -52.983704)
			(xy 430.489627 -52.990644) (xy 430.520301 -52.988377) (xy 430.54892 -52.977108) (xy 430.561242 -52.96789)
			(xy 430.581659 -52.951937) (xy 430.62602 -52.925161) (xy 430.673598 -52.904638) (xy 430.723516 -52.890745)
			(xy 430.774856 -52.883738) (xy 430.800764 -52.883308) (xy 430.828134 -52.883793) (xy 430.882312 -52.891606)
			(xy 430.934815 -52.907091) (xy 430.984562 -52.929928) (xy 431.03053 -52.959649) (xy 431.051462 -52.977288)
			(xy 431.06279 -52.986524) (xy 431.089347 -52.9987) (xy 431.118264 -53.002873) (xy 431.147181 -52.9987)
			(xy 431.173738 -52.986524) (xy 431.185066 -52.977288) (xy 431.205999 -52.95965) (xy 431.251971 -52.929938)
			(xy 431.301719 -52.907102) (xy 431.354219 -52.891611) (xy 431.408395 -52.883782) (xy 431.435764 -52.883308)
			(xy 431.465276 -52.883875) (xy 431.523597 -52.892961) (xy 431.579823 -52.910922) (xy 431.632611 -52.937328)
			(xy 431.680702 -52.97155) (xy 431.70221 -52.991766) (xy 431.713589 -53.002006) (xy 431.740854 -53.015882)
			(xy 431.771003 -53.021076) (xy 431.801339 -53.017123) (xy 431.82915 -53.004375) (xy 431.840894 -52.99456)
			(xy 431.861973 -52.976257) (xy 431.908518 -52.945435) (xy 431.959057 -52.921725) (xy 432.012513 -52.905634)
			(xy 432.067743 -52.897506) (xy 432.095656 -52.897024) (xy 432.124842 -52.897613) (xy 432.182533 -52.906505)
			(xy 432.238198 -52.924075) (xy 432.29054 -52.949912) (xy 432.338341 -52.983414) (xy 432.380485 -53.023801)
			(xy 432.398678 -53.04663) (xy 432.407273 -53.057141) (xy 432.428869 -53.073581) (xy 432.454033 -53.083755)
			(xy 432.480987 -53.086942) (xy 432.507829 -53.082919) (xy 432.532664 -53.071969) (xy 432.553739 -53.054866)
			(xy 432.562 -53.04409) (xy 432.577449 -53.023253) (xy 432.613004 -52.985486) (xy 432.653348 -52.952885)
			(xy 432.697737 -52.926051) (xy 432.745353 -52.905477) (xy 432.795316 -52.891545) (xy 432.846707 -52.884509)
			(xy 432.872642 -52.88407) (xy 432.900387 -52.884563) (xy 432.955291 -52.892607) (xy 433.008451 -52.90852)
			(xy 433.058744 -52.931966) (xy 433.105111 -52.96245) (xy 433.146573 -52.999329) (xy 433.182255 -53.041825)
			(xy 433.197254 -53.065172) (xy 433.205615 -53.077809) (xy 433.228365 -53.097807) (xy 433.255973 -53.110268)
			(xy 433.286019 -53.1141) (xy 433.315871 -53.108968) (xy 433.342913 -53.095322) (xy 433.354226 -53.085238)
			(xy 433.375661 -53.065403) (xy 433.423454 -53.031843) (xy 433.475799 -53.00595) (xy 433.531476 -52.988329)
			(xy 433.589187 -52.97939) (xy 433.618386 -52.978812) (xy 433.645641 -52.979234) (xy 433.699596 -52.98699)
			(xy 433.751899 -53.002345) (xy 433.801483 -53.024988) (xy 433.847341 -53.054457) (xy 433.888537 -53.090153)
			(xy 433.924234 -53.131348) (xy 433.953705 -53.177205) (xy 433.97635 -53.226788) (xy 433.991707 -53.27909)
			(xy 433.999465 -53.333045) (xy 433.999465 -53.387555) (xy 433.991707 -53.44151) (xy 433.97635 -53.493812)
			(xy 433.953705 -53.543395) (xy 433.924234 -53.589252) (xy 433.888537 -53.630447) (xy 433.847341 -53.666143)
			(xy 433.801483 -53.695612) (xy 433.751899 -53.718255) (xy 433.699596 -53.73361) (xy 433.645641 -53.741366)
			(xy 433.618386 -53.741828) (xy 433.590229 -53.741343) (xy 433.534526 -53.733076) (xy 433.480643 -53.716709)
			(xy 433.429753 -53.692597) (xy 433.38296 -53.661266) (xy 433.341282 -53.623395) (xy 433.305626 -53.579808)
			(xy 433.276765 -53.531453) (xy 433.26558 -53.505608) (xy 433.261051 -53.495825) (xy 433.245429 -53.480995)
			(xy 433.225106 -53.473859) (xy 433.203641 -53.475669) (xy 433.184799 -53.486106) (xy 433.17795 -53.494432)
			(xy 433.16017 -53.516276) (xy 433.150957 -53.52762) (xy 433.13878 -53.554172) (xy 433.134605 -53.583083)
			(xy 433.138771 -53.611996) (xy 433.150939 -53.638552) (xy 433.16017 -53.64988) (xy 433.177809 -53.670813)
			(xy 433.207521 -53.716785) (xy 433.230358 -53.766532) (xy 433.245849 -53.819033) (xy 433.253677 -53.873209)
			(xy 433.25415 -53.900578) (xy 433.253591 -53.930883) (xy 433.243998 -53.990728) (xy 433.225064 -54.048304)
			(xy 433.197268 -54.102163) (xy 433.161306 -54.150952) (xy 433.140104 -54.172612) (xy 433.130665 -54.182541)
			(xy 433.11702 -54.206286) (xy 433.110167 -54.232801) (xy 433.110597 -54.260184) (xy 433.11828 -54.28647)
			(xy 433.132664 -54.309775) (xy 433.14239 -54.319424) (xy 433.15353 -54.329979) (xy 433.174256 -54.352613)
			(xy 433.183792 -54.364636) (xy 433.193277 -54.375863) (xy 433.217199 -54.392905) (xy 433.244978 -54.402451)
			(xy 433.274324 -54.403712) (xy 433.302819 -54.396586) (xy 433.328116 -54.381659) (xy 433.338478 -54.37124)
			(xy 433.356615 -54.352319) (xy 433.397123 -54.319063) (xy 433.441807 -54.291672) (xy 433.489823 -54.270663)
			(xy 433.540265 -54.256433) (xy 433.592181 -54.249248) (xy 433.618386 -54.248812) (xy 433.645639 -54.249268)
			(xy 433.699592 -54.257024) (xy 433.751891 -54.272379) (xy 433.801472 -54.295022) (xy 433.847326 -54.32449)
			(xy 433.88852 -54.360185) (xy 433.924214 -54.401378) (xy 433.953681 -54.447233) (xy 433.976323 -54.496815)
			(xy 433.991677 -54.549114) (xy 433.999432 -54.603067) (xy 433.999894 -54.63032) (xy 433.999441 -54.657691)
			(xy 433.99162 -54.71187) (xy 433.976128 -54.764374) (xy 433.953284 -54.81412) (xy 433.923556 -54.860087)
			(xy 433.905914 -54.881018) (xy 433.896657 -54.89233) (xy 433.88448 -54.918893) (xy 433.880311 -54.947815)
			(xy 433.884489 -54.976736) (xy 433.896673 -55.003295) (xy 433.905914 -55.014622) (xy 433.923573 -55.03554)
			(xy 433.953293 -55.081511) (xy 433.976135 -55.13126) (xy 433.991628 -55.183764) (xy 433.999454 -55.237944)
			(xy 433.999452 -55.292686) (xy 433.991622 -55.346865) (xy 433.976125 -55.399368) (xy 433.953279 -55.449115)
			(xy 433.923554 -55.495084) (xy 433.905914 -55.516018) (xy 433.896657 -55.52733) (xy 433.88448 -55.553893)
			(xy 433.880311 -55.582815) (xy 433.884489 -55.611736) (xy 433.896673 -55.638295) (xy 433.905914 -55.649622)
			(xy 433.923573 -55.67054) (xy 433.953293 -55.716511) (xy 433.976135 -55.76626) (xy 433.991628 -55.818764)
			(xy 433.999454 -55.872944) (xy 433.999452 -55.927686) (xy 433.991622 -55.981865) (xy 433.976125 -56.034368)
			(xy 433.953279 -56.084115) (xy 433.923554 -56.130084) (xy 433.905914 -56.151018) (xy 433.896657 -56.16233)
			(xy 433.88448 -56.188893) (xy 433.880311 -56.217815) (xy 433.884489 -56.246736) (xy 433.896673 -56.273295)
			(xy 433.905914 -56.284622) (xy 433.923573 -56.30554) (xy 433.953293 -56.351511) (xy 433.976135 -56.40126)
			(xy 433.991628 -56.453764) (xy 433.999454 -56.507944) (xy 433.999452 -56.562686) (xy 433.991622 -56.616865)
			(xy 433.976125 -56.669368) (xy 433.953279 -56.719115) (xy 433.923554 -56.765084) (xy 433.905914 -56.786018)
			(xy 433.896657 -56.79733) (xy 433.88448 -56.823893) (xy 433.880311 -56.852815) (xy 433.884489 -56.881736)
			(xy 433.896673 -56.908295) (xy 433.905914 -56.919622) (xy 433.923532 -56.940571) (xy 433.953247 -56.986539)
			(xy 433.976086 -57.036283) (xy 433.991582 -57.088779) (xy 433.999417 -57.142952) (xy 433.999894 -57.17032)
			(xy 433.999408 -57.197571) (xy 433.991652 -57.251519) (xy 433.976297 -57.303814) (xy 433.953655 -57.353391)
			(xy 433.924189 -57.399241) (xy 433.888498 -57.440432) (xy 433.847307 -57.476123) (xy 433.801457 -57.505589)
			(xy 433.75188 -57.528231) (xy 433.699585 -57.543586) (xy 433.645637 -57.551342) (xy 433.591135 -57.551342)
			(xy 433.537187 -57.543586) (xy 433.484892 -57.528231) (xy 433.435315 -57.505589) (xy 433.389465 -57.476123)
			(xy 433.348274 -57.440432) (xy 433.312583 -57.399241) (xy 433.283117 -57.353391) (xy 433.260475 -57.303814)
			(xy 433.24512 -57.251519) (xy 433.237364 -57.197571) (xy 433.236878 -57.17032) (xy 433.237337 -57.142949)
			(xy 433.245153 -57.088769) (xy 433.260643 -57.036265) (xy 433.283487 -56.986518) (xy 433.313215 -56.940553)
			(xy 433.330858 -56.919622) (xy 433.340071 -56.908278) (xy 433.352244 -56.881726) (xy 433.356417 -56.852815)
			(xy 433.352252 -56.823904) (xy 433.340087 -56.797347) (xy 433.330858 -56.786018) (xy 433.330604 -56.785764)
			(xy 433.320196 -56.774568) (xy 433.294269 -56.758405) (xy 433.264722 -56.750633) (xy 433.234198 -56.751946)
			(xy 433.205427 -56.762227) (xy 433.180983 -56.780556) (xy 433.1716 -56.792622) (xy 433.156153 -56.813153)
			(xy 433.120646 -56.850289) (xy 433.080475 -56.882323) (xy 433.036368 -56.908674) (xy 432.989122 -56.928866)
			(xy 432.939594 -56.942534) (xy 432.88868 -56.949429) (xy 432.86299 -56.949848) (xy 432.83574 -56.949332)
			(xy 432.781796 -56.941575) (xy 432.729504 -56.92622) (xy 432.679929 -56.903581) (xy 432.634081 -56.874117)
			(xy 432.592892 -56.838429) (xy 432.557201 -56.797243) (xy 432.527733 -56.751397) (xy 432.50509 -56.701824)
			(xy 432.489732 -56.649534) (xy 432.481971 -56.59559) (xy 432.481482 -56.56834) (xy 432.481903 -56.541695)
			(xy 432.489309 -56.488921) (xy 432.503997 -56.437695) (xy 432.525678 -56.389015) (xy 432.553931 -56.34383)
			(xy 432.588205 -56.303023) (xy 432.60772 -56.284876) (xy 432.617643 -56.275375) (xy 432.632425 -56.252231)
			(xy 432.64051 -56.225985) (xy 432.641313 -56.198534) (xy 432.634776 -56.171861) (xy 432.621371 -56.147892)
			(xy 432.612038 -56.13781) (xy 432.604111 -56.129693) (xy 432.589114 -56.112665) (xy 432.582066 -56.103774)
			(xy 432.572169 -56.091969) (xy 432.546845 -56.07445) (xy 432.517452 -56.065274) (xy 432.48666 -56.065274)
			(xy 432.457267 -56.07445) (xy 432.431943 -56.091969) (xy 432.422046 -56.103774) (xy 432.403822 -56.12623)
			(xy 432.36181 -56.165968) (xy 432.314282 -56.198911) (xy 432.262327 -56.224304) (xy 432.207135 -56.241566)
			(xy 432.14997 -56.250302) (xy 432.121056 -56.25084) (xy 432.092423 -56.250308) (xy 432.035799 -56.241768)
			(xy 431.981088 -56.224857) (xy 431.929522 -56.199954) (xy 431.882259 -56.167621) (xy 431.86096 -56.148478)
			(xy 431.849747 -56.13867) (xy 431.823058 -56.125462) (xy 431.793693 -56.120517) (xy 431.76415 -56.124254)
			(xy 431.736942 -56.136357) (xy 431.725324 -56.145684) (xy 431.704466 -56.1631) (xy 431.658712 -56.192416)
			(xy 431.609259 -56.214937) (xy 431.55711 -56.230207) (xy 431.50332 -56.237916) (xy 431.47615 -56.238394)
			(xy 431.448781 -56.2379) (xy 431.394603 -56.230089) (xy 431.3421 -56.214607) (xy 431.292353 -56.191771)
			(xy 431.246385 -56.162052) (xy 431.225452 -56.144414) (xy 431.214124 -56.135178) (xy 431.187567 -56.123002)
			(xy 431.15865 -56.118829) (xy 431.129733 -56.123002) (xy 431.103176 -56.135178) (xy 431.091848 -56.144414)
			(xy 431.070915 -56.162055) (xy 431.024947 -56.191779) (xy 430.975201 -56.214625) (xy 430.922699 -56.230121)
			(xy 430.868521 -56.23795) (xy 430.813779 -56.23795) (xy 430.759601 -56.230121) (xy 430.707099 -56.214625)
			(xy 430.657353 -56.191779) (xy 430.611385 -56.162055) (xy 430.590452 -56.144414) (xy 430.579124 -56.135178)
			(xy 430.552567 -56.123002) (xy 430.52365 -56.118829) (xy 430.494733 -56.123002) (xy 430.468176 -56.135178)
			(xy 430.456848 -56.144414) (xy 430.43591 -56.162046) (xy 430.389939 -56.191759) (xy 430.340193 -56.214596)
			(xy 430.287693 -56.230088) (xy 430.233519 -56.237919) (xy 430.20615 -56.238394) (xy 430.178898 -56.237898)
			(xy 430.124947 -56.230148) (xy 430.072649 -56.214797) (xy 430.023068 -56.19216) (xy 429.977214 -56.162695)
			(xy 429.936021 -56.127005) (xy 429.900326 -56.085815) (xy 429.870858 -56.039963) (xy 429.848215 -55.990385)
			(xy 429.83286 -55.938088) (xy 429.825104 -55.884138) (xy 429.824642 -55.856886) (xy 429.82509 -55.829515)
			(xy 429.83291 -55.775335) (xy 429.848403 -55.722831) (xy 429.871249 -55.673084) (xy 429.900978 -55.627119)
			(xy 429.918622 -55.606188) (xy 429.927871 -55.59487) (xy 429.940044 -55.568309) (xy 429.944213 -55.539389)
			(xy 429.940038 -55.510471) (xy 429.927859 -55.483912) (xy 429.918622 -55.472584) (xy 429.901012 -55.451628)
			(xy 429.871295 -55.405662) (xy 429.848453 -55.355921) (xy 429.832955 -55.303425) (xy 429.82512 -55.249254)
			(xy 429.824642 -55.221886) (xy 429.825083 -55.195161) (xy 429.832537 -55.142234) (xy 429.847296 -55.090863)
			(xy 429.869073 -55.042052) (xy 429.897442 -54.996753) (xy 429.914304 -54.976014) (xy 429.922662 -54.9654)
			(xy 429.934098 -54.940939) (xy 429.938707 -54.914332) (xy 429.936164 -54.88745) (xy 429.926649 -54.862179)
			(xy 429.910829 -54.840296) (xy 429.900588 -54.831488) (xy 429.878857 -54.813288) (xy 429.840524 -54.771532)
			(xy 429.808792 -54.724563) (xy 429.78436 -54.673416) (xy 429.767766 -54.619216) (xy 429.759375 -54.563158)
			(xy 429.758856 -54.534816) (xy 417.156138 -54.534816) (xy 417.156138 -55.085972) (xy 424.924625 -55.085972)
			(xy 424.932379 -55.032017) (xy 424.947732 -54.979714) (xy 424.970373 -54.930128) (xy 424.99984 -54.88427)
			(xy 425.035533 -54.843071) (xy 425.076726 -54.807372) (xy 425.122581 -54.777899) (xy 425.172163 -54.755251)
			(xy 425.224464 -54.73989) (xy 425.278418 -54.732129) (xy 425.332928 -54.732125) (xy 425.386884 -54.739879)
			(xy 425.439187 -54.755232) (xy 425.488772 -54.777873) (xy 425.534631 -54.80734) (xy 425.575829 -54.843034)
			(xy 425.611528 -54.884227) (xy 425.641002 -54.930082) (xy 425.663649 -54.979664) (xy 425.67901 -55.031965)
			(xy 425.686771 -55.085919) (xy 425.687236 -55.113174) (xy 425.686645 -55.144073) (xy 425.681306 -55.176674)
			(xy 426.082458 -55.176674) (xy 426.086529 -55.121052) (xy 426.098655 -55.066615) (xy 426.118578 -55.014524)
			(xy 426.145874 -54.965889) (xy 426.17996 -54.921746) (xy 426.220109 -54.883037) (xy 426.265467 -54.850586)
			(xy 426.315067 -54.825085) (xy 426.367851 -54.807078) (xy 426.422694 -54.796948) (xy 426.478428 -54.794911)
			(xy 426.533865 -54.801011) (xy 426.587822 -54.815117) (xy 426.639151 -54.836929) (xy 426.686757 -54.865983)
			(xy 426.729625 -54.901658) (xy 426.766842 -54.943195) (xy 426.797615 -54.989708) (xy 426.821287 -55.040205)
			(xy 426.837355 -55.093612) (xy 426.845475 -55.148788) (xy 426.845984 -55.176674) (xy 426.845475 -55.20456)
			(xy 426.837355 -55.259736) (xy 426.821287 -55.313143) (xy 426.797615 -55.36364) (xy 426.766842 -55.410153)
			(xy 426.729625 -55.45169) (xy 426.686757 -55.487365) (xy 426.639151 -55.516419) (xy 426.587822 -55.538231)
			(xy 426.533865 -55.552337) (xy 426.478428 -55.558437) (xy 426.422694 -55.5564) (xy 426.367851 -55.54627)
			(xy 426.315067 -55.528263) (xy 426.265467 -55.502762) (xy 426.220109 -55.470311) (xy 426.17996 -55.431602)
			(xy 426.145874 -55.387459) (xy 426.118578 -55.338824) (xy 426.098655 -55.286733) (xy 426.086529 -55.232296)
			(xy 426.082458 -55.176674) (xy 425.681306 -55.176674) (xy 425.676658 -55.20506) (xy 425.656958 -55.263634)
			(xy 425.64304 -55.291228) (xy 425.637025 -55.30355) (xy 425.63116 -55.330325) (xy 425.632625 -55.357696)
			(xy 425.641313 -55.383693) (xy 425.6566 -55.406444) (xy 425.677385 -55.424313) (xy 425.702172 -55.436014)
			(xy 425.729178 -55.440704) (xy 425.742862 -55.439818) (xy 425.7802 -55.43804) (xy 425.807451 -55.438478)
			(xy 425.861397 -55.446234) (xy 425.91369 -55.461588) (xy 425.963266 -55.484228) (xy 426.009116 -55.513693)
			(xy 426.050306 -55.549383) (xy 426.085997 -55.590571) (xy 426.115464 -55.636419) (xy 426.138106 -55.685995)
			(xy 426.153463 -55.738287) (xy 426.161221 -55.792233) (xy 426.161223 -55.846735) (xy 426.15347 -55.900681)
			(xy 426.138117 -55.952975) (xy 426.11548 -56.002552) (xy 426.086017 -56.048403) (xy 426.050329 -56.089595)
			(xy 426.009142 -56.125288) (xy 425.963295 -56.154757) (xy 425.91372 -56.177401) (xy 425.861428 -56.192759)
			(xy 425.807482 -56.20052) (xy 425.752981 -56.200525) (xy 425.699034 -56.192773) (xy 425.64674 -56.177423)
			(xy 425.597162 -56.154787) (xy 425.55131 -56.125326) (xy 425.510117 -56.08964) (xy 425.474422 -56.048455)
			(xy 425.444951 -56.002609) (xy 425.422305 -55.953035) (xy 425.406944 -55.900744) (xy 425.399181 -55.846798)
			(xy 425.398692 -55.819548) (xy 425.3993 -55.78865) (xy 425.409281 -55.727664) (xy 425.428974 -55.669089)
			(xy 425.442888 -55.641494) (xy 425.44885 -55.629149) (xy 425.454714 -55.602383) (xy 425.453253 -55.575021)
			(xy 425.444571 -55.549032) (xy 425.429293 -55.526285) (xy 425.408518 -55.508418) (xy 425.383741 -55.496716)
			(xy 425.356745 -55.492022) (xy 425.343066 -55.492904) (xy 425.305728 -55.494682) (xy 425.278473 -55.494275)
			(xy 425.224517 -55.486521) (xy 425.172215 -55.471168) (xy 425.122629 -55.448528) (xy 425.07677 -55.419061)
			(xy 425.035572 -55.383367) (xy 424.999873 -55.342174) (xy 424.970399 -55.29632) (xy 424.947751 -55.246737)
			(xy 424.93239 -55.194437) (xy 424.924629 -55.140482) (xy 424.924625 -55.085972) (xy 417.156138 -55.085972)
			(xy 417.156138 -56.017414) (xy 424.457366 -56.017414) (xy 424.461437 -55.961792) (xy 424.473563 -55.907355)
			(xy 424.493486 -55.855264) (xy 424.520782 -55.806629) (xy 424.554868 -55.762486) (xy 424.595017 -55.723777)
			(xy 424.640375 -55.691326) (xy 424.689975 -55.665825) (xy 424.742759 -55.647818) (xy 424.797602 -55.637688)
			(xy 424.853336 -55.635651) (xy 424.908773 -55.641751) (xy 424.96273 -55.655857) (xy 425.014059 -55.677669)
			(xy 425.061665 -55.706723) (xy 425.104533 -55.742398) (xy 425.14175 -55.783935) (xy 425.172523 -55.830448)
			(xy 425.196195 -55.880945) (xy 425.212263 -55.934352) (xy 425.220383 -55.989528) (xy 425.220892 -56.017414)
			(xy 425.220383 -56.0453) (xy 425.212263 -56.100476) (xy 425.196195 -56.153883) (xy 425.172523 -56.20438)
			(xy 425.14175 -56.250893) (xy 425.104533 -56.29243) (xy 425.061665 -56.328105) (xy 425.014059 -56.357159)
			(xy 424.96273 -56.378971) (xy 424.908773 -56.393077) (xy 424.853336 -56.399177) (xy 424.797602 -56.39714)
			(xy 424.742759 -56.38701) (xy 424.689975 -56.369003) (xy 424.640375 -56.343502) (xy 424.595017 -56.311051)
			(xy 424.554868 -56.272342) (xy 424.520782 -56.228199) (xy 424.493486 -56.179564) (xy 424.473563 -56.127473)
			(xy 424.461437 -56.073036) (xy 424.457366 -56.017414) (xy 417.156138 -56.017414) (xy 417.156138 -56.497728)
			(xy 423.398186 -56.497728) (xy 423.402257 -56.442106) (xy 423.414383 -56.387669) (xy 423.434306 -56.335578)
			(xy 423.461602 -56.286943) (xy 423.495688 -56.2428) (xy 423.535837 -56.204091) (xy 423.581195 -56.17164)
			(xy 423.630795 -56.146139) (xy 423.683579 -56.128132) (xy 423.738422 -56.118002) (xy 423.794156 -56.115965)
			(xy 423.849593 -56.122065) (xy 423.90355 -56.136171) (xy 423.954879 -56.157983) (xy 424.002485 -56.187037)
			(xy 424.045353 -56.222712) (xy 424.08257 -56.264249) (xy 424.113343 -56.310762) (xy 424.137015 -56.361259)
			(xy 424.153083 -56.414666) (xy 424.161203 -56.469842) (xy 424.161712 -56.497728) (xy 424.161203 -56.525614)
			(xy 424.153083 -56.58079) (xy 424.137015 -56.634197) (xy 424.113343 -56.684694) (xy 424.08257 -56.731207)
			(xy 424.045353 -56.772744) (xy 424.002485 -56.808419) (xy 423.954879 -56.837473) (xy 423.90355 -56.859285)
			(xy 423.849593 -56.873391) (xy 423.794156 -56.879491) (xy 423.738422 -56.877454) (xy 423.683579 -56.867324)
			(xy 423.630795 -56.849317) (xy 423.581195 -56.823816) (xy 423.535837 -56.791365) (xy 423.495688 -56.752656)
			(xy 423.461602 -56.708513) (xy 423.434306 -56.659878) (xy 423.414383 -56.607787) (xy 423.402257 -56.55335)
			(xy 423.398186 -56.497728) (xy 417.156138 -56.497728) (xy 417.156138 -57.191148) (xy 422.493946 -57.191148)
			(xy 422.498017 -57.135526) (xy 422.510143 -57.081089) (xy 422.530066 -57.028998) (xy 422.557362 -56.980363)
			(xy 422.591448 -56.93622) (xy 422.631597 -56.897511) (xy 422.676955 -56.86506) (xy 422.726555 -56.839559)
			(xy 422.779339 -56.821552) (xy 422.834182 -56.811422) (xy 422.889916 -56.809385) (xy 422.945353 -56.815485)
			(xy 422.99931 -56.829591) (xy 423.050639 -56.851403) (xy 423.098245 -56.880457) (xy 423.141113 -56.916132)
			(xy 423.17833 -56.957669) (xy 423.209103 -57.004182) (xy 423.232775 -57.054679) (xy 423.248843 -57.108086)
			(xy 423.256963 -57.163262) (xy 423.257472 -57.191148) (xy 423.256963 -57.219034) (xy 423.248843 -57.27421)
			(xy 423.232775 -57.327617) (xy 423.209103 -57.378114) (xy 423.17833 -57.424627) (xy 423.141113 -57.466164)
			(xy 423.098245 -57.501839) (xy 423.050639 -57.530893) (xy 422.99931 -57.552705) (xy 422.945353 -57.566811)
			(xy 422.889916 -57.572911) (xy 422.834182 -57.570874) (xy 422.779339 -57.560744) (xy 422.726555 -57.542737)
			(xy 422.676955 -57.517236) (xy 422.631597 -57.484785) (xy 422.591448 -57.446076) (xy 422.557362 -57.401933)
			(xy 422.530066 -57.353298) (xy 422.510143 -57.301207) (xy 422.498017 -57.24677) (xy 422.493946 -57.191148)
			(xy 417.156138 -57.191148) (xy 417.156138 -57.797192) (xy 421.476676 -57.797192) (xy 421.480747 -57.74157)
			(xy 421.492873 -57.687133) (xy 421.512796 -57.635042) (xy 421.540092 -57.586407) (xy 421.574178 -57.542264)
			(xy 421.614327 -57.503555) (xy 421.659685 -57.471104) (xy 421.709285 -57.445603) (xy 421.762069 -57.427596)
			(xy 421.816912 -57.417466) (xy 421.872646 -57.415429) (xy 421.928083 -57.421529) (xy 421.98204 -57.435635)
			(xy 422.033369 -57.457447) (xy 422.080975 -57.486501) (xy 422.123843 -57.522176) (xy 422.16106 -57.563713)
			(xy 422.191833 -57.610226) (xy 422.215505 -57.660723) (xy 422.231573 -57.71413) (xy 422.239693 -57.769306)
			(xy 422.240202 -57.797192) (xy 422.239693 -57.825078) (xy 422.231573 -57.880254) (xy 422.215505 -57.933661)
			(xy 422.191833 -57.984158) (xy 422.16106 -58.030671) (xy 422.123843 -58.072208) (xy 422.080975 -58.107883)
			(xy 422.033369 -58.136937) (xy 421.98204 -58.158749) (xy 421.928083 -58.172855) (xy 421.872646 -58.178955)
			(xy 421.816912 -58.176918) (xy 421.762069 -58.166788) (xy 421.709285 -58.148781) (xy 421.659685 -58.12328)
			(xy 421.614327 -58.090829) (xy 421.574178 -58.05212) (xy 421.540092 -58.007977) (xy 421.512796 -57.959342)
			(xy 421.492873 -57.907251) (xy 421.480747 -57.852814) (xy 421.476676 -57.797192) (xy 417.156138 -57.797192)
			(xy 417.156138 -58.6994) (xy 421.302686 -58.6994) (xy 421.306757 -58.643778) (xy 421.318883 -58.589341)
			(xy 421.338806 -58.53725) (xy 421.366102 -58.488615) (xy 421.400188 -58.444472) (xy 421.440337 -58.405763)
			(xy 421.485695 -58.373312) (xy 421.535295 -58.347811) (xy 421.588079 -58.329804) (xy 421.642922 -58.319674)
			(xy 421.698656 -58.317637) (xy 421.754093 -58.323737) (xy 421.80805 -58.337843) (xy 421.828046 -58.34634)
			(xy 422.800778 -58.34634) (xy 422.804849 -58.290718) (xy 422.816975 -58.236281) (xy 422.836898 -58.18419)
			(xy 422.864194 -58.135555) (xy 422.89828 -58.091412) (xy 422.938429 -58.052703) (xy 422.983787 -58.020252)
			(xy 423.033387 -57.994751) (xy 423.086171 -57.976744) (xy 423.141014 -57.966614) (xy 423.196748 -57.964577)
			(xy 423.252185 -57.970677) (xy 423.306142 -57.984783) (xy 423.357471 -58.006595) (xy 423.405077 -58.035649)
			(xy 423.447945 -58.071324) (xy 423.485162 -58.112861) (xy 423.515935 -58.159374) (xy 423.539607 -58.209871)
			(xy 423.555675 -58.263278) (xy 423.558629 -58.283348) (xy 423.899582 -58.283348) (xy 423.903653 -58.227726)
			(xy 423.915779 -58.173289) (xy 423.935702 -58.121198) (xy 423.962998 -58.072563) (xy 423.997084 -58.02842)
			(xy 424.037233 -57.989711) (xy 424.082591 -57.95726) (xy 424.132191 -57.931759) (xy 424.184975 -57.913752)
			(xy 424.239818 -57.903622) (xy 424.295552 -57.901585) (xy 424.302486 -57.902348) (xy 426.820582 -57.902348)
			(xy 426.824653 -57.846726) (xy 426.836779 -57.792289) (xy 426.856702 -57.740198) (xy 426.883998 -57.691563)
			(xy 426.918084 -57.64742) (xy 426.958233 -57.608711) (xy 427.003591 -57.57626) (xy 427.053191 -57.550759)
			(xy 427.105975 -57.532752) (xy 427.160818 -57.522622) (xy 427.216552 -57.520585) (xy 427.271989 -57.526685)
			(xy 427.325946 -57.540791) (xy 427.377275 -57.562603) (xy 427.424881 -57.591657) (xy 427.467749 -57.627332)
			(xy 427.504966 -57.668869) (xy 427.535739 -57.715382) (xy 427.559411 -57.765879) (xy 427.575479 -57.819286)
			(xy 427.583599 -57.874462) (xy 427.584108 -57.902348) (xy 427.583599 -57.930234) (xy 427.575479 -57.98541)
			(xy 427.559411 -58.038817) (xy 427.535739 -58.089314) (xy 427.504966 -58.135827) (xy 427.467749 -58.177364)
			(xy 427.424881 -58.213039) (xy 427.377275 -58.242093) (xy 427.325946 -58.263905) (xy 427.271989 -58.278011)
			(xy 427.216552 -58.284111) (xy 427.160818 -58.282074) (xy 427.105975 -58.271944) (xy 427.053191 -58.253937)
			(xy 427.003591 -58.228436) (xy 426.958233 -58.195985) (xy 426.918084 -58.157276) (xy 426.883998 -58.113133)
			(xy 426.856702 -58.064498) (xy 426.836779 -58.012407) (xy 426.824653 -57.95797) (xy 426.820582 -57.902348)
			(xy 424.302486 -57.902348) (xy 424.350989 -57.907685) (xy 424.404946 -57.921791) (xy 424.456275 -57.943603)
			(xy 424.503881 -57.972657) (xy 424.546749 -58.008332) (xy 424.583966 -58.049869) (xy 424.614739 -58.096382)
			(xy 424.638411 -58.146879) (xy 424.654479 -58.200286) (xy 424.662599 -58.255462) (xy 424.663108 -58.283348)
			(xy 424.662599 -58.311234) (xy 424.654479 -58.36641) (xy 424.638411 -58.419817) (xy 424.614739 -58.470314)
			(xy 424.583966 -58.516827) (xy 424.546749 -58.558364) (xy 424.503881 -58.594039) (xy 424.456275 -58.623093)
			(xy 424.404946 -58.644905) (xy 424.350989 -58.659011) (xy 424.295552 -58.665111) (xy 424.239818 -58.663074)
			(xy 424.184975 -58.652944) (xy 424.132191 -58.634937) (xy 424.082591 -58.609436) (xy 424.037233 -58.576985)
			(xy 423.997084 -58.538276) (xy 423.962998 -58.494133) (xy 423.935702 -58.445498) (xy 423.915779 -58.393407)
			(xy 423.903653 -58.33897) (xy 423.899582 -58.283348) (xy 423.558629 -58.283348) (xy 423.563795 -58.318454)
			(xy 423.564304 -58.34634) (xy 423.563795 -58.374226) (xy 423.555675 -58.429402) (xy 423.539607 -58.482809)
			(xy 423.515935 -58.533306) (xy 423.485162 -58.579819) (xy 423.447945 -58.621356) (xy 423.405077 -58.657031)
			(xy 423.357471 -58.686085) (xy 423.306142 -58.707897) (xy 423.252185 -58.722003) (xy 423.196748 -58.728103)
			(xy 423.141014 -58.726066) (xy 423.086171 -58.715936) (xy 423.033387 -58.697929) (xy 422.983787 -58.672428)
			(xy 422.938429 -58.639977) (xy 422.89828 -58.601268) (xy 422.864194 -58.557125) (xy 422.836898 -58.50849)
			(xy 422.816975 -58.456399) (xy 422.804849 -58.401962) (xy 422.800778 -58.34634) (xy 421.828046 -58.34634)
			(xy 421.859379 -58.359655) (xy 421.906985 -58.388709) (xy 421.949853 -58.424384) (xy 421.98707 -58.465921)
			(xy 422.017843 -58.512434) (xy 422.041515 -58.562931) (xy 422.057583 -58.616338) (xy 422.065703 -58.671514)
			(xy 422.066212 -58.6994) (xy 422.065703 -58.727286) (xy 422.057583 -58.782462) (xy 422.041515 -58.835869)
			(xy 422.017843 -58.886366) (xy 421.98707 -58.932879) (xy 421.949853 -58.974416) (xy 421.906985 -59.010091)
			(xy 421.859379 -59.039145) (xy 421.80805 -59.060957) (xy 421.754093 -59.075063) (xy 421.698656 -59.081163)
			(xy 421.642922 -59.079126) (xy 421.588079 -59.068996) (xy 421.535295 -59.050989) (xy 421.485695 -59.025488)
			(xy 421.440337 -58.993037) (xy 421.400188 -58.954328) (xy 421.366102 -58.910185) (xy 421.338806 -58.86155)
			(xy 421.318883 -58.809459) (xy 421.306757 -58.755022) (xy 421.302686 -58.6994) (xy 417.156138 -58.6994)
			(xy 417.156138 -59.226196) (xy 429.89119 -59.226196) (xy 429.891671 -59.197277) (xy 429.900403 -59.140103)
			(xy 429.917666 -59.084902) (xy 429.943065 -59.032939) (xy 429.976016 -58.985407) (xy 430.015766 -58.943393)
			(xy 430.038256 -58.925206) (xy 430.050068 -58.915315) (xy 430.067591 -58.889991) (xy 430.076769 -58.860595)
			(xy 430.076768 -58.8298) (xy 430.067589 -58.800405) (xy 430.050065 -58.775082) (xy 430.038256 -58.765186)
			(xy 430.015757 -58.747014) (xy 429.976024 -58.704989) (xy 429.943089 -58.65745) (xy 429.917703 -58.605485)
			(xy 429.90045 -58.550285) (xy 429.891724 -58.493113) (xy 429.89119 -58.464196) (xy 429.891676 -58.436945)
			(xy 429.899432 -58.382997) (xy 429.914787 -58.330702) (xy 429.937429 -58.281125) (xy 429.966895 -58.235275)
			(xy 430.002586 -58.194084) (xy 430.043777 -58.158393) (xy 430.089627 -58.128927) (xy 430.139204 -58.106285)
			(xy 430.191499 -58.09093) (xy 430.245447 -58.083174) (xy 430.299949 -58.083174) (xy 430.353897 -58.09093)
			(xy 430.406192 -58.106285) (xy 430.455769 -58.128927) (xy 430.501619 -58.158393) (xy 430.54281 -58.194084)
			(xy 430.578501 -58.235275) (xy 430.607967 -58.281125) (xy 430.630609 -58.330702) (xy 430.645964 -58.382997)
			(xy 430.65372 -58.436945) (xy 430.654206 -58.464196) (xy 430.653721 -58.493115) (xy 430.64499 -58.550289)
			(xy 430.627728 -58.60549) (xy 430.60233 -58.657452) (xy 430.569379 -58.704985) (xy 430.52963 -58.746999)
			(xy 430.50714 -58.765186) (xy 430.495336 -58.775086) (xy 430.477814 -58.800408) (xy 430.468635 -58.829801)
			(xy 430.468635 -58.860594) (xy 430.477812 -58.889988) (xy 430.495333 -58.91531) (xy 430.50714 -58.925206)
			(xy 430.529635 -58.943384) (xy 430.556876 -58.972196) (xy 432.30368 -58.972196) (xy 432.307751 -58.916574)
			(xy 432.319877 -58.862137) (xy 432.3398 -58.810046) (xy 432.367096 -58.761411) (xy 432.401182 -58.717268)
			(xy 432.441331 -58.678559) (xy 432.486689 -58.646108) (xy 432.536289 -58.620607) (xy 432.589073 -58.6026)
			(xy 432.643916 -58.59247) (xy 432.69965 -58.590433) (xy 432.755087 -58.596533) (xy 432.809044 -58.610639)
			(xy 432.860373 -58.632451) (xy 432.907979 -58.661505) (xy 432.950847 -58.69718) (xy 432.988064 -58.738717)
			(xy 433.018837 -58.78523) (xy 433.042509 -58.835727) (xy 433.058577 -58.889134) (xy 433.066697 -58.94431)
			(xy 433.067206 -58.972196) (xy 433.066697 -59.000082) (xy 433.058577 -59.055258) (xy 433.042509 -59.108665)
			(xy 433.018837 -59.159162) (xy 432.988064 -59.205675) (xy 432.950847 -59.247212) (xy 432.907979 -59.282887)
			(xy 432.860373 -59.311941) (xy 432.809044 -59.333753) (xy 432.755087 -59.347859) (xy 432.69965 -59.353959)
			(xy 432.643916 -59.351922) (xy 432.589073 -59.341792) (xy 432.536289 -59.323785) (xy 432.486689 -59.298284)
			(xy 432.441331 -59.265833) (xy 432.401182 -59.227124) (xy 432.367096 -59.182981) (xy 432.3398 -59.134346)
			(xy 432.319877 -59.082255) (xy 432.307751 -59.027818) (xy 432.30368 -58.972196) (xy 430.556876 -58.972196)
			(xy 430.569367 -58.985407) (xy 430.602304 -59.032945) (xy 430.62769 -59.084909) (xy 430.644944 -59.140108)
			(xy 430.653672 -59.197279) (xy 430.654206 -59.226196) (xy 430.65372 -59.253447) (xy 430.645964 -59.307395)
			(xy 430.630609 -59.35969) (xy 430.607967 -59.409267) (xy 430.578501 -59.455117) (xy 430.54281 -59.496308)
			(xy 430.501619 -59.531999) (xy 430.455769 -59.561465) (xy 430.406192 -59.584107) (xy 430.353897 -59.599462)
			(xy 430.299949 -59.607218) (xy 430.245447 -59.607218) (xy 430.191499 -59.599462) (xy 430.139204 -59.584107)
			(xy 430.089627 -59.561465) (xy 430.043777 -59.531999) (xy 430.002586 -59.496308) (xy 429.966895 -59.455117)
			(xy 429.937429 -59.409267) (xy 429.914787 -59.35969) (xy 429.899432 -59.307395) (xy 429.891676 -59.253447)
			(xy 429.89119 -59.226196) (xy 417.156138 -59.226196) (xy 417.156138 -74.767948) (xy 421.29456 -74.767948)
			(xy 421.29456 -66.06794) (xy 421.295065 -65.962416) (xy 421.303149 -65.751522) (xy 421.319305 -65.541093)
			(xy 421.343508 -65.331436) (xy 421.375725 -65.122861) (xy 421.415907 -64.915673) (xy 421.463995 -64.710176)
			(xy 421.519919 -64.506672) (xy 421.583596 -64.305459) (xy 421.654934 -64.106832) (xy 421.733828 -63.911084)
			(xy 421.820161 -63.718502) (xy 421.913808 -63.529367) (xy 422.01463 -63.343958) (xy 422.12248 -63.162547)
			(xy 422.237199 -62.9854) (xy 422.358619 -62.812778) (xy 422.486562 -62.644932) (xy 422.62084 -62.48211)
			(xy 422.761256 -62.324551) (xy 422.907604 -62.172486) (xy 423.059669 -62.026138) (xy 423.217228 -61.885722)
			(xy 423.38005 -61.751444) (xy 423.547896 -61.623501) (xy 423.720518 -61.502081) (xy 423.897665 -61.387362)
			(xy 424.079076 -61.279512) (xy 424.264485 -61.17869) (xy 424.45362 -61.085043) (xy 424.646202 -60.99871)
			(xy 424.84195 -60.919816) (xy 425.040577 -60.848478) (xy 425.24179 -60.784801) (xy 425.445294 -60.728877)
			(xy 425.650791 -60.680789) (xy 425.857979 -60.640607) (xy 426.066554 -60.60839) (xy 426.276211 -60.584187)
			(xy 426.48664 -60.568031) (xy 426.697534 -60.559947) (xy 426.908582 -60.559947) (xy 427.119476 -60.568031)
			(xy 427.329905 -60.584187) (xy 427.539562 -60.60839) (xy 427.748137 -60.640607) (xy 427.955325 -60.680789)
			(xy 428.160822 -60.728877) (xy 428.364326 -60.784801) (xy 428.565539 -60.848478) (xy 428.764166 -60.919816)
			(xy 428.959914 -60.99871) (xy 429.152496 -61.085043) (xy 429.341631 -61.17869) (xy 429.52704 -61.279512)
			(xy 429.708451 -61.387362) (xy 429.885598 -61.502081) (xy 430.05822 -61.623501) (xy 430.226066 -61.751444)
			(xy 430.388888 -61.885722) (xy 430.546447 -62.026138) (xy 430.698512 -62.172486) (xy 430.84486 -62.324551)
			(xy 430.985276 -62.48211) (xy 431.119554 -62.644932) (xy 431.247497 -62.812778) (xy 431.368917 -62.9854)
			(xy 431.483636 -63.162547) (xy 431.591486 -63.343958) (xy 431.692308 -63.529367) (xy 431.785955 -63.718502)
			(xy 431.872288 -63.911084) (xy 431.951182 -64.106832) (xy 432.02252 -64.305459) (xy 432.086197 -64.506672)
			(xy 432.142121 -64.710176) (xy 432.190209 -64.915673) (xy 432.230391 -65.122861) (xy 432.262608 -65.331436)
			(xy 432.286811 -65.541093) (xy 432.302967 -65.751522) (xy 432.311051 -65.962416) (xy 432.311556 -66.06794)
			(xy 432.311556 -74.767948) (xy 432.311051 -74.873472) (xy 432.302967 -75.084366) (xy 432.286811 -75.294795)
			(xy 432.262608 -75.504452) (xy 432.230391 -75.713027) (xy 432.190209 -75.920215) (xy 432.142121 -76.125712)
			(xy 432.086197 -76.329216) (xy 432.02252 -76.530429) (xy 431.951182 -76.729056) (xy 431.872288 -76.924804)
			(xy 431.785955 -77.117386) (xy 431.692308 -77.306521) (xy 431.591486 -77.49193) (xy 431.483636 -77.673341)
			(xy 431.368917 -77.850488) (xy 431.247497 -78.02311) (xy 431.119554 -78.190956) (xy 430.985276 -78.353778)
			(xy 430.84486 -78.511337) (xy 430.698512 -78.663402) (xy 430.546447 -78.80975) (xy 430.388888 -78.950166)
			(xy 430.226066 -79.084444) (xy 430.05822 -79.212387) (xy 429.885598 -79.333807) (xy 429.708451 -79.448526)
			(xy 429.52704 -79.556376) (xy 429.341631 -79.657198) (xy 429.152496 -79.750845) (xy 428.959914 -79.837178)
			(xy 428.764166 -79.916072) (xy 428.565539 -79.98741) (xy 428.364326 -80.051087) (xy 428.160822 -80.107011)
			(xy 427.955325 -80.155099) (xy 427.748137 -80.195281) (xy 427.539562 -80.227498) (xy 427.329905 -80.251701)
			(xy 427.119476 -80.267857) (xy 426.908582 -80.275941) (xy 426.697534 -80.275941) (xy 426.48664 -80.267857)
			(xy 426.276211 -80.251701) (xy 426.066554 -80.227498) (xy 425.857979 -80.195281) (xy 425.650791 -80.155099)
			(xy 425.445294 -80.107011) (xy 425.24179 -80.051087) (xy 425.040577 -79.98741) (xy 424.84195 -79.916072)
			(xy 424.646202 -79.837178) (xy 424.45362 -79.750845) (xy 424.264485 -79.657198) (xy 424.079076 -79.556376)
			(xy 423.897665 -79.448526) (xy 423.720518 -79.333807) (xy 423.547896 -79.212387) (xy 423.38005 -79.084444)
			(xy 423.217228 -78.950166) (xy 423.059669 -78.80975) (xy 422.907604 -78.663402) (xy 422.761256 -78.511337)
			(xy 422.62084 -78.353778) (xy 422.486562 -78.190956) (xy 422.358619 -78.02311) (xy 422.237199 -77.850488)
			(xy 422.12248 -77.673341) (xy 422.01463 -77.49193) (xy 421.913808 -77.306521) (xy 421.820161 -77.117386)
			(xy 421.733828 -76.924804) (xy 421.654934 -76.729056) (xy 421.583596 -76.530429) (xy 421.519919 -76.329216)
			(xy 421.463995 -76.125712) (xy 421.415907 -75.920215) (xy 421.375725 -75.713027) (xy 421.343508 -75.504452)
			(xy 421.319305 -75.294795) (xy 421.303149 -75.084366) (xy 421.295065 -74.873472) (xy 421.29456 -74.767948)
			(xy 417.156138 -74.767948) (xy 417.156138 -91.270836) (xy 437.855358 -91.270836) (xy 437.859429 -91.215214)
			(xy 437.871555 -91.160777) (xy 437.891478 -91.108686) (xy 437.918774 -91.060051) (xy 437.95286 -91.015908)
			(xy 437.993009 -90.977199) (xy 438.038367 -90.944748) (xy 438.087967 -90.919247) (xy 438.140751 -90.90124)
			(xy 438.195594 -90.89111) (xy 438.251328 -90.889073) (xy 438.306765 -90.895173) (xy 438.360722 -90.909279)
			(xy 438.412051 -90.931091) (xy 438.459657 -90.960145) (xy 438.502525 -90.99582) (xy 438.539742 -91.037357)
			(xy 438.570515 -91.08387) (xy 438.594187 -91.134367) (xy 438.610255 -91.187774) (xy 438.618375 -91.24295)
			(xy 438.618884 -91.270836) (xy 438.618375 -91.298722) (xy 438.610255 -91.353898) (xy 438.594187 -91.407305)
			(xy 438.570515 -91.457802) (xy 438.539742 -91.504315) (xy 438.502525 -91.545852) (xy 438.459657 -91.581527)
			(xy 438.412051 -91.610581) (xy 438.360722 -91.632393) (xy 438.306765 -91.646499) (xy 438.251328 -91.652599)
			(xy 438.195594 -91.650562) (xy 438.140751 -91.640432) (xy 438.087967 -91.622425) (xy 438.038367 -91.596924)
			(xy 437.993009 -91.564473) (xy 437.95286 -91.525764) (xy 437.918774 -91.481621) (xy 437.891478 -91.432986)
			(xy 437.871555 -91.380895) (xy 437.859429 -91.326458) (xy 437.855358 -91.270836) (xy 417.156138 -91.270836)
			(xy 417.156138 -93.891608) (xy 430.965862 -93.891608) (xy 430.969933 -93.835986) (xy 430.982059 -93.781549)
			(xy 431.001982 -93.729458) (xy 431.029278 -93.680823) (xy 431.063364 -93.63668) (xy 431.103513 -93.597971)
			(xy 431.148871 -93.56552) (xy 431.198471 -93.540019) (xy 431.251255 -93.522012) (xy 431.306098 -93.511882)
			(xy 431.361832 -93.509845) (xy 431.417269 -93.515945) (xy 431.471226 -93.530051) (xy 431.522555 -93.551863)
			(xy 431.570161 -93.580917) (xy 431.613029 -93.616592) (xy 431.650246 -93.658129) (xy 431.681019 -93.704642)
			(xy 431.704691 -93.755139) (xy 431.720759 -93.808546) (xy 431.728879 -93.863722) (xy 431.729388 -93.891608)
			(xy 431.728879 -93.919494) (xy 431.720759 -93.97467) (xy 431.704691 -94.028077) (xy 431.681019 -94.078574)
			(xy 431.650246 -94.125087) (xy 431.613029 -94.166624) (xy 431.570161 -94.202299) (xy 431.522555 -94.231353)
			(xy 431.471226 -94.253165) (xy 431.417269 -94.267271) (xy 431.361832 -94.273371) (xy 431.306098 -94.271334)
			(xy 431.251255 -94.261204) (xy 431.198471 -94.243197) (xy 431.148871 -94.217696) (xy 431.103513 -94.185245)
			(xy 431.063364 -94.146536) (xy 431.029278 -94.102393) (xy 431.001982 -94.053758) (xy 430.982059 -94.001667)
			(xy 430.969933 -93.94723) (xy 430.965862 -93.891608) (xy 417.156138 -93.891608) (xy 417.156138 -94.275148)
			(xy 436.294782 -94.275148) (xy 436.298853 -94.219526) (xy 436.310979 -94.165089) (xy 436.330902 -94.112998)
			(xy 436.358198 -94.064363) (xy 436.392284 -94.02022) (xy 436.432433 -93.981511) (xy 436.477791 -93.94906)
			(xy 436.527391 -93.923559) (xy 436.580175 -93.905552) (xy 436.635018 -93.895422) (xy 436.690752 -93.893385)
			(xy 436.746189 -93.899485) (xy 436.800146 -93.913591) (xy 436.851475 -93.935403) (xy 436.899081 -93.964457)
			(xy 436.941949 -94.000132) (xy 436.979166 -94.041669) (xy 437.009939 -94.088182) (xy 437.033611 -94.138679)
			(xy 437.049679 -94.192086) (xy 437.057799 -94.247262) (xy 437.058308 -94.275148) (xy 437.057799 -94.303034)
			(xy 437.049679 -94.35821) (xy 437.033611 -94.411617) (xy 437.009939 -94.462114) (xy 436.982394 -94.503748)
			(xy 437.869582 -94.503748) (xy 437.873653 -94.448126) (xy 437.885779 -94.393689) (xy 437.905702 -94.341598)
			(xy 437.932998 -94.292963) (xy 437.967084 -94.24882) (xy 438.007233 -94.210111) (xy 438.052591 -94.17766)
			(xy 438.102191 -94.152159) (xy 438.154975 -94.134152) (xy 438.209818 -94.124022) (xy 438.265552 -94.121985)
			(xy 438.320989 -94.128085) (xy 438.374946 -94.142191) (xy 438.426275 -94.164003) (xy 438.473881 -94.193057)
			(xy 438.516749 -94.228732) (xy 438.553966 -94.270269) (xy 438.584739 -94.316782) (xy 438.608411 -94.367279)
			(xy 438.624479 -94.420686) (xy 438.632599 -94.475862) (xy 438.633108 -94.503748) (xy 438.632599 -94.531634)
			(xy 438.624479 -94.58681) (xy 438.608411 -94.640217) (xy 438.584739 -94.690714) (xy 438.553966 -94.737227)
			(xy 438.516749 -94.778764) (xy 438.473881 -94.814439) (xy 438.426275 -94.843493) (xy 438.374946 -94.865305)
			(xy 438.320989 -94.879411) (xy 438.265552 -94.885511) (xy 438.209818 -94.883474) (xy 438.154975 -94.873344)
			(xy 438.102191 -94.855337) (xy 438.052591 -94.829836) (xy 438.007233 -94.797385) (xy 437.967084 -94.758676)
			(xy 437.932998 -94.714533) (xy 437.905702 -94.665898) (xy 437.885779 -94.613807) (xy 437.873653 -94.55937)
			(xy 437.869582 -94.503748) (xy 436.982394 -94.503748) (xy 436.979166 -94.508627) (xy 436.941949 -94.550164)
			(xy 436.899081 -94.585839) (xy 436.851475 -94.614893) (xy 436.800146 -94.636705) (xy 436.746189 -94.650811)
			(xy 436.690752 -94.656911) (xy 436.635018 -94.654874) (xy 436.580175 -94.644744) (xy 436.527391 -94.626737)
			(xy 436.477791 -94.601236) (xy 436.432433 -94.568785) (xy 436.392284 -94.530076) (xy 436.358198 -94.485933)
			(xy 436.330902 -94.437298) (xy 436.310979 -94.385207) (xy 436.298853 -94.33077) (xy 436.294782 -94.275148)
			(xy 417.156138 -94.275148) (xy 417.156138 -95.113348) (xy 436.853582 -95.113348) (xy 436.857653 -95.057726)
			(xy 436.869779 -95.003289) (xy 436.889702 -94.951198) (xy 436.916998 -94.902563) (xy 436.951084 -94.85842)
			(xy 436.991233 -94.819711) (xy 437.036591 -94.78726) (xy 437.086191 -94.761759) (xy 437.138975 -94.743752)
			(xy 437.193818 -94.733622) (xy 437.249552 -94.731585) (xy 437.304989 -94.737685) (xy 437.358946 -94.751791)
			(xy 437.410275 -94.773603) (xy 437.457881 -94.802657) (xy 437.500749 -94.838332) (xy 437.537966 -94.879869)
			(xy 437.568739 -94.926382) (xy 437.592411 -94.976879) (xy 437.608479 -95.030286) (xy 437.616599 -95.085462)
			(xy 437.617108 -95.113348) (xy 437.616599 -95.141234) (xy 437.608479 -95.19641) (xy 437.592411 -95.249817)
			(xy 437.568739 -95.300314) (xy 437.537966 -95.346827) (xy 437.500749 -95.388364) (xy 437.457881 -95.424039)
			(xy 437.410275 -95.453093) (xy 437.358946 -95.474905) (xy 437.304989 -95.489011) (xy 437.249552 -95.495111)
			(xy 437.193818 -95.493074) (xy 437.138975 -95.482944) (xy 437.086191 -95.464937) (xy 437.036591 -95.439436)
			(xy 436.991233 -95.406985) (xy 436.951084 -95.368276) (xy 436.916998 -95.324133) (xy 436.889702 -95.275498)
			(xy 436.869779 -95.223407) (xy 436.857653 -95.16897) (xy 436.853582 -95.113348) (xy 417.156138 -95.113348)
			(xy 417.156138 -97.450148) (xy 437.894982 -97.450148) (xy 437.899053 -97.394526) (xy 437.911179 -97.340089)
			(xy 437.931102 -97.287998) (xy 437.958398 -97.239363) (xy 437.992484 -97.19522) (xy 438.032633 -97.156511)
			(xy 438.077991 -97.12406) (xy 438.127591 -97.098559) (xy 438.180375 -97.080552) (xy 438.235218 -97.070422)
			(xy 438.290952 -97.068385) (xy 438.346389 -97.074485) (xy 438.400346 -97.088591) (xy 438.451675 -97.110403)
			(xy 438.499281 -97.139457) (xy 438.542149 -97.175132) (xy 438.579366 -97.216669) (xy 438.610139 -97.263182)
			(xy 438.633811 -97.313679) (xy 438.649879 -97.367086) (xy 438.657999 -97.422262) (xy 438.658508 -97.450148)
			(xy 438.657999 -97.478034) (xy 438.649879 -97.53321) (xy 438.633811 -97.586617) (xy 438.610139 -97.637114)
			(xy 438.579366 -97.683627) (xy 438.542149 -97.725164) (xy 438.499281 -97.760839) (xy 438.451675 -97.789893)
			(xy 438.400346 -97.811705) (xy 438.346389 -97.825811) (xy 438.290952 -97.831911) (xy 438.235218 -97.829874)
			(xy 438.180375 -97.819744) (xy 438.127591 -97.801737) (xy 438.077991 -97.776236) (xy 438.032633 -97.743785)
			(xy 437.992484 -97.705076) (xy 437.958398 -97.660933) (xy 437.931102 -97.612298) (xy 437.911179 -97.560207)
			(xy 437.899053 -97.50577) (xy 437.894982 -97.450148) (xy 417.156138 -97.450148) (xy 417.156138 -98.626168)
			(xy 418.996368 -100.466398)
		)
		(stroke
			(width 0)
			(type solid)
		)
		(fill yes)
		(layer "In13.Cu")
		(net "P3V3_OCP_SFF")
	)
	(gr_poly
		(pts
			(xy 332.378812 -331.909166) (xy 332.393544 -331.89418) (xy 332.393544 -330.858876) (xy 332.393973 -330.848809)
			(xy 332.401698 -330.830215) (xy 332.40853 -330.822808) (xy 334.193388 -329.03795) (xy 334.200783 -329.031096)
			(xy 334.219382 -329.02335) (xy 334.229456 -329.022964) (xy 339.780372 -329.022964) (xy 339.790333 -329.022476)
			(xy 339.808752 -329.014883) (xy 339.816186 -329.008232) (xy 343.032588 -325.79183) (xy 343.039985 -325.784979)
			(xy 343.058583 -325.777235) (xy 343.068656 -325.776844) (xy 371.907816 -325.776844) (xy 371.917884 -325.777271)
			(xy 371.93648 -325.784995) (xy 371.943884 -325.79183) (xy 372.015512 -325.863458) (xy 372.015766 -325.863458)
			(xy 372.10492 -325.952612) (xy 372.104666 -325.952612) (xy 375.336054 -329.184) (xy 375.35104 -329.198732)
			(xy 379.937264 -329.198732) (xy 379.947328 -329.199167) (xy 379.965913 -329.206902) (xy 379.973332 -329.213718)
			(xy 381.713232 -330.953364) (xy 382.003808 -331.24394) (xy 382.018794 -331.258672) (xy 387.854444 -331.258672)
			(xy 388.34568 -330.767436) (xy 388.34568 -328.02449) (xy 385.19608 -311.31129) (xy 385.19608 -291.328348)
			(xy 383.97688 -290.109148) (xy 383.32029 -290.109148) (xy 383.310892 -290.112958) (xy 383.290877 -290.120836)
			(xy 383.249318 -290.131925) (xy 383.206669 -290.137515) (xy 383.185162 -290.13785) (xy 383.163657 -290.137487)
			(xy 383.121013 -290.131887) (xy 383.07945 -290.120824) (xy 383.059432 -290.112958) (xy 383.050034 -290.109148)
			(xy 382.38049 -290.109148) (xy 382.371092 -290.112958) (xy 382.351077 -290.120836) (xy 382.309518 -290.131925)
			(xy 382.266869 -290.137515) (xy 382.245362 -290.13785) (xy 382.223857 -290.137487) (xy 382.181213 -290.131887)
			(xy 382.13965 -290.120824) (xy 382.119632 -290.112958) (xy 382.110234 -290.109148) (xy 381.494284 -290.109148)
			(xy 381.469879 -290.123744) (xy 381.417483 -290.145831) (xy 381.362243 -290.159312) (xy 381.305562 -290.163845)
			(xy 381.248881 -290.159312) (xy 381.193641 -290.145831) (xy 381.141245 -290.123744) (xy 381.11684 -290.109148)
			(xy 380.554484 -290.109148) (xy 380.530079 -290.123744) (xy 380.477683 -290.145831) (xy 380.422443 -290.159312)
			(xy 380.365762 -290.163845) (xy 380.309081 -290.159312) (xy 380.253841 -290.145831) (xy 380.201445 -290.123744)
			(xy 380.17704 -290.109148) (xy 379.614684 -290.109148) (xy 379.590279 -290.123744) (xy 379.537883 -290.145831)
			(xy 379.482643 -290.159312) (xy 379.425962 -290.163845) (xy 379.369281 -290.159312) (xy 379.314041 -290.145831)
			(xy 379.261645 -290.123744) (xy 379.23724 -290.109148) (xy 378.674884 -290.109148) (xy 378.650479 -290.123744)
			(xy 378.598083 -290.145831) (xy 378.542843 -290.159312) (xy 378.486162 -290.163845) (xy 378.429481 -290.159312)
			(xy 378.374241 -290.145831) (xy 378.321845 -290.123744) (xy 378.29744 -290.109148) (xy 377.735084 -290.109148)
			(xy 377.710679 -290.123744) (xy 377.658283 -290.145831) (xy 377.603043 -290.159312) (xy 377.546362 -290.163845)
			(xy 377.489681 -290.159312) (xy 377.434441 -290.145831) (xy 377.382045 -290.123744) (xy 377.35764 -290.109148)
			(xy 376.795284 -290.109148) (xy 376.770879 -290.123744) (xy 376.718483 -290.145831) (xy 376.663243 -290.159312)
			(xy 376.606562 -290.163845) (xy 376.549881 -290.159312) (xy 376.494641 -290.145831) (xy 376.442245 -290.123744)
			(xy 376.41784 -290.109148) (xy 375.855484 -290.109148) (xy 375.831079 -290.123744) (xy 375.778683 -290.145831)
			(xy 375.723443 -290.159312) (xy 375.666762 -290.163845) (xy 375.610081 -290.159312) (xy 375.554841 -290.145831)
			(xy 375.502445 -290.123744) (xy 375.47804 -290.109148) (xy 374.915684 -290.109148) (xy 374.891279 -290.123744)
			(xy 374.838883 -290.145831) (xy 374.783643 -290.159312) (xy 374.726962 -290.163845) (xy 374.670281 -290.159312)
			(xy 374.615041 -290.145831) (xy 374.562645 -290.123744) (xy 374.53824 -290.109148) (xy 373.975884 -290.109148)
			(xy 373.951479 -290.123744) (xy 373.899083 -290.145831) (xy 373.843843 -290.159312) (xy 373.787162 -290.163845)
			(xy 373.730481 -290.159312) (xy 373.675241 -290.145831) (xy 373.622845 -290.123744) (xy 373.59844 -290.109148)
			(xy 373.036084 -290.109148) (xy 373.011679 -290.123744) (xy 372.959283 -290.145831) (xy 372.904043 -290.159312)
			(xy 372.847362 -290.163845) (xy 372.790681 -290.159312) (xy 372.735441 -290.145831) (xy 372.683045 -290.123744)
			(xy 372.65864 -290.109148) (xy 372.096284 -290.109148) (xy 372.071879 -290.123744) (xy 372.019483 -290.145831)
			(xy 371.964243 -290.159312) (xy 371.907562 -290.163845) (xy 371.850881 -290.159312) (xy 371.795641 -290.145831)
			(xy 371.743245 -290.123744) (xy 371.71884 -290.109148) (xy 371.156484 -290.109148) (xy 371.135171 -290.121982)
			(xy 371.089725 -290.142221) (xy 371.041903 -290.155935) (xy 370.992637 -290.162857) (xy 370.967762 -290.16325)
			(xy 370.936772 -290.162598) (xy 370.875722 -290.15191) (xy 370.817439 -290.130828) (xy 370.790216 -290.116006)
			(xy 370.778532 -290.109148) (xy 370.69268 -290.109148) (xy 370.513864 -289.930332) (xy 370.503704 -289.920795)
			(xy 370.479409 -289.907163) (xy 370.452337 -289.900596) (xy 370.424497 -289.901582) (xy 370.397957 -289.910047)
			(xy 370.374687 -289.925362) (xy 370.356416 -289.946391) (xy 370.350034 -289.95878) (xy 370.338929 -289.981378)
			(xy 370.3113 -290.023471) (xy 370.278013 -290.061248) (xy 370.239733 -290.093956) (xy 370.197225 -290.120942)
			(xy 370.151337 -290.141666) (xy 370.102986 -290.155714) (xy 370.053137 -290.162806) (xy 370.027962 -290.16325)
			(xy 369.99998 -290.162698) (xy 369.944705 -290.153939) (xy 369.89148 -290.136641) (xy 369.841616 -290.111232)
			(xy 369.79634 -290.078336) (xy 369.756767 -290.038763) (xy 369.72387 -289.993487) (xy 369.69846 -289.943624)
			(xy 369.681162 -289.890399) (xy 369.672402 -289.835124) (xy 369.671854 -289.807142) (xy 369.672294 -289.781968)
			(xy 369.679397 -289.732124) (xy 369.693452 -289.683778) (xy 369.714181 -289.637895) (xy 369.741168 -289.595391)
			(xy 369.773875 -289.557113) (xy 369.811649 -289.523827) (xy 369.853738 -289.496196) (xy 369.876324 -289.48507)
			(xy 369.888745 -289.478728) (xy 369.909802 -289.460456) (xy 369.92514 -289.437174) (xy 369.933617 -289.410615)
			(xy 369.934604 -289.382753) (xy 369.928026 -289.35566) (xy 369.914374 -289.331352) (xy 369.904772 -289.32124)
			(xy 369.781328 -289.197796) (xy 369.747038 -289.219132) (xy 369.725725 -289.231963) (xy 369.680278 -289.252198)
			(xy 369.632455 -289.265906) (xy 369.58319 -289.272822) (xy 369.558316 -289.273234) (xy 369.530331 -289.272686)
			(xy 369.475051 -289.263933) (xy 369.42182 -289.246641) (xy 369.37195 -289.221234) (xy 369.326668 -289.188338)
			(xy 369.287089 -289.148764) (xy 369.254188 -289.103486) (xy 369.228775 -289.053619) (xy 369.211476 -289.00039)
			(xy 369.202717 -288.945111) (xy 369.202208 -288.917126) (xy 369.202582 -288.893881) (xy 369.208624 -288.847784)
			(xy 369.220608 -288.802865) (xy 369.229132 -288.781236) (xy 369.238784 -288.758122) (xy 369.098068 -288.514536)
			(xy 369.039648 -288.456116) (xy 369.024154 -288.453322) (xy 368.997786 -288.447985) (xy 368.946936 -288.430429)
			(xy 368.899305 -288.405424) (xy 368.855978 -288.373538) (xy 368.817941 -288.335497) (xy 368.786059 -288.292167)
			(xy 368.761058 -288.244534) (xy 368.743507 -288.193682) (xy 368.73815 -288.167318) (xy 368.735356 -288.151824)
			(xy 368.674142 -288.09061) (xy 368.663797 -288.080903) (xy 368.639021 -288.06711) (xy 368.611408 -288.060659)
			(xy 368.583085 -288.062048) (xy 368.556236 -288.071168) (xy 368.532927 -288.087318) (xy 368.514957 -288.109254)
			(xy 368.503708 -288.135284) (xy 368.501422 -288.149284) (xy 368.497643 -288.174668) (xy 368.483739 -288.224068)
			(xy 368.462889 -288.27096) (xy 368.435524 -288.314375) (xy 368.402211 -288.353412) (xy 368.36364 -288.387264)
			(xy 368.320609 -288.415228) (xy 368.27401 -288.436727) (xy 368.224808 -288.451315) (xy 368.174022 -288.45869)
			(xy 368.148362 -288.459164) (xy 368.12038 -288.458641) (xy 368.065105 -288.44988) (xy 368.011882 -288.43258)
			(xy 367.96202 -288.407167) (xy 367.916748 -288.374267) (xy 367.87718 -288.33469) (xy 367.84429 -288.28941)
			(xy 367.818889 -288.239542) (xy 367.801601 -288.186315) (xy 367.792853 -288.131038) (xy 367.792254 -288.103056)
			(xy 367.792699 -288.077392) (xy 367.800061 -288.026596) (xy 367.814641 -287.977383) (xy 367.836137 -287.930774)
			(xy 367.864102 -287.887734) (xy 367.897958 -287.849156) (xy 367.937003 -287.815839) (xy 367.980427 -287.788474)
			(xy 368.02733 -287.767628) (xy 368.076741 -287.753733) (xy 368.102134 -287.749996) (xy 368.116155 -287.747735)
			(xy 368.142236 -287.736526) (xy 368.164219 -287.718566) (xy 368.180404 -287.695243) (xy 368.189536 -287.668365)
			(xy 368.190909 -287.64001) (xy 368.184417 -287.612375) (xy 368.170562 -287.587598) (xy 368.160808 -287.577276)
			(xy 368.098324 -287.514792) (xy 368.088121 -287.505256) (xy 368.063739 -287.491657) (xy 368.036588 -287.485161)
			(xy 368.008692 -287.486253) (xy 367.982131 -287.494851) (xy 367.958887 -287.510313) (xy 367.94948 -287.520634)
			(xy 367.932472 -287.53983) (xy 367.893892 -287.573621) (xy 367.850868 -287.601535) (xy 367.804288 -287.622995)
			(xy 367.755113 -287.637558) (xy 367.704359 -287.644924) (xy 367.678716 -287.645348) (xy 367.650731 -287.6448)
			(xy 367.595449 -287.636047) (xy 367.542218 -287.618755) (xy 367.492346 -287.593348) (xy 367.447063 -287.560453)
			(xy 367.407483 -287.520879) (xy 367.374581 -287.475601) (xy 367.349167 -287.425734) (xy 367.331866 -287.372505)
			(xy 367.323104 -287.317225) (xy 367.322608 -287.28924) (xy 367.323053 -287.263577) (xy 367.330414 -287.212781)
			(xy 367.34499 -287.163567) (xy 367.366479 -287.116956) (xy 367.394436 -287.073911) (xy 367.428281 -287.035325)
			(xy 367.467314 -287.001996) (xy 367.510727 -286.974615) (xy 367.557621 -286.953748) (xy 367.582196 -286.94634)
			(xy 367.61928 -286.935926) (xy 367.61928 -286.813244) (xy 367.618794 -286.798529) (xy 367.610416 -286.770316)
			(xy 367.594342 -286.745663) (xy 367.571907 -286.726615) (xy 367.544972 -286.714754) (xy 367.515774 -286.711065)
			(xy 367.486736 -286.715852) (xy 367.460268 -286.72872) (xy 367.4491 -286.738314) (xy 367.429297 -286.755756)
			(xy 367.385512 -286.78521) (xy 367.337863 -286.807887) (xy 367.287392 -286.823293) (xy 367.235201 -286.831089)
			(xy 367.208816 -286.831532) (xy 367.182162 -286.83106) (xy 367.12945 -286.823117) (xy 367.07851 -286.807406)
			(xy 367.030481 -286.784278) (xy 366.986436 -286.754251) (xy 366.947358 -286.717993) (xy 366.91412 -286.676317)
			(xy 366.887466 -286.630151) (xy 366.86799 -286.580529) (xy 366.856128 -286.528558) (xy 366.852144 -286.4754)
			(xy 366.856128 -286.422242) (xy 366.86799 -286.370271) (xy 366.887466 -286.320649) (xy 366.91412 -286.274483)
			(xy 366.947358 -286.232807) (xy 366.986436 -286.196549) (xy 367.030481 -286.166522) (xy 367.07851 -286.143394)
			(xy 367.12945 -286.127683) (xy 367.182162 -286.11974) (xy 367.208816 -286.119316) (xy 367.235199 -286.119795)
			(xy 367.287387 -286.127582) (xy 367.337855 -286.142982) (xy 367.385498 -286.16566) (xy 367.429275 -286.195119)
			(xy 367.4491 -286.212534) (xy 367.460283 -286.222106) (xy 367.486749 -286.234965) (xy 367.515781 -286.239749)
			(xy 367.544973 -286.236059) (xy 367.571903 -286.224203) (xy 367.594337 -286.205163) (xy 367.610414 -286.18052)
			(xy 367.618801 -286.152316) (xy 367.61928 -286.137604) (xy 367.61928 -286.014668) (xy 367.582196 -286.004254)
			(xy 367.557598 -285.996883) (xy 367.510665 -285.976047) (xy 367.467213 -285.948684) (xy 367.428143 -285.915362)
			(xy 367.394265 -285.876772) (xy 367.366284 -285.833716) (xy 367.344779 -285.787086) (xy 367.330197 -285.73785)
			(xy 367.32284 -285.687029) (xy 367.322354 -285.661354) (xy 367.322732 -285.63811) (xy 367.328782 -285.592016)
			(xy 367.340773 -285.5471) (xy 367.349278 -285.525464) (xy 367.35893 -285.50235) (xy 367.186464 -285.2039)
			(xy 367.161826 -285.200598) (xy 367.136483 -285.196774) (xy 367.087175 -285.182797) (xy 367.04038 -285.161893)
			(xy 366.997067 -285.134496) (xy 366.95813 -285.10117) (xy 366.924374 -285.062605) (xy 366.896496 -285.019599)
			(xy 366.875074 -284.973039) (xy 366.86055 -284.923889) (xy 366.853224 -284.873164) (xy 366.852708 -284.847538)
			(xy 366.853226 -284.819551) (xy 366.861977 -284.764266) (xy 366.87927 -284.711031) (xy 366.904678 -284.661156)
			(xy 366.937576 -284.615871) (xy 366.977154 -284.576291) (xy 367.022437 -284.543389) (xy 367.07231 -284.517978)
			(xy 367.125545 -284.500682) (xy 367.180829 -284.491927) (xy 367.208816 -284.49143) (xy 367.236399 -284.491949)
			(xy 367.290905 -284.50046) (xy 367.343447 -284.517275) (xy 367.392766 -284.541993) (xy 367.437683 -284.574021)
			(xy 367.477123 -284.612594) (xy 367.510142 -284.656787) (xy 367.523522 -284.680914) (xy 367.538 -284.708092)
			(xy 367.61928 -284.708092) (xy 367.61928 -284.495748) (xy 367.241074 -284.117542) (xy 367.230418 -284.107543)
			(xy 367.204774 -284.093559) (xy 367.17622 -284.087405) (xy 367.147093 -284.089585) (xy 367.119773 -284.09992)
			(xy 367.096495 -284.117565) (xy 367.079164 -284.141077) (xy 367.073688 -284.154626) (xy 367.063944 -284.1801)
			(xy 367.037826 -284.227979) (xy 367.004712 -284.271314) (xy 366.965376 -284.309092) (xy 366.920738 -284.340428)
			(xy 366.871843 -284.36459) (xy 366.819836 -284.381011) (xy 366.765932 -284.389308) (xy 366.738662 -284.38983)
			(xy 366.71068 -284.389278) (xy 366.655406 -284.380519) (xy 366.602183 -284.363221) (xy 366.55232 -284.337811)
			(xy 366.507046 -284.304915) (xy 366.467475 -284.265342) (xy 366.43458 -284.220066) (xy 366.409173 -284.170202)
			(xy 366.391878 -284.116978) (xy 366.383121 -284.061704) (xy 366.382554 -284.033722) (xy 366.383079 -284.006457)
			(xy 366.391401 -283.952565) (xy 366.407839 -283.900571) (xy 366.432009 -283.85169) (xy 366.463346 -283.807063)
			(xy 366.501118 -283.767732) (xy 366.544442 -283.734618) (xy 366.592307 -283.708493) (xy 366.617758 -283.698696)
			(xy 366.63134 -283.693281) (xy 366.654884 -283.675964) (xy 366.672552 -283.652681) (xy 366.682891 -283.625343)
			(xy 366.685054 -283.596196) (xy 366.678862 -283.567632) (xy 366.664824 -283.541997) (xy 366.654842 -283.53131)
			(xy 366.558068 -283.434536) (xy 366.522 -283.470604) (xy 366.501798 -283.490212) (xy 366.456362 -283.523449)
			(xy 366.406266 -283.549132) (xy 366.352757 -283.566624) (xy 366.297164 -283.575489) (xy 366.269016 -283.576014)
			(xy 366.24103 -283.575495) (xy 366.185746 -283.566741) (xy 366.132512 -283.549447) (xy 366.082639 -283.524038)
			(xy 366.037355 -283.491139) (xy 365.997775 -283.451562) (xy 365.964874 -283.40628) (xy 365.939461 -283.356409)
			(xy 365.922164 -283.303176) (xy 365.913407 -283.247892) (xy 365.912908 -283.219906) (xy 365.91344 -283.191758)
			(xy 365.922294 -283.136164) (xy 365.939783 -283.082654) (xy 365.965472 -283.032562) (xy 365.99872 -282.987133)
			(xy 366.018318 -282.966922) (xy 366.054386 -282.930854) (xy 365.877602 -282.75407) (xy 365.852202 -282.75788)
			(xy 365.839011 -282.759762) (xy 365.81244 -282.761798) (xy 365.799116 -282.761944) (xy 365.771131 -282.761396)
			(xy 365.71585 -282.752643) (xy 365.662618 -282.735351) (xy 365.612747 -282.709944) (xy 365.567464 -282.677049)
			(xy 365.527885 -282.637475) (xy 365.494983 -282.592197) (xy 365.469569 -282.54233) (xy 365.452269 -282.489101)
			(xy 365.443508 -282.433821) (xy 365.443008 -282.405836) (xy 365.443149 -282.392512) (xy 365.445185 -282.365941)
			(xy 365.447072 -282.35275) (xy 365.450882 -282.32735) (xy 364.54588 -281.422348) (xy 364.54588 -280.947622)
			(xy 364.540546 -280.936954) (xy 364.528767 -280.912167) (xy 364.512127 -280.859872) (xy 364.503707 -280.805643)
			(xy 364.503707 -280.750764) (xy 364.512125 -280.696535) (xy 364.528764 -280.64424) (xy 364.540546 -280.619454)
			(xy 364.54588 -280.608786) (xy 364.54588 -280.41854) (xy 364.545395 -280.404193) (xy 364.537422 -280.376629)
			(xy 364.522095 -280.352373) (xy 364.500624 -280.333338) (xy 364.474705 -280.32103) (xy 364.446384 -280.316419)
			(xy 364.432088 -280.317702) (xy 364.421461 -280.318896) (xy 364.40011 -280.320165) (xy 364.389416 -280.320242)
			(xy 364.362762 -280.31977) (xy 364.310048 -280.311827) (xy 364.259107 -280.296115) (xy 364.211076 -280.272987)
			(xy 364.16703 -280.242958) (xy 364.127951 -280.2067) (xy 364.094712 -280.165022) (xy 364.068057 -280.118856)
			(xy 364.048581 -280.069232) (xy 364.036718 -280.01726) (xy 364.032734 -279.9641) (xy 364.036718 -279.91094)
			(xy 364.048581 -279.858968) (xy 364.068057 -279.809344) (xy 364.094712 -279.763178) (xy 364.127951 -279.7215)
			(xy 364.16703 -279.685242) (xy 364.211076 -279.655213) (xy 364.259107 -279.632085) (xy 364.310048 -279.616373)
			(xy 364.362762 -279.60843) (xy 364.389416 -279.608026) (xy 364.40011 -279.608098) (xy 364.421461 -279.609368)
			(xy 364.432088 -279.610566) (xy 364.446386 -279.611804) (xy 364.474701 -279.607195) (xy 364.500617 -279.594894)
			(xy 364.522089 -279.57587) (xy 364.537423 -279.551625) (xy 364.545409 -279.524071) (xy 364.54588 -279.509728)
			(xy 364.54588 -279.319482) (xy 364.540546 -279.308814) (xy 364.531233 -279.289378) (xy 364.516843 -279.248752)
			(xy 364.511844 -279.227788) (xy 364.508542 -279.21331) (xy 364.443518 -279.148286) (xy 364.433298 -279.138682)
			(xy 364.408838 -279.124986) (xy 364.381572 -279.118464) (xy 364.353562 -279.119611) (xy 364.326921 -279.128339)
			(xy 364.303661 -279.143989) (xy 364.28554 -279.165379) (xy 364.273926 -279.190894) (xy 364.271306 -279.204674)
			(xy 364.266476 -279.232318) (xy 364.249271 -279.285731) (xy 364.223909 -279.335788) (xy 364.191017 -279.381253)
			(xy 364.151407 -279.421002) (xy 364.106058 -279.454054) (xy 364.05609 -279.479592) (xy 364.002738 -279.496985)
			(xy 363.94732 -279.505803) (xy 363.919262 -279.506426) (xy 363.89128 -279.505874) (xy 363.836007 -279.497115)
			(xy 363.782784 -279.479817) (xy 363.732921 -279.454407) (xy 363.687647 -279.421511) (xy 363.648076 -279.381937)
			(xy 363.615182 -279.336662) (xy 363.589775 -279.286798) (xy 363.572481 -279.233574) (xy 363.563724 -279.1783)
			(xy 363.563154 -279.150318) (xy 363.563671 -279.122249) (xy 363.57246 -279.066804) (xy 363.589838 -279.013424)
			(xy 363.615375 -278.963432) (xy 363.648438 -278.918064) (xy 363.68821 -278.878446) (xy 363.733704 -278.845557)
			(xy 363.783795 -278.820213) (xy 363.837241 -278.803041) (xy 363.864906 -278.798274) (xy 363.878683 -278.795687)
			(xy 363.904163 -278.784028) (xy 363.925519 -278.765887) (xy 363.941146 -278.742628) (xy 363.949868 -278.715999)
			(xy 363.951031 -278.688002) (xy 363.944546 -278.660742) (xy 363.930902 -278.636267) (xy 363.921294 -278.626062)
			(xy 363.863382 -278.56815) (xy 363.853278 -278.558688) (xy 363.829183 -278.545085) (xy 363.802316 -278.538466)
			(xy 363.77466 -278.539319) (xy 363.748252 -278.547581) (xy 363.725041 -278.562642) (xy 363.715554 -278.572722)
			(xy 363.698595 -278.591192) (xy 363.660381 -278.623656) (xy 363.617986 -278.650431) (xy 363.57225 -278.670985)
			(xy 363.524081 -278.684912) (xy 363.474433 -278.691936) (xy 363.449362 -278.692356) (xy 363.421379 -278.691804)
			(xy 363.366104 -278.683045) (xy 363.312879 -278.665748) (xy 363.263015 -278.640338) (xy 363.217738 -278.607442)
			(xy 363.178164 -278.567869) (xy 363.145267 -278.522594) (xy 363.119856 -278.47273) (xy 363.102558 -278.419506)
			(xy 363.093797 -278.364231) (xy 363.093254 -278.336248) (xy 363.093686 -278.311179) (xy 363.100727 -278.261538)
			(xy 363.114663 -278.213376) (xy 363.135217 -278.167645) (xy 363.161984 -278.12525) (xy 363.194434 -278.087029)
			(xy 363.212888 -278.070056) (xy 363.222911 -278.060534) (xy 363.237897 -278.037314) (xy 363.246115 -278.010929)
			(xy 363.246966 -277.983307) (xy 363.240387 -277.956466) (xy 363.226859 -277.932369) (xy 363.21746 -277.922228)
			(xy 363.138212 -277.84298) (xy 363.107224 -277.854664) (xy 363.076452 -277.865752) (xy 363.012162 -277.877761)
			(xy 362.979462 -277.87854) (xy 362.95148 -277.877988) (xy 362.896205 -277.869229) (xy 362.842981 -277.851931)
			(xy 362.793118 -277.826522) (xy 362.747843 -277.793625) (xy 362.708271 -277.754052) (xy 362.675375 -277.708777)
			(xy 362.649967 -277.658913) (xy 362.63267 -277.605689) (xy 362.623911 -277.550414) (xy 362.623354 -277.522432)
			(xy 362.62414 -277.489733) (xy 362.636152 -277.425445) (xy 362.64723 -277.39467) (xy 362.658914 -277.363682)
			(xy 361.3785 -276.083268) (xy 361.3785 -275.381212) (xy 361.355567 -275.365992) (xy 361.314252 -275.329629)
			(xy 361.279019 -275.287346) (xy 361.250706 -275.240149) (xy 361.229986 -275.189159) (xy 361.217353 -275.13559)
			(xy 361.213107 -275.080716) (xy 361.217348 -275.025842) (xy 361.229977 -274.972272) (xy 361.250691 -274.92128)
			(xy 361.279 -274.87408) (xy 361.314229 -274.831794) (xy 361.355542 -274.795428) (xy 361.3785 -274.780248)
			(xy 361.3785 -273.75358) (xy 361.35557 -273.73836) (xy 361.314259 -273.701998) (xy 361.279031 -273.659716)
			(xy 361.250722 -273.612521) (xy 361.230007 -273.561535) (xy 361.217377 -273.507969) (xy 361.213134 -273.453099)
			(xy 361.217378 -273.398229) (xy 361.230007 -273.344663) (xy 361.250723 -273.293677) (xy 361.279032 -273.246482)
			(xy 361.314261 -273.204201) (xy 361.355571 -273.167839) (xy 361.3785 -273.152616) (xy 361.3785 -272.125694)
			(xy 361.355569 -272.110474) (xy 361.314256 -272.074111) (xy 361.279025 -272.031829) (xy 361.250715 -271.984633)
			(xy 361.229998 -271.933645) (xy 361.217367 -271.880079) (xy 361.213122 -271.825206) (xy 361.217365 -271.770334)
			(xy 361.229994 -271.716767) (xy 361.250709 -271.665778) (xy 361.279018 -271.618581) (xy 361.314247 -271.576298)
			(xy 361.355558 -271.539934) (xy 361.3785 -271.52473) (xy 361.3785 -270.498062) (xy 361.355571 -270.482842)
			(xy 361.314263 -270.44648) (xy 361.279038 -270.4042) (xy 361.250731 -270.357006) (xy 361.230018 -270.306021)
			(xy 361.217391 -270.252457) (xy 361.213149 -270.197589) (xy 361.217394 -270.142721) (xy 361.230025 -270.089159)
			(xy 361.250741 -270.038175) (xy 361.27905 -269.990983) (xy 361.314278 -269.948704) (xy 361.355588 -269.912345)
			(xy 361.3785 -269.897098) (xy 361.3785 -268.870176) (xy 361.35557 -268.854956) (xy 361.31426 -268.818594)
			(xy 361.279032 -268.776313) (xy 361.250724 -268.729118) (xy 361.230009 -268.678132) (xy 361.21738 -268.624567)
			(xy 361.213137 -268.569697) (xy 361.217381 -268.514827) (xy 361.230011 -268.461262) (xy 361.250727 -268.410276)
			(xy 361.279036 -268.363082) (xy 361.314265 -268.320802) (xy 361.355575 -268.28444) (xy 361.3785 -268.269212)
			(xy 361.3785 -267.24229) (xy 361.355569 -267.22707) (xy 361.314257 -267.190707) (xy 361.279027 -267.148426)
			(xy 361.250717 -267.10123) (xy 361.23 -267.050242) (xy 361.21737 -266.996676) (xy 361.213125 -266.941804)
			(xy 361.217368 -266.886933) (xy 361.229998 -266.833366) (xy 361.250713 -266.782378) (xy 361.279022 -266.735181)
			(xy 361.314251 -266.692899) (xy 361.355562 -266.656535) (xy 361.3785 -266.641326) (xy 361.3785 -266.172188)
			(xy 362.160566 -265.390122) (xy 362.15701 -265.364722) (xy 362.155326 -265.352154) (xy 362.153546 -265.326856)
			(xy 362.153454 -265.314176) (xy 362.154005 -265.286193) (xy 362.162762 -265.230917) (xy 362.180059 -265.17769)
			(xy 362.205467 -265.127825) (xy 362.238363 -265.082547) (xy 362.277936 -265.042972) (xy 362.323213 -265.010075)
			(xy 362.373077 -264.984664) (xy 362.426303 -264.967366) (xy 362.481579 -264.958606) (xy 362.509562 -264.958068)
			(xy 362.522242 -264.958173) (xy 362.547538 -264.959955) (xy 362.560108 -264.961624) (xy 362.585508 -264.96518)
			(xy 362.72724 -264.823448) (xy 362.733934 -264.816037) (xy 362.741547 -264.797598) (xy 362.741557 -264.777649)
			(xy 362.733961 -264.759203) (xy 362.72724 -264.75182) (xy 362.707921 -264.731644) (xy 362.67517 -264.686397)
			(xy 362.649876 -264.636596) (xy 362.632658 -264.58346) (xy 362.623938 -264.528288) (xy 362.623354 -264.50036)
			(xy 362.623906 -264.472378) (xy 362.632666 -264.417103) (xy 362.649963 -264.363879) (xy 362.675373 -264.314016)
			(xy 362.708269 -264.26874) (xy 362.747842 -264.229168) (xy 362.793117 -264.196272) (xy 362.842981 -264.170862)
			(xy 362.896205 -264.153565) (xy 362.95148 -264.144806) (xy 362.979462 -264.144252) (xy 363.007393 -264.144794)
			(xy 363.06257 -264.153509) (xy 363.11571 -264.170733) (xy 363.16551 -264.196041) (xy 363.210747 -264.228814)
			(xy 363.230922 -264.248138) (xy 363.266736 -264.283952) (xy 363.32668 -264.224008) (xy 363.32668 -264.022332)
			(xy 363.29747 -264.008616) (xy 363.273426 -263.996701) (xy 363.228911 -263.966735) (xy 363.189393 -263.930434)
			(xy 363.155764 -263.888618) (xy 363.128785 -263.842232) (xy 363.109065 -263.792326) (xy 363.097051 -263.740028)
			(xy 363.093014 -263.686519) (xy 363.097045 -263.63301) (xy 363.109054 -263.58071) (xy 363.128768 -263.530802)
			(xy 363.155742 -263.484413) (xy 363.189367 -263.442594) (xy 363.228882 -263.406288) (xy 363.273393 -263.376318)
			(xy 363.29747 -263.364472) (xy 363.32668 -263.350756) (xy 363.32668 -260.975348) (xy 364.21568 -260.086348)
			(xy 366.769142 -260.086348) (xy 366.816894 -260.038596) (xy 366.82045 -260.024626) (xy 366.822282 -260.017855)
			(xy 366.829106 -260.005605) (xy 366.833912 -260.000496) (xy 367.948972 -258.885436) (xy 367.948972 -250.16841)
			(xy 366.377474 -248.596912) (xy 366.377474 -247.018048) (xy 366.332516 -247.012968) (xy 366.306127 -247.009489)
			(xy 366.254731 -246.995654) (xy 366.205972 -246.974309) (xy 366.16094 -246.945933) (xy 366.140492 -246.928894)
			(xy 366.128906 -246.919609) (xy 366.101794 -246.907535) (xy 366.07236 -246.903737) (xy 366.043072 -246.908532)
			(xy 366.016386 -246.921519) (xy 366.00511 -246.93118) (xy 365.98527 -246.948791) (xy 365.941353 -246.978546)
			(xy 365.893509 -247.001459) (xy 365.842795 -247.017022) (xy 365.790334 -247.024891) (xy 365.76381 -247.025414)
			(xy 365.737158 -247.024941) (xy 365.684449 -247.016998) (xy 365.633513 -247.001288) (xy 365.585487 -246.978161)
			(xy 365.541444 -246.948134) (xy 365.502369 -246.911879) (xy 365.469134 -246.870204) (xy 365.442482 -246.824042)
			(xy 365.423007 -246.774423) (xy 365.411145 -246.722455) (xy 365.407162 -246.6693) (xy 365.411145 -246.616145)
			(xy 365.423007 -246.564177) (xy 365.442482 -246.514558) (xy 365.469134 -246.468396) (xy 365.502369 -246.426721)
			(xy 365.541444 -246.390466) (xy 365.585487 -246.360439) (xy 365.633513 -246.337312) (xy 365.684449 -246.321602)
			(xy 365.737158 -246.313659) (xy 365.76381 -246.313198) (xy 365.789146 -246.313646) (xy 365.839305 -246.320832)
			(xy 365.887939 -246.335058) (xy 365.934064 -246.356036) (xy 365.976748 -246.383343) (xy 365.99622 -246.399558)
			(xy 366.007804 -246.408845) (xy 366.034915 -246.420921) (xy 366.064349 -246.424719) (xy 366.093636 -246.419919)
			(xy 366.120318 -246.406924) (xy 366.131602 -246.397272) (xy 366.152628 -246.378627) (xy 366.199427 -246.347519)
			(xy 366.250528 -246.324142) (xy 366.304665 -246.309075) (xy 366.332516 -246.305324) (xy 366.377474 -246.300244)
			(xy 366.377474 -245.073678) (xy 367.948972 -243.50218) (xy 367.948972 -241.391948) (xy 366.65408 -240.097056)
			(xy 366.65408 -239.763046) (xy 366.653616 -239.74917) (xy 366.646153 -239.722442) (xy 366.631765 -239.698713)
			(xy 366.611516 -239.679736) (xy 366.586904 -239.666916) (xy 366.559748 -239.6612) (xy 366.545876 -239.6617)
			(xy 366.522508 -239.662462) (xy 366.497839 -239.662042) (xy 366.448973 -239.655232) (xy 366.401515 -239.641739)
			(xy 366.356375 -239.621824) (xy 366.314417 -239.595867) (xy 366.295178 -239.58042) (xy 366.284048 -239.571793)
			(xy 366.258288 -239.560446) (xy 366.230408 -239.556565) (xy 366.202528 -239.560446) (xy 366.176768 -239.571793)
			(xy 366.165638 -239.58042) (xy 366.144222 -239.597543) (xy 366.097165 -239.625682) (xy 366.046348 -239.646271)
			(xy 365.992975 -239.658823) (xy 365.938308 -239.66304) (xy 365.883641 -239.658823) (xy 365.830268 -239.646271)
			(xy 365.779451 -239.625682) (xy 365.732394 -239.597543) (xy 365.710978 -239.58042) (xy 365.699848 -239.571793)
			(xy 365.674088 -239.560446) (xy 365.646208 -239.556565) (xy 365.618328 -239.560446) (xy 365.592568 -239.571793)
			(xy 365.581438 -239.58042) (xy 365.562191 -239.595857) (xy 365.520241 -239.621831) (xy 365.475104 -239.641758)
			(xy 365.427646 -239.655254) (xy 365.378778 -239.662061) (xy 365.354108 -239.662462) (xy 365.32746 -239.661989)
			(xy 365.274759 -239.654047) (xy 365.22383 -239.638339) (xy 365.175812 -239.615215) (xy 365.131776 -239.585193)
			(xy 365.092707 -239.548943) (xy 365.059477 -239.507275) (xy 365.032828 -239.461119) (xy 365.013357 -239.411507)
			(xy 365.001497 -239.359547) (xy 364.997514 -239.3064) (xy 365.001497 -239.253253) (xy 365.013357 -239.201293)
			(xy 365.032828 -239.151681) (xy 365.059477 -239.105525) (xy 365.092707 -239.063857) (xy 365.131776 -239.027607)
			(xy 365.175812 -238.997585) (xy 365.22383 -238.974461) (xy 365.274759 -238.958753) (xy 365.32746 -238.950811)
			(xy 365.354108 -238.950246) (xy 365.378777 -238.950667) (xy 365.427642 -238.95748) (xy 365.475098 -238.970974)
			(xy 365.520236 -238.990891) (xy 365.562193 -239.01685) (xy 365.581438 -239.032288) (xy 365.592568 -239.040915)
			(xy 365.618328 -239.052262) (xy 365.646208 -239.056143) (xy 365.674088 -239.052262) (xy 365.699848 -239.040915)
			(xy 365.710978 -239.032288) (xy 365.732394 -239.015165) (xy 365.779451 -238.987026) (xy 365.830268 -238.966437)
			(xy 365.883641 -238.953885) (xy 365.938308 -238.949668) (xy 365.992975 -238.953885) (xy 366.046348 -238.966437)
			(xy 366.097165 -238.987026) (xy 366.144222 -239.015165) (xy 366.165638 -239.032288) (xy 366.176768 -239.040915)
			(xy 366.202528 -239.052262) (xy 366.230408 -239.056143) (xy 366.258288 -239.052262) (xy 366.284048 -239.040915)
			(xy 366.295178 -239.032288) (xy 366.314426 -239.016852) (xy 366.356376 -238.990879) (xy 366.401513 -238.970954)
			(xy 366.448971 -238.95746) (xy 366.497838 -238.950655) (xy 366.522508 -238.950246) (xy 366.538278 -238.950415)
			(xy 366.569694 -238.953215) (xy 366.585246 -238.955834) (xy 366.599949 -238.95797) (xy 366.629456 -238.954619)
			(xy 366.656751 -238.94292) (xy 366.679527 -238.923864) (xy 366.695857 -238.89906) (xy 366.704361 -238.870607)
			(xy 366.70488 -238.855758) (xy 366.70488 -237.912148) (xy 366.146588 -237.353856) (xy 363.573314 -237.353856)
			(xy 363.557832 -237.375072) (xy 363.521651 -237.413142) (xy 363.48027 -237.445484) (xy 363.434588 -237.471397)
			(xy 363.385595 -237.490319) (xy 363.334354 -237.501838) (xy 363.281976 -237.505706) (xy 363.229598 -237.501838)
			(xy 363.178357 -237.490319) (xy 363.129364 -237.471397) (xy 363.083682 -237.445484) (xy 363.042301 -237.413142)
			(xy 363.00612 -237.375072) (xy 362.990638 -237.353856) (xy 361.816142 -237.353856) (xy 361.816142 -237.405418)
			(xy 361.816142 -237.411514) (xy 361.815592 -237.439497) (xy 361.806835 -237.494775) (xy 361.78954 -237.548002)
			(xy 361.764132 -237.597869) (xy 361.731236 -237.643147) (xy 361.691663 -237.682723) (xy 361.646386 -237.715621)
			(xy 361.596521 -237.741032) (xy 361.543294 -237.758331) (xy 361.488017 -237.76709) (xy 361.460034 -237.767622)
			(xy 361.433218 -237.767139) (xy 361.380193 -237.759102) (xy 361.328972 -237.743205) (xy 361.280715 -237.719807)
			(xy 361.236511 -237.689437) (xy 361.197361 -237.652782) (xy 361.16415 -237.610672) (xy 361.137629 -237.564057)
			(xy 361.118398 -237.513993) (xy 361.106892 -237.46161) (xy 361.104688 -237.434882) (xy 361.096465 -237.422535)
			(xy 361.081845 -237.396719) (xy 361.075478 -237.38332) (xy 361.061762 -237.353856) (xy 360.876342 -237.353856)
			(xy 360.876342 -237.405418) (xy 360.876342 -237.411514) (xy 360.875792 -237.439497) (xy 360.867035 -237.494775)
			(xy 360.84974 -237.548002) (xy 360.824332 -237.597869) (xy 360.791436 -237.643147) (xy 360.751863 -237.682723)
			(xy 360.706586 -237.715621) (xy 360.656721 -237.741032) (xy 360.603494 -237.758331) (xy 360.548217 -237.76709)
			(xy 360.520234 -237.767622) (xy 360.493418 -237.767139) (xy 360.440393 -237.759102) (xy 360.389172 -237.743205)
			(xy 360.340915 -237.719807) (xy 360.296711 -237.689437) (xy 360.257561 -237.652782) (xy 360.22435 -237.610672)
			(xy 360.197829 -237.564057) (xy 360.178598 -237.513993) (xy 360.167092 -237.46161) (xy 360.164888 -237.434882)
			(xy 360.156665 -237.422535) (xy 360.142045 -237.396719) (xy 360.135678 -237.38332) (xy 360.121962 -237.353856)
			(xy 359.936542 -237.353856) (xy 359.936542 -237.405418) (xy 359.936542 -237.411514) (xy 359.935992 -237.439497)
			(xy 359.927235 -237.494775) (xy 359.90994 -237.548002) (xy 359.884532 -237.597869) (xy 359.851636 -237.643147)
			(xy 359.812063 -237.682723) (xy 359.766786 -237.715621) (xy 359.716921 -237.741032) (xy 359.663694 -237.758331)
			(xy 359.608417 -237.76709) (xy 359.580434 -237.767622) (xy 359.553618 -237.767139) (xy 359.500593 -237.759102)
			(xy 359.449372 -237.743205) (xy 359.401115 -237.719807) (xy 359.356911 -237.689437) (xy 359.317761 -237.652782)
			(xy 359.28455 -237.610672) (xy 359.258029 -237.564057) (xy 359.238798 -237.513993) (xy 359.227292 -237.46161)
			(xy 359.225088 -237.434882) (xy 359.216865 -237.422535) (xy 359.202245 -237.396719) (xy 359.195878 -237.38332)
			(xy 359.182162 -237.353856) (xy 358.996742 -237.353856) (xy 358.996742 -237.405418) (xy 358.996742 -237.411514)
			(xy 358.996192 -237.439497) (xy 358.987435 -237.494775) (xy 358.97014 -237.548002) (xy 358.944732 -237.597869)
			(xy 358.911836 -237.643147) (xy 358.872263 -237.682723) (xy 358.826986 -237.715621) (xy 358.777121 -237.741032)
			(xy 358.723894 -237.758331) (xy 358.668617 -237.76709) (xy 358.640634 -237.767622) (xy 358.613818 -237.767139)
			(xy 358.560793 -237.759102) (xy 358.509572 -237.743205) (xy 358.461315 -237.719807) (xy 358.417111 -237.689437)
			(xy 358.377961 -237.652782) (xy 358.34475 -237.610672) (xy 358.318229 -237.564057) (xy 358.298998 -237.513993)
			(xy 358.287492 -237.46161) (xy 358.285288 -237.434882) (xy 358.277065 -237.422535) (xy 358.262445 -237.396719)
			(xy 358.256078 -237.38332) (xy 358.242362 -237.353856) (xy 358.056942 -237.353856) (xy 358.056942 -237.405418)
			(xy 358.056942 -237.411514) (xy 358.056392 -237.439497) (xy 358.047635 -237.494775) (xy 358.03034 -237.548002)
			(xy 358.004932 -237.597869) (xy 357.972036 -237.643147) (xy 357.932463 -237.682723) (xy 357.887186 -237.715621)
			(xy 357.837321 -237.741032) (xy 357.784094 -237.758331) (xy 357.728817 -237.76709) (xy 357.700834 -237.767622)
			(xy 357.674018 -237.767139) (xy 357.620993 -237.759102) (xy 357.569772 -237.743205) (xy 357.521515 -237.719807)
			(xy 357.477311 -237.689437) (xy 357.438161 -237.652782) (xy 357.40495 -237.610672) (xy 357.378429 -237.564057)
			(xy 357.359198 -237.513993) (xy 357.347692 -237.46161) (xy 357.345488 -237.434882) (xy 357.337265 -237.422535)
			(xy 357.322645 -237.396719) (xy 357.316278 -237.38332) (xy 357.302562 -237.353856) (xy 356.954074 -237.353856)
			(xy 356.941374 -237.357158) (xy 356.920038 -237.362238) (xy 356.851204 -237.482634) (xy 356.865418 -237.503864)
			(xy 356.888286 -237.549552) (xy 356.904411 -237.598032) (xy 356.90937 -237.623096) (xy 356.911402 -237.63351)
			(xy 356.935532 -237.669324) (xy 357.023924 -237.722156) (xy 357.04653 -237.713774) (xy 357.076175 -237.703597)
			(xy 357.137876 -237.692606) (xy 357.169212 -237.69193) (xy 357.169466 -237.69193) (xy 357.196293 -237.692414)
			(xy 357.24934 -237.700459) (xy 357.30058 -237.716372) (xy 357.348852 -237.739792) (xy 357.393064 -237.77019)
			(xy 357.432214 -237.806877) (xy 357.465418 -237.849022) (xy 357.491922 -237.895673) (xy 357.511126 -237.945771)
			(xy 357.522597 -237.998184) (xy 357.524812 -238.024924) (xy 357.539454 -238.047211) (xy 357.562616 -238.095244)
			(xy 357.578352 -238.146194) (xy 357.58631 -238.198922) (xy 357.586788 -238.225584) (xy 357.586294 -238.252233)
			(xy 357.81487 -238.252233) (xy 357.81487 -238.198935) (xy 357.822813 -238.146231) (xy 357.838523 -238.095301)
			(xy 357.861649 -238.04728) (xy 357.891673 -238.003243) (xy 357.927925 -237.964172) (xy 357.969596 -237.930941)
			(xy 358.015754 -237.904292) (xy 358.065368 -237.88482) (xy 358.11733 -237.87296) (xy 358.17048 -237.868977)
			(xy 358.22363 -237.87296) (xy 358.275592 -237.88482) (xy 358.325206 -237.904292) (xy 358.371364 -237.930941)
			(xy 358.413035 -237.964172) (xy 358.449287 -238.003243) (xy 358.479311 -238.04728) (xy 358.502437 -238.095301)
			(xy 358.518147 -238.146231) (xy 358.52609 -238.198935) (xy 358.526588 -238.225584) (xy 358.52609 -238.252233)
			(xy 358.75467 -238.252233) (xy 358.75467 -238.198935) (xy 358.762613 -238.146231) (xy 358.778323 -238.095301)
			(xy 358.801449 -238.04728) (xy 358.831473 -238.003243) (xy 358.867725 -237.964172) (xy 358.909396 -237.930941)
			(xy 358.955554 -237.904292) (xy 359.005168 -237.88482) (xy 359.05713 -237.87296) (xy 359.11028 -237.868977)
			(xy 359.16343 -237.87296) (xy 359.215392 -237.88482) (xy 359.265006 -237.904292) (xy 359.311164 -237.930941)
			(xy 359.352835 -237.964172) (xy 359.389087 -238.003243) (xy 359.419111 -238.04728) (xy 359.442237 -238.095301)
			(xy 359.457947 -238.146231) (xy 359.46589 -238.198935) (xy 359.466388 -238.225584) (xy 359.46589 -238.252233)
			(xy 359.69447 -238.252233) (xy 359.69447 -238.198935) (xy 359.702413 -238.146231) (xy 359.718123 -238.095301)
			(xy 359.741249 -238.04728) (xy 359.771273 -238.003243) (xy 359.807525 -237.964172) (xy 359.849196 -237.930941)
			(xy 359.895354 -237.904292) (xy 359.944968 -237.88482) (xy 359.99693 -237.87296) (xy 360.05008 -237.868977)
			(xy 360.10323 -237.87296) (xy 360.155192 -237.88482) (xy 360.204806 -237.904292) (xy 360.250964 -237.930941)
			(xy 360.292635 -237.964172) (xy 360.328887 -238.003243) (xy 360.358911 -238.04728) (xy 360.382037 -238.095301)
			(xy 360.397747 -238.146231) (xy 360.40569 -238.198935) (xy 360.406188 -238.225584) (xy 360.40569 -238.252233)
			(xy 360.63427 -238.252233) (xy 360.63427 -238.198935) (xy 360.642213 -238.146231) (xy 360.657923 -238.095301)
			(xy 360.681049 -238.04728) (xy 360.711073 -238.003243) (xy 360.747325 -237.964172) (xy 360.788996 -237.930941)
			(xy 360.835154 -237.904292) (xy 360.884768 -237.88482) (xy 360.93673 -237.87296) (xy 360.98988 -237.868977)
			(xy 361.04303 -237.87296) (xy 361.094992 -237.88482) (xy 361.144606 -237.904292) (xy 361.190764 -237.930941)
			(xy 361.232435 -237.964172) (xy 361.268687 -238.003243) (xy 361.298711 -238.04728) (xy 361.321837 -238.095301)
			(xy 361.337547 -238.146231) (xy 361.34549 -238.198935) (xy 361.345988 -238.225584) (xy 361.34549 -238.252233)
			(xy 361.57407 -238.252233) (xy 361.57407 -238.198935) (xy 361.582013 -238.146231) (xy 361.597723 -238.095301)
			(xy 361.620849 -238.04728) (xy 361.650873 -238.003243) (xy 361.687125 -237.964172) (xy 361.728796 -237.930941)
			(xy 361.774954 -237.904292) (xy 361.824568 -237.88482) (xy 361.87653 -237.87296) (xy 361.92968 -237.868977)
			(xy 361.98283 -237.87296) (xy 362.034792 -237.88482) (xy 362.084406 -237.904292) (xy 362.130564 -237.930941)
			(xy 362.172235 -237.964172) (xy 362.208487 -238.003243) (xy 362.238511 -238.04728) (xy 362.261637 -238.095301)
			(xy 362.277347 -238.146231) (xy 362.28529 -238.198935) (xy 362.285788 -238.225584) (xy 362.28529 -238.252233)
			(xy 362.277347 -238.304937) (xy 362.261637 -238.355867) (xy 362.238511 -238.403888) (xy 362.208487 -238.447925)
			(xy 362.172235 -238.486996) (xy 362.130564 -238.520227) (xy 362.084406 -238.546876) (xy 362.034792 -238.566348)
			(xy 361.98283 -238.578208) (xy 361.92968 -238.582192) (xy 361.87653 -238.578208) (xy 361.824568 -238.566348)
			(xy 361.774954 -238.546876) (xy 361.728796 -238.520227) (xy 361.687125 -238.486996) (xy 361.650873 -238.447925)
			(xy 361.620849 -238.403888) (xy 361.597723 -238.355867) (xy 361.582013 -238.304937) (xy 361.57407 -238.252233)
			(xy 361.34549 -238.252233) (xy 361.337547 -238.304937) (xy 361.321837 -238.355867) (xy 361.298711 -238.403888)
			(xy 361.268687 -238.447925) (xy 361.232435 -238.486996) (xy 361.190764 -238.520227) (xy 361.144606 -238.546876)
			(xy 361.094992 -238.566348) (xy 361.04303 -238.578208) (xy 360.98988 -238.582192) (xy 360.93673 -238.578208)
			(xy 360.884768 -238.566348) (xy 360.835154 -238.546876) (xy 360.788996 -238.520227) (xy 360.747325 -238.486996)
			(xy 360.711073 -238.447925) (xy 360.681049 -238.403888) (xy 360.657923 -238.355867) (xy 360.642213 -238.304937)
			(xy 360.63427 -238.252233) (xy 360.40569 -238.252233) (xy 360.397747 -238.304937) (xy 360.382037 -238.355867)
			(xy 360.358911 -238.403888) (xy 360.328887 -238.447925) (xy 360.292635 -238.486996) (xy 360.250964 -238.520227)
			(xy 360.204806 -238.546876) (xy 360.155192 -238.566348) (xy 360.10323 -238.578208) (xy 360.05008 -238.582192)
			(xy 359.99693 -238.578208) (xy 359.944968 -238.566348) (xy 359.895354 -238.546876) (xy 359.849196 -238.520227)
			(xy 359.807525 -238.486996) (xy 359.771273 -238.447925) (xy 359.741249 -238.403888) (xy 359.718123 -238.355867)
			(xy 359.702413 -238.304937) (xy 359.69447 -238.252233) (xy 359.46589 -238.252233) (xy 359.457947 -238.304937)
			(xy 359.442237 -238.355867) (xy 359.419111 -238.403888) (xy 359.389087 -238.447925) (xy 359.352835 -238.486996)
			(xy 359.311164 -238.520227) (xy 359.265006 -238.546876) (xy 359.215392 -238.566348) (xy 359.16343 -238.578208)
			(xy 359.11028 -238.582192) (xy 359.05713 -238.578208) (xy 359.005168 -238.566348) (xy 358.955554 -238.546876)
			(xy 358.909396 -238.520227) (xy 358.867725 -238.486996) (xy 358.831473 -238.447925) (xy 358.801449 -238.403888)
			(xy 358.778323 -238.355867) (xy 358.762613 -238.304937) (xy 358.75467 -238.252233) (xy 358.52609 -238.252233)
			(xy 358.518147 -238.304937) (xy 358.502437 -238.355867) (xy 358.479311 -238.403888) (xy 358.449287 -238.447925)
			(xy 358.413035 -238.486996) (xy 358.371364 -238.520227) (xy 358.325206 -238.546876) (xy 358.275592 -238.566348)
			(xy 358.22363 -238.578208) (xy 358.17048 -238.582192) (xy 358.11733 -238.578208) (xy 358.065368 -238.566348)
			(xy 358.015754 -238.546876) (xy 357.969596 -238.520227) (xy 357.927925 -238.486996) (xy 357.891673 -238.447925)
			(xy 357.861649 -238.403888) (xy 357.838523 -238.355867) (xy 357.822813 -238.304937) (xy 357.81487 -238.252233)
			(xy 357.586294 -238.252233) (xy 357.586269 -238.25357) (xy 357.577515 -238.308852) (xy 357.56022 -238.362084)
			(xy 357.53481 -238.411955) (xy 357.501912 -238.457237) (xy 357.462334 -238.496814) (xy 357.417052 -238.529712)
			(xy 357.36718 -238.555122) (xy 357.313948 -238.572416) (xy 357.258666 -238.581169) (xy 357.23068 -238.581692)
			(xy 357.203868 -238.581205) (xy 357.15085 -238.573161) (xy 357.099638 -238.557259) (xy 357.051389 -238.533857)
			(xy 357.007195 -238.503486) (xy 356.968054 -238.466831) (xy 356.934852 -238.424721) (xy 356.90834 -238.378109)
			(xy 356.889117 -238.328049) (xy 356.877617 -238.275672) (xy 356.875334 -238.248952) (xy 356.868077 -238.238145)
			(xy 356.854983 -238.215643) (xy 356.849172 -238.203994) (xy 356.844345 -238.195103) (xy 356.829155 -238.181765)
			(xy 356.809996 -238.175316) (xy 356.789832 -238.176755) (xy 356.780592 -238.18088) (xy 356.755569 -238.192944)
			(xy 356.702709 -238.210019) (xy 356.647838 -238.218674) (xy 356.620064 -238.219234) (xy 356.593239 -238.218745)
			(xy 356.540196 -238.210692) (xy 356.488962 -238.194774) (xy 356.440695 -238.171351) (xy 356.396487 -238.140953)
			(xy 356.357339 -238.104267) (xy 356.324137 -238.062125) (xy 356.297632 -238.015479) (xy 356.278424 -237.965385)
			(xy 356.266947 -237.912977) (xy 356.264718 -237.88624) (xy 356.250077 -237.863952) (xy 356.226919 -237.81592)
			(xy 356.211186 -237.76497) (xy 356.203232 -237.712242) (xy 356.202742 -237.68558) (xy 356.202742 -237.685326)
			(xy 356.203131 -237.661897) (xy 356.209308 -237.615446) (xy 356.22152 -237.570206) (xy 356.239556 -237.526957)
			(xy 356.251002 -237.50651) (xy 356.26548 -237.48111) (xy 356.19944 -237.36554) (xy 356.174548 -237.353856)
			(xy 353.42068 -237.353856) (xy 352.88728 -237.887256) (xy 352.88728 -238.85398) (xy 352.8877 -238.867499)
			(xy 352.894799 -238.893589) (xy 352.908504 -238.916897) (xy 352.927852 -238.935784) (xy 352.951482 -238.948925)
			(xy 352.977735 -238.955395) (xy 353.004765 -238.95474) (xy 353.017836 -238.951262) (xy 353.042667 -238.944363)
			(xy 353.093668 -238.936962) (xy 353.119436 -238.93653) (xy 353.146081 -238.937031) (xy 353.198774 -238.944978)
			(xy 353.249695 -238.960689) (xy 353.297705 -238.983814) (xy 353.341733 -239.013836) (xy 353.380795 -239.050084)
			(xy 353.393526 -239.066049) (xy 361.10417 -239.066049) (xy 361.10417 -239.012751) (xy 361.112113 -238.960047)
			(xy 361.127823 -238.909117) (xy 361.150949 -238.861096) (xy 361.180973 -238.817059) (xy 361.217225 -238.777988)
			(xy 361.258896 -238.744757) (xy 361.305054 -238.718108) (xy 361.354668 -238.698636) (xy 361.40663 -238.686776)
			(xy 361.45978 -238.682793) (xy 361.51293 -238.686776) (xy 361.564892 -238.698636) (xy 361.614506 -238.718108)
			(xy 361.660664 -238.744757) (xy 361.702335 -238.777988) (xy 361.738587 -238.817059) (xy 361.768611 -238.861096)
			(xy 361.791737 -238.909117) (xy 361.807447 -238.960047) (xy 361.81539 -239.012751) (xy 361.815888 -239.0394)
			(xy 361.81539 -239.066049) (xy 361.807447 -239.118753) (xy 361.791737 -239.169683) (xy 361.768611 -239.217704)
			(xy 361.738587 -239.261741) (xy 361.702335 -239.300812) (xy 361.660664 -239.334043) (xy 361.614506 -239.360692)
			(xy 361.564892 -239.380164) (xy 361.51293 -239.392024) (xy 361.45978 -239.396008) (xy 361.40663 -239.392024)
			(xy 361.354668 -239.380164) (xy 361.305054 -239.360692) (xy 361.258896 -239.334043) (xy 361.217225 -239.300812)
			(xy 361.180973 -239.261741) (xy 361.150949 -239.217704) (xy 361.127823 -239.169683) (xy 361.112113 -239.118753)
			(xy 361.10417 -239.066049) (xy 353.393526 -239.066049) (xy 353.414019 -239.091749) (xy 353.440662 -239.1379)
			(xy 353.46013 -239.187506) (xy 353.471987 -239.23946) (xy 353.475969 -239.2926) (xy 353.471987 -239.34574)
			(xy 353.46013 -239.397694) (xy 353.440662 -239.4473) (xy 353.414019 -239.493451) (xy 353.380795 -239.535116)
			(xy 353.341733 -239.571364) (xy 353.297705 -239.601386) (xy 353.249695 -239.624511) (xy 353.198774 -239.640222)
			(xy 353.146081 -239.648169) (xy 353.119436 -239.648746) (xy 353.093018 -239.648261) (xy 353.040761 -239.64045)
			(xy 352.990231 -239.625008) (xy 352.942535 -239.602274) (xy 352.898719 -239.572747) (xy 352.878898 -239.555274)
			(xy 352.554307 -239.879865) (xy 357.815124 -239.879865) (xy 357.815124 -239.826567) (xy 357.823067 -239.773863)
			(xy 357.838777 -239.722933) (xy 357.861903 -239.674912) (xy 357.891927 -239.630875) (xy 357.928179 -239.591804)
			(xy 357.96985 -239.558573) (xy 358.016008 -239.531924) (xy 358.065622 -239.512452) (xy 358.117584 -239.500592)
			(xy 358.170734 -239.496609) (xy 358.223884 -239.500592) (xy 358.275846 -239.512452) (xy 358.32546 -239.531924)
			(xy 358.371618 -239.558573) (xy 358.413289 -239.591804) (xy 358.449541 -239.630875) (xy 358.479565 -239.674912)
			(xy 358.502691 -239.722933) (xy 358.518401 -239.773863) (xy 358.526344 -239.826567) (xy 358.526842 -239.853216)
			(xy 358.526344 -239.879865) (xy 358.518401 -239.932569) (xy 358.502691 -239.983499) (xy 358.479565 -240.03152)
			(xy 358.449541 -240.075557) (xy 358.413289 -240.114628) (xy 358.371618 -240.147859) (xy 358.32546 -240.174508)
			(xy 358.275846 -240.19398) (xy 358.223884 -240.20584) (xy 358.170734 -240.209824) (xy 358.117584 -240.20584)
			(xy 358.065622 -240.19398) (xy 358.016008 -240.174508) (xy 357.96985 -240.147859) (xy 357.928179 -240.114628)
			(xy 357.891927 -240.075557) (xy 357.861903 -240.03152) (xy 357.838777 -239.983499) (xy 357.823067 -239.932569)
			(xy 357.815124 -239.879865) (xy 352.554307 -239.879865) (xy 351.990152 -240.44402) (xy 351.689416 -240.74501)
			(xy 351.689416 -241.172492) (xy 356.009956 -241.172492) (xy 356.010354 -241.147822) (xy 356.017161 -241.098954)
			(xy 356.030658 -241.051496) (xy 356.050585 -241.006359) (xy 356.07656 -240.964409) (xy 356.091998 -240.945162)
			(xy 356.100635 -240.934039) (xy 356.111985 -240.908277) (xy 356.115866 -240.880394) (xy 356.111982 -240.852511)
			(xy 356.100628 -240.826751) (xy 356.091998 -240.815622) (xy 356.076554 -240.796381) (xy 356.050596 -240.754424)
			(xy 356.03068 -240.709284) (xy 356.017187 -240.661827) (xy 356.010376 -240.612961) (xy 356.009956 -240.588292)
			(xy 356.010454 -240.561643) (xy 356.018397 -240.508939) (xy 356.034107 -240.458009) (xy 356.057233 -240.409988)
			(xy 356.087257 -240.365951) (xy 356.123509 -240.32688) (xy 356.16518 -240.293649) (xy 356.211338 -240.267)
			(xy 356.260952 -240.247528) (xy 356.312914 -240.235668) (xy 356.366064 -240.231685) (xy 356.419214 -240.235668)
			(xy 356.471176 -240.247528) (xy 356.52079 -240.267) (xy 356.566948 -240.293649) (xy 356.608619 -240.32688)
			(xy 356.644871 -240.365951) (xy 356.674895 -240.409988) (xy 356.698021 -240.458009) (xy 356.713731 -240.508939)
			(xy 356.721674 -240.561643) (xy 356.722172 -240.588292) (xy 356.721759 -240.612962) (xy 356.714955 -240.661829)
			(xy 356.705826 -240.693935) (xy 361.104424 -240.693935) (xy 361.104424 -240.640637) (xy 361.112367 -240.587933)
			(xy 361.128077 -240.537003) (xy 361.151203 -240.488982) (xy 361.181227 -240.444945) (xy 361.217479 -240.405874)
			(xy 361.25915 -240.372643) (xy 361.305308 -240.345994) (xy 361.354922 -240.326522) (xy 361.406884 -240.314662)
			(xy 361.460034 -240.310679) (xy 361.513184 -240.314662) (xy 361.565146 -240.326522) (xy 361.61476 -240.345994)
			(xy 361.660918 -240.372643) (xy 361.702589 -240.405874) (xy 361.738841 -240.444945) (xy 361.768865 -240.488982)
			(xy 361.791991 -240.537003) (xy 361.807701 -240.587933) (xy 361.815644 -240.640637) (xy 361.816142 -240.667286)
			(xy 361.815644 -240.693935) (xy 361.807701 -240.746639) (xy 361.791991 -240.797569) (xy 361.768865 -240.84559)
			(xy 361.738841 -240.889627) (xy 361.702589 -240.928698) (xy 361.660918 -240.961929) (xy 361.61476 -240.988578)
			(xy 361.565146 -241.00805) (xy 361.513184 -241.01991) (xy 361.460034 -241.023894) (xy 361.406884 -241.01991)
			(xy 361.354922 -241.00805) (xy 361.305308 -240.988578) (xy 361.25915 -240.961929) (xy 361.217479 -240.928698)
			(xy 361.181227 -240.889627) (xy 361.151203 -240.84559) (xy 361.128077 -240.797569) (xy 361.112367 -240.746639)
			(xy 361.104424 -240.693935) (xy 356.705826 -240.693935) (xy 356.701461 -240.709287) (xy 356.681537 -240.754424)
			(xy 356.655566 -240.796374) (xy 356.64013 -240.815622) (xy 356.631513 -240.826758) (xy 356.620169 -240.852517)
			(xy 356.616289 -240.880394) (xy 356.620166 -240.908271) (xy 356.631507 -240.934031) (xy 356.64013 -240.945162)
			(xy 356.655571 -240.964405) (xy 356.681529 -241.006362) (xy 356.701445 -241.051501) (xy 356.714939 -241.098958)
			(xy 356.721751 -241.147823) (xy 356.722172 -241.172492) (xy 356.721674 -241.199141) (xy 356.713731 -241.251845)
			(xy 356.698021 -241.302775) (xy 356.674895 -241.350796) (xy 356.644871 -241.394833) (xy 356.608619 -241.433904)
			(xy 356.566948 -241.467135) (xy 356.52079 -241.493784) (xy 356.485203 -241.507751) (xy 357.815124 -241.507751)
			(xy 357.815124 -241.454453) (xy 357.823067 -241.401749) (xy 357.838777 -241.350819) (xy 357.861903 -241.302798)
			(xy 357.891927 -241.258761) (xy 357.928179 -241.21969) (xy 357.96985 -241.186459) (xy 358.016008 -241.15981)
			(xy 358.065622 -241.140338) (xy 358.117584 -241.128478) (xy 358.170734 -241.124495) (xy 358.223884 -241.128478)
			(xy 358.275846 -241.140338) (xy 358.32546 -241.15981) (xy 358.371618 -241.186459) (xy 358.413289 -241.21969)
			(xy 358.449541 -241.258761) (xy 358.479565 -241.302798) (xy 358.502691 -241.350819) (xy 358.518401 -241.401749)
			(xy 358.526344 -241.454453) (xy 358.526842 -241.481102) (xy 358.526344 -241.507751) (xy 358.518401 -241.560455)
			(xy 358.502691 -241.611385) (xy 358.479565 -241.659406) (xy 358.475579 -241.665252) (xy 363.007148 -241.665252)
			(xy 363.007582 -241.640583) (xy 363.014381 -241.591717) (xy 363.027869 -241.544259) (xy 363.047789 -241.499121)
			(xy 363.073756 -241.457171) (xy 363.08919 -241.437922) (xy 363.097865 -241.426826) (xy 363.109212 -241.401054)
			(xy 363.113085 -241.373163) (xy 363.109191 -241.345274) (xy 363.097826 -241.319511) (xy 363.08919 -241.308382)
			(xy 363.073772 -241.289121) (xy 363.047811 -241.247169) (xy 363.027889 -241.202034) (xy 363.01439 -241.154582)
			(xy 363.007572 -241.10572) (xy 363.007148 -241.081052) (xy 363.007646 -241.054403) (xy 363.015589 -241.001699)
			(xy 363.031299 -240.950769) (xy 363.054425 -240.902748) (xy 363.084449 -240.858711) (xy 363.120701 -240.81964)
			(xy 363.162372 -240.786409) (xy 363.20853 -240.75976) (xy 363.258144 -240.740288) (xy 363.310106 -240.728428)
			(xy 363.363256 -240.724445) (xy 363.416406 -240.728428) (xy 363.468368 -240.740288) (xy 363.517982 -240.75976)
			(xy 363.56414 -240.786409) (xy 363.605811 -240.81964) (xy 363.642063 -240.858711) (xy 363.672087 -240.902748)
			(xy 363.695213 -240.950769) (xy 363.710923 -241.001699) (xy 363.718866 -241.054403) (xy 363.719364 -241.081052)
			(xy 363.71893 -241.105721) (xy 363.712131 -241.154587) (xy 363.698642 -241.202045) (xy 363.678723 -241.247182)
			(xy 363.652756 -241.289133) (xy 363.637322 -241.308382) (xy 363.628744 -241.319546) (xy 363.617396 -241.345294)
			(xy 363.613508 -241.373163) (xy 363.617376 -241.401034) (xy 363.628705 -241.426791) (xy 363.637322 -241.437922)
			(xy 363.652743 -241.45718) (xy 363.678704 -241.499133) (xy 363.698625 -241.544268) (xy 363.712123 -241.591722)
			(xy 363.718941 -241.640584) (xy 363.719364 -241.665252) (xy 363.718866 -241.691901) (xy 363.710923 -241.744605)
			(xy 363.695213 -241.795535) (xy 363.672087 -241.843556) (xy 363.642063 -241.887593) (xy 363.605811 -241.926664)
			(xy 363.56414 -241.959895) (xy 363.517982 -241.986544) (xy 363.468368 -242.006016) (xy 363.416406 -242.017876)
			(xy 363.363256 -242.02186) (xy 363.310106 -242.017876) (xy 363.258144 -242.006016) (xy 363.20853 -241.986544)
			(xy 363.162372 -241.959895) (xy 363.120701 -241.926664) (xy 363.084449 -241.887593) (xy 363.054425 -241.843556)
			(xy 363.031299 -241.795535) (xy 363.015589 -241.744605) (xy 363.007646 -241.691901) (xy 363.007148 -241.665252)
			(xy 358.475579 -241.665252) (xy 358.449541 -241.703443) (xy 358.413289 -241.742514) (xy 358.371618 -241.775745)
			(xy 358.32546 -241.802394) (xy 358.275846 -241.821866) (xy 358.223884 -241.833726) (xy 358.170734 -241.83771)
			(xy 358.117584 -241.833726) (xy 358.065622 -241.821866) (xy 358.016008 -241.802394) (xy 357.96985 -241.775745)
			(xy 357.928179 -241.742514) (xy 357.891927 -241.703443) (xy 357.861903 -241.659406) (xy 357.838777 -241.611385)
			(xy 357.823067 -241.560455) (xy 357.815124 -241.507751) (xy 356.485203 -241.507751) (xy 356.471176 -241.513256)
			(xy 356.419214 -241.525116) (xy 356.366064 -241.5291) (xy 356.312914 -241.525116) (xy 356.260952 -241.513256)
			(xy 356.211338 -241.493784) (xy 356.16518 -241.467135) (xy 356.123509 -241.433904) (xy 356.087257 -241.394833)
			(xy 356.057233 -241.350796) (xy 356.034107 -241.302775) (xy 356.018397 -241.251845) (xy 356.010454 -241.199141)
			(xy 356.009956 -241.172492) (xy 351.689416 -241.172492) (xy 351.689416 -242.321567) (xy 361.104424 -242.321567)
			(xy 361.104424 -242.268269) (xy 361.112367 -242.215565) (xy 361.128077 -242.164635) (xy 361.151203 -242.116614)
			(xy 361.181227 -242.072577) (xy 361.217479 -242.033506) (xy 361.25915 -242.000275) (xy 361.305308 -241.973626)
			(xy 361.354922 -241.954154) (xy 361.406884 -241.942294) (xy 361.460034 -241.938311) (xy 361.513184 -241.942294)
			(xy 361.565146 -241.954154) (xy 361.61476 -241.973626) (xy 361.660918 -242.000275) (xy 361.702589 -242.033506)
			(xy 361.738841 -242.072577) (xy 361.768865 -242.116614) (xy 361.791991 -242.164635) (xy 361.807701 -242.215565)
			(xy 361.815644 -242.268269) (xy 361.816142 -242.294918) (xy 361.815644 -242.321567) (xy 361.807701 -242.374271)
			(xy 361.791991 -242.425201) (xy 361.768865 -242.473222) (xy 361.738841 -242.517259) (xy 361.702589 -242.55633)
			(xy 361.660918 -242.589561) (xy 361.61476 -242.61621) (xy 361.565146 -242.635682) (xy 361.513184 -242.647542)
			(xy 361.460034 -242.651526) (xy 361.406884 -242.647542) (xy 361.354922 -242.635682) (xy 361.305308 -242.61621)
			(xy 361.25915 -242.589561) (xy 361.217479 -242.55633) (xy 361.181227 -242.517259) (xy 361.151203 -242.473222)
			(xy 361.128077 -242.425201) (xy 361.112367 -242.374271) (xy 361.104424 -242.321567) (xy 351.689416 -242.321567)
			(xy 351.689416 -243.135637) (xy 357.815124 -243.135637) (xy 357.815124 -243.082339) (xy 357.823067 -243.029635)
			(xy 357.838777 -242.978705) (xy 357.861903 -242.930684) (xy 357.891927 -242.886647) (xy 357.928179 -242.847576)
			(xy 357.96985 -242.814345) (xy 358.016008 -242.787696) (xy 358.065622 -242.768224) (xy 358.117584 -242.756364)
			(xy 358.170734 -242.752381) (xy 358.223884 -242.756364) (xy 358.275846 -242.768224) (xy 358.32546 -242.787696)
			(xy 358.371618 -242.814345) (xy 358.413289 -242.847576) (xy 358.449541 -242.886647) (xy 358.479565 -242.930684)
			(xy 358.494116 -242.9609) (xy 365.407174 -242.9609) (xy 365.411157 -242.907747) (xy 365.423018 -242.855781)
			(xy 365.442492 -242.806163) (xy 365.469144 -242.760002) (xy 365.502378 -242.718329) (xy 365.541452 -242.682075)
			(xy 365.585493 -242.652049) (xy 365.633517 -242.628923) (xy 365.684452 -242.613213) (xy 365.737159 -242.60527)
			(xy 365.76381 -242.604798) (xy 365.789744 -242.605284) (xy 365.841064 -242.6128) (xy 365.890754 -242.627672)
			(xy 365.937765 -242.649586) (xy 365.981105 -242.67808) (xy 366.000792 -242.694968) (xy 366.012186 -242.704456)
			(xy 366.039034 -242.717005) (xy 366.068356 -242.721309) (xy 366.097678 -242.717005) (xy 366.124526 -242.704456)
			(xy 366.13592 -242.694968) (xy 366.15557 -242.67803) (xy 366.198903 -242.649505) (xy 366.245921 -242.62758)
			(xy 366.295626 -242.61272) (xy 366.346962 -242.605239) (xy 366.372902 -242.604798) (xy 366.399552 -242.605284)
			(xy 366.452256 -242.613228) (xy 366.503187 -242.628938) (xy 366.551208 -242.652064) (xy 366.595246 -242.682089)
			(xy 366.634317 -242.718342) (xy 366.667548 -242.760013) (xy 366.694198 -242.806172) (xy 366.71367 -242.855787)
			(xy 366.72553 -242.90775) (xy 366.729514 -242.9609) (xy 366.72553 -243.01405) (xy 366.71367 -243.066013)
			(xy 366.694198 -243.115628) (xy 366.667548 -243.161787) (xy 366.634317 -243.203458) (xy 366.595246 -243.239711)
			(xy 366.551208 -243.269736) (xy 366.503187 -243.292862) (xy 366.452256 -243.308572) (xy 366.399552 -243.316516)
			(xy 366.372902 -243.317014) (xy 366.346969 -243.316518) (xy 366.295649 -243.309004) (xy 366.245959 -243.294134)
			(xy 366.198948 -243.272222) (xy 366.155608 -243.243731) (xy 366.13592 -243.226844) (xy 366.124526 -243.217356)
			(xy 366.097678 -243.204807) (xy 366.068356 -243.200503) (xy 366.039034 -243.204807) (xy 366.012186 -243.217356)
			(xy 366.000792 -243.226844) (xy 365.981139 -243.243778) (xy 365.937806 -243.272303) (xy 365.890789 -243.294229)
			(xy 365.841085 -243.30909) (xy 365.78975 -243.316572) (xy 365.76381 -243.317014) (xy 365.737159 -243.31653)
			(xy 365.684452 -243.308587) (xy 365.633517 -243.292877) (xy 365.585493 -243.269751) (xy 365.541452 -243.239725)
			(xy 365.502378 -243.203471) (xy 365.469144 -243.161798) (xy 365.442492 -243.115637) (xy 365.423018 -243.066019)
			(xy 365.411157 -243.014053) (xy 365.407174 -242.9609) (xy 358.494116 -242.9609) (xy 358.502691 -242.978705)
			(xy 358.518401 -243.029635) (xy 358.526344 -243.082339) (xy 358.526842 -243.108988) (xy 358.526344 -243.135637)
			(xy 358.518401 -243.188341) (xy 358.502691 -243.239271) (xy 358.479565 -243.287292) (xy 358.449541 -243.331329)
			(xy 358.413289 -243.3704) (xy 358.371618 -243.403631) (xy 358.32546 -243.43028) (xy 358.275846 -243.449752)
			(xy 358.223884 -243.461612) (xy 358.170734 -243.465596) (xy 358.117584 -243.461612) (xy 358.065622 -243.449752)
			(xy 358.016008 -243.43028) (xy 357.96985 -243.403631) (xy 357.928179 -243.3704) (xy 357.891927 -243.331329)
			(xy 357.861903 -243.287292) (xy 357.838777 -243.239271) (xy 357.823067 -243.188341) (xy 357.815124 -243.135637)
			(xy 351.689416 -243.135637) (xy 351.689416 -243.262912) (xy 352.375835 -243.949453) (xy 361.104424 -243.949453)
			(xy 361.104424 -243.896155) (xy 361.112367 -243.843451) (xy 361.128077 -243.792521) (xy 361.151203 -243.7445)
			(xy 361.181227 -243.700463) (xy 361.217479 -243.661392) (xy 361.25915 -243.628161) (xy 361.305308 -243.601512)
			(xy 361.354922 -243.58204) (xy 361.406884 -243.57018) (xy 361.460034 -243.566197) (xy 361.513184 -243.57018)
			(xy 361.565146 -243.58204) (xy 361.61476 -243.601512) (xy 361.660918 -243.628161) (xy 361.702589 -243.661392)
			(xy 361.738841 -243.700463) (xy 361.768865 -243.7445) (xy 361.791991 -243.792521) (xy 361.807701 -243.843451)
			(xy 361.815644 -243.896155) (xy 361.816142 -243.922804) (xy 361.815644 -243.949453) (xy 361.807701 -244.002157)
			(xy 361.791991 -244.053087) (xy 361.768865 -244.101108) (xy 361.738841 -244.145145) (xy 361.702589 -244.184216)
			(xy 361.660918 -244.217447) (xy 361.61476 -244.244096) (xy 361.565146 -244.263568) (xy 361.513184 -244.275428)
			(xy 361.460034 -244.279412) (xy 361.406884 -244.275428) (xy 361.354922 -244.263568) (xy 361.305308 -244.244096)
			(xy 361.25915 -244.217447) (xy 361.217479 -244.184216) (xy 361.181227 -244.145145) (xy 361.151203 -244.101108)
			(xy 361.128077 -244.053087) (xy 361.112367 -244.002157) (xy 361.104424 -243.949453) (xy 352.375835 -243.949453)
			(xy 353.114864 -244.688614) (xy 353.114864 -245.347236) (xy 356.017576 -245.347236) (xy 356.017994 -245.322567)
			(xy 356.024796 -245.273699) (xy 356.038288 -245.226241) (xy 356.058211 -245.181104) (xy 356.084182 -245.139154)
			(xy 356.099618 -245.119906) (xy 356.108212 -245.108752) (xy 356.119565 -245.083001) (xy 356.123453 -245.055128)
			(xy 356.11958 -245.027253) (xy 356.108241 -245.001495) (xy 356.099618 -244.990366) (xy 356.084182 -244.971119)
			(xy 356.058225 -244.929162) (xy 356.038308 -244.884024) (xy 356.024813 -244.836569) (xy 356.017998 -244.787704)
			(xy 356.017576 -244.763036) (xy 356.018074 -244.736387) (xy 356.026017 -244.683683) (xy 356.041727 -244.632753)
			(xy 356.064853 -244.584732) (xy 356.094877 -244.540695) (xy 356.131129 -244.501624) (xy 356.1728 -244.468393)
			(xy 356.218958 -244.441744) (xy 356.268572 -244.422272) (xy 356.320534 -244.410412) (xy 356.373684 -244.406429)
			(xy 356.426834 -244.410412) (xy 356.478796 -244.422272) (xy 356.52841 -244.441744) (xy 356.574568 -244.468393)
			(xy 356.616239 -244.501624) (xy 356.652491 -244.540695) (xy 356.682515 -244.584732) (xy 356.705641 -244.632753)
			(xy 356.721351 -244.683683) (xy 356.729294 -244.736387) (xy 356.729792 -244.763036) (xy 356.729788 -244.763269)
			(xy 357.815124 -244.763269) (xy 357.815124 -244.709971) (xy 357.823067 -244.657267) (xy 357.838777 -244.606337)
			(xy 357.861903 -244.558316) (xy 357.891927 -244.514279) (xy 357.928179 -244.475208) (xy 357.96985 -244.441977)
			(xy 358.016008 -244.415328) (xy 358.065622 -244.395856) (xy 358.117584 -244.383996) (xy 358.170734 -244.380013)
			(xy 358.223884 -244.383996) (xy 358.275846 -244.395856) (xy 358.32546 -244.415328) (xy 358.371618 -244.441977)
			(xy 358.413289 -244.475208) (xy 358.449541 -244.514279) (xy 358.479565 -244.558316) (xy 358.502691 -244.606337)
			(xy 358.518401 -244.657267) (xy 358.526344 -244.709971) (xy 358.526842 -244.73662) (xy 358.526344 -244.763269)
			(xy 358.518401 -244.815973) (xy 358.502691 -244.866903) (xy 358.479565 -244.914924) (xy 358.449541 -244.958961)
			(xy 358.413289 -244.998032) (xy 358.371618 -245.031263) (xy 358.32546 -245.057912) (xy 358.275846 -245.077384)
			(xy 358.223884 -245.089244) (xy 358.170734 -245.093228) (xy 358.117584 -245.089244) (xy 358.065622 -245.077384)
			(xy 358.016008 -245.057912) (xy 357.96985 -245.031263) (xy 357.928179 -244.998032) (xy 357.891927 -244.958961)
			(xy 357.861903 -244.914924) (xy 357.838777 -244.866903) (xy 357.823067 -244.815973) (xy 357.815124 -244.763269)
			(xy 356.729788 -244.763269) (xy 356.729342 -244.787704) (xy 356.722546 -244.83657) (xy 356.70906 -244.884027)
			(xy 356.689145 -244.929165) (xy 356.663182 -244.971116) (xy 356.64775 -244.990366) (xy 356.63909 -245.001472)
			(xy 356.627749 -245.027241) (xy 356.623876 -245.055128) (xy 356.627764 -245.083013) (xy 356.639119 -245.108776)
			(xy 356.64775 -245.119906) (xy 356.663168 -245.139166) (xy 356.689129 -245.181119) (xy 356.70905 -245.226254)
			(xy 356.722549 -245.273707) (xy 356.729368 -245.322568) (xy 356.729792 -245.347236) (xy 356.729294 -245.373885)
			(xy 356.721351 -245.426589) (xy 356.705641 -245.477519) (xy 356.682515 -245.52554) (xy 356.652491 -245.569577)
			(xy 356.645289 -245.577339) (xy 361.104424 -245.577339) (xy 361.104424 -245.524041) (xy 361.112367 -245.471337)
			(xy 361.128077 -245.420407) (xy 361.151203 -245.372386) (xy 361.181227 -245.328349) (xy 361.217479 -245.289278)
			(xy 361.25915 -245.256047) (xy 361.305308 -245.229398) (xy 361.354922 -245.209926) (xy 361.406884 -245.198066)
			(xy 361.460034 -245.194083) (xy 361.513184 -245.198066) (xy 361.565146 -245.209926) (xy 361.61476 -245.229398)
			(xy 361.660918 -245.256047) (xy 361.702589 -245.289278) (xy 361.738841 -245.328349) (xy 361.768865 -245.372386)
			(xy 361.780484 -245.396512) (xy 362.999528 -245.396512) (xy 362.999943 -245.371843) (xy 363.006747 -245.322975)
			(xy 363.02024 -245.275518) (xy 363.040163 -245.23038) (xy 363.066134 -245.18843) (xy 363.08157 -245.169182)
			(xy 363.090183 -245.158043) (xy 363.101527 -245.132286) (xy 363.105409 -245.104409) (xy 363.101532 -245.076532)
			(xy 363.090193 -245.050773) (xy 363.08157 -245.039642) (xy 363.066131 -245.020398) (xy 363.040173 -244.978441)
			(xy 363.020256 -244.933302) (xy 363.006762 -244.885846) (xy 362.999949 -244.836981) (xy 362.999528 -244.812312)
			(xy 363.000026 -244.785663) (xy 363.007969 -244.732959) (xy 363.023679 -244.682029) (xy 363.046805 -244.634008)
			(xy 363.076829 -244.589971) (xy 363.113081 -244.5509) (xy 363.154752 -244.517669) (xy 363.20091 -244.49102)
			(xy 363.250524 -244.471548) (xy 363.302486 -244.459688) (xy 363.355636 -244.455705) (xy 363.408786 -244.459688)
			(xy 363.460748 -244.471548) (xy 363.510362 -244.49102) (xy 363.55652 -244.517669) (xy 363.598191 -244.5509)
			(xy 363.634443 -244.589971) (xy 363.664467 -244.634008) (xy 363.687593 -244.682029) (xy 363.703303 -244.732959)
			(xy 363.711246 -244.785663) (xy 363.711744 -244.812312) (xy 363.711349 -244.836982) (xy 363.704541 -244.88585)
			(xy 363.691043 -244.933309) (xy 363.671116 -244.978446) (xy 363.64514 -245.020395) (xy 363.629702 -245.039642)
			(xy 363.621061 -245.050763) (xy 363.609712 -245.076526) (xy 363.605832 -245.104409) (xy 363.609717 -245.132292)
			(xy 363.621071 -245.158053) (xy 363.629702 -245.169182) (xy 363.645102 -245.188457) (xy 363.671067 -245.230405)
			(xy 363.690992 -245.275536) (xy 363.704495 -245.322986) (xy 363.711318 -245.371845) (xy 363.711744 -245.396512)
			(xy 363.711246 -245.423161) (xy 363.703303 -245.475865) (xy 363.687593 -245.526795) (xy 363.664467 -245.574816)
			(xy 363.634443 -245.618853) (xy 363.598191 -245.657924) (xy 363.55652 -245.691155) (xy 363.510362 -245.717804)
			(xy 363.460748 -245.737276) (xy 363.408786 -245.749136) (xy 363.355636 -245.75312) (xy 363.302486 -245.749136)
			(xy 363.250524 -245.737276) (xy 363.20091 -245.717804) (xy 363.154752 -245.691155) (xy 363.113081 -245.657924)
			(xy 363.076829 -245.618853) (xy 363.046805 -245.574816) (xy 363.023679 -245.526795) (xy 363.007969 -245.475865)
			(xy 363.000026 -245.423161) (xy 362.999528 -245.396512) (xy 361.780484 -245.396512) (xy 361.791991 -245.420407)
			(xy 361.807701 -245.471337) (xy 361.815644 -245.524041) (xy 361.816142 -245.55069) (xy 361.815644 -245.577339)
			(xy 361.807701 -245.630043) (xy 361.791991 -245.680973) (xy 361.768865 -245.728994) (xy 361.738841 -245.773031)
			(xy 361.702589 -245.812102) (xy 361.660918 -245.845333) (xy 361.61476 -245.871982) (xy 361.565146 -245.891454)
			(xy 361.513184 -245.903314) (xy 361.460034 -245.907298) (xy 361.406884 -245.903314) (xy 361.354922 -245.891454)
			(xy 361.305308 -245.871982) (xy 361.25915 -245.845333) (xy 361.217479 -245.812102) (xy 361.181227 -245.773031)
			(xy 361.151203 -245.728994) (xy 361.128077 -245.680973) (xy 361.112367 -245.630043) (xy 361.104424 -245.577339)
			(xy 356.645289 -245.577339) (xy 356.616239 -245.608648) (xy 356.574568 -245.641879) (xy 356.52841 -245.668528)
			(xy 356.478796 -245.688) (xy 356.426834 -245.69986) (xy 356.373684 -245.703844) (xy 356.320534 -245.69986)
			(xy 356.268572 -245.688) (xy 356.218958 -245.668528) (xy 356.1728 -245.641879) (xy 356.131129 -245.608648)
			(xy 356.094877 -245.569577) (xy 356.064853 -245.52554) (xy 356.041727 -245.477519) (xy 356.026017 -245.426589)
			(xy 356.018074 -245.373885) (xy 356.017576 -245.347236) (xy 353.114864 -245.347236) (xy 353.114864 -246.21236)
			(xy 353.11535 -246.227772) (xy 353.124452 -246.257219) (xy 353.141929 -246.282607) (xy 353.166187 -246.30162)
			(xy 353.195015 -246.312525) (xy 353.210368 -246.31396) (xy 353.239844 -246.316361) (xy 353.297457 -246.329691)
			(xy 353.352083 -246.352341) (xy 353.402224 -246.383692) (xy 353.424744 -246.40286) (xy 353.436122 -246.41225)
			(xy 353.462874 -246.424653) (xy 353.492054 -246.428905) (xy 353.521234 -246.424653) (xy 353.547986 -246.41225)
			(xy 353.559364 -246.40286) (xy 353.579007 -246.386065) (xy 353.622229 -246.357732) (xy 353.66909 -246.335941)
			(xy 353.718608 -246.321149) (xy 353.769744 -246.313666) (xy 353.795584 -246.313198) (xy 353.822235 -246.31367)
			(xy 353.874943 -246.321612) (xy 353.925879 -246.337322) (xy 353.973904 -246.360447) (xy 354.017946 -246.390473)
			(xy 354.018681 -246.391155) (xy 357.815124 -246.391155) (xy 357.815124 -246.337857) (xy 357.823067 -246.285153)
			(xy 357.838777 -246.234223) (xy 357.861903 -246.186202) (xy 357.891927 -246.142165) (xy 357.928179 -246.103094)
			(xy 357.96985 -246.069863) (xy 358.016008 -246.043214) (xy 358.065622 -246.023742) (xy 358.117584 -246.011882)
			(xy 358.170734 -246.007899) (xy 358.223884 -246.011882) (xy 358.275846 -246.023742) (xy 358.32546 -246.043214)
			(xy 358.371618 -246.069863) (xy 358.413289 -246.103094) (xy 358.449541 -246.142165) (xy 358.479565 -246.186202)
			(xy 358.502691 -246.234223) (xy 358.518401 -246.285153) (xy 358.526344 -246.337857) (xy 358.526842 -246.364506)
			(xy 358.526344 -246.391155) (xy 358.518401 -246.443859) (xy 358.502691 -246.494789) (xy 358.479565 -246.54281)
			(xy 358.449541 -246.586847) (xy 358.413289 -246.625918) (xy 358.371618 -246.659149) (xy 358.32546 -246.685798)
			(xy 358.275846 -246.70527) (xy 358.223884 -246.71713) (xy 358.170734 -246.721114) (xy 358.117584 -246.71713)
			(xy 358.065622 -246.70527) (xy 358.016008 -246.685798) (xy 357.96985 -246.659149) (xy 357.928179 -246.625918)
			(xy 357.891927 -246.586847) (xy 357.861903 -246.54281) (xy 357.838777 -246.494789) (xy 357.823067 -246.443859)
			(xy 357.815124 -246.391155) (xy 354.018681 -246.391155) (xy 354.05702 -246.426727) (xy 354.090255 -246.4684)
			(xy 354.116907 -246.514562) (xy 354.136381 -246.56418) (xy 354.148243 -246.616146) (xy 354.152226 -246.6693)
			(xy 354.148243 -246.722454) (xy 354.136381 -246.77442) (xy 354.116907 -246.824038) (xy 354.090255 -246.8702)
			(xy 354.05702 -246.911873) (xy 354.017946 -246.948127) (xy 353.973904 -246.978153) (xy 353.925879 -247.001278)
			(xy 353.874943 -247.016988) (xy 353.822235 -247.02493) (xy 353.795584 -247.025414) (xy 353.769741 -247.024958)
			(xy 353.718598 -247.017494) (xy 353.669072 -247.002711) (xy 353.622204 -246.98092) (xy 353.578982 -246.952579)
			(xy 353.559364 -246.935752) (xy 353.547986 -246.926362) (xy 353.521234 -246.913959) (xy 353.492054 -246.909707)
			(xy 353.462874 -246.913959) (xy 353.436122 -246.926362) (xy 353.424744 -246.935752) (xy 353.402233 -246.954938)
			(xy 353.352107 -246.986325) (xy 353.297477 -247.008985) (xy 353.239851 -247.022293) (xy 353.210368 -247.024652)
			(xy 353.195025 -247.026114) (xy 353.166224 -247.037045) (xy 353.141985 -247.056058) (xy 353.124507 -247.081426)
			(xy 353.115377 -247.110848) (xy 353.114864 -247.126252) (xy 353.114864 -247.204971) (xy 361.104424 -247.204971)
			(xy 361.104424 -247.151673) (xy 361.112367 -247.098969) (xy 361.128077 -247.048039) (xy 361.151203 -247.000018)
			(xy 361.181227 -246.955981) (xy 361.217479 -246.91691) (xy 361.25915 -246.883679) (xy 361.305308 -246.85703)
			(xy 361.354922 -246.837558) (xy 361.406884 -246.825698) (xy 361.460034 -246.821715) (xy 361.513184 -246.825698)
			(xy 361.565146 -246.837558) (xy 361.61476 -246.85703) (xy 361.660918 -246.883679) (xy 361.702589 -246.91691)
			(xy 361.738841 -246.955981) (xy 361.768865 -247.000018) (xy 361.791991 -247.048039) (xy 361.807701 -247.098969)
			(xy 361.815644 -247.151673) (xy 361.816142 -247.178322) (xy 361.815644 -247.204971) (xy 361.807701 -247.257675)
			(xy 361.791991 -247.308605) (xy 361.768865 -247.356626) (xy 361.738841 -247.400663) (xy 361.702589 -247.439734)
			(xy 361.660918 -247.472965) (xy 361.61476 -247.499614) (xy 361.565146 -247.519086) (xy 361.513184 -247.530946)
			(xy 361.460034 -247.53493) (xy 361.406884 -247.530946) (xy 361.354922 -247.519086) (xy 361.305308 -247.499614)
			(xy 361.25915 -247.472965) (xy 361.217479 -247.439734) (xy 361.181227 -247.400663) (xy 361.151203 -247.356626)
			(xy 361.128077 -247.308605) (xy 361.112367 -247.257675) (xy 361.104424 -247.204971) (xy 353.114864 -247.204971)
			(xy 353.114864 -248.018787) (xy 357.815124 -248.018787) (xy 357.815124 -247.965489) (xy 357.823067 -247.912785)
			(xy 357.838777 -247.861855) (xy 357.861903 -247.813834) (xy 357.891927 -247.769797) (xy 357.928179 -247.730726)
			(xy 357.96985 -247.697495) (xy 358.016008 -247.670846) (xy 358.065622 -247.651374) (xy 358.117584 -247.639514)
			(xy 358.170734 -247.635531) (xy 358.223884 -247.639514) (xy 358.275846 -247.651374) (xy 358.32546 -247.670846)
			(xy 358.371618 -247.697495) (xy 358.413289 -247.730726) (xy 358.449541 -247.769797) (xy 358.479565 -247.813834)
			(xy 358.502691 -247.861855) (xy 358.518401 -247.912785) (xy 358.526344 -247.965489) (xy 358.526842 -247.992138)
			(xy 358.526344 -248.018787) (xy 358.518401 -248.071491) (xy 358.502691 -248.122421) (xy 358.479565 -248.170442)
			(xy 358.449541 -248.214479) (xy 358.413289 -248.25355) (xy 358.371618 -248.286781) (xy 358.32546 -248.31343)
			(xy 358.275846 -248.332902) (xy 358.223884 -248.344762) (xy 358.170734 -248.348746) (xy 358.117584 -248.344762)
			(xy 358.065622 -248.332902) (xy 358.016008 -248.31343) (xy 357.96985 -248.286781) (xy 357.928179 -248.25355)
			(xy 357.891927 -248.214479) (xy 357.861903 -248.170442) (xy 357.838777 -248.122421) (xy 357.823067 -248.071491)
			(xy 357.815124 -248.018787) (xy 353.114864 -248.018787) (xy 353.114864 -249.00509) (xy 356.017576 -249.00509)
			(xy 356.017968 -248.98042) (xy 356.024776 -248.931551) (xy 356.038274 -248.884093) (xy 356.058203 -248.838956)
			(xy 356.084179 -248.797007) (xy 356.099618 -248.77776) (xy 356.108255 -248.766637) (xy 356.119603 -248.740875)
			(xy 356.123482 -248.712992) (xy 356.119599 -248.68511) (xy 356.108247 -248.659349) (xy 356.099618 -248.64822)
			(xy 356.084207 -248.628954) (xy 356.058246 -248.587003) (xy 356.038325 -248.541869) (xy 356.024824 -248.494418)
			(xy 356.018002 -248.445557) (xy 356.017576 -248.42089) (xy 356.018074 -248.394241) (xy 356.026017 -248.341537)
			(xy 356.041727 -248.290607) (xy 356.064853 -248.242586) (xy 356.094877 -248.198549) (xy 356.131129 -248.159478)
			(xy 356.1728 -248.126247) (xy 356.218958 -248.099598) (xy 356.268572 -248.080126) (xy 356.320534 -248.068266)
			(xy 356.373684 -248.064283) (xy 356.426834 -248.068266) (xy 356.478796 -248.080126) (xy 356.52841 -248.099598)
			(xy 356.574568 -248.126247) (xy 356.616239 -248.159478) (xy 356.652491 -248.198549) (xy 356.682515 -248.242586)
			(xy 356.705641 -248.290607) (xy 356.721351 -248.341537) (xy 356.729294 -248.394241) (xy 356.729792 -248.42089)
			(xy 356.729374 -248.445559) (xy 356.72257 -248.494426) (xy 356.709077 -248.541884) (xy 356.689155 -248.587021)
			(xy 356.663185 -248.628972) (xy 356.64775 -248.64822) (xy 356.639134 -248.659357) (xy 356.627788 -248.685115)
			(xy 356.623906 -248.712992) (xy 356.627783 -248.74087) (xy 356.639126 -248.76663) (xy 356.64775 -248.77776)
			(xy 356.663193 -248.797001) (xy 356.685375 -248.832857) (xy 361.104424 -248.832857) (xy 361.104424 -248.779559)
			(xy 361.112367 -248.726855) (xy 361.128077 -248.675925) (xy 361.151203 -248.627904) (xy 361.181227 -248.583867)
			(xy 361.217479 -248.544796) (xy 361.25915 -248.511565) (xy 361.305308 -248.484916) (xy 361.354922 -248.465444)
			(xy 361.406884 -248.453584) (xy 361.460034 -248.449601) (xy 361.513184 -248.453584) (xy 361.565146 -248.465444)
			(xy 361.61476 -248.484916) (xy 361.660918 -248.511565) (xy 361.702589 -248.544796) (xy 361.738841 -248.583867)
			(xy 361.768865 -248.627904) (xy 361.791991 -248.675925) (xy 361.807701 -248.726855) (xy 361.815644 -248.779559)
			(xy 361.816142 -248.806208) (xy 361.815644 -248.832857) (xy 361.807701 -248.885561) (xy 361.791991 -248.936491)
			(xy 361.768865 -248.984512) (xy 361.738841 -249.028549) (xy 361.702589 -249.06762) (xy 361.660918 -249.100851)
			(xy 361.61476 -249.1275) (xy 361.565146 -249.146972) (xy 361.513184 -249.158832) (xy 361.460034 -249.162816)
			(xy 361.406884 -249.158832) (xy 361.354922 -249.146972) (xy 361.305308 -249.1275) (xy 361.25915 -249.100851)
			(xy 361.217479 -249.06762) (xy 361.181227 -249.028549) (xy 361.151203 -248.984512) (xy 361.128077 -248.936491)
			(xy 361.112367 -248.885561) (xy 361.104424 -248.832857) (xy 356.685375 -248.832857) (xy 356.68915 -248.838959)
			(xy 356.709066 -248.884099) (xy 356.722559 -248.931556) (xy 356.729372 -248.980421) (xy 356.729792 -249.00509)
			(xy 356.729294 -249.031739) (xy 356.721351 -249.084443) (xy 356.705641 -249.135373) (xy 356.682515 -249.183394)
			(xy 356.652899 -249.226832) (xy 362.966508 -249.226832) (xy 362.966939 -249.202163) (xy 362.97374 -249.153297)
			(xy 362.98723 -249.105839) (xy 363.007149 -249.060702) (xy 363.033116 -249.018751) (xy 363.04855 -248.999502)
			(xy 363.057145 -248.98835) (xy 363.068494 -248.962598) (xy 363.07238 -248.934725) (xy 363.068508 -248.90685)
			(xy 363.057171 -248.881092) (xy 363.04855 -248.869962) (xy 363.033117 -248.850713) (xy 363.007159 -248.808757)
			(xy 362.987241 -248.763619) (xy 362.973745 -248.716164) (xy 362.96693 -248.6673) (xy 362.966508 -248.642632)
			(xy 362.967006 -248.615983) (xy 362.974949 -248.563279) (xy 362.990659 -248.512349) (xy 363.013785 -248.464328)
			(xy 363.043809 -248.420291) (xy 363.080061 -248.38122) (xy 363.121732 -248.347989) (xy 363.16789 -248.32134)
			(xy 363.217504 -248.301868) (xy 363.269466 -248.290008) (xy 363.322616 -248.286025) (xy 363.375766 -248.290008)
			(xy 363.427728 -248.301868) (xy 363.477342 -248.32134) (xy 363.5235 -248.347989) (xy 363.565171 -248.38122)
			(xy 363.601423 -248.420291) (xy 363.631447 -248.464328) (xy 363.654573 -248.512349) (xy 363.670283 -248.563279)
			(xy 363.678226 -248.615983) (xy 363.678724 -248.642632) (xy 363.678345 -248.667303) (xy 363.671534 -248.716172)
			(xy 363.658033 -248.76363) (xy 363.638101 -248.808767) (xy 363.612122 -248.850715) (xy 363.596682 -248.869962)
			(xy 363.588023 -248.881069) (xy 363.576678 -248.906838) (xy 363.572803 -248.934725) (xy 363.576692 -248.96261)
			(xy 363.588049 -248.988373) (xy 363.596682 -248.999502) (xy 363.612103 -249.01876) (xy 363.638062 -249.060714)
			(xy 363.657982 -249.105849) (xy 363.671481 -249.153302) (xy 363.6783 -249.202164) (xy 363.678724 -249.226832)
			(xy 363.678226 -249.253481) (xy 363.670283 -249.306185) (xy 363.654573 -249.357115) (xy 363.631447 -249.405136)
			(xy 363.601423 -249.449173) (xy 363.565171 -249.488244) (xy 363.5235 -249.521475) (xy 363.477342 -249.548124)
			(xy 363.427728 -249.567596) (xy 363.375766 -249.579456) (xy 363.322616 -249.58344) (xy 363.269466 -249.579456)
			(xy 363.217504 -249.567596) (xy 363.16789 -249.548124) (xy 363.121732 -249.521475) (xy 363.080061 -249.488244)
			(xy 363.043809 -249.449173) (xy 363.013785 -249.405136) (xy 362.990659 -249.357115) (xy 362.974949 -249.306185)
			(xy 362.967006 -249.253481) (xy 362.966508 -249.226832) (xy 356.652899 -249.226832) (xy 356.652491 -249.227431)
			(xy 356.616239 -249.266502) (xy 356.574568 -249.299733) (xy 356.52841 -249.326382) (xy 356.478796 -249.345854)
			(xy 356.426834 -249.357714) (xy 356.373684 -249.361698) (xy 356.320534 -249.357714) (xy 356.268572 -249.345854)
			(xy 356.218958 -249.326382) (xy 356.1728 -249.299733) (xy 356.131129 -249.266502) (xy 356.094877 -249.227431)
			(xy 356.064853 -249.183394) (xy 356.041727 -249.135373) (xy 356.026017 -249.084443) (xy 356.018074 -249.031739)
			(xy 356.017576 -249.00509) (xy 353.114864 -249.00509) (xy 353.114864 -249.646673) (xy 357.815124 -249.646673)
			(xy 357.815124 -249.593375) (xy 357.823067 -249.540671) (xy 357.838777 -249.489741) (xy 357.861903 -249.44172)
			(xy 357.891927 -249.397683) (xy 357.928179 -249.358612) (xy 357.96985 -249.325381) (xy 358.016008 -249.298732)
			(xy 358.065622 -249.27926) (xy 358.117584 -249.2674) (xy 358.170734 -249.263417) (xy 358.223884 -249.2674)
			(xy 358.275846 -249.27926) (xy 358.32546 -249.298732) (xy 358.371618 -249.325381) (xy 358.413289 -249.358612)
			(xy 358.449541 -249.397683) (xy 358.479565 -249.44172) (xy 358.502691 -249.489741) (xy 358.518401 -249.540671)
			(xy 358.526344 -249.593375) (xy 358.526842 -249.620024) (xy 358.526344 -249.646673) (xy 358.518401 -249.699377)
			(xy 358.502691 -249.750307) (xy 358.479565 -249.798328) (xy 358.449541 -249.842365) (xy 358.413289 -249.881436)
			(xy 358.371618 -249.914667) (xy 358.32546 -249.941316) (xy 358.275846 -249.960788) (xy 358.223884 -249.972648)
			(xy 358.170734 -249.976632) (xy 358.117584 -249.972648) (xy 358.065622 -249.960788) (xy 358.016008 -249.941316)
			(xy 357.96985 -249.914667) (xy 357.928179 -249.881436) (xy 357.891927 -249.842365) (xy 357.861903 -249.798328)
			(xy 357.838777 -249.750307) (xy 357.823067 -249.699377) (xy 357.815124 -249.646673) (xy 353.114864 -249.646673)
			(xy 353.114864 -249.916442) (xy 353.115352 -249.930811) (xy 353.123355 -249.958412) (xy 353.138743 -249.982683)
			(xy 353.160292 -250.001696) (xy 353.18629 -250.013941) (xy 353.214673 -250.018445) (xy 353.243185 -250.014849)
			(xy 353.256596 -250.00966) (xy 353.278843 -250.000581) (xy 353.325163 -249.9878) (xy 353.372779 -249.981344)
			(xy 353.396804 -249.980958) (xy 353.422645 -249.98142) (xy 353.473782 -249.988895) (xy 353.523302 -250.003687)
			(xy 353.570161 -250.025484) (xy 353.613376 -250.05383) (xy 353.633024 -250.07062) (xy 353.644402 -250.08001)
			(xy 353.671154 -250.092413) (xy 353.700334 -250.096665) (xy 353.729514 -250.092413) (xy 353.756266 -250.08001)
			(xy 353.767644 -250.07062) (xy 353.787285 -250.053821) (xy 353.830505 -250.025482) (xy 353.877366 -250.003684)
			(xy 353.926885 -249.988887) (xy 353.978023 -249.981399) (xy 354.003864 -249.980958) (xy 354.030519 -249.981429)
			(xy 354.083236 -249.989369) (xy 354.134179 -250.005079) (xy 354.182212 -250.028206) (xy 354.226262 -250.058234)
			(xy 354.265343 -250.094493) (xy 354.298584 -250.136172) (xy 354.32524 -250.182339) (xy 354.344718 -250.231964)
			(xy 354.356582 -250.283938) (xy 354.360566 -250.3371) (xy 365.407134 -250.3371) (xy 365.411118 -250.283941)
			(xy 365.42298 -250.231969) (xy 365.442456 -250.182346) (xy 365.469111 -250.13618) (xy 365.502349 -250.094502)
			(xy 365.541427 -250.058244) (xy 365.585473 -250.028215) (xy 365.633502 -250.005086) (xy 365.684443 -249.989374)
			(xy 365.737156 -249.981431) (xy 365.76381 -249.980958) (xy 365.789745 -249.981429) (xy 365.841066 -249.988946)
			(xy 365.890757 -250.003821) (xy 365.937767 -250.025739) (xy 365.981106 -250.054238) (xy 366.000792 -250.071128)
			(xy 366.012186 -250.080616) (xy 366.039034 -250.093165) (xy 366.068356 -250.097469) (xy 366.097678 -250.093165)
			(xy 366.124526 -250.080616) (xy 366.13592 -250.071128) (xy 366.155578 -250.054199) (xy 366.198908 -250.025671)
			(xy 366.245924 -250.003743) (xy 366.295627 -249.988881) (xy 366.346963 -249.981399) (xy 366.372902 -249.980958)
			(xy 366.399549 -249.981524) (xy 366.452247 -249.989467) (xy 366.503172 -250.005176) (xy 366.551188 -250.028299)
			(xy 366.595221 -250.058321) (xy 366.634287 -250.094569) (xy 366.667515 -250.136236) (xy 366.694161 -250.182389)
			(xy 366.713632 -250.231999) (xy 366.72549 -250.283956) (xy 366.729473 -250.3371) (xy 366.72549 -250.390244)
			(xy 366.713632 -250.442201) (xy 366.694161 -250.491811) (xy 366.667515 -250.537964) (xy 366.634287 -250.579631)
			(xy 366.595221 -250.615879) (xy 366.551188 -250.645901) (xy 366.503172 -250.669024) (xy 366.452247 -250.684733)
			(xy 366.399549 -250.692676) (xy 366.372902 -250.693174) (xy 366.346968 -250.692688) (xy 366.295648 -250.685173)
			(xy 366.245957 -250.670301) (xy 366.198946 -250.648387) (xy 366.155607 -250.619892) (xy 366.13592 -250.603004)
			(xy 366.124526 -250.593516) (xy 366.097678 -250.580967) (xy 366.068356 -250.576663) (xy 366.039034 -250.580967)
			(xy 366.012186 -250.593516) (xy 366.000792 -250.603004) (xy 365.981133 -250.619932) (xy 365.937803 -250.648459)
			(xy 365.890788 -250.670387) (xy 365.841085 -250.685249) (xy 365.789749 -250.692732) (xy 365.76381 -250.693174)
			(xy 365.737156 -250.692769) (xy 365.684443 -250.684826) (xy 365.633502 -250.669114) (xy 365.585473 -250.645985)
			(xy 365.541427 -250.615956) (xy 365.502349 -250.579698) (xy 365.469111 -250.53802) (xy 365.442456 -250.491854)
			(xy 365.42298 -250.442231) (xy 365.411118 -250.390259) (xy 365.407134 -250.3371) (xy 354.360566 -250.3371)
			(xy 354.356582 -250.390262) (xy 354.344718 -250.442236) (xy 354.32524 -250.491861) (xy 354.298584 -250.538028)
			(xy 354.265343 -250.579707) (xy 354.226262 -250.615966) (xy 354.182212 -250.645994) (xy 354.134179 -250.669121)
			(xy 354.083236 -250.684831) (xy 354.030519 -250.692771) (xy 354.003864 -250.693174) (xy 353.978022 -250.692716)
			(xy 353.92688 -250.685249) (xy 353.877357 -250.670463) (xy 353.830493 -250.648668) (xy 353.787275 -250.620324)
			(xy 353.767644 -250.603512) (xy 353.756266 -250.594122) (xy 353.729514 -250.581719) (xy 353.700334 -250.577467)
			(xy 353.671154 -250.581719) (xy 353.644402 -250.594122) (xy 353.633024 -250.603512) (xy 353.613381 -250.620308)
			(xy 353.57016 -250.648641) (xy 353.523298 -250.670432) (xy 353.47378 -250.685224) (xy 353.422644 -250.692706)
			(xy 353.396804 -250.693174) (xy 353.372776 -250.692803) (xy 353.325154 -250.686374) (xy 353.278834 -250.673579)
			(xy 353.256596 -250.664472) (xy 353.243209 -250.659256) (xy 353.214709 -250.655717) (xy 353.186352 -250.660254)
			(xy 353.160379 -250.672508) (xy 353.138847 -250.691511) (xy 353.123459 -250.715758) (xy 353.115431 -250.743331)
			(xy 353.114864 -250.75769) (xy 353.114864 -252.659134) (xy 356.017576 -252.659134) (xy 356.017993 -252.634465)
			(xy 356.024795 -252.585597) (xy 356.038287 -252.538139) (xy 356.05821 -252.493002) (xy 356.084182 -252.451052)
			(xy 356.099618 -252.431804) (xy 356.108213 -252.420652) (xy 356.119567 -252.3949) (xy 356.123454 -252.367026)
			(xy 356.119581 -252.339151) (xy 356.108241 -252.313393) (xy 356.099618 -252.302264) (xy 356.084181 -252.283018)
			(xy 356.058224 -252.241061) (xy 356.038308 -252.195922) (xy 356.024813 -252.148467) (xy 356.017998 -252.099603)
			(xy 356.017576 -252.074934) (xy 356.018074 -252.048285) (xy 356.026017 -251.995581) (xy 356.041727 -251.944651)
			(xy 356.064853 -251.89663) (xy 356.094877 -251.852593) (xy 356.131129 -251.813522) (xy 356.1728 -251.780291)
			(xy 356.218958 -251.753642) (xy 356.268572 -251.73417) (xy 356.320534 -251.72231) (xy 356.373684 -251.718327)
			(xy 356.426834 -251.72231) (xy 356.478796 -251.73417) (xy 356.52841 -251.753642) (xy 356.574568 -251.780291)
			(xy 356.616239 -251.813522) (xy 356.652491 -251.852593) (xy 356.682515 -251.89663) (xy 356.705641 -251.944651)
			(xy 356.721351 -251.995581) (xy 356.729294 -252.048285) (xy 356.729792 -252.074934) (xy 356.729341 -252.099602)
			(xy 356.722545 -252.148468) (xy 356.70906 -252.195925) (xy 356.689145 -252.241063) (xy 356.663182 -252.283014)
			(xy 356.64775 -252.302264) (xy 356.639092 -252.313371) (xy 356.627751 -252.33914) (xy 356.623877 -252.367026)
			(xy 356.627765 -252.394911) (xy 356.63912 -252.420674) (xy 356.64775 -252.431804) (xy 356.663167 -252.451065)
			(xy 356.689128 -252.493018) (xy 356.709049 -252.538152) (xy 356.722548 -252.585605) (xy 356.729368 -252.634466)
			(xy 356.729792 -252.659134) (xy 356.729294 -252.685783) (xy 356.721351 -252.738487) (xy 356.705641 -252.789417)
			(xy 356.697803 -252.805692) (xy 363.017308 -252.805692) (xy 363.017716 -252.781022) (xy 363.024523 -252.732155)
			(xy 363.038018 -252.684697) (xy 363.057942 -252.63956) (xy 363.083914 -252.59761) (xy 363.09935 -252.578362)
			(xy 363.107983 -252.567237) (xy 363.119328 -252.541475) (xy 363.123206 -252.513594) (xy 363.119324 -252.485713)
			(xy 363.107977 -252.459952) (xy 363.09935 -252.448822) (xy 363.083898 -252.429587) (xy 363.057943 -252.387627)
			(xy 363.038029 -252.342486) (xy 363.024537 -252.295028) (xy 363.017727 -252.246161) (xy 363.017308 -252.221492)
			(xy 363.017806 -252.194843) (xy 363.025749 -252.142139) (xy 363.041459 -252.091209) (xy 363.064585 -252.043188)
			(xy 363.094609 -251.999151) (xy 363.130861 -251.96008) (xy 363.172532 -251.926849) (xy 363.21869 -251.9002)
			(xy 363.268304 -251.880728) (xy 363.320266 -251.868868) (xy 363.373416 -251.864885) (xy 363.426566 -251.868868)
			(xy 363.478528 -251.880728) (xy 363.528142 -251.9002) (xy 363.5743 -251.926849) (xy 363.615971 -251.96008)
			(xy 363.652223 -251.999151) (xy 363.682247 -252.043188) (xy 363.705373 -252.091209) (xy 363.721083 -252.142139)
			(xy 363.729026 -252.194843) (xy 363.729524 -252.221492) (xy 363.729122 -252.246162) (xy 363.722316 -252.29503)
			(xy 363.708821 -252.342488) (xy 363.688894 -252.387625) (xy 363.66292 -252.429575) (xy 363.647482 -252.448822)
			(xy 363.638862 -252.459957) (xy 363.627512 -252.485715) (xy 363.623629 -252.513594) (xy 363.627509 -252.541473)
			(xy 363.638855 -252.567233) (xy 363.647482 -252.578362) (xy 363.662931 -252.597599) (xy 363.688886 -252.639558)
			(xy 363.7088 -252.684699) (xy 363.722292 -252.732157) (xy 363.729104 -252.781023) (xy 363.729524 -252.805692)
			(xy 363.729026 -252.832341) (xy 363.721083 -252.885045) (xy 363.705373 -252.935975) (xy 363.682247 -252.983996)
			(xy 363.652223 -253.028033) (xy 363.615971 -253.067104) (xy 363.5743 -253.100335) (xy 363.528142 -253.126984)
			(xy 363.478528 -253.146456) (xy 363.426566 -253.158316) (xy 363.373416 -253.1623) (xy 363.320266 -253.158316)
			(xy 363.268304 -253.146456) (xy 363.21869 -253.126984) (xy 363.172532 -253.100335) (xy 363.130861 -253.067104)
			(xy 363.094609 -253.028033) (xy 363.064585 -252.983996) (xy 363.041459 -252.935975) (xy 363.025749 -252.885045)
			(xy 363.017806 -252.832341) (xy 363.017308 -252.805692) (xy 356.697803 -252.805692) (xy 356.682515 -252.837438)
			(xy 356.652491 -252.881475) (xy 356.616239 -252.920546) (xy 356.574568 -252.953777) (xy 356.52841 -252.980426)
			(xy 356.478796 -252.999898) (xy 356.426834 -253.011758) (xy 356.373684 -253.015742) (xy 356.320534 -253.011758)
			(xy 356.268572 -252.999898) (xy 356.218958 -252.980426) (xy 356.1728 -252.953777) (xy 356.131129 -252.920546)
			(xy 356.094877 -252.881475) (xy 356.064853 -252.837438) (xy 356.041727 -252.789417) (xy 356.026017 -252.738487)
			(xy 356.018074 -252.685783) (xy 356.017576 -252.659134) (xy 353.114864 -252.659134) (xy 353.114864 -253.594362)
			(xy 353.115354 -253.608729) (xy 353.123361 -253.636325) (xy 353.138749 -253.660591) (xy 353.160297 -253.6796)
			(xy 353.186292 -253.691842) (xy 353.214671 -253.696344) (xy 353.243179 -253.692751) (xy 353.256596 -253.68758)
			(xy 353.278843 -253.678501) (xy 353.325163 -253.665719) (xy 353.372779 -253.659263) (xy 353.396804 -253.658878)
			(xy 353.422644 -253.65934) (xy 353.473782 -253.666815) (xy 353.523301 -253.681608) (xy 353.57016 -253.703406)
			(xy 353.613373 -253.731753) (xy 353.633024 -253.74854) (xy 353.644402 -253.75793) (xy 353.671154 -253.770333)
			(xy 353.700334 -253.774585) (xy 353.729514 -253.770333) (xy 353.756266 -253.75793) (xy 353.767644 -253.74854)
			(xy 353.787287 -253.731745) (xy 353.830509 -253.703411) (xy 353.87737 -253.681619) (xy 353.926888 -253.666825)
			(xy 353.978024 -253.659339) (xy 354.003864 -253.658878) (xy 354.030518 -253.659349) (xy 354.083231 -253.667289)
			(xy 354.134172 -253.682998) (xy 354.182202 -253.706123) (xy 354.226249 -253.73615) (xy 354.265328 -253.772407)
			(xy 354.298567 -253.814083) (xy 354.325222 -253.860248) (xy 354.344699 -253.90987) (xy 354.353034 -253.946385)
			(xy 361.214152 -253.946385) (xy 361.214152 -253.893087) (xy 361.222095 -253.840383) (xy 361.237805 -253.789453)
			(xy 361.260931 -253.741432) (xy 361.290955 -253.697395) (xy 361.327207 -253.658324) (xy 361.368878 -253.625093)
			(xy 361.415036 -253.598444) (xy 361.46465 -253.578972) (xy 361.516612 -253.567112) (xy 361.569762 -253.563129)
			(xy 361.622912 -253.567112) (xy 361.674874 -253.578972) (xy 361.724488 -253.598444) (xy 361.770646 -253.625093)
			(xy 361.812317 -253.658324) (xy 361.848569 -253.697395) (xy 361.878593 -253.741432) (xy 361.901719 -253.789453)
			(xy 361.917429 -253.840383) (xy 361.925372 -253.893087) (xy 361.92587 -253.919736) (xy 361.925372 -253.946385)
			(xy 361.917429 -253.999089) (xy 361.912521 -254.015) (xy 365.407154 -254.015) (xy 365.411138 -253.961844)
			(xy 365.422999 -253.909875) (xy 365.442474 -253.860255) (xy 365.469127 -253.814091) (xy 365.502363 -253.772416)
			(xy 365.541439 -253.736159) (xy 365.585483 -253.706132) (xy 365.63351 -253.683005) (xy 365.684447 -253.667294)
			(xy 365.737157 -253.659351) (xy 365.76381 -253.658878) (xy 365.789745 -253.659344) (xy 365.841067 -253.666862)
			(xy 365.890758 -253.681737) (xy 365.937768 -253.703657) (xy 365.981107 -253.732157) (xy 366.000792 -253.749048)
			(xy 366.012186 -253.758536) (xy 366.039034 -253.771085) (xy 366.068356 -253.775389) (xy 366.097678 -253.771085)
			(xy 366.124526 -253.758536) (xy 366.13592 -253.749048) (xy 366.155568 -253.732107) (xy 366.198902 -253.703583)
			(xy 366.24592 -253.681659) (xy 366.295625 -253.666799) (xy 366.346962 -253.659319) (xy 366.372902 -253.658878)
			(xy 366.39955 -253.659404) (xy 366.452251 -253.667347) (xy 366.50318 -253.683057) (xy 366.551198 -253.706182)
			(xy 366.595233 -253.736205) (xy 366.634302 -253.772456) (xy 366.667532 -253.814124) (xy 366.69418 -253.86028)
			(xy 366.713651 -253.909893) (xy 366.725511 -253.961853) (xy 366.729494 -254.015) (xy 366.725511 -254.068147)
			(xy 366.713651 -254.120107) (xy 366.69418 -254.16972) (xy 366.667532 -254.215876) (xy 366.634302 -254.257544)
			(xy 366.595233 -254.293795) (xy 366.551198 -254.323818) (xy 366.50318 -254.346943) (xy 366.452251 -254.362653)
			(xy 366.39955 -254.370596) (xy 366.372902 -254.371094) (xy 366.346968 -254.370603) (xy 366.295648 -254.363088)
			(xy 366.245958 -254.348218) (xy 366.198947 -254.326305) (xy 366.155607 -254.297812) (xy 366.13592 -254.280924)
			(xy 366.124526 -254.271436) (xy 366.097678 -254.258887) (xy 366.068356 -254.254583) (xy 366.039034 -254.258887)
			(xy 366.012186 -254.271436) (xy 366.000792 -254.280924) (xy 365.981136 -254.297855) (xy 365.937805 -254.326381)
			(xy 365.890788 -254.348308) (xy 365.841085 -254.36317) (xy 365.789749 -254.370652) (xy 365.76381 -254.371094)
			(xy 365.737157 -254.370649) (xy 365.684447 -254.362706) (xy 365.63351 -254.346995) (xy 365.585483 -254.323868)
			(xy 365.541439 -254.293841) (xy 365.502363 -254.257584) (xy 365.469127 -254.215909) (xy 365.442474 -254.169745)
			(xy 365.422999 -254.120125) (xy 365.411138 -254.068156) (xy 365.407154 -254.015) (xy 361.912521 -254.015)
			(xy 361.901719 -254.050019) (xy 361.878593 -254.09804) (xy 361.848569 -254.142077) (xy 361.812317 -254.181148)
			(xy 361.770646 -254.214379) (xy 361.724488 -254.241028) (xy 361.674874 -254.2605) (xy 361.622912 -254.27236)
			(xy 361.569762 -254.276344) (xy 361.516612 -254.27236) (xy 361.46465 -254.2605) (xy 361.415036 -254.241028)
			(xy 361.368878 -254.214379) (xy 361.327207 -254.181148) (xy 361.290955 -254.142077) (xy 361.260931 -254.09804)
			(xy 361.237805 -254.050019) (xy 361.222095 -253.999089) (xy 361.214152 -253.946385) (xy 354.353034 -253.946385)
			(xy 354.356562 -253.961841) (xy 354.360546 -254.015) (xy 354.356562 -254.068159) (xy 354.344699 -254.12013)
			(xy 354.325222 -254.169752) (xy 354.298567 -254.215917) (xy 354.265328 -254.257593) (xy 354.226249 -254.29385)
			(xy 354.182202 -254.323877) (xy 354.134172 -254.347002) (xy 354.083231 -254.362711) (xy 354.030518 -254.370651)
			(xy 354.003864 -254.371094) (xy 353.978022 -254.370636) (xy 353.92688 -254.36317) (xy 353.877356 -254.348384)
			(xy 353.830492 -254.32659) (xy 353.787272 -254.298247) (xy 353.767644 -254.281432) (xy 353.756266 -254.272042)
			(xy 353.729514 -254.259639) (xy 353.700334 -254.255387) (xy 353.671154 -254.259639) (xy 353.644402 -254.272042)
			(xy 353.633024 -254.281432) (xy 353.613381 -254.298227) (xy 353.570159 -254.326559) (xy 353.523297 -254.348348)
			(xy 353.473779 -254.363139) (xy 353.422644 -254.370621) (xy 353.396804 -254.371094) (xy 353.372776 -254.370723)
			(xy 353.325153 -254.364295) (xy 353.278833 -254.351501) (xy 353.256596 -254.342392) (xy 353.243209 -254.337176)
			(xy 353.214712 -254.333635) (xy 353.186355 -254.338172) (xy 353.160385 -254.350427) (xy 353.138855 -254.369431)
			(xy 353.12347 -254.393679) (xy 353.115447 -254.421252) (xy 353.114864 -254.43561) (xy 353.114864 -254.760201)
			(xy 357.924852 -254.760201) (xy 357.924852 -254.706903) (xy 357.932795 -254.654199) (xy 357.948505 -254.603269)
			(xy 357.971631 -254.555248) (xy 358.001655 -254.511211) (xy 358.037907 -254.47214) (xy 358.079578 -254.438909)
			(xy 358.125736 -254.41226) (xy 358.17535 -254.392788) (xy 358.227312 -254.380928) (xy 358.280462 -254.376945)
			(xy 358.333612 -254.380928) (xy 358.385574 -254.392788) (xy 358.435188 -254.41226) (xy 358.481346 -254.438909)
			(xy 358.523017 -254.47214) (xy 358.559269 -254.511211) (xy 358.589293 -254.555248) (xy 358.612419 -254.603269)
			(xy 358.628129 -254.654199) (xy 358.636072 -254.706903) (xy 358.63657 -254.733552) (xy 358.636072 -254.760201)
			(xy 358.628129 -254.812905) (xy 358.612419 -254.863835) (xy 358.589293 -254.911856) (xy 358.559269 -254.955893)
			(xy 358.523017 -254.994964) (xy 358.481346 -255.028195) (xy 358.435188 -255.054844) (xy 358.385574 -255.074316)
			(xy 358.333612 -255.086176) (xy 358.280462 -255.09016) (xy 358.227312 -255.086176) (xy 358.17535 -255.074316)
			(xy 358.125736 -255.054844) (xy 358.079578 -255.028195) (xy 358.037907 -254.994964) (xy 358.001655 -254.955893)
			(xy 357.971631 -254.911856) (xy 357.948505 -254.863835) (xy 357.932795 -254.812905) (xy 357.924852 -254.760201)
			(xy 353.114864 -254.760201) (xy 353.114864 -255.517904) (xy 353.364292 -255.767332) (xy 353.364292 -256.330196)
			(xy 356.017576 -256.330196) (xy 356.017971 -256.305526) (xy 356.024779 -256.256657) (xy 356.038276 -256.209199)
			(xy 356.058204 -256.164062) (xy 356.08418 -256.122113) (xy 356.099618 -256.102866) (xy 356.10825 -256.091739)
			(xy 356.119598 -256.065978) (xy 356.123479 -256.038097) (xy 356.119596 -256.010216) (xy 356.108246 -255.984455)
			(xy 356.099618 -255.973326) (xy 356.084163 -255.954094) (xy 356.058209 -255.912133) (xy 356.038296 -255.866991)
			(xy 356.024806 -255.819532) (xy 356.017995 -255.770665) (xy 356.017576 -255.745996) (xy 356.018074 -255.719347)
			(xy 356.026017 -255.666643) (xy 356.041727 -255.615713) (xy 356.064853 -255.567692) (xy 356.094877 -255.523655)
			(xy 356.131129 -255.484584) (xy 356.1728 -255.451353) (xy 356.218958 -255.424704) (xy 356.268572 -255.405232)
			(xy 356.320534 -255.393372) (xy 356.373684 -255.389389) (xy 356.426834 -255.393372) (xy 356.478796 -255.405232)
			(xy 356.52841 -255.424704) (xy 356.574568 -255.451353) (xy 356.616239 -255.484584) (xy 356.652491 -255.523655)
			(xy 356.682515 -255.567692) (xy 356.685683 -255.574271) (xy 361.214152 -255.574271) (xy 361.214152 -255.520973)
			(xy 361.222095 -255.468269) (xy 361.237805 -255.417339) (xy 361.260931 -255.369318) (xy 361.290955 -255.325281)
			(xy 361.327207 -255.28621) (xy 361.368878 -255.252979) (xy 361.415036 -255.22633) (xy 361.46465 -255.206858)
			(xy 361.516612 -255.194998) (xy 361.569762 -255.191015) (xy 361.622912 -255.194998) (xy 361.674874 -255.206858)
			(xy 361.724488 -255.22633) (xy 361.770646 -255.252979) (xy 361.812317 -255.28621) (xy 361.848569 -255.325281)
			(xy 361.878593 -255.369318) (xy 361.901719 -255.417339) (xy 361.917429 -255.468269) (xy 361.925372 -255.520973)
			(xy 361.92587 -255.547622) (xy 361.925372 -255.574271) (xy 361.917429 -255.626975) (xy 361.901719 -255.677905)
			(xy 361.878593 -255.725926) (xy 361.848569 -255.769963) (xy 361.812317 -255.809034) (xy 361.770646 -255.842265)
			(xy 361.724488 -255.868914) (xy 361.674874 -255.888386) (xy 361.622912 -255.900246) (xy 361.569762 -255.90423)
			(xy 361.516612 -255.900246) (xy 361.46465 -255.888386) (xy 361.415036 -255.868914) (xy 361.368878 -255.842265)
			(xy 361.327207 -255.809034) (xy 361.290955 -255.769963) (xy 361.260931 -255.725926) (xy 361.237805 -255.677905)
			(xy 361.222095 -255.626975) (xy 361.214152 -255.574271) (xy 356.685683 -255.574271) (xy 356.705641 -255.615713)
			(xy 356.721351 -255.666643) (xy 356.729294 -255.719347) (xy 356.729792 -255.745996) (xy 356.729377 -255.770665)
			(xy 356.722572 -255.819532) (xy 356.709079 -255.86699) (xy 356.689156 -255.912127) (xy 356.663186 -255.954078)
			(xy 356.64775 -255.973326) (xy 356.639128 -255.984459) (xy 356.627782 -256.010218) (xy 356.623901 -256.038097)
			(xy 356.627781 -256.065976) (xy 356.639125 -256.091736) (xy 356.64775 -256.102866) (xy 356.663196 -256.122105)
			(xy 356.689152 -256.164064) (xy 356.709068 -256.209204) (xy 356.72256 -256.256661) (xy 356.729372 -256.305527)
			(xy 356.729792 -256.330196) (xy 356.729294 -256.356845) (xy 356.724586 -256.388087) (xy 357.924852 -256.388087)
			(xy 357.924852 -256.334789) (xy 357.932795 -256.282085) (xy 357.948505 -256.231155) (xy 357.971631 -256.183134)
			(xy 358.001655 -256.139097) (xy 358.037907 -256.100026) (xy 358.079578 -256.066795) (xy 358.125736 -256.040146)
			(xy 358.17535 -256.020674) (xy 358.227312 -256.008814) (xy 358.280462 -256.004831) (xy 358.333612 -256.008814)
			(xy 358.385574 -256.020674) (xy 358.435188 -256.040146) (xy 358.481346 -256.066795) (xy 358.523017 -256.100026)
			(xy 358.559269 -256.139097) (xy 358.589293 -256.183134) (xy 358.612419 -256.231155) (xy 358.628129 -256.282085)
			(xy 358.636072 -256.334789) (xy 358.63657 -256.361438) (xy 358.636072 -256.388087) (xy 358.635839 -256.389632)
			(xy 363.012228 -256.389632) (xy 363.012655 -256.364963) (xy 363.019456 -256.316096) (xy 363.032947 -256.268639)
			(xy 363.052867 -256.223501) (xy 363.078836 -256.181551) (xy 363.09427 -256.162302) (xy 363.102863 -256.151149)
			(xy 363.11421 -256.125397) (xy 363.118096 -256.097525) (xy 363.114224 -256.069651) (xy 363.10289 -256.043893)
			(xy 363.09427 -256.032762) (xy 363.07884 -256.01351) (xy 363.052881 -255.971556) (xy 363.032962 -255.926419)
			(xy 363.019466 -255.878964) (xy 363.01265 -255.8301) (xy 363.012228 -255.805432) (xy 363.012726 -255.778783)
			(xy 363.020669 -255.726079) (xy 363.036379 -255.675149) (xy 363.059505 -255.627128) (xy 363.089529 -255.583091)
			(xy 363.125781 -255.54402) (xy 363.167452 -255.510789) (xy 363.21361 -255.48414) (xy 363.263224 -255.464668)
			(xy 363.315186 -255.452808) (xy 363.368336 -255.448825) (xy 363.421486 -255.452808) (xy 363.473448 -255.464668)
			(xy 363.523062 -255.48414) (xy 363.56922 -255.510789) (xy 363.610891 -255.54402) (xy 363.647143 -255.583091)
			(xy 363.677167 -255.627128) (xy 363.700293 -255.675149) (xy 363.716003 -255.726079) (xy 363.723946 -255.778783)
			(xy 363.724444 -255.805432) (xy 363.724061 -255.830103) (xy 363.71725 -255.878971) (xy 363.70375 -255.92643)
			(xy 363.683819 -255.971567) (xy 363.657841 -256.013515) (xy 363.642402 -256.032762) (xy 363.633742 -256.043869)
			(xy 363.622395 -256.069637) (xy 363.618519 -256.097525) (xy 363.622409 -256.125411) (xy 363.633768 -256.151173)
			(xy 363.642402 -256.162302) (xy 363.657811 -256.18157) (xy 363.683774 -256.22352) (xy 363.703698 -256.268653)
			(xy 363.717199 -256.316104) (xy 363.724019 -256.364965) (xy 363.724444 -256.389632) (xy 363.723946 -256.416281)
			(xy 363.716003 -256.468985) (xy 363.700293 -256.519915) (xy 363.677167 -256.567936) (xy 363.647143 -256.611973)
			(xy 363.610891 -256.651044) (xy 363.56922 -256.684275) (xy 363.523062 -256.710924) (xy 363.473448 -256.730396)
			(xy 363.421486 -256.742256) (xy 363.368336 -256.74624) (xy 363.315186 -256.742256) (xy 363.263224 -256.730396)
			(xy 363.21361 -256.710924) (xy 363.167452 -256.684275) (xy 363.125781 -256.651044) (xy 363.089529 -256.611973)
			(xy 363.059505 -256.567936) (xy 363.036379 -256.519915) (xy 363.020669 -256.468985) (xy 363.012726 -256.416281)
			(xy 363.012228 -256.389632) (xy 358.635839 -256.389632) (xy 358.628129 -256.440791) (xy 358.612419 -256.491721)
			(xy 358.589293 -256.539742) (xy 358.559269 -256.583779) (xy 358.523017 -256.62285) (xy 358.481346 -256.656081)
			(xy 358.435188 -256.68273) (xy 358.385574 -256.702202) (xy 358.333612 -256.714062) (xy 358.280462 -256.718046)
			(xy 358.227312 -256.714062) (xy 358.17535 -256.702202) (xy 358.125736 -256.68273) (xy 358.079578 -256.656081)
			(xy 358.037907 -256.62285) (xy 358.001655 -256.583779) (xy 357.971631 -256.539742) (xy 357.948505 -256.491721)
			(xy 357.932795 -256.440791) (xy 357.924852 -256.388087) (xy 356.724586 -256.388087) (xy 356.721351 -256.409549)
			(xy 356.705641 -256.460479) (xy 356.682515 -256.5085) (xy 356.652491 -256.552537) (xy 356.616239 -256.591608)
			(xy 356.574568 -256.624839) (xy 356.52841 -256.651488) (xy 356.478796 -256.67096) (xy 356.426834 -256.68282)
			(xy 356.373684 -256.686804) (xy 356.320534 -256.68282) (xy 356.268572 -256.67096) (xy 356.218958 -256.651488)
			(xy 356.1728 -256.624839) (xy 356.131129 -256.591608) (xy 356.094877 -256.552537) (xy 356.064853 -256.5085)
			(xy 356.041727 -256.460479) (xy 356.026017 -256.409549) (xy 356.018074 -256.356845) (xy 356.017576 -256.330196)
			(xy 353.364292 -256.330196) (xy 353.364292 -257.201903) (xy 361.214152 -257.201903) (xy 361.214152 -257.148605)
			(xy 361.222095 -257.095901) (xy 361.237805 -257.044971) (xy 361.260931 -256.99695) (xy 361.290955 -256.952913)
			(xy 361.327207 -256.913842) (xy 361.368878 -256.880611) (xy 361.415036 -256.853962) (xy 361.46465 -256.83449)
			(xy 361.516612 -256.82263) (xy 361.569762 -256.818647) (xy 361.622912 -256.82263) (xy 361.674874 -256.83449)
			(xy 361.724488 -256.853962) (xy 361.770646 -256.880611) (xy 361.812317 -256.913842) (xy 361.848569 -256.952913)
			(xy 361.878593 -256.99695) (xy 361.901719 -257.044971) (xy 361.917429 -257.095901) (xy 361.925372 -257.148605)
			(xy 361.92587 -257.175254) (xy 361.925372 -257.201903) (xy 361.917429 -257.254607) (xy 361.901719 -257.305537)
			(xy 361.878593 -257.353558) (xy 361.848569 -257.397595) (xy 361.812317 -257.436666) (xy 361.770646 -257.469897)
			(xy 361.724488 -257.496546) (xy 361.674874 -257.516018) (xy 361.622912 -257.527878) (xy 361.569762 -257.531862)
			(xy 361.516612 -257.527878) (xy 361.46465 -257.516018) (xy 361.415036 -257.496546) (xy 361.368878 -257.469897)
			(xy 361.327207 -257.436666) (xy 361.290955 -257.397595) (xy 361.260931 -257.353558) (xy 361.237805 -257.305537)
			(xy 361.222095 -257.254607) (xy 361.214152 -257.201903) (xy 353.364292 -257.201903) (xy 353.364292 -257.286506)
			(xy 353.364774 -257.296198) (xy 353.372064 -257.314164) (xy 353.38549 -257.328153) (xy 353.403142 -257.336173)
			(xy 353.412806 -257.337052) (xy 353.437003 -257.338568) (xy 353.484686 -257.347331) (xy 353.530742 -257.362476)
			(xy 353.57432 -257.383724) (xy 353.614615 -257.410684) (xy 353.633024 -257.42646) (xy 353.644402 -257.43585)
			(xy 353.671154 -257.448253) (xy 353.700334 -257.452505) (xy 353.729514 -257.448253) (xy 353.756266 -257.43585)
			(xy 353.767644 -257.42646) (xy 353.787287 -257.409664) (xy 353.830508 -257.381329) (xy 353.877369 -257.359535)
			(xy 353.926887 -257.34474) (xy 353.978024 -257.337254) (xy 354.003864 -257.336798) (xy 354.030516 -257.337269)
			(xy 354.083227 -257.345208) (xy 354.134165 -257.360916) (xy 354.182192 -257.384041) (xy 354.226237 -257.414066)
			(xy 354.265314 -257.45032) (xy 354.29855 -257.491994) (xy 354.325204 -257.538156) (xy 354.34468 -257.587776)
			(xy 354.356542 -257.639744) (xy 354.360526 -257.6929) (xy 354.356542 -257.746056) (xy 354.34468 -257.798024)
			(xy 354.325204 -257.847644) (xy 354.29855 -257.893806) (xy 354.265314 -257.93548) (xy 354.226237 -257.971734)
			(xy 354.182192 -258.001759) (xy 354.153199 -258.015719) (xy 357.924852 -258.015719) (xy 357.924852 -257.962421)
			(xy 357.932795 -257.909717) (xy 357.948505 -257.858787) (xy 357.971631 -257.810766) (xy 358.001655 -257.766729)
			(xy 358.037907 -257.727658) (xy 358.079578 -257.694427) (xy 358.125736 -257.667778) (xy 358.17535 -257.648306)
			(xy 358.227312 -257.636446) (xy 358.280462 -257.632463) (xy 358.333612 -257.636446) (xy 358.385574 -257.648306)
			(xy 358.435188 -257.667778) (xy 358.478701 -257.6929) (xy 365.407174 -257.6929) (xy 365.411157 -257.639747)
			(xy 365.423018 -257.587781) (xy 365.442492 -257.538163) (xy 365.469144 -257.492002) (xy 365.502378 -257.450329)
			(xy 365.541452 -257.414075) (xy 365.585493 -257.384049) (xy 365.633517 -257.360923) (xy 365.684452 -257.345213)
			(xy 365.737159 -257.33727) (xy 365.76381 -257.336798) (xy 365.789744 -257.337284) (xy 365.841064 -257.3448)
			(xy 365.890754 -257.359672) (xy 365.937765 -257.381586) (xy 365.981105 -257.41008) (xy 366.000792 -257.426968)
			(xy 366.012186 -257.436456) (xy 366.039034 -257.449005) (xy 366.068356 -257.453309) (xy 366.097678 -257.449005)
			(xy 366.124526 -257.436456) (xy 366.13592 -257.426968) (xy 366.15557 -257.41003) (xy 366.198903 -257.381505)
			(xy 366.245921 -257.35958) (xy 366.295626 -257.34472) (xy 366.346962 -257.337239) (xy 366.372902 -257.336798)
			(xy 366.399552 -257.337284) (xy 366.452256 -257.345228) (xy 366.503187 -257.360938) (xy 366.551208 -257.384064)
			(xy 366.595246 -257.414089) (xy 366.634317 -257.450342) (xy 366.667548 -257.492013) (xy 366.694198 -257.538172)
			(xy 366.71367 -257.587787) (xy 366.72553 -257.63975) (xy 366.729514 -257.6929) (xy 366.72553 -257.74605)
			(xy 366.71367 -257.798013) (xy 366.694198 -257.847628) (xy 366.667548 -257.893787) (xy 366.634317 -257.935458)
			(xy 366.595246 -257.971711) (xy 366.551208 -258.001736) (xy 366.503187 -258.024862) (xy 366.452256 -258.040572)
			(xy 366.399552 -258.048516) (xy 366.372902 -258.049014) (xy 366.346969 -258.048518) (xy 366.295649 -258.041004)
			(xy 366.245959 -258.026134) (xy 366.198948 -258.004222) (xy 366.155608 -257.975731) (xy 366.13592 -257.958844)
			(xy 366.124526 -257.949356) (xy 366.097678 -257.936807) (xy 366.068356 -257.932503) (xy 366.039034 -257.936807)
			(xy 366.012186 -257.949356) (xy 366.000792 -257.958844) (xy 365.981139 -257.975778) (xy 365.937806 -258.004303)
			(xy 365.890789 -258.026229) (xy 365.841085 -258.04109) (xy 365.78975 -258.048572) (xy 365.76381 -258.049014)
			(xy 365.737159 -258.04853) (xy 365.684452 -258.040587) (xy 365.633517 -258.024877) (xy 365.585493 -258.001751)
			(xy 365.541452 -257.971725) (xy 365.502378 -257.935471) (xy 365.469144 -257.893798) (xy 365.442492 -257.847637)
			(xy 365.423018 -257.798019) (xy 365.411157 -257.746053) (xy 365.407174 -257.6929) (xy 358.478701 -257.6929)
			(xy 358.481346 -257.694427) (xy 358.523017 -257.727658) (xy 358.559269 -257.766729) (xy 358.589293 -257.810766)
			(xy 358.612419 -257.858787) (xy 358.628129 -257.909717) (xy 358.636072 -257.962421) (xy 358.63657 -257.98907)
			(xy 358.636072 -258.015719) (xy 358.628129 -258.068423) (xy 358.612419 -258.119353) (xy 358.589293 -258.167374)
			(xy 358.559269 -258.211411) (xy 358.523017 -258.250482) (xy 358.481346 -258.283713) (xy 358.435188 -258.310362)
			(xy 358.385574 -258.329834) (xy 358.333612 -258.341694) (xy 358.280462 -258.345678) (xy 358.227312 -258.341694)
			(xy 358.17535 -258.329834) (xy 358.125736 -258.310362) (xy 358.079578 -258.283713) (xy 358.037907 -258.250482)
			(xy 358.001655 -258.211411) (xy 357.971631 -258.167374) (xy 357.948505 -258.119353) (xy 357.932795 -258.068423)
			(xy 357.924852 -258.015719) (xy 354.153199 -258.015719) (xy 354.134165 -258.024884) (xy 354.083227 -258.040592)
			(xy 354.030516 -258.048531) (xy 354.003864 -258.049014) (xy 353.978022 -258.048556) (xy 353.92688 -258.04109)
			(xy 353.877355 -258.026305) (xy 353.83049 -258.004512) (xy 353.78727 -257.97617) (xy 353.767644 -257.959352)
			(xy 353.756266 -257.949962) (xy 353.729514 -257.937559) (xy 353.700334 -257.933307) (xy 353.671154 -257.937559)
			(xy 353.644402 -257.949962) (xy 353.633024 -257.959352) (xy 353.614622 -257.975138) (xy 353.57433 -258.002103)
			(xy 353.530751 -258.023351) (xy 353.484691 -258.038488) (xy 353.437003 -258.047234) (xy 353.412806 -258.04876)
			(xy 353.403124 -258.049609) (xy 353.385427 -258.057601) (xy 353.371969 -258.071599) (xy 353.36468 -258.089598)
			(xy 353.364292 -258.099306) (xy 353.364292 -259.578348) (xy 356.017576 -259.578348) (xy 356.018001 -259.553679)
			(xy 356.024801 -259.504812) (xy 356.038291 -259.457354) (xy 356.058213 -259.412216) (xy 356.084183 -259.370266)
			(xy 356.099618 -259.351018) (xy 356.1082 -259.339856) (xy 356.119555 -259.314108) (xy 356.123445 -259.286237)
			(xy 356.119575 -259.258364) (xy 356.108239 -259.232607) (xy 356.099618 -259.221478) (xy 356.084188 -259.202227)
			(xy 356.05823 -259.160271) (xy 356.038312 -259.115134) (xy 356.024816 -259.067679) (xy 356.017999 -259.018816)
			(xy 356.017576 -258.994148) (xy 356.018074 -258.967499) (xy 356.026017 -258.914795) (xy 356.041727 -258.863865)
			(xy 356.064853 -258.815844) (xy 356.094877 -258.771807) (xy 356.131129 -258.732736) (xy 356.1728 -258.699505)
			(xy 356.218958 -258.672856) (xy 356.268572 -258.653384) (xy 356.320534 -258.641524) (xy 356.373684 -258.637541)
			(xy 356.426834 -258.641524) (xy 356.478796 -258.653384) (xy 356.52841 -258.672856) (xy 356.574568 -258.699505)
			(xy 356.616239 -258.732736) (xy 356.652491 -258.771807) (xy 356.682515 -258.815844) (xy 356.689231 -258.829789)
			(xy 361.214152 -258.829789) (xy 361.214152 -258.776491) (xy 361.222095 -258.723787) (xy 361.237805 -258.672857)
			(xy 361.260931 -258.624836) (xy 361.290955 -258.580799) (xy 361.327207 -258.541728) (xy 361.368878 -258.508497)
			(xy 361.415036 -258.481848) (xy 361.46465 -258.462376) (xy 361.516612 -258.450516) (xy 361.569762 -258.446533)
			(xy 361.622912 -258.450516) (xy 361.674874 -258.462376) (xy 361.724488 -258.481848) (xy 361.770646 -258.508497)
			(xy 361.812317 -258.541728) (xy 361.848569 -258.580799) (xy 361.878593 -258.624836) (xy 361.901719 -258.672857)
			(xy 361.917429 -258.723787) (xy 361.925372 -258.776491) (xy 361.92587 -258.80314) (xy 361.925372 -258.829789)
			(xy 361.917429 -258.882493) (xy 361.901719 -258.933423) (xy 361.878593 -258.981444) (xy 361.848569 -259.025481)
			(xy 361.812317 -259.064552) (xy 361.770646 -259.097783) (xy 361.724488 -259.124432) (xy 361.674874 -259.143904)
			(xy 361.622912 -259.155764) (xy 361.569762 -259.159748) (xy 361.516612 -259.155764) (xy 361.46465 -259.143904)
			(xy 361.415036 -259.124432) (xy 361.368878 -259.097783) (xy 361.327207 -259.064552) (xy 361.290955 -259.025481)
			(xy 361.260931 -258.981444) (xy 361.237805 -258.933423) (xy 361.222095 -258.882493) (xy 361.214152 -258.829789)
			(xy 356.689231 -258.829789) (xy 356.705641 -258.863865) (xy 356.721351 -258.914795) (xy 356.729294 -258.967499)
			(xy 356.729792 -258.994148) (xy 356.729349 -259.018816) (xy 356.722551 -259.067682) (xy 356.709064 -259.11514)
			(xy 356.689147 -259.160277) (xy 356.663183 -259.202229) (xy 356.64775 -259.221478) (xy 356.639079 -259.232576)
			(xy 356.627739 -259.258348) (xy 356.623868 -259.286237) (xy 356.62776 -259.314124) (xy 356.639118 -259.339888)
			(xy 356.64775 -259.351018) (xy 356.663174 -259.370274) (xy 356.689134 -259.412228) (xy 356.709053 -259.457364)
			(xy 356.722551 -259.504817) (xy 356.729369 -259.55368) (xy 356.729792 -259.578348) (xy 356.729294 -259.604997)
			(xy 356.723475 -259.643605) (xy 357.924852 -259.643605) (xy 357.924852 -259.590307) (xy 357.932795 -259.537603)
			(xy 357.948505 -259.486673) (xy 357.971631 -259.438652) (xy 358.001655 -259.394615) (xy 358.037907 -259.355544)
			(xy 358.079578 -259.322313) (xy 358.125736 -259.295664) (xy 358.17535 -259.276192) (xy 358.227312 -259.264332)
			(xy 358.280462 -259.260349) (xy 358.333612 -259.264332) (xy 358.385574 -259.276192) (xy 358.435188 -259.295664)
			(xy 358.481346 -259.322313) (xy 358.523017 -259.355544) (xy 358.559269 -259.394615) (xy 358.589293 -259.438652)
			(xy 358.612419 -259.486673) (xy 358.628129 -259.537603) (xy 358.636072 -259.590307) (xy 358.63657 -259.616956)
			(xy 358.636233 -259.63499) (xy 363.009942 -259.63499) (xy 363.010341 -259.61032) (xy 363.017149 -259.561452)
			(xy 363.030645 -259.513994) (xy 363.050572 -259.468857) (xy 363.076546 -259.426907) (xy 363.091984 -259.40766)
			(xy 363.100624 -259.396538) (xy 363.111975 -259.370776) (xy 363.115856 -259.342892) (xy 363.111971 -259.315009)
			(xy 363.100616 -259.289248) (xy 363.091984 -259.27812) (xy 363.076583 -259.258846) (xy 363.050619 -259.216898)
			(xy 363.030694 -259.171766) (xy 363.017191 -259.124316) (xy 363.010368 -259.075457) (xy 363.009942 -259.05079)
			(xy 363.01044 -259.024141) (xy 363.018383 -258.971437) (xy 363.034093 -258.920507) (xy 363.057219 -258.872486)
			(xy 363.087243 -258.828449) (xy 363.123495 -258.789378) (xy 363.165166 -258.756147) (xy 363.211324 -258.729498)
			(xy 363.260938 -258.710026) (xy 363.3129 -258.698166) (xy 363.36605 -258.694183) (xy 363.4192 -258.698166)
			(xy 363.471162 -258.710026) (xy 363.520776 -258.729498) (xy 363.566934 -258.756147) (xy 363.608605 -258.789378)
			(xy 363.644857 -258.828449) (xy 363.674881 -258.872486) (xy 363.698007 -258.920507) (xy 363.713717 -258.971437)
			(xy 363.72166 -259.024141) (xy 363.722158 -259.05079) (xy 363.721747 -259.07546) (xy 363.714942 -259.124327)
			(xy 363.701448 -259.171785) (xy 363.681524 -259.216922) (xy 363.655552 -259.258872) (xy 363.640116 -259.27812)
			(xy 363.631495 -259.289255) (xy 363.620141 -259.315013) (xy 363.616257 -259.342892) (xy 363.620137 -259.370772)
			(xy 363.631487 -259.396532) (xy 363.640116 -259.40766) (xy 363.655554 -259.426905) (xy 363.681512 -259.468862)
			(xy 363.70143 -259.514) (xy 363.714924 -259.561456) (xy 363.721737 -259.610321) (xy 363.722158 -259.63499)
			(xy 363.72166 -259.661639) (xy 363.713717 -259.714343) (xy 363.698007 -259.765273) (xy 363.674881 -259.813294)
			(xy 363.644857 -259.857331) (xy 363.608605 -259.896402) (xy 363.566934 -259.929633) (xy 363.520776 -259.956282)
			(xy 363.471162 -259.975754) (xy 363.4192 -259.987614) (xy 363.36605 -259.991598) (xy 363.3129 -259.987614)
			(xy 363.260938 -259.975754) (xy 363.211324 -259.956282) (xy 363.165166 -259.929633) (xy 363.123495 -259.896402)
			(xy 363.087243 -259.857331) (xy 363.057219 -259.813294) (xy 363.034093 -259.765273) (xy 363.018383 -259.714343)
			(xy 363.01044 -259.661639) (xy 363.009942 -259.63499) (xy 358.636233 -259.63499) (xy 358.636072 -259.643605)
			(xy 358.628129 -259.696309) (xy 358.612419 -259.747239) (xy 358.589293 -259.79526) (xy 358.559269 -259.839297)
			(xy 358.523017 -259.878368) (xy 358.481346 -259.911599) (xy 358.435188 -259.938248) (xy 358.385574 -259.95772)
			(xy 358.333612 -259.96958) (xy 358.280462 -259.973564) (xy 358.227312 -259.96958) (xy 358.17535 -259.95772)
			(xy 358.125736 -259.938248) (xy 358.079578 -259.911599) (xy 358.037907 -259.878368) (xy 358.001655 -259.839297)
			(xy 357.971631 -259.79526) (xy 357.948505 -259.747239) (xy 357.932795 -259.696309) (xy 357.924852 -259.643605)
			(xy 356.723475 -259.643605) (xy 356.721351 -259.657701) (xy 356.705641 -259.708631) (xy 356.682515 -259.756652)
			(xy 356.652491 -259.800689) (xy 356.616239 -259.83976) (xy 356.574568 -259.872991) (xy 356.52841 -259.89964)
			(xy 356.478796 -259.919112) (xy 356.426834 -259.930972) (xy 356.373684 -259.934956) (xy 356.320534 -259.930972)
			(xy 356.268572 -259.919112) (xy 356.218958 -259.89964) (xy 356.1728 -259.872991) (xy 356.131129 -259.83976)
			(xy 356.094877 -259.800689) (xy 356.064853 -259.756652) (xy 356.041727 -259.708631) (xy 356.026017 -259.657701)
			(xy 356.018074 -259.604997) (xy 356.017576 -259.578348) (xy 353.364292 -259.578348) (xy 353.364292 -259.599938)
			(xy 353.647502 -259.883148) (xy 354.81768 -259.883148) (xy 355.391953 -260.457421) (xy 361.214152 -260.457421)
			(xy 361.214152 -260.404123) (xy 361.222095 -260.351419) (xy 361.237805 -260.300489) (xy 361.260931 -260.252468)
			(xy 361.290955 -260.208431) (xy 361.327207 -260.16936) (xy 361.368878 -260.136129) (xy 361.415036 -260.10948)
			(xy 361.46465 -260.090008) (xy 361.516612 -260.078148) (xy 361.569762 -260.074165) (xy 361.622912 -260.078148)
			(xy 361.674874 -260.090008) (xy 361.724488 -260.10948) (xy 361.770646 -260.136129) (xy 361.812317 -260.16936)
			(xy 361.848569 -260.208431) (xy 361.878593 -260.252468) (xy 361.901719 -260.300489) (xy 361.917429 -260.351419)
			(xy 361.925372 -260.404123) (xy 361.92587 -260.430772) (xy 361.925372 -260.457421) (xy 361.917429 -260.510125)
			(xy 361.901719 -260.561055) (xy 361.878593 -260.609076) (xy 361.848569 -260.653113) (xy 361.812317 -260.692184)
			(xy 361.770646 -260.725415) (xy 361.724488 -260.752064) (xy 361.674874 -260.771536) (xy 361.622912 -260.783396)
			(xy 361.569762 -260.78738) (xy 361.516612 -260.783396) (xy 361.46465 -260.771536) (xy 361.415036 -260.752064)
			(xy 361.368878 -260.725415) (xy 361.327207 -260.692184) (xy 361.290955 -260.653113) (xy 361.260931 -260.609076)
			(xy 361.237805 -260.561055) (xy 361.222095 -260.510125) (xy 361.214152 -260.457421) (xy 355.391953 -260.457421)
			(xy 355.73208 -260.797548) (xy 355.73208 -261.271491) (xy 357.924852 -261.271491) (xy 357.924852 -261.218193)
			(xy 357.932795 -261.165489) (xy 357.948505 -261.114559) (xy 357.971631 -261.066538) (xy 358.001655 -261.022501)
			(xy 358.037907 -260.98343) (xy 358.079578 -260.950199) (xy 358.125736 -260.92355) (xy 358.17535 -260.904078)
			(xy 358.227312 -260.892218) (xy 358.280462 -260.888235) (xy 358.333612 -260.892218) (xy 358.385574 -260.904078)
			(xy 358.435188 -260.92355) (xy 358.481346 -260.950199) (xy 358.523017 -260.98343) (xy 358.559269 -261.022501)
			(xy 358.589293 -261.066538) (xy 358.612419 -261.114559) (xy 358.628129 -261.165489) (xy 358.636072 -261.218193)
			(xy 358.63657 -261.244842) (xy 358.636072 -261.271491) (xy 358.628129 -261.324195) (xy 358.612419 -261.375125)
			(xy 358.589293 -261.423146) (xy 358.559269 -261.467183) (xy 358.523017 -261.506254) (xy 358.481346 -261.539485)
			(xy 358.435188 -261.566134) (xy 358.385574 -261.585606) (xy 358.333612 -261.597466) (xy 358.280462 -261.60145)
			(xy 358.227312 -261.597466) (xy 358.17535 -261.585606) (xy 358.125736 -261.566134) (xy 358.079578 -261.539485)
			(xy 358.037907 -261.506254) (xy 358.001655 -261.467183) (xy 357.971631 -261.423146) (xy 357.948505 -261.375125)
			(xy 357.932795 -261.324195) (xy 357.924852 -261.271491) (xy 355.73208 -261.271491) (xy 355.73208 -261.661148)
			(xy 355.307921 -262.085307) (xy 361.214152 -262.085307) (xy 361.214152 -262.032009) (xy 361.222095 -261.979305)
			(xy 361.237805 -261.928375) (xy 361.260931 -261.880354) (xy 361.290955 -261.836317) (xy 361.327207 -261.797246)
			(xy 361.368878 -261.764015) (xy 361.415036 -261.737366) (xy 361.46465 -261.717894) (xy 361.516612 -261.706034)
			(xy 361.569762 -261.702051) (xy 361.622912 -261.706034) (xy 361.674874 -261.717894) (xy 361.724488 -261.737366)
			(xy 361.770646 -261.764015) (xy 361.812317 -261.797246) (xy 361.848569 -261.836317) (xy 361.878593 -261.880354)
			(xy 361.901719 -261.928375) (xy 361.917429 -261.979305) (xy 361.925372 -262.032009) (xy 361.92587 -262.058658)
			(xy 361.925372 -262.085307) (xy 361.917429 -262.138011) (xy 361.901719 -262.188941) (xy 361.878593 -262.236962)
			(xy 361.848569 -262.280999) (xy 361.812317 -262.32007) (xy 361.770646 -262.353301) (xy 361.724488 -262.37995)
			(xy 361.674874 -262.399422) (xy 361.622912 -262.411282) (xy 361.569762 -262.415266) (xy 361.516612 -262.411282)
			(xy 361.46465 -262.399422) (xy 361.415036 -262.37995) (xy 361.368878 -262.353301) (xy 361.327207 -262.32007)
			(xy 361.290955 -262.280999) (xy 361.260931 -262.236962) (xy 361.237805 -262.188941) (xy 361.222095 -262.138011)
			(xy 361.214152 -262.085307) (xy 355.307921 -262.085307) (xy 354.84308 -262.550148) (xy 354.84308 -262.899123)
			(xy 357.924852 -262.899123) (xy 357.924852 -262.845825) (xy 357.932795 -262.793121) (xy 357.948505 -262.742191)
			(xy 357.971631 -262.69417) (xy 358.001655 -262.650133) (xy 358.037907 -262.611062) (xy 358.079578 -262.577831)
			(xy 358.125736 -262.551182) (xy 358.17535 -262.53171) (xy 358.227312 -262.51985) (xy 358.280462 -262.515867)
			(xy 358.333612 -262.51985) (xy 358.385574 -262.53171) (xy 358.435188 -262.551182) (xy 358.481346 -262.577831)
			(xy 358.523017 -262.611062) (xy 358.559269 -262.650133) (xy 358.589293 -262.69417) (xy 358.612419 -262.742191)
			(xy 358.628129 -262.793121) (xy 358.636072 -262.845825) (xy 358.63657 -262.872474) (xy 358.636072 -262.899123)
			(xy 358.628129 -262.951827) (xy 358.612419 -263.002757) (xy 358.589293 -263.050778) (xy 358.559269 -263.094815)
			(xy 358.523017 -263.133886) (xy 358.481346 -263.167117) (xy 358.435188 -263.193766) (xy 358.385574 -263.213238)
			(xy 358.333612 -263.225098) (xy 358.280462 -263.229082) (xy 358.227312 -263.225098) (xy 358.17535 -263.213238)
			(xy 358.125736 -263.193766) (xy 358.079578 -263.167117) (xy 358.037907 -263.133886) (xy 358.001655 -263.094815)
			(xy 357.971631 -263.050778) (xy 357.948505 -263.002757) (xy 357.932795 -262.951827) (xy 357.924852 -262.899123)
			(xy 354.84308 -262.899123) (xy 354.84308 -263.713193) (xy 361.214152 -263.713193) (xy 361.214152 -263.659895)
			(xy 361.222095 -263.607191) (xy 361.237805 -263.556261) (xy 361.260931 -263.50824) (xy 361.290955 -263.464203)
			(xy 361.327207 -263.425132) (xy 361.368878 -263.391901) (xy 361.415036 -263.365252) (xy 361.46465 -263.34578)
			(xy 361.516612 -263.33392) (xy 361.569762 -263.329937) (xy 361.622912 -263.33392) (xy 361.674874 -263.34578)
			(xy 361.724488 -263.365252) (xy 361.770646 -263.391901) (xy 361.812317 -263.425132) (xy 361.848569 -263.464203)
			(xy 361.878593 -263.50824) (xy 361.901719 -263.556261) (xy 361.917429 -263.607191) (xy 361.925372 -263.659895)
			(xy 361.92587 -263.686544) (xy 361.925372 -263.713193) (xy 361.917429 -263.765897) (xy 361.901719 -263.816827)
			(xy 361.878593 -263.864848) (xy 361.848569 -263.908885) (xy 361.812317 -263.947956) (xy 361.770646 -263.981187)
			(xy 361.724488 -264.007836) (xy 361.674874 -264.027308) (xy 361.622912 -264.039168) (xy 361.569762 -264.043152)
			(xy 361.516612 -264.039168) (xy 361.46465 -264.027308) (xy 361.415036 -264.007836) (xy 361.368878 -263.981187)
			(xy 361.327207 -263.947956) (xy 361.290955 -263.908885) (xy 361.260931 -263.864848) (xy 361.237805 -263.816827)
			(xy 361.222095 -263.765897) (xy 361.214152 -263.713193) (xy 354.84308 -263.713193) (xy 354.84308 -263.743948)
			(xy 355.287072 -264.18794) (xy 355.318822 -264.17397) (xy 355.341384 -264.164558) (xy 355.388443 -264.151314)
			(xy 355.436872 -264.144644) (xy 355.461316 -264.144252) (xy 355.489299 -264.144802) (xy 355.544577 -264.153559)
			(xy 355.597804 -264.170854) (xy 355.647671 -264.196263) (xy 355.69295 -264.229158) (xy 355.732526 -264.268732)
			(xy 355.765425 -264.314008) (xy 355.790836 -264.363873) (xy 355.808136 -264.4171) (xy 355.816896 -264.472377)
			(xy 355.817424 -264.50036) (xy 355.817018 -264.524802) (xy 355.816714 -264.527009) (xy 356.045506 -264.527009)
			(xy 356.045506 -264.473711) (xy 356.053449 -264.421007) (xy 356.069159 -264.370077) (xy 356.092285 -264.322056)
			(xy 356.122309 -264.278019) (xy 356.158561 -264.238948) (xy 356.200232 -264.205717) (xy 356.24639 -264.179068)
			(xy 356.296004 -264.159596) (xy 356.347966 -264.147736) (xy 356.401116 -264.143753) (xy 356.454266 -264.147736)
			(xy 356.506228 -264.159596) (xy 356.555842 -264.179068) (xy 356.602 -264.205717) (xy 356.643671 -264.238948)
			(xy 356.679923 -264.278019) (xy 356.709947 -264.322056) (xy 356.733073 -264.370077) (xy 356.748783 -264.421007)
			(xy 356.756726 -264.473711) (xy 356.757224 -264.50036) (xy 356.756726 -264.527009) (xy 356.748783 -264.579713)
			(xy 356.733073 -264.630643) (xy 356.709947 -264.678664) (xy 356.679923 -264.722701) (xy 356.643671 -264.761772)
			(xy 356.602 -264.795003) (xy 356.555842 -264.821652) (xy 356.506228 -264.841124) (xy 356.454266 -264.852984)
			(xy 356.401116 -264.856968) (xy 356.347966 -264.852984) (xy 356.296004 -264.841124) (xy 356.24639 -264.821652)
			(xy 356.200232 -264.795003) (xy 356.158561 -264.761772) (xy 356.122309 -264.722701) (xy 356.092285 -264.678664)
			(xy 356.069159 -264.630643) (xy 356.053449 -264.579713) (xy 356.045506 -264.527009) (xy 355.816714 -264.527009)
			(xy 355.810337 -264.573228) (xy 355.797107 -264.620289) (xy 355.787706 -264.642854) (xy 355.773736 -264.674604)
			(xy 356.099364 -265.000232) (xy 356.10546 -265.003534) (xy 356.127305 -265.016292) (xy 356.16748 -265.047034)
			(xy 356.202895 -265.083159) (xy 356.232834 -265.123936) (xy 356.24516 -265.146028) (xy 356.31628 -265.217148)
			(xy 356.31628 -265.340825) (xy 356.515406 -265.340825) (xy 356.515406 -265.287527) (xy 356.523349 -265.234823)
			(xy 356.539059 -265.183893) (xy 356.562185 -265.135872) (xy 356.592209 -265.091835) (xy 356.628461 -265.052764)
			(xy 356.670132 -265.019533) (xy 356.71629 -264.992884) (xy 356.765904 -264.973412) (xy 356.817866 -264.961552)
			(xy 356.871016 -264.957569) (xy 356.924166 -264.961552) (xy 356.976128 -264.973412) (xy 357.025742 -264.992884)
			(xy 357.0719 -265.019533) (xy 357.113571 -265.052764) (xy 357.149823 -265.091835) (xy 357.179847 -265.135872)
			(xy 357.202973 -265.183893) (xy 357.218683 -265.234823) (xy 357.226626 -265.287527) (xy 357.227124 -265.314176)
			(xy 357.226626 -265.340825) (xy 357.218683 -265.393529) (xy 357.202973 -265.444459) (xy 357.179847 -265.49248)
			(xy 357.149823 -265.536517) (xy 357.113571 -265.575588) (xy 357.0719 -265.608819) (xy 357.025742 -265.635468)
			(xy 356.976128 -265.65494) (xy 356.924166 -265.6668) (xy 356.871016 -265.670784) (xy 356.817866 -265.6668)
			(xy 356.765904 -265.65494) (xy 356.71629 -265.635468) (xy 356.670132 -265.608819) (xy 356.628461 -265.575588)
			(xy 356.592209 -265.536517) (xy 356.562185 -265.49248) (xy 356.539059 -265.444459) (xy 356.523349 -265.393529)
			(xy 356.515406 -265.340825) (xy 356.31628 -265.340825) (xy 356.31628 -265.670792) (xy 356.316858 -265.686403)
			(xy 356.326298 -265.716166) (xy 356.344273 -265.741697) (xy 356.369108 -265.760622) (xy 356.398493 -265.771178)
			(xy 356.41407 -265.772392) (xy 356.441354 -265.7739) (xy 356.495009 -265.78424) (xy 356.546454 -265.802656)
			(xy 356.594482 -265.828715) (xy 356.637965 -265.861807) (xy 356.675881 -265.901153) (xy 356.707341 -265.94583)
			(xy 356.731606 -265.994789) (xy 356.748106 -266.04688) (xy 356.756454 -266.100881) (xy 356.756454 -266.154895)
			(xy 356.985306 -266.154895) (xy 356.985306 -266.101597) (xy 356.993249 -266.048893) (xy 357.008959 -265.997963)
			(xy 357.032085 -265.949942) (xy 357.062109 -265.905905) (xy 357.098361 -265.866834) (xy 357.140032 -265.833603)
			(xy 357.18619 -265.806954) (xy 357.235804 -265.787482) (xy 357.287766 -265.775622) (xy 357.340916 -265.771639)
			(xy 357.394066 -265.775622) (xy 357.446028 -265.787482) (xy 357.495642 -265.806954) (xy 357.5418 -265.833603)
			(xy 357.583471 -265.866834) (xy 357.619723 -265.905905) (xy 357.649747 -265.949942) (xy 357.672873 -265.997963)
			(xy 357.688583 -266.048893) (xy 357.696526 -266.101597) (xy 357.697024 -266.128246) (xy 357.696526 -266.154895)
			(xy 357.688583 -266.207599) (xy 357.672873 -266.258529) (xy 357.649747 -266.30655) (xy 357.619723 -266.350587)
			(xy 357.583471 -266.389658) (xy 357.5418 -266.422889) (xy 357.495642 -266.449538) (xy 357.446028 -266.46901)
			(xy 357.394066 -266.48087) (xy 357.340916 -266.484854) (xy 357.287766 -266.48087) (xy 357.235804 -266.46901)
			(xy 357.18619 -266.449538) (xy 357.140032 -266.422889) (xy 357.098361 -266.389658) (xy 357.062109 -266.350587)
			(xy 357.032085 -266.30655) (xy 357.008959 -266.258529) (xy 356.993249 -266.207599) (xy 356.985306 -266.154895)
			(xy 356.756454 -266.154895) (xy 356.756454 -266.155523) (xy 356.748105 -266.209523) (xy 356.731605 -266.261615)
			(xy 356.707339 -266.310573) (xy 356.675879 -266.35525) (xy 356.637962 -266.394596) (xy 356.594479 -266.427687)
			(xy 356.546451 -266.453746) (xy 356.495006 -266.472161) (xy 356.441351 -266.482501) (xy 356.41407 -266.4841)
			(xy 356.398475 -266.485242) (xy 356.369049 -266.495775) (xy 356.344183 -266.514708) (xy 356.326201 -266.540271)
			(xy 356.316785 -266.570073) (xy 356.31628 -266.5857) (xy 356.31628 -266.968457) (xy 356.515406 -266.968457)
			(xy 356.515406 -266.915159) (xy 356.523349 -266.862455) (xy 356.539059 -266.811525) (xy 356.562185 -266.763504)
			(xy 356.592209 -266.719467) (xy 356.628461 -266.680396) (xy 356.670132 -266.647165) (xy 356.71629 -266.620516)
			(xy 356.765904 -266.601044) (xy 356.817866 -266.589184) (xy 356.871016 -266.585201) (xy 356.924166 -266.589184)
			(xy 356.976128 -266.601044) (xy 357.025742 -266.620516) (xy 357.0719 -266.647165) (xy 357.113571 -266.680396)
			(xy 357.149823 -266.719467) (xy 357.179847 -266.763504) (xy 357.202973 -266.811525) (xy 357.218683 -266.862455)
			(xy 357.226626 -266.915159) (xy 357.227124 -266.941808) (xy 357.226626 -266.968457) (xy 357.454952 -266.968457)
			(xy 357.454952 -266.915159) (xy 357.462895 -266.862455) (xy 357.478605 -266.811525) (xy 357.501731 -266.763504)
			(xy 357.531755 -266.719467) (xy 357.568007 -266.680396) (xy 357.609678 -266.647165) (xy 357.655836 -266.620516)
			(xy 357.70545 -266.601044) (xy 357.757412 -266.589184) (xy 357.810562 -266.585201) (xy 357.863712 -266.589184)
			(xy 357.915674 -266.601044) (xy 357.965288 -266.620516) (xy 358.011446 -266.647165) (xy 358.053117 -266.680396)
			(xy 358.089369 -266.719467) (xy 358.119393 -266.763504) (xy 358.142519 -266.811525) (xy 358.158229 -266.862455)
			(xy 358.166172 -266.915159) (xy 358.16667 -266.941808) (xy 358.166172 -266.968457) (xy 358.158229 -267.021161)
			(xy 358.142519 -267.072091) (xy 358.119393 -267.120112) (xy 358.089369 -267.164149) (xy 358.053117 -267.20322)
			(xy 358.011446 -267.236451) (xy 357.965288 -267.2631) (xy 357.915674 -267.282572) (xy 357.863712 -267.294432)
			(xy 357.810562 -267.298416) (xy 357.757412 -267.294432) (xy 357.70545 -267.282572) (xy 357.655836 -267.2631)
			(xy 357.609678 -267.236451) (xy 357.568007 -267.20322) (xy 357.531755 -267.164149) (xy 357.501731 -267.120112)
			(xy 357.478605 -267.072091) (xy 357.462895 -267.021161) (xy 357.454952 -266.968457) (xy 357.226626 -266.968457)
			(xy 357.218683 -267.021161) (xy 357.202973 -267.072091) (xy 357.179847 -267.120112) (xy 357.149823 -267.164149)
			(xy 357.113571 -267.20322) (xy 357.0719 -267.236451) (xy 357.025742 -267.2631) (xy 356.976128 -267.282572)
			(xy 356.924166 -267.294432) (xy 356.871016 -267.298416) (xy 356.817866 -267.294432) (xy 356.765904 -267.282572)
			(xy 356.71629 -267.2631) (xy 356.670132 -267.236451) (xy 356.628461 -267.20322) (xy 356.592209 -267.164149)
			(xy 356.562185 -267.120112) (xy 356.539059 -267.072091) (xy 356.523349 -267.021161) (xy 356.515406 -266.968457)
			(xy 356.31628 -266.968457) (xy 356.31628 -267.298424) (xy 356.316848 -267.314042) (xy 356.326277 -267.343822)
			(xy 356.344248 -267.369372) (xy 356.369088 -267.388311) (xy 356.398484 -267.398876) (xy 356.41407 -267.400024)
			(xy 356.441359 -267.401532) (xy 356.495024 -267.411874) (xy 356.54648 -267.430293) (xy 356.594517 -267.456357)
			(xy 356.638008 -267.489454) (xy 356.675932 -267.528807) (xy 356.707398 -267.573493) (xy 356.731668 -267.622461)
			(xy 356.748172 -267.674562) (xy 356.756522 -267.728573) (xy 356.756522 -267.782527) (xy 356.985052 -267.782527)
			(xy 356.985052 -267.729229) (xy 356.992995 -267.676525) (xy 357.008705 -267.625595) (xy 357.031831 -267.577574)
			(xy 357.061855 -267.533537) (xy 357.098107 -267.494466) (xy 357.139778 -267.461235) (xy 357.185936 -267.434586)
			(xy 357.23555 -267.415114) (xy 357.287512 -267.403254) (xy 357.340662 -267.399271) (xy 357.393812 -267.403254)
			(xy 357.445774 -267.415114) (xy 357.495388 -267.434586) (xy 357.541546 -267.461235) (xy 357.583217 -267.494466)
			(xy 357.619469 -267.533537) (xy 357.649493 -267.577574) (xy 357.672619 -267.625595) (xy 357.688329 -267.676525)
			(xy 357.696272 -267.729229) (xy 357.69677 -267.755878) (xy 357.696272 -267.782527) (xy 357.924852 -267.782527)
			(xy 357.924852 -267.729229) (xy 357.932795 -267.676525) (xy 357.948505 -267.625595) (xy 357.971631 -267.577574)
			(xy 358.001655 -267.533537) (xy 358.037907 -267.494466) (xy 358.079578 -267.461235) (xy 358.125736 -267.434586)
			(xy 358.17535 -267.415114) (xy 358.227312 -267.403254) (xy 358.280462 -267.399271) (xy 358.333612 -267.403254)
			(xy 358.385574 -267.415114) (xy 358.435188 -267.434586) (xy 358.481346 -267.461235) (xy 358.523017 -267.494466)
			(xy 358.559269 -267.533537) (xy 358.589293 -267.577574) (xy 358.612419 -267.625595) (xy 358.628129 -267.676525)
			(xy 358.636072 -267.729229) (xy 358.63657 -267.755878) (xy 358.636072 -267.782527) (xy 358.628129 -267.835231)
			(xy 358.612419 -267.886161) (xy 358.589293 -267.934182) (xy 358.559269 -267.978219) (xy 358.523017 -268.01729)
			(xy 358.481346 -268.050521) (xy 358.435188 -268.07717) (xy 358.385574 -268.096642) (xy 358.333612 -268.108502)
			(xy 358.280462 -268.112486) (xy 358.227312 -268.108502) (xy 358.17535 -268.096642) (xy 358.125736 -268.07717)
			(xy 358.079578 -268.050521) (xy 358.037907 -268.01729) (xy 358.001655 -267.978219) (xy 357.971631 -267.934182)
			(xy 357.948505 -267.886161) (xy 357.932795 -267.835231) (xy 357.924852 -267.782527) (xy 357.696272 -267.782527)
			(xy 357.688329 -267.835231) (xy 357.672619 -267.886161) (xy 357.649493 -267.934182) (xy 357.619469 -267.978219)
			(xy 357.583217 -268.01729) (xy 357.541546 -268.050521) (xy 357.495388 -268.07717) (xy 357.445774 -268.096642)
			(xy 357.393812 -268.108502) (xy 357.340662 -268.112486) (xy 357.287512 -268.108502) (xy 357.23555 -268.096642)
			(xy 357.185936 -268.07717) (xy 357.139778 -268.050521) (xy 357.098107 -268.01729) (xy 357.061855 -267.978219)
			(xy 357.031831 -267.934182) (xy 357.008705 -267.886161) (xy 356.992995 -267.835231) (xy 356.985052 -267.782527)
			(xy 356.756522 -267.782527) (xy 356.756522 -267.783225) (xy 356.748172 -267.837236) (xy 356.731669 -267.889338)
			(xy 356.707399 -267.938306) (xy 356.675933 -267.982991) (xy 356.638009 -268.022345) (xy 356.594518 -268.055442)
			(xy 356.546481 -268.081507) (xy 356.495026 -268.099926) (xy 356.441361 -268.110268) (xy 356.41407 -268.111732)
			(xy 356.398476 -268.112874) (xy 356.369055 -268.123408) (xy 356.344194 -268.142342) (xy 356.326219 -268.167906)
			(xy 356.316812 -268.197706) (xy 356.31628 -268.213332) (xy 356.31628 -268.596343) (xy 356.515152 -268.596343)
			(xy 356.515152 -268.543045) (xy 356.523095 -268.490341) (xy 356.538805 -268.439411) (xy 356.561931 -268.39139)
			(xy 356.591955 -268.347353) (xy 356.628207 -268.308282) (xy 356.669878 -268.275051) (xy 356.716036 -268.248402)
			(xy 356.76565 -268.22893) (xy 356.817612 -268.21707) (xy 356.870762 -268.213087) (xy 356.923912 -268.21707)
			(xy 356.975874 -268.22893) (xy 357.025488 -268.248402) (xy 357.071646 -268.275051) (xy 357.113317 -268.308282)
			(xy 357.149569 -268.347353) (xy 357.179593 -268.39139) (xy 357.202719 -268.439411) (xy 357.218429 -268.490341)
			(xy 357.226372 -268.543045) (xy 357.22687 -268.569694) (xy 357.226372 -268.596343) (xy 357.454952 -268.596343)
			(xy 357.454952 -268.543045) (xy 357.462895 -268.490341) (xy 357.478605 -268.439411) (xy 357.501731 -268.39139)
			(xy 357.531755 -268.347353) (xy 357.568007 -268.308282) (xy 357.609678 -268.275051) (xy 357.655836 -268.248402)
			(xy 357.70545 -268.22893) (xy 357.757412 -268.21707) (xy 357.810562 -268.213087) (xy 357.863712 -268.21707)
			(xy 357.915674 -268.22893) (xy 357.965288 -268.248402) (xy 358.011446 -268.275051) (xy 358.053117 -268.308282)
			(xy 358.089369 -268.347353) (xy 358.119393 -268.39139) (xy 358.142519 -268.439411) (xy 358.158229 -268.490341)
			(xy 358.166172 -268.543045) (xy 358.16667 -268.569694) (xy 358.166172 -268.596343) (xy 358.158229 -268.649047)
			(xy 358.142519 -268.699977) (xy 358.119393 -268.747998) (xy 358.089369 -268.792035) (xy 358.053117 -268.831106)
			(xy 358.011446 -268.864337) (xy 357.965288 -268.890986) (xy 357.915674 -268.910458) (xy 357.863712 -268.922318)
			(xy 357.810562 -268.926302) (xy 357.757412 -268.922318) (xy 357.70545 -268.910458) (xy 357.655836 -268.890986)
			(xy 357.609678 -268.864337) (xy 357.568007 -268.831106) (xy 357.531755 -268.792035) (xy 357.501731 -268.747998)
			(xy 357.478605 -268.699977) (xy 357.462895 -268.649047) (xy 357.454952 -268.596343) (xy 357.226372 -268.596343)
			(xy 357.218429 -268.649047) (xy 357.202719 -268.699977) (xy 357.179593 -268.747998) (xy 357.149569 -268.792035)
			(xy 357.113317 -268.831106) (xy 357.071646 -268.864337) (xy 357.025488 -268.890986) (xy 356.975874 -268.910458)
			(xy 356.923912 -268.922318) (xy 356.870762 -268.926302) (xy 356.817612 -268.922318) (xy 356.76565 -268.910458)
			(xy 356.716036 -268.890986) (xy 356.669878 -268.864337) (xy 356.628207 -268.831106) (xy 356.591955 -268.792035)
			(xy 356.561931 -268.747998) (xy 356.538805 -268.699977) (xy 356.523095 -268.649047) (xy 356.515152 -268.596343)
			(xy 356.31628 -268.596343) (xy 356.31628 -268.926056) (xy 356.316853 -268.941671) (xy 356.326287 -268.971443)
			(xy 356.34426 -268.996984) (xy 356.369098 -269.015916) (xy 356.398489 -269.026477) (xy 356.41407 -269.027656)
			(xy 356.441357 -269.029164) (xy 356.495017 -269.039505) (xy 356.546468 -269.057922) (xy 356.5945 -269.083984)
			(xy 356.637988 -269.117079) (xy 356.675908 -269.156429) (xy 356.707371 -269.20111) (xy 356.731639 -269.250074)
			(xy 356.748141 -269.30217) (xy 356.75649 -269.356177) (xy 356.75649 -269.410159) (xy 356.985052 -269.410159)
			(xy 356.985052 -269.356861) (xy 356.992995 -269.304157) (xy 357.008705 -269.253227) (xy 357.031831 -269.205206)
			(xy 357.061855 -269.161169) (xy 357.098107 -269.122098) (xy 357.139778 -269.088867) (xy 357.185936 -269.062218)
			(xy 357.23555 -269.042746) (xy 357.287512 -269.030886) (xy 357.340662 -269.026903) (xy 357.393812 -269.030886)
			(xy 357.445774 -269.042746) (xy 357.495388 -269.062218) (xy 357.541546 -269.088867) (xy 357.583217 -269.122098)
			(xy 357.619469 -269.161169) (xy 357.649493 -269.205206) (xy 357.672619 -269.253227) (xy 357.688329 -269.304157)
			(xy 357.696272 -269.356861) (xy 357.69677 -269.38351) (xy 357.696272 -269.410159) (xy 357.924852 -269.410159)
			(xy 357.924852 -269.356861) (xy 357.932795 -269.304157) (xy 357.948505 -269.253227) (xy 357.971631 -269.205206)
			(xy 358.001655 -269.161169) (xy 358.037907 -269.122098) (xy 358.079578 -269.088867) (xy 358.125736 -269.062218)
			(xy 358.17535 -269.042746) (xy 358.227312 -269.030886) (xy 358.280462 -269.026903) (xy 358.333612 -269.030886)
			(xy 358.385574 -269.042746) (xy 358.435188 -269.062218) (xy 358.481346 -269.088867) (xy 358.523017 -269.122098)
			(xy 358.559269 -269.161169) (xy 358.589293 -269.205206) (xy 358.612419 -269.253227) (xy 358.628129 -269.304157)
			(xy 358.636072 -269.356861) (xy 358.63657 -269.38351) (xy 358.636072 -269.410159) (xy 358.628129 -269.462863)
			(xy 358.612419 -269.513793) (xy 358.589293 -269.561814) (xy 358.559269 -269.605851) (xy 358.523017 -269.644922)
			(xy 358.481346 -269.678153) (xy 358.435188 -269.704802) (xy 358.385574 -269.724274) (xy 358.333612 -269.736134)
			(xy 358.280462 -269.740118) (xy 358.227312 -269.736134) (xy 358.17535 -269.724274) (xy 358.125736 -269.704802)
			(xy 358.079578 -269.678153) (xy 358.037907 -269.644922) (xy 358.001655 -269.605851) (xy 357.971631 -269.561814)
			(xy 357.948505 -269.513793) (xy 357.932795 -269.462863) (xy 357.924852 -269.410159) (xy 357.696272 -269.410159)
			(xy 357.688329 -269.462863) (xy 357.672619 -269.513793) (xy 357.649493 -269.561814) (xy 357.619469 -269.605851)
			(xy 357.583217 -269.644922) (xy 357.541546 -269.678153) (xy 357.495388 -269.704802) (xy 357.445774 -269.724274)
			(xy 357.393812 -269.736134) (xy 357.340662 -269.740118) (xy 357.287512 -269.736134) (xy 357.23555 -269.724274)
			(xy 357.185936 -269.704802) (xy 357.139778 -269.678153) (xy 357.098107 -269.644922) (xy 357.061855 -269.605851)
			(xy 357.031831 -269.561814) (xy 357.008705 -269.513793) (xy 356.992995 -269.462863) (xy 356.985052 -269.410159)
			(xy 356.75649 -269.410159) (xy 356.75649 -269.410824) (xy 356.748141 -269.46483) (xy 356.731639 -269.516927)
			(xy 356.707371 -269.565891) (xy 356.675907 -269.610572) (xy 356.637987 -269.649922) (xy 356.5945 -269.683016)
			(xy 356.546467 -269.709078) (xy 356.495016 -269.727495) (xy 356.441356 -269.737836) (xy 356.41407 -269.739364)
			(xy 356.398478 -269.740507) (xy 356.369061 -269.751042) (xy 356.344206 -269.769977) (xy 356.326238 -269.795541)
			(xy 356.31684 -269.82534) (xy 356.31628 -269.840964) (xy 356.31628 -270.224229) (xy 356.515152 -270.224229)
			(xy 356.515152 -270.170931) (xy 356.523095 -270.118227) (xy 356.538805 -270.067297) (xy 356.561931 -270.019276)
			(xy 356.591955 -269.975239) (xy 356.628207 -269.936168) (xy 356.669878 -269.902937) (xy 356.716036 -269.876288)
			(xy 356.76565 -269.856816) (xy 356.817612 -269.844956) (xy 356.870762 -269.840973) (xy 356.923912 -269.844956)
			(xy 356.975874 -269.856816) (xy 357.025488 -269.876288) (xy 357.071646 -269.902937) (xy 357.113317 -269.936168)
			(xy 357.149569 -269.975239) (xy 357.179593 -270.019276) (xy 357.202719 -270.067297) (xy 357.218429 -270.118227)
			(xy 357.226372 -270.170931) (xy 357.22687 -270.19758) (xy 357.226372 -270.224229) (xy 357.454952 -270.224229)
			(xy 357.454952 -270.170931) (xy 357.462895 -270.118227) (xy 357.478605 -270.067297) (xy 357.501731 -270.019276)
			(xy 357.531755 -269.975239) (xy 357.568007 -269.936168) (xy 357.609678 -269.902937) (xy 357.655836 -269.876288)
			(xy 357.70545 -269.856816) (xy 357.757412 -269.844956) (xy 357.810562 -269.840973) (xy 357.863712 -269.844956)
			(xy 357.915674 -269.856816) (xy 357.965288 -269.876288) (xy 358.011446 -269.902937) (xy 358.053117 -269.936168)
			(xy 358.089369 -269.975239) (xy 358.119393 -270.019276) (xy 358.142519 -270.067297) (xy 358.158229 -270.118227)
			(xy 358.166172 -270.170931) (xy 358.16667 -270.19758) (xy 358.166172 -270.224229) (xy 358.158229 -270.276933)
			(xy 358.142519 -270.327863) (xy 358.119393 -270.375884) (xy 358.089369 -270.419921) (xy 358.053117 -270.458992)
			(xy 358.011446 -270.492223) (xy 357.965288 -270.518872) (xy 357.915674 -270.538344) (xy 357.863712 -270.550204)
			(xy 357.810562 -270.554188) (xy 357.757412 -270.550204) (xy 357.70545 -270.538344) (xy 357.655836 -270.518872)
			(xy 357.609678 -270.492223) (xy 357.568007 -270.458992) (xy 357.531755 -270.419921) (xy 357.501731 -270.375884)
			(xy 357.478605 -270.327863) (xy 357.462895 -270.276933) (xy 357.454952 -270.224229) (xy 357.226372 -270.224229)
			(xy 357.218429 -270.276933) (xy 357.202719 -270.327863) (xy 357.179593 -270.375884) (xy 357.149569 -270.419921)
			(xy 357.113317 -270.458992) (xy 357.071646 -270.492223) (xy 357.025488 -270.518872) (xy 356.975874 -270.538344)
			(xy 356.923912 -270.550204) (xy 356.870762 -270.554188) (xy 356.817612 -270.550204) (xy 356.76565 -270.538344)
			(xy 356.716036 -270.518872) (xy 356.669878 -270.492223) (xy 356.628207 -270.458992) (xy 356.591955 -270.419921)
			(xy 356.561931 -270.375884) (xy 356.538805 -270.327863) (xy 356.523095 -270.276933) (xy 356.515152 -270.224229)
			(xy 356.31628 -270.224229) (xy 356.31628 -270.553942) (xy 356.316851 -270.569558) (xy 356.326282 -270.599334)
			(xy 356.344255 -270.624879) (xy 356.369094 -270.643814) (xy 356.398487 -270.654377) (xy 356.41407 -270.655542)
			(xy 356.441358 -270.65705) (xy 356.49502 -270.667391) (xy 356.546473 -270.685809) (xy 356.594508 -270.711872)
			(xy 356.637996 -270.744968) (xy 356.675918 -270.784319) (xy 356.707383 -270.829002) (xy 356.731652 -270.877968)
			(xy 356.748154 -270.930067) (xy 356.756504 -270.984075) (xy 356.756504 -271.038045) (xy 356.985052 -271.038045)
			(xy 356.985052 -270.984747) (xy 356.992995 -270.932043) (xy 357.008705 -270.881113) (xy 357.031831 -270.833092)
			(xy 357.061855 -270.789055) (xy 357.098107 -270.749984) (xy 357.139778 -270.716753) (xy 357.185936 -270.690104)
			(xy 357.23555 -270.670632) (xy 357.287512 -270.658772) (xy 357.340662 -270.654789) (xy 357.393812 -270.658772)
			(xy 357.445774 -270.670632) (xy 357.495388 -270.690104) (xy 357.541546 -270.716753) (xy 357.583217 -270.749984)
			(xy 357.619469 -270.789055) (xy 357.649493 -270.833092) (xy 357.672619 -270.881113) (xy 357.688329 -270.932043)
			(xy 357.696272 -270.984747) (xy 357.69677 -271.011396) (xy 357.696272 -271.038045) (xy 357.924852 -271.038045)
			(xy 357.924852 -270.984747) (xy 357.932795 -270.932043) (xy 357.948505 -270.881113) (xy 357.971631 -270.833092)
			(xy 358.001655 -270.789055) (xy 358.037907 -270.749984) (xy 358.079578 -270.716753) (xy 358.125736 -270.690104)
			(xy 358.17535 -270.670632) (xy 358.227312 -270.658772) (xy 358.280462 -270.654789) (xy 358.333612 -270.658772)
			(xy 358.385574 -270.670632) (xy 358.435188 -270.690104) (xy 358.481346 -270.716753) (xy 358.523017 -270.749984)
			(xy 358.559269 -270.789055) (xy 358.589293 -270.833092) (xy 358.612419 -270.881113) (xy 358.628129 -270.932043)
			(xy 358.636072 -270.984747) (xy 358.63657 -271.011396) (xy 358.636072 -271.038045) (xy 358.628129 -271.090749)
			(xy 358.612419 -271.141679) (xy 358.589293 -271.1897) (xy 358.559269 -271.233737) (xy 358.523017 -271.272808)
			(xy 358.481346 -271.306039) (xy 358.435188 -271.332688) (xy 358.385574 -271.35216) (xy 358.333612 -271.36402)
			(xy 358.280462 -271.368004) (xy 358.227312 -271.36402) (xy 358.17535 -271.35216) (xy 358.125736 -271.332688)
			(xy 358.079578 -271.306039) (xy 358.037907 -271.272808) (xy 358.001655 -271.233737) (xy 357.971631 -271.1897)
			(xy 357.948505 -271.141679) (xy 357.932795 -271.090749) (xy 357.924852 -271.038045) (xy 357.696272 -271.038045)
			(xy 357.688329 -271.090749) (xy 357.672619 -271.141679) (xy 357.649493 -271.1897) (xy 357.619469 -271.233737)
			(xy 357.583217 -271.272808) (xy 357.541546 -271.306039) (xy 357.495388 -271.332688) (xy 357.445774 -271.35216)
			(xy 357.393812 -271.36402) (xy 357.340662 -271.368004) (xy 357.287512 -271.36402) (xy 357.23555 -271.35216)
			(xy 357.185936 -271.332688) (xy 357.139778 -271.306039) (xy 357.098107 -271.272808) (xy 357.061855 -271.233737)
			(xy 357.031831 -271.1897) (xy 357.008705 -271.141679) (xy 356.992995 -271.090749) (xy 356.985052 -271.038045)
			(xy 356.756504 -271.038045) (xy 356.756504 -271.038725) (xy 356.748154 -271.092733) (xy 356.731652 -271.144832)
			(xy 356.707383 -271.193797) (xy 356.675919 -271.23848) (xy 356.637997 -271.277832) (xy 356.594508 -271.310928)
			(xy 356.546473 -271.336991) (xy 356.495021 -271.355409) (xy 356.441358 -271.36575) (xy 356.41407 -271.36725)
			(xy 356.398478 -271.368393) (xy 356.369059 -271.378927) (xy 356.344201 -271.397862) (xy 356.32623 -271.423425)
			(xy 356.316828 -271.453225) (xy 356.31628 -271.46885) (xy 356.31628 -271.851861) (xy 356.515406 -271.851861)
			(xy 356.515406 -271.798563) (xy 356.523349 -271.745859) (xy 356.539059 -271.694929) (xy 356.562185 -271.646908)
			(xy 356.592209 -271.602871) (xy 356.628461 -271.5638) (xy 356.670132 -271.530569) (xy 356.71629 -271.50392)
			(xy 356.765904 -271.484448) (xy 356.817866 -271.472588) (xy 356.871016 -271.468605) (xy 356.924166 -271.472588)
			(xy 356.976128 -271.484448) (xy 357.025742 -271.50392) (xy 357.0719 -271.530569) (xy 357.113571 -271.5638)
			(xy 357.149823 -271.602871) (xy 357.179847 -271.646908) (xy 357.202973 -271.694929) (xy 357.218683 -271.745859)
			(xy 357.226626 -271.798563) (xy 357.227124 -271.825212) (xy 357.226626 -271.851861) (xy 357.454698 -271.851861)
			(xy 357.454698 -271.798563) (xy 357.462641 -271.745859) (xy 357.478351 -271.694929) (xy 357.501477 -271.646908)
			(xy 357.531501 -271.602871) (xy 357.567753 -271.5638) (xy 357.609424 -271.530569) (xy 357.655582 -271.50392)
			(xy 357.705196 -271.484448) (xy 357.757158 -271.472588) (xy 357.810308 -271.468605) (xy 357.863458 -271.472588)
			(xy 357.91542 -271.484448) (xy 357.965034 -271.50392) (xy 358.011192 -271.530569) (xy 358.052863 -271.5638)
			(xy 358.089115 -271.602871) (xy 358.119139 -271.646908) (xy 358.142265 -271.694929) (xy 358.157975 -271.745859)
			(xy 358.165918 -271.798563) (xy 358.166416 -271.825212) (xy 358.165918 -271.851861) (xy 358.157975 -271.904565)
			(xy 358.142265 -271.955495) (xy 358.119139 -272.003516) (xy 358.089115 -272.047553) (xy 358.052863 -272.086624)
			(xy 358.011192 -272.119855) (xy 357.965034 -272.146504) (xy 357.91542 -272.165976) (xy 357.863458 -272.177836)
			(xy 357.810308 -272.18182) (xy 357.757158 -272.177836) (xy 357.705196 -272.165976) (xy 357.655582 -272.146504)
			(xy 357.609424 -272.119855) (xy 357.567753 -272.086624) (xy 357.531501 -272.047553) (xy 357.501477 -272.003516)
			(xy 357.478351 -271.955495) (xy 357.462641 -271.904565) (xy 357.454698 -271.851861) (xy 357.226626 -271.851861)
			(xy 357.218683 -271.904565) (xy 357.202973 -271.955495) (xy 357.179847 -272.003516) (xy 357.149823 -272.047553)
			(xy 357.113571 -272.086624) (xy 357.0719 -272.119855) (xy 357.025742 -272.146504) (xy 356.976128 -272.165976)
			(xy 356.924166 -272.177836) (xy 356.871016 -272.18182) (xy 356.817866 -272.177836) (xy 356.765904 -272.165976)
			(xy 356.71629 -272.146504) (xy 356.670132 -272.119855) (xy 356.628461 -272.086624) (xy 356.592209 -272.047553)
			(xy 356.562185 -272.003516) (xy 356.539059 -271.955495) (xy 356.523349 -271.904565) (xy 356.515406 -271.851861)
			(xy 356.31628 -271.851861) (xy 356.31628 -272.181828) (xy 356.316849 -272.197446) (xy 356.326278 -272.227225)
			(xy 356.344249 -272.252773) (xy 356.36909 -272.271712) (xy 356.398485 -272.282276) (xy 356.41407 -272.283428)
			(xy 356.441359 -272.284936) (xy 356.495024 -272.295278) (xy 356.546478 -272.313696) (xy 356.594515 -272.33976)
			(xy 356.638005 -272.372857) (xy 356.675929 -272.41221) (xy 356.707395 -272.456895) (xy 356.731664 -272.505862)
			(xy 356.748168 -272.557963) (xy 356.756518 -272.611973) (xy 356.756518 -272.665931) (xy 356.985052 -272.665931)
			(xy 356.985052 -272.612633) (xy 356.992995 -272.559929) (xy 357.008705 -272.508999) (xy 357.031831 -272.460978)
			(xy 357.061855 -272.416941) (xy 357.098107 -272.37787) (xy 357.139778 -272.344639) (xy 357.185936 -272.31799)
			(xy 357.23555 -272.298518) (xy 357.287512 -272.286658) (xy 357.340662 -272.282675) (xy 357.393812 -272.286658)
			(xy 357.445774 -272.298518) (xy 357.495388 -272.31799) (xy 357.541546 -272.344639) (xy 357.583217 -272.37787)
			(xy 357.619469 -272.416941) (xy 357.649493 -272.460978) (xy 357.672619 -272.508999) (xy 357.688329 -272.559929)
			(xy 357.696272 -272.612633) (xy 357.69677 -272.639282) (xy 357.696272 -272.665931) (xy 357.924852 -272.665931)
			(xy 357.924852 -272.612633) (xy 357.932795 -272.559929) (xy 357.948505 -272.508999) (xy 357.971631 -272.460978)
			(xy 358.001655 -272.416941) (xy 358.037907 -272.37787) (xy 358.079578 -272.344639) (xy 358.125736 -272.31799)
			(xy 358.17535 -272.298518) (xy 358.227312 -272.286658) (xy 358.280462 -272.282675) (xy 358.333612 -272.286658)
			(xy 358.385574 -272.298518) (xy 358.435188 -272.31799) (xy 358.481346 -272.344639) (xy 358.523017 -272.37787)
			(xy 358.559269 -272.416941) (xy 358.589293 -272.460978) (xy 358.612419 -272.508999) (xy 358.628129 -272.559929)
			(xy 358.636072 -272.612633) (xy 358.63657 -272.639282) (xy 358.636072 -272.665931) (xy 358.628129 -272.718635)
			(xy 358.612419 -272.769565) (xy 358.589293 -272.817586) (xy 358.559269 -272.861623) (xy 358.523017 -272.900694)
			(xy 358.481346 -272.933925) (xy 358.435188 -272.960574) (xy 358.385574 -272.980046) (xy 358.333612 -272.991906)
			(xy 358.280462 -272.99589) (xy 358.227312 -272.991906) (xy 358.17535 -272.980046) (xy 358.125736 -272.960574)
			(xy 358.079578 -272.933925) (xy 358.037907 -272.900694) (xy 358.001655 -272.861623) (xy 357.971631 -272.817586)
			(xy 357.948505 -272.769565) (xy 357.932795 -272.718635) (xy 357.924852 -272.665931) (xy 357.696272 -272.665931)
			(xy 357.688329 -272.718635) (xy 357.672619 -272.769565) (xy 357.649493 -272.817586) (xy 357.619469 -272.861623)
			(xy 357.583217 -272.900694) (xy 357.541546 -272.933925) (xy 357.495388 -272.960574) (xy 357.445774 -272.980046)
			(xy 357.393812 -272.991906) (xy 357.340662 -272.99589) (xy 357.287512 -272.991906) (xy 357.23555 -272.980046)
			(xy 357.185936 -272.960574) (xy 357.139778 -272.933925) (xy 357.098107 -272.900694) (xy 357.061855 -272.861623)
			(xy 357.031831 -272.817586) (xy 357.008705 -272.769565) (xy 356.992995 -272.718635) (xy 356.985052 -272.665931)
			(xy 356.756518 -272.665931) (xy 356.756518 -272.666625) (xy 356.748168 -272.720636) (xy 356.731665 -272.772736)
			(xy 356.707395 -272.821704) (xy 356.67593 -272.866389) (xy 356.638006 -272.905742) (xy 356.594516 -272.938839)
			(xy 356.546479 -272.964903) (xy 356.495025 -272.983322) (xy 356.44136 -272.993664) (xy 356.41407 -272.995136)
			(xy 356.398477 -272.996278) (xy 356.369056 -273.006812) (xy 356.344196 -273.025747) (xy 356.326222 -273.05131)
			(xy 356.316815 -273.08111) (xy 356.31628 -273.096736) (xy 356.31628 -273.453098) (xy 356.514654 -273.453098)
			(xy 356.515152 -273.426449) (xy 356.523095 -273.373745) (xy 356.538805 -273.322815) (xy 356.561931 -273.274794)
			(xy 356.591955 -273.230757) (xy 356.628207 -273.191686) (xy 356.669878 -273.158455) (xy 356.716036 -273.131806)
			(xy 356.76565 -273.112334) (xy 356.817612 -273.100474) (xy 356.870762 -273.096491) (xy 356.923912 -273.100474)
			(xy 356.975874 -273.112334) (xy 357.025488 -273.131806) (xy 357.071646 -273.158455) (xy 357.113317 -273.191686)
			(xy 357.149569 -273.230757) (xy 357.179593 -273.274794) (xy 357.202719 -273.322815) (xy 357.218429 -273.373745)
			(xy 357.226372 -273.426449) (xy 357.22687 -273.453098) (xy 357.226491 -273.476301) (xy 357.226038 -273.479747)
			(xy 357.454952 -273.479747) (xy 357.454952 -273.426449) (xy 357.462895 -273.373745) (xy 357.478605 -273.322815)
			(xy 357.501731 -273.274794) (xy 357.531755 -273.230757) (xy 357.568007 -273.191686) (xy 357.609678 -273.158455)
			(xy 357.655836 -273.131806) (xy 357.70545 -273.112334) (xy 357.757412 -273.100474) (xy 357.810562 -273.096491)
			(xy 357.863712 -273.100474) (xy 357.915674 -273.112334) (xy 357.965288 -273.131806) (xy 358.011446 -273.158455)
			(xy 358.053117 -273.191686) (xy 358.089369 -273.230757) (xy 358.119393 -273.274794) (xy 358.142519 -273.322815)
			(xy 358.158229 -273.373745) (xy 358.166172 -273.426449) (xy 358.16667 -273.453098) (xy 358.166172 -273.479747)
			(xy 358.158229 -273.532451) (xy 358.142519 -273.583381) (xy 358.119393 -273.631402) (xy 358.089369 -273.675439)
			(xy 358.053117 -273.71451) (xy 358.011446 -273.747741) (xy 357.965288 -273.77439) (xy 357.915674 -273.793862)
			(xy 357.863712 -273.805722) (xy 357.810562 -273.809706) (xy 357.757412 -273.805722) (xy 357.70545 -273.793862)
			(xy 357.655836 -273.77439) (xy 357.609678 -273.747741) (xy 357.568007 -273.71451) (xy 357.531755 -273.675439)
			(xy 357.501731 -273.631402) (xy 357.478605 -273.583381) (xy 357.462895 -273.532451) (xy 357.454952 -273.479747)
			(xy 357.226038 -273.479747) (xy 357.220441 -273.522312) (xy 357.208456 -273.567144) (xy 357.199946 -273.588734)
			(xy 357.190548 -273.611848) (xy 357.363014 -273.910552) (xy 357.387652 -273.913854) (xy 357.412991 -273.917696)
			(xy 357.462294 -273.931688) (xy 357.509083 -273.952599) (xy 357.552393 -273.979999) (xy 357.59133 -274.013322)
			(xy 357.625091 -274.051881) (xy 357.652978 -274.094879) (xy 357.674416 -274.141429) (xy 357.688963 -274.19057)
			(xy 357.696319 -274.241289) (xy 357.69677 -274.266914) (xy 357.696272 -274.293563) (xy 357.924852 -274.293563)
			(xy 357.924852 -274.240265) (xy 357.932795 -274.187561) (xy 357.948505 -274.136631) (xy 357.971631 -274.08861)
			(xy 358.001655 -274.044573) (xy 358.037907 -274.005502) (xy 358.079578 -273.972271) (xy 358.125736 -273.945622)
			(xy 358.17535 -273.92615) (xy 358.227312 -273.91429) (xy 358.280462 -273.910307) (xy 358.333612 -273.91429)
			(xy 358.385574 -273.92615) (xy 358.435188 -273.945622) (xy 358.481346 -273.972271) (xy 358.523017 -274.005502)
			(xy 358.559269 -274.044573) (xy 358.589293 -274.08861) (xy 358.612419 -274.136631) (xy 358.628129 -274.187561)
			(xy 358.636072 -274.240265) (xy 358.63657 -274.266914) (xy 358.636072 -274.293563) (xy 358.628129 -274.346267)
			(xy 358.612419 -274.397197) (xy 358.589293 -274.445218) (xy 358.559269 -274.489255) (xy 358.523017 -274.528326)
			(xy 358.481346 -274.561557) (xy 358.435188 -274.588206) (xy 358.385574 -274.607678) (xy 358.333612 -274.619538)
			(xy 358.280462 -274.623522) (xy 358.227312 -274.619538) (xy 358.17535 -274.607678) (xy 358.125736 -274.588206)
			(xy 358.079578 -274.561557) (xy 358.037907 -274.528326) (xy 358.001655 -274.489255) (xy 357.971631 -274.445218)
			(xy 357.948505 -274.397197) (xy 357.932795 -274.346267) (xy 357.924852 -274.293563) (xy 357.696272 -274.293563)
			(xy 357.688329 -274.346267) (xy 357.672619 -274.397197) (xy 357.649493 -274.445218) (xy 357.619469 -274.489255)
			(xy 357.583217 -274.528326) (xy 357.541546 -274.561557) (xy 357.495388 -274.588206) (xy 357.445774 -274.607678)
			(xy 357.393812 -274.619538) (xy 357.340662 -274.623522) (xy 357.287512 -274.619538) (xy 357.23555 -274.607678)
			(xy 357.185936 -274.588206) (xy 357.139778 -274.561557) (xy 357.098107 -274.528326) (xy 357.061855 -274.489255)
			(xy 357.031831 -274.445218) (xy 357.008705 -274.397197) (xy 356.992995 -274.346267) (xy 356.985052 -274.293563)
			(xy 356.984554 -274.266914) (xy 356.984931 -274.243669) (xy 356.990975 -274.197574) (xy 357.002962 -274.152656)
			(xy 357.011478 -274.131024) (xy 357.02113 -274.10791) (xy 356.848664 -273.80946) (xy 356.823772 -273.806158)
			(xy 356.798438 -273.802285) (xy 356.749136 -273.788298) (xy 356.702348 -273.76739) (xy 356.659038 -273.739994)
			(xy 356.620101 -273.706674) (xy 356.58634 -273.668119) (xy 356.558451 -273.625124) (xy 356.537012 -273.578577)
			(xy 356.522463 -273.529438) (xy 356.515106 -273.478722) (xy 356.514654 -273.453098) (xy 356.31628 -273.453098)
			(xy 356.31628 -273.80946) (xy 356.316853 -273.825075) (xy 356.326288 -273.854845) (xy 356.344261 -273.880385)
			(xy 356.369099 -273.899317) (xy 356.398489 -273.909877) (xy 356.41407 -273.91106) (xy 356.441367 -273.912554)
			(xy 356.49505 -273.922871) (xy 356.546526 -273.941272) (xy 356.594585 -273.967323) (xy 356.638098 -274.000414)
			(xy 356.676042 -274.039767) (xy 356.707526 -274.084456) (xy 356.73181 -274.133432) (xy 356.748323 -274.185544)
			(xy 356.756678 -274.239568) (xy 356.756678 -274.294233) (xy 356.748323 -274.348257) (xy 356.731809 -274.400369)
			(xy 356.707525 -274.449345) (xy 356.676041 -274.494034) (xy 356.638097 -274.533387) (xy 356.594584 -274.566477)
			(xy 356.546525 -274.592529) (xy 356.495049 -274.610929) (xy 356.441366 -274.621246) (xy 356.41407 -274.622768)
			(xy 356.398479 -274.623911) (xy 356.369062 -274.634446) (xy 356.344207 -274.653381) (xy 356.326241 -274.678945)
			(xy 356.316843 -274.708744) (xy 356.31628 -274.724368) (xy 356.31628 -275.107379) (xy 356.515152 -275.107379)
			(xy 356.515152 -275.054081) (xy 356.523095 -275.001377) (xy 356.538805 -274.950447) (xy 356.561931 -274.902426)
			(xy 356.591955 -274.858389) (xy 356.628207 -274.819318) (xy 356.669878 -274.786087) (xy 356.716036 -274.759438)
			(xy 356.76565 -274.739966) (xy 356.817612 -274.728106) (xy 356.870762 -274.724123) (xy 356.923912 -274.728106)
			(xy 356.975874 -274.739966) (xy 357.025488 -274.759438) (xy 357.071646 -274.786087) (xy 357.113317 -274.819318)
			(xy 357.149569 -274.858389) (xy 357.179593 -274.902426) (xy 357.202719 -274.950447) (xy 357.218429 -275.001377)
			(xy 357.226372 -275.054081) (xy 357.22687 -275.08073) (xy 357.226372 -275.107379) (xy 357.454952 -275.107379)
			(xy 357.454952 -275.054081) (xy 357.462895 -275.001377) (xy 357.478605 -274.950447) (xy 357.501731 -274.902426)
			(xy 357.531755 -274.858389) (xy 357.568007 -274.819318) (xy 357.609678 -274.786087) (xy 357.655836 -274.759438)
			(xy 357.70545 -274.739966) (xy 357.757412 -274.728106) (xy 357.810562 -274.724123) (xy 357.863712 -274.728106)
			(xy 357.915674 -274.739966) (xy 357.965288 -274.759438) (xy 358.011446 -274.786087) (xy 358.053117 -274.819318)
			(xy 358.089369 -274.858389) (xy 358.119393 -274.902426) (xy 358.142519 -274.950447) (xy 358.158229 -275.001377)
			(xy 358.166172 -275.054081) (xy 358.16667 -275.08073) (xy 358.166172 -275.107379) (xy 358.158229 -275.160083)
			(xy 358.142519 -275.211013) (xy 358.119393 -275.259034) (xy 358.089369 -275.303071) (xy 358.053117 -275.342142)
			(xy 358.011446 -275.375373) (xy 357.965288 -275.402022) (xy 357.915674 -275.421494) (xy 357.863712 -275.433354)
			(xy 357.810562 -275.437338) (xy 357.757412 -275.433354) (xy 357.70545 -275.421494) (xy 357.655836 -275.402022)
			(xy 357.609678 -275.375373) (xy 357.568007 -275.342142) (xy 357.531755 -275.303071) (xy 357.501731 -275.259034)
			(xy 357.478605 -275.211013) (xy 357.462895 -275.160083) (xy 357.454952 -275.107379) (xy 357.226372 -275.107379)
			(xy 357.218429 -275.160083) (xy 357.202719 -275.211013) (xy 357.179593 -275.259034) (xy 357.149569 -275.303071)
			(xy 357.113317 -275.342142) (xy 357.071646 -275.375373) (xy 357.025488 -275.402022) (xy 356.975874 -275.421494)
			(xy 356.923912 -275.433354) (xy 356.870762 -275.437338) (xy 356.817612 -275.433354) (xy 356.76565 -275.421494)
			(xy 356.716036 -275.402022) (xy 356.669878 -275.375373) (xy 356.628207 -275.342142) (xy 356.591955 -275.303071)
			(xy 356.561931 -275.259034) (xy 356.538805 -275.211013) (xy 356.523095 -275.160083) (xy 356.515152 -275.107379)
			(xy 356.31628 -275.107379) (xy 356.31628 -275.353018) (xy 356.423468 -275.538438) (xy 356.448106 -275.54174)
			(xy 356.473454 -275.545559) (xy 356.522774 -275.559529) (xy 356.569581 -275.580426) (xy 356.612907 -275.60782)
			(xy 356.651858 -275.641144) (xy 356.685627 -275.679709) (xy 356.713517 -275.722717) (xy 356.734952 -275.769281)
			(xy 356.749487 -275.818437) (xy 356.756824 -275.86917) (xy 356.757224 -275.8948) (xy 356.756725 -275.922137)
			(xy 356.748369 -275.976168) (xy 356.731854 -276.028287) (xy 356.707567 -276.077269) (xy 356.676078 -276.121964)
			(xy 356.638129 -276.161322) (xy 356.594611 -276.194417) (xy 356.546545 -276.220472) (xy 356.495062 -276.238875)
			(xy 356.441372 -276.249194) (xy 356.41407 -276.250654) (xy 356.398478 -276.251797) (xy 356.36906 -276.262331)
			(xy 356.344202 -276.281266) (xy 356.326232 -276.30683) (xy 356.316831 -276.336629) (xy 356.31628 -276.352254)
			(xy 356.31628 -276.708616) (xy 356.514654 -276.708616) (xy 356.515088 -276.682987) (xy 356.522422 -276.632257)
			(xy 356.536954 -276.583103) (xy 356.558385 -276.53654) (xy 356.586271 -276.493532) (xy 356.620037 -276.454967)
			(xy 356.658983 -276.421643) (xy 356.702306 -276.394248) (xy 356.749109 -276.373348) (xy 356.798426 -276.359376)
			(xy 356.823772 -276.355556) (xy 356.84841 -276.352254) (xy 357.020876 -276.053804) (xy 357.011224 -276.03069)
			(xy 357.002708 -276.009058) (xy 356.99072 -275.96414) (xy 356.984676 -275.918045) (xy 356.9843 -275.8948)
			(xy 356.984798 -275.868151) (xy 356.992741 -275.815447) (xy 357.008451 -275.764517) (xy 357.031577 -275.716496)
			(xy 357.061601 -275.672459) (xy 357.097853 -275.633388) (xy 357.139524 -275.600157) (xy 357.185682 -275.573508)
			(xy 357.235296 -275.554036) (xy 357.287258 -275.542176) (xy 357.340408 -275.538193) (xy 357.393558 -275.542176)
			(xy 357.44552 -275.554036) (xy 357.495134 -275.573508) (xy 357.541292 -275.600157) (xy 357.582963 -275.633388)
			(xy 357.619215 -275.672459) (xy 357.649239 -275.716496) (xy 357.672365 -275.764517) (xy 357.688075 -275.815447)
			(xy 357.696018 -275.868151) (xy 357.696516 -275.8948) (xy 357.696065 -275.920418) (xy 357.695916 -275.921449)
			(xy 357.924852 -275.921449) (xy 357.924852 -275.868151) (xy 357.932795 -275.815447) (xy 357.948505 -275.764517)
			(xy 357.971631 -275.716496) (xy 358.001655 -275.672459) (xy 358.037907 -275.633388) (xy 358.079578 -275.600157)
			(xy 358.125736 -275.573508) (xy 358.17535 -275.554036) (xy 358.227312 -275.542176) (xy 358.280462 -275.538193)
			(xy 358.333612 -275.542176) (xy 358.385574 -275.554036) (xy 358.435188 -275.573508) (xy 358.481346 -275.600157)
			(xy 358.523017 -275.633388) (xy 358.559269 -275.672459) (xy 358.589293 -275.716496) (xy 358.612419 -275.764517)
			(xy 358.628129 -275.815447) (xy 358.636072 -275.868151) (xy 358.63657 -275.8948) (xy 358.636072 -275.921449)
			(xy 358.628129 -275.974153) (xy 358.612419 -276.025083) (xy 358.589293 -276.073104) (xy 358.559269 -276.117141)
			(xy 358.523017 -276.156212) (xy 358.481346 -276.189443) (xy 358.435188 -276.216092) (xy 358.385574 -276.235564)
			(xy 358.333612 -276.247424) (xy 358.280462 -276.251408) (xy 358.227312 -276.247424) (xy 358.17535 -276.235564)
			(xy 358.125736 -276.216092) (xy 358.079578 -276.189443) (xy 358.037907 -276.156212) (xy 358.001655 -276.117141)
			(xy 357.971631 -276.073104) (xy 357.948505 -276.025083) (xy 357.932795 -275.974153) (xy 357.924852 -275.921449)
			(xy 357.695916 -275.921449) (xy 357.688749 -275.971128) (xy 357.674238 -276.020265) (xy 357.652834 -276.066814)
			(xy 357.624977 -276.109815) (xy 357.591244 -276.148378) (xy 357.552331 -276.181706) (xy 357.509042 -276.209112)
			(xy 357.462271 -276.230029) (xy 357.412985 -276.244025) (xy 357.387652 -276.24786) (xy 357.36276 -276.251162)
			(xy 357.190294 -276.549612) (xy 357.199946 -276.572726) (xy 357.208466 -276.594357) (xy 357.220452 -276.639275)
			(xy 357.226495 -276.685371) (xy 357.22687 -276.708616) (xy 357.226372 -276.735265) (xy 357.454952 -276.735265)
			(xy 357.454952 -276.681967) (xy 357.462895 -276.629263) (xy 357.478605 -276.578333) (xy 357.501731 -276.530312)
			(xy 357.531755 -276.486275) (xy 357.568007 -276.447204) (xy 357.609678 -276.413973) (xy 357.655836 -276.387324)
			(xy 357.70545 -276.367852) (xy 357.757412 -276.355992) (xy 357.810562 -276.352009) (xy 357.863712 -276.355992)
			(xy 357.915674 -276.367852) (xy 357.965288 -276.387324) (xy 358.011446 -276.413973) (xy 358.053117 -276.447204)
			(xy 358.089369 -276.486275) (xy 358.119393 -276.530312) (xy 358.142519 -276.578333) (xy 358.158229 -276.629263)
			(xy 358.166172 -276.681967) (xy 358.16667 -276.708616) (xy 358.166172 -276.735265) (xy 358.158229 -276.787969)
			(xy 358.142519 -276.838899) (xy 358.119393 -276.88692) (xy 358.089369 -276.930957) (xy 358.053117 -276.970028)
			(xy 358.011446 -277.003259) (xy 357.965288 -277.029908) (xy 357.915674 -277.04938) (xy 357.863712 -277.06124)
			(xy 357.810562 -277.065224) (xy 357.757412 -277.06124) (xy 357.70545 -277.04938) (xy 357.655836 -277.029908)
			(xy 357.609678 -277.003259) (xy 357.568007 -276.970028) (xy 357.531755 -276.930957) (xy 357.501731 -276.88692)
			(xy 357.478605 -276.838899) (xy 357.462895 -276.787969) (xy 357.454952 -276.735265) (xy 357.226372 -276.735265)
			(xy 357.218429 -276.787969) (xy 357.202719 -276.838899) (xy 357.179593 -276.88692) (xy 357.149569 -276.930957)
			(xy 357.113317 -276.970028) (xy 357.071646 -277.003259) (xy 357.025488 -277.029908) (xy 356.975874 -277.04938)
			(xy 356.923912 -277.06124) (xy 356.870762 -277.065224) (xy 356.817612 -277.06124) (xy 356.76565 -277.04938)
			(xy 356.716036 -277.029908) (xy 356.669878 -277.003259) (xy 356.628207 -276.970028) (xy 356.591955 -276.930957)
			(xy 356.561931 -276.88692) (xy 356.538805 -276.838899) (xy 356.523095 -276.787969) (xy 356.515152 -276.735265)
			(xy 356.514654 -276.708616) (xy 356.31628 -276.708616) (xy 356.31628 -277.064978) (xy 356.316856 -277.080591)
			(xy 356.326294 -277.110357) (xy 356.344268 -277.135892) (xy 356.369104 -277.15482) (xy 356.398491 -277.165378)
			(xy 356.41407 -277.166578) (xy 356.442121 -277.168123) (xy 356.497245 -277.17895) (xy 356.549983 -277.198304)
			(xy 356.599025 -277.225703) (xy 356.643153 -277.260468) (xy 356.681271 -277.301734) (xy 356.69728 -277.32482)
			(xy 357.044244 -277.32482) (xy 357.058482 -277.304248) (xy 357.091802 -277.266929) (xy 357.130016 -277.234637)
			(xy 357.17237 -277.20801) (xy 357.218034 -277.187569) (xy 357.266108 -277.173717) (xy 357.315647 -277.166727)
			(xy 357.340662 -277.166324) (xy 357.367313 -277.166794) (xy 357.420019 -277.174733) (xy 357.470954 -277.19044)
			(xy 357.518978 -277.213563) (xy 357.563019 -277.243585) (xy 357.602094 -277.279837) (xy 357.635329 -277.321508)
			(xy 357.661981 -277.367667) (xy 357.681455 -277.417283) (xy 357.693317 -277.469248) (xy 357.6973 -277.5224)
			(xy 357.695301 -277.549081) (xy 357.924852 -277.549081) (xy 357.924852 -277.495783) (xy 357.932795 -277.443079)
			(xy 357.948505 -277.392149) (xy 357.971631 -277.344128) (xy 358.001655 -277.300091) (xy 358.037907 -277.26102)
			(xy 358.079578 -277.227789) (xy 358.125736 -277.20114) (xy 358.17535 -277.181668) (xy 358.227312 -277.169808)
			(xy 358.280462 -277.165825) (xy 358.333612 -277.169808) (xy 358.385574 -277.181668) (xy 358.435188 -277.20114)
			(xy 358.481346 -277.227789) (xy 358.523017 -277.26102) (xy 358.559269 -277.300091) (xy 358.589293 -277.344128)
			(xy 358.612419 -277.392149) (xy 358.628129 -277.443079) (xy 358.636072 -277.495783) (xy 358.63657 -277.522432)
			(xy 358.636072 -277.549081) (xy 358.628129 -277.601785) (xy 358.612419 -277.652715) (xy 358.589293 -277.700736)
			(xy 358.559269 -277.744773) (xy 358.523017 -277.783844) (xy 358.481346 -277.817075) (xy 358.435188 -277.843724)
			(xy 358.385574 -277.863196) (xy 358.333612 -277.875056) (xy 358.280462 -277.87904) (xy 358.227312 -277.875056)
			(xy 358.17535 -277.863196) (xy 358.125736 -277.843724) (xy 358.079578 -277.817075) (xy 358.037907 -277.783844)
			(xy 358.001655 -277.744773) (xy 357.971631 -277.700736) (xy 357.948505 -277.652715) (xy 357.932795 -277.601785)
			(xy 357.924852 -277.549081) (xy 357.695301 -277.549081) (xy 357.693317 -277.575552) (xy 357.681455 -277.627517)
			(xy 357.661981 -277.677133) (xy 357.635329 -277.723292) (xy 357.602094 -277.764963) (xy 357.563019 -277.801215)
			(xy 357.518978 -277.831237) (xy 357.470954 -277.85436) (xy 357.420019 -277.870067) (xy 357.367313 -277.878006)
			(xy 357.340662 -277.87854) (xy 357.31565 -277.878115) (xy 357.266117 -277.871115) (xy 357.21805 -277.857258)
			(xy 357.172392 -277.836817) (xy 357.130041 -277.810192) (xy 357.091829 -277.777907) (xy 357.058506 -277.740597)
			(xy 357.044244 -277.720044) (xy 356.69728 -277.720044) (xy 356.68125 -277.743111) (xy 356.643122 -277.784358)
			(xy 356.598993 -277.81911) (xy 356.549957 -277.846506) (xy 356.497229 -277.865866) (xy 356.442116 -277.876711)
			(xy 356.41407 -277.878286) (xy 356.398474 -277.879428) (xy 356.369046 -277.889961) (xy 356.344178 -277.908893)
			(xy 356.326193 -277.934456) (xy 356.316773 -277.964258) (xy 356.31628 -277.979886) (xy 356.31628 -278.363151)
			(xy 356.515152 -278.363151) (xy 356.515152 -278.309853) (xy 356.523095 -278.257149) (xy 356.538805 -278.206219)
			(xy 356.561931 -278.158198) (xy 356.591955 -278.114161) (xy 356.628207 -278.07509) (xy 356.669878 -278.041859)
			(xy 356.716036 -278.01521) (xy 356.76565 -277.995738) (xy 356.817612 -277.983878) (xy 356.870762 -277.979895)
			(xy 356.923912 -277.983878) (xy 356.975874 -277.995738) (xy 357.025488 -278.01521) (xy 357.071646 -278.041859)
			(xy 357.113317 -278.07509) (xy 357.149569 -278.114161) (xy 357.179593 -278.158198) (xy 357.202719 -278.206219)
			(xy 357.218429 -278.257149) (xy 357.226372 -278.309853) (xy 357.22687 -278.336502) (xy 357.226372 -278.363151)
			(xy 357.454952 -278.363151) (xy 357.454952 -278.309853) (xy 357.462895 -278.257149) (xy 357.478605 -278.206219)
			(xy 357.501731 -278.158198) (xy 357.531755 -278.114161) (xy 357.568007 -278.07509) (xy 357.609678 -278.041859)
			(xy 357.655836 -278.01521) (xy 357.70545 -277.995738) (xy 357.757412 -277.983878) (xy 357.810562 -277.979895)
			(xy 357.863712 -277.983878) (xy 357.915674 -277.995738) (xy 357.965288 -278.01521) (xy 358.011446 -278.041859)
			(xy 358.053117 -278.07509) (xy 358.089369 -278.114161) (xy 358.119393 -278.158198) (xy 358.142519 -278.206219)
			(xy 358.158229 -278.257149) (xy 358.166172 -278.309853) (xy 358.16667 -278.336502) (xy 358.166177 -278.362897)
			(xy 362.153952 -278.362897) (xy 362.153952 -278.309599) (xy 362.161895 -278.256895) (xy 362.177605 -278.205965)
			(xy 362.200731 -278.157944) (xy 362.230755 -278.113907) (xy 362.267007 -278.074836) (xy 362.308678 -278.041605)
			(xy 362.354836 -278.014956) (xy 362.40445 -277.995484) (xy 362.456412 -277.983624) (xy 362.509562 -277.979641)
			(xy 362.562712 -277.983624) (xy 362.614674 -277.995484) (xy 362.664288 -278.014956) (xy 362.710446 -278.041605)
			(xy 362.752117 -278.074836) (xy 362.788369 -278.113907) (xy 362.818393 -278.157944) (xy 362.841519 -278.205965)
			(xy 362.857229 -278.256895) (xy 362.865172 -278.309599) (xy 362.86567 -278.336248) (xy 362.865172 -278.362897)
			(xy 362.857229 -278.415601) (xy 362.841519 -278.466531) (xy 362.818393 -278.514552) (xy 362.788369 -278.558589)
			(xy 362.752117 -278.59766) (xy 362.710446 -278.630891) (xy 362.664288 -278.65754) (xy 362.614674 -278.677012)
			(xy 362.562712 -278.688872) (xy 362.509562 -278.692856) (xy 362.456412 -278.688872) (xy 362.40445 -278.677012)
			(xy 362.354836 -278.65754) (xy 362.308678 -278.630891) (xy 362.267007 -278.59766) (xy 362.230755 -278.558589)
			(xy 362.200731 -278.514552) (xy 362.177605 -278.466531) (xy 362.161895 -278.415601) (xy 362.153952 -278.362897)
			(xy 358.166177 -278.362897) (xy 358.166172 -278.363151) (xy 358.158229 -278.415855) (xy 358.142519 -278.466785)
			(xy 358.119393 -278.514806) (xy 358.089369 -278.558843) (xy 358.053117 -278.597914) (xy 358.011446 -278.631145)
			(xy 357.965288 -278.657794) (xy 357.915674 -278.677266) (xy 357.863712 -278.689126) (xy 357.810562 -278.69311)
			(xy 357.757412 -278.689126) (xy 357.70545 -278.677266) (xy 357.655836 -278.657794) (xy 357.609678 -278.631145)
			(xy 357.568007 -278.597914) (xy 357.531755 -278.558843) (xy 357.501731 -278.514806) (xy 357.478605 -278.466785)
			(xy 357.462895 -278.415855) (xy 357.454952 -278.363151) (xy 357.226372 -278.363151) (xy 357.218429 -278.415855)
			(xy 357.202719 -278.466785) (xy 357.179593 -278.514806) (xy 357.149569 -278.558843) (xy 357.113317 -278.597914)
			(xy 357.071646 -278.631145) (xy 357.025488 -278.657794) (xy 356.975874 -278.677266) (xy 356.923912 -278.689126)
			(xy 356.870762 -278.69311) (xy 356.817612 -278.689126) (xy 356.76565 -278.677266) (xy 356.716036 -278.657794)
			(xy 356.669878 -278.631145) (xy 356.628207 -278.597914) (xy 356.591955 -278.558843) (xy 356.561931 -278.514806)
			(xy 356.538805 -278.466785) (xy 356.523095 -278.415855) (xy 356.515152 -278.363151) (xy 356.31628 -278.363151)
			(xy 356.31628 -278.692864) (xy 356.316854 -278.708478) (xy 356.326289 -278.738248) (xy 356.344262 -278.763787)
			(xy 356.3691 -278.782717) (xy 356.39849 -278.793277) (xy 356.41407 -278.794464) (xy 356.441356 -278.795972)
			(xy 356.495015 -278.806313) (xy 356.546465 -278.82473) (xy 356.594496 -278.850791) (xy 356.637982 -278.883885)
			(xy 356.675902 -278.923234) (xy 356.707365 -278.967914) (xy 356.731632 -279.016877) (xy 356.748133 -279.068972)
			(xy 356.756482 -279.122977) (xy 356.756482 -279.176967) (xy 362.623852 -279.176967) (xy 362.623852 -279.123669)
			(xy 362.631795 -279.070965) (xy 362.647505 -279.020035) (xy 362.670631 -278.972014) (xy 362.700655 -278.927977)
			(xy 362.736907 -278.888906) (xy 362.778578 -278.855675) (xy 362.824736 -278.829026) (xy 362.87435 -278.809554)
			(xy 362.926312 -278.797694) (xy 362.979462 -278.793711) (xy 363.032612 -278.797694) (xy 363.084574 -278.809554)
			(xy 363.134188 -278.829026) (xy 363.180346 -278.855675) (xy 363.222017 -278.888906) (xy 363.258269 -278.927977)
			(xy 363.288293 -278.972014) (xy 363.311419 -279.020035) (xy 363.327129 -279.070965) (xy 363.335072 -279.123669)
			(xy 363.33557 -279.150318) (xy 363.335072 -279.176967) (xy 363.327129 -279.229671) (xy 363.311419 -279.280601)
			(xy 363.288293 -279.328622) (xy 363.258269 -279.372659) (xy 363.222017 -279.41173) (xy 363.180346 -279.444961)
			(xy 363.134188 -279.47161) (xy 363.084574 -279.491082) (xy 363.032612 -279.502942) (xy 362.979462 -279.506926)
			(xy 362.926312 -279.502942) (xy 362.87435 -279.491082) (xy 362.824736 -279.47161) (xy 362.778578 -279.444961)
			(xy 362.736907 -279.41173) (xy 362.700655 -279.372659) (xy 362.670631 -279.328622) (xy 362.647505 -279.280601)
			(xy 362.631795 -279.229671) (xy 362.623852 -279.176967) (xy 356.756482 -279.176967) (xy 356.756482 -279.177624)
			(xy 356.748133 -279.231629) (xy 356.731631 -279.283724) (xy 356.707364 -279.332687) (xy 356.675901 -279.377367)
			(xy 356.637981 -279.416716) (xy 356.594495 -279.44981) (xy 356.546463 -279.475871) (xy 356.495014 -279.494288)
			(xy 356.441355 -279.504628) (xy 356.41407 -279.506172) (xy 356.398479 -279.507315) (xy 356.369063 -279.51785)
			(xy 356.344209 -279.536786) (xy 356.326243 -279.562349) (xy 356.316847 -279.592148) (xy 356.31628 -279.607772)
			(xy 356.31628 -279.822148) (xy 356.273862 -279.864566) (xy 356.27945 -279.89149) (xy 356.282978 -279.909445)
			(xy 356.286794 -279.945838) (xy 356.28707 -279.964134) (xy 356.286572 -279.990783) (xy 361.214152 -279.990783)
			(xy 361.214152 -279.937485) (xy 361.222095 -279.884781) (xy 361.237805 -279.833851) (xy 361.260931 -279.78583)
			(xy 361.290955 -279.741793) (xy 361.327207 -279.702722) (xy 361.368878 -279.669491) (xy 361.415036 -279.642842)
			(xy 361.46465 -279.62337) (xy 361.516612 -279.61151) (xy 361.569762 -279.607527) (xy 361.622912 -279.61151)
			(xy 361.674874 -279.62337) (xy 361.724488 -279.642842) (xy 361.770646 -279.669491) (xy 361.812317 -279.702722)
			(xy 361.848569 -279.741793) (xy 361.878593 -279.78583) (xy 361.901719 -279.833851) (xy 361.917429 -279.884781)
			(xy 361.925372 -279.937485) (xy 361.92587 -279.964134) (xy 361.925372 -279.990783) (xy 361.917429 -280.043487)
			(xy 361.901719 -280.094417) (xy 361.878593 -280.142438) (xy 361.848569 -280.186475) (xy 361.812317 -280.225546)
			(xy 361.770646 -280.258777) (xy 361.724488 -280.285426) (xy 361.674874 -280.304898) (xy 361.622912 -280.316758)
			(xy 361.569762 -280.320742) (xy 361.516612 -280.316758) (xy 361.46465 -280.304898) (xy 361.415036 -280.285426)
			(xy 361.368878 -280.258777) (xy 361.327207 -280.225546) (xy 361.290955 -280.186475) (xy 361.260931 -280.142438)
			(xy 361.237805 -280.094417) (xy 361.222095 -280.043487) (xy 361.214152 -279.990783) (xy 356.286572 -279.990783)
			(xy 356.286547 -279.992117) (xy 356.277787 -280.047392) (xy 356.260487 -280.100616) (xy 356.235075 -280.150479)
			(xy 356.202175 -280.195752) (xy 356.162597 -280.235322) (xy 356.117317 -280.268212) (xy 356.067449 -280.293615)
			(xy 356.014222 -280.310904) (xy 355.958945 -280.319653) (xy 355.930962 -280.320242) (xy 355.912664 -280.319994)
			(xy 355.876268 -280.316181) (xy 355.858318 -280.312622) (xy 355.831394 -280.307034) (xy 355.733604 -280.404824)
			(xy 355.723129 -280.416014) (xy 355.70884 -280.443117) (xy 355.703244 -280.47324) (xy 355.706845 -280.503666)
			(xy 355.719318 -280.531651) (xy 355.729032 -280.543508) (xy 355.745571 -280.563093) (xy 355.773444 -280.606114)
			(xy 355.794868 -280.652683) (xy 355.8094 -280.701841) (xy 355.816742 -280.752574) (xy 355.81717 -280.778204)
			(xy 355.816674 -280.804853) (xy 357.924852 -280.804853) (xy 357.924852 -280.751555) (xy 357.932795 -280.698851)
			(xy 357.948505 -280.647921) (xy 357.971631 -280.5999) (xy 358.001655 -280.555863) (xy 358.037907 -280.516792)
			(xy 358.079578 -280.483561) (xy 358.125736 -280.456912) (xy 358.17535 -280.43744) (xy 358.227312 -280.42558)
			(xy 358.280462 -280.421597) (xy 358.333612 -280.42558) (xy 358.385574 -280.43744) (xy 358.435188 -280.456912)
			(xy 358.481346 -280.483561) (xy 358.523017 -280.516792) (xy 358.559269 -280.555863) (xy 358.589293 -280.5999)
			(xy 358.612419 -280.647921) (xy 358.628129 -280.698851) (xy 358.636072 -280.751555) (xy 358.63657 -280.778204)
			(xy 358.636072 -280.804853) (xy 358.628129 -280.857557) (xy 358.612419 -280.908487) (xy 358.589293 -280.956508)
			(xy 358.559269 -281.000545) (xy 358.523017 -281.039616) (xy 358.481346 -281.072847) (xy 358.435188 -281.099496)
			(xy 358.385574 -281.118968) (xy 358.333612 -281.130828) (xy 358.280462 -281.134812) (xy 358.227312 -281.130828)
			(xy 358.17535 -281.118968) (xy 358.125736 -281.099496) (xy 358.079578 -281.072847) (xy 358.037907 -281.039616)
			(xy 358.001655 -281.000545) (xy 357.971631 -280.956508) (xy 357.948505 -280.908487) (xy 357.932795 -280.857557)
			(xy 357.924852 -280.804853) (xy 355.816674 -280.804853) (xy 355.816649 -280.806188) (xy 355.807893 -280.861467)
			(xy 355.790596 -280.914695) (xy 355.765185 -280.964562) (xy 355.732285 -281.00984) (xy 355.692708 -281.049413)
			(xy 355.647426 -281.082307) (xy 355.597556 -281.107712) (xy 355.544326 -281.125002) (xy 355.489046 -281.133752)
			(xy 355.461062 -281.134312) (xy 355.435429 -281.13389) (xy 355.384687 -281.12658) (xy 355.33552 -281.112059)
			(xy 355.288949 -281.090629) (xy 355.245937 -281.062734) (xy 355.226366 -281.046174) (xy 355.214491 -281.036508)
			(xy 355.186506 -281.024117) (xy 355.15611 -281.020548) (xy 355.126016 -281.02612) (xy 355.098912 -281.040337)
			(xy 355.087682 -281.050746) (xy 355.055424 -281.083004) (xy 355.045223 -281.093944) (xy 355.031099 -281.120294)
			(xy 355.025201 -281.149603) (xy 355.028034 -281.179365) (xy 355.039356 -281.207035) (xy 355.058198 -281.230247)
			(xy 355.082949 -281.247015) (xy 355.09708 -281.251914) (xy 355.123921 -281.260819) (xy 355.174596 -281.285916)
			(xy 355.220666 -281.318709) (xy 355.260973 -281.358373) (xy 355.294502 -281.40391) (xy 355.32041 -281.454175)
			(xy 355.338047 -281.507904) (xy 355.346968 -281.563745) (xy 355.347524 -281.59202) (xy 355.347 -281.618669)
			(xy 361.214152 -281.618669) (xy 361.214152 -281.565371) (xy 361.222095 -281.512667) (xy 361.237805 -281.461737)
			(xy 361.260931 -281.413716) (xy 361.290955 -281.369679) (xy 361.327207 -281.330608) (xy 361.368878 -281.297377)
			(xy 361.415036 -281.270728) (xy 361.46465 -281.251256) (xy 361.516612 -281.239396) (xy 361.569762 -281.235413)
			(xy 361.622912 -281.239396) (xy 361.674874 -281.251256) (xy 361.724488 -281.270728) (xy 361.770646 -281.297377)
			(xy 361.812317 -281.330608) (xy 361.848569 -281.369679) (xy 361.878593 -281.413716) (xy 361.901719 -281.461737)
			(xy 361.917429 -281.512667) (xy 361.925372 -281.565371) (xy 361.92587 -281.59202) (xy 361.925372 -281.618669)
			(xy 361.917429 -281.671373) (xy 361.901719 -281.722303) (xy 361.878593 -281.770324) (xy 361.848569 -281.814361)
			(xy 361.812317 -281.853432) (xy 361.770646 -281.886663) (xy 361.724488 -281.913312) (xy 361.674874 -281.932784)
			(xy 361.622912 -281.944644) (xy 361.569762 -281.948628) (xy 361.516612 -281.944644) (xy 361.46465 -281.932784)
			(xy 361.415036 -281.913312) (xy 361.368878 -281.886663) (xy 361.327207 -281.853432) (xy 361.290955 -281.814361)
			(xy 361.260931 -281.770324) (xy 361.237805 -281.722303) (xy 361.222095 -281.671373) (xy 361.214152 -281.618669)
			(xy 355.347 -281.618669) (xy 355.346974 -281.620003) (xy 355.338216 -281.675278) (xy 355.32092 -281.728504)
			(xy 355.295511 -281.778368) (xy 355.262615 -281.823644) (xy 355.223041 -281.863218) (xy 355.177765 -281.896113)
			(xy 355.1279 -281.921522) (xy 355.074674 -281.938817) (xy 355.019399 -281.947574) (xy 354.991416 -281.948128)
			(xy 354.96314 -281.947587) (xy 354.907298 -281.938654) (xy 354.853569 -281.921011) (xy 354.803302 -281.895101)
			(xy 354.75776 -281.861574) (xy 354.718088 -281.821273) (xy 354.685281 -281.77521) (xy 354.660164 -281.724542)
			(xy 354.65131 -281.697684) (xy 354.646366 -281.683575) (xy 354.629607 -281.658836) (xy 354.606406 -281.640003)
			(xy 354.57875 -281.628688) (xy 354.549003 -281.625857) (xy 354.519709 -281.631752) (xy 354.493373 -281.645871)
			(xy 354.4824 -281.656028) (xy 354.377244 -281.761184) (xy 354.543614 -282.049474) (xy 354.568252 -282.052776)
			(xy 354.593597 -282.056598) (xy 354.642909 -282.070573) (xy 354.689708 -282.091474) (xy 354.733026 -282.118871)
			(xy 354.771968 -282.152196) (xy 354.805729 -282.19076) (xy 354.833611 -282.233768) (xy 354.855038 -282.280329)
			(xy 354.869567 -282.329481) (xy 354.876897 -282.380209) (xy 354.87737 -282.405836) (xy 354.876872 -282.432485)
			(xy 355.105452 -282.432485) (xy 355.105452 -282.379187) (xy 355.113395 -282.326483) (xy 355.129105 -282.275553)
			(xy 355.152231 -282.227532) (xy 355.182255 -282.183495) (xy 355.218507 -282.144424) (xy 355.260178 -282.111193)
			(xy 355.306336 -282.084544) (xy 355.35595 -282.065072) (xy 355.407912 -282.053212) (xy 355.461062 -282.049229)
			(xy 355.514212 -282.053212) (xy 355.566174 -282.065072) (xy 355.615788 -282.084544) (xy 355.661946 -282.111193)
			(xy 355.703617 -282.144424) (xy 355.739869 -282.183495) (xy 355.769893 -282.227532) (xy 355.793019 -282.275553)
			(xy 355.808729 -282.326483) (xy 355.816672 -282.379187) (xy 355.81717 -282.405836) (xy 355.816672 -282.432485)
			(xy 357.924852 -282.432485) (xy 357.924852 -282.379187) (xy 357.932795 -282.326483) (xy 357.948505 -282.275553)
			(xy 357.971631 -282.227532) (xy 358.001655 -282.183495) (xy 358.037907 -282.144424) (xy 358.079578 -282.111193)
			(xy 358.125736 -282.084544) (xy 358.17535 -282.065072) (xy 358.227312 -282.053212) (xy 358.280462 -282.049229)
			(xy 358.333612 -282.053212) (xy 358.385574 -282.065072) (xy 358.435188 -282.084544) (xy 358.481346 -282.111193)
			(xy 358.523017 -282.144424) (xy 358.559269 -282.183495) (xy 358.589293 -282.227532) (xy 358.612419 -282.275553)
			(xy 358.628129 -282.326483) (xy 358.636072 -282.379187) (xy 358.63657 -282.405836) (xy 358.636072 -282.432485)
			(xy 358.628129 -282.485189) (xy 358.612419 -282.536119) (xy 358.589293 -282.58414) (xy 358.559269 -282.628177)
			(xy 358.523017 -282.667248) (xy 358.481346 -282.700479) (xy 358.435188 -282.727128) (xy 358.385574 -282.7466)
			(xy 358.333612 -282.75846) (xy 358.280462 -282.762444) (xy 358.227312 -282.75846) (xy 358.17535 -282.7466)
			(xy 358.125736 -282.727128) (xy 358.079578 -282.700479) (xy 358.037907 -282.667248) (xy 358.001655 -282.628177)
			(xy 357.971631 -282.58414) (xy 357.948505 -282.536119) (xy 357.932795 -282.485189) (xy 357.924852 -282.432485)
			(xy 355.816672 -282.432485) (xy 355.808729 -282.485189) (xy 355.793019 -282.536119) (xy 355.769893 -282.58414)
			(xy 355.739869 -282.628177) (xy 355.703617 -282.667248) (xy 355.661946 -282.700479) (xy 355.615788 -282.727128)
			(xy 355.566174 -282.7466) (xy 355.514212 -282.75846) (xy 355.461062 -282.762444) (xy 355.407912 -282.75846)
			(xy 355.35595 -282.7466) (xy 355.306336 -282.727128) (xy 355.260178 -282.700479) (xy 355.218507 -282.667248)
			(xy 355.182255 -282.628177) (xy 355.152231 -282.58414) (xy 355.129105 -282.536119) (xy 355.113395 -282.485189)
			(xy 355.105452 -282.432485) (xy 354.876872 -282.432485) (xy 354.868929 -282.485189) (xy 354.853219 -282.536119)
			(xy 354.830093 -282.58414) (xy 354.800069 -282.628177) (xy 354.763817 -282.667248) (xy 354.722146 -282.700479)
			(xy 354.675988 -282.727128) (xy 354.626374 -282.7466) (xy 354.574412 -282.75846) (xy 354.521262 -282.762444)
			(xy 354.468112 -282.75846) (xy 354.41615 -282.7466) (xy 354.366536 -282.727128) (xy 354.320378 -282.700479)
			(xy 354.278707 -282.667248) (xy 354.242455 -282.628177) (xy 354.212431 -282.58414) (xy 354.189305 -282.536119)
			(xy 354.173595 -282.485189) (xy 354.165652 -282.432485) (xy 354.165154 -282.405836) (xy 354.165527 -282.38259)
			(xy 354.171567 -282.336494) (xy 354.183549 -282.291573) (xy 354.192078 -282.269946) (xy 354.20173 -282.246832)
			(xy 354.154232 -282.165044) (xy 354.14719 -282.15374) (xy 354.128354 -282.134929) (xy 354.105297 -282.121623)
			(xy 354.079585 -282.114726) (xy 354.052964 -282.114706) (xy 354.027241 -282.121566) (xy 354.004165 -282.134838)
			(xy 353.994466 -282.143962) (xy 353.898454 -282.239974) (xy 353.911154 -282.271216) (xy 353.919523 -282.292661)
			(xy 353.931292 -282.337167) (xy 353.937223 -282.382818) (xy 353.93757 -282.405836) (xy 353.937123 -282.43145)
			(xy 353.929781 -282.48215) (xy 353.915252 -282.531276) (xy 353.893837 -282.577814) (xy 353.865977 -282.620804)
			(xy 353.832247 -282.659362) (xy 353.793342 -282.69269) (xy 353.750065 -282.720103) (xy 353.703308 -282.741035)
			(xy 353.654034 -282.755053) (xy 353.628706 -282.758896) (xy 353.604068 -282.762198) (xy 353.431348 -283.060902)
			(xy 353.441 -283.084016) (xy 353.449517 -283.105648) (xy 353.461506 -283.150565) (xy 353.467552 -283.196661)
			(xy 353.467924 -283.219906) (xy 353.467401 -283.246555) (xy 353.695752 -283.246555) (xy 353.695752 -283.193257)
			(xy 353.703695 -283.140553) (xy 353.719405 -283.089623) (xy 353.742531 -283.041602) (xy 353.772555 -282.997565)
			(xy 353.808807 -282.958494) (xy 353.850478 -282.925263) (xy 353.896636 -282.898614) (xy 353.94625 -282.879142)
			(xy 353.998212 -282.867282) (xy 354.051362 -282.863299) (xy 354.104512 -282.867282) (xy 354.156474 -282.879142)
			(xy 354.206088 -282.898614) (xy 354.252246 -282.925263) (xy 354.293917 -282.958494) (xy 354.330169 -282.997565)
			(xy 354.360193 -283.041602) (xy 354.383319 -283.089623) (xy 354.399029 -283.140553) (xy 354.406972 -283.193257)
			(xy 354.40747 -283.219906) (xy 354.406972 -283.246555) (xy 354.635806 -283.246555) (xy 354.635806 -283.193257)
			(xy 354.643749 -283.140553) (xy 354.659459 -283.089623) (xy 354.682585 -283.041602) (xy 354.712609 -282.997565)
			(xy 354.748861 -282.958494) (xy 354.790532 -282.925263) (xy 354.83669 -282.898614) (xy 354.886304 -282.879142)
			(xy 354.938266 -282.867282) (xy 354.991416 -282.863299) (xy 355.044566 -282.867282) (xy 355.096528 -282.879142)
			(xy 355.146142 -282.898614) (xy 355.1923 -282.925263) (xy 355.233971 -282.958494) (xy 355.270223 -282.997565)
			(xy 355.300247 -283.041602) (xy 355.323373 -283.089623) (xy 355.339083 -283.140553) (xy 355.347026 -283.193257)
			(xy 355.347524 -283.219906) (xy 355.347026 -283.246555) (xy 361.214152 -283.246555) (xy 361.214152 -283.193257)
			(xy 361.222095 -283.140553) (xy 361.237805 -283.089623) (xy 361.260931 -283.041602) (xy 361.290955 -282.997565)
			(xy 361.327207 -282.958494) (xy 361.368878 -282.925263) (xy 361.415036 -282.898614) (xy 361.46465 -282.879142)
			(xy 361.516612 -282.867282) (xy 361.569762 -282.863299) (xy 361.622912 -282.867282) (xy 361.674874 -282.879142)
			(xy 361.724488 -282.898614) (xy 361.770646 -282.925263) (xy 361.812317 -282.958494) (xy 361.848569 -282.997565)
			(xy 361.878593 -283.041602) (xy 361.901719 -283.089623) (xy 361.917429 -283.140553) (xy 361.925372 -283.193257)
			(xy 361.92587 -283.219906) (xy 361.925372 -283.246555) (xy 364.033806 -283.246555) (xy 364.033806 -283.193257)
			(xy 364.041749 -283.140553) (xy 364.057459 -283.089623) (xy 364.080585 -283.041602) (xy 364.110609 -282.997565)
			(xy 364.146861 -282.958494) (xy 364.188532 -282.925263) (xy 364.23469 -282.898614) (xy 364.284304 -282.879142)
			(xy 364.336266 -282.867282) (xy 364.389416 -282.863299) (xy 364.442566 -282.867282) (xy 364.494528 -282.879142)
			(xy 364.544142 -282.898614) (xy 364.5903 -282.925263) (xy 364.631971 -282.958494) (xy 364.668223 -282.997565)
			(xy 364.698247 -283.041602) (xy 364.721373 -283.089623) (xy 364.737083 -283.140553) (xy 364.745026 -283.193257)
			(xy 364.745524 -283.219906) (xy 364.745026 -283.246555) (xy 364.737083 -283.299259) (xy 364.721373 -283.350189)
			(xy 364.698247 -283.39821) (xy 364.668223 -283.442247) (xy 364.631971 -283.481318) (xy 364.5903 -283.514549)
			(xy 364.544142 -283.541198) (xy 364.494528 -283.56067) (xy 364.442566 -283.57253) (xy 364.389416 -283.576514)
			(xy 364.336266 -283.57253) (xy 364.284304 -283.56067) (xy 364.23469 -283.541198) (xy 364.188532 -283.514549)
			(xy 364.146861 -283.481318) (xy 364.110609 -283.442247) (xy 364.080585 -283.39821) (xy 364.057459 -283.350189)
			(xy 364.041749 -283.299259) (xy 364.033806 -283.246555) (xy 361.925372 -283.246555) (xy 361.917429 -283.299259)
			(xy 361.901719 -283.350189) (xy 361.878593 -283.39821) (xy 361.848569 -283.442247) (xy 361.812317 -283.481318)
			(xy 361.770646 -283.514549) (xy 361.724488 -283.541198) (xy 361.674874 -283.56067) (xy 361.622912 -283.57253)
			(xy 361.569762 -283.576514) (xy 361.516612 -283.57253) (xy 361.46465 -283.56067) (xy 361.415036 -283.541198)
			(xy 361.368878 -283.514549) (xy 361.327207 -283.481318) (xy 361.290955 -283.442247) (xy 361.260931 -283.39821)
			(xy 361.237805 -283.350189) (xy 361.222095 -283.299259) (xy 361.214152 -283.246555) (xy 355.347026 -283.246555)
			(xy 355.339083 -283.299259) (xy 355.323373 -283.350189) (xy 355.300247 -283.39821) (xy 355.270223 -283.442247)
			(xy 355.233971 -283.481318) (xy 355.1923 -283.514549) (xy 355.146142 -283.541198) (xy 355.096528 -283.56067)
			(xy 355.044566 -283.57253) (xy 354.991416 -283.576514) (xy 354.938266 -283.57253) (xy 354.886304 -283.56067)
			(xy 354.83669 -283.541198) (xy 354.790532 -283.514549) (xy 354.748861 -283.481318) (xy 354.712609 -283.442247)
			(xy 354.682585 -283.39821) (xy 354.659459 -283.350189) (xy 354.643749 -283.299259) (xy 354.635806 -283.246555)
			(xy 354.406972 -283.246555) (xy 354.399029 -283.299259) (xy 354.383319 -283.350189) (xy 354.360193 -283.39821)
			(xy 354.330169 -283.442247) (xy 354.293917 -283.481318) (xy 354.252246 -283.514549) (xy 354.206088 -283.541198)
			(xy 354.156474 -283.56067) (xy 354.104512 -283.57253) (xy 354.051362 -283.576514) (xy 353.998212 -283.57253)
			(xy 353.94625 -283.56067) (xy 353.896636 -283.541198) (xy 353.850478 -283.514549) (xy 353.808807 -283.481318)
			(xy 353.772555 -283.442247) (xy 353.742531 -283.39821) (xy 353.719405 -283.350189) (xy 353.703695 -283.299259)
			(xy 353.695752 -283.246555) (xy 353.467401 -283.246555) (xy 353.467375 -283.247889) (xy 353.458619 -283.303167)
			(xy 353.441324 -283.356394) (xy 353.415916 -283.40626) (xy 353.38302 -283.451539) (xy 353.343446 -283.491113)
			(xy 353.298169 -283.524011) (xy 353.248303 -283.54942) (xy 353.195076 -283.566717) (xy 353.139799 -283.575474)
			(xy 353.111816 -283.576014) (xy 353.086225 -283.575551) (xy 353.035575 -283.568187) (xy 352.9865 -283.553652)
			(xy 352.94001 -283.532245) (xy 352.897061 -283.504406) (xy 352.858537 -283.470708) (xy 352.84156 -283.451554)
			(xy 352.832119 -283.441217) (xy 352.808822 -283.42571) (xy 352.782191 -283.417107) (xy 352.754225 -283.416054)
			(xy 352.727023 -283.42263) (xy 352.702626 -283.43634) (xy 352.692462 -283.445966) (xy 352.630232 -283.508196)
			(xy 352.62055 -283.518515) (xy 352.606789 -283.543228) (xy 352.600347 -283.570771) (xy 352.601719 -283.599023)
			(xy 352.610799 -283.625812) (xy 352.626888 -283.649076) (xy 352.64875 -283.667025) (xy 352.674701 -283.678277)
			(xy 352.688652 -283.680662) (xy 352.713997 -283.684484) (xy 352.76331 -283.698459) (xy 352.81011 -283.71936)
			(xy 352.85343 -283.746756) (xy 352.892373 -283.780081) (xy 352.926135 -283.818645) (xy 352.954019 -283.861652)
			(xy 352.975447 -283.908213) (xy 352.989978 -283.957366) (xy 352.99731 -284.008094) (xy 352.99777 -284.033722)
			(xy 352.997273 -284.060371) (xy 353.225852 -284.060371) (xy 353.225852 -284.007073) (xy 353.233795 -283.954369)
			(xy 353.249505 -283.903439) (xy 353.272631 -283.855418) (xy 353.302655 -283.811381) (xy 353.338907 -283.77231)
			(xy 353.380578 -283.739079) (xy 353.426736 -283.71243) (xy 353.47635 -283.692958) (xy 353.528312 -283.681098)
			(xy 353.581462 -283.677115) (xy 353.634612 -283.681098) (xy 353.686574 -283.692958) (xy 353.736188 -283.71243)
			(xy 353.782346 -283.739079) (xy 353.824017 -283.77231) (xy 353.860269 -283.811381) (xy 353.890293 -283.855418)
			(xy 353.913419 -283.903439) (xy 353.929129 -283.954369) (xy 353.937072 -284.007073) (xy 353.93757 -284.033722)
			(xy 353.937072 -284.060371) (xy 355.105452 -284.060371) (xy 355.105452 -284.007073) (xy 355.113395 -283.954369)
			(xy 355.129105 -283.903439) (xy 355.152231 -283.855418) (xy 355.182255 -283.811381) (xy 355.218507 -283.77231)
			(xy 355.260178 -283.739079) (xy 355.306336 -283.71243) (xy 355.35595 -283.692958) (xy 355.407912 -283.681098)
			(xy 355.461062 -283.677115) (xy 355.514212 -283.681098) (xy 355.566174 -283.692958) (xy 355.615788 -283.71243)
			(xy 355.661946 -283.739079) (xy 355.703617 -283.77231) (xy 355.739869 -283.811381) (xy 355.769893 -283.855418)
			(xy 355.793019 -283.903439) (xy 355.808729 -283.954369) (xy 355.816672 -284.007073) (xy 355.81717 -284.033722)
			(xy 355.816672 -284.060371) (xy 357.924852 -284.060371) (xy 357.924852 -284.007073) (xy 357.932795 -283.954369)
			(xy 357.948505 -283.903439) (xy 357.971631 -283.855418) (xy 358.001655 -283.811381) (xy 358.037907 -283.77231)
			(xy 358.079578 -283.739079) (xy 358.125736 -283.71243) (xy 358.17535 -283.692958) (xy 358.227312 -283.681098)
			(xy 358.280462 -283.677115) (xy 358.333612 -283.681098) (xy 358.385574 -283.692958) (xy 358.435188 -283.71243)
			(xy 358.481346 -283.739079) (xy 358.523017 -283.77231) (xy 358.559269 -283.811381) (xy 358.589293 -283.855418)
			(xy 358.612419 -283.903439) (xy 358.628129 -283.954369) (xy 358.636072 -284.007073) (xy 358.63657 -284.033722)
			(xy 358.636072 -284.060371) (xy 358.628129 -284.113075) (xy 358.612419 -284.164005) (xy 358.589293 -284.212026)
			(xy 358.559269 -284.256063) (xy 358.523017 -284.295134) (xy 358.481346 -284.328365) (xy 358.435188 -284.355014)
			(xy 358.385574 -284.374486) (xy 358.333612 -284.386346) (xy 358.280462 -284.39033) (xy 358.227312 -284.386346)
			(xy 358.17535 -284.374486) (xy 358.125736 -284.355014) (xy 358.079578 -284.328365) (xy 358.037907 -284.295134)
			(xy 358.001655 -284.256063) (xy 357.971631 -284.212026) (xy 357.948505 -284.164005) (xy 357.932795 -284.113075)
			(xy 357.924852 -284.060371) (xy 355.816672 -284.060371) (xy 355.808729 -284.113075) (xy 355.793019 -284.164005)
			(xy 355.769893 -284.212026) (xy 355.739869 -284.256063) (xy 355.703617 -284.295134) (xy 355.661946 -284.328365)
			(xy 355.615788 -284.355014) (xy 355.566174 -284.374486) (xy 355.514212 -284.386346) (xy 355.461062 -284.39033)
			(xy 355.407912 -284.386346) (xy 355.35595 -284.374486) (xy 355.306336 -284.355014) (xy 355.260178 -284.328365)
			(xy 355.218507 -284.295134) (xy 355.182255 -284.256063) (xy 355.152231 -284.212026) (xy 355.129105 -284.164005)
			(xy 355.113395 -284.113075) (xy 355.105452 -284.060371) (xy 353.937072 -284.060371) (xy 353.929129 -284.113075)
			(xy 353.913419 -284.164005) (xy 353.890293 -284.212026) (xy 353.860269 -284.256063) (xy 353.824017 -284.295134)
			(xy 353.782346 -284.328365) (xy 353.736188 -284.355014) (xy 353.686574 -284.374486) (xy 353.634612 -284.386346)
			(xy 353.581462 -284.39033) (xy 353.528312 -284.386346) (xy 353.47635 -284.374486) (xy 353.426736 -284.355014)
			(xy 353.380578 -284.328365) (xy 353.338907 -284.295134) (xy 353.302655 -284.256063) (xy 353.272631 -284.212026)
			(xy 353.249505 -284.164005) (xy 353.233795 -284.113075) (xy 353.225852 -284.060371) (xy 352.997273 -284.060371)
			(xy 352.997248 -284.061705) (xy 352.988489 -284.116982) (xy 352.971191 -284.170208) (xy 352.945779 -284.220072)
			(xy 352.912879 -284.265347) (xy 352.873302 -284.304918) (xy 352.828021 -284.33781) (xy 352.778152 -284.363214)
			(xy 352.724923 -284.380503) (xy 352.669645 -284.389252) (xy 352.641662 -284.38983) (xy 352.615246 -284.388814)
			(xy 352.601312 -284.388239) (xy 352.574 -284.39382) (xy 352.549215 -284.406582) (xy 352.528808 -284.425574)
			(xy 352.5143 -284.449379) (xy 352.506774 -284.476221) (xy 352.50628 -284.49016) (xy 352.50628 -284.724348)
			(xy 352.509074 -284.732476) (xy 352.517958 -284.760409) (xy 352.527533 -284.818233) (xy 352.528124 -284.847538)
			(xy 352.527604 -284.874187) (xy 352.755952 -284.874187) (xy 352.755952 -284.820889) (xy 352.763895 -284.768185)
			(xy 352.779605 -284.717255) (xy 352.802731 -284.669234) (xy 352.832755 -284.625197) (xy 352.869007 -284.586126)
			(xy 352.910678 -284.552895) (xy 352.956836 -284.526246) (xy 353.00645 -284.506774) (xy 353.058412 -284.494914)
			(xy 353.111562 -284.490931) (xy 353.164712 -284.494914) (xy 353.216674 -284.506774) (xy 353.266288 -284.526246)
			(xy 353.312446 -284.552895) (xy 353.354117 -284.586126) (xy 353.390369 -284.625197) (xy 353.420393 -284.669234)
			(xy 353.443519 -284.717255) (xy 353.459229 -284.768185) (xy 353.467172 -284.820889) (xy 353.46767 -284.847538)
			(xy 353.467172 -284.874187) (xy 361.214152 -284.874187) (xy 361.214152 -284.820889) (xy 361.222095 -284.768185)
			(xy 361.237805 -284.717255) (xy 361.260931 -284.669234) (xy 361.290955 -284.625197) (xy 361.327207 -284.586126)
			(xy 361.368878 -284.552895) (xy 361.415036 -284.526246) (xy 361.46465 -284.506774) (xy 361.516612 -284.494914)
			(xy 361.569762 -284.490931) (xy 361.622912 -284.494914) (xy 361.674874 -284.506774) (xy 361.724488 -284.526246)
			(xy 361.770646 -284.552895) (xy 361.812317 -284.586126) (xy 361.848569 -284.625197) (xy 361.878593 -284.669234)
			(xy 361.901719 -284.717255) (xy 361.917429 -284.768185) (xy 361.925372 -284.820889) (xy 361.92587 -284.847538)
			(xy 361.925372 -284.874187) (xy 364.033806 -284.874187) (xy 364.033806 -284.820889) (xy 364.041749 -284.768185)
			(xy 364.057459 -284.717255) (xy 364.080585 -284.669234) (xy 364.110609 -284.625197) (xy 364.146861 -284.586126)
			(xy 364.188532 -284.552895) (xy 364.23469 -284.526246) (xy 364.284304 -284.506774) (xy 364.336266 -284.494914)
			(xy 364.389416 -284.490931) (xy 364.442566 -284.494914) (xy 364.494528 -284.506774) (xy 364.544142 -284.526246)
			(xy 364.5903 -284.552895) (xy 364.631971 -284.586126) (xy 364.668223 -284.625197) (xy 364.698247 -284.669234)
			(xy 364.721373 -284.717255) (xy 364.737083 -284.768185) (xy 364.745026 -284.820889) (xy 364.745524 -284.847538)
			(xy 364.745026 -284.874187) (xy 365.913406 -284.874187) (xy 365.913406 -284.820889) (xy 365.921349 -284.768185)
			(xy 365.937059 -284.717255) (xy 365.960185 -284.669234) (xy 365.990209 -284.625197) (xy 366.026461 -284.586126)
			(xy 366.068132 -284.552895) (xy 366.11429 -284.526246) (xy 366.163904 -284.506774) (xy 366.215866 -284.494914)
			(xy 366.269016 -284.490931) (xy 366.322166 -284.494914) (xy 366.374128 -284.506774) (xy 366.423742 -284.526246)
			(xy 366.4699 -284.552895) (xy 366.511571 -284.586126) (xy 366.547823 -284.625197) (xy 366.577847 -284.669234)
			(xy 366.600973 -284.717255) (xy 366.616683 -284.768185) (xy 366.624626 -284.820889) (xy 366.625124 -284.847538)
			(xy 366.624626 -284.874187) (xy 366.616683 -284.926891) (xy 366.600973 -284.977821) (xy 366.577847 -285.025842)
			(xy 366.547823 -285.069879) (xy 366.511571 -285.10895) (xy 366.4699 -285.142181) (xy 366.423742 -285.16883)
			(xy 366.374128 -285.188302) (xy 366.322166 -285.200162) (xy 366.269016 -285.204146) (xy 366.215866 -285.200162)
			(xy 366.163904 -285.188302) (xy 366.11429 -285.16883) (xy 366.068132 -285.142181) (xy 366.026461 -285.10895)
			(xy 365.990209 -285.069879) (xy 365.960185 -285.025842) (xy 365.937059 -284.977821) (xy 365.921349 -284.926891)
			(xy 365.913406 -284.874187) (xy 364.745026 -284.874187) (xy 364.737083 -284.926891) (xy 364.721373 -284.977821)
			(xy 364.698247 -285.025842) (xy 364.668223 -285.069879) (xy 364.631971 -285.10895) (xy 364.5903 -285.142181)
			(xy 364.544142 -285.16883) (xy 364.494528 -285.188302) (xy 364.442566 -285.200162) (xy 364.389416 -285.204146)
			(xy 364.336266 -285.200162) (xy 364.284304 -285.188302) (xy 364.23469 -285.16883) (xy 364.188532 -285.142181)
			(xy 364.146861 -285.10895) (xy 364.110609 -285.069879) (xy 364.080585 -285.025842) (xy 364.057459 -284.977821)
			(xy 364.041749 -284.926891) (xy 364.033806 -284.874187) (xy 361.925372 -284.874187) (xy 361.917429 -284.926891)
			(xy 361.901719 -284.977821) (xy 361.878593 -285.025842) (xy 361.848569 -285.069879) (xy 361.812317 -285.10895)
			(xy 361.770646 -285.142181) (xy 361.724488 -285.16883) (xy 361.674874 -285.188302) (xy 361.622912 -285.200162)
			(xy 361.569762 -285.204146) (xy 361.516612 -285.200162) (xy 361.46465 -285.188302) (xy 361.415036 -285.16883)
			(xy 361.368878 -285.142181) (xy 361.327207 -285.10895) (xy 361.290955 -285.069879) (xy 361.260931 -285.025842)
			(xy 361.237805 -284.977821) (xy 361.222095 -284.926891) (xy 361.214152 -284.874187) (xy 353.467172 -284.874187)
			(xy 353.459229 -284.926891) (xy 353.443519 -284.977821) (xy 353.420393 -285.025842) (xy 353.390369 -285.069879)
			(xy 353.354117 -285.10895) (xy 353.312446 -285.142181) (xy 353.266288 -285.16883) (xy 353.216674 -285.188302)
			(xy 353.164712 -285.200162) (xy 353.111562 -285.204146) (xy 353.058412 -285.200162) (xy 353.00645 -285.188302)
			(xy 352.956836 -285.16883) (xy 352.910678 -285.142181) (xy 352.869007 -285.10895) (xy 352.832755 -285.069879)
			(xy 352.802731 -285.025842) (xy 352.779605 -284.977821) (xy 352.763895 -284.926891) (xy 352.755952 -284.874187)
			(xy 352.527604 -284.874187) (xy 352.527552 -284.876846) (xy 352.517981 -284.934673) (xy 352.509074 -284.9626)
			(xy 352.50628 -284.970728) (xy 352.50628 -285.204916) (xy 352.506716 -285.218857) (xy 352.51426 -285.2457)
			(xy 352.528782 -285.269502) (xy 352.549199 -285.28849) (xy 352.573991 -285.30125) (xy 352.601309 -285.30683)
			(xy 352.615246 -285.306262) (xy 352.641662 -285.305246) (xy 352.668318 -285.305717) (xy 352.721037 -285.313657)
			(xy 352.771982 -285.329367) (xy 352.820017 -285.352495) (xy 352.864068 -285.382524) (xy 352.903151 -285.418784)
			(xy 352.936393 -285.460464) (xy 352.963051 -285.506633) (xy 352.98253 -285.55626) (xy 352.994394 -285.608236)
			(xy 352.998378 -285.6614) (xy 352.996384 -285.688003) (xy 355.105452 -285.688003) (xy 355.105452 -285.634705)
			(xy 355.113395 -285.582001) (xy 355.129105 -285.531071) (xy 355.152231 -285.48305) (xy 355.182255 -285.439013)
			(xy 355.218507 -285.399942) (xy 355.260178 -285.366711) (xy 355.306336 -285.340062) (xy 355.35595 -285.32059)
			(xy 355.407912 -285.30873) (xy 355.461062 -285.304747) (xy 355.514212 -285.30873) (xy 355.566174 -285.32059)
			(xy 355.615788 -285.340062) (xy 355.661946 -285.366711) (xy 355.703617 -285.399942) (xy 355.739869 -285.439013)
			(xy 355.769893 -285.48305) (xy 355.793019 -285.531071) (xy 355.808729 -285.582001) (xy 355.816672 -285.634705)
			(xy 355.81717 -285.661354) (xy 355.816672 -285.688003) (xy 357.924852 -285.688003) (xy 357.924852 -285.634705)
			(xy 357.932795 -285.582001) (xy 357.948505 -285.531071) (xy 357.971631 -285.48305) (xy 358.001655 -285.439013)
			(xy 358.037907 -285.399942) (xy 358.079578 -285.366711) (xy 358.125736 -285.340062) (xy 358.17535 -285.32059)
			(xy 358.227312 -285.30873) (xy 358.280462 -285.304747) (xy 358.333612 -285.30873) (xy 358.385574 -285.32059)
			(xy 358.435188 -285.340062) (xy 358.481346 -285.366711) (xy 358.523017 -285.399942) (xy 358.559269 -285.439013)
			(xy 358.589293 -285.48305) (xy 358.612419 -285.531071) (xy 358.628129 -285.582001) (xy 358.636072 -285.634705)
			(xy 358.63657 -285.661354) (xy 358.636072 -285.688003) (xy 366.383306 -285.688003) (xy 366.383306 -285.634705)
			(xy 366.391249 -285.582001) (xy 366.406959 -285.531071) (xy 366.430085 -285.48305) (xy 366.460109 -285.439013)
			(xy 366.496361 -285.399942) (xy 366.538032 -285.366711) (xy 366.58419 -285.340062) (xy 366.633804 -285.32059)
			(xy 366.685766 -285.30873) (xy 366.738916 -285.304747) (xy 366.792066 -285.30873) (xy 366.844028 -285.32059)
			(xy 366.893642 -285.340062) (xy 366.9398 -285.366711) (xy 366.981471 -285.399942) (xy 367.017723 -285.439013)
			(xy 367.047747 -285.48305) (xy 367.070873 -285.531071) (xy 367.086583 -285.582001) (xy 367.094526 -285.634705)
			(xy 367.095024 -285.661354) (xy 367.094526 -285.688003) (xy 367.086583 -285.740707) (xy 367.070873 -285.791637)
			(xy 367.047747 -285.839658) (xy 367.017723 -285.883695) (xy 366.981471 -285.922766) (xy 366.9398 -285.955997)
			(xy 366.893642 -285.982646) (xy 366.844028 -286.002118) (xy 366.792066 -286.013978) (xy 366.738916 -286.017962)
			(xy 366.685766 -286.013978) (xy 366.633804 -286.002118) (xy 366.58419 -285.982646) (xy 366.538032 -285.955997)
			(xy 366.496361 -285.922766) (xy 366.460109 -285.883695) (xy 366.430085 -285.839658) (xy 366.406959 -285.791637)
			(xy 366.391249 -285.740707) (xy 366.383306 -285.688003) (xy 358.636072 -285.688003) (xy 358.628129 -285.740707)
			(xy 358.612419 -285.791637) (xy 358.589293 -285.839658) (xy 358.559269 -285.883695) (xy 358.523017 -285.922766)
			(xy 358.481346 -285.955997) (xy 358.435188 -285.982646) (xy 358.385574 -286.002118) (xy 358.333612 -286.013978)
			(xy 358.280462 -286.017962) (xy 358.227312 -286.013978) (xy 358.17535 -286.002118) (xy 358.125736 -285.982646)
			(xy 358.079578 -285.955997) (xy 358.037907 -285.922766) (xy 358.001655 -285.883695) (xy 357.971631 -285.839658)
			(xy 357.948505 -285.791637) (xy 357.932795 -285.740707) (xy 357.924852 -285.688003) (xy 355.816672 -285.688003)
			(xy 355.808729 -285.740707) (xy 355.793019 -285.791637) (xy 355.769893 -285.839658) (xy 355.739869 -285.883695)
			(xy 355.703617 -285.922766) (xy 355.661946 -285.955997) (xy 355.615788 -285.982646) (xy 355.566174 -286.002118)
			(xy 355.514212 -286.013978) (xy 355.461062 -286.017962) (xy 355.407912 -286.013978) (xy 355.35595 -286.002118)
			(xy 355.306336 -285.982646) (xy 355.260178 -285.955997) (xy 355.218507 -285.922766) (xy 355.182255 -285.883695)
			(xy 355.152231 -285.839658) (xy 355.129105 -285.791637) (xy 355.113395 -285.740707) (xy 355.105452 -285.688003)
			(xy 352.996384 -285.688003) (xy 352.994394 -285.714564) (xy 352.98253 -285.76654) (xy 352.963051 -285.816167)
			(xy 352.936393 -285.862336) (xy 352.903151 -285.904016) (xy 352.864068 -285.940276) (xy 352.820017 -285.970305)
			(xy 352.771982 -285.993433) (xy 352.721037 -286.009143) (xy 352.668318 -286.017083) (xy 352.641662 -286.017462)
			(xy 352.615246 -286.016446) (xy 352.601309 -286.01587) (xy 352.573989 -286.021451) (xy 352.549197 -286.034212)
			(xy 352.528779 -286.053202) (xy 352.514258 -286.077006) (xy 352.506715 -286.10385) (xy 352.50628 -286.117792)
			(xy 352.50628 -286.352996) (xy 352.509074 -286.36087) (xy 352.517888 -286.388683) (xy 352.52734 -286.446253)
			(xy 352.52787 -286.475424) (xy 352.527349 -286.502073) (xy 352.756206 -286.502073) (xy 352.756206 -286.448775)
			(xy 352.764149 -286.396071) (xy 352.779859 -286.345141) (xy 352.802985 -286.29712) (xy 352.833009 -286.253083)
			(xy 352.869261 -286.214012) (xy 352.910932 -286.180781) (xy 352.95709 -286.154132) (xy 353.006704 -286.13466)
			(xy 353.058666 -286.1228) (xy 353.111816 -286.118817) (xy 353.164966 -286.1228) (xy 353.216928 -286.13466)
			(xy 353.266542 -286.154132) (xy 353.3127 -286.180781) (xy 353.354371 -286.214012) (xy 353.390623 -286.253083)
			(xy 353.420647 -286.29712) (xy 353.443773 -286.345141) (xy 353.459483 -286.396071) (xy 353.467426 -286.448775)
			(xy 353.467924 -286.475424) (xy 353.467426 -286.502073) (xy 361.214152 -286.502073) (xy 361.214152 -286.448775)
			(xy 361.222095 -286.396071) (xy 361.237805 -286.345141) (xy 361.260931 -286.29712) (xy 361.290955 -286.253083)
			(xy 361.327207 -286.214012) (xy 361.368878 -286.180781) (xy 361.415036 -286.154132) (xy 361.46465 -286.13466)
			(xy 361.516612 -286.1228) (xy 361.569762 -286.118817) (xy 361.622912 -286.1228) (xy 361.674874 -286.13466)
			(xy 361.724488 -286.154132) (xy 361.770646 -286.180781) (xy 361.812317 -286.214012) (xy 361.848569 -286.253083)
			(xy 361.878593 -286.29712) (xy 361.901719 -286.345141) (xy 361.917429 -286.396071) (xy 361.925372 -286.448775)
			(xy 361.92587 -286.475424) (xy 361.925372 -286.502073) (xy 364.033806 -286.502073) (xy 364.033806 -286.448775)
			(xy 364.041749 -286.396071) (xy 364.057459 -286.345141) (xy 364.080585 -286.29712) (xy 364.110609 -286.253083)
			(xy 364.146861 -286.214012) (xy 364.188532 -286.180781) (xy 364.23469 -286.154132) (xy 364.284304 -286.13466)
			(xy 364.336266 -286.1228) (xy 364.389416 -286.118817) (xy 364.442566 -286.1228) (xy 364.494528 -286.13466)
			(xy 364.544142 -286.154132) (xy 364.5903 -286.180781) (xy 364.631971 -286.214012) (xy 364.668223 -286.253083)
			(xy 364.698247 -286.29712) (xy 364.721373 -286.345141) (xy 364.737083 -286.396071) (xy 364.745026 -286.448775)
			(xy 364.745524 -286.475424) (xy 364.745026 -286.502073) (xy 364.737083 -286.554777) (xy 364.721373 -286.605707)
			(xy 364.698247 -286.653728) (xy 364.668223 -286.697765) (xy 364.631971 -286.736836) (xy 364.5903 -286.770067)
			(xy 364.544142 -286.796716) (xy 364.494528 -286.816188) (xy 364.442566 -286.828048) (xy 364.389416 -286.832032)
			(xy 364.336266 -286.828048) (xy 364.284304 -286.816188) (xy 364.23469 -286.796716) (xy 364.188532 -286.770067)
			(xy 364.146861 -286.736836) (xy 364.110609 -286.697765) (xy 364.080585 -286.653728) (xy 364.057459 -286.605707)
			(xy 364.041749 -286.554777) (xy 364.033806 -286.502073) (xy 361.925372 -286.502073) (xy 361.917429 -286.554777)
			(xy 361.901719 -286.605707) (xy 361.878593 -286.653728) (xy 361.848569 -286.697765) (xy 361.812317 -286.736836)
			(xy 361.770646 -286.770067) (xy 361.724488 -286.796716) (xy 361.674874 -286.816188) (xy 361.622912 -286.828048)
			(xy 361.569762 -286.832032) (xy 361.516612 -286.828048) (xy 361.46465 -286.816188) (xy 361.415036 -286.796716)
			(xy 361.368878 -286.770067) (xy 361.327207 -286.736836) (xy 361.290955 -286.697765) (xy 361.260931 -286.653728)
			(xy 361.237805 -286.605707) (xy 361.222095 -286.554777) (xy 361.214152 -286.502073) (xy 353.467426 -286.502073)
			(xy 353.459483 -286.554777) (xy 353.443773 -286.605707) (xy 353.420647 -286.653728) (xy 353.390623 -286.697765)
			(xy 353.354371 -286.736836) (xy 353.3127 -286.770067) (xy 353.266542 -286.796716) (xy 353.216928 -286.816188)
			(xy 353.164966 -286.828048) (xy 353.111816 -286.832032) (xy 353.058666 -286.828048) (xy 353.006704 -286.816188)
			(xy 352.95709 -286.796716) (xy 352.910932 -286.770067) (xy 352.869261 -286.736836) (xy 352.833009 -286.697765)
			(xy 352.802985 -286.653728) (xy 352.779859 -286.605707) (xy 352.764149 -286.554777) (xy 352.756206 -286.502073)
			(xy 352.527349 -286.502073) (xy 352.5273 -286.504592) (xy 352.517849 -286.562156) (xy 352.509074 -286.589978)
			(xy 352.50628 -286.597852) (xy 352.50628 -286.832802) (xy 352.506717 -286.846765) (xy 352.514281 -286.873649)
			(xy 352.528844 -286.897478) (xy 352.549317 -286.916472) (xy 352.574169 -286.929212) (xy 352.601542 -286.934744)
			(xy 352.6155 -286.934148) (xy 352.641916 -286.933132) (xy 352.668562 -286.933631) (xy 352.721257 -286.941576)
			(xy 352.77218 -286.957286) (xy 352.820193 -286.980409) (xy 352.864223 -287.01043) (xy 352.903287 -287.046678)
			(xy 352.936513 -287.088344) (xy 352.963158 -287.134496) (xy 352.982627 -287.184103) (xy 352.994485 -287.236058)
			(xy 352.998467 -287.2892) (xy 352.996467 -287.315889) (xy 355.105452 -287.315889) (xy 355.105452 -287.262591)
			(xy 355.113395 -287.209887) (xy 355.129105 -287.158957) (xy 355.152231 -287.110936) (xy 355.182255 -287.066899)
			(xy 355.218507 -287.027828) (xy 355.260178 -286.994597) (xy 355.306336 -286.967948) (xy 355.35595 -286.948476)
			(xy 355.407912 -286.936616) (xy 355.461062 -286.932633) (xy 355.514212 -286.936616) (xy 355.566174 -286.948476)
			(xy 355.615788 -286.967948) (xy 355.661946 -286.994597) (xy 355.703617 -287.027828) (xy 355.739869 -287.066899)
			(xy 355.769893 -287.110936) (xy 355.793019 -287.158957) (xy 355.808729 -287.209887) (xy 355.816672 -287.262591)
			(xy 355.81717 -287.28924) (xy 355.816672 -287.315889) (xy 357.924852 -287.315889) (xy 357.924852 -287.262591)
			(xy 357.932795 -287.209887) (xy 357.948505 -287.158957) (xy 357.971631 -287.110936) (xy 358.001655 -287.066899)
			(xy 358.037907 -287.027828) (xy 358.079578 -286.994597) (xy 358.125736 -286.967948) (xy 358.17535 -286.948476)
			(xy 358.227312 -286.936616) (xy 358.280462 -286.932633) (xy 358.333612 -286.936616) (xy 358.385574 -286.948476)
			(xy 358.435188 -286.967948) (xy 358.481346 -286.994597) (xy 358.523017 -287.027828) (xy 358.559269 -287.066899)
			(xy 358.589293 -287.110936) (xy 358.612419 -287.158957) (xy 358.628129 -287.209887) (xy 358.636072 -287.262591)
			(xy 358.63657 -287.28924) (xy 358.636072 -287.315889) (xy 358.628129 -287.368593) (xy 358.612419 -287.419523)
			(xy 358.589293 -287.467544) (xy 358.559269 -287.511581) (xy 358.523017 -287.550652) (xy 358.481346 -287.583883)
			(xy 358.435188 -287.610532) (xy 358.385574 -287.630004) (xy 358.333612 -287.641864) (xy 358.280462 -287.645848)
			(xy 358.227312 -287.641864) (xy 358.17535 -287.630004) (xy 358.125736 -287.610532) (xy 358.079578 -287.583883)
			(xy 358.037907 -287.550652) (xy 358.001655 -287.511581) (xy 357.971631 -287.467544) (xy 357.948505 -287.419523)
			(xy 357.932795 -287.368593) (xy 357.924852 -287.315889) (xy 355.816672 -287.315889) (xy 355.808729 -287.368593)
			(xy 355.793019 -287.419523) (xy 355.769893 -287.467544) (xy 355.739869 -287.511581) (xy 355.703617 -287.550652)
			(xy 355.661946 -287.583883) (xy 355.615788 -287.610532) (xy 355.566174 -287.630004) (xy 355.514212 -287.641864)
			(xy 355.461062 -287.645848) (xy 355.407912 -287.641864) (xy 355.35595 -287.630004) (xy 355.306336 -287.610532)
			(xy 355.260178 -287.583883) (xy 355.218507 -287.550652) (xy 355.182255 -287.511581) (xy 355.152231 -287.467544)
			(xy 355.129105 -287.419523) (xy 355.113395 -287.368593) (xy 355.105452 -287.315889) (xy 352.996467 -287.315889)
			(xy 352.994485 -287.342342) (xy 352.982627 -287.394297) (xy 352.963158 -287.443905) (xy 352.936513 -287.490056)
			(xy 352.903287 -287.531722) (xy 352.864223 -287.56797) (xy 352.820193 -287.597991) (xy 352.77218 -287.621114)
			(xy 352.721257 -287.636824) (xy 352.668561 -287.644769) (xy 352.641916 -287.645348) (xy 352.6155 -287.644332)
			(xy 352.601545 -287.643723) (xy 352.574176 -287.649257) (xy 352.549331 -287.662) (xy 352.528868 -287.680999)
			(xy 352.51432 -287.704832) (xy 352.506774 -287.731716) (xy 352.50628 -287.745678) (xy 352.50628 -287.979866)
			(xy 352.509074 -287.987994) (xy 352.517957 -288.015927) (xy 352.527529 -288.073751) (xy 352.528124 -288.103056)
			(xy 352.527602 -288.129705) (xy 352.756206 -288.129705) (xy 352.756206 -288.076407) (xy 352.764149 -288.023703)
			(xy 352.779859 -287.972773) (xy 352.802985 -287.924752) (xy 352.833009 -287.880715) (xy 352.869261 -287.841644)
			(xy 352.910932 -287.808413) (xy 352.95709 -287.781764) (xy 353.006704 -287.762292) (xy 353.058666 -287.750432)
			(xy 353.111816 -287.746449) (xy 353.164966 -287.750432) (xy 353.216928 -287.762292) (xy 353.266542 -287.781764)
			(xy 353.3127 -287.808413) (xy 353.354371 -287.841644) (xy 353.390623 -287.880715) (xy 353.420647 -287.924752)
			(xy 353.443773 -287.972773) (xy 353.459483 -288.023703) (xy 353.467426 -288.076407) (xy 353.467924 -288.103056)
			(xy 353.467426 -288.129705) (xy 361.214152 -288.129705) (xy 361.214152 -288.076407) (xy 361.222095 -288.023703)
			(xy 361.237805 -287.972773) (xy 361.260931 -287.924752) (xy 361.290955 -287.880715) (xy 361.327207 -287.841644)
			(xy 361.368878 -287.808413) (xy 361.415036 -287.781764) (xy 361.46465 -287.762292) (xy 361.516612 -287.750432)
			(xy 361.569762 -287.746449) (xy 361.622912 -287.750432) (xy 361.674874 -287.762292) (xy 361.724488 -287.781764)
			(xy 361.770646 -287.808413) (xy 361.812317 -287.841644) (xy 361.848569 -287.880715) (xy 361.878593 -287.924752)
			(xy 361.901719 -287.972773) (xy 361.917429 -288.023703) (xy 361.925372 -288.076407) (xy 361.92587 -288.103056)
			(xy 361.925372 -288.129705) (xy 364.033806 -288.129705) (xy 364.033806 -288.076407) (xy 364.041749 -288.023703)
			(xy 364.057459 -287.972773) (xy 364.080585 -287.924752) (xy 364.110609 -287.880715) (xy 364.146861 -287.841644)
			(xy 364.188532 -287.808413) (xy 364.23469 -287.781764) (xy 364.284304 -287.762292) (xy 364.336266 -287.750432)
			(xy 364.389416 -287.746449) (xy 364.442566 -287.750432) (xy 364.494528 -287.762292) (xy 364.544142 -287.781764)
			(xy 364.5903 -287.808413) (xy 364.631971 -287.841644) (xy 364.668223 -287.880715) (xy 364.698247 -287.924752)
			(xy 364.721373 -287.972773) (xy 364.737083 -288.023703) (xy 364.745026 -288.076407) (xy 364.745524 -288.103056)
			(xy 364.745026 -288.129705) (xy 364.737083 -288.182409) (xy 364.721373 -288.233339) (xy 364.698247 -288.28136)
			(xy 364.668223 -288.325397) (xy 364.631971 -288.364468) (xy 364.5903 -288.397699) (xy 364.544142 -288.424348)
			(xy 364.494528 -288.44382) (xy 364.442566 -288.45568) (xy 364.389416 -288.459664) (xy 364.336266 -288.45568)
			(xy 364.284304 -288.44382) (xy 364.23469 -288.424348) (xy 364.188532 -288.397699) (xy 364.146861 -288.364468)
			(xy 364.110609 -288.325397) (xy 364.080585 -288.28136) (xy 364.057459 -288.233339) (xy 364.041749 -288.182409)
			(xy 364.033806 -288.129705) (xy 361.925372 -288.129705) (xy 361.917429 -288.182409) (xy 361.901719 -288.233339)
			(xy 361.878593 -288.28136) (xy 361.848569 -288.325397) (xy 361.812317 -288.364468) (xy 361.770646 -288.397699)
			(xy 361.724488 -288.424348) (xy 361.674874 -288.44382) (xy 361.622912 -288.45568) (xy 361.569762 -288.459664)
			(xy 361.516612 -288.45568) (xy 361.46465 -288.44382) (xy 361.415036 -288.424348) (xy 361.368878 -288.397699)
			(xy 361.327207 -288.364468) (xy 361.290955 -288.325397) (xy 361.260931 -288.28136) (xy 361.237805 -288.233339)
			(xy 361.222095 -288.182409) (xy 361.214152 -288.129705) (xy 353.467426 -288.129705) (xy 353.459483 -288.182409)
			(xy 353.443773 -288.233339) (xy 353.420647 -288.28136) (xy 353.390623 -288.325397) (xy 353.354371 -288.364468)
			(xy 353.3127 -288.397699) (xy 353.266542 -288.424348) (xy 353.216928 -288.44382) (xy 353.164966 -288.45568)
			(xy 353.111816 -288.459664) (xy 353.058666 -288.45568) (xy 353.006704 -288.44382) (xy 352.95709 -288.424348)
			(xy 352.910932 -288.397699) (xy 352.869261 -288.364468) (xy 352.833009 -288.325397) (xy 352.802985 -288.28136)
			(xy 352.779859 -288.233339) (xy 352.764149 -288.182409) (xy 352.756206 -288.129705) (xy 352.527602 -288.129705)
			(xy 352.52755 -288.132363) (xy 352.517976 -288.19019) (xy 352.509074 -288.218118) (xy 352.50628 -288.226246)
			(xy 352.50628 -288.460688) (xy 352.506715 -288.474653) (xy 352.514277 -288.501539) (xy 352.528839 -288.525372)
			(xy 352.549312 -288.544369) (xy 352.574166 -288.557111) (xy 352.601542 -288.562644) (xy 352.6155 -288.562034)
			(xy 352.641916 -288.561018) (xy 352.668563 -288.561517) (xy 352.72126 -288.569462) (xy 352.772185 -288.585173)
			(xy 352.8202 -288.608297) (xy 352.864232 -288.638319) (xy 352.903298 -288.674569) (xy 352.936524 -288.716236)
			(xy 352.96317 -288.762389) (xy 352.98264 -288.811999) (xy 352.994499 -288.863956) (xy 352.998481 -288.9171)
			(xy 352.996482 -288.943775) (xy 355.105706 -288.943775) (xy 355.105706 -288.890477) (xy 355.113649 -288.837773)
			(xy 355.129359 -288.786843) (xy 355.152485 -288.738822) (xy 355.182509 -288.694785) (xy 355.218761 -288.655714)
			(xy 355.260432 -288.622483) (xy 355.30659 -288.595834) (xy 355.356204 -288.576362) (xy 355.408166 -288.564502)
			(xy 355.461316 -288.560519) (xy 355.514466 -288.564502) (xy 355.566428 -288.576362) (xy 355.616042 -288.595834)
			(xy 355.6622 -288.622483) (xy 355.703871 -288.655714) (xy 355.740123 -288.694785) (xy 355.770147 -288.738822)
			(xy 355.793273 -288.786843) (xy 355.808983 -288.837773) (xy 355.816926 -288.890477) (xy 355.817424 -288.917126)
			(xy 355.816926 -288.943775) (xy 355.808983 -288.996479) (xy 355.801735 -289.019975) (xy 357.925106 -289.019975)
			(xy 357.925106 -288.966677) (xy 357.933049 -288.913973) (xy 357.948759 -288.863043) (xy 357.971885 -288.815022)
			(xy 358.001909 -288.770985) (xy 358.038161 -288.731914) (xy 358.079832 -288.698683) (xy 358.12599 -288.672034)
			(xy 358.175604 -288.652562) (xy 358.227566 -288.640702) (xy 358.280716 -288.636719) (xy 358.333866 -288.640702)
			(xy 358.385828 -288.652562) (xy 358.435442 -288.672034) (xy 358.4816 -288.698683) (xy 358.523271 -288.731914)
			(xy 358.559523 -288.770985) (xy 358.589547 -288.815022) (xy 358.612673 -288.863043) (xy 358.628383 -288.913973)
			(xy 358.632874 -288.943775) (xy 367.323106 -288.943775) (xy 367.323106 -288.890477) (xy 367.331049 -288.837773)
			(xy 367.346759 -288.786843) (xy 367.369885 -288.738822) (xy 367.399909 -288.694785) (xy 367.436161 -288.655714)
			(xy 367.477832 -288.622483) (xy 367.52399 -288.595834) (xy 367.573604 -288.576362) (xy 367.625566 -288.564502)
			(xy 367.678716 -288.560519) (xy 367.731866 -288.564502) (xy 367.783828 -288.576362) (xy 367.833442 -288.595834)
			(xy 367.8796 -288.622483) (xy 367.921271 -288.655714) (xy 367.957523 -288.694785) (xy 367.987547 -288.738822)
			(xy 368.010673 -288.786843) (xy 368.026383 -288.837773) (xy 368.034326 -288.890477) (xy 368.034824 -288.917126)
			(xy 368.034326 -288.943775) (xy 368.026383 -288.996479) (xy 368.010673 -289.047409) (xy 367.987547 -289.09543)
			(xy 367.957523 -289.139467) (xy 367.921271 -289.178538) (xy 367.8796 -289.211769) (xy 367.833442 -289.238418)
			(xy 367.783828 -289.25789) (xy 367.731866 -289.26975) (xy 367.678716 -289.273734) (xy 367.625566 -289.26975)
			(xy 367.573604 -289.25789) (xy 367.52399 -289.238418) (xy 367.477832 -289.211769) (xy 367.436161 -289.178538)
			(xy 367.399909 -289.139467) (xy 367.369885 -289.09543) (xy 367.346759 -289.047409) (xy 367.331049 -288.996479)
			(xy 367.323106 -288.943775) (xy 358.632874 -288.943775) (xy 358.636326 -288.966677) (xy 358.636824 -288.993326)
			(xy 358.636326 -289.019975) (xy 358.628383 -289.072679) (xy 358.612673 -289.123609) (xy 358.589547 -289.17163)
			(xy 358.559523 -289.215667) (xy 358.523271 -289.254738) (xy 358.4816 -289.287969) (xy 358.435442 -289.314618)
			(xy 358.385828 -289.33409) (xy 358.333866 -289.34595) (xy 358.280716 -289.349934) (xy 358.227566 -289.34595)
			(xy 358.175604 -289.33409) (xy 358.12599 -289.314618) (xy 358.079832 -289.287969) (xy 358.038161 -289.254738)
			(xy 358.001909 -289.215667) (xy 357.971885 -289.17163) (xy 357.948759 -289.123609) (xy 357.933049 -289.072679)
			(xy 357.925106 -289.019975) (xy 355.801735 -289.019975) (xy 355.793273 -289.047409) (xy 355.770147 -289.09543)
			(xy 355.740123 -289.139467) (xy 355.703871 -289.178538) (xy 355.6622 -289.211769) (xy 355.616042 -289.238418)
			(xy 355.566428 -289.25789) (xy 355.514466 -289.26975) (xy 355.461316 -289.273734) (xy 355.408166 -289.26975)
			(xy 355.356204 -289.25789) (xy 355.30659 -289.238418) (xy 355.260432 -289.211769) (xy 355.218761 -289.178538)
			(xy 355.182509 -289.139467) (xy 355.152485 -289.09543) (xy 355.129359 -289.047409) (xy 355.113649 -288.996479)
			(xy 355.105706 -288.943775) (xy 352.996482 -288.943775) (xy 352.994499 -288.970244) (xy 352.98264 -289.022201)
			(xy 352.96317 -289.071811) (xy 352.936524 -289.117964) (xy 352.903298 -289.159631) (xy 352.864232 -289.195881)
			(xy 352.8202 -289.225903) (xy 352.772185 -289.249027) (xy 352.72126 -289.264738) (xy 352.668563 -289.272683)
			(xy 352.641916 -289.273234) (xy 352.617746 -289.27285) (xy 352.569846 -289.266347) (xy 352.523268 -289.253417)
			(xy 352.47887 -289.234299) (xy 352.437469 -289.209345) (xy 352.418396 -289.194494) (xy 352.410891 -289.188916)
			(xy 352.393137 -289.183103) (xy 352.37448 -289.184068) (xy 352.35742 -289.191681) (xy 352.350578 -289.19805)
			(xy 352.246692 -289.301936) (xy 352.236646 -289.312732) (xy 352.222682 -289.338694) (xy 352.216713 -289.367561)
			(xy 352.219234 -289.396931) (xy 352.230036 -289.424359) (xy 352.248219 -289.447561) (xy 352.27227 -289.464606)
			(xy 352.286062 -289.46983) (xy 352.312131 -289.479221) (xy 352.36122 -289.504921) (xy 352.405734 -289.537915)
			(xy 352.444599 -289.577408) (xy 352.476875 -289.622445) (xy 352.501785 -289.671939) (xy 352.518726 -289.724694)
			(xy 352.527288 -289.779437) (xy 352.52787 -289.807142) (xy 352.527344 -289.833791) (xy 366.852952 -289.833791)
			(xy 366.852952 -289.780493) (xy 366.860895 -289.727789) (xy 366.876605 -289.676859) (xy 366.899731 -289.628838)
			(xy 366.929755 -289.584801) (xy 366.966007 -289.54573) (xy 367.007678 -289.512499) (xy 367.053836 -289.48585)
			(xy 367.10345 -289.466378) (xy 367.155412 -289.454518) (xy 367.208562 -289.450535) (xy 367.261712 -289.454518)
			(xy 367.313674 -289.466378) (xy 367.363288 -289.48585) (xy 367.409446 -289.512499) (xy 367.451117 -289.54573)
			(xy 367.487369 -289.584801) (xy 367.517393 -289.628838) (xy 367.540519 -289.676859) (xy 367.556229 -289.727789)
			(xy 367.564172 -289.780493) (xy 367.56467 -289.807142) (xy 367.792254 -289.807142) (xy 367.792654 -289.781501)
			(xy 367.800004 -289.730748) (xy 367.814559 -289.681575) (xy 367.836017 -289.634998) (xy 367.863935 -289.591981)
			(xy 367.897735 -289.553414) (xy 367.936717 -289.520094) (xy 367.980076 -289.492711) (xy 368.026915 -289.471831)
			(xy 368.076265 -289.457886) (xy 368.101626 -289.454082) (xy 368.127534 -289.45078) (xy 368.312446 -289.101022)
			(xy 368.300508 -289.077654) (xy 368.288479 -289.052624) (xy 368.271494 -288.999756) (xy 368.262918 -288.944892)
			(xy 368.262408 -288.917126) (xy 368.262906 -288.890477) (xy 368.270849 -288.837773) (xy 368.286559 -288.786843)
			(xy 368.309685 -288.738822) (xy 368.339709 -288.694785) (xy 368.375961 -288.655714) (xy 368.417632 -288.622483)
			(xy 368.46379 -288.595834) (xy 368.513404 -288.576362) (xy 368.565366 -288.564502) (xy 368.618516 -288.560519)
			(xy 368.671666 -288.564502) (xy 368.723628 -288.576362) (xy 368.773242 -288.595834) (xy 368.8194 -288.622483)
			(xy 368.861071 -288.655714) (xy 368.897323 -288.694785) (xy 368.927347 -288.738822) (xy 368.950473 -288.786843)
			(xy 368.966183 -288.837773) (xy 368.974126 -288.890477) (xy 368.974624 -288.917126) (xy 368.974127 -288.942763)
			(xy 368.966783 -288.993508) (xy 368.952236 -289.042676) (xy 368.930788 -289.089248) (xy 368.902881 -289.132262)
			(xy 368.869092 -289.170829) (xy 368.830122 -289.20415) (xy 368.786774 -289.231537) (xy 368.739947 -289.252423)
			(xy 368.690608 -289.266377) (xy 368.665252 -289.270186) (xy 368.639344 -289.273488) (xy 368.454432 -289.623246)
			(xy 368.46637 -289.646614) (xy 368.478386 -289.671649) (xy 368.495377 -289.724515) (xy 368.503957 -289.779377)
			(xy 368.50447 -289.807142) (xy 368.503972 -289.833791) (xy 368.732552 -289.833791) (xy 368.732552 -289.780493)
			(xy 368.740495 -289.727789) (xy 368.756205 -289.676859) (xy 368.779331 -289.628838) (xy 368.809355 -289.584801)
			(xy 368.845607 -289.54573) (xy 368.887278 -289.512499) (xy 368.933436 -289.48585) (xy 368.98305 -289.466378)
			(xy 369.035012 -289.454518) (xy 369.088162 -289.450535) (xy 369.141312 -289.454518) (xy 369.193274 -289.466378)
			(xy 369.242888 -289.48585) (xy 369.289046 -289.512499) (xy 369.330717 -289.54573) (xy 369.366969 -289.584801)
			(xy 369.396993 -289.628838) (xy 369.420119 -289.676859) (xy 369.435829 -289.727789) (xy 369.443772 -289.780493)
			(xy 369.44427 -289.807142) (xy 369.443772 -289.833791) (xy 369.435829 -289.886495) (xy 369.420119 -289.937425)
			(xy 369.396993 -289.985446) (xy 369.366969 -290.029483) (xy 369.330717 -290.068554) (xy 369.289046 -290.101785)
			(xy 369.242888 -290.128434) (xy 369.193274 -290.147906) (xy 369.141312 -290.159766) (xy 369.088162 -290.16375)
			(xy 369.035012 -290.159766) (xy 368.98305 -290.147906) (xy 368.933436 -290.128434) (xy 368.887278 -290.101785)
			(xy 368.845607 -290.068554) (xy 368.809355 -290.029483) (xy 368.779331 -289.985446) (xy 368.756205 -289.937425)
			(xy 368.740495 -289.886495) (xy 368.732552 -289.833791) (xy 368.503972 -289.833791) (xy 368.496029 -289.886495)
			(xy 368.480319 -289.937425) (xy 368.457193 -289.985446) (xy 368.427169 -290.029483) (xy 368.390917 -290.068554)
			(xy 368.349246 -290.101785) (xy 368.303088 -290.128434) (xy 368.253474 -290.147906) (xy 368.201512 -290.159766)
			(xy 368.148362 -290.16375) (xy 368.095212 -290.159766) (xy 368.04325 -290.147906) (xy 367.993636 -290.128434)
			(xy 367.947478 -290.101785) (xy 367.905807 -290.068554) (xy 367.869555 -290.029483) (xy 367.839531 -289.985446)
			(xy 367.816405 -289.937425) (xy 367.800695 -289.886495) (xy 367.792752 -289.833791) (xy 367.792254 -289.807142)
			(xy 367.56467 -289.807142) (xy 367.564172 -289.833791) (xy 367.556229 -289.886495) (xy 367.540519 -289.937425)
			(xy 367.517393 -289.985446) (xy 367.487369 -290.029483) (xy 367.451117 -290.068554) (xy 367.409446 -290.101785)
			(xy 367.363288 -290.128434) (xy 367.313674 -290.147906) (xy 367.261712 -290.159766) (xy 367.208562 -290.16375)
			(xy 367.155412 -290.159766) (xy 367.10345 -290.147906) (xy 367.053836 -290.128434) (xy 367.007678 -290.101785)
			(xy 366.966007 -290.068554) (xy 366.929755 -290.029483) (xy 366.899731 -289.985446) (xy 366.876605 -289.937425)
			(xy 366.860895 -289.886495) (xy 366.852952 -289.833791) (xy 352.527344 -289.833791) (xy 352.527318 -289.835122)
			(xy 352.518557 -289.890392) (xy 352.501259 -289.943611) (xy 352.475848 -289.993468) (xy 352.44295 -290.038737)
			(xy 352.403376 -290.078302) (xy 352.3581 -290.11119) (xy 352.308237 -290.136589) (xy 352.255014 -290.153876)
			(xy 352.199742 -290.162624) (xy 352.171762 -290.16325) (xy 352.144057 -290.162721) (xy 352.089316 -290.154136)
			(xy 352.036564 -290.137179) (xy 351.987073 -290.112259) (xy 351.942038 -290.079977) (xy 351.902544 -290.041111)
			(xy 351.869543 -289.996599) (xy 351.843833 -289.947515) (xy 351.83445 -289.921442) (xy 351.829271 -289.907618)
			(xy 351.81225 -289.883516) (xy 351.789043 -289.865292) (xy 351.761591 -289.854472) (xy 351.732191 -289.851961)
			(xy 351.703302 -289.857969) (xy 351.677341 -289.871993) (xy 351.666556 -289.882072) (xy 351.00768 -290.540948)
			(xy 335.18348 -290.540948) (xy 334.04048 -291.683948) (xy 334.04048 -292.982951) (xy 351.177581 -292.982951)
			(xy 351.177581 -292.928449) (xy 351.185338 -292.874501) (xy 351.200693 -292.822206) (xy 351.223335 -292.772629)
			(xy 351.252801 -292.726779) (xy 351.288493 -292.685589) (xy 351.329684 -292.649898) (xy 351.375534 -292.620432)
			(xy 351.425112 -292.597791) (xy 351.477407 -292.582437) (xy 351.531355 -292.574681) (xy 351.558606 -292.574218)
			(xy 351.586683 -292.574702) (xy 351.642232 -292.582918) (xy 351.695978 -292.599186) (xy 351.746759 -292.623155)
			(xy 351.793479 -292.654308) (xy 351.814638 -292.67277) (xy 351.826251 -292.682602) (xy 351.85379 -292.695511)
			(xy 351.883911 -292.699721) (xy 351.913933 -292.694856) (xy 351.941183 -292.681349) (xy 351.95256 -292.671246)
			(xy 351.973948 -292.651738) (xy 352.021512 -292.618747) (xy 352.073518 -292.593328) (xy 352.128771 -292.576069)
			(xy 352.185999 -292.567365) (xy 352.214942 -292.566852) (xy 352.242188 -292.567421) (xy 352.296126 -292.575182)
			(xy 352.34841 -292.590539) (xy 352.397977 -292.61318) (xy 352.443817 -292.642644) (xy 352.484998 -292.678332)
			(xy 352.520681 -292.719517) (xy 352.55014 -292.76536) (xy 352.572776 -292.814929) (xy 352.588127 -292.867215)
			(xy 352.595882 -292.921154) (xy 352.595882 -292.975646) (xy 352.594832 -292.982951) (xy 357.228881 -292.982951)
			(xy 357.228881 -292.928449) (xy 357.236638 -292.874501) (xy 357.251993 -292.822207) (xy 357.274634 -292.77263)
			(xy 357.3041 -292.72678) (xy 357.339792 -292.68559) (xy 357.380982 -292.649899) (xy 357.426832 -292.620433)
			(xy 357.476409 -292.597792) (xy 357.528703 -292.582437) (xy 357.582651 -292.574681) (xy 357.609902 -292.574218)
			(xy 357.637272 -292.574679) (xy 357.691452 -292.582497) (xy 357.743955 -292.597987) (xy 357.793702 -292.62083)
			(xy 357.839669 -292.650556) (xy 357.8606 -292.668198) (xy 357.871928 -292.677434) (xy 357.898485 -292.68961)
			(xy 357.927402 -292.693783) (xy 357.956319 -292.68961) (xy 357.982876 -292.677434) (xy 357.994204 -292.668198)
			(xy 358.015123 -292.650543) (xy 358.0611 -292.620834) (xy 358.11085 -292.598001) (xy 358.163354 -292.582514)
			(xy 358.217532 -292.57469) (xy 358.244902 -292.574218) (xy 358.272155 -292.574652) (xy 358.326106 -292.582409)
			(xy 358.378404 -292.597766) (xy 358.427985 -292.620408) (xy 358.473838 -292.649877) (xy 358.515031 -292.685571)
			(xy 358.550724 -292.726764) (xy 358.580193 -292.772617) (xy 358.602835 -292.822198) (xy 358.618191 -292.874496)
			(xy 358.625948 -292.928447) (xy 358.625948 -292.982949) (xy 363.686604 -292.982949) (xy 363.686604 -292.928451)
			(xy 363.69436 -292.874507) (xy 363.709714 -292.822216) (xy 363.732354 -292.772642) (xy 363.761818 -292.726795)
			(xy 363.797506 -292.685608) (xy 363.838694 -292.649919) (xy 363.884541 -292.620454) (xy 363.934114 -292.597815)
			(xy 363.986405 -292.582461) (xy 364.040349 -292.574704) (xy 364.067598 -292.574218) (xy 364.094968 -292.574681)
			(xy 364.149148 -292.582499) (xy 364.201651 -292.597988) (xy 364.251398 -292.620831) (xy 364.297365 -292.650556)
			(xy 364.318296 -292.668198) (xy 364.329624 -292.677434) (xy 364.356181 -292.68961) (xy 364.385098 -292.693783)
			(xy 364.414015 -292.68961) (xy 364.440572 -292.677434) (xy 364.4519 -292.668198) (xy 364.472821 -292.650545)
			(xy 364.518797 -292.620835) (xy 364.568547 -292.598002) (xy 364.62105 -292.582514) (xy 364.675228 -292.57469)
			(xy 364.702598 -292.574218) (xy 364.729853 -292.574629) (xy 364.783808 -292.582386) (xy 364.836109 -292.597743)
			(xy 364.885693 -292.620387) (xy 364.93155 -292.649857) (xy 364.972746 -292.685553) (xy 365.008442 -292.726749)
			(xy 365.037912 -292.772605) (xy 365.060556 -292.822189) (xy 365.075914 -292.87449) (xy 365.083671 -292.928445)
			(xy 365.083671 -292.982955) (xy 365.075914 -293.03691) (xy 365.060556 -293.089211) (xy 365.037912 -293.138795)
			(xy 365.008442 -293.184651) (xy 364.972746 -293.225847) (xy 364.93155 -293.261543) (xy 364.885693 -293.291013)
			(xy 364.836109 -293.313657) (xy 364.783808 -293.329014) (xy 364.729853 -293.336771) (xy 364.702598 -293.337234)
			(xy 364.675227 -293.336785) (xy 364.621046 -293.328966) (xy 364.568543 -293.313473) (xy 364.518796 -293.290627)
			(xy 364.47283 -293.260898) (xy 364.4519 -293.243254) (xy 364.440572 -293.234018) (xy 364.414015 -293.221842)
			(xy 364.385098 -293.217669) (xy 364.356181 -293.221842) (xy 364.329624 -293.234018) (xy 364.318296 -293.243254)
			(xy 364.29737 -293.260901) (xy 364.251397 -293.290613) (xy 364.201647 -293.313449) (xy 364.149145 -293.328938)
			(xy 364.094968 -293.336762) (xy 364.067598 -293.337234) (xy 364.040349 -293.336696) (xy 363.986405 -293.328939)
			(xy 363.934114 -293.313585) (xy 363.884541 -293.290946) (xy 363.838694 -293.261481) (xy 363.797506 -293.225792)
			(xy 363.761818 -293.184605) (xy 363.732354 -293.138758) (xy 363.709714 -293.089184) (xy 363.69436 -293.036893)
			(xy 363.686604 -292.982949) (xy 358.625948 -292.982949) (xy 358.625948 -292.982953) (xy 358.618191 -293.036904)
			(xy 358.602835 -293.089202) (xy 358.580193 -293.138783) (xy 358.550724 -293.184636) (xy 358.515031 -293.225829)
			(xy 358.473838 -293.261523) (xy 358.427985 -293.290992) (xy 358.378404 -293.313634) (xy 358.326106 -293.328991)
			(xy 358.272155 -293.336748) (xy 358.244902 -293.337234) (xy 358.217531 -293.336783) (xy 358.163351 -293.328964)
			(xy 358.110847 -293.313472) (xy 358.0611 -293.290627) (xy 358.015135 -293.260898) (xy 357.994204 -293.243254)
			(xy 357.982876 -293.234018) (xy 357.956319 -293.221842) (xy 357.927402 -293.217669) (xy 357.898485 -293.221842)
			(xy 357.871928 -293.234018) (xy 357.8606 -293.243254) (xy 357.839673 -293.260899) (xy 357.793699 -293.290612)
			(xy 357.743951 -293.313447) (xy 357.691449 -293.328937) (xy 357.637272 -293.336762) (xy 357.609902 -293.337234)
			(xy 357.582651 -293.336719) (xy 357.528703 -293.328963) (xy 357.476409 -293.313608) (xy 357.426832 -293.290967)
			(xy 357.380982 -293.261501) (xy 357.339792 -293.22581) (xy 357.3041 -293.18462) (xy 357.274634 -293.13877)
			(xy 357.251993 -293.089193) (xy 357.236638 -293.036899) (xy 357.228881 -292.982951) (xy 352.594832 -292.982951)
			(xy 352.588127 -293.029585) (xy 352.572776 -293.081871) (xy 352.55014 -293.13144) (xy 352.520681 -293.177283)
			(xy 352.484998 -293.218468) (xy 352.443817 -293.254156) (xy 352.397977 -293.28362) (xy 352.34841 -293.306261)
			(xy 352.296126 -293.321618) (xy 352.242188 -293.329379) (xy 352.214942 -293.329868) (xy 352.186864 -293.329419)
			(xy 352.131313 -293.321195) (xy 352.077567 -293.304919) (xy 352.026786 -293.280942) (xy 351.980068 -293.249782)
			(xy 351.95891 -293.231316) (xy 351.947336 -293.221434) (xy 351.919783 -293.208533) (xy 351.889651 -293.204334)
			(xy 351.85962 -293.209211) (xy 351.832366 -293.22273) (xy 351.820988 -293.23284) (xy 351.799593 -293.25234)
			(xy 351.75203 -293.285329) (xy 351.700025 -293.310748) (xy 351.644774 -293.32801) (xy 351.587549 -293.336718)
			(xy 351.558606 -293.337234) (xy 351.531355 -293.336719) (xy 351.477407 -293.328963) (xy 351.425112 -293.313609)
			(xy 351.375534 -293.290968) (xy 351.329684 -293.261502) (xy 351.288493 -293.225811) (xy 351.252801 -293.184621)
			(xy 351.223335 -293.138771) (xy 351.200693 -293.089194) (xy 351.185338 -293.036899) (xy 351.177581 -292.982951)
			(xy 334.04048 -292.982951) (xy 334.04048 -295.060651) (xy 351.198901 -295.060651) (xy 351.198901 -295.006149)
			(xy 351.206658 -294.9522) (xy 351.222015 -294.899906) (xy 351.244658 -294.850329) (xy 351.274126 -294.804479)
			(xy 351.30982 -294.76329) (xy 351.351013 -294.727601) (xy 351.396865 -294.698137) (xy 351.446445 -294.6755)
			(xy 351.498742 -294.66015) (xy 351.55269 -294.652398) (xy 351.579942 -294.651938) (xy 351.606876 -294.652417)
			(xy 351.660206 -294.660004) (xy 351.711939 -294.675019) (xy 351.761043 -294.697165) (xy 351.806543 -294.726001)
			(xy 351.827338 -294.743124) (xy 351.838806 -294.752175) (xy 351.865494 -294.764022) (xy 351.89444 -294.767861)
			(xy 351.923294 -294.763379) (xy 351.949712 -294.750941) (xy 351.960942 -294.7416) (xy 351.982009 -294.723433)
			(xy 352.028438 -294.692794) (xy 352.078823 -294.669218) (xy 352.132095 -294.653205) (xy 352.187129 -294.645094)
			(xy 352.214942 -294.644572) (xy 352.24219 -294.645101) (xy 352.29613 -294.652862) (xy 352.348417 -294.66822)
			(xy 352.397986 -294.690862) (xy 352.443829 -294.720328) (xy 352.485012 -294.756018) (xy 352.520697 -294.797205)
			(xy 352.550158 -294.843051) (xy 352.572795 -294.892622) (xy 352.588147 -294.944911) (xy 352.595902 -294.998852)
			(xy 352.595902 -295.053348) (xy 352.594119 -295.065751) (xy 357.228881 -295.065751) (xy 357.228881 -295.011249)
			(xy 357.236638 -294.957301) (xy 357.251993 -294.905007) (xy 357.274634 -294.85543) (xy 357.3041 -294.80958)
			(xy 357.339792 -294.76839) (xy 357.380982 -294.732699) (xy 357.426832 -294.703233) (xy 357.476409 -294.680592)
			(xy 357.528703 -294.665237) (xy 357.582651 -294.657481) (xy 357.609902 -294.657018) (xy 357.640025 -294.657597)
			(xy 357.699521 -294.667077) (xy 357.756788 -294.685787) (xy 357.810405 -294.713261) (xy 357.85904 -294.748816)
			(xy 357.880666 -294.769794) (xy 357.890388 -294.779012) (xy 357.91355 -294.792457) (xy 357.939411 -294.799419)
			(xy 357.966193 -294.799419) (xy 357.992054 -294.792457) (xy 358.015216 -294.779012) (xy 358.024938 -294.769794)
			(xy 358.046566 -294.748817) (xy 358.095194 -294.713249) (xy 358.14881 -294.685768) (xy 358.206079 -294.667059)
			(xy 358.265578 -294.657587) (xy 358.295702 -294.657018) (xy 358.322955 -294.657452) (xy 358.376906 -294.665209)
			(xy 358.429204 -294.680566) (xy 358.478785 -294.703208) (xy 358.524638 -294.732677) (xy 358.565831 -294.768371)
			(xy 358.601524 -294.809564) (xy 358.630993 -294.855417) (xy 358.653635 -294.904998) (xy 358.668991 -294.957296)
			(xy 358.676748 -295.011247) (xy 358.676748 -295.065749) (xy 363.572304 -295.065749) (xy 363.572304 -295.011251)
			(xy 363.58006 -294.957307) (xy 363.595414 -294.905016) (xy 363.618054 -294.855442) (xy 363.647518 -294.809595)
			(xy 363.683206 -294.768408) (xy 363.724394 -294.732719) (xy 363.770241 -294.703254) (xy 363.819814 -294.680615)
			(xy 363.872105 -294.665261) (xy 363.926049 -294.657504) (xy 363.953298 -294.657018) (xy 363.980668 -294.657481)
			(xy 364.034848 -294.665299) (xy 364.087351 -294.680788) (xy 364.137098 -294.703631) (xy 364.183065 -294.733356)
			(xy 364.203996 -294.750998) (xy 364.215324 -294.760234) (xy 364.241881 -294.77241) (xy 364.270798 -294.776583)
			(xy 364.299715 -294.77241) (xy 364.326272 -294.760234) (xy 364.3376 -294.750998) (xy 364.358521 -294.733345)
			(xy 364.404497 -294.703635) (xy 364.454247 -294.680802) (xy 364.50675 -294.665314) (xy 364.560928 -294.65749)
			(xy 364.588298 -294.657018) (xy 364.615553 -294.657429) (xy 364.669508 -294.665186) (xy 364.721809 -294.680543)
			(xy 364.771393 -294.703187) (xy 364.81725 -294.732657) (xy 364.858446 -294.768353) (xy 364.894142 -294.809549)
			(xy 364.923612 -294.855405) (xy 364.946256 -294.904989) (xy 364.961614 -294.95729) (xy 364.969371 -295.011245)
			(xy 364.969371 -295.038526) (xy 370.181376 -295.038526) (xy 370.185447 -294.982904) (xy 370.197573 -294.928467)
			(xy 370.217496 -294.876376) (xy 370.244792 -294.827741) (xy 370.278878 -294.783598) (xy 370.319027 -294.744889)
			(xy 370.364385 -294.712438) (xy 370.413985 -294.686937) (xy 370.466769 -294.66893) (xy 370.521612 -294.6588)
			(xy 370.577346 -294.656763) (xy 370.632783 -294.662863) (xy 370.68674 -294.676969) (xy 370.738069 -294.698781)
			(xy 370.785675 -294.727835) (xy 370.828543 -294.76351) (xy 370.86576 -294.805047) (xy 370.896533 -294.85156)
			(xy 370.920205 -294.902057) (xy 370.936273 -294.955464) (xy 370.944393 -295.01064) (xy 370.944902 -295.038526)
			(xy 370.944393 -295.066412) (xy 370.936273 -295.121588) (xy 370.920205 -295.174995) (xy 370.896533 -295.225492)
			(xy 370.86576 -295.272005) (xy 370.828543 -295.313542) (xy 370.785675 -295.349217) (xy 370.738069 -295.378271)
			(xy 370.68674 -295.400083) (xy 370.632783 -295.414189) (xy 370.577346 -295.420289) (xy 370.521612 -295.418252)
			(xy 370.466769 -295.408122) (xy 370.413985 -295.390115) (xy 370.364385 -295.364614) (xy 370.319027 -295.332163)
			(xy 370.278878 -295.293454) (xy 370.244792 -295.249311) (xy 370.217496 -295.200676) (xy 370.197573 -295.148585)
			(xy 370.185447 -295.094148) (xy 370.181376 -295.038526) (xy 364.969371 -295.038526) (xy 364.969371 -295.065755)
			(xy 364.961614 -295.11971) (xy 364.946256 -295.172011) (xy 364.923612 -295.221595) (xy 364.894142 -295.267451)
			(xy 364.858446 -295.308647) (xy 364.81725 -295.344343) (xy 364.771393 -295.373813) (xy 364.721809 -295.396457)
			(xy 364.669508 -295.411814) (xy 364.615553 -295.419571) (xy 364.588298 -295.420034) (xy 364.560927 -295.419585)
			(xy 364.506746 -295.411766) (xy 364.454243 -295.396273) (xy 364.404496 -295.373427) (xy 364.35853 -295.343698)
			(xy 364.3376 -295.326054) (xy 364.326272 -295.316818) (xy 364.299715 -295.304642) (xy 364.270798 -295.300469)
			(xy 364.241881 -295.304642) (xy 364.215324 -295.316818) (xy 364.203996 -295.326054) (xy 364.18307 -295.343701)
			(xy 364.137097 -295.373413) (xy 364.087347 -295.396249) (xy 364.034845 -295.411738) (xy 363.980668 -295.419562)
			(xy 363.953298 -295.420034) (xy 363.926049 -295.419496) (xy 363.872105 -295.411739) (xy 363.819814 -295.396385)
			(xy 363.770241 -295.373746) (xy 363.724394 -295.344281) (xy 363.683206 -295.308592) (xy 363.647518 -295.267405)
			(xy 363.618054 -295.221558) (xy 363.595414 -295.171984) (xy 363.58006 -295.119693) (xy 363.572304 -295.065749)
			(xy 358.676748 -295.065749) (xy 358.676748 -295.065753) (xy 358.668991 -295.119704) (xy 358.653635 -295.172002)
			(xy 358.630993 -295.221583) (xy 358.601524 -295.267436) (xy 358.565831 -295.308629) (xy 358.524638 -295.344323)
			(xy 358.478785 -295.373792) (xy 358.429204 -295.396434) (xy 358.376906 -295.411791) (xy 358.322955 -295.419548)
			(xy 358.295702 -295.420034) (xy 358.265578 -295.419467) (xy 358.206082 -295.409986) (xy 358.148813 -295.391274)
			(xy 358.095196 -295.363797) (xy 358.046562 -295.328238) (xy 358.024938 -295.307258) (xy 358.015216 -295.29804)
			(xy 357.992054 -295.284595) (xy 357.966193 -295.277633) (xy 357.939411 -295.277633) (xy 357.91355 -295.284595)
			(xy 357.890388 -295.29804) (xy 357.880666 -295.307258) (xy 357.859028 -295.328224) (xy 357.810404 -295.363796)
			(xy 357.756791 -295.39128) (xy 357.699523 -295.409991) (xy 357.640025 -295.419465) (xy 357.609902 -295.420034)
			(xy 357.582651 -295.419519) (xy 357.528703 -295.411763) (xy 357.476409 -295.396408) (xy 357.426832 -295.373767)
			(xy 357.380982 -295.344301) (xy 357.339792 -295.30861) (xy 357.3041 -295.26742) (xy 357.274634 -295.22157)
			(xy 357.251993 -295.171993) (xy 357.236638 -295.119699) (xy 357.228881 -295.065751) (xy 352.594119 -295.065751)
			(xy 352.588147 -295.107289) (xy 352.572795 -295.159578) (xy 352.550158 -295.209149) (xy 352.520697 -295.254995)
			(xy 352.485012 -295.296182) (xy 352.443829 -295.331872) (xy 352.397986 -295.361338) (xy 352.348417 -295.38398)
			(xy 352.29613 -295.399338) (xy 352.24219 -295.407099) (xy 352.214942 -295.407588) (xy 352.188008 -295.407112)
			(xy 352.134678 -295.399524) (xy 352.082946 -295.384507) (xy 352.033841 -295.362361) (xy 351.988342 -295.333525)
			(xy 351.967546 -295.316402) (xy 351.956087 -295.307342) (xy 351.929394 -295.295506) (xy 351.900448 -295.291673)
			(xy 351.871595 -295.296155) (xy 351.845175 -295.308589) (xy 351.833942 -295.317926) (xy 351.812846 -295.336057)
			(xy 351.766425 -295.366701) (xy 351.716047 -295.390283) (xy 351.662781 -295.406305) (xy 351.607753 -295.414427)
			(xy 351.579942 -295.414954) (xy 351.55269 -295.414402) (xy 351.498741 -295.40665) (xy 351.446445 -295.3913)
			(xy 351.396865 -295.368663) (xy 351.351013 -295.339199) (xy 351.30982 -295.30351) (xy 351.274126 -295.262321)
			(xy 351.244658 -295.216471) (xy 351.222015 -295.166894) (xy 351.206658 -295.1146) (xy 351.198901 -295.060651)
			(xy 334.04048 -295.060651) (xy 334.04048 -297.515026) (xy 336.155548 -297.515026) (xy 336.159529 -297.382006)
			(xy 336.171458 -297.249461) (xy 336.191293 -297.117868) (xy 336.218962 -296.987696) (xy 336.254366 -296.859411)
			(xy 336.297379 -296.733474) (xy 336.347846 -296.610335) (xy 336.405587 -296.490434) (xy 336.470396 -296.374201)
			(xy 336.54204 -296.262051) (xy 336.620262 -296.154387) (xy 336.704783 -296.051594) (xy 336.795301 -295.954039)
			(xy 336.89149 -295.862073) (xy 336.993008 -295.776023) (xy 337.099489 -295.696199) (xy 337.210554 -295.622886)
			(xy 337.325805 -295.556346) (xy 337.444829 -295.496817) (xy 337.5672 -295.444513) (xy 337.692479 -295.399621)
			(xy 337.82022 -295.362302) (xy 337.949963 -295.332689) (xy 338.081245 -295.310888) (xy 338.213596 -295.296978)
			(xy 338.346542 -295.291007) (xy 338.479607 -295.292998) (xy 338.612315 -295.302943) (xy 338.744191 -295.320807)
			(xy 338.874762 -295.346525) (xy 339.003562 -295.380006) (xy 339.130128 -295.42113) (xy 339.254009 -295.46975)
			(xy 339.37476 -295.525691) (xy 339.49195 -295.588753) (xy 339.605159 -295.658711) (xy 339.713981 -295.735315)
			(xy 339.818027 -295.818289) (xy 339.916925 -295.907337) (xy 340.01032 -296.00214) (xy 340.097878 -296.102358)
			(xy 340.179287 -296.207634) (xy 340.254253 -296.31759) (xy 340.32251 -296.431832) (xy 340.383812 -296.549952)
			(xy 340.437941 -296.671527) (xy 340.484702 -296.796121) (xy 340.523928 -296.923289) (xy 340.555478 -297.052575)
			(xy 340.565056 -297.105351) (xy 351.198901 -297.105351) (xy 351.198901 -297.050849) (xy 351.206658 -296.9969)
			(xy 351.222015 -296.944606) (xy 351.244658 -296.895029) (xy 351.274126 -296.849179) (xy 351.30982 -296.80799)
			(xy 351.351013 -296.772301) (xy 351.396865 -296.742837) (xy 351.446445 -296.7202) (xy 351.498742 -296.70485)
			(xy 351.55269 -296.697098) (xy 351.579942 -296.696638) (xy 351.606876 -296.697117) (xy 351.660206 -296.704704)
			(xy 351.711939 -296.719719) (xy 351.761043 -296.741865) (xy 351.806543 -296.770701) (xy 351.827338 -296.787824)
			(xy 351.838806 -296.796875) (xy 351.865494 -296.808722) (xy 351.89444 -296.812561) (xy 351.923294 -296.808079)
			(xy 351.949712 -296.795641) (xy 351.960942 -296.7863) (xy 351.982009 -296.768133) (xy 352.028438 -296.737494)
			(xy 352.078823 -296.713918) (xy 352.132095 -296.697905) (xy 352.187129 -296.689794) (xy 352.214942 -296.689272)
			(xy 352.24219 -296.689801) (xy 352.29613 -296.697562) (xy 352.348417 -296.71292) (xy 352.397986 -296.735562)
			(xy 352.443829 -296.765028) (xy 352.485012 -296.800718) (xy 352.520697 -296.841905) (xy 352.550158 -296.887751)
			(xy 352.572795 -296.937322) (xy 352.588147 -296.989611) (xy 352.595902 -297.043552) (xy 352.595902 -297.098048)
			(xy 352.588147 -297.151989) (xy 352.572795 -297.204278) (xy 352.563446 -297.224751) (xy 357.228881 -297.224751)
			(xy 357.228881 -297.170249) (xy 357.236638 -297.116301) (xy 357.251993 -297.064007) (xy 357.274634 -297.01443)
			(xy 357.3041 -296.96858) (xy 357.339792 -296.92739) (xy 357.380982 -296.891699) (xy 357.426832 -296.862233)
			(xy 357.476409 -296.839592) (xy 357.528703 -296.824237) (xy 357.582651 -296.816481) (xy 357.609902 -296.816018)
			(xy 357.640025 -296.816597) (xy 357.699521 -296.826077) (xy 357.756788 -296.844787) (xy 357.810405 -296.872261)
			(xy 357.85904 -296.907816) (xy 357.880666 -296.928794) (xy 357.890388 -296.938012) (xy 357.91355 -296.951457)
			(xy 357.939411 -296.958419) (xy 357.966193 -296.958419) (xy 357.992054 -296.951457) (xy 358.015216 -296.938012)
			(xy 358.024938 -296.928794) (xy 358.046566 -296.907817) (xy 358.095194 -296.872249) (xy 358.14881 -296.844768)
			(xy 358.206079 -296.826059) (xy 358.265578 -296.816587) (xy 358.295702 -296.816018) (xy 358.322955 -296.816452)
			(xy 358.376906 -296.824209) (xy 358.429204 -296.839566) (xy 358.478785 -296.862208) (xy 358.524638 -296.891677)
			(xy 358.565831 -296.927371) (xy 358.601524 -296.968564) (xy 358.630993 -297.014417) (xy 358.653635 -297.063998)
			(xy 358.668991 -297.116296) (xy 358.676748 -297.170247) (xy 358.676748 -297.224749) (xy 363.572304 -297.224749)
			(xy 363.572304 -297.170251) (xy 363.58006 -297.116307) (xy 363.595414 -297.064016) (xy 363.618054 -297.014442)
			(xy 363.647518 -296.968595) (xy 363.683206 -296.927408) (xy 363.724394 -296.891719) (xy 363.770241 -296.862254)
			(xy 363.819814 -296.839615) (xy 363.872105 -296.824261) (xy 363.926049 -296.816504) (xy 363.953298 -296.816018)
			(xy 363.980668 -296.816481) (xy 364.034848 -296.824299) (xy 364.087351 -296.839788) (xy 364.137098 -296.862631)
			(xy 364.183065 -296.892356) (xy 364.203996 -296.909998) (xy 364.215324 -296.919234) (xy 364.241881 -296.93141)
			(xy 364.270798 -296.935583) (xy 364.299715 -296.93141) (xy 364.326272 -296.919234) (xy 364.3376 -296.909998)
			(xy 364.358521 -296.892345) (xy 364.404497 -296.862635) (xy 364.454247 -296.839802) (xy 364.50675 -296.824314)
			(xy 364.560928 -296.81649) (xy 364.588298 -296.816018) (xy 364.615553 -296.816429) (xy 364.669508 -296.824186)
			(xy 364.721809 -296.839543) (xy 364.771393 -296.862187) (xy 364.81725 -296.891657) (xy 364.858446 -296.927353)
			(xy 364.894142 -296.968549) (xy 364.923612 -297.014405) (xy 364.946256 -297.063989) (xy 364.961614 -297.11629)
			(xy 364.969371 -297.170245) (xy 364.969371 -297.197526) (xy 370.181376 -297.197526) (xy 370.185447 -297.141904)
			(xy 370.197573 -297.087467) (xy 370.217496 -297.035376) (xy 370.244792 -296.986741) (xy 370.278878 -296.942598)
			(xy 370.319027 -296.903889) (xy 370.364385 -296.871438) (xy 370.413985 -296.845937) (xy 370.466769 -296.82793)
			(xy 370.521612 -296.8178) (xy 370.577346 -296.815763) (xy 370.632783 -296.821863) (xy 370.68674 -296.835969)
			(xy 370.738069 -296.857781) (xy 370.785675 -296.886835) (xy 370.828543 -296.92251) (xy 370.86576 -296.964047)
			(xy 370.896533 -297.01056) (xy 370.920205 -297.061057) (xy 370.936273 -297.114464) (xy 370.944393 -297.16964)
			(xy 370.944902 -297.197526) (xy 370.944393 -297.225412) (xy 370.936273 -297.280588) (xy 370.920205 -297.333995)
			(xy 370.896533 -297.384492) (xy 370.86576 -297.431005) (xy 370.828543 -297.472542) (xy 370.785675 -297.508217)
			(xy 370.774518 -297.515026) (xy 379.13565 -297.515026) (xy 379.139631 -297.382006) (xy 379.15156 -297.249461)
			(xy 379.171395 -297.117868) (xy 379.199064 -296.987696) (xy 379.234468 -296.859411) (xy 379.277481 -296.733474)
			(xy 379.327948 -296.610335) (xy 379.385689 -296.490434) (xy 379.450498 -296.374201) (xy 379.522142 -296.262051)
			(xy 379.600364 -296.154387) (xy 379.684885 -296.051594) (xy 379.775403 -295.954039) (xy 379.871592 -295.862073)
			(xy 379.97311 -295.776023) (xy 380.079591 -295.696199) (xy 380.190656 -295.622886) (xy 380.305907 -295.556346)
			(xy 380.424931 -295.496817) (xy 380.547302 -295.444513) (xy 380.672581 -295.399621) (xy 380.800322 -295.362302)
			(xy 380.930065 -295.332689) (xy 381.061347 -295.310888) (xy 381.193698 -295.296978) (xy 381.326644 -295.291007)
			(xy 381.459709 -295.292998) (xy 381.592417 -295.302943) (xy 381.724293 -295.320807) (xy 381.854864 -295.346525)
			(xy 381.983664 -295.380006) (xy 382.11023 -295.42113) (xy 382.234111 -295.46975) (xy 382.354862 -295.525691)
			(xy 382.472052 -295.588753) (xy 382.585261 -295.658711) (xy 382.694083 -295.735315) (xy 382.798129 -295.818289)
			(xy 382.897027 -295.907337) (xy 382.990422 -296.00214) (xy 383.07798 -296.102358) (xy 383.159389 -296.207634)
			(xy 383.234355 -296.31759) (xy 383.302612 -296.431832) (xy 383.363914 -296.549952) (xy 383.418043 -296.671527)
			(xy 383.464804 -296.796121) (xy 383.50403 -296.923289) (xy 383.53558 -297.052575) (xy 383.559343 -297.183516)
			(xy 383.575232 -297.315644) (xy 383.58319 -297.448486) (xy 383.583688 -297.515026) (xy 383.58319 -297.581566)
			(xy 383.575232 -297.714408) (xy 383.559343 -297.846536) (xy 383.53558 -297.977477) (xy 383.50403 -298.106763)
			(xy 383.464804 -298.233931) (xy 383.418043 -298.358525) (xy 383.363914 -298.4801) (xy 383.302612 -298.59822)
			(xy 383.234355 -298.712462) (xy 383.159389 -298.822418) (xy 383.07798 -298.927694) (xy 382.990422 -299.027912)
			(xy 382.897027 -299.122715) (xy 382.798129 -299.211763) (xy 382.694083 -299.294737) (xy 382.585261 -299.371341)
			(xy 382.472052 -299.441299) (xy 382.354862 -299.504361) (xy 382.234111 -299.560302) (xy 382.11023 -299.608922)
			(xy 381.983664 -299.650046) (xy 381.854864 -299.683527) (xy 381.724293 -299.709245) (xy 381.592417 -299.727109)
			(xy 381.459709 -299.737054) (xy 381.326644 -299.739045) (xy 381.193698 -299.733074) (xy 381.061347 -299.719164)
			(xy 380.930065 -299.697363) (xy 380.800322 -299.66775) (xy 380.672581 -299.630431) (xy 380.547302 -299.585539)
			(xy 380.424931 -299.533235) (xy 380.305907 -299.473706) (xy 380.190656 -299.407166) (xy 380.079591 -299.333853)
			(xy 379.97311 -299.254029) (xy 379.871592 -299.167979) (xy 379.775403 -299.076013) (xy 379.684885 -298.978458)
			(xy 379.600364 -298.875665) (xy 379.522142 -298.768001) (xy 379.450498 -298.655851) (xy 379.385689 -298.539618)
			(xy 379.327948 -298.419717) (xy 379.277481 -298.296578) (xy 379.234468 -298.170641) (xy 379.199064 -298.042356)
			(xy 379.171395 -297.912184) (xy 379.15156 -297.780591) (xy 379.139631 -297.648046) (xy 379.13565 -297.515026)
			(xy 370.774518 -297.515026) (xy 370.738069 -297.537271) (xy 370.68674 -297.559083) (xy 370.632783 -297.573189)
			(xy 370.577346 -297.579289) (xy 370.521612 -297.577252) (xy 370.466769 -297.567122) (xy 370.413985 -297.549115)
			(xy 370.364385 -297.523614) (xy 370.319027 -297.491163) (xy 370.278878 -297.452454) (xy 370.244792 -297.408311)
			(xy 370.217496 -297.359676) (xy 370.197573 -297.307585) (xy 370.185447 -297.253148) (xy 370.181376 -297.197526)
			(xy 364.969371 -297.197526) (xy 364.969371 -297.224755) (xy 364.961614 -297.27871) (xy 364.946256 -297.331011)
			(xy 364.923612 -297.380595) (xy 364.894142 -297.426451) (xy 364.858446 -297.467647) (xy 364.81725 -297.503343)
			(xy 364.771393 -297.532813) (xy 364.721809 -297.555457) (xy 364.669508 -297.570814) (xy 364.615553 -297.578571)
			(xy 364.588298 -297.579034) (xy 364.560927 -297.578585) (xy 364.506746 -297.570766) (xy 364.454243 -297.555273)
			(xy 364.404496 -297.532427) (xy 364.35853 -297.502698) (xy 364.3376 -297.485054) (xy 364.326272 -297.475818)
			(xy 364.299715 -297.463642) (xy 364.270798 -297.459469) (xy 364.241881 -297.463642) (xy 364.215324 -297.475818)
			(xy 364.203996 -297.485054) (xy 364.18307 -297.502701) (xy 364.137097 -297.532413) (xy 364.087347 -297.555249)
			(xy 364.034845 -297.570738) (xy 363.980668 -297.578562) (xy 363.953298 -297.579034) (xy 363.926049 -297.578496)
			(xy 363.872105 -297.570739) (xy 363.819814 -297.555385) (xy 363.770241 -297.532746) (xy 363.724394 -297.503281)
			(xy 363.683206 -297.467592) (xy 363.647518 -297.426405) (xy 363.618054 -297.380558) (xy 363.595414 -297.330984)
			(xy 363.58006 -297.278693) (xy 363.572304 -297.224749) (xy 358.676748 -297.224749) (xy 358.676748 -297.224753)
			(xy 358.668991 -297.278704) (xy 358.653635 -297.331002) (xy 358.630993 -297.380583) (xy 358.601524 -297.426436)
			(xy 358.565831 -297.467629) (xy 358.524638 -297.503323) (xy 358.478785 -297.532792) (xy 358.429204 -297.555434)
			(xy 358.376906 -297.570791) (xy 358.322955 -297.578548) (xy 358.295702 -297.579034) (xy 358.265578 -297.578467)
			(xy 358.206082 -297.568986) (xy 358.148813 -297.550274) (xy 358.095196 -297.522797) (xy 358.046562 -297.487238)
			(xy 358.024938 -297.466258) (xy 358.015216 -297.45704) (xy 357.992054 -297.443595) (xy 357.966193 -297.436633)
			(xy 357.939411 -297.436633) (xy 357.91355 -297.443595) (xy 357.890388 -297.45704) (xy 357.880666 -297.466258)
			(xy 357.859028 -297.487224) (xy 357.810404 -297.522796) (xy 357.756791 -297.55028) (xy 357.699523 -297.568991)
			(xy 357.640025 -297.578465) (xy 357.609902 -297.579034) (xy 357.582651 -297.578519) (xy 357.528703 -297.570763)
			(xy 357.476409 -297.555408) (xy 357.426832 -297.532767) (xy 357.380982 -297.503301) (xy 357.339792 -297.46761)
			(xy 357.3041 -297.42642) (xy 357.274634 -297.38057) (xy 357.251993 -297.330993) (xy 357.236638 -297.278699)
			(xy 357.228881 -297.224751) (xy 352.563446 -297.224751) (xy 352.550158 -297.253849) (xy 352.520697 -297.299695)
			(xy 352.485012 -297.340882) (xy 352.443829 -297.376572) (xy 352.397986 -297.406038) (xy 352.348417 -297.42868)
			(xy 352.29613 -297.444038) (xy 352.24219 -297.451799) (xy 352.214942 -297.452288) (xy 352.188008 -297.451812)
			(xy 352.134678 -297.444224) (xy 352.082946 -297.429207) (xy 352.033841 -297.407061) (xy 351.988342 -297.378225)
			(xy 351.967546 -297.361102) (xy 351.956087 -297.352042) (xy 351.929394 -297.340206) (xy 351.900448 -297.336373)
			(xy 351.871595 -297.340855) (xy 351.845175 -297.353289) (xy 351.833942 -297.362626) (xy 351.812846 -297.380757)
			(xy 351.766425 -297.411401) (xy 351.716047 -297.434983) (xy 351.662781 -297.451005) (xy 351.607753 -297.459127)
			(xy 351.579942 -297.459654) (xy 351.55269 -297.459102) (xy 351.498741 -297.45135) (xy 351.446445 -297.436)
			(xy 351.396865 -297.413363) (xy 351.351013 -297.383899) (xy 351.30982 -297.34821) (xy 351.274126 -297.307021)
			(xy 351.244658 -297.261171) (xy 351.222015 -297.211594) (xy 351.206658 -297.1593) (xy 351.198901 -297.105351)
			(xy 340.565056 -297.105351) (xy 340.579241 -297.183516) (xy 340.59513 -297.315644) (xy 340.603088 -297.448486)
			(xy 340.603586 -297.515026) (xy 340.603088 -297.581566) (xy 340.59513 -297.714408) (xy 340.579241 -297.846536)
			(xy 340.555478 -297.977477) (xy 340.523928 -298.106763) (xy 340.484702 -298.233931) (xy 340.437941 -298.358525)
			(xy 340.383812 -298.4801) (xy 340.32251 -298.59822) (xy 340.254253 -298.712462) (xy 340.179287 -298.822418)
			(xy 340.097878 -298.927694) (xy 340.01032 -299.027912) (xy 339.916925 -299.122715) (xy 339.818027 -299.211763)
			(xy 339.713981 -299.294737) (xy 339.605159 -299.371341) (xy 339.49195 -299.441299) (xy 339.37476 -299.504361)
			(xy 339.254009 -299.560302) (xy 339.130128 -299.608922) (xy 339.003562 -299.650046) (xy 338.874762 -299.683527)
			(xy 338.744191 -299.709245) (xy 338.612315 -299.727109) (xy 338.479607 -299.737054) (xy 338.346542 -299.739045)
			(xy 338.213596 -299.733074) (xy 338.081245 -299.719164) (xy 337.949963 -299.697363) (xy 337.82022 -299.66775)
			(xy 337.692479 -299.630431) (xy 337.5672 -299.585539) (xy 337.444829 -299.533235) (xy 337.325805 -299.473706)
			(xy 337.210554 -299.407166) (xy 337.099489 -299.333853) (xy 336.993008 -299.254029) (xy 336.89149 -299.167979)
			(xy 336.795301 -299.076013) (xy 336.704783 -298.978458) (xy 336.620262 -298.875665) (xy 336.54204 -298.768001)
			(xy 336.470396 -298.655851) (xy 336.405587 -298.539618) (xy 336.347846 -298.419717) (xy 336.297379 -298.296578)
			(xy 336.254366 -298.170641) (xy 336.218962 -298.042356) (xy 336.191293 -297.912184) (xy 336.171458 -297.780591)
			(xy 336.159529 -297.648046) (xy 336.155548 -297.515026) (xy 334.04048 -297.515026) (xy 334.04048 -312.740548)
			(xy 333.480336 -315.709738) (xy 345.576648 -315.709738) (xy 345.576648 -315.625042) (xy 345.584699 -315.540728)
			(xy 345.600728 -315.457562) (xy 345.624589 -315.376295) (xy 345.656068 -315.297665) (xy 345.694879 -315.222384)
			(xy 345.740669 -315.151132) (xy 345.793025 -315.084556) (xy 345.851473 -315.023258) (xy 345.915483 -314.967793)
			(xy 345.984475 -314.918664) (xy 346.057825 -314.876315) (xy 346.134868 -314.841131) (xy 346.214907 -314.813429)
			(xy 346.297216 -314.793461) (xy 346.381051 -314.781408) (xy 346.465652 -314.777378) (xy 346.550253 -314.781408)
			(xy 346.634088 -314.793461) (xy 346.716397 -314.813429) (xy 346.796436 -314.841131) (xy 346.873479 -314.876315)
			(xy 346.946829 -314.918664) (xy 347.015821 -314.967793) (xy 347.079831 -315.023258) (xy 347.138279 -315.084556)
			(xy 347.190635 -315.151132) (xy 347.236425 -315.222384) (xy 347.275236 -315.297665) (xy 347.306715 -315.376295)
			(xy 347.330576 -315.457562) (xy 347.346605 -315.540728) (xy 347.354656 -315.625042) (xy 347.35516 -315.66739)
			(xy 347.550237 -315.66739) (xy 347.554259 -315.58167) (xy 347.56629 -315.496702) (xy 347.586226 -315.413235)
			(xy 347.613889 -315.332001) (xy 347.649038 -315.253715) (xy 347.691364 -315.179064) (xy 347.740493 -315.108705)
			(xy 347.795996 -315.043255) (xy 347.857383 -314.983291) (xy 347.924116 -314.929338) (xy 347.995608 -314.881871)
			(xy 348.07123 -314.841307) (xy 348.150319 -314.808003) (xy 348.232179 -314.782251) (xy 348.31609 -314.764278)
			(xy 348.401316 -314.754242) (xy 348.487108 -314.75223) (xy 348.57271 -314.758261) (xy 348.657372 -314.772281)
			(xy 348.740349 -314.794167) (xy 348.820912 -314.823728) (xy 348.898352 -314.860702) (xy 348.971991 -314.904766)
			(xy 349.041179 -314.955532) (xy 349.10531 -315.012553) (xy 349.163819 -315.075329) (xy 349.216192 -315.143309)
			(xy 349.26197 -315.215894) (xy 349.30075 -315.292446) (xy 349.332191 -315.372294) (xy 349.356017 -315.454735)
			(xy 349.372018 -315.539045) (xy 349.380053 -315.624483) (xy 349.380556 -315.66739) (xy 349.38006 -315.709738)
			(xy 351.774248 -315.709738) (xy 351.774248 -315.625042) (xy 351.782299 -315.540728) (xy 351.798328 -315.457562)
			(xy 351.822189 -315.376295) (xy 351.853668 -315.297665) (xy 351.892479 -315.222384) (xy 351.938269 -315.151132)
			(xy 351.990625 -315.084556) (xy 352.049073 -315.023258) (xy 352.113083 -314.967793) (xy 352.182075 -314.918664)
			(xy 352.255425 -314.876315) (xy 352.332468 -314.841131) (xy 352.412507 -314.813429) (xy 352.494816 -314.793461)
			(xy 352.578651 -314.781408) (xy 352.663252 -314.777378) (xy 352.747853 -314.781408) (xy 352.831688 -314.793461)
			(xy 352.913997 -314.813429) (xy 352.994036 -314.841131) (xy 353.071079 -314.876315) (xy 353.144429 -314.918664)
			(xy 353.213421 -314.967793) (xy 353.277431 -315.023258) (xy 353.335879 -315.084556) (xy 353.388235 -315.151132)
			(xy 353.434025 -315.222384) (xy 353.472836 -315.297665) (xy 353.504315 -315.376295) (xy 353.528176 -315.457562)
			(xy 353.544205 -315.540728) (xy 353.552256 -315.625042) (xy 353.55276 -315.66739) (xy 353.747837 -315.66739)
			(xy 353.751859 -315.58167) (xy 353.76389 -315.496702) (xy 353.783826 -315.413235) (xy 353.811489 -315.332001)
			(xy 353.846638 -315.253715) (xy 353.888964 -315.179064) (xy 353.938093 -315.108705) (xy 353.993596 -315.043255)
			(xy 354.054983 -314.983291) (xy 354.121716 -314.929338) (xy 354.193208 -314.881871) (xy 354.26883 -314.841307)
			(xy 354.347919 -314.808003) (xy 354.429779 -314.782251) (xy 354.51369 -314.764278) (xy 354.598916 -314.754242)
			(xy 354.684708 -314.75223) (xy 354.77031 -314.758261) (xy 354.854972 -314.772281) (xy 354.937949 -314.794167)
			(xy 355.018512 -314.823728) (xy 355.095952 -314.860702) (xy 355.169591 -314.904766) (xy 355.238779 -314.955532)
			(xy 355.30291 -315.012553) (xy 355.361419 -315.075329) (xy 355.413792 -315.143309) (xy 355.45957 -315.215894)
			(xy 355.49835 -315.292446) (xy 355.529791 -315.372294) (xy 355.553617 -315.454735) (xy 355.569618 -315.539045)
			(xy 355.577653 -315.624483) (xy 355.578156 -315.66739) (xy 355.57766 -315.709738) (xy 357.952036 -315.709738)
			(xy 357.952036 -315.625042) (xy 357.960087 -315.540728) (xy 357.976116 -315.457562) (xy 357.999977 -315.376295)
			(xy 358.031456 -315.297665) (xy 358.070267 -315.222384) (xy 358.116057 -315.151132) (xy 358.168413 -315.084556)
			(xy 358.226861 -315.023258) (xy 358.290871 -314.967793) (xy 358.359863 -314.918664) (xy 358.433213 -314.876315)
			(xy 358.510256 -314.841131) (xy 358.590295 -314.813429) (xy 358.672604 -314.793461) (xy 358.756439 -314.781408)
			(xy 358.84104 -314.777378) (xy 358.925641 -314.781408) (xy 359.009476 -314.793461) (xy 359.091785 -314.813429)
			(xy 359.171824 -314.841131) (xy 359.248867 -314.876315) (xy 359.322217 -314.918664) (xy 359.391209 -314.967793)
			(xy 359.455219 -315.023258) (xy 359.513667 -315.084556) (xy 359.566023 -315.151132) (xy 359.611813 -315.222384)
			(xy 359.650624 -315.297665) (xy 359.682103 -315.376295) (xy 359.705964 -315.457562) (xy 359.721993 -315.540728)
			(xy 359.730044 -315.625042) (xy 359.730548 -315.66739) (xy 359.925625 -315.66739) (xy 359.929647 -315.58167)
			(xy 359.941678 -315.496702) (xy 359.961614 -315.413235) (xy 359.989277 -315.332001) (xy 360.024426 -315.253715)
			(xy 360.066752 -315.179064) (xy 360.115881 -315.108705) (xy 360.171384 -315.043255) (xy 360.232771 -314.983291)
			(xy 360.299504 -314.929338) (xy 360.370996 -314.881871) (xy 360.446618 -314.841307) (xy 360.525707 -314.808003)
			(xy 360.607567 -314.782251) (xy 360.691478 -314.764278) (xy 360.776704 -314.754242) (xy 360.862496 -314.75223)
			(xy 360.948098 -314.758261) (xy 361.03276 -314.772281) (xy 361.115737 -314.794167) (xy 361.1963 -314.823728)
			(xy 361.27374 -314.860702) (xy 361.347379 -314.904766) (xy 361.416567 -314.955532) (xy 361.480698 -315.012553)
			(xy 361.539207 -315.075329) (xy 361.59158 -315.143309) (xy 361.637358 -315.215894) (xy 361.676138 -315.292446)
			(xy 361.707579 -315.372294) (xy 361.731405 -315.454735) (xy 361.747406 -315.539045) (xy 361.755441 -315.624483)
			(xy 361.755944 -315.66739) (xy 361.755448 -315.709738) (xy 364.149636 -315.709738) (xy 364.149636 -315.625042)
			(xy 364.157687 -315.540728) (xy 364.173716 -315.457562) (xy 364.197577 -315.376295) (xy 364.229056 -315.297665)
			(xy 364.267867 -315.222384) (xy 364.313657 -315.151132) (xy 364.366013 -315.084556) (xy 364.424461 -315.023258)
			(xy 364.488471 -314.967793) (xy 364.557463 -314.918664) (xy 364.630813 -314.876315) (xy 364.707856 -314.841131)
			(xy 364.787895 -314.813429) (xy 364.870204 -314.793461) (xy 364.954039 -314.781408) (xy 365.03864 -314.777378)
			(xy 365.123241 -314.781408) (xy 365.207076 -314.793461) (xy 365.289385 -314.813429) (xy 365.369424 -314.841131)
			(xy 365.446467 -314.876315) (xy 365.519817 -314.918664) (xy 365.588809 -314.967793) (xy 365.652819 -315.023258)
			(xy 365.711267 -315.084556) (xy 365.763623 -315.151132) (xy 365.809413 -315.222384) (xy 365.848224 -315.297665)
			(xy 365.879703 -315.376295) (xy 365.903564 -315.457562) (xy 365.919593 -315.540728) (xy 365.927644 -315.625042)
			(xy 365.928148 -315.66739) (xy 366.123225 -315.66739) (xy 366.127247 -315.58167) (xy 366.139278 -315.496702)
			(xy 366.159214 -315.413235) (xy 366.186877 -315.332001) (xy 366.222026 -315.253715) (xy 366.264352 -315.179064)
			(xy 366.313481 -315.108705) (xy 366.368984 -315.043255) (xy 366.430371 -314.983291) (xy 366.497104 -314.929338)
			(xy 366.568596 -314.881871) (xy 366.644218 -314.841307) (xy 366.723307 -314.808003) (xy 366.805167 -314.782251)
			(xy 366.889078 -314.764278) (xy 366.974304 -314.754242) (xy 367.060096 -314.75223) (xy 367.145698 -314.758261)
			(xy 367.23036 -314.772281) (xy 367.313337 -314.794167) (xy 367.3939 -314.823728) (xy 367.47134 -314.860702)
			(xy 367.544979 -314.904766) (xy 367.614167 -314.955532) (xy 367.678298 -315.012553) (xy 367.736807 -315.075329)
			(xy 367.78918 -315.143309) (xy 367.834958 -315.215894) (xy 367.873738 -315.292446) (xy 367.905179 -315.372294)
			(xy 367.929005 -315.454735) (xy 367.945006 -315.539045) (xy 367.953041 -315.624483) (xy 367.953544 -315.66739)
			(xy 367.953048 -315.709738) (xy 370.347236 -315.709738) (xy 370.347236 -315.625042) (xy 370.355287 -315.540728)
			(xy 370.371316 -315.457562) (xy 370.395177 -315.376295) (xy 370.426656 -315.297665) (xy 370.465467 -315.222384)
			(xy 370.511257 -315.151132) (xy 370.563613 -315.084556) (xy 370.622061 -315.023258) (xy 370.686071 -314.967793)
			(xy 370.755063 -314.918664) (xy 370.828413 -314.876315) (xy 370.905456 -314.841131) (xy 370.985495 -314.813429)
			(xy 371.067804 -314.793461) (xy 371.151639 -314.781408) (xy 371.23624 -314.777378) (xy 371.320841 -314.781408)
			(xy 371.404676 -314.793461) (xy 371.486985 -314.813429) (xy 371.567024 -314.841131) (xy 371.644067 -314.876315)
			(xy 371.717417 -314.918664) (xy 371.786409 -314.967793) (xy 371.850419 -315.023258) (xy 371.908867 -315.084556)
			(xy 371.961223 -315.151132) (xy 372.007013 -315.222384) (xy 372.045824 -315.297665) (xy 372.077303 -315.376295)
			(xy 372.101164 -315.457562) (xy 372.117193 -315.540728) (xy 372.125244 -315.625042) (xy 372.125748 -315.66739)
			(xy 372.320825 -315.66739) (xy 372.324847 -315.58167) (xy 372.336878 -315.496702) (xy 372.356814 -315.413235)
			(xy 372.384477 -315.332001) (xy 372.419626 -315.253715) (xy 372.461952 -315.179064) (xy 372.511081 -315.108705)
			(xy 372.566584 -315.043255) (xy 372.627971 -314.983291) (xy 372.694704 -314.929338) (xy 372.766196 -314.881871)
			(xy 372.841818 -314.841307) (xy 372.920907 -314.808003) (xy 373.002767 -314.782251) (xy 373.086678 -314.764278)
			(xy 373.171904 -314.754242) (xy 373.257696 -314.75223) (xy 373.343298 -314.758261) (xy 373.42796 -314.772281)
			(xy 373.510937 -314.794167) (xy 373.5915 -314.823728) (xy 373.66894 -314.860702) (xy 373.742579 -314.904766)
			(xy 373.811767 -314.955532) (xy 373.875898 -315.012553) (xy 373.934407 -315.075329) (xy 373.98678 -315.143309)
			(xy 374.032558 -315.215894) (xy 374.071338 -315.292446) (xy 374.102779 -315.372294) (xy 374.126605 -315.454735)
			(xy 374.142606 -315.539045) (xy 374.150641 -315.624483) (xy 374.151144 -315.66739) (xy 374.150641 -315.710297)
			(xy 374.142606 -315.795735) (xy 374.126605 -315.880045) (xy 374.102779 -315.962486) (xy 374.071338 -316.042334)
			(xy 374.032558 -316.118886) (xy 373.98678 -316.191471) (xy 373.934407 -316.259451) (xy 373.875898 -316.322227)
			(xy 373.811767 -316.379248) (xy 373.742579 -316.430014) (xy 373.66894 -316.474078) (xy 373.5915 -316.511052)
			(xy 373.510937 -316.540613) (xy 373.42796 -316.562499) (xy 373.343298 -316.576519) (xy 373.257696 -316.58255)
			(xy 373.171904 -316.580538) (xy 373.086678 -316.570502) (xy 373.002767 -316.552529) (xy 372.920907 -316.526777)
			(xy 372.841818 -316.493473) (xy 372.766196 -316.452909) (xy 372.694704 -316.405442) (xy 372.627971 -316.351489)
			(xy 372.566584 -316.291525) (xy 372.511081 -316.226075) (xy 372.461952 -316.155716) (xy 372.419626 -316.081065)
			(xy 372.384477 -316.002779) (xy 372.356814 -315.921545) (xy 372.336878 -315.838078) (xy 372.324847 -315.75311)
			(xy 372.320825 -315.66739) (xy 372.125748 -315.66739) (xy 372.125244 -315.709738) (xy 372.117193 -315.794052)
			(xy 372.101164 -315.877218) (xy 372.077303 -315.958485) (xy 372.045824 -316.037115) (xy 372.007013 -316.112396)
			(xy 371.961223 -316.183648) (xy 371.908867 -316.250224) (xy 371.850419 -316.311522) (xy 371.786409 -316.366987)
			(xy 371.717417 -316.416116) (xy 371.644067 -316.458465) (xy 371.567024 -316.493649) (xy 371.486985 -316.521351)
			(xy 371.404676 -316.541319) (xy 371.320841 -316.553372) (xy 371.23624 -316.557403) (xy 371.151639 -316.553372)
			(xy 371.067804 -316.541319) (xy 370.985495 -316.521351) (xy 370.905456 -316.493649) (xy 370.828413 -316.458465)
			(xy 370.755063 -316.416116) (xy 370.686071 -316.366987) (xy 370.622061 -316.311522) (xy 370.563613 -316.250224)
			(xy 370.511257 -316.183648) (xy 370.465467 -316.112396) (xy 370.426656 -316.037115) (xy 370.395177 -315.958485)
			(xy 370.371316 -315.877218) (xy 370.355287 -315.794052) (xy 370.347236 -315.709738) (xy 367.953048 -315.709738)
			(xy 367.953041 -315.710297) (xy 367.945006 -315.795735) (xy 367.929005 -315.880045) (xy 367.905179 -315.962486)
			(xy 367.873738 -316.042334) (xy 367.834958 -316.118886) (xy 367.78918 -316.191471) (xy 367.736807 -316.259451)
			(xy 367.678298 -316.322227) (xy 367.614167 -316.379248) (xy 367.544979 -316.430014) (xy 367.47134 -316.474078)
			(xy 367.3939 -316.511052) (xy 367.313337 -316.540613) (xy 367.23036 -316.562499) (xy 367.145698 -316.576519)
			(xy 367.060096 -316.58255) (xy 366.974304 -316.580538) (xy 366.889078 -316.570502) (xy 366.805167 -316.552529)
			(xy 366.723307 -316.526777) (xy 366.644218 -316.493473) (xy 366.568596 -316.452909) (xy 366.497104 -316.405442)
			(xy 366.430371 -316.351489) (xy 366.368984 -316.291525) (xy 366.313481 -316.226075) (xy 366.264352 -316.155716)
			(xy 366.222026 -316.081065) (xy 366.186877 -316.002779) (xy 366.159214 -315.921545) (xy 366.139278 -315.838078)
			(xy 366.127247 -315.75311) (xy 366.123225 -315.66739) (xy 365.928148 -315.66739) (xy 365.927644 -315.709738)
			(xy 365.919593 -315.794052) (xy 365.903564 -315.877218) (xy 365.879703 -315.958485) (xy 365.848224 -316.037115)
			(xy 365.809413 -316.112396) (xy 365.763623 -316.183648) (xy 365.711267 -316.250224) (xy 365.652819 -316.311522)
			(xy 365.588809 -316.366987) (xy 365.519817 -316.416116) (xy 365.446467 -316.458465) (xy 365.369424 -316.493649)
			(xy 365.289385 -316.521351) (xy 365.207076 -316.541319) (xy 365.123241 -316.553372) (xy 365.03864 -316.557403)
			(xy 364.954039 -316.553372) (xy 364.870204 -316.541319) (xy 364.787895 -316.521351) (xy 364.707856 -316.493649)
			(xy 364.630813 -316.458465) (xy 364.557463 -316.416116) (xy 364.488471 -316.366987) (xy 364.424461 -316.311522)
			(xy 364.366013 -316.250224) (xy 364.313657 -316.183648) (xy 364.267867 -316.112396) (xy 364.229056 -316.037115)
			(xy 364.197577 -315.958485) (xy 364.173716 -315.877218) (xy 364.157687 -315.794052) (xy 364.149636 -315.709738)
			(xy 361.755448 -315.709738) (xy 361.755441 -315.710297) (xy 361.747406 -315.795735) (xy 361.731405 -315.880045)
			(xy 361.707579 -315.962486) (xy 361.676138 -316.042334) (xy 361.637358 -316.118886) (xy 361.59158 -316.191471)
			(xy 361.539207 -316.259451) (xy 361.480698 -316.322227) (xy 361.416567 -316.379248) (xy 361.347379 -316.430014)
			(xy 361.27374 -316.474078) (xy 361.1963 -316.511052) (xy 361.115737 -316.540613) (xy 361.03276 -316.562499)
			(xy 360.948098 -316.576519) (xy 360.862496 -316.58255) (xy 360.776704 -316.580538) (xy 360.691478 -316.570502)
			(xy 360.607567 -316.552529) (xy 360.525707 -316.526777) (xy 360.446618 -316.493473) (xy 360.370996 -316.452909)
			(xy 360.299504 -316.405442) (xy 360.232771 -316.351489) (xy 360.171384 -316.291525) (xy 360.115881 -316.226075)
			(xy 360.066752 -316.155716) (xy 360.024426 -316.081065) (xy 359.989277 -316.002779) (xy 359.961614 -315.921545)
			(xy 359.941678 -315.838078) (xy 359.929647 -315.75311) (xy 359.925625 -315.66739) (xy 359.730548 -315.66739)
			(xy 359.730044 -315.709738) (xy 359.721993 -315.794052) (xy 359.705964 -315.877218) (xy 359.682103 -315.958485)
			(xy 359.650624 -316.037115) (xy 359.611813 -316.112396) (xy 359.566023 -316.183648) (xy 359.513667 -316.250224)
			(xy 359.455219 -316.311522) (xy 359.391209 -316.366987) (xy 359.322217 -316.416116) (xy 359.248867 -316.458465)
			(xy 359.171824 -316.493649) (xy 359.091785 -316.521351) (xy 359.009476 -316.541319) (xy 358.925641 -316.553372)
			(xy 358.84104 -316.557403) (xy 358.756439 -316.553372) (xy 358.672604 -316.541319) (xy 358.590295 -316.521351)
			(xy 358.510256 -316.493649) (xy 358.433213 -316.458465) (xy 358.359863 -316.416116) (xy 358.290871 -316.366987)
			(xy 358.226861 -316.311522) (xy 358.168413 -316.250224) (xy 358.116057 -316.183648) (xy 358.070267 -316.112396)
			(xy 358.031456 -316.037115) (xy 357.999977 -315.958485) (xy 357.976116 -315.877218) (xy 357.960087 -315.794052)
			(xy 357.952036 -315.709738) (xy 355.57766 -315.709738) (xy 355.577653 -315.710297) (xy 355.569618 -315.795735)
			(xy 355.553617 -315.880045) (xy 355.529791 -315.962486) (xy 355.49835 -316.042334) (xy 355.45957 -316.118886)
			(xy 355.413792 -316.191471) (xy 355.361419 -316.259451) (xy 355.30291 -316.322227) (xy 355.238779 -316.379248)
			(xy 355.169591 -316.430014) (xy 355.095952 -316.474078) (xy 355.018512 -316.511052) (xy 354.937949 -316.540613)
			(xy 354.854972 -316.562499) (xy 354.77031 -316.576519) (xy 354.684708 -316.58255) (xy 354.598916 -316.580538)
			(xy 354.51369 -316.570502) (xy 354.429779 -316.552529) (xy 354.347919 -316.526777) (xy 354.26883 -316.493473)
			(xy 354.193208 -316.452909) (xy 354.121716 -316.405442) (xy 354.054983 -316.351489) (xy 353.993596 -316.291525)
			(xy 353.938093 -316.226075) (xy 353.888964 -316.155716) (xy 353.846638 -316.081065) (xy 353.811489 -316.002779)
			(xy 353.783826 -315.921545) (xy 353.76389 -315.838078) (xy 353.751859 -315.75311) (xy 353.747837 -315.66739)
			(xy 353.55276 -315.66739) (xy 353.552256 -315.709738) (xy 353.544205 -315.794052) (xy 353.528176 -315.877218)
			(xy 353.504315 -315.958485) (xy 353.472836 -316.037115) (xy 353.434025 -316.112396) (xy 353.388235 -316.183648)
			(xy 353.335879 -316.250224) (xy 353.277431 -316.311522) (xy 353.213421 -316.366987) (xy 353.144429 -316.416116)
			(xy 353.071079 -316.458465) (xy 352.994036 -316.493649) (xy 352.913997 -316.521351) (xy 352.831688 -316.541319)
			(xy 352.747853 -316.553372) (xy 352.663252 -316.557403) (xy 352.578651 -316.553372) (xy 352.494816 -316.541319)
			(xy 352.412507 -316.521351) (xy 352.332468 -316.493649) (xy 352.255425 -316.458465) (xy 352.182075 -316.416116)
			(xy 352.113083 -316.366987) (xy 352.049073 -316.311522) (xy 351.990625 -316.250224) (xy 351.938269 -316.183648)
			(xy 351.892479 -316.112396) (xy 351.853668 -316.037115) (xy 351.822189 -315.958485) (xy 351.798328 -315.877218)
			(xy 351.782299 -315.794052) (xy 351.774248 -315.709738) (xy 349.38006 -315.709738) (xy 349.380053 -315.710297)
			(xy 349.372018 -315.795735) (xy 349.356017 -315.880045) (xy 349.332191 -315.962486) (xy 349.30075 -316.042334)
			(xy 349.26197 -316.118886) (xy 349.216192 -316.191471) (xy 349.163819 -316.259451) (xy 349.10531 -316.322227)
			(xy 349.041179 -316.379248) (xy 348.971991 -316.430014) (xy 348.898352 -316.474078) (xy 348.820912 -316.511052)
			(xy 348.740349 -316.540613) (xy 348.657372 -316.562499) (xy 348.57271 -316.576519) (xy 348.487108 -316.58255)
			(xy 348.401316 -316.580538) (xy 348.31609 -316.570502) (xy 348.232179 -316.552529) (xy 348.150319 -316.526777)
			(xy 348.07123 -316.493473) (xy 347.995608 -316.452909) (xy 347.924116 -316.405442) (xy 347.857383 -316.351489)
			(xy 347.795996 -316.291525) (xy 347.740493 -316.226075) (xy 347.691364 -316.155716) (xy 347.649038 -316.081065)
			(xy 347.613889 -316.002779) (xy 347.586226 -315.921545) (xy 347.56629 -315.838078) (xy 347.554259 -315.75311)
			(xy 347.550237 -315.66739) (xy 347.35516 -315.66739) (xy 347.354656 -315.709738) (xy 347.346605 -315.794052)
			(xy 347.330576 -315.877218) (xy 347.306715 -315.958485) (xy 347.275236 -316.037115) (xy 347.236425 -316.112396)
			(xy 347.190635 -316.183648) (xy 347.138279 -316.250224) (xy 347.079831 -316.311522) (xy 347.015821 -316.366987)
			(xy 346.946829 -316.416116) (xy 346.873479 -316.458465) (xy 346.796436 -316.493649) (xy 346.716397 -316.521351)
			(xy 346.634088 -316.541319) (xy 346.550253 -316.553372) (xy 346.465652 -316.557403) (xy 346.381051 -316.553372)
			(xy 346.297216 -316.541319) (xy 346.214907 -316.521351) (xy 346.134868 -316.493649) (xy 346.057825 -316.458465)
			(xy 345.984475 -316.416116) (xy 345.915483 -316.366987) (xy 345.851473 -316.311522) (xy 345.793025 -316.250224)
			(xy 345.740669 -316.183648) (xy 345.694879 -316.112396) (xy 345.656068 -316.037115) (xy 345.624589 -315.958485)
			(xy 345.600728 -315.877218) (xy 345.584699 -315.794052) (xy 345.576648 -315.709738) (xy 333.480336 -315.709738)
			(xy 332.311756 -321.904106) (xy 328.24928 -327.472548) (xy 328.24928 -332.273402) (xy 328.55408 -332.578202)
			(xy 331.709776 -332.578202)
		)
		(stroke
			(width 0)
			(type solid)
		)
		(fill yes)
		(layer "In13.Cu")
		(net "PVCCIN_CPU0")
	)
	(gr_poly
		(pts
			(xy 84.438998 -331.909166) (xy 84.45373 -331.89418) (xy 84.45373 -330.858876) (xy 84.454158 -330.848808)
			(xy 84.461882 -330.830213) (xy 84.468716 -330.822808) (xy 86.253574 -329.03795) (xy 86.260974 -329.03111)
			(xy 86.279573 -329.023394) (xy 86.289642 -329.022964) (xy 91.840558 -329.022964) (xy 91.85052 -329.022478)
			(xy 91.868943 -329.014889) (xy 91.876372 -329.008232) (xy 95.092774 -325.79183) (xy 95.100175 -325.784992)
			(xy 95.118774 -325.77728) (xy 95.128842 -325.776844) (xy 123.968002 -325.776844) (xy 123.978071 -325.777269)
			(xy 123.996671 -325.784989) (xy 124.00407 -325.79183) (xy 124.075698 -325.863458) (xy 124.075952 -325.863458)
			(xy 124.165106 -325.952612) (xy 124.164852 -325.952612) (xy 127.39624 -329.184) (xy 127.411226 -329.198732)
			(xy 131.99745 -329.198732) (xy 132.007515 -329.199165) (xy 132.026104 -329.206896) (xy 132.033518 -329.213718)
			(xy 133.773418 -330.953364) (xy 134.063994 -331.24394) (xy 134.07898 -331.258672) (xy 139.91463 -331.258672)
			(xy 140.405866 -330.767436) (xy 140.405866 -326.812148) (xy 137.256266 -310.098948) (xy 137.256266 -291.328348)
			(xy 136.037066 -290.109148) (xy 135.380222 -290.109148) (xy 135.370824 -290.112958) (xy 135.350808 -290.120832)
			(xy 135.309248 -290.131913) (xy 135.2666 -290.137493) (xy 135.245094 -290.13785) (xy 135.22359 -290.137483)
			(xy 135.180949 -290.131874) (xy 135.139389 -290.120804) (xy 135.119364 -290.112958) (xy 135.109966 -290.109148)
			(xy 134.440422 -290.109148) (xy 134.431024 -290.112958) (xy 134.411008 -290.120832) (xy 134.369448 -290.131913)
			(xy 134.3268 -290.137493) (xy 134.305294 -290.13785) (xy 134.28379 -290.137483) (xy 134.241149 -290.131874)
			(xy 134.199589 -290.120804) (xy 134.179564 -290.112958) (xy 134.170166 -290.109148) (xy 133.554216 -290.109148)
			(xy 133.529811 -290.123744) (xy 133.477415 -290.145831) (xy 133.422175 -290.159312) (xy 133.365494 -290.163845)
			(xy 133.308813 -290.159312) (xy 133.253573 -290.145831) (xy 133.201177 -290.123744) (xy 133.176772 -290.109148)
			(xy 132.614416 -290.109148) (xy 132.590011 -290.123744) (xy 132.537615 -290.145831) (xy 132.482375 -290.159312)
			(xy 132.425694 -290.163845) (xy 132.369013 -290.159312) (xy 132.313773 -290.145831) (xy 132.261377 -290.123744)
			(xy 132.236972 -290.109148) (xy 131.674616 -290.109148) (xy 131.650211 -290.123744) (xy 131.597815 -290.145831)
			(xy 131.542575 -290.159312) (xy 131.485894 -290.163845) (xy 131.429213 -290.159312) (xy 131.373973 -290.145831)
			(xy 131.321577 -290.123744) (xy 131.297172 -290.109148) (xy 130.734816 -290.109148) (xy 130.710411 -290.123744)
			(xy 130.658015 -290.145831) (xy 130.602775 -290.159312) (xy 130.546094 -290.163845) (xy 130.489413 -290.159312)
			(xy 130.434173 -290.145831) (xy 130.381777 -290.123744) (xy 130.357372 -290.109148) (xy 129.795016 -290.109148)
			(xy 129.770611 -290.123744) (xy 129.718215 -290.145831) (xy 129.662975 -290.159312) (xy 129.606294 -290.163845)
			(xy 129.549613 -290.159312) (xy 129.494373 -290.145831) (xy 129.441977 -290.123744) (xy 129.417572 -290.109148)
			(xy 128.855216 -290.109148) (xy 128.830811 -290.123744) (xy 128.778415 -290.145831) (xy 128.723175 -290.159312)
			(xy 128.666494 -290.163845) (xy 128.609813 -290.159312) (xy 128.554573 -290.145831) (xy 128.502177 -290.123744)
			(xy 128.477772 -290.109148) (xy 127.915416 -290.109148) (xy 127.891011 -290.123744) (xy 127.838615 -290.145831)
			(xy 127.783375 -290.159312) (xy 127.726694 -290.163845) (xy 127.670013 -290.159312) (xy 127.614773 -290.145831)
			(xy 127.562377 -290.123744) (xy 127.537972 -290.109148) (xy 126.975616 -290.109148) (xy 126.951211 -290.123744)
			(xy 126.898815 -290.145831) (xy 126.843575 -290.159312) (xy 126.786894 -290.163845) (xy 126.730213 -290.159312)
			(xy 126.674973 -290.145831) (xy 126.622577 -290.123744) (xy 126.598172 -290.109148) (xy 126.035816 -290.109148)
			(xy 126.011411 -290.123744) (xy 125.959015 -290.145831) (xy 125.903775 -290.159312) (xy 125.847094 -290.163845)
			(xy 125.790413 -290.159312) (xy 125.735173 -290.145831) (xy 125.682777 -290.123744) (xy 125.658372 -290.109148)
			(xy 125.096016 -290.109148) (xy 125.071611 -290.123744) (xy 125.019215 -290.145831) (xy 124.963975 -290.159312)
			(xy 124.907294 -290.163845) (xy 124.850613 -290.159312) (xy 124.795373 -290.145831) (xy 124.742977 -290.123744)
			(xy 124.718572 -290.109148) (xy 124.156216 -290.109148) (xy 124.131811 -290.123744) (xy 124.079415 -290.145831)
			(xy 124.024175 -290.159312) (xy 123.967494 -290.163845) (xy 123.910813 -290.159312) (xy 123.855573 -290.145831)
			(xy 123.803177 -290.123744) (xy 123.778772 -290.109148) (xy 123.216416 -290.109148) (xy 123.195102 -290.121977)
			(xy 123.149654 -290.142208) (xy 123.101832 -290.155913) (xy 123.052568 -290.162826) (xy 123.027694 -290.16325)
			(xy 122.996704 -290.162601) (xy 122.935651 -290.151918) (xy 122.877365 -290.13084) (xy 122.850148 -290.116006)
			(xy 122.838464 -290.109148) (xy 122.752866 -290.109148) (xy 122.573796 -289.930078) (xy 122.56363 -289.920564)
			(xy 122.539335 -289.906982) (xy 122.512276 -289.900461) (xy 122.484462 -289.901488) (xy 122.457957 -289.909984)
			(xy 122.434729 -289.92532) (xy 122.416504 -289.946357) (xy 122.41022 -289.95878) (xy 122.399088 -289.981377)
			(xy 122.371409 -290.023463) (xy 122.338081 -290.061233) (xy 122.299768 -290.093936) (xy 122.257232 -290.120918)
			(xy 122.21132 -290.141643) (xy 122.162949 -290.155698) (xy 122.11308 -290.162803) (xy 122.087894 -290.16325)
			(xy 122.05991 -290.162701) (xy 122.004631 -290.153945) (xy 121.951402 -290.136651) (xy 121.901534 -290.111243)
			(xy 121.856253 -290.078347) (xy 121.816676 -290.038774) (xy 121.783776 -289.993497) (xy 121.758363 -289.943631)
			(xy 121.741063 -289.890404) (xy 121.732302 -289.835126) (xy 121.731786 -289.807142) (xy 121.732219 -289.781954)
			(xy 121.73931 -289.732079) (xy 121.753358 -289.683701) (xy 121.774081 -289.637785) (xy 121.801066 -289.595247)
			(xy 121.833776 -289.556934) (xy 121.871557 -289.523612) (xy 121.913656 -289.495946) (xy 121.936256 -289.484816)
			(xy 121.948674 -289.478514) (xy 121.969741 -289.460317) (xy 121.985099 -289.437099) (xy 121.993602 -289.410591)
			(xy 121.994617 -289.382772) (xy 121.988068 -289.355715) (xy 121.974443 -289.33144) (xy 121.964958 -289.32124)
			(xy 121.84126 -289.197542) (xy 121.80697 -289.219132) (xy 121.785657 -289.231965) (xy 121.740211 -289.252204)
			(xy 121.692388 -289.265917) (xy 121.643123 -289.272837) (xy 121.618248 -289.273234) (xy 121.590259 -289.272718)
			(xy 121.53497 -289.263968) (xy 121.481731 -289.246677) (xy 121.431852 -289.221269) (xy 121.386562 -289.188372)
			(xy 121.346976 -289.148794) (xy 121.314069 -289.103511) (xy 121.288652 -289.053638) (xy 121.271349 -289.000402)
			(xy 121.262588 -288.945114) (xy 121.26214 -288.917126) (xy 121.262514 -288.893881) (xy 121.268556 -288.847785)
			(xy 121.280542 -288.802866) (xy 121.289064 -288.781236) (xy 121.298716 -288.758122) (xy 121.157492 -288.513774)
			(xy 121.099834 -288.456116) (xy 121.08434 -288.453322) (xy 121.05794 -288.447998) (xy 121.007025 -288.430455)
			(xy 120.959332 -288.405442) (xy 120.915951 -288.373532) (xy 120.877871 -288.335453) (xy 120.84596 -288.292072)
			(xy 120.820947 -288.24438) (xy 120.803403 -288.193464) (xy 120.798082 -288.167064) (xy 120.795288 -288.15157)
			(xy 120.734074 -288.090356) (xy 120.723725 -288.080648) (xy 120.698941 -288.066852) (xy 120.671321 -288.060399)
			(xy 120.64299 -288.061784) (xy 120.616131 -288.070902) (xy 120.592812 -288.08705) (xy 120.574827 -288.108984)
			(xy 120.563563 -288.135016) (xy 120.561354 -288.14903) (xy 120.557591 -288.174427) (xy 120.543714 -288.223858)
			(xy 120.522882 -288.270783) (xy 120.495528 -288.314231) (xy 120.462219 -288.353301) (xy 120.423645 -288.387182)
			(xy 120.380605 -288.415174) (xy 120.333992 -288.436695) (xy 120.284772 -288.4513) (xy 120.233965 -288.458686)
			(xy 120.208294 -288.459164) (xy 120.18031 -288.458643) (xy 120.125032 -288.449886) (xy 120.071804 -288.432589)
			(xy 120.021938 -288.407178) (xy 119.976661 -288.374278) (xy 119.937089 -288.334701) (xy 119.904196 -288.289419)
			(xy 119.878792 -288.239549) (xy 119.861502 -288.186319) (xy 119.852753 -288.13104) (xy 119.852186 -288.103056)
			(xy 119.852632 -288.07738) (xy 119.860001 -288.026561) (xy 119.874596 -287.977328) (xy 119.896113 -287.930702)
			(xy 119.924105 -287.887651) (xy 119.957992 -287.849069) (xy 119.99707 -287.815756) (xy 120.04053 -287.788402)
			(xy 120.087468 -287.767577) (xy 120.136911 -287.753711) (xy 120.16232 -287.749996) (xy 120.176342 -287.747737)
			(xy 120.202427 -287.73653) (xy 120.224414 -287.718569) (xy 120.2406 -287.695246) (xy 120.249734 -287.668365)
			(xy 120.251107 -287.640008) (xy 120.244613 -287.61237) (xy 120.230755 -287.587592) (xy 120.220994 -287.577276)
			(xy 120.15851 -287.514792) (xy 120.148307 -287.505212) (xy 120.123897 -287.491543) (xy 120.096692 -287.485015)
			(xy 120.068737 -287.486118) (xy 120.042131 -287.494769) (xy 120.018873 -287.510318) (xy 120.009412 -287.520634)
			(xy 119.992402 -287.539826) (xy 119.953821 -287.57361) (xy 119.910795 -287.601515) (xy 119.864215 -287.622967)
			(xy 119.815041 -287.637521) (xy 119.764289 -287.644877) (xy 119.738648 -287.645348) (xy 119.710659 -287.644832)
			(xy 119.655369 -287.636082) (xy 119.602129 -287.618791) (xy 119.552249 -287.593384) (xy 119.506958 -287.560487)
			(xy 119.467371 -287.520909) (xy 119.434462 -287.475626) (xy 119.409043 -287.425753) (xy 119.391739 -287.372517)
			(xy 119.382975 -287.317229) (xy 119.38254 -287.28924) (xy 119.382993 -287.263566) (xy 119.390373 -287.212751)
			(xy 119.404972 -287.163522) (xy 119.426488 -287.116899) (xy 119.454474 -287.073848) (xy 119.488351 -287.03526)
			(xy 119.527417 -287.001936) (xy 119.570862 -286.974566) (xy 119.617786 -286.953716) (xy 119.642382 -286.94634)
			(xy 119.679466 -286.935926) (xy 119.679466 -286.81299) (xy 119.678974 -286.798282) (xy 119.670587 -286.770086)
			(xy 119.654513 -286.74545) (xy 119.632083 -286.726417) (xy 119.60516 -286.714565) (xy 119.575976 -286.710879)
			(xy 119.546951 -286.715662) (xy 119.520493 -286.72852) (xy 119.509286 -286.73806) (xy 119.489478 -286.755549)
			(xy 119.445664 -286.785084) (xy 119.397965 -286.807817) (xy 119.34743 -286.823248) (xy 119.295168 -286.831038)
			(xy 119.268748 -286.831532) (xy 119.242093 -286.831062) (xy 119.189377 -286.823123) (xy 119.138433 -286.807415)
			(xy 119.0904 -286.784289) (xy 119.04635 -286.754262) (xy 119.007268 -286.718004) (xy 118.974027 -286.676327)
			(xy 118.94737 -286.63016) (xy 118.927892 -286.580535) (xy 118.916028 -286.528561) (xy 118.912044 -286.4754)
			(xy 118.916028 -286.422239) (xy 118.927892 -286.370265) (xy 118.94737 -286.32064) (xy 118.974027 -286.274473)
			(xy 119.007268 -286.232796) (xy 119.04635 -286.196538) (xy 119.0904 -286.166511) (xy 119.138433 -286.143385)
			(xy 119.189377 -286.127677) (xy 119.242093 -286.119738) (xy 119.268748 -286.119316) (xy 119.295167 -286.119799)
			(xy 119.347425 -286.127608) (xy 119.397958 -286.143047) (xy 119.445657 -286.165777) (xy 119.489477 -286.195301)
			(xy 119.509286 -286.212788) (xy 119.520473 -286.222359) (xy 119.546944 -286.235216) (xy 119.575982 -286.239998)
			(xy 119.605178 -286.236309) (xy 119.632113 -286.224455) (xy 119.654555 -286.205418) (xy 119.670642 -286.180776)
			(xy 119.679043 -286.152572) (xy 119.679466 -286.137858) (xy 119.679466 -286.014668) (xy 119.642382 -286.004254)
			(xy 119.617767 -285.996895) (xy 119.570799 -285.97608) (xy 119.527309 -285.948732) (xy 119.488199 -285.915418)
			(xy 119.454282 -285.876831) (xy 119.426262 -285.833771) (xy 119.404719 -285.787132) (xy 119.390101 -285.737881)
			(xy 119.382712 -285.687041) (xy 119.382286 -285.661354) (xy 119.382664 -285.63811) (xy 119.388715 -285.592016)
			(xy 119.400707 -285.547101) (xy 119.40921 -285.525464) (xy 119.418862 -285.50235) (xy 119.246396 -285.2039)
			(xy 119.221758 -285.200598) (xy 119.196414 -285.196776) (xy 119.147102 -285.182802) (xy 119.100303 -285.161901)
			(xy 119.056986 -285.134504) (xy 119.018045 -285.101179) (xy 118.984285 -285.062614) (xy 118.956405 -285.019606)
			(xy 118.934981 -284.973045) (xy 118.920455 -284.923893) (xy 118.913128 -284.873165) (xy 118.91264 -284.847538)
			(xy 118.913158 -284.819552) (xy 118.921909 -284.764269) (xy 118.939202 -284.711035) (xy 118.964611 -284.661163)
			(xy 118.99751 -284.615881) (xy 119.037089 -284.576304) (xy 119.082372 -284.543406) (xy 119.132245 -284.517998)
			(xy 119.185478 -284.500707) (xy 119.240762 -284.491957) (xy 119.268748 -284.49143) (xy 119.296374 -284.491947)
			(xy 119.350965 -284.500474) (xy 119.403584 -284.517331) (xy 119.452967 -284.542114) (xy 119.497929 -284.574227)
			(xy 119.537391 -284.6129) (xy 119.570405 -284.657205) (xy 119.583708 -284.681422) (xy 119.597932 -284.7086)
			(xy 119.679466 -284.7086) (xy 119.679466 -284.495748) (xy 119.301006 -284.117288) (xy 119.290336 -284.107294)
			(xy 119.264664 -284.093329) (xy 119.236088 -284.087206) (xy 119.206949 -284.089427) (xy 119.179631 -284.099809)
			(xy 119.156372 -284.117504) (xy 119.139077 -284.141061) (xy 119.13362 -284.154626) (xy 119.123876 -284.180102)
			(xy 119.09776 -284.227983) (xy 119.064646 -284.271321) (xy 119.025311 -284.309102) (xy 118.980673 -284.340442)
			(xy 118.931778 -284.364608) (xy 118.87977 -284.381034) (xy 118.825865 -284.389336) (xy 118.798594 -284.38983)
			(xy 118.770611 -284.389281) (xy 118.715333 -284.380525) (xy 118.662105 -284.36323) (xy 118.612238 -284.337822)
			(xy 118.56696 -284.304926) (xy 118.527384 -284.265353) (xy 118.494486 -284.220075) (xy 118.469076 -284.17021)
			(xy 118.451779 -284.116983) (xy 118.443021 -284.061705) (xy 118.442486 -284.033722) (xy 118.443011 -284.006456)
			(xy 118.451332 -283.952561) (xy 118.467768 -283.900564) (xy 118.491936 -283.851679) (xy 118.52327 -283.807047)
			(xy 118.561039 -283.767711) (xy 118.604361 -283.734589) (xy 118.652224 -283.708455) (xy 118.67769 -283.698696)
			(xy 118.69127 -283.693276) (xy 118.714817 -283.675962) (xy 118.732502 -283.652692) (xy 118.742881 -283.62537)
			(xy 118.745104 -283.596227) (xy 118.738991 -283.567646) (xy 118.725041 -283.541963) (xy 118.715028 -283.53131)
			(xy 118.618 -283.434282) (xy 118.582186 -283.47035) (xy 118.581932 -283.47035) (xy 118.561753 -283.49)
			(xy 118.516341 -283.523314) (xy 118.466248 -283.549059) (xy 118.412725 -283.56659) (xy 118.357109 -283.57547)
			(xy 118.328948 -283.576014) (xy 118.30096 -283.575498) (xy 118.245672 -283.566748) (xy 118.192434 -283.549456)
			(xy 118.142557 -283.524049) (xy 118.097268 -283.491151) (xy 118.057684 -283.451573) (xy 118.02478 -283.40629)
			(xy 117.999364 -283.356416) (xy 117.982065 -283.30318) (xy 117.973307 -283.247894) (xy 117.97284 -283.219906)
			(xy 117.973395 -283.191748) (xy 117.982297 -283.136138) (xy 117.999832 -283.082619) (xy 118.025564 -283.032524)
			(xy 118.058854 -282.987098) (xy 118.078504 -282.966922) (xy 118.078504 -282.966668) (xy 118.114572 -282.930854)
			(xy 117.937788 -282.75407) (xy 117.912388 -282.75788) (xy 117.899134 -282.759773) (xy 117.872436 -282.761809)
			(xy 117.859048 -282.761944) (xy 117.831059 -282.761428) (xy 117.77577 -282.752678) (xy 117.722529 -282.735387)
			(xy 117.67265 -282.70998) (xy 117.627359 -282.677082) (xy 117.587772 -282.637505) (xy 117.554864 -282.592222)
			(xy 117.529445 -282.542348) (xy 117.512142 -282.489112) (xy 117.503379 -282.433825) (xy 117.50294 -282.405836)
			(xy 117.503072 -282.392448) (xy 117.505104 -282.365749) (xy 117.507004 -282.352496) (xy 117.510814 -282.327096)
			(xy 116.606066 -281.422348) (xy 116.606066 -280.94813) (xy 116.600732 -280.937462) (xy 116.588876 -280.912606)
			(xy 116.572122 -280.860149) (xy 116.563644 -280.805737) (xy 116.563643 -280.75067) (xy 116.572121 -280.696258)
			(xy 116.588874 -280.643801) (xy 116.600732 -280.618946) (xy 116.606066 -280.608278) (xy 116.606066 -280.41854)
			(xy 116.605581 -280.404194) (xy 116.597608 -280.376632) (xy 116.58228 -280.352378) (xy 116.560809 -280.333346)
			(xy 116.53489 -280.32104) (xy 116.506571 -280.316433) (xy 116.492274 -280.317702) (xy 116.481583 -280.318903)
			(xy 116.460106 -280.320176) (xy 116.449348 -280.320242) (xy 116.422692 -280.319772) (xy 116.369975 -280.311833)
			(xy 116.319029 -280.296124) (xy 116.270995 -280.272998) (xy 116.226944 -280.24297) (xy 116.187861 -280.206711)
			(xy 116.154619 -280.165032) (xy 116.127961 -280.118864) (xy 116.108482 -280.069238) (xy 116.096618 -280.017263)
			(xy 116.092634 -279.9641) (xy 116.096618 -279.910937) (xy 116.108482 -279.858962) (xy 116.127961 -279.809336)
			(xy 116.154619 -279.763168) (xy 116.187861 -279.721489) (xy 116.226944 -279.68523) (xy 116.270995 -279.655202)
			(xy 116.319029 -279.632076) (xy 116.369975 -279.616367) (xy 116.422692 -279.608428) (xy 116.449348 -279.608026)
			(xy 116.460106 -279.60809) (xy 116.481584 -279.60936) (xy 116.492274 -279.610566) (xy 116.506574 -279.611806)
			(xy 116.534892 -279.6072) (xy 116.560811 -279.594899) (xy 116.582286 -279.575875) (xy 116.597623 -279.551629)
			(xy 116.60561 -279.524073) (xy 116.606066 -279.509728) (xy 116.606066 -279.31999) (xy 116.600732 -279.309322)
			(xy 116.588879 -279.284465) (xy 116.572131 -279.232008) (xy 116.563659 -279.177597) (xy 116.56314 -279.150064)
			(xy 116.563648 -279.130252) (xy 116.564918 -279.107646) (xy 116.507768 -279.050496) (xy 116.497784 -279.041131)
			(xy 116.473998 -279.027608) (xy 116.447473 -279.020889) (xy 116.420117 -279.021459) (xy 116.393895 -279.029275)
			(xy 116.370691 -279.043777) (xy 116.352174 -279.063922) (xy 116.339674 -279.088262) (xy 116.334089 -279.115048)
			(xy 116.33454 -279.128728) (xy 116.335302 -279.150318) (xy 116.334795 -279.177397) (xy 116.326591 -279.230931)
			(xy 116.310376 -279.282605) (xy 116.286523 -279.331228) (xy 116.255582 -279.375678) (xy 116.218266 -279.414931)
			(xy 116.175438 -279.44808) (xy 116.128083 -279.474361) (xy 116.077295 -279.493169) (xy 116.024245 -279.50407)
			(xy 115.970156 -279.506811) (xy 115.916275 -279.501331) (xy 115.863846 -279.487754) (xy 115.814077 -279.466396)
			(xy 115.768116 -279.437747) (xy 115.727023 -279.402468) (xy 115.691746 -279.361375) (xy 115.663099 -279.315413)
			(xy 115.641742 -279.265643) (xy 115.628167 -279.213213) (xy 115.622688 -279.159332) (xy 115.625432 -279.105243)
			(xy 115.636334 -279.052193) (xy 115.655144 -279.001406) (xy 115.681427 -278.954052) (xy 115.714577 -278.911225)
			(xy 115.753831 -278.873911) (xy 115.798282 -278.842971) (xy 115.846906 -278.81912) (xy 115.898581 -278.802906)
			(xy 115.952115 -278.794704) (xy 115.979194 -278.79421) (xy 116.000784 -278.794972) (xy 116.014461 -278.795381)
			(xy 116.041233 -278.789775) (xy 116.065557 -278.777265) (xy 116.08569 -278.75875) (xy 116.100187 -278.735555)
			(xy 116.10801 -278.709346) (xy 116.108597 -278.681999) (xy 116.101906 -278.655478) (xy 116.088417 -278.631683)
			(xy 116.079016 -278.621744) (xy 115.967256 -278.509984) (xy 115.956136 -278.499637) (xy 115.929319 -278.485405)
			(xy 115.899503 -278.479688) (xy 115.869325 -278.482992) (xy 115.841452 -278.495023) (xy 115.818349 -278.514719)
			(xy 115.809776 -278.527256) (xy 115.79569 -278.548592) (xy 115.762375 -278.587373) (xy 115.72386 -278.620994)
			(xy 115.680935 -278.648765) (xy 115.634481 -278.670115) (xy 115.585453 -278.684606) (xy 115.534856 -278.691941)
			(xy 115.509294 -278.692356) (xy 115.48131 -278.691807) (xy 115.426031 -278.683051) (xy 115.372801 -278.665757)
			(xy 115.322932 -278.640349) (xy 115.277652 -278.607454) (xy 115.238074 -278.56788) (xy 115.205173 -278.522603)
			(xy 115.179759 -278.472738) (xy 115.162459 -278.41951) (xy 115.153697 -278.364232) (xy 115.153186 -278.336248)
			(xy 115.153625 -278.310684) (xy 115.160934 -278.260082) (xy 115.175408 -278.211046) (xy 115.19675 -278.164585)
			(xy 115.224521 -278.121657) (xy 115.258148 -278.083144) (xy 115.296941 -278.04984) (xy 115.318286 -278.035766)
			(xy 115.330758 -278.02713) (xy 115.350388 -278.004024) (xy 115.36238 -277.976177) (xy 115.36568 -277.946038)
			(xy 115.359998 -277.916255) (xy 115.345833 -277.889448) (xy 115.335558 -277.878286) (xy 115.261136 -277.803864)
			(xy 115.2271 -277.8252) (xy 115.20586 -277.837851) (xy 115.160632 -277.857809) (xy 115.113078 -277.871321)
			(xy 115.064112 -277.878128) (xy 115.039394 -277.87854) (xy 115.01141 -277.877991) (xy 114.956132 -277.869235)
			(xy 114.902904 -277.85194) (xy 114.853036 -277.826532) (xy 114.807757 -277.793637) (xy 114.76818 -277.754063)
			(xy 114.735281 -277.708786) (xy 114.70987 -277.65892) (xy 114.692571 -277.605693) (xy 114.683811 -277.550416)
			(xy 114.683286 -277.522432) (xy 114.683693 -277.497714) (xy 114.690501 -277.448749) (xy 114.704018 -277.401196)
			(xy 114.723985 -277.355972) (xy 114.736626 -277.334726) (xy 114.757962 -277.30069) (xy 114.518694 -277.061422)
			(xy 114.5032 -277.058374) (xy 114.47716 -277.05292) (xy 114.426956 -277.035317) (xy 114.37993 -277.01044)
			(xy 114.33713 -276.978842) (xy 114.299507 -276.941227) (xy 114.2679 -276.898433) (xy 114.243013 -276.851413)
			(xy 114.2254 -276.801212) (xy 114.21999 -276.775164) (xy 114.216942 -276.75967) (xy 113.54308 -276.085808)
			(xy 113.54308 -275.427948) (xy 113.509552 -275.41601) (xy 113.483997 -275.406325) (xy 113.435972 -275.38025)
			(xy 113.392492 -275.347146) (xy 113.354579 -275.307789) (xy 113.323122 -275.263103) (xy 113.29886 -275.214137)
			(xy 113.282361 -275.16204) (xy 113.274012 -275.108034) (xy 113.274011 -275.053386) (xy 113.282356 -274.99938)
			(xy 113.298852 -274.947281) (xy 113.323112 -274.898314) (xy 113.354566 -274.853627) (xy 113.392477 -274.814268)
			(xy 113.435955 -274.781161) (xy 113.483979 -274.755083) (xy 113.509552 -274.74545) (xy 113.54308 -274.733512)
			(xy 113.54308 -273.800316) (xy 113.509552 -273.788378) (xy 113.484 -273.778693) (xy 113.435979 -273.752619)
			(xy 113.392504 -273.719516) (xy 113.354596 -273.680162) (xy 113.323143 -273.635479) (xy 113.298884 -273.586516)
			(xy 113.282388 -273.534423) (xy 113.274042 -273.480421) (xy 113.274042 -273.425778) (xy 113.282388 -273.371776)
			(xy 113.298884 -273.319683) (xy 113.323143 -273.27072) (xy 113.354597 -273.226037) (xy 113.392505 -273.186683)
			(xy 113.43598 -273.15358) (xy 113.484001 -273.127506) (xy 113.509552 -273.117818) (xy 113.54308 -273.10588)
			(xy 113.54308 -272.17243) (xy 113.509552 -272.160492) (xy 113.483999 -272.150807) (xy 113.435976 -272.124733)
			(xy 113.392499 -272.091629) (xy 113.354589 -272.052274) (xy 113.323134 -272.007589) (xy 113.298873 -271.958625)
			(xy 113.282376 -271.90653) (xy 113.274029 -271.852527) (xy 113.274028 -271.797882) (xy 113.282374 -271.743878)
			(xy 113.29887 -271.691782) (xy 113.32313 -271.642817) (xy 113.354583 -271.598133) (xy 113.392493 -271.558776)
			(xy 113.435969 -271.525672) (xy 113.483991 -271.499596) (xy 113.509552 -271.489932) (xy 113.54308 -271.477994)
			(xy 113.54308 -270.544798) (xy 113.509552 -270.53286) (xy 113.484001 -270.523175) (xy 113.435983 -270.497101)
			(xy 113.392511 -270.463999) (xy 113.354605 -270.424646) (xy 113.323154 -270.379965) (xy 113.298897 -270.331004)
			(xy 113.282403 -270.278913) (xy 113.274058 -270.224913) (xy 113.274059 -270.170273) (xy 113.282406 -270.116274)
			(xy 113.298902 -270.064183) (xy 113.323161 -270.015224) (xy 113.354614 -269.970543) (xy 113.392521 -269.931192)
			(xy 113.435995 -269.898091) (xy 113.484014 -269.872019) (xy 113.509552 -269.8623) (xy 113.54308 -269.850362)
			(xy 113.54308 -268.916912) (xy 113.509552 -268.904974) (xy 113.484 -268.895289) (xy 113.43598 -268.869215)
			(xy 113.392506 -268.836112) (xy 113.354598 -268.796758) (xy 113.323145 -268.752076) (xy 113.298887 -268.703113)
			(xy 113.282391 -268.65102) (xy 113.274045 -268.597019) (xy 113.274046 -268.542377) (xy 113.282392 -268.488376)
			(xy 113.298888 -268.436283) (xy 113.323147 -268.387321) (xy 113.3546 -268.342639) (xy 113.392509 -268.303285)
			(xy 113.435983 -268.270183) (xy 113.484004 -268.244109) (xy 113.509552 -268.234414) (xy 113.54308 -268.222476)
			(xy 113.54308 -267.289026) (xy 113.509552 -267.277088) (xy 113.483999 -267.267403) (xy 113.435977 -267.241329)
			(xy 113.392501 -267.208225) (xy 113.354591 -267.16887) (xy 113.323136 -267.124186) (xy 113.298876 -267.075223)
			(xy 113.282379 -267.023128) (xy 113.274032 -266.969125) (xy 113.274032 -266.914481) (xy 113.282378 -266.860477)
			(xy 113.298874 -266.808382) (xy 113.323134 -266.759418) (xy 113.354587 -266.714734) (xy 113.392497 -266.675378)
			(xy 113.435972 -266.642274) (xy 113.483994 -266.616199) (xy 113.509552 -266.606528) (xy 113.54308 -266.59459)
			(xy 113.54308 -266.123928) (xy 114.232944 -265.434064) (xy 114.225324 -265.40587) (xy 114.219733 -265.383361)
			(xy 114.213751 -265.337367) (xy 114.213386 -265.314176) (xy 114.213937 -265.286194) (xy 114.222695 -265.230919)
			(xy 114.239991 -265.177695) (xy 114.265401 -265.127832) (xy 114.298297 -265.082557) (xy 114.337871 -265.042985)
			(xy 114.383147 -265.010091) (xy 114.433012 -264.984684) (xy 114.486237 -264.967391) (xy 114.541512 -264.958635)
			(xy 114.569494 -264.958068) (xy 114.592685 -264.958427) (xy 114.638677 -264.96442) (xy 114.661188 -264.970006)
			(xy 114.689382 -264.977626) (xy 114.779552 -264.887456) (xy 114.788531 -264.877913) (xy 114.801732 -264.85529)
			(xy 114.808727 -264.830048) (xy 114.809051 -264.803857) (xy 114.802685 -264.778449) (xy 114.790049 -264.755506)
			(xy 114.78133 -264.745724) (xy 114.763037 -264.725747) (xy 114.732091 -264.681291) (xy 114.708232 -264.632663)
			(xy 114.692011 -264.580983) (xy 114.683801 -264.527443) (xy 114.683286 -264.50036) (xy 114.683838 -264.472379)
			(xy 114.692598 -264.417106) (xy 114.709896 -264.363884) (xy 114.735306 -264.314023) (xy 114.768203 -264.26875)
			(xy 114.807776 -264.229181) (xy 114.853052 -264.196288) (xy 114.902915 -264.170883) (xy 114.956139 -264.15359)
			(xy 115.011413 -264.144835) (xy 115.039394 -264.144252) (xy 115.064641 -264.144673) (xy 115.114632 -264.151775)
			(xy 115.163115 -264.165881) (xy 115.209113 -264.186706) (xy 115.230656 -264.199878) (xy 115.242356 -264.206827)
			(xy 115.268338 -264.214879) (xy 115.295524 -264.215785) (xy 115.321984 -264.20948) (xy 115.345841 -264.196412)
			(xy 115.3654 -264.177508) (xy 115.379274 -264.154111) (xy 115.386477 -264.12788) (xy 115.386866 -264.11428)
			(xy 115.386866 -264.022332) (xy 115.357656 -264.008616) (xy 115.33358 -263.996727) (xy 115.289 -263.966801)
			(xy 115.249418 -263.93052) (xy 115.215731 -263.888709) (xy 115.188703 -263.842314) (xy 115.168946 -263.792387)
			(xy 115.156909 -263.74006) (xy 115.152865 -263.686519) (xy 115.156904 -263.632977) (xy 115.168935 -263.580649)
			(xy 115.188686 -263.53072) (xy 115.215709 -263.484322) (xy 115.249392 -263.442507) (xy 115.28897 -263.406223)
			(xy 115.333547 -263.376291) (xy 115.357656 -263.364472) (xy 115.386866 -263.350756) (xy 115.386866 -260.975348)
			(xy 116.275866 -260.086348) (xy 118.829328 -260.086348) (xy 118.87708 -260.038596) (xy 118.880636 -260.024626)
			(xy 118.882467 -260.017854) (xy 118.88929 -260.005603) (xy 118.894098 -260.000496) (xy 120.009158 -258.885436)
			(xy 120.009158 -258.093464) (xy 120.008605 -258.078361) (xy 119.999767 -258.049476) (xy 119.982875 -258.024434)
			(xy 119.959401 -258.005423) (xy 119.931397 -257.9941) (xy 119.901306 -257.991456) (xy 119.871756 -257.99772)
			(xy 119.858282 -258.004564) (xy 119.831717 -258.018585) (xy 119.77505 -258.038494) (xy 119.715847 -258.048618)
			(xy 119.685816 -258.049268) (xy 119.661182 -258.048852) (xy 119.612383 -258.042064) (xy 119.564986 -258.028614)
			(xy 119.519895 -258.00876) (xy 119.477971 -257.982881) (xy 119.45874 -257.96748) (xy 119.447525 -257.958867)
			(xy 119.4216 -257.947599) (xy 119.393581 -257.943861) (xy 119.365609 -257.947938) (xy 119.339823 -257.959519)
			(xy 119.328692 -257.968242) (xy 119.309341 -257.983962) (xy 119.267079 -258.010408) (xy 119.221545 -258.030709)
			(xy 119.173626 -258.044469) (xy 119.124257 -258.051418) (xy 119.09933 -258.051808) (xy 119.070156 -258.051227)
			(xy 119.012586 -258.041725) (xy 118.957334 -258.02297) (xy 118.905876 -257.995464) (xy 118.859588 -257.959941)
			(xy 118.839234 -257.939032) (xy 118.829458 -257.929271) (xy 118.805871 -257.914912) (xy 118.779301 -257.907391)
			(xy 118.751687 -257.907256) (xy 118.725045 -257.914518) (xy 118.701319 -257.928646) (xy 118.691406 -257.93827)
			(xy 118.671089 -257.958857) (xy 118.625017 -257.993821) (xy 118.573901 -258.020881) (xy 118.519084 -258.039326)
			(xy 118.462007 -258.04867) (xy 118.433088 -258.049268) (xy 118.407149 -258.048826) (xy 118.355814 -258.041343)
			(xy 118.306111 -258.02648) (xy 118.259096 -258.004552) (xy 118.215766 -257.976024) (xy 118.196106 -257.959098)
			(xy 118.184712 -257.94961) (xy 118.157864 -257.937061) (xy 118.128542 -257.932757) (xy 118.09922 -257.937061)
			(xy 118.072372 -257.94961) (xy 118.060978 -257.959098) (xy 118.041291 -257.975987) (xy 117.997952 -258.004481)
			(xy 117.950941 -258.026396) (xy 117.901251 -258.041267) (xy 117.84993 -258.048782) (xy 117.823996 -258.049268)
			(xy 117.79735 -258.04877) (xy 117.744653 -258.040826) (xy 117.693729 -258.025118) (xy 117.645714 -258.001995)
			(xy 117.601682 -257.971974) (xy 117.562617 -257.935726) (xy 117.52939 -257.89406) (xy 117.502744 -257.847908)
			(xy 117.483274 -257.798299) (xy 117.471416 -257.746343) (xy 117.467433 -257.6932) (xy 117.471416 -257.640057)
			(xy 117.483274 -257.588101) (xy 117.502744 -257.538492) (xy 117.52939 -257.49234) (xy 117.562617 -257.450674)
			(xy 117.601682 -257.414426) (xy 117.645714 -257.384405) (xy 117.693729 -257.361282) (xy 117.744653 -257.345574)
			(xy 117.79735 -257.33763) (xy 117.823996 -257.337052) (xy 117.849933 -257.3375) (xy 117.901262 -257.344994)
			(xy 117.950957 -257.359867) (xy 117.997963 -257.381804) (xy 118.041282 -257.410339) (xy 118.060978 -257.427222)
			(xy 118.072372 -257.43671) (xy 118.09922 -257.449259) (xy 118.128542 -257.453563) (xy 118.157864 -257.449259)
			(xy 118.184712 -257.43671) (xy 118.196106 -257.427222) (xy 118.215792 -257.410332) (xy 118.259131 -257.381833)
			(xy 118.306141 -257.359916) (xy 118.355832 -257.345041) (xy 118.407153 -257.337523) (xy 118.433088 -257.337052)
			(xy 118.462261 -257.337635) (xy 118.519828 -257.347141) (xy 118.575076 -257.3659) (xy 118.626529 -257.393411)
			(xy 118.672811 -257.428939) (xy 118.693184 -257.449828) (xy 118.702963 -257.459595) (xy 118.726557 -257.473967)
			(xy 118.753136 -257.481503) (xy 118.780762 -257.481653) (xy 118.807422 -257.474406) (xy 118.831171 -257.460291)
			(xy 118.841012 -257.45059) (xy 118.861326 -257.429995) (xy 118.907393 -257.395014) (xy 118.958508 -257.367938)
			(xy 119.013327 -257.349478) (xy 119.070408 -257.340119) (xy 119.09933 -257.339592) (xy 119.123963 -257.340011)
			(xy 119.172758 -257.346806) (xy 119.22015 -257.360263) (xy 119.265235 -257.380124) (xy 119.307152 -257.40601)
			(xy 119.326406 -257.42138) (xy 119.33762 -257.430004) (xy 119.363549 -257.44129) (xy 119.391577 -257.445043)
			(xy 119.419562 -257.440974) (xy 119.445361 -257.429395) (xy 119.456454 -257.420618) (xy 119.475806 -257.404902)
			(xy 119.51807 -257.378464) (xy 119.563605 -257.358172) (xy 119.611523 -257.34442) (xy 119.66089 -257.337477)
			(xy 119.685816 -257.337052) (xy 119.715848 -257.337694) (xy 119.775055 -257.347811) (xy 119.831723 -257.367722)
			(xy 119.858282 -257.381756) (xy 119.871763 -257.38861) (xy 119.901326 -257.394906) (xy 119.931438 -257.39228)
			(xy 119.959465 -257.380961) (xy 119.982955 -257.361939) (xy 119.999853 -257.336877) (xy 120.008682 -257.307969)
			(xy 120.009158 -257.292856) (xy 120.009158 -250.100592) (xy 118.443248 -248.534682) (xy 118.443248 -247.018302)
			(xy 118.397528 -247.01373) (xy 118.370499 -247.010499) (xy 118.317797 -246.996878) (xy 118.267786 -246.975385)
			(xy 118.221636 -246.946521) (xy 118.200678 -246.929148) (xy 118.189094 -246.919861) (xy 118.161984 -246.907785)
			(xy 118.13255 -246.903988) (xy 118.103263 -246.908788) (xy 118.076581 -246.921784) (xy 118.065296 -246.931434)
			(xy 118.045459 -246.949052) (xy 118.001545 -246.978821) (xy 117.953702 -247.001749) (xy 117.902987 -247.017326)
			(xy 117.850523 -247.025209) (xy 117.823996 -247.025668) (xy 117.79735 -247.02517) (xy 117.744653 -247.017226)
			(xy 117.693729 -247.001518) (xy 117.645714 -246.978395) (xy 117.601682 -246.948374) (xy 117.562617 -246.912126)
			(xy 117.52939 -246.87046) (xy 117.502744 -246.824308) (xy 117.483274 -246.774699) (xy 117.471416 -246.722743)
			(xy 117.467433 -246.6696) (xy 117.471416 -246.616457) (xy 117.483274 -246.564501) (xy 117.502744 -246.514892)
			(xy 117.52939 -246.46874) (xy 117.562617 -246.427074) (xy 117.601682 -246.390826) (xy 117.645714 -246.360805)
			(xy 117.693729 -246.337682) (xy 117.744653 -246.321974) (xy 117.79735 -246.31403) (xy 117.823996 -246.313452)
			(xy 117.849332 -246.313899) (xy 117.899491 -246.321084) (xy 117.948125 -246.335311) (xy 117.994249 -246.35629)
			(xy 118.036933 -246.383599) (xy 118.056406 -246.399812) (xy 118.067992 -246.409097) (xy 118.095104 -246.421171)
			(xy 118.124538 -246.424969) (xy 118.153827 -246.420174) (xy 118.180514 -246.407188) (xy 118.191788 -246.397526)
			(xy 118.213288 -246.378498) (xy 118.261199 -246.346868) (xy 118.313562 -246.32333) (xy 118.369023 -246.308495)
			(xy 118.397528 -246.30507) (xy 118.443248 -246.300498) (xy 118.443248 -244.596158) (xy 120.009158 -243.030248)
			(xy 120.009158 -241.391948) (xy 118.714266 -240.097056) (xy 118.714266 -239.7633) (xy 118.713796 -239.749429)
			(xy 118.706325 -239.722713) (xy 118.691934 -239.698997) (xy 118.671687 -239.680033) (xy 118.647081 -239.667223)
			(xy 118.619933 -239.661513) (xy 118.606062 -239.661954) (xy 118.582694 -239.662716) (xy 118.558025 -239.662296)
			(xy 118.509159 -239.655484) (xy 118.461701 -239.641992) (xy 118.41656 -239.622078) (xy 118.374601 -239.596123)
			(xy 118.355364 -239.580674) (xy 118.344234 -239.572047) (xy 118.318474 -239.5607) (xy 118.290594 -239.556819)
			(xy 118.262714 -239.5607) (xy 118.236954 -239.572047) (xy 118.225824 -239.580674) (xy 118.204408 -239.597797)
			(xy 118.157351 -239.625936) (xy 118.106534 -239.646525) (xy 118.053161 -239.659077) (xy 117.998494 -239.663294)
			(xy 117.943827 -239.659077) (xy 117.890454 -239.646525) (xy 117.839637 -239.625936) (xy 117.79258 -239.597797)
			(xy 117.771164 -239.580674) (xy 117.760034 -239.572047) (xy 117.734274 -239.5607) (xy 117.706394 -239.556819)
			(xy 117.678514 -239.5607) (xy 117.652754 -239.572047) (xy 117.641624 -239.580674) (xy 117.622377 -239.596112)
			(xy 117.580428 -239.622087) (xy 117.535291 -239.642015) (xy 117.487832 -239.655511) (xy 117.438964 -239.662317)
			(xy 117.414294 -239.662716) (xy 117.387644 -239.662218) (xy 117.334941 -239.654273) (xy 117.284009 -239.638562)
			(xy 117.235989 -239.615436) (xy 117.191951 -239.585411) (xy 117.15288 -239.549158) (xy 117.119649 -239.507487)
			(xy 117.093 -239.461328) (xy 117.073528 -239.411713) (xy 117.061668 -239.35975) (xy 117.057684 -239.3066)
			(xy 117.061668 -239.25345) (xy 117.073528 -239.201487) (xy 117.093 -239.151872) (xy 117.119649 -239.105713)
			(xy 117.15288 -239.064042) (xy 117.191951 -239.027789) (xy 117.235989 -238.997764) (xy 117.284009 -238.974638)
			(xy 117.334941 -238.958927) (xy 117.387644 -238.950982) (xy 117.414294 -238.9505) (xy 117.438963 -238.950919)
			(xy 117.48783 -238.95773) (xy 117.535288 -238.971221) (xy 117.58043 -238.991135) (xy 117.622389 -239.01709)
			(xy 117.641624 -239.032542) (xy 117.652754 -239.041169) (xy 117.678514 -239.052516) (xy 117.706394 -239.056397)
			(xy 117.734274 -239.052516) (xy 117.760034 -239.041169) (xy 117.771164 -239.032542) (xy 117.79258 -239.015419)
			(xy 117.839637 -238.98728) (xy 117.890454 -238.966691) (xy 117.943827 -238.954139) (xy 117.998494 -238.949922)
			(xy 118.053161 -238.954139) (xy 118.106534 -238.966691) (xy 118.157351 -238.98728) (xy 118.204408 -239.015419)
			(xy 118.225824 -239.032542) (xy 118.236954 -239.041169) (xy 118.262714 -239.052516) (xy 118.290594 -239.056397)
			(xy 118.318474 -239.052516) (xy 118.344234 -239.041169) (xy 118.355364 -239.032542) (xy 118.374612 -239.017106)
			(xy 118.416563 -238.991135) (xy 118.4617 -238.971211) (xy 118.509157 -238.957717) (xy 118.558024 -238.950911)
			(xy 118.582694 -238.9505) (xy 118.598464 -238.950668) (xy 118.62988 -238.953466) (xy 118.645432 -238.956088)
			(xy 118.660139 -238.958226) (xy 118.689654 -238.954878) (xy 118.716959 -238.943181) (xy 118.739746 -238.924126)
			(xy 118.75609 -238.899322) (xy 118.764609 -238.870865) (xy 118.765066 -238.856012) (xy 118.765066 -237.912148)
			(xy 118.206774 -237.353856) (xy 115.633754 -237.353856) (xy 115.618273 -237.375112) (xy 115.582081 -237.413259)
			(xy 115.540672 -237.445669) (xy 115.494949 -237.471637) (xy 115.445903 -237.490601) (xy 115.394603 -237.502146)
			(xy 115.342162 -237.506023) (xy 115.289721 -237.502146) (xy 115.238421 -237.490601) (xy 115.189375 -237.471637)
			(xy 115.143652 -237.445669) (xy 115.102243 -237.413259) (xy 115.066051 -237.375112) (xy 115.05057 -237.353856)
			(xy 113.975896 -237.353856) (xy 113.960877 -237.354394) (xy 113.932139 -237.363134) (xy 113.907187 -237.379859)
			(xy 113.888181 -237.403119) (xy 113.876764 -237.430903) (xy 113.874804 -237.445804) (xy 113.871832 -237.471926)
			(xy 113.859184 -237.522954) (xy 113.839169 -237.571567) (xy 113.812223 -237.616708) (xy 113.778932 -237.657397)
			(xy 113.740019 -237.692747) (xy 113.696331 -237.72199) (xy 113.648817 -237.74449) (xy 113.598511 -237.759759)
			(xy 113.546506 -237.767464) (xy 113.52022 -237.767876) (xy 113.493394 -237.767391) (xy 113.440348 -237.759345)
			(xy 113.38911 -237.743431) (xy 113.340839 -237.72001) (xy 113.296628 -237.689612) (xy 113.257479 -237.652925)
			(xy 113.224277 -237.61078) (xy 113.197773 -237.56413) (xy 113.178568 -237.514032) (xy 113.167097 -237.46162)
			(xy 113.164874 -237.434882) (xy 113.156652 -237.422534) (xy 113.142032 -237.396718) (xy 113.135664 -237.38332)
			(xy 113.121948 -237.353856) (xy 113.036096 -237.353856) (xy 113.021077 -237.354394) (xy 112.992339 -237.363134)
			(xy 112.967387 -237.379859) (xy 112.948381 -237.403119) (xy 112.936964 -237.430903) (xy 112.935004 -237.445804)
			(xy 112.932032 -237.471926) (xy 112.919384 -237.522954) (xy 112.899369 -237.571567) (xy 112.872423 -237.616708)
			(xy 112.839132 -237.657397) (xy 112.800219 -237.692747) (xy 112.756531 -237.72199) (xy 112.709017 -237.74449)
			(xy 112.658711 -237.759759) (xy 112.606706 -237.767464) (xy 112.58042 -237.767876) (xy 112.553594 -237.767391)
			(xy 112.500548 -237.759345) (xy 112.44931 -237.743431) (xy 112.401039 -237.72001) (xy 112.356828 -237.689612)
			(xy 112.317679 -237.652925) (xy 112.284477 -237.61078) (xy 112.257973 -237.56413) (xy 112.238768 -237.514032)
			(xy 112.227297 -237.46162) (xy 112.225074 -237.434882) (xy 112.216852 -237.422534) (xy 112.202232 -237.396718)
			(xy 112.195864 -237.38332) (xy 112.182148 -237.353856) (xy 112.096296 -237.353856) (xy 112.081277 -237.354394)
			(xy 112.052539 -237.363134) (xy 112.027587 -237.379859) (xy 112.008581 -237.403119) (xy 111.997164 -237.430903)
			(xy 111.995204 -237.445804) (xy 111.992232 -237.471926) (xy 111.979584 -237.522954) (xy 111.959569 -237.571567)
			(xy 111.932623 -237.616708) (xy 111.899332 -237.657397) (xy 111.860419 -237.692747) (xy 111.816731 -237.72199)
			(xy 111.769217 -237.74449) (xy 111.718911 -237.759759) (xy 111.666906 -237.767464) (xy 111.64062 -237.767876)
			(xy 111.613794 -237.767391) (xy 111.560748 -237.759345) (xy 111.50951 -237.743431) (xy 111.461239 -237.72001)
			(xy 111.417028 -237.689612) (xy 111.377879 -237.652925) (xy 111.344677 -237.61078) (xy 111.318173 -237.56413)
			(xy 111.298968 -237.514032) (xy 111.287497 -237.46162) (xy 111.285274 -237.434882) (xy 111.277052 -237.422534)
			(xy 111.262432 -237.396718) (xy 111.256064 -237.38332) (xy 111.242348 -237.353856) (xy 111.156496 -237.353856)
			(xy 111.141477 -237.354394) (xy 111.112739 -237.363134) (xy 111.087787 -237.379859) (xy 111.068781 -237.403119)
			(xy 111.057364 -237.430903) (xy 111.055404 -237.445804) (xy 111.052432 -237.471926) (xy 111.039784 -237.522954)
			(xy 111.019769 -237.571567) (xy 110.992823 -237.616708) (xy 110.959532 -237.657397) (xy 110.920619 -237.692747)
			(xy 110.876931 -237.72199) (xy 110.829417 -237.74449) (xy 110.779111 -237.759759) (xy 110.727106 -237.767464)
			(xy 110.70082 -237.767876) (xy 110.673994 -237.767391) (xy 110.620948 -237.759345) (xy 110.56971 -237.743431)
			(xy 110.521439 -237.72001) (xy 110.477228 -237.689612) (xy 110.438079 -237.652925) (xy 110.404877 -237.61078)
			(xy 110.378373 -237.56413) (xy 110.359168 -237.514032) (xy 110.347697 -237.46162) (xy 110.345474 -237.434882)
			(xy 110.337252 -237.422534) (xy 110.322632 -237.396718) (xy 110.316264 -237.38332) (xy 110.302548 -237.353856)
			(xy 110.216696 -237.353856) (xy 110.201677 -237.354394) (xy 110.172939 -237.363134) (xy 110.147987 -237.379859)
			(xy 110.128981 -237.403119) (xy 110.117564 -237.430903) (xy 110.115604 -237.445804) (xy 110.112632 -237.471926)
			(xy 110.099984 -237.522954) (xy 110.079969 -237.571567) (xy 110.053023 -237.616708) (xy 110.019732 -237.657397)
			(xy 109.980819 -237.692747) (xy 109.937131 -237.72199) (xy 109.889617 -237.74449) (xy 109.839311 -237.759759)
			(xy 109.787306 -237.767464) (xy 109.76102 -237.767876) (xy 109.734194 -237.767391) (xy 109.681148 -237.759345)
			(xy 109.62991 -237.743431) (xy 109.581639 -237.72001) (xy 109.537428 -237.689612) (xy 109.498279 -237.652925)
			(xy 109.465077 -237.61078) (xy 109.438573 -237.56413) (xy 109.419368 -237.514032) (xy 109.407897 -237.46162)
			(xy 109.405674 -237.434882) (xy 109.397452 -237.422534) (xy 109.382832 -237.396718) (xy 109.376464 -237.38332)
			(xy 109.362748 -237.353856) (xy 109.01426 -237.353856) (xy 109.00156 -237.357158) (xy 108.980224 -237.362238)
			(xy 108.91901 -237.469172) (xy 108.920788 -237.49635) (xy 108.926884 -237.506764) (xy 108.941935 -237.53405)
			(xy 108.963383 -237.592551) (xy 108.969556 -237.623096) (xy 108.971588 -237.63351) (xy 108.995718 -237.669324)
			(xy 109.08411 -237.722156) (xy 109.106716 -237.713774) (xy 109.136361 -237.703596) (xy 109.198062 -237.692603)
			(xy 109.229398 -237.69193) (xy 109.229652 -237.69193) (xy 109.256492 -237.692414) (xy 109.309565 -237.700465)
			(xy 109.360829 -237.716391) (xy 109.40912 -237.739832) (xy 109.453346 -237.770256) (xy 109.492504 -237.806975)
			(xy 109.525706 -237.849155) (xy 109.552201 -237.895841) (xy 109.571387 -237.945975) (xy 109.582831 -237.998422)
			(xy 109.584998 -238.025178) (xy 109.599643 -238.047464) (xy 109.622812 -238.095495) (xy 109.638555 -238.146446)
			(xy 109.646521 -238.199175) (xy 109.646974 -238.225838) (xy 109.646448 -238.252487) (xy 109.875056 -238.252487)
			(xy 109.875056 -238.199189) (xy 109.882999 -238.146485) (xy 109.898709 -238.095555) (xy 109.921835 -238.047534)
			(xy 109.951859 -238.003497) (xy 109.988111 -237.964426) (xy 110.029782 -237.931195) (xy 110.07594 -237.904546)
			(xy 110.125554 -237.885074) (xy 110.177516 -237.873214) (xy 110.230666 -237.869231) (xy 110.283816 -237.873214)
			(xy 110.335778 -237.885074) (xy 110.385392 -237.904546) (xy 110.43155 -237.931195) (xy 110.473221 -237.964426)
			(xy 110.509473 -238.003497) (xy 110.539497 -238.047534) (xy 110.562623 -238.095555) (xy 110.578333 -238.146485)
			(xy 110.586276 -238.199189) (xy 110.586774 -238.225838) (xy 110.586276 -238.252487) (xy 110.814856 -238.252487)
			(xy 110.814856 -238.199189) (xy 110.822799 -238.146485) (xy 110.838509 -238.095555) (xy 110.861635 -238.047534)
			(xy 110.891659 -238.003497) (xy 110.927911 -237.964426) (xy 110.969582 -237.931195) (xy 111.01574 -237.904546)
			(xy 111.065354 -237.885074) (xy 111.117316 -237.873214) (xy 111.170466 -237.869231) (xy 111.223616 -237.873214)
			(xy 111.275578 -237.885074) (xy 111.325192 -237.904546) (xy 111.37135 -237.931195) (xy 111.413021 -237.964426)
			(xy 111.449273 -238.003497) (xy 111.479297 -238.047534) (xy 111.502423 -238.095555) (xy 111.518133 -238.146485)
			(xy 111.526076 -238.199189) (xy 111.526574 -238.225838) (xy 111.526076 -238.252487) (xy 111.754656 -238.252487)
			(xy 111.754656 -238.199189) (xy 111.762599 -238.146485) (xy 111.778309 -238.095555) (xy 111.801435 -238.047534)
			(xy 111.831459 -238.003497) (xy 111.867711 -237.964426) (xy 111.909382 -237.931195) (xy 111.95554 -237.904546)
			(xy 112.005154 -237.885074) (xy 112.057116 -237.873214) (xy 112.110266 -237.869231) (xy 112.163416 -237.873214)
			(xy 112.215378 -237.885074) (xy 112.264992 -237.904546) (xy 112.31115 -237.931195) (xy 112.352821 -237.964426)
			(xy 112.389073 -238.003497) (xy 112.419097 -238.047534) (xy 112.442223 -238.095555) (xy 112.457933 -238.146485)
			(xy 112.465876 -238.199189) (xy 112.466374 -238.225838) (xy 112.465876 -238.252487) (xy 112.694456 -238.252487)
			(xy 112.694456 -238.199189) (xy 112.702399 -238.146485) (xy 112.718109 -238.095555) (xy 112.741235 -238.047534)
			(xy 112.771259 -238.003497) (xy 112.807511 -237.964426) (xy 112.849182 -237.931195) (xy 112.89534 -237.904546)
			(xy 112.944954 -237.885074) (xy 112.996916 -237.873214) (xy 113.050066 -237.869231) (xy 113.103216 -237.873214)
			(xy 113.155178 -237.885074) (xy 113.204792 -237.904546) (xy 113.25095 -237.931195) (xy 113.292621 -237.964426)
			(xy 113.328873 -238.003497) (xy 113.358897 -238.047534) (xy 113.382023 -238.095555) (xy 113.397733 -238.146485)
			(xy 113.405676 -238.199189) (xy 113.406174 -238.225838) (xy 113.405676 -238.252487) (xy 113.634256 -238.252487)
			(xy 113.634256 -238.199189) (xy 113.642199 -238.146485) (xy 113.657909 -238.095555) (xy 113.681035 -238.047534)
			(xy 113.711059 -238.003497) (xy 113.747311 -237.964426) (xy 113.788982 -237.931195) (xy 113.83514 -237.904546)
			(xy 113.884754 -237.885074) (xy 113.936716 -237.873214) (xy 113.989866 -237.869231) (xy 114.043016 -237.873214)
			(xy 114.094978 -237.885074) (xy 114.144592 -237.904546) (xy 114.19075 -237.931195) (xy 114.232421 -237.964426)
			(xy 114.268673 -238.003497) (xy 114.298697 -238.047534) (xy 114.321823 -238.095555) (xy 114.337533 -238.146485)
			(xy 114.345476 -238.199189) (xy 114.345974 -238.225838) (xy 114.345476 -238.252487) (xy 114.337533 -238.305191)
			(xy 114.321823 -238.356121) (xy 114.298697 -238.404142) (xy 114.268673 -238.448179) (xy 114.232421 -238.48725)
			(xy 114.19075 -238.520481) (xy 114.144592 -238.54713) (xy 114.094978 -238.566602) (xy 114.043016 -238.578462)
			(xy 113.989866 -238.582446) (xy 113.936716 -238.578462) (xy 113.884754 -238.566602) (xy 113.83514 -238.54713)
			(xy 113.788982 -238.520481) (xy 113.747311 -238.48725) (xy 113.711059 -238.448179) (xy 113.681035 -238.404142)
			(xy 113.657909 -238.356121) (xy 113.642199 -238.305191) (xy 113.634256 -238.252487) (xy 113.405676 -238.252487)
			(xy 113.397733 -238.305191) (xy 113.382023 -238.356121) (xy 113.358897 -238.404142) (xy 113.328873 -238.448179)
			(xy 113.292621 -238.48725) (xy 113.25095 -238.520481) (xy 113.204792 -238.54713) (xy 113.155178 -238.566602)
			(xy 113.103216 -238.578462) (xy 113.050066 -238.582446) (xy 112.996916 -238.578462) (xy 112.944954 -238.566602)
			(xy 112.89534 -238.54713) (xy 112.849182 -238.520481) (xy 112.807511 -238.48725) (xy 112.771259 -238.448179)
			(xy 112.741235 -238.404142) (xy 112.718109 -238.356121) (xy 112.702399 -238.305191) (xy 112.694456 -238.252487)
			(xy 112.465876 -238.252487) (xy 112.457933 -238.305191) (xy 112.442223 -238.356121) (xy 112.419097 -238.404142)
			(xy 112.389073 -238.448179) (xy 112.352821 -238.48725) (xy 112.31115 -238.520481) (xy 112.264992 -238.54713)
			(xy 112.215378 -238.566602) (xy 112.163416 -238.578462) (xy 112.110266 -238.582446) (xy 112.057116 -238.578462)
			(xy 112.005154 -238.566602) (xy 111.95554 -238.54713) (xy 111.909382 -238.520481) (xy 111.867711 -238.48725)
			(xy 111.831459 -238.448179) (xy 111.801435 -238.404142) (xy 111.778309 -238.356121) (xy 111.762599 -238.305191)
			(xy 111.754656 -238.252487) (xy 111.526076 -238.252487) (xy 111.518133 -238.305191) (xy 111.502423 -238.356121)
			(xy 111.479297 -238.404142) (xy 111.449273 -238.448179) (xy 111.413021 -238.48725) (xy 111.37135 -238.520481)
			(xy 111.325192 -238.54713) (xy 111.275578 -238.566602) (xy 111.223616 -238.578462) (xy 111.170466 -238.582446)
			(xy 111.117316 -238.578462) (xy 111.065354 -238.566602) (xy 111.01574 -238.54713) (xy 110.969582 -238.520481)
			(xy 110.927911 -238.48725) (xy 110.891659 -238.448179) (xy 110.861635 -238.404142) (xy 110.838509 -238.356121)
			(xy 110.822799 -238.305191) (xy 110.814856 -238.252487) (xy 110.586276 -238.252487) (xy 110.578333 -238.305191)
			(xy 110.562623 -238.356121) (xy 110.539497 -238.404142) (xy 110.509473 -238.448179) (xy 110.473221 -238.48725)
			(xy 110.43155 -238.520481) (xy 110.385392 -238.54713) (xy 110.335778 -238.566602) (xy 110.283816 -238.578462)
			(xy 110.230666 -238.582446) (xy 110.177516 -238.578462) (xy 110.125554 -238.566602) (xy 110.07594 -238.54713)
			(xy 110.029782 -238.520481) (xy 109.988111 -238.48725) (xy 109.951859 -238.448179) (xy 109.921835 -238.404142)
			(xy 109.898709 -238.356121) (xy 109.882999 -238.305191) (xy 109.875056 -238.252487) (xy 109.646448 -238.252487)
			(xy 109.646422 -238.253818) (xy 109.637662 -238.309089) (xy 109.620364 -238.362309) (xy 109.594953 -238.412167)
			(xy 109.562056 -238.457437) (xy 109.522482 -238.497003) (xy 109.477206 -238.529891) (xy 109.427342 -238.555291)
			(xy 109.374119 -238.572579) (xy 109.318846 -238.581328) (xy 109.290866 -238.581946) (xy 109.264026 -238.581463)
			(xy 109.210952 -238.573415) (xy 109.159687 -238.55749) (xy 109.111395 -238.534049) (xy 109.067168 -238.503625)
			(xy 109.028011 -238.466906) (xy 108.994809 -238.424725) (xy 108.968315 -238.378037) (xy 108.949131 -238.327902)
			(xy 108.93769 -238.275454) (xy 108.93552 -238.248698) (xy 108.928341 -238.23801) (xy 108.915374 -238.215762)
			(xy 108.909612 -238.204248) (xy 108.904781 -238.195358) (xy 108.889588 -238.182019) (xy 108.870429 -238.175563)
			(xy 108.850262 -238.176988) (xy 108.841032 -238.181134) (xy 108.81597 -238.193215) (xy 108.763026 -238.210307)
			(xy 108.708067 -238.218954) (xy 108.68025 -238.219488) (xy 108.653409 -238.219004) (xy 108.600335 -238.210954)
			(xy 108.54907 -238.195028) (xy 108.500777 -238.171588) (xy 108.45655 -238.141164) (xy 108.41739 -238.104446)
			(xy 108.384186 -238.062266) (xy 108.357689 -238.015579) (xy 108.3385 -237.965445) (xy 108.327054 -237.912998)
			(xy 108.324904 -237.88624) (xy 108.310264 -237.863952) (xy 108.287106 -237.81592) (xy 108.271374 -237.764969)
			(xy 108.263421 -237.712242) (xy 108.262928 -237.68558) (xy 108.262928 -237.685326) (xy 108.263317 -237.661897)
			(xy 108.269494 -237.615446) (xy 108.281706 -237.570206) (xy 108.299741 -237.526957) (xy 108.311188 -237.50651)
			(xy 108.325666 -237.48111) (xy 108.259626 -237.36554) (xy 108.234734 -237.353856) (xy 105.480866 -237.353856)
			(xy 104.947466 -237.887256) (xy 104.947466 -238.854234) (xy 104.947881 -238.867752) (xy 104.954973 -238.893841)
			(xy 104.968675 -238.917147) (xy 104.988023 -238.93603) (xy 105.011656 -238.949162) (xy 105.037909 -238.955617)
			(xy 105.064937 -238.954941) (xy 105.078022 -238.951516) (xy 105.102854 -238.944623) (xy 105.153855 -238.937233)
			(xy 105.179622 -238.936784) (xy 105.204291 -238.937205) (xy 105.253156 -238.944019) (xy 105.300612 -238.957513)
			(xy 105.345751 -238.977428) (xy 105.387709 -239.003385) (xy 105.406952 -239.018826) (xy 105.418082 -239.027453)
			(xy 105.443842 -239.0388) (xy 105.471722 -239.042681) (xy 105.499602 -239.0388) (xy 105.525362 -239.027453)
			(xy 105.536492 -239.018826) (xy 105.557908 -239.001703) (xy 105.604965 -238.973564) (xy 105.655782 -238.952975)
			(xy 105.709155 -238.940423) (xy 105.763822 -238.936206) (xy 105.818489 -238.940423) (xy 105.871862 -238.952975)
			(xy 105.922679 -238.973564) (xy 105.969736 -239.001703) (xy 105.991152 -239.018826) (xy 106.002282 -239.027453)
			(xy 106.028042 -239.0388) (xy 106.055922 -239.042681) (xy 106.083802 -239.0388) (xy 106.109562 -239.027453)
			(xy 106.120692 -239.018826) (xy 106.139939 -239.003389) (xy 106.181889 -238.977415) (xy 106.227026 -238.95749)
			(xy 106.274484 -238.943996) (xy 106.323352 -238.937192) (xy 106.348022 -238.936784) (xy 106.374671 -238.937283)
			(xy 106.427373 -238.94523) (xy 106.478302 -238.960942) (xy 106.52632 -238.984069) (xy 106.570356 -239.014095)
			(xy 106.609425 -239.050348) (xy 106.622148 -239.066303) (xy 113.164356 -239.066303) (xy 113.164356 -239.013005)
			(xy 113.172299 -238.960301) (xy 113.188009 -238.909371) (xy 113.211135 -238.86135) (xy 113.241159 -238.817313)
			(xy 113.277411 -238.778242) (xy 113.319082 -238.745011) (xy 113.36524 -238.718362) (xy 113.414854 -238.69889)
			(xy 113.466816 -238.68703) (xy 113.519966 -238.683047) (xy 113.573116 -238.68703) (xy 113.625078 -238.69889)
			(xy 113.674692 -238.718362) (xy 113.72085 -238.745011) (xy 113.762521 -238.778242) (xy 113.798773 -238.817313)
			(xy 113.828797 -238.86135) (xy 113.851923 -238.909371) (xy 113.867633 -238.960301) (xy 113.875576 -239.013005)
			(xy 113.876074 -239.039654) (xy 113.875576 -239.066303) (xy 113.867633 -239.119007) (xy 113.851923 -239.169937)
			(xy 113.828797 -239.217958) (xy 113.798773 -239.261995) (xy 113.762521 -239.301066) (xy 113.72085 -239.334297)
			(xy 113.674692 -239.360946) (xy 113.625078 -239.380418) (xy 113.573116 -239.392278) (xy 113.519966 -239.396262)
			(xy 113.466816 -239.392278) (xy 113.414854 -239.380418) (xy 113.36524 -239.360946) (xy 113.319082 -239.334297)
			(xy 113.277411 -239.301066) (xy 113.241159 -239.261995) (xy 113.211135 -239.217958) (xy 113.188009 -239.169937)
			(xy 113.172299 -239.119007) (xy 113.164356 -239.066303) (xy 106.622148 -239.066303) (xy 106.642654 -239.092018)
			(xy 106.669302 -239.138176) (xy 106.688773 -239.18779) (xy 106.700633 -239.239751) (xy 106.704616 -239.2929)
			(xy 106.700633 -239.346049) (xy 106.688773 -239.39801) (xy 106.669302 -239.447624) (xy 106.642654 -239.493782)
			(xy 106.609425 -239.535452) (xy 106.570356 -239.571705) (xy 106.52632 -239.601731) (xy 106.478302 -239.624858)
			(xy 106.427373 -239.64057) (xy 106.374671 -239.648517) (xy 106.348022 -239.649) (xy 106.323355 -239.648575)
			(xy 106.274494 -239.641754) (xy 106.227042 -239.628254) (xy 106.181908 -239.608332) (xy 106.139956 -239.582371)
			(xy 106.120692 -239.566958) (xy 106.109562 -239.558331) (xy 106.083802 -239.546984) (xy 106.055922 -239.543103)
			(xy 106.028042 -239.546984) (xy 106.002282 -239.558331) (xy 105.991152 -239.566958) (xy 105.969736 -239.584081)
			(xy 105.922679 -239.61222) (xy 105.871862 -239.632809) (xy 105.818489 -239.645361) (xy 105.763822 -239.649578)
			(xy 105.709155 -239.645361) (xy 105.655782 -239.632809) (xy 105.604965 -239.61222) (xy 105.557908 -239.584081)
			(xy 105.536492 -239.566958) (xy 105.525362 -239.558331) (xy 105.499602 -239.546984) (xy 105.471722 -239.543103)
			(xy 105.443842 -239.546984) (xy 105.418082 -239.558331) (xy 105.406952 -239.566958) (xy 105.387704 -239.582395)
			(xy 105.345754 -239.608367) (xy 105.300617 -239.628293) (xy 105.253159 -239.64179) (xy 105.204292 -239.648598)
			(xy 105.179622 -239.649) (xy 105.15192 -239.648498) (xy 105.097178 -239.639965) (xy 105.044419 -239.623054)
			(xy 104.994917 -239.598174) (xy 104.972104 -239.582452) (xy 104.937052 -239.557306) (xy 104.614239 -239.880119)
			(xy 109.87531 -239.880119) (xy 109.87531 -239.826821) (xy 109.883253 -239.774117) (xy 109.898963 -239.723187)
			(xy 109.922089 -239.675166) (xy 109.952113 -239.631129) (xy 109.988365 -239.592058) (xy 110.030036 -239.558827)
			(xy 110.076194 -239.532178) (xy 110.125808 -239.512706) (xy 110.17777 -239.500846) (xy 110.23092 -239.496863)
			(xy 110.28407 -239.500846) (xy 110.336032 -239.512706) (xy 110.385646 -239.532178) (xy 110.431804 -239.558827)
			(xy 110.473475 -239.592058) (xy 110.509727 -239.631129) (xy 110.539751 -239.675166) (xy 110.562877 -239.723187)
			(xy 110.578587 -239.774117) (xy 110.58653 -239.826821) (xy 110.587028 -239.85347) (xy 110.58653 -239.880119)
			(xy 110.578587 -239.932823) (xy 110.562877 -239.983753) (xy 110.539751 -240.031774) (xy 110.509727 -240.075811)
			(xy 110.473475 -240.114882) (xy 110.431804 -240.148113) (xy 110.385646 -240.174762) (xy 110.336032 -240.194234)
			(xy 110.28407 -240.206094) (xy 110.23092 -240.210078) (xy 110.17777 -240.206094) (xy 110.125808 -240.194234)
			(xy 110.076194 -240.174762) (xy 110.030036 -240.148113) (xy 109.988365 -240.114882) (xy 109.952113 -240.075811)
			(xy 109.922089 -240.031774) (xy 109.898963 -239.983753) (xy 109.883253 -239.932823) (xy 109.87531 -239.880119)
			(xy 104.614239 -239.880119) (xy 104.050338 -240.44402) (xy 103.827072 -240.66754) (xy 103.827072 -241.172746)
			(xy 108.070142 -241.172746) (xy 108.070574 -241.148077) (xy 108.077373 -241.09921) (xy 108.090862 -241.051753)
			(xy 108.110782 -241.006615) (xy 108.13675 -240.964665) (xy 108.152184 -240.945416) (xy 108.160771 -240.934257)
			(xy 108.172129 -240.908508) (xy 108.17602 -240.880636) (xy 108.172149 -240.852761) (xy 108.160808 -240.827004)
			(xy 108.152184 -240.815876) (xy 108.136763 -240.796618) (xy 108.110802 -240.754665) (xy 108.090881 -240.70953)
			(xy 108.077383 -240.662076) (xy 108.070565 -240.613214) (xy 108.070142 -240.588546) (xy 108.07064 -240.561897)
			(xy 108.078583 -240.509193) (xy 108.094293 -240.458263) (xy 108.117419 -240.410242) (xy 108.147443 -240.366205)
			(xy 108.183695 -240.327134) (xy 108.225366 -240.293903) (xy 108.271524 -240.267254) (xy 108.321138 -240.247782)
			(xy 108.3731 -240.235922) (xy 108.42625 -240.231939) (xy 108.4794 -240.235922) (xy 108.531362 -240.247782)
			(xy 108.580976 -240.267254) (xy 108.627134 -240.293903) (xy 108.668805 -240.327134) (xy 108.705057 -240.366205)
			(xy 108.735081 -240.410242) (xy 108.758207 -240.458263) (xy 108.773917 -240.509193) (xy 108.78186 -240.561897)
			(xy 108.782358 -240.588546) (xy 108.781922 -240.613215) (xy 108.775123 -240.662081) (xy 108.765998 -240.694189)
			(xy 113.16461 -240.694189) (xy 113.16461 -240.640891) (xy 113.172553 -240.588187) (xy 113.188263 -240.537257)
			(xy 113.211389 -240.489236) (xy 113.241413 -240.445199) (xy 113.277665 -240.406128) (xy 113.319336 -240.372897)
			(xy 113.365494 -240.346248) (xy 113.415108 -240.326776) (xy 113.46707 -240.314916) (xy 113.52022 -240.310933)
			(xy 113.57337 -240.314916) (xy 113.625332 -240.326776) (xy 113.674946 -240.346248) (xy 113.721104 -240.372897)
			(xy 113.762775 -240.406128) (xy 113.799027 -240.445199) (xy 113.829051 -240.489236) (xy 113.852177 -240.537257)
			(xy 113.867887 -240.588187) (xy 113.87583 -240.640891) (xy 113.876328 -240.66754) (xy 113.87583 -240.694189)
			(xy 113.867887 -240.746893) (xy 113.852177 -240.797823) (xy 113.829051 -240.845844) (xy 113.799027 -240.889881)
			(xy 113.762775 -240.928952) (xy 113.721104 -240.962183) (xy 113.674946 -240.988832) (xy 113.625332 -241.008304)
			(xy 113.57337 -241.020164) (xy 113.52022 -241.024148) (xy 113.46707 -241.020164) (xy 113.415108 -241.008304)
			(xy 113.365494 -240.988832) (xy 113.319336 -240.962183) (xy 113.277665 -240.928952) (xy 113.241413 -240.889881)
			(xy 113.211389 -240.845844) (xy 113.188263 -240.797823) (xy 113.172553 -240.746893) (xy 113.16461 -240.694189)
			(xy 108.765998 -240.694189) (xy 108.761635 -240.709539) (xy 108.741716 -240.754676) (xy 108.71575 -240.796627)
			(xy 108.700316 -240.815876) (xy 108.691642 -240.826973) (xy 108.680295 -240.852745) (xy 108.676421 -240.880636)
			(xy 108.680314 -240.908524) (xy 108.691679 -240.934287) (xy 108.700316 -240.945416) (xy 108.715733 -240.964677)
			(xy 108.741695 -241.006629) (xy 108.761616 -241.051764) (xy 108.775116 -241.099216) (xy 108.781934 -241.148078)
			(xy 108.782358 -241.172746) (xy 108.78186 -241.199395) (xy 108.773917 -241.252099) (xy 108.758207 -241.303029)
			(xy 108.735081 -241.35105) (xy 108.705057 -241.395087) (xy 108.668805 -241.434158) (xy 108.627134 -241.467389)
			(xy 108.580976 -241.494038) (xy 108.545389 -241.508005) (xy 109.87531 -241.508005) (xy 109.87531 -241.454707)
			(xy 109.883253 -241.402003) (xy 109.898963 -241.351073) (xy 109.922089 -241.303052) (xy 109.952113 -241.259015)
			(xy 109.988365 -241.219944) (xy 110.030036 -241.186713) (xy 110.076194 -241.160064) (xy 110.125808 -241.140592)
			(xy 110.17777 -241.128732) (xy 110.23092 -241.124749) (xy 110.28407 -241.128732) (xy 110.336032 -241.140592)
			(xy 110.385646 -241.160064) (xy 110.431804 -241.186713) (xy 110.473475 -241.219944) (xy 110.509727 -241.259015)
			(xy 110.539751 -241.303052) (xy 110.562877 -241.351073) (xy 110.578587 -241.402003) (xy 110.58653 -241.454707)
			(xy 110.587028 -241.481356) (xy 110.58653 -241.508005) (xy 110.578587 -241.560709) (xy 110.562877 -241.611639)
			(xy 110.539751 -241.65966) (xy 110.535765 -241.665506) (xy 115.067334 -241.665506) (xy 115.067744 -241.640836)
			(xy 115.074549 -241.591969) (xy 115.088043 -241.544511) (xy 115.107968 -241.499374) (xy 115.133939 -241.457424)
			(xy 115.149376 -241.438176) (xy 115.157994 -241.427041) (xy 115.169337 -241.401282) (xy 115.173217 -241.373405)
			(xy 115.16934 -241.345527) (xy 115.157999 -241.319767) (xy 115.149376 -241.308636) (xy 115.133935 -241.289393)
			(xy 115.107977 -241.247436) (xy 115.088061 -241.202297) (xy 115.074567 -241.15484) (xy 115.067754 -241.105975)
			(xy 115.067334 -241.081306) (xy 115.067832 -241.054657) (xy 115.075775 -241.001953) (xy 115.091485 -240.951023)
			(xy 115.114611 -240.903002) (xy 115.144635 -240.858965) (xy 115.180887 -240.819894) (xy 115.222558 -240.786663)
			(xy 115.268716 -240.760014) (xy 115.31833 -240.740542) (xy 115.370292 -240.728682) (xy 115.423442 -240.724699)
			(xy 115.476592 -240.728682) (xy 115.528554 -240.740542) (xy 115.578168 -240.760014) (xy 115.624326 -240.786663)
			(xy 115.665997 -240.819894) (xy 115.702249 -240.858965) (xy 115.732273 -240.903002) (xy 115.755399 -240.951023)
			(xy 115.771109 -241.001953) (xy 115.779052 -241.054657) (xy 115.77955 -241.081306) (xy 115.77915 -241.105976)
			(xy 115.772343 -241.154844) (xy 115.758846 -241.202302) (xy 115.73892 -241.247439) (xy 115.712945 -241.289388)
			(xy 115.697508 -241.308636) (xy 115.688873 -241.31976) (xy 115.677522 -241.345522) (xy 115.67364 -241.373405)
			(xy 115.677524 -241.401287) (xy 115.688877 -241.427047) (xy 115.697508 -241.438176) (xy 115.712952 -241.457417)
			(xy 115.73891 -241.499374) (xy 115.758826 -241.544514) (xy 115.772319 -241.591971) (xy 115.77913 -241.640837)
			(xy 115.77955 -241.665506) (xy 115.779052 -241.692155) (xy 115.771109 -241.744859) (xy 115.755399 -241.795789)
			(xy 115.732273 -241.84381) (xy 115.702249 -241.887847) (xy 115.665997 -241.926918) (xy 115.624326 -241.960149)
			(xy 115.578168 -241.986798) (xy 115.528554 -242.00627) (xy 115.476592 -242.01813) (xy 115.423442 -242.022114)
			(xy 115.370292 -242.01813) (xy 115.31833 -242.00627) (xy 115.268716 -241.986798) (xy 115.222558 -241.960149)
			(xy 115.180887 -241.926918) (xy 115.144635 -241.887847) (xy 115.114611 -241.84381) (xy 115.091485 -241.795789)
			(xy 115.075775 -241.744859) (xy 115.067832 -241.692155) (xy 115.067334 -241.665506) (xy 110.535765 -241.665506)
			(xy 110.509727 -241.703697) (xy 110.473475 -241.742768) (xy 110.431804 -241.775999) (xy 110.385646 -241.802648)
			(xy 110.336032 -241.82212) (xy 110.28407 -241.83398) (xy 110.23092 -241.837964) (xy 110.17777 -241.83398)
			(xy 110.125808 -241.82212) (xy 110.076194 -241.802648) (xy 110.030036 -241.775999) (xy 109.988365 -241.742768)
			(xy 109.952113 -241.703697) (xy 109.922089 -241.65966) (xy 109.898963 -241.611639) (xy 109.883253 -241.560709)
			(xy 109.87531 -241.508005) (xy 108.545389 -241.508005) (xy 108.531362 -241.51351) (xy 108.4794 -241.52537)
			(xy 108.42625 -241.529354) (xy 108.3731 -241.52537) (xy 108.321138 -241.51351) (xy 108.271524 -241.494038)
			(xy 108.225366 -241.467389) (xy 108.183695 -241.434158) (xy 108.147443 -241.395087) (xy 108.117419 -241.35105)
			(xy 108.094293 -241.303029) (xy 108.078583 -241.252099) (xy 108.07064 -241.199395) (xy 108.070142 -241.172746)
			(xy 103.827072 -241.172746) (xy 103.827072 -242.321821) (xy 113.16461 -242.321821) (xy 113.16461 -242.268523)
			(xy 113.172553 -242.215819) (xy 113.188263 -242.164889) (xy 113.211389 -242.116868) (xy 113.241413 -242.072831)
			(xy 113.277665 -242.03376) (xy 113.319336 -242.000529) (xy 113.365494 -241.97388) (xy 113.415108 -241.954408)
			(xy 113.46707 -241.942548) (xy 113.52022 -241.938565) (xy 113.57337 -241.942548) (xy 113.625332 -241.954408)
			(xy 113.674946 -241.97388) (xy 113.721104 -242.000529) (xy 113.762775 -242.03376) (xy 113.799027 -242.072831)
			(xy 113.829051 -242.116868) (xy 113.852177 -242.164889) (xy 113.867887 -242.215819) (xy 113.87583 -242.268523)
			(xy 113.876328 -242.295172) (xy 113.87583 -242.321821) (xy 113.867887 -242.374525) (xy 113.852177 -242.425455)
			(xy 113.829051 -242.473476) (xy 113.799027 -242.517513) (xy 113.762775 -242.556584) (xy 113.721104 -242.589815)
			(xy 113.674946 -242.616464) (xy 113.625332 -242.635936) (xy 113.57337 -242.647796) (xy 113.52022 -242.65178)
			(xy 113.46707 -242.647796) (xy 113.415108 -242.635936) (xy 113.365494 -242.616464) (xy 113.319336 -242.589815)
			(xy 113.277665 -242.556584) (xy 113.241413 -242.517513) (xy 113.211389 -242.473476) (xy 113.188263 -242.425455)
			(xy 113.172553 -242.374525) (xy 113.16461 -242.321821) (xy 103.827072 -242.321821) (xy 103.827072 -243.135891)
			(xy 109.87531 -243.135891) (xy 109.87531 -243.082593) (xy 109.883253 -243.029889) (xy 109.898963 -242.978959)
			(xy 109.922089 -242.930938) (xy 109.952113 -242.886901) (xy 109.988365 -242.84783) (xy 110.030036 -242.814599)
			(xy 110.076194 -242.78795) (xy 110.125808 -242.768478) (xy 110.17777 -242.756618) (xy 110.23092 -242.752635)
			(xy 110.28407 -242.756618) (xy 110.336032 -242.768478) (xy 110.385646 -242.78795) (xy 110.431804 -242.814599)
			(xy 110.473475 -242.84783) (xy 110.509727 -242.886901) (xy 110.539751 -242.930938) (xy 110.554325 -242.9612)
			(xy 117.467352 -242.9612) (xy 117.471336 -242.908045) (xy 117.483197 -242.856077) (xy 117.502671 -242.806457)
			(xy 117.529323 -242.760295) (xy 117.562558 -242.718619) (xy 117.601632 -242.682363) (xy 117.645674 -242.652336)
			(xy 117.693699 -242.629207) (xy 117.744635 -242.613495) (xy 117.797344 -242.60555) (xy 117.823996 -242.605052)
			(xy 117.84993 -242.605533) (xy 117.901251 -242.613048) (xy 117.950942 -242.627921) (xy 117.997953 -242.649836)
			(xy 118.041292 -242.678333) (xy 118.060978 -242.695222) (xy 118.072372 -242.70471) (xy 118.09922 -242.717259)
			(xy 118.128542 -242.721563) (xy 118.157864 -242.717259) (xy 118.184712 -242.70471) (xy 118.196106 -242.695222)
			(xy 118.215769 -242.678299) (xy 118.259097 -242.64977) (xy 118.306112 -242.627841) (xy 118.355814 -242.612977)
			(xy 118.407149 -242.605494) (xy 118.433088 -242.605052) (xy 118.459737 -242.605604) (xy 118.512439 -242.613546)
			(xy 118.563369 -242.629255) (xy 118.611389 -242.652378) (xy 118.655426 -242.682401) (xy 118.694497 -242.718652)
			(xy 118.727728 -242.760321) (xy 118.754377 -242.806477) (xy 118.773849 -242.85609) (xy 118.785709 -242.908052)
			(xy 118.789692 -242.9612) (xy 118.785709 -243.014348) (xy 118.773849 -243.06631) (xy 118.754377 -243.115923)
			(xy 118.727728 -243.162079) (xy 118.694497 -243.203748) (xy 118.655426 -243.239999) (xy 118.611389 -243.270022)
			(xy 118.563369 -243.293145) (xy 118.512439 -243.308854) (xy 118.459737 -243.316796) (xy 118.433088 -243.317268)
			(xy 118.407154 -243.316792) (xy 118.355833 -243.309275) (xy 118.306142 -243.294401) (xy 118.259132 -243.272484)
			(xy 118.215792 -243.243987) (xy 118.196106 -243.227098) (xy 118.184712 -243.21761) (xy 118.157864 -243.205061)
			(xy 118.128542 -243.200757) (xy 118.09922 -243.205061) (xy 118.072372 -243.21761) (xy 118.060978 -243.227098)
			(xy 118.041285 -243.243984) (xy 117.997964 -243.272518) (xy 117.950958 -243.294454) (xy 117.901262 -243.309326)
			(xy 117.849933 -243.31682) (xy 117.823996 -243.317268) (xy 117.797344 -243.31685) (xy 117.744635 -243.308905)
			(xy 117.693699 -243.293193) (xy 117.645674 -243.270064) (xy 117.601632 -243.240037) (xy 117.562558 -243.203781)
			(xy 117.529323 -243.162105) (xy 117.502671 -243.115943) (xy 117.483197 -243.066323) (xy 117.471336 -243.014355)
			(xy 117.467352 -242.9612) (xy 110.554325 -242.9612) (xy 110.562877 -242.978959) (xy 110.578587 -243.029889)
			(xy 110.58653 -243.082593) (xy 110.587028 -243.109242) (xy 110.58653 -243.135891) (xy 110.578587 -243.188595)
			(xy 110.562877 -243.239525) (xy 110.539751 -243.287546) (xy 110.509727 -243.331583) (xy 110.473475 -243.370654)
			(xy 110.431804 -243.403885) (xy 110.385646 -243.430534) (xy 110.336032 -243.450006) (xy 110.28407 -243.461866)
			(xy 110.23092 -243.46585) (xy 110.17777 -243.461866) (xy 110.125808 -243.450006) (xy 110.076194 -243.430534)
			(xy 110.030036 -243.403885) (xy 109.988365 -243.370654) (xy 109.952113 -243.331583) (xy 109.922089 -243.287546)
			(xy 109.898963 -243.239525) (xy 109.883253 -243.188595) (xy 109.87531 -243.135891) (xy 103.827072 -243.135891)
			(xy 103.827072 -243.14404) (xy 104.632739 -243.949707) (xy 113.16461 -243.949707) (xy 113.16461 -243.896409)
			(xy 113.172553 -243.843705) (xy 113.188263 -243.792775) (xy 113.211389 -243.744754) (xy 113.241413 -243.700717)
			(xy 113.277665 -243.661646) (xy 113.319336 -243.628415) (xy 113.365494 -243.601766) (xy 113.415108 -243.582294)
			(xy 113.46707 -243.570434) (xy 113.52022 -243.566451) (xy 113.57337 -243.570434) (xy 113.625332 -243.582294)
			(xy 113.674946 -243.601766) (xy 113.721104 -243.628415) (xy 113.762775 -243.661646) (xy 113.799027 -243.700717)
			(xy 113.829051 -243.744754) (xy 113.852177 -243.792775) (xy 113.867887 -243.843705) (xy 113.87583 -243.896409)
			(xy 113.876328 -243.923058) (xy 113.87583 -243.949707) (xy 113.867887 -244.002411) (xy 113.852177 -244.053341)
			(xy 113.829051 -244.101362) (xy 113.799027 -244.145399) (xy 113.762775 -244.18447) (xy 113.721104 -244.217701)
			(xy 113.674946 -244.24435) (xy 113.625332 -244.263822) (xy 113.57337 -244.275682) (xy 113.52022 -244.279666)
			(xy 113.46707 -244.275682) (xy 113.415108 -244.263822) (xy 113.365494 -244.24435) (xy 113.319336 -244.217701)
			(xy 113.277665 -244.18447) (xy 113.241413 -244.145399) (xy 113.211389 -244.101362) (xy 113.188263 -244.053341)
			(xy 113.172553 -244.002411) (xy 113.16461 -243.949707) (xy 104.632739 -243.949707) (xy 105.32364 -244.640608)
			(xy 105.32364 -245.34749) (xy 108.077762 -245.34749) (xy 108.078157 -245.32282) (xy 108.084965 -245.273951)
			(xy 108.098462 -245.226493) (xy 108.11839 -245.181356) (xy 108.144366 -245.139407) (xy 108.159804 -245.12016)
			(xy 108.168442 -245.109038) (xy 108.179792 -245.083275) (xy 108.183672 -245.055392) (xy 108.179787 -245.02751)
			(xy 108.168434 -245.001749) (xy 108.159804 -244.99062) (xy 108.144406 -244.971344) (xy 108.118441 -244.929396)
			(xy 108.098515 -244.884266) (xy 108.085012 -244.836816) (xy 108.078188 -244.787957) (xy 108.077762 -244.76329)
			(xy 108.07826 -244.736641) (xy 108.086203 -244.683937) (xy 108.101913 -244.633007) (xy 108.125039 -244.584986)
			(xy 108.155063 -244.540949) (xy 108.191315 -244.501878) (xy 108.232986 -244.468647) (xy 108.279144 -244.441998)
			(xy 108.328758 -244.422526) (xy 108.38072 -244.410666) (xy 108.43387 -244.406683) (xy 108.48702 -244.410666)
			(xy 108.538982 -244.422526) (xy 108.588596 -244.441998) (xy 108.634754 -244.468647) (xy 108.676425 -244.501878)
			(xy 108.712677 -244.540949) (xy 108.742701 -244.584986) (xy 108.765827 -244.633007) (xy 108.781537 -244.683937)
			(xy 108.78948 -244.736641) (xy 108.789978 -244.76329) (xy 108.789974 -244.763523) (xy 109.87531 -244.763523)
			(xy 109.87531 -244.710225) (xy 109.883253 -244.657521) (xy 109.898963 -244.606591) (xy 109.922089 -244.55857)
			(xy 109.952113 -244.514533) (xy 109.988365 -244.475462) (xy 110.030036 -244.442231) (xy 110.076194 -244.415582)
			(xy 110.125808 -244.39611) (xy 110.17777 -244.38425) (xy 110.23092 -244.380267) (xy 110.28407 -244.38425)
			(xy 110.336032 -244.39611) (xy 110.385646 -244.415582) (xy 110.431804 -244.442231) (xy 110.473475 -244.475462)
			(xy 110.509727 -244.514533) (xy 110.539751 -244.55857) (xy 110.562877 -244.606591) (xy 110.578587 -244.657521)
			(xy 110.58653 -244.710225) (xy 110.587028 -244.736874) (xy 110.58653 -244.763523) (xy 110.578587 -244.816227)
			(xy 110.562877 -244.867157) (xy 110.539751 -244.915178) (xy 110.509727 -244.959215) (xy 110.473475 -244.998286)
			(xy 110.431804 -245.031517) (xy 110.385646 -245.058166) (xy 110.336032 -245.077638) (xy 110.28407 -245.089498)
			(xy 110.23092 -245.093482) (xy 110.17777 -245.089498) (xy 110.125808 -245.077638) (xy 110.076194 -245.058166)
			(xy 110.030036 -245.031517) (xy 109.988365 -244.998286) (xy 109.952113 -244.959215) (xy 109.922089 -244.915178)
			(xy 109.898963 -244.867157) (xy 109.883253 -244.816227) (xy 109.87531 -244.763523) (xy 108.789974 -244.763523)
			(xy 108.789563 -244.787959) (xy 108.782759 -244.836827) (xy 108.769265 -244.884284) (xy 108.749342 -244.929422)
			(xy 108.723372 -244.971372) (xy 108.707936 -244.99062) (xy 108.699321 -245.001757) (xy 108.687976 -245.027515)
			(xy 108.684094 -245.055392) (xy 108.687972 -245.08327) (xy 108.699313 -245.10903) (xy 108.707936 -245.12016)
			(xy 108.723377 -245.139403) (xy 108.749335 -245.18136) (xy 108.769251 -245.226499) (xy 108.782745 -245.273956)
			(xy 108.789558 -245.322821) (xy 108.789978 -245.34749) (xy 108.78948 -245.374139) (xy 108.781537 -245.426843)
			(xy 108.765827 -245.477773) (xy 108.742701 -245.525794) (xy 108.712677 -245.569831) (xy 108.705475 -245.577593)
			(xy 113.16461 -245.577593) (xy 113.16461 -245.524295) (xy 113.172553 -245.471591) (xy 113.188263 -245.420661)
			(xy 113.211389 -245.37264) (xy 113.241413 -245.328603) (xy 113.277665 -245.289532) (xy 113.319336 -245.256301)
			(xy 113.365494 -245.229652) (xy 113.415108 -245.21018) (xy 113.46707 -245.19832) (xy 113.52022 -245.194337)
			(xy 113.57337 -245.19832) (xy 113.625332 -245.21018) (xy 113.674946 -245.229652) (xy 113.721104 -245.256301)
			(xy 113.762775 -245.289532) (xy 113.799027 -245.328603) (xy 113.829051 -245.37264) (xy 113.84067 -245.396766)
			(xy 115.059714 -245.396766) (xy 115.060163 -245.372098) (xy 115.06696 -245.323232) (xy 115.080445 -245.275775)
			(xy 115.100361 -245.230637) (xy 115.126324 -245.188685) (xy 115.141756 -245.169436) (xy 115.150414 -245.158329)
			(xy 115.161754 -245.13256) (xy 115.165627 -245.104674) (xy 115.16174 -245.07679) (xy 115.150386 -245.051027)
			(xy 115.141756 -245.039896) (xy 115.12634 -245.020634) (xy 115.100378 -244.978682) (xy 115.080457 -244.933548)
			(xy 115.066958 -244.886095) (xy 115.060138 -244.837234) (xy 115.059714 -244.812566) (xy 115.060212 -244.785917)
			(xy 115.068155 -244.733213) (xy 115.083865 -244.682283) (xy 115.106991 -244.634262) (xy 115.137015 -244.590225)
			(xy 115.173267 -244.551154) (xy 115.214938 -244.517923) (xy 115.261096 -244.491274) (xy 115.31071 -244.471802)
			(xy 115.362672 -244.459942) (xy 115.415822 -244.455959) (xy 115.468972 -244.459942) (xy 115.520934 -244.471802)
			(xy 115.570548 -244.491274) (xy 115.616706 -244.517923) (xy 115.658377 -244.551154) (xy 115.694629 -244.590225)
			(xy 115.724653 -244.634262) (xy 115.747779 -244.682283) (xy 115.763489 -244.733213) (xy 115.771432 -244.785917)
			(xy 115.77193 -244.812566) (xy 115.771512 -244.837235) (xy 115.76471 -244.886103) (xy 115.751218 -244.933561)
			(xy 115.731295 -244.978698) (xy 115.705324 -245.020648) (xy 115.689888 -245.039896) (xy 115.681292 -245.051048)
			(xy 115.669938 -245.0768) (xy 115.66605 -245.104674) (xy 115.669924 -245.132549) (xy 115.681264 -245.158307)
			(xy 115.689888 -245.169436) (xy 115.705326 -245.188681) (xy 115.731282 -245.230639) (xy 115.751198 -245.275777)
			(xy 115.764693 -245.323233) (xy 115.771508 -245.372097) (xy 115.77193 -245.396766) (xy 115.771432 -245.423415)
			(xy 115.763489 -245.476119) (xy 115.747779 -245.527049) (xy 115.724653 -245.57507) (xy 115.694629 -245.619107)
			(xy 115.658377 -245.658178) (xy 115.616706 -245.691409) (xy 115.570548 -245.718058) (xy 115.520934 -245.73753)
			(xy 115.468972 -245.74939) (xy 115.415822 -245.753374) (xy 115.362672 -245.74939) (xy 115.31071 -245.73753)
			(xy 115.261096 -245.718058) (xy 115.214938 -245.691409) (xy 115.173267 -245.658178) (xy 115.137015 -245.619107)
			(xy 115.106991 -245.57507) (xy 115.083865 -245.527049) (xy 115.068155 -245.476119) (xy 115.060212 -245.423415)
			(xy 115.059714 -245.396766) (xy 113.84067 -245.396766) (xy 113.852177 -245.420661) (xy 113.867887 -245.471591)
			(xy 113.87583 -245.524295) (xy 113.876328 -245.550944) (xy 113.87583 -245.577593) (xy 113.867887 -245.630297)
			(xy 113.852177 -245.681227) (xy 113.829051 -245.729248) (xy 113.799027 -245.773285) (xy 113.762775 -245.812356)
			(xy 113.721104 -245.845587) (xy 113.674946 -245.872236) (xy 113.625332 -245.891708) (xy 113.57337 -245.903568)
			(xy 113.52022 -245.907552) (xy 113.46707 -245.903568) (xy 113.415108 -245.891708) (xy 113.365494 -245.872236)
			(xy 113.319336 -245.845587) (xy 113.277665 -245.812356) (xy 113.241413 -245.773285) (xy 113.211389 -245.729248)
			(xy 113.188263 -245.681227) (xy 113.172553 -245.630297) (xy 113.16461 -245.577593) (xy 108.705475 -245.577593)
			(xy 108.676425 -245.608902) (xy 108.634754 -245.642133) (xy 108.588596 -245.668782) (xy 108.538982 -245.688254)
			(xy 108.48702 -245.700114) (xy 108.43387 -245.704098) (xy 108.38072 -245.700114) (xy 108.328758 -245.688254)
			(xy 108.279144 -245.668782) (xy 108.232986 -245.642133) (xy 108.191315 -245.608902) (xy 108.155063 -245.569831)
			(xy 108.125039 -245.525794) (xy 108.101913 -245.477773) (xy 108.086203 -245.426843) (xy 108.07826 -245.374139)
			(xy 108.077762 -245.34749) (xy 105.32364 -245.34749) (xy 105.32364 -246.319548) (xy 105.358692 -246.330978)
			(xy 105.381793 -246.338889) (xy 105.425747 -246.360156) (xy 105.46638 -246.387235) (xy 105.48493 -246.403114)
			(xy 105.496308 -246.412504) (xy 105.52306 -246.424907) (xy 105.55224 -246.429159) (xy 105.58142 -246.424907)
			(xy 105.608172 -246.412504) (xy 105.61955 -246.403114) (xy 105.639192 -246.386316) (xy 105.682412 -246.357977)
			(xy 105.729273 -246.336181) (xy 105.778792 -246.321385) (xy 105.829929 -246.313899) (xy 105.85577 -246.313452)
			(xy 105.882426 -246.313923) (xy 105.935142 -246.321865) (xy 105.986086 -246.337575) (xy 106.034119 -246.360703)
			(xy 106.078168 -246.390732) (xy 106.078898 -246.391409) (xy 109.87531 -246.391409) (xy 109.87531 -246.338111)
			(xy 109.883253 -246.285407) (xy 109.898963 -246.234477) (xy 109.922089 -246.186456) (xy 109.952113 -246.142419)
			(xy 109.988365 -246.103348) (xy 110.030036 -246.070117) (xy 110.076194 -246.043468) (xy 110.125808 -246.023996)
			(xy 110.17777 -246.012136) (xy 110.23092 -246.008153) (xy 110.28407 -246.012136) (xy 110.336032 -246.023996)
			(xy 110.385646 -246.043468) (xy 110.431804 -246.070117) (xy 110.473475 -246.103348) (xy 110.509727 -246.142419)
			(xy 110.539751 -246.186456) (xy 110.562877 -246.234477) (xy 110.578587 -246.285407) (xy 110.58653 -246.338111)
			(xy 110.587028 -246.36476) (xy 110.58653 -246.391409) (xy 110.578587 -246.444113) (xy 110.562877 -246.495043)
			(xy 110.539751 -246.543064) (xy 110.509727 -246.587101) (xy 110.473475 -246.626172) (xy 110.431804 -246.659403)
			(xy 110.385646 -246.686052) (xy 110.336032 -246.705524) (xy 110.28407 -246.717384) (xy 110.23092 -246.721368)
			(xy 110.17777 -246.717384) (xy 110.125808 -246.705524) (xy 110.076194 -246.686052) (xy 110.030036 -246.659403)
			(xy 109.988365 -246.626172) (xy 109.952113 -246.587101) (xy 109.922089 -246.543064) (xy 109.898963 -246.495043)
			(xy 109.883253 -246.444113) (xy 109.87531 -246.391409) (xy 106.078898 -246.391409) (xy 106.117249 -246.426991)
			(xy 106.15049 -246.46867) (xy 106.177147 -246.514838) (xy 106.196624 -246.564464) (xy 106.208488 -246.616438)
			(xy 106.212472 -246.6696) (xy 106.208488 -246.722762) (xy 106.196624 -246.774736) (xy 106.177147 -246.824362)
			(xy 106.15049 -246.87053) (xy 106.117249 -246.912209) (xy 106.078168 -246.948468) (xy 106.034119 -246.978497)
			(xy 105.986086 -247.001625) (xy 105.935142 -247.017335) (xy 105.882426 -247.025277) (xy 105.85577 -247.025668)
			(xy 105.829928 -247.025211) (xy 105.778786 -247.017744) (xy 105.729262 -247.002958) (xy 105.682398 -246.981164)
			(xy 105.63918 -246.952819) (xy 105.61955 -246.936006) (xy 105.608172 -246.926616) (xy 105.58142 -246.914213)
			(xy 105.55224 -246.909961) (xy 105.52306 -246.914213) (xy 105.496308 -246.926616) (xy 105.48493 -246.936006)
			(xy 105.466383 -246.951888) (xy 105.425744 -246.978956) (xy 105.381788 -247.000216) (xy 105.358692 -247.008142)
			(xy 105.32364 -247.019572) (xy 105.32364 -247.205225) (xy 113.16461 -247.205225) (xy 113.16461 -247.151927)
			(xy 113.172553 -247.099223) (xy 113.188263 -247.048293) (xy 113.211389 -247.000272) (xy 113.241413 -246.956235)
			(xy 113.277665 -246.917164) (xy 113.319336 -246.883933) (xy 113.365494 -246.857284) (xy 113.415108 -246.837812)
			(xy 113.46707 -246.825952) (xy 113.52022 -246.821969) (xy 113.57337 -246.825952) (xy 113.625332 -246.837812)
			(xy 113.674946 -246.857284) (xy 113.721104 -246.883933) (xy 113.762775 -246.917164) (xy 113.799027 -246.956235)
			(xy 113.829051 -247.000272) (xy 113.852177 -247.048293) (xy 113.867887 -247.099223) (xy 113.87583 -247.151927)
			(xy 113.876328 -247.178576) (xy 113.87583 -247.205225) (xy 113.867887 -247.257929) (xy 113.852177 -247.308859)
			(xy 113.829051 -247.35688) (xy 113.799027 -247.400917) (xy 113.762775 -247.439988) (xy 113.721104 -247.473219)
			(xy 113.674946 -247.499868) (xy 113.625332 -247.51934) (xy 113.57337 -247.5312) (xy 113.52022 -247.535184)
			(xy 113.46707 -247.5312) (xy 113.415108 -247.51934) (xy 113.365494 -247.499868) (xy 113.319336 -247.473219)
			(xy 113.277665 -247.439988) (xy 113.241413 -247.400917) (xy 113.211389 -247.35688) (xy 113.188263 -247.308859)
			(xy 113.172553 -247.257929) (xy 113.16461 -247.205225) (xy 105.32364 -247.205225) (xy 105.32364 -248.019041)
			(xy 109.87531 -248.019041) (xy 109.87531 -247.965743) (xy 109.883253 -247.913039) (xy 109.898963 -247.862109)
			(xy 109.922089 -247.814088) (xy 109.952113 -247.770051) (xy 109.988365 -247.73098) (xy 110.030036 -247.697749)
			(xy 110.076194 -247.6711) (xy 110.125808 -247.651628) (xy 110.17777 -247.639768) (xy 110.23092 -247.635785)
			(xy 110.28407 -247.639768) (xy 110.336032 -247.651628) (xy 110.385646 -247.6711) (xy 110.431804 -247.697749)
			(xy 110.473475 -247.73098) (xy 110.509727 -247.770051) (xy 110.539751 -247.814088) (xy 110.562877 -247.862109)
			(xy 110.578587 -247.913039) (xy 110.58653 -247.965743) (xy 110.587028 -247.992392) (xy 110.58653 -248.019041)
			(xy 110.578587 -248.071745) (xy 110.562877 -248.122675) (xy 110.539751 -248.170696) (xy 110.509727 -248.214733)
			(xy 110.473475 -248.253804) (xy 110.431804 -248.287035) (xy 110.385646 -248.313684) (xy 110.336032 -248.333156)
			(xy 110.28407 -248.345016) (xy 110.23092 -248.349) (xy 110.17777 -248.345016) (xy 110.125808 -248.333156)
			(xy 110.076194 -248.313684) (xy 110.030036 -248.287035) (xy 109.988365 -248.253804) (xy 109.952113 -248.214733)
			(xy 109.922089 -248.170696) (xy 109.898963 -248.122675) (xy 109.883253 -248.071745) (xy 109.87531 -248.019041)
			(xy 105.32364 -248.019041) (xy 105.32364 -249.005344) (xy 108.077762 -249.005344) (xy 108.078188 -248.980675)
			(xy 108.084988 -248.931808) (xy 108.098479 -248.88435) (xy 108.1184 -248.839213) (xy 108.144369 -248.797262)
			(xy 108.159804 -248.778014) (xy 108.168391 -248.766855) (xy 108.179747 -248.741106) (xy 108.183637 -248.713234)
			(xy 108.179766 -248.685359) (xy 108.168427 -248.659603) (xy 108.159804 -248.648474) (xy 108.144385 -248.629214)
			(xy 108.118423 -248.587262) (xy 108.098502 -248.542127) (xy 108.085003 -248.494674) (xy 108.078185 -248.445812)
			(xy 108.077762 -248.421144) (xy 108.07826 -248.394495) (xy 108.086203 -248.341791) (xy 108.101913 -248.290861)
			(xy 108.125039 -248.24284) (xy 108.155063 -248.198803) (xy 108.191315 -248.159732) (xy 108.232986 -248.126501)
			(xy 108.279144 -248.099852) (xy 108.328758 -248.08038) (xy 108.38072 -248.06852) (xy 108.43387 -248.064537)
			(xy 108.48702 -248.06852) (xy 108.538982 -248.08038) (xy 108.588596 -248.099852) (xy 108.634754 -248.126501)
			(xy 108.676425 -248.159732) (xy 108.712677 -248.198803) (xy 108.742701 -248.24284) (xy 108.765827 -248.290861)
			(xy 108.781537 -248.341791) (xy 108.78948 -248.394495) (xy 108.789978 -248.421144) (xy 108.789536 -248.445812)
			(xy 108.782738 -248.494679) (xy 108.769251 -248.542136) (xy 108.749334 -248.587274) (xy 108.723369 -248.629225)
			(xy 108.707936 -248.648474) (xy 108.699269 -248.659575) (xy 108.687931 -248.685346) (xy 108.68406 -248.713234)
			(xy 108.68795 -248.741119) (xy 108.699305 -248.766883) (xy 108.707936 -248.778014) (xy 108.723356 -248.797273)
			(xy 108.745533 -248.833111) (xy 113.16461 -248.833111) (xy 113.16461 -248.779813) (xy 113.172553 -248.727109)
			(xy 113.188263 -248.676179) (xy 113.211389 -248.628158) (xy 113.241413 -248.584121) (xy 113.277665 -248.54505)
			(xy 113.319336 -248.511819) (xy 113.365494 -248.48517) (xy 113.415108 -248.465698) (xy 113.46707 -248.453838)
			(xy 113.52022 -248.449855) (xy 113.57337 -248.453838) (xy 113.625332 -248.465698) (xy 113.674946 -248.48517)
			(xy 113.721104 -248.511819) (xy 113.762775 -248.54505) (xy 113.799027 -248.584121) (xy 113.829051 -248.628158)
			(xy 113.852177 -248.676179) (xy 113.867887 -248.727109) (xy 113.87583 -248.779813) (xy 113.876328 -248.806462)
			(xy 113.87583 -248.833111) (xy 113.867887 -248.885815) (xy 113.852177 -248.936745) (xy 113.829051 -248.984766)
			(xy 113.799027 -249.028803) (xy 113.762775 -249.067874) (xy 113.721104 -249.101105) (xy 113.674946 -249.127754)
			(xy 113.625332 -249.147226) (xy 113.57337 -249.159086) (xy 113.52022 -249.16307) (xy 113.46707 -249.159086)
			(xy 113.415108 -249.147226) (xy 113.365494 -249.127754) (xy 113.319336 -249.101105) (xy 113.277665 -249.067874)
			(xy 113.241413 -249.028803) (xy 113.211389 -248.984766) (xy 113.188263 -248.936745) (xy 113.172553 -248.885815)
			(xy 113.16461 -248.833111) (xy 108.745533 -248.833111) (xy 108.749317 -248.839226) (xy 108.769237 -248.884361)
			(xy 108.782736 -248.931814) (xy 108.789555 -248.980676) (xy 108.789978 -249.005344) (xy 108.78948 -249.031993)
			(xy 108.781537 -249.084697) (xy 108.765827 -249.135627) (xy 108.742701 -249.183648) (xy 108.713085 -249.227086)
			(xy 115.026694 -249.227086) (xy 115.02708 -249.202415) (xy 115.033889 -249.153546) (xy 115.047388 -249.106088)
			(xy 115.067318 -249.060951) (xy 115.093296 -249.019003) (xy 115.108736 -248.999756) (xy 115.117376 -248.988636)
			(xy 115.128721 -248.962872) (xy 115.132599 -248.934989) (xy 115.128715 -248.907107) (xy 115.117365 -248.881346)
			(xy 115.108736 -248.870216) (xy 115.093326 -248.850949) (xy 115.067364 -248.808998) (xy 115.047442 -248.763865)
			(xy 115.033941 -248.716414) (xy 115.027119 -248.667553) (xy 115.026694 -248.642886) (xy 115.027192 -248.616237)
			(xy 115.035135 -248.563533) (xy 115.050845 -248.512603) (xy 115.073971 -248.464582) (xy 115.103995 -248.420545)
			(xy 115.140247 -248.381474) (xy 115.181918 -248.348243) (xy 115.228076 -248.321594) (xy 115.27769 -248.302122)
			(xy 115.329652 -248.290262) (xy 115.382802 -248.286279) (xy 115.435952 -248.290262) (xy 115.487914 -248.302122)
			(xy 115.537528 -248.321594) (xy 115.583686 -248.348243) (xy 115.625357 -248.381474) (xy 115.661609 -248.420545)
			(xy 115.691633 -248.464582) (xy 115.714759 -248.512603) (xy 115.730469 -248.563533) (xy 115.738412 -248.616237)
			(xy 115.73891 -248.642886) (xy 115.738508 -248.667556) (xy 115.731702 -248.716424) (xy 115.718207 -248.763883)
			(xy 115.698281 -248.80902) (xy 115.672306 -248.850969) (xy 115.656868 -248.870216) (xy 115.648255 -248.881355)
			(xy 115.636906 -248.907112) (xy 115.633022 -248.934989) (xy 115.6369 -248.962867) (xy 115.648243 -248.988626)
			(xy 115.656868 -248.999756) (xy 115.672312 -249.018996) (xy 115.698268 -249.060955) (xy 115.718183 -249.106095)
			(xy 115.731677 -249.153552) (xy 115.73849 -249.202417) (xy 115.73891 -249.227086) (xy 115.738412 -249.253735)
			(xy 115.730469 -249.306439) (xy 115.714759 -249.357369) (xy 115.691633 -249.40539) (xy 115.661609 -249.449427)
			(xy 115.625357 -249.488498) (xy 115.583686 -249.521729) (xy 115.537528 -249.548378) (xy 115.487914 -249.56785)
			(xy 115.435952 -249.57971) (xy 115.382802 -249.583694) (xy 115.329652 -249.57971) (xy 115.27769 -249.56785)
			(xy 115.228076 -249.548378) (xy 115.181918 -249.521729) (xy 115.140247 -249.488498) (xy 115.103995 -249.449427)
			(xy 115.073971 -249.40539) (xy 115.050845 -249.357369) (xy 115.035135 -249.306439) (xy 115.027192 -249.253735)
			(xy 115.026694 -249.227086) (xy 108.713085 -249.227086) (xy 108.712677 -249.227685) (xy 108.676425 -249.266756)
			(xy 108.634754 -249.299987) (xy 108.588596 -249.326636) (xy 108.538982 -249.346108) (xy 108.48702 -249.357968)
			(xy 108.43387 -249.361952) (xy 108.38072 -249.357968) (xy 108.328758 -249.346108) (xy 108.279144 -249.326636)
			(xy 108.232986 -249.299987) (xy 108.191315 -249.266756) (xy 108.155063 -249.227685) (xy 108.125039 -249.183648)
			(xy 108.101913 -249.135627) (xy 108.086203 -249.084697) (xy 108.07826 -249.031993) (xy 108.077762 -249.005344)
			(xy 105.32364 -249.005344) (xy 105.32364 -249.646927) (xy 109.87531 -249.646927) (xy 109.87531 -249.593629)
			(xy 109.883253 -249.540925) (xy 109.898963 -249.489995) (xy 109.922089 -249.441974) (xy 109.952113 -249.397937)
			(xy 109.988365 -249.358866) (xy 110.030036 -249.325635) (xy 110.076194 -249.298986) (xy 110.125808 -249.279514)
			(xy 110.17777 -249.267654) (xy 110.23092 -249.263671) (xy 110.28407 -249.267654) (xy 110.336032 -249.279514)
			(xy 110.385646 -249.298986) (xy 110.431804 -249.325635) (xy 110.473475 -249.358866) (xy 110.509727 -249.397937)
			(xy 110.539751 -249.441974) (xy 110.562877 -249.489995) (xy 110.578587 -249.540925) (xy 110.58653 -249.593629)
			(xy 110.587028 -249.620278) (xy 110.58653 -249.646927) (xy 110.578587 -249.699631) (xy 110.562877 -249.750561)
			(xy 110.539751 -249.798582) (xy 110.509727 -249.842619) (xy 110.473475 -249.88169) (xy 110.431804 -249.914921)
			(xy 110.385646 -249.94157) (xy 110.336032 -249.961042) (xy 110.28407 -249.972902) (xy 110.23092 -249.976886)
			(xy 110.17777 -249.972902) (xy 110.125808 -249.961042) (xy 110.076194 -249.94157) (xy 110.030036 -249.914921)
			(xy 109.988365 -249.88169) (xy 109.952113 -249.842619) (xy 109.922089 -249.798582) (xy 109.898963 -249.750561)
			(xy 109.883253 -249.699631) (xy 109.87531 -249.646927) (xy 105.32364 -249.646927) (xy 105.32364 -249.880628)
			(xy 105.324075 -249.894544) (xy 105.331599 -249.921339) (xy 105.346082 -249.945106) (xy 105.366445 -249.964078)
			(xy 105.391176 -249.976845) (xy 105.418436 -249.982458) (xy 105.432352 -249.981974) (xy 105.45699 -249.981212)
			(xy 105.482831 -249.981673) (xy 105.533969 -249.989147) (xy 105.583488 -250.003939) (xy 105.630347 -250.025738)
			(xy 105.67356 -250.054086) (xy 105.69321 -250.070874) (xy 105.704588 -250.080264) (xy 105.73134 -250.092667)
			(xy 105.76052 -250.096919) (xy 105.7897 -250.092667) (xy 105.816452 -250.080264) (xy 105.82783 -250.070874)
			(xy 105.847472 -250.054076) (xy 105.890693 -250.025739) (xy 105.937554 -250.003942) (xy 105.987072 -249.989145)
			(xy 106.038209 -249.981657) (xy 106.06405 -249.981212) (xy 106.090702 -249.981682) (xy 106.143412 -249.989619)
			(xy 106.194349 -250.005325) (xy 106.242377 -250.028448) (xy 106.286422 -250.058472) (xy 106.325499 -250.094725)
			(xy 106.358736 -250.136398) (xy 106.38539 -250.182559) (xy 106.404866 -250.232178) (xy 106.416728 -250.284145)
			(xy 106.420712 -250.3373) (xy 117.467413 -250.3373) (xy 117.471396 -250.284154) (xy 117.483255 -250.232195)
			(xy 117.502726 -250.182584) (xy 117.529373 -250.136429) (xy 117.562602 -250.094761) (xy 117.60167 -250.05851)
			(xy 117.645704 -250.028488) (xy 117.693721 -250.005364) (xy 117.744649 -249.989654) (xy 117.797348 -249.98171)
			(xy 117.823996 -249.981212) (xy 117.84993 -249.981703) (xy 117.90125 -249.989217) (xy 117.95094 -250.004088)
			(xy 117.997951 -250.026001) (xy 118.041291 -250.054494) (xy 118.060978 -250.071382) (xy 118.072372 -250.08087)
			(xy 118.09922 -250.093419) (xy 118.128542 -250.097723) (xy 118.157864 -250.093419) (xy 118.184712 -250.08087)
			(xy 118.196106 -250.071382) (xy 118.215764 -250.054453) (xy 118.259094 -250.025926) (xy 118.30611 -250.003999)
			(xy 118.355813 -249.989137) (xy 118.407149 -249.981654) (xy 118.433088 -249.981212) (xy 118.459741 -249.981644)
			(xy 118.512452 -249.989588) (xy 118.563391 -250.005299) (xy 118.611419 -250.028426) (xy 118.655464 -250.058454)
			(xy 118.694541 -250.094711) (xy 118.727777 -250.136387) (xy 118.754431 -250.182551) (xy 118.773906 -250.232173)
			(xy 118.785768 -250.284143) (xy 118.789752 -250.3373) (xy 118.785768 -250.390457) (xy 118.773906 -250.442427)
			(xy 118.754431 -250.492049) (xy 118.727777 -250.538213) (xy 118.694541 -250.579889) (xy 118.655464 -250.616146)
			(xy 118.611419 -250.646174) (xy 118.563391 -250.669301) (xy 118.512452 -250.685012) (xy 118.459741 -250.692956)
			(xy 118.433088 -250.693428) (xy 118.407153 -250.692962) (xy 118.355831 -250.685444) (xy 118.306141 -250.670568)
			(xy 118.25913 -250.648649) (xy 118.215791 -250.620149) (xy 118.196106 -250.603258) (xy 118.184712 -250.59377)
			(xy 118.157864 -250.581221) (xy 118.128542 -250.576917) (xy 118.09922 -250.581221) (xy 118.072372 -250.59377)
			(xy 118.060978 -250.603258) (xy 118.04128 -250.620138) (xy 117.997961 -250.648674) (xy 117.950956 -250.670611)
			(xy 117.901261 -250.685485) (xy 117.849933 -250.69298) (xy 117.823996 -250.693428) (xy 117.797348 -250.69289)
			(xy 117.744649 -250.684946) (xy 117.693721 -250.669236) (xy 117.645704 -250.646112) (xy 117.60167 -250.61609)
			(xy 117.562602 -250.579839) (xy 117.529373 -250.538171) (xy 117.502726 -250.492016) (xy 117.483255 -250.442405)
			(xy 117.471396 -250.390446) (xy 117.467413 -250.3373) (xy 106.420712 -250.3373) (xy 106.416728 -250.390455)
			(xy 106.404866 -250.442422) (xy 106.38539 -250.492041) (xy 106.358736 -250.538202) (xy 106.325499 -250.579875)
			(xy 106.286422 -250.616128) (xy 106.242377 -250.646152) (xy 106.194349 -250.669275) (xy 106.143412 -250.684981)
			(xy 106.090702 -250.692918) (xy 106.06405 -250.693428) (xy 106.038208 -250.69297) (xy 105.987067 -250.685502)
			(xy 105.937543 -250.670715) (xy 105.890679 -250.648922) (xy 105.847459 -250.620579) (xy 105.82783 -250.603766)
			(xy 105.816452 -250.594376) (xy 105.7897 -250.581973) (xy 105.76052 -250.577721) (xy 105.73134 -250.581973)
			(xy 105.704588 -250.594376) (xy 105.69321 -250.603766) (xy 105.673566 -250.620559) (xy 105.630343 -250.648886)
			(xy 105.583481 -250.670672) (xy 105.533964 -250.685459) (xy 105.482829 -250.692938) (xy 105.45699 -250.693428)
			(xy 105.432352 -250.692666) (xy 105.418433 -250.692116) (xy 105.391159 -250.697733) (xy 105.366417 -250.710509)
			(xy 105.346047 -250.729495) (xy 105.331563 -250.753277) (xy 105.324043 -250.780089) (xy 105.32364 -250.794012)
			(xy 105.32364 -252.659388) (xy 108.077762 -252.659388) (xy 108.078156 -252.634718) (xy 108.084964 -252.585849)
			(xy 108.098462 -252.538391) (xy 108.11839 -252.493254) (xy 108.144366 -252.451305) (xy 108.159804 -252.432058)
			(xy 108.168444 -252.420937) (xy 108.179793 -252.395174) (xy 108.183673 -252.367291) (xy 108.179788 -252.339408)
			(xy 108.168434 -252.313647) (xy 108.159804 -252.302518) (xy 108.144405 -252.283243) (xy 108.11844 -252.241295)
			(xy 108.098515 -252.196164) (xy 108.085011 -252.148714) (xy 108.078188 -252.099855) (xy 108.077762 -252.075188)
			(xy 108.07826 -252.048539) (xy 108.086203 -251.995835) (xy 108.101913 -251.944905) (xy 108.125039 -251.896884)
			(xy 108.155063 -251.852847) (xy 108.191315 -251.813776) (xy 108.232986 -251.780545) (xy 108.279144 -251.753896)
			(xy 108.328758 -251.734424) (xy 108.38072 -251.722564) (xy 108.43387 -251.718581) (xy 108.48702 -251.722564)
			(xy 108.538982 -251.734424) (xy 108.588596 -251.753896) (xy 108.634754 -251.780545) (xy 108.676425 -251.813776)
			(xy 108.712677 -251.852847) (xy 108.742701 -251.896884) (xy 108.765827 -251.944905) (xy 108.781537 -251.995835)
			(xy 108.78948 -252.048539) (xy 108.789978 -252.075188) (xy 108.789562 -252.099857) (xy 108.782758 -252.148725)
			(xy 108.769265 -252.196182) (xy 108.749342 -252.24132) (xy 108.723372 -252.28327) (xy 108.707936 -252.302518)
			(xy 108.699323 -252.313657) (xy 108.687977 -252.339414) (xy 108.684096 -252.367291) (xy 108.687972 -252.395168)
			(xy 108.699313 -252.420928) (xy 108.707936 -252.432058) (xy 108.723376 -252.451301) (xy 108.749334 -252.493259)
			(xy 108.769251 -252.538398) (xy 108.782745 -252.585854) (xy 108.789558 -252.634719) (xy 108.789978 -252.659388)
			(xy 108.78948 -252.686037) (xy 108.781537 -252.738741) (xy 108.765827 -252.789671) (xy 108.757989 -252.805946)
			(xy 115.077494 -252.805946) (xy 115.077914 -252.781277) (xy 115.084715 -252.732409) (xy 115.098206 -252.684951)
			(xy 115.118128 -252.639813) (xy 115.1441 -252.597864) (xy 115.159536 -252.578616) (xy 115.168119 -252.567455)
			(xy 115.179471 -252.541706) (xy 115.18336 -252.513836) (xy 115.179491 -252.485962) (xy 115.168156 -252.460206)
			(xy 115.159536 -252.449076) (xy 115.144107 -252.429824) (xy 115.118149 -252.387869) (xy 115.09823 -252.342732)
			(xy 115.084733 -252.295277) (xy 115.077917 -252.246414) (xy 115.077494 -252.221746) (xy 115.077992 -252.195097)
			(xy 115.085935 -252.142393) (xy 115.101645 -252.091463) (xy 115.124771 -252.043442) (xy 115.154795 -251.999405)
			(xy 115.191047 -251.960334) (xy 115.232718 -251.927103) (xy 115.278876 -251.900454) (xy 115.32849 -251.880982)
			(xy 115.380452 -251.869122) (xy 115.433602 -251.865139) (xy 115.486752 -251.869122) (xy 115.538714 -251.880982)
			(xy 115.588328 -251.900454) (xy 115.634486 -251.927103) (xy 115.676157 -251.960334) (xy 115.712409 -251.999405)
			(xy 115.742433 -252.043442) (xy 115.765559 -252.091463) (xy 115.781269 -252.142393) (xy 115.789212 -252.195097)
			(xy 115.78971 -252.221746) (xy 115.789285 -252.246415) (xy 115.782485 -252.295283) (xy 115.768995 -252.342741)
			(xy 115.749074 -252.387878) (xy 115.723104 -252.429828) (xy 115.707668 -252.449076) (xy 115.698997 -252.460174)
			(xy 115.687656 -252.485946) (xy 115.683783 -252.513836) (xy 115.687675 -252.541722) (xy 115.699035 -252.567486)
			(xy 115.707668 -252.578616) (xy 115.723094 -252.597871) (xy 115.749053 -252.639825) (xy 115.768971 -252.684961)
			(xy 115.782469 -252.732415) (xy 115.789287 -252.781278) (xy 115.78971 -252.805946) (xy 115.789212 -252.832595)
			(xy 115.781269 -252.885299) (xy 115.765559 -252.936229) (xy 115.742433 -252.98425) (xy 115.712409 -253.028287)
			(xy 115.676157 -253.067358) (xy 115.634486 -253.100589) (xy 115.588328 -253.127238) (xy 115.538714 -253.14671)
			(xy 115.486752 -253.15857) (xy 115.433602 -253.162554) (xy 115.380452 -253.15857) (xy 115.32849 -253.14671)
			(xy 115.278876 -253.127238) (xy 115.232718 -253.100589) (xy 115.191047 -253.067358) (xy 115.154795 -253.028287)
			(xy 115.124771 -252.98425) (xy 115.101645 -252.936229) (xy 115.085935 -252.885299) (xy 115.077992 -252.832595)
			(xy 115.077494 -252.805946) (xy 108.757989 -252.805946) (xy 108.742701 -252.837692) (xy 108.712677 -252.881729)
			(xy 108.676425 -252.9208) (xy 108.634754 -252.954031) (xy 108.588596 -252.98068) (xy 108.538982 -253.000152)
			(xy 108.48702 -253.012012) (xy 108.43387 -253.015996) (xy 108.38072 -253.012012) (xy 108.328758 -253.000152)
			(xy 108.279144 -252.98068) (xy 108.232986 -252.954031) (xy 108.191315 -252.9208) (xy 108.155063 -252.881729)
			(xy 108.125039 -252.837692) (xy 108.101913 -252.789671) (xy 108.086203 -252.738741) (xy 108.07826 -252.686037)
			(xy 108.077762 -252.659388) (xy 105.32364 -252.659388) (xy 105.32364 -253.558548) (xy 105.324065 -253.572471)
			(xy 105.331576 -253.599285) (xy 105.346053 -253.623071) (xy 105.36642 -253.642061) (xy 105.391161 -253.65484)
			(xy 105.418434 -253.660458) (xy 105.432352 -253.659894) (xy 105.45699 -253.659132) (xy 105.482831 -253.659593)
			(xy 105.533968 -253.667068) (xy 105.583487 -253.68186) (xy 105.630345 -253.70366) (xy 105.673557 -253.732009)
			(xy 105.69321 -253.748794) (xy 105.704588 -253.758184) (xy 105.73134 -253.770587) (xy 105.76052 -253.774839)
			(xy 105.7897 -253.770587) (xy 105.816452 -253.758184) (xy 105.82783 -253.748794) (xy 105.847472 -253.731995)
			(xy 105.890692 -253.703656) (xy 105.937553 -253.681859) (xy 105.987072 -253.66706) (xy 106.038209 -253.659572)
			(xy 106.06405 -253.659132) (xy 106.090701 -253.659602) (xy 106.143407 -253.667539) (xy 106.194342 -253.683244)
			(xy 106.242367 -253.706366) (xy 106.286409 -253.736387) (xy 106.325484 -253.772638) (xy 106.358719 -253.814309)
			(xy 106.385372 -253.860468) (xy 106.404847 -253.910084) (xy 106.413191 -253.946639) (xy 113.274338 -253.946639)
			(xy 113.274338 -253.893341) (xy 113.282281 -253.840637) (xy 113.297991 -253.789707) (xy 113.321117 -253.741686)
			(xy 113.351141 -253.697649) (xy 113.387393 -253.658578) (xy 113.429064 -253.625347) (xy 113.475222 -253.598698)
			(xy 113.524836 -253.579226) (xy 113.576798 -253.567366) (xy 113.629948 -253.563383) (xy 113.683098 -253.567366)
			(xy 113.73506 -253.579226) (xy 113.784674 -253.598698) (xy 113.830832 -253.625347) (xy 113.872503 -253.658578)
			(xy 113.908755 -253.697649) (xy 113.938779 -253.741686) (xy 113.961905 -253.789707) (xy 113.977615 -253.840637)
			(xy 113.985558 -253.893341) (xy 113.986056 -253.91999) (xy 113.985558 -253.946639) (xy 113.977615 -253.999343)
			(xy 113.972724 -254.0152) (xy 117.467433 -254.0152) (xy 117.471416 -253.962057) (xy 117.483274 -253.910101)
			(xy 117.502744 -253.860492) (xy 117.52939 -253.81434) (xy 117.562617 -253.772674) (xy 117.601682 -253.736426)
			(xy 117.645714 -253.706405) (xy 117.693729 -253.683282) (xy 117.744653 -253.667574) (xy 117.79735 -253.65963)
			(xy 117.823996 -253.659132) (xy 117.84993 -253.659618) (xy 117.901251 -253.667133) (xy 117.950941 -253.682004)
			(xy 117.997952 -253.703919) (xy 118.041291 -253.732413) (xy 118.060978 -253.749302) (xy 118.072372 -253.75879)
			(xy 118.09922 -253.771339) (xy 118.128542 -253.775643) (xy 118.157864 -253.771339) (xy 118.184712 -253.75879)
			(xy 118.196106 -253.749302) (xy 118.215766 -253.732376) (xy 118.259096 -253.703848) (xy 118.306111 -253.68192)
			(xy 118.355814 -253.667057) (xy 118.407149 -253.659574) (xy 118.433088 -253.659132) (xy 118.459743 -253.659524)
			(xy 118.512457 -253.667468) (xy 118.563398 -253.68318) (xy 118.611429 -253.706309) (xy 118.655476 -253.736338)
			(xy 118.694555 -253.772597) (xy 118.727794 -253.814276) (xy 118.754449 -253.860443) (xy 118.773925 -253.910067)
			(xy 118.785788 -253.96204) (xy 118.789772 -254.0152) (xy 118.785788 -254.06836) (xy 118.773925 -254.120333)
			(xy 118.754449 -254.169957) (xy 118.727794 -254.216124) (xy 118.694555 -254.257803) (xy 118.655476 -254.294062)
			(xy 118.611429 -254.324091) (xy 118.563398 -254.34722) (xy 118.512457 -254.362932) (xy 118.459743 -254.370876)
			(xy 118.433088 -254.371348) (xy 118.407153 -254.370877) (xy 118.355832 -254.363359) (xy 118.306141 -254.348484)
			(xy 118.259131 -254.326567) (xy 118.215792 -254.298068) (xy 118.196106 -254.281178) (xy 118.184712 -254.27169)
			(xy 118.157864 -254.259141) (xy 118.128542 -254.254837) (xy 118.09922 -254.259141) (xy 118.072372 -254.27169)
			(xy 118.060978 -254.281178) (xy 118.041282 -254.298061) (xy 117.997963 -254.326596) (xy 117.950957 -254.348533)
			(xy 117.901262 -254.363406) (xy 117.849933 -254.3709) (xy 117.823996 -254.371348) (xy 117.79735 -254.37077)
			(xy 117.744653 -254.362826) (xy 117.693729 -254.347118) (xy 117.645714 -254.323995) (xy 117.601682 -254.293974)
			(xy 117.562617 -254.257726) (xy 117.52939 -254.21606) (xy 117.502744 -254.169908) (xy 117.483274 -254.120299)
			(xy 117.471416 -254.068343) (xy 117.467433 -254.0152) (xy 113.972724 -254.0152) (xy 113.961905 -254.050273)
			(xy 113.938779 -254.098294) (xy 113.908755 -254.142331) (xy 113.872503 -254.181402) (xy 113.830832 -254.214633)
			(xy 113.784674 -254.241282) (xy 113.73506 -254.260754) (xy 113.683098 -254.272614) (xy 113.629948 -254.276598)
			(xy 113.576798 -254.272614) (xy 113.524836 -254.260754) (xy 113.475222 -254.241282) (xy 113.429064 -254.214633)
			(xy 113.387393 -254.181402) (xy 113.351141 -254.142331) (xy 113.321117 -254.098294) (xy 113.297991 -254.050273)
			(xy 113.282281 -253.999343) (xy 113.274338 -253.946639) (xy 106.413191 -253.946639) (xy 106.416708 -253.962048)
			(xy 106.420692 -254.0152) (xy 106.416708 -254.068352) (xy 106.404847 -254.120316) (xy 106.385372 -254.169932)
			(xy 106.358719 -254.216091) (xy 106.325484 -254.257762) (xy 106.286409 -254.294013) (xy 106.242367 -254.324034)
			(xy 106.194342 -254.347156) (xy 106.143407 -254.362861) (xy 106.090701 -254.370798) (xy 106.06405 -254.371348)
			(xy 106.038208 -254.37089) (xy 105.987066 -254.363422) (xy 105.937542 -254.348636) (xy 105.890677 -254.326844)
			(xy 105.847457 -254.298503) (xy 105.82783 -254.281686) (xy 105.816452 -254.272296) (xy 105.7897 -254.259893)
			(xy 105.76052 -254.255641) (xy 105.73134 -254.259893) (xy 105.704588 -254.272296) (xy 105.69321 -254.281686)
			(xy 105.673568 -254.298482) (xy 105.630346 -254.326816) (xy 105.583485 -254.348606) (xy 105.533966 -254.363397)
			(xy 105.48283 -254.370878) (xy 105.45699 -254.371348) (xy 105.432352 -254.370586) (xy 105.418434 -254.370036)
			(xy 105.391163 -254.375653) (xy 105.366423 -254.38843) (xy 105.346056 -254.407416) (xy 105.331576 -254.431199)
			(xy 105.324061 -254.45801) (xy 105.32364 -254.471932) (xy 105.32364 -254.760455) (xy 109.985038 -254.760455)
			(xy 109.985038 -254.707157) (xy 109.992981 -254.654453) (xy 110.008691 -254.603523) (xy 110.031817 -254.555502)
			(xy 110.061841 -254.511465) (xy 110.098093 -254.472394) (xy 110.139764 -254.439163) (xy 110.185922 -254.412514)
			(xy 110.235536 -254.393042) (xy 110.287498 -254.381182) (xy 110.340648 -254.377199) (xy 110.393798 -254.381182)
			(xy 110.44576 -254.393042) (xy 110.495374 -254.412514) (xy 110.541532 -254.439163) (xy 110.583203 -254.472394)
			(xy 110.619455 -254.511465) (xy 110.649479 -254.555502) (xy 110.672605 -254.603523) (xy 110.688315 -254.654453)
			(xy 110.696258 -254.707157) (xy 110.696756 -254.733806) (xy 110.696258 -254.760455) (xy 110.688315 -254.813159)
			(xy 110.672605 -254.864089) (xy 110.649479 -254.91211) (xy 110.619455 -254.956147) (xy 110.583203 -254.995218)
			(xy 110.541532 -255.028449) (xy 110.495374 -255.055098) (xy 110.44576 -255.07457) (xy 110.393798 -255.08643)
			(xy 110.340648 -255.090414) (xy 110.287498 -255.08643) (xy 110.235536 -255.07457) (xy 110.185922 -255.055098)
			(xy 110.139764 -255.028449) (xy 110.098093 -254.995218) (xy 110.061841 -254.956147) (xy 110.031817 -254.91211)
			(xy 110.008691 -254.864089) (xy 109.992981 -254.813159) (xy 109.985038 -254.760455) (xy 105.32364 -254.760455)
			(xy 105.32364 -255.949958) (xy 105.64622 -256.272538) (xy 105.64622 -256.33045) (xy 108.077762 -256.33045)
			(xy 108.078191 -256.305781) (xy 108.084991 -256.256914) (xy 108.09848 -256.209456) (xy 108.118401 -256.164319)
			(xy 108.144369 -256.122368) (xy 108.159804 -256.10312) (xy 108.168385 -256.091957) (xy 108.179742 -256.066209)
			(xy 108.183633 -256.038339) (xy 108.179763 -256.010465) (xy 108.168426 -255.984709) (xy 108.159804 -255.97358)
			(xy 108.144388 -255.954318) (xy 108.118425 -255.912367) (xy 108.098503 -255.867232) (xy 108.085004 -255.81978)
			(xy 108.078185 -255.770918) (xy 108.077762 -255.74625) (xy 108.07826 -255.719601) (xy 108.086203 -255.666897)
			(xy 108.101913 -255.615967) (xy 108.125039 -255.567946) (xy 108.155063 -255.523909) (xy 108.191315 -255.484838)
			(xy 108.232986 -255.451607) (xy 108.279144 -255.424958) (xy 108.328758 -255.405486) (xy 108.38072 -255.393626)
			(xy 108.43387 -255.389643) (xy 108.48702 -255.393626) (xy 108.538982 -255.405486) (xy 108.588596 -255.424958)
			(xy 108.634754 -255.451607) (xy 108.676425 -255.484838) (xy 108.712677 -255.523909) (xy 108.742701 -255.567946)
			(xy 108.745869 -255.574525) (xy 113.274338 -255.574525) (xy 113.274338 -255.521227) (xy 113.282281 -255.468523)
			(xy 113.297991 -255.417593) (xy 113.321117 -255.369572) (xy 113.351141 -255.325535) (xy 113.387393 -255.286464)
			(xy 113.429064 -255.253233) (xy 113.475222 -255.226584) (xy 113.524836 -255.207112) (xy 113.576798 -255.195252)
			(xy 113.629948 -255.191269) (xy 113.683098 -255.195252) (xy 113.73506 -255.207112) (xy 113.784674 -255.226584)
			(xy 113.830832 -255.253233) (xy 113.872503 -255.286464) (xy 113.908755 -255.325535) (xy 113.938779 -255.369572)
			(xy 113.961905 -255.417593) (xy 113.977615 -255.468523) (xy 113.985558 -255.521227) (xy 113.986056 -255.547876)
			(xy 113.985558 -255.574525) (xy 113.977615 -255.627229) (xy 113.961905 -255.678159) (xy 113.938779 -255.72618)
			(xy 113.908755 -255.770217) (xy 113.872503 -255.809288) (xy 113.830832 -255.842519) (xy 113.784674 -255.869168)
			(xy 113.73506 -255.88864) (xy 113.683098 -255.9005) (xy 113.629948 -255.904484) (xy 113.576798 -255.9005)
			(xy 113.524836 -255.88864) (xy 113.475222 -255.869168) (xy 113.429064 -255.842519) (xy 113.387393 -255.809288)
			(xy 113.351141 -255.770217) (xy 113.321117 -255.72618) (xy 113.297991 -255.678159) (xy 113.282281 -255.627229)
			(xy 113.274338 -255.574525) (xy 108.745869 -255.574525) (xy 108.765827 -255.615967) (xy 108.781537 -255.666897)
			(xy 108.78948 -255.719601) (xy 108.789978 -255.74625) (xy 108.78954 -255.770919) (xy 108.782741 -255.819785)
			(xy 108.769253 -255.867242) (xy 108.749335 -255.91238) (xy 108.723369 -255.954331) (xy 108.707936 -255.97358)
			(xy 108.699264 -255.984677) (xy 108.687926 -256.01045) (xy 108.684056 -256.038339) (xy 108.687947 -256.066225)
			(xy 108.699304 -256.091989) (xy 108.707936 -256.10312) (xy 108.723359 -256.122377) (xy 108.749319 -256.16433)
			(xy 108.769239 -256.209466) (xy 108.782737 -256.25692) (xy 108.789555 -256.305782) (xy 108.789978 -256.33045)
			(xy 108.78948 -256.357099) (xy 108.784772 -256.388341) (xy 109.984784 -256.388341) (xy 109.984784 -256.335043)
			(xy 109.992727 -256.282339) (xy 110.008437 -256.231409) (xy 110.031563 -256.183388) (xy 110.061587 -256.139351)
			(xy 110.097839 -256.10028) (xy 110.13951 -256.067049) (xy 110.185668 -256.0404) (xy 110.235282 -256.020928)
			(xy 110.287244 -256.009068) (xy 110.340394 -256.005085) (xy 110.393544 -256.009068) (xy 110.445506 -256.020928)
			(xy 110.49512 -256.0404) (xy 110.541278 -256.067049) (xy 110.582949 -256.10028) (xy 110.619201 -256.139351)
			(xy 110.649225 -256.183388) (xy 110.672351 -256.231409) (xy 110.688061 -256.282339) (xy 110.696004 -256.335043)
			(xy 110.696502 -256.361692) (xy 110.696004 -256.388341) (xy 110.695771 -256.389886) (xy 115.072414 -256.389886)
			(xy 115.072817 -256.365216) (xy 115.079625 -256.316349) (xy 115.093121 -256.268891) (xy 115.113046 -256.223754)
			(xy 115.139019 -256.181804) (xy 115.154456 -256.162556) (xy 115.163095 -256.151435) (xy 115.174437 -256.125671)
			(xy 115.178315 -256.097789) (xy 115.174432 -256.069908) (xy 115.163083 -256.044146) (xy 115.154456 -256.033016)
			(xy 115.139049 -256.013747) (xy 115.113086 -255.971797) (xy 115.093163 -255.926664) (xy 115.079662 -255.879213)
			(xy 115.072839 -255.830353) (xy 115.072414 -255.805686) (xy 115.072912 -255.779037) (xy 115.080855 -255.726333)
			(xy 115.096565 -255.675403) (xy 115.119691 -255.627382) (xy 115.149715 -255.583345) (xy 115.185967 -255.544274)
			(xy 115.227638 -255.511043) (xy 115.273796 -255.484394) (xy 115.32341 -255.464922) (xy 115.375372 -255.453062)
			(xy 115.428522 -255.449079) (xy 115.481672 -255.453062) (xy 115.533634 -255.464922) (xy 115.583248 -255.484394)
			(xy 115.629406 -255.511043) (xy 115.671077 -255.544274) (xy 115.707329 -255.583345) (xy 115.737353 -255.627382)
			(xy 115.760479 -255.675403) (xy 115.776189 -255.726333) (xy 115.784132 -255.779037) (xy 115.78463 -255.805686)
			(xy 115.784223 -255.830356) (xy 115.777418 -255.879224) (xy 115.763924 -255.926682) (xy 115.743999 -255.971819)
			(xy 115.718025 -256.013768) (xy 115.702588 -256.033016) (xy 115.693973 -256.044155) (xy 115.682622 -256.069911)
			(xy 115.678738 -256.097789) (xy 115.682616 -256.125668) (xy 115.693962 -256.151427) (xy 115.702588 -256.162556)
			(xy 115.718035 -256.181794) (xy 115.74399 -256.223754) (xy 115.763904 -256.268894) (xy 115.777397 -256.316351)
			(xy 115.78421 -256.365217) (xy 115.78463 -256.389886) (xy 115.784132 -256.416535) (xy 115.776189 -256.469239)
			(xy 115.760479 -256.520169) (xy 115.737353 -256.56819) (xy 115.707329 -256.612227) (xy 115.671077 -256.651298)
			(xy 115.629406 -256.684529) (xy 115.583248 -256.711178) (xy 115.533634 -256.73065) (xy 115.481672 -256.74251)
			(xy 115.428522 -256.746494) (xy 115.375372 -256.74251) (xy 115.32341 -256.73065) (xy 115.273796 -256.711178)
			(xy 115.227638 -256.684529) (xy 115.185967 -256.651298) (xy 115.149715 -256.612227) (xy 115.119691 -256.56819)
			(xy 115.096565 -256.520169) (xy 115.080855 -256.469239) (xy 115.072912 -256.416535) (xy 115.072414 -256.389886)
			(xy 110.695771 -256.389886) (xy 110.688061 -256.441045) (xy 110.672351 -256.491975) (xy 110.649225 -256.539996)
			(xy 110.619201 -256.584033) (xy 110.582949 -256.623104) (xy 110.541278 -256.656335) (xy 110.49512 -256.682984)
			(xy 110.445506 -256.702456) (xy 110.393544 -256.714316) (xy 110.340394 -256.7183) (xy 110.287244 -256.714316)
			(xy 110.235282 -256.702456) (xy 110.185668 -256.682984) (xy 110.13951 -256.656335) (xy 110.097839 -256.623104)
			(xy 110.061587 -256.584033) (xy 110.031563 -256.539996) (xy 110.008437 -256.491975) (xy 109.992727 -256.441045)
			(xy 109.984784 -256.388341) (xy 108.784772 -256.388341) (xy 108.781537 -256.409803) (xy 108.765827 -256.460733)
			(xy 108.742701 -256.508754) (xy 108.712677 -256.552791) (xy 108.676425 -256.591862) (xy 108.634754 -256.625093)
			(xy 108.588596 -256.651742) (xy 108.538982 -256.671214) (xy 108.48702 -256.683074) (xy 108.43387 -256.687058)
			(xy 108.38072 -256.683074) (xy 108.328758 -256.671214) (xy 108.279144 -256.651742) (xy 108.232986 -256.625093)
			(xy 108.191315 -256.591862) (xy 108.155063 -256.552791) (xy 108.125039 -256.508754) (xy 108.101913 -256.460733)
			(xy 108.086203 -256.409803) (xy 108.07826 -256.357099) (xy 108.077762 -256.33045) (xy 105.64622 -256.33045)
			(xy 105.64622 -257.202157) (xy 113.274338 -257.202157) (xy 113.274338 -257.148859) (xy 113.282281 -257.096155)
			(xy 113.297991 -257.045225) (xy 113.321117 -256.997204) (xy 113.351141 -256.953167) (xy 113.387393 -256.914096)
			(xy 113.429064 -256.880865) (xy 113.475222 -256.854216) (xy 113.524836 -256.834744) (xy 113.576798 -256.822884)
			(xy 113.629948 -256.818901) (xy 113.683098 -256.822884) (xy 113.73506 -256.834744) (xy 113.784674 -256.854216)
			(xy 113.830832 -256.880865) (xy 113.872503 -256.914096) (xy 113.908755 -256.953167) (xy 113.938779 -256.997204)
			(xy 113.961905 -257.045225) (xy 113.977615 -257.096155) (xy 113.985558 -257.148859) (xy 113.986056 -257.175508)
			(xy 113.985558 -257.202157) (xy 113.977615 -257.254861) (xy 113.961905 -257.305791) (xy 113.938779 -257.353812)
			(xy 113.908755 -257.397849) (xy 113.872503 -257.43692) (xy 113.830832 -257.470151) (xy 113.784674 -257.4968)
			(xy 113.73506 -257.516272) (xy 113.683098 -257.528132) (xy 113.629948 -257.532116) (xy 113.576798 -257.528132)
			(xy 113.524836 -257.516272) (xy 113.475222 -257.4968) (xy 113.429064 -257.470151) (xy 113.387393 -257.43692)
			(xy 113.351141 -257.397849) (xy 113.321117 -257.353812) (xy 113.297991 -257.305791) (xy 113.282281 -257.254861)
			(xy 113.274338 -257.202157) (xy 105.64622 -257.202157) (xy 105.64622 -257.391408) (xy 105.658594 -257.399369)
			(xy 105.682119 -257.417045) (xy 105.69321 -257.426714) (xy 105.704588 -257.436104) (xy 105.73134 -257.448507)
			(xy 105.76052 -257.452759) (xy 105.7897 -257.448507) (xy 105.816452 -257.436104) (xy 105.82783 -257.426714)
			(xy 105.847471 -257.409915) (xy 105.890691 -257.381574) (xy 105.937552 -257.359775) (xy 105.987071 -257.344976)
			(xy 106.038209 -257.337487) (xy 106.06405 -257.337052) (xy 106.090707 -257.337522) (xy 106.143425 -257.345461)
			(xy 106.194371 -257.361169) (xy 106.242407 -257.384296) (xy 106.286459 -257.414325) (xy 106.325543 -257.450584)
			(xy 106.358785 -257.492264) (xy 106.385444 -257.538433) (xy 106.404923 -257.58806) (xy 106.416788 -257.640036)
			(xy 106.420772 -257.6932) (xy 106.416788 -257.746364) (xy 106.404923 -257.79834) (xy 106.385444 -257.847967)
			(xy 106.358785 -257.894136) (xy 106.325543 -257.935816) (xy 106.286459 -257.972075) (xy 106.242407 -258.002104)
			(xy 106.2136 -258.015973) (xy 109.985038 -258.015973) (xy 109.985038 -257.962675) (xy 109.992981 -257.909971)
			(xy 110.008691 -257.859041) (xy 110.031817 -257.81102) (xy 110.061841 -257.766983) (xy 110.098093 -257.727912)
			(xy 110.139764 -257.694681) (xy 110.185922 -257.668032) (xy 110.235536 -257.64856) (xy 110.287498 -257.6367)
			(xy 110.340648 -257.632717) (xy 110.393798 -257.6367) (xy 110.44576 -257.64856) (xy 110.495374 -257.668032)
			(xy 110.541532 -257.694681) (xy 110.583203 -257.727912) (xy 110.619455 -257.766983) (xy 110.649479 -257.81102)
			(xy 110.672605 -257.859041) (xy 110.688315 -257.909971) (xy 110.696258 -257.962675) (xy 110.696756 -257.989324)
			(xy 110.696258 -258.015973) (xy 110.688315 -258.068677) (xy 110.672605 -258.119607) (xy 110.649479 -258.167628)
			(xy 110.619455 -258.211665) (xy 110.583203 -258.250736) (xy 110.541532 -258.283967) (xy 110.495374 -258.310616)
			(xy 110.44576 -258.330088) (xy 110.393798 -258.341948) (xy 110.340648 -258.345932) (xy 110.287498 -258.341948)
			(xy 110.235536 -258.330088) (xy 110.185922 -258.310616) (xy 110.139764 -258.283967) (xy 110.098093 -258.250736)
			(xy 110.061841 -258.211665) (xy 110.031817 -258.167628) (xy 110.008691 -258.119607) (xy 109.992981 -258.068677)
			(xy 109.985038 -258.015973) (xy 106.2136 -258.015973) (xy 106.194371 -258.025231) (xy 106.143425 -258.040939)
			(xy 106.090707 -258.048878) (xy 106.06405 -258.049268) (xy 106.038208 -258.048809) (xy 105.987068 -258.04134)
			(xy 105.937546 -258.026552) (xy 105.890684 -258.004756) (xy 105.847467 -257.97641) (xy 105.82783 -257.959606)
			(xy 105.816452 -257.950216) (xy 105.7897 -257.937813) (xy 105.76052 -257.933561) (xy 105.73134 -257.937813)
			(xy 105.704588 -257.950216) (xy 105.69321 -257.959606) (xy 105.682114 -257.969269) (xy 105.658588 -257.986942)
			(xy 105.64622 -257.994912) (xy 105.64622 -259.438902) (xy 105.78592 -259.578602) (xy 108.077762 -259.578602)
			(xy 108.078164 -259.553932) (xy 108.08497 -259.505064) (xy 108.098466 -259.457606) (xy 108.118392 -259.412469)
			(xy 108.144367 -259.370519) (xy 108.159804 -259.351272) (xy 108.168431 -259.340142) (xy 108.179782 -259.314382)
			(xy 108.183664 -259.286502) (xy 108.179782 -259.258621) (xy 108.168433 -259.232861) (xy 108.159804 -259.221732)
			(xy 108.144365 -259.202487) (xy 108.118406 -259.160531) (xy 108.098489 -259.115392) (xy 108.084995 -259.067936)
			(xy 108.078182 -259.019071) (xy 108.077762 -258.994402) (xy 108.07826 -258.967753) (xy 108.086203 -258.915049)
			(xy 108.101913 -258.864119) (xy 108.125039 -258.816098) (xy 108.155063 -258.772061) (xy 108.191315 -258.73299)
			(xy 108.232986 -258.699759) (xy 108.279144 -258.67311) (xy 108.328758 -258.653638) (xy 108.38072 -258.641778)
			(xy 108.43387 -258.637795) (xy 108.48702 -258.641778) (xy 108.538982 -258.653638) (xy 108.588596 -258.67311)
			(xy 108.634754 -258.699759) (xy 108.676425 -258.73299) (xy 108.712677 -258.772061) (xy 108.742701 -258.816098)
			(xy 108.749417 -258.830043) (xy 113.274338 -258.830043) (xy 113.274338 -258.776745) (xy 113.282281 -258.724041)
			(xy 113.297991 -258.673111) (xy 113.321117 -258.62509) (xy 113.351141 -258.581053) (xy 113.387393 -258.541982)
			(xy 113.429064 -258.508751) (xy 113.475222 -258.482102) (xy 113.524836 -258.46263) (xy 113.576798 -258.45077)
			(xy 113.629948 -258.446787) (xy 113.683098 -258.45077) (xy 113.73506 -258.46263) (xy 113.784674 -258.482102)
			(xy 113.830832 -258.508751) (xy 113.872503 -258.541982) (xy 113.908755 -258.581053) (xy 113.938779 -258.62509)
			(xy 113.961905 -258.673111) (xy 113.977615 -258.724041) (xy 113.985558 -258.776745) (xy 113.986056 -258.803394)
			(xy 113.985558 -258.830043) (xy 113.977615 -258.882747) (xy 113.961905 -258.933677) (xy 113.938779 -258.981698)
			(xy 113.908755 -259.025735) (xy 113.872503 -259.064806) (xy 113.830832 -259.098037) (xy 113.784674 -259.124686)
			(xy 113.73506 -259.144158) (xy 113.683098 -259.156018) (xy 113.629948 -259.160002) (xy 113.576798 -259.156018)
			(xy 113.524836 -259.144158) (xy 113.475222 -259.124686) (xy 113.429064 -259.098037) (xy 113.387393 -259.064806)
			(xy 113.351141 -259.025735) (xy 113.321117 -258.981698) (xy 113.297991 -258.933677) (xy 113.282281 -258.882747)
			(xy 113.274338 -258.830043) (xy 108.749417 -258.830043) (xy 108.765827 -258.864119) (xy 108.781537 -258.915049)
			(xy 108.78948 -258.967753) (xy 108.789978 -258.994402) (xy 108.78957 -259.019072) (xy 108.782764 -259.067939)
			(xy 108.769269 -259.115397) (xy 108.749344 -259.160534) (xy 108.723372 -259.202484) (xy 108.707936 -259.221732)
			(xy 108.699309 -259.232861) (xy 108.687966 -259.258622) (xy 108.684087 -259.286502) (xy 108.687967 -259.314381)
			(xy 108.699311 -259.340141) (xy 108.707936 -259.351272) (xy 108.723383 -259.370511) (xy 108.749339 -259.412469)
			(xy 108.769255 -259.457609) (xy 108.782747 -259.505067) (xy 108.789559 -259.553933) (xy 108.789978 -259.578602)
			(xy 108.78948 -259.605251) (xy 108.783661 -259.643859) (xy 109.984784 -259.643859) (xy 109.984784 -259.590561)
			(xy 109.992727 -259.537857) (xy 110.008437 -259.486927) (xy 110.031563 -259.438906) (xy 110.061587 -259.394869)
			(xy 110.097839 -259.355798) (xy 110.13951 -259.322567) (xy 110.185668 -259.295918) (xy 110.235282 -259.276446)
			(xy 110.287244 -259.264586) (xy 110.340394 -259.260603) (xy 110.393544 -259.264586) (xy 110.445506 -259.276446)
			(xy 110.49512 -259.295918) (xy 110.541278 -259.322567) (xy 110.582949 -259.355798) (xy 110.619201 -259.394869)
			(xy 110.649225 -259.438906) (xy 110.672351 -259.486927) (xy 110.688061 -259.537857) (xy 110.696004 -259.590561)
			(xy 110.696502 -259.61721) (xy 110.696165 -259.635244) (xy 115.070128 -259.635244) (xy 115.070562 -259.610575)
			(xy 115.077361 -259.561709) (xy 115.09085 -259.514251) (xy 115.110769 -259.469114) (xy 115.136736 -259.427163)
			(xy 115.15217 -259.407914) (xy 115.160752 -259.396753) (xy 115.172101 -259.371004) (xy 115.175988 -259.343134)
			(xy 115.172119 -259.315262) (xy 115.160788 -259.289505) (xy 115.15217 -259.278374) (xy 115.136746 -259.259118)
			(xy 115.110786 -259.217164) (xy 115.090866 -259.172029) (xy 115.077368 -259.124575) (xy 115.070551 -259.075712)
			(xy 115.070128 -259.051044) (xy 115.070626 -259.024395) (xy 115.078569 -258.971691) (xy 115.094279 -258.920761)
			(xy 115.117405 -258.87274) (xy 115.147429 -258.828703) (xy 115.183681 -258.789632) (xy 115.225352 -258.756401)
			(xy 115.27151 -258.729752) (xy 115.321124 -258.71028) (xy 115.373086 -258.69842) (xy 115.426236 -258.694437)
			(xy 115.479386 -258.69842) (xy 115.531348 -258.71028) (xy 115.580962 -258.729752) (xy 115.62712 -258.756401)
			(xy 115.668791 -258.789632) (xy 115.705043 -258.828703) (xy 115.735067 -258.87274) (xy 115.758193 -258.920761)
			(xy 115.773903 -258.971691) (xy 115.781846 -259.024395) (xy 115.782344 -259.051044) (xy 115.78191 -259.075713)
			(xy 115.775111 -259.12458) (xy 115.761623 -259.172037) (xy 115.741704 -259.217175) (xy 115.715736 -259.259125)
			(xy 115.700302 -259.278374) (xy 115.691631 -259.289473) (xy 115.680285 -259.315244) (xy 115.676411 -259.343134)
			(xy 115.680304 -259.371022) (xy 115.691667 -259.396785) (xy 115.700302 -259.407914) (xy 115.715716 -259.427177)
			(xy 115.741679 -259.469129) (xy 115.761601 -259.514263) (xy 115.775101 -259.561715) (xy 115.78192 -259.610576)
			(xy 115.782344 -259.635244) (xy 115.781846 -259.661893) (xy 115.773903 -259.714597) (xy 115.758193 -259.765527)
			(xy 115.735067 -259.813548) (xy 115.705043 -259.857585) (xy 115.668791 -259.896656) (xy 115.62712 -259.929887)
			(xy 115.580962 -259.956536) (xy 115.531348 -259.976008) (xy 115.479386 -259.987868) (xy 115.426236 -259.991852)
			(xy 115.373086 -259.987868) (xy 115.321124 -259.976008) (xy 115.27151 -259.956536) (xy 115.225352 -259.929887)
			(xy 115.183681 -259.896656) (xy 115.147429 -259.857585) (xy 115.117405 -259.813548) (xy 115.094279 -259.765527)
			(xy 115.078569 -259.714597) (xy 115.070626 -259.661893) (xy 115.070128 -259.635244) (xy 110.696165 -259.635244)
			(xy 110.696004 -259.643859) (xy 110.688061 -259.696563) (xy 110.672351 -259.747493) (xy 110.649225 -259.795514)
			(xy 110.619201 -259.839551) (xy 110.582949 -259.878622) (xy 110.541278 -259.911853) (xy 110.49512 -259.938502)
			(xy 110.445506 -259.957974) (xy 110.393544 -259.969834) (xy 110.340394 -259.973818) (xy 110.287244 -259.969834)
			(xy 110.235282 -259.957974) (xy 110.185668 -259.938502) (xy 110.13951 -259.911853) (xy 110.097839 -259.878622)
			(xy 110.061587 -259.839551) (xy 110.031563 -259.795514) (xy 110.008437 -259.747493) (xy 109.992727 -259.696563)
			(xy 109.984784 -259.643859) (xy 108.783661 -259.643859) (xy 108.781537 -259.657955) (xy 108.765827 -259.708885)
			(xy 108.742701 -259.756906) (xy 108.712677 -259.800943) (xy 108.676425 -259.840014) (xy 108.634754 -259.873245)
			(xy 108.588596 -259.899894) (xy 108.538982 -259.919366) (xy 108.48702 -259.931226) (xy 108.43387 -259.93521)
			(xy 108.38072 -259.931226) (xy 108.328758 -259.919366) (xy 108.279144 -259.899894) (xy 108.232986 -259.873245)
			(xy 108.191315 -259.840014) (xy 108.155063 -259.800943) (xy 108.125039 -259.756906) (xy 108.101913 -259.708885)
			(xy 108.086203 -259.657955) (xy 108.07826 -259.605251) (xy 108.077762 -259.578602) (xy 105.78592 -259.578602)
			(xy 106.090466 -259.883148) (xy 106.877866 -259.883148) (xy 107.452393 -260.457675) (xy 113.274338 -260.457675)
			(xy 113.274338 -260.404377) (xy 113.282281 -260.351673) (xy 113.297991 -260.300743) (xy 113.321117 -260.252722)
			(xy 113.351141 -260.208685) (xy 113.387393 -260.169614) (xy 113.429064 -260.136383) (xy 113.475222 -260.109734)
			(xy 113.524836 -260.090262) (xy 113.576798 -260.078402) (xy 113.629948 -260.074419) (xy 113.683098 -260.078402)
			(xy 113.73506 -260.090262) (xy 113.784674 -260.109734) (xy 113.830832 -260.136383) (xy 113.872503 -260.169614)
			(xy 113.908755 -260.208685) (xy 113.938779 -260.252722) (xy 113.961905 -260.300743) (xy 113.977615 -260.351673)
			(xy 113.985558 -260.404377) (xy 113.986056 -260.431026) (xy 113.985558 -260.457675) (xy 113.977615 -260.510379)
			(xy 113.961905 -260.561309) (xy 113.938779 -260.60933) (xy 113.908755 -260.653367) (xy 113.872503 -260.692438)
			(xy 113.830832 -260.725669) (xy 113.784674 -260.752318) (xy 113.73506 -260.77179) (xy 113.683098 -260.78365)
			(xy 113.629948 -260.787634) (xy 113.576798 -260.78365) (xy 113.524836 -260.77179) (xy 113.475222 -260.752318)
			(xy 113.429064 -260.725669) (xy 113.387393 -260.692438) (xy 113.351141 -260.653367) (xy 113.321117 -260.60933)
			(xy 113.297991 -260.561309) (xy 113.282281 -260.510379) (xy 113.274338 -260.457675) (xy 107.452393 -260.457675)
			(xy 107.792266 -260.797548) (xy 107.792266 -261.271745) (xy 109.984784 -261.271745) (xy 109.984784 -261.218447)
			(xy 109.992727 -261.165743) (xy 110.008437 -261.114813) (xy 110.031563 -261.066792) (xy 110.061587 -261.022755)
			(xy 110.097839 -260.983684) (xy 110.13951 -260.950453) (xy 110.185668 -260.923804) (xy 110.235282 -260.904332)
			(xy 110.287244 -260.892472) (xy 110.340394 -260.888489) (xy 110.393544 -260.892472) (xy 110.445506 -260.904332)
			(xy 110.49512 -260.923804) (xy 110.541278 -260.950453) (xy 110.582949 -260.983684) (xy 110.619201 -261.022755)
			(xy 110.649225 -261.066792) (xy 110.672351 -261.114813) (xy 110.688061 -261.165743) (xy 110.696004 -261.218447)
			(xy 110.696502 -261.245096) (xy 110.696004 -261.271745) (xy 110.688061 -261.324449) (xy 110.672351 -261.375379)
			(xy 110.649225 -261.4234) (xy 110.619201 -261.467437) (xy 110.582949 -261.506508) (xy 110.541278 -261.539739)
			(xy 110.49512 -261.566388) (xy 110.445506 -261.58586) (xy 110.393544 -261.59772) (xy 110.340394 -261.601704)
			(xy 110.287244 -261.59772) (xy 110.235282 -261.58586) (xy 110.185668 -261.566388) (xy 110.13951 -261.539739)
			(xy 110.097839 -261.506508) (xy 110.061587 -261.467437) (xy 110.031563 -261.4234) (xy 110.008437 -261.375379)
			(xy 109.992727 -261.324449) (xy 109.984784 -261.271745) (xy 107.792266 -261.271745) (xy 107.792266 -261.661148)
			(xy 107.367853 -262.085561) (xy 113.274338 -262.085561) (xy 113.274338 -262.032263) (xy 113.282281 -261.979559)
			(xy 113.297991 -261.928629) (xy 113.321117 -261.880608) (xy 113.351141 -261.836571) (xy 113.387393 -261.7975)
			(xy 113.429064 -261.764269) (xy 113.475222 -261.73762) (xy 113.524836 -261.718148) (xy 113.576798 -261.706288)
			(xy 113.629948 -261.702305) (xy 113.683098 -261.706288) (xy 113.73506 -261.718148) (xy 113.784674 -261.73762)
			(xy 113.830832 -261.764269) (xy 113.872503 -261.7975) (xy 113.908755 -261.836571) (xy 113.938779 -261.880608)
			(xy 113.961905 -261.928629) (xy 113.977615 -261.979559) (xy 113.985558 -262.032263) (xy 113.986056 -262.058912)
			(xy 113.985558 -262.085561) (xy 113.977615 -262.138265) (xy 113.961905 -262.189195) (xy 113.938779 -262.237216)
			(xy 113.908755 -262.281253) (xy 113.872503 -262.320324) (xy 113.830832 -262.353555) (xy 113.784674 -262.380204)
			(xy 113.73506 -262.399676) (xy 113.683098 -262.411536) (xy 113.629948 -262.41552) (xy 113.576798 -262.411536)
			(xy 113.524836 -262.399676) (xy 113.475222 -262.380204) (xy 113.429064 -262.353555) (xy 113.387393 -262.320324)
			(xy 113.351141 -262.281253) (xy 113.321117 -262.237216) (xy 113.297991 -262.189195) (xy 113.282281 -262.138265)
			(xy 113.274338 -262.085561) (xy 107.367853 -262.085561) (xy 106.903266 -262.550148) (xy 106.903266 -262.899377)
			(xy 109.985038 -262.899377) (xy 109.985038 -262.846079) (xy 109.992981 -262.793375) (xy 110.008691 -262.742445)
			(xy 110.031817 -262.694424) (xy 110.061841 -262.650387) (xy 110.098093 -262.611316) (xy 110.139764 -262.578085)
			(xy 110.185922 -262.551436) (xy 110.235536 -262.531964) (xy 110.287498 -262.520104) (xy 110.340648 -262.516121)
			(xy 110.393798 -262.520104) (xy 110.44576 -262.531964) (xy 110.495374 -262.551436) (xy 110.541532 -262.578085)
			(xy 110.583203 -262.611316) (xy 110.619455 -262.650387) (xy 110.649479 -262.694424) (xy 110.672605 -262.742445)
			(xy 110.688315 -262.793375) (xy 110.696258 -262.846079) (xy 110.696756 -262.872728) (xy 110.696258 -262.899377)
			(xy 110.688315 -262.952081) (xy 110.672605 -263.003011) (xy 110.649479 -263.051032) (xy 110.619455 -263.095069)
			(xy 110.583203 -263.13414) (xy 110.541532 -263.167371) (xy 110.495374 -263.19402) (xy 110.44576 -263.213492)
			(xy 110.393798 -263.225352) (xy 110.340648 -263.229336) (xy 110.287498 -263.225352) (xy 110.235536 -263.213492)
			(xy 110.185922 -263.19402) (xy 110.139764 -263.167371) (xy 110.098093 -263.13414) (xy 110.061841 -263.095069)
			(xy 110.031817 -263.051032) (xy 110.008691 -263.003011) (xy 109.992981 -262.952081) (xy 109.985038 -262.899377)
			(xy 106.903266 -262.899377) (xy 106.903266 -263.713193) (xy 113.27383 -263.713193) (xy 113.27383 -263.659895)
			(xy 113.281773 -263.607191) (xy 113.297483 -263.556261) (xy 113.320609 -263.50824) (xy 113.350633 -263.464203)
			(xy 113.386885 -263.425132) (xy 113.428556 -263.391901) (xy 113.474714 -263.365252) (xy 113.524328 -263.34578)
			(xy 113.57629 -263.33392) (xy 113.62944 -263.329937) (xy 113.68259 -263.33392) (xy 113.734552 -263.34578)
			(xy 113.784166 -263.365252) (xy 113.830324 -263.391901) (xy 113.871995 -263.425132) (xy 113.908247 -263.464203)
			(xy 113.938271 -263.50824) (xy 113.961397 -263.556261) (xy 113.977107 -263.607191) (xy 113.98505 -263.659895)
			(xy 113.985548 -263.686544) (xy 113.98505 -263.713193) (xy 113.977107 -263.765897) (xy 113.961397 -263.816827)
			(xy 113.938271 -263.864848) (xy 113.908247 -263.908885) (xy 113.871995 -263.947956) (xy 113.830324 -263.981187)
			(xy 113.784166 -264.007836) (xy 113.734552 -264.027308) (xy 113.68259 -264.039168) (xy 113.62944 -264.043152)
			(xy 113.57629 -264.039168) (xy 113.524328 -264.027308) (xy 113.474714 -264.007836) (xy 113.428556 -263.981187)
			(xy 113.386885 -263.947956) (xy 113.350633 -263.908885) (xy 113.320609 -263.864848) (xy 113.297483 -263.816827)
			(xy 113.281773 -263.765897) (xy 113.27383 -263.713193) (xy 106.903266 -263.713193) (xy 106.903266 -263.743948)
			(xy 107.347004 -264.187686) (xy 107.378754 -264.17397) (xy 107.401317 -264.16456) (xy 107.448376 -264.15132)
			(xy 107.496805 -264.144655) (xy 107.521248 -264.144252) (xy 107.54923 -264.144805) (xy 107.604504 -264.153565)
			(xy 107.657727 -264.170864) (xy 107.707589 -264.196274) (xy 107.752864 -264.22917) (xy 107.792435 -264.268743)
			(xy 107.825331 -264.314018) (xy 107.85074 -264.363881) (xy 107.868037 -264.417104) (xy 107.876796 -264.472378)
			(xy 107.877356 -264.50036) (xy 107.87695 -264.524802) (xy 107.876646 -264.527009) (xy 108.105438 -264.527009)
			(xy 108.105438 -264.473711) (xy 108.113381 -264.421007) (xy 108.129091 -264.370077) (xy 108.152217 -264.322056)
			(xy 108.182241 -264.278019) (xy 108.218493 -264.238948) (xy 108.260164 -264.205717) (xy 108.306322 -264.179068)
			(xy 108.355936 -264.159596) (xy 108.407898 -264.147736) (xy 108.461048 -264.143753) (xy 108.514198 -264.147736)
			(xy 108.56616 -264.159596) (xy 108.615774 -264.179068) (xy 108.661932 -264.205717) (xy 108.703603 -264.238948)
			(xy 108.739855 -264.278019) (xy 108.769879 -264.322056) (xy 108.793005 -264.370077) (xy 108.808715 -264.421007)
			(xy 108.816658 -264.473711) (xy 108.817156 -264.50036) (xy 108.816658 -264.527009) (xy 108.808715 -264.579713)
			(xy 108.793005 -264.630643) (xy 108.769879 -264.678664) (xy 108.739855 -264.722701) (xy 108.703603 -264.761772)
			(xy 108.661932 -264.795003) (xy 108.615774 -264.821652) (xy 108.56616 -264.841124) (xy 108.514198 -264.852984)
			(xy 108.461048 -264.856968) (xy 108.407898 -264.852984) (xy 108.355936 -264.841124) (xy 108.306322 -264.821652)
			(xy 108.260164 -264.795003) (xy 108.218493 -264.761772) (xy 108.182241 -264.722701) (xy 108.152217 -264.678664)
			(xy 108.129091 -264.630643) (xy 108.113381 -264.579713) (xy 108.105438 -264.527009) (xy 107.876646 -264.527009)
			(xy 107.870269 -264.573228) (xy 107.857041 -264.620289) (xy 107.847638 -264.642854) (xy 107.833922 -264.674604)
			(xy 108.159804 -265.000486) (xy 108.181752 -265.01278) (xy 108.222269 -265.042597) (xy 108.258196 -265.077809)
			(xy 108.28882 -265.117718) (xy 108.301536 -265.139424) (xy 108.304838 -265.14552) (xy 108.376466 -265.217148)
			(xy 108.376466 -265.340825) (xy 108.575338 -265.340825) (xy 108.575338 -265.287527) (xy 108.583281 -265.234823)
			(xy 108.598991 -265.183893) (xy 108.622117 -265.135872) (xy 108.652141 -265.091835) (xy 108.688393 -265.052764)
			(xy 108.730064 -265.019533) (xy 108.776222 -264.992884) (xy 108.825836 -264.973412) (xy 108.877798 -264.961552)
			(xy 108.930948 -264.957569) (xy 108.984098 -264.961552) (xy 109.03606 -264.973412) (xy 109.085674 -264.992884)
			(xy 109.131832 -265.019533) (xy 109.173503 -265.052764) (xy 109.209755 -265.091835) (xy 109.239779 -265.135872)
			(xy 109.262905 -265.183893) (xy 109.278615 -265.234823) (xy 109.286558 -265.287527) (xy 109.287056 -265.314176)
			(xy 109.286558 -265.340825) (xy 109.278615 -265.393529) (xy 109.262905 -265.444459) (xy 109.239779 -265.49248)
			(xy 109.209755 -265.536517) (xy 109.173503 -265.575588) (xy 109.131832 -265.608819) (xy 109.085674 -265.635468)
			(xy 109.03606 -265.65494) (xy 108.984098 -265.6668) (xy 108.930948 -265.670784) (xy 108.877798 -265.6668)
			(xy 108.825836 -265.65494) (xy 108.776222 -265.635468) (xy 108.730064 -265.608819) (xy 108.688393 -265.575588)
			(xy 108.652141 -265.536517) (xy 108.622117 -265.49248) (xy 108.598991 -265.444459) (xy 108.583281 -265.393529)
			(xy 108.575338 -265.340825) (xy 108.376466 -265.340825) (xy 108.376466 -265.670792) (xy 108.377044 -265.686404)
			(xy 108.386484 -265.716168) (xy 108.404458 -265.741702) (xy 108.429293 -265.760629) (xy 108.458678 -265.771189)
			(xy 108.474256 -265.772392) (xy 108.501525 -265.77392) (xy 108.555146 -265.784294) (xy 108.606555 -265.802734)
			(xy 108.654544 -265.828807) (xy 108.697989 -265.861903) (xy 108.735871 -265.901245) (xy 108.767301 -265.94591)
			(xy 108.791543 -265.994851) (xy 108.808026 -266.046919) (xy 108.816366 -266.100894) (xy 108.816366 -266.154895)
			(xy 109.045238 -266.154895) (xy 109.045238 -266.101597) (xy 109.053181 -266.048893) (xy 109.068891 -265.997963)
			(xy 109.092017 -265.949942) (xy 109.122041 -265.905905) (xy 109.158293 -265.866834) (xy 109.199964 -265.833603)
			(xy 109.246122 -265.806954) (xy 109.295736 -265.787482) (xy 109.347698 -265.775622) (xy 109.400848 -265.771639)
			(xy 109.453998 -265.775622) (xy 109.50596 -265.787482) (xy 109.555574 -265.806954) (xy 109.601732 -265.833603)
			(xy 109.643403 -265.866834) (xy 109.679655 -265.905905) (xy 109.709679 -265.949942) (xy 109.732805 -265.997963)
			(xy 109.748515 -266.048893) (xy 109.756458 -266.101597) (xy 109.756956 -266.128246) (xy 109.756458 -266.154895)
			(xy 109.748515 -266.207599) (xy 109.732805 -266.258529) (xy 109.709679 -266.30655) (xy 109.679655 -266.350587)
			(xy 109.643403 -266.389658) (xy 109.601732 -266.422889) (xy 109.555574 -266.449538) (xy 109.50596 -266.46901)
			(xy 109.453998 -266.48087) (xy 109.400848 -266.484854) (xy 109.347698 -266.48087) (xy 109.295736 -266.46901)
			(xy 109.246122 -266.449538) (xy 109.199964 -266.422889) (xy 109.158293 -266.389658) (xy 109.122041 -266.350587)
			(xy 109.092017 -266.30655) (xy 109.068891 -266.258529) (xy 109.053181 -266.207599) (xy 109.045238 -266.154895)
			(xy 108.816366 -266.154895) (xy 108.816366 -266.155509) (xy 108.808026 -266.209484) (xy 108.791541 -266.261552)
			(xy 108.7673 -266.310493) (xy 108.735869 -266.355158) (xy 108.697987 -266.394499) (xy 108.654541 -266.427595)
			(xy 108.606551 -266.453668) (xy 108.555143 -266.472107) (xy 108.501522 -266.48248) (xy 108.474256 -266.4841)
			(xy 108.458662 -266.485244) (xy 108.42924 -266.495779) (xy 108.404377 -266.514713) (xy 108.386398 -266.540274)
			(xy 108.376984 -266.570074) (xy 108.376466 -266.5857) (xy 108.376466 -266.968457) (xy 108.575338 -266.968457)
			(xy 108.575338 -266.915159) (xy 108.583281 -266.862455) (xy 108.598991 -266.811525) (xy 108.622117 -266.763504)
			(xy 108.652141 -266.719467) (xy 108.688393 -266.680396) (xy 108.730064 -266.647165) (xy 108.776222 -266.620516)
			(xy 108.825836 -266.601044) (xy 108.877798 -266.589184) (xy 108.930948 -266.585201) (xy 108.984098 -266.589184)
			(xy 109.03606 -266.601044) (xy 109.085674 -266.620516) (xy 109.131832 -266.647165) (xy 109.173503 -266.680396)
			(xy 109.209755 -266.719467) (xy 109.239779 -266.763504) (xy 109.262905 -266.811525) (xy 109.278615 -266.862455)
			(xy 109.286558 -266.915159) (xy 109.287056 -266.941808) (xy 109.286558 -266.968457) (xy 109.514884 -266.968457)
			(xy 109.514884 -266.915159) (xy 109.522827 -266.862455) (xy 109.538537 -266.811525) (xy 109.561663 -266.763504)
			(xy 109.591687 -266.719467) (xy 109.627939 -266.680396) (xy 109.66961 -266.647165) (xy 109.715768 -266.620516)
			(xy 109.765382 -266.601044) (xy 109.817344 -266.589184) (xy 109.870494 -266.585201) (xy 109.923644 -266.589184)
			(xy 109.975606 -266.601044) (xy 110.02522 -266.620516) (xy 110.071378 -266.647165) (xy 110.113049 -266.680396)
			(xy 110.149301 -266.719467) (xy 110.179325 -266.763504) (xy 110.202451 -266.811525) (xy 110.218161 -266.862455)
			(xy 110.226104 -266.915159) (xy 110.226602 -266.941808) (xy 110.226104 -266.968457) (xy 110.218161 -267.021161)
			(xy 110.202451 -267.072091) (xy 110.179325 -267.120112) (xy 110.149301 -267.164149) (xy 110.113049 -267.20322)
			(xy 110.071378 -267.236451) (xy 110.02522 -267.2631) (xy 109.975606 -267.282572) (xy 109.923644 -267.294432)
			(xy 109.870494 -267.298416) (xy 109.817344 -267.294432) (xy 109.765382 -267.282572) (xy 109.715768 -267.2631)
			(xy 109.66961 -267.236451) (xy 109.627939 -267.20322) (xy 109.591687 -267.164149) (xy 109.561663 -267.120112)
			(xy 109.538537 -267.072091) (xy 109.522827 -267.021161) (xy 109.514884 -266.968457) (xy 109.286558 -266.968457)
			(xy 109.278615 -267.021161) (xy 109.262905 -267.072091) (xy 109.239779 -267.120112) (xy 109.209755 -267.164149)
			(xy 109.173503 -267.20322) (xy 109.131832 -267.236451) (xy 109.085674 -267.2631) (xy 109.03606 -267.282572)
			(xy 108.984098 -267.294432) (xy 108.930948 -267.298416) (xy 108.877798 -267.294432) (xy 108.825836 -267.282572)
			(xy 108.776222 -267.2631) (xy 108.730064 -267.236451) (xy 108.688393 -267.20322) (xy 108.652141 -267.164149)
			(xy 108.622117 -267.120112) (xy 108.598991 -267.072091) (xy 108.583281 -267.021161) (xy 108.575338 -266.968457)
			(xy 108.376466 -266.968457) (xy 108.376466 -267.298424) (xy 108.377034 -267.314043) (xy 108.386462 -267.343825)
			(xy 108.404433 -267.369376) (xy 108.429273 -267.388319) (xy 108.458669 -267.398888) (xy 108.474256 -267.400024)
			(xy 108.501531 -267.401552) (xy 108.555162 -267.411928) (xy 108.60658 -267.430371) (xy 108.654579 -267.456449)
			(xy 108.698033 -267.489551) (xy 108.735922 -267.5289) (xy 108.767359 -267.573573) (xy 108.791605 -267.622523)
			(xy 108.808092 -267.674601) (xy 108.816433 -267.728586) (xy 108.816434 -267.782527) (xy 109.044984 -267.782527)
			(xy 109.044984 -267.729229) (xy 109.052927 -267.676525) (xy 109.068637 -267.625595) (xy 109.091763 -267.577574)
			(xy 109.121787 -267.533537) (xy 109.158039 -267.494466) (xy 109.19971 -267.461235) (xy 109.245868 -267.434586)
			(xy 109.295482 -267.415114) (xy 109.347444 -267.403254) (xy 109.400594 -267.399271) (xy 109.453744 -267.403254)
			(xy 109.505706 -267.415114) (xy 109.55532 -267.434586) (xy 109.601478 -267.461235) (xy 109.643149 -267.494466)
			(xy 109.679401 -267.533537) (xy 109.709425 -267.577574) (xy 109.732551 -267.625595) (xy 109.748261 -267.676525)
			(xy 109.756204 -267.729229) (xy 109.756702 -267.755878) (xy 109.756204 -267.782527) (xy 109.984784 -267.782527)
			(xy 109.984784 -267.729229) (xy 109.992727 -267.676525) (xy 110.008437 -267.625595) (xy 110.031563 -267.577574)
			(xy 110.061587 -267.533537) (xy 110.097839 -267.494466) (xy 110.13951 -267.461235) (xy 110.185668 -267.434586)
			(xy 110.235282 -267.415114) (xy 110.287244 -267.403254) (xy 110.340394 -267.399271) (xy 110.393544 -267.403254)
			(xy 110.445506 -267.415114) (xy 110.49512 -267.434586) (xy 110.541278 -267.461235) (xy 110.582949 -267.494466)
			(xy 110.619201 -267.533537) (xy 110.649225 -267.577574) (xy 110.672351 -267.625595) (xy 110.688061 -267.676525)
			(xy 110.696004 -267.729229) (xy 110.696502 -267.755878) (xy 110.696004 -267.782527) (xy 110.688061 -267.835231)
			(xy 110.672351 -267.886161) (xy 110.649225 -267.934182) (xy 110.619201 -267.978219) (xy 110.582949 -268.01729)
			(xy 110.541278 -268.050521) (xy 110.49512 -268.07717) (xy 110.445506 -268.096642) (xy 110.393544 -268.108502)
			(xy 110.340394 -268.112486) (xy 110.287244 -268.108502) (xy 110.235282 -268.096642) (xy 110.185668 -268.07717)
			(xy 110.13951 -268.050521) (xy 110.097839 -268.01729) (xy 110.061587 -267.978219) (xy 110.031563 -267.934182)
			(xy 110.008437 -267.886161) (xy 109.992727 -267.835231) (xy 109.984784 -267.782527) (xy 109.756204 -267.782527)
			(xy 109.748261 -267.835231) (xy 109.732551 -267.886161) (xy 109.709425 -267.934182) (xy 109.679401 -267.978219)
			(xy 109.643149 -268.01729) (xy 109.601478 -268.050521) (xy 109.55532 -268.07717) (xy 109.505706 -268.096642)
			(xy 109.453744 -268.108502) (xy 109.400594 -268.112486) (xy 109.347444 -268.108502) (xy 109.295482 -268.096642)
			(xy 109.245868 -268.07717) (xy 109.19971 -268.050521) (xy 109.158039 -268.01729) (xy 109.121787 -267.978219)
			(xy 109.091763 -267.934182) (xy 109.068637 -267.886161) (xy 109.052927 -267.835231) (xy 109.044984 -267.782527)
			(xy 108.816434 -267.782527) (xy 108.816434 -267.783212) (xy 108.808092 -267.837197) (xy 108.791605 -267.889275)
			(xy 108.767359 -267.938225) (xy 108.735923 -267.982899) (xy 108.698034 -268.022248) (xy 108.65458 -268.05535)
			(xy 108.606582 -268.081429) (xy 108.555164 -268.099872) (xy 108.501532 -268.110247) (xy 108.474256 -268.111732)
			(xy 108.458664 -268.112876) (xy 108.429246 -268.123413) (xy 108.404389 -268.142347) (xy 108.386417 -268.167909)
			(xy 108.377011 -268.197708) (xy 108.376466 -268.213332) (xy 108.376466 -268.596343) (xy 108.575084 -268.596343)
			(xy 108.575084 -268.543045) (xy 108.583027 -268.490341) (xy 108.598737 -268.439411) (xy 108.621863 -268.39139)
			(xy 108.651887 -268.347353) (xy 108.688139 -268.308282) (xy 108.72981 -268.275051) (xy 108.775968 -268.248402)
			(xy 108.825582 -268.22893) (xy 108.877544 -268.21707) (xy 108.930694 -268.213087) (xy 108.983844 -268.21707)
			(xy 109.035806 -268.22893) (xy 109.08542 -268.248402) (xy 109.131578 -268.275051) (xy 109.173249 -268.308282)
			(xy 109.209501 -268.347353) (xy 109.239525 -268.39139) (xy 109.262651 -268.439411) (xy 109.278361 -268.490341)
			(xy 109.286304 -268.543045) (xy 109.286802 -268.569694) (xy 109.286304 -268.596343) (xy 109.514884 -268.596343)
			(xy 109.514884 -268.543045) (xy 109.522827 -268.490341) (xy 109.538537 -268.439411) (xy 109.561663 -268.39139)
			(xy 109.591687 -268.347353) (xy 109.627939 -268.308282) (xy 109.66961 -268.275051) (xy 109.715768 -268.248402)
			(xy 109.765382 -268.22893) (xy 109.817344 -268.21707) (xy 109.870494 -268.213087) (xy 109.923644 -268.21707)
			(xy 109.975606 -268.22893) (xy 110.02522 -268.248402) (xy 110.071378 -268.275051) (xy 110.113049 -268.308282)
			(xy 110.149301 -268.347353) (xy 110.179325 -268.39139) (xy 110.202451 -268.439411) (xy 110.218161 -268.490341)
			(xy 110.226104 -268.543045) (xy 110.226602 -268.569694) (xy 110.226104 -268.596343) (xy 110.218161 -268.649047)
			(xy 110.202451 -268.699977) (xy 110.179325 -268.747998) (xy 110.149301 -268.792035) (xy 110.113049 -268.831106)
			(xy 110.071378 -268.864337) (xy 110.02522 -268.890986) (xy 109.975606 -268.910458) (xy 109.923644 -268.922318)
			(xy 109.870494 -268.926302) (xy 109.817344 -268.922318) (xy 109.765382 -268.910458) (xy 109.715768 -268.890986)
			(xy 109.66961 -268.864337) (xy 109.627939 -268.831106) (xy 109.591687 -268.792035) (xy 109.561663 -268.747998)
			(xy 109.538537 -268.699977) (xy 109.522827 -268.649047) (xy 109.514884 -268.596343) (xy 109.286304 -268.596343)
			(xy 109.278361 -268.649047) (xy 109.262651 -268.699977) (xy 109.239525 -268.747998) (xy 109.209501 -268.792035)
			(xy 109.173249 -268.831106) (xy 109.131578 -268.864337) (xy 109.08542 -268.890986) (xy 109.035806 -268.910458)
			(xy 108.983844 -268.922318) (xy 108.930694 -268.926302) (xy 108.877544 -268.922318) (xy 108.825582 -268.910458)
			(xy 108.775968 -268.890986) (xy 108.72981 -268.864337) (xy 108.688139 -268.831106) (xy 108.651887 -268.792035)
			(xy 108.621863 -268.747998) (xy 108.598737 -268.699977) (xy 108.583027 -268.649047) (xy 108.575084 -268.596343)
			(xy 108.376466 -268.596343) (xy 108.376466 -268.926056) (xy 108.377039 -268.941672) (xy 108.386472 -268.971445)
			(xy 108.404445 -268.996988) (xy 108.429282 -269.015924) (xy 108.458673 -269.026488) (xy 108.474256 -269.027656)
			(xy 108.501528 -269.029184) (xy 108.555155 -269.039559) (xy 108.606568 -269.058) (xy 108.654562 -269.084076)
			(xy 108.698012 -269.117175) (xy 108.735898 -269.156521) (xy 108.767332 -269.201191) (xy 108.791576 -269.250136)
			(xy 108.808061 -269.30221) (xy 108.816402 -269.35619) (xy 108.816402 -269.410159) (xy 109.044984 -269.410159)
			(xy 109.044984 -269.356861) (xy 109.052927 -269.304157) (xy 109.068637 -269.253227) (xy 109.091763 -269.205206)
			(xy 109.121787 -269.161169) (xy 109.158039 -269.122098) (xy 109.19971 -269.088867) (xy 109.245868 -269.062218)
			(xy 109.295482 -269.042746) (xy 109.347444 -269.030886) (xy 109.400594 -269.026903) (xy 109.453744 -269.030886)
			(xy 109.505706 -269.042746) (xy 109.55532 -269.062218) (xy 109.601478 -269.088867) (xy 109.643149 -269.122098)
			(xy 109.679401 -269.161169) (xy 109.709425 -269.205206) (xy 109.732551 -269.253227) (xy 109.748261 -269.304157)
			(xy 109.756204 -269.356861) (xy 109.756702 -269.38351) (xy 109.756204 -269.410159) (xy 109.984784 -269.410159)
			(xy 109.984784 -269.356861) (xy 109.992727 -269.304157) (xy 110.008437 -269.253227) (xy 110.031563 -269.205206)
			(xy 110.061587 -269.161169) (xy 110.097839 -269.122098) (xy 110.13951 -269.088867) (xy 110.185668 -269.062218)
			(xy 110.235282 -269.042746) (xy 110.287244 -269.030886) (xy 110.340394 -269.026903) (xy 110.393544 -269.030886)
			(xy 110.445506 -269.042746) (xy 110.49512 -269.062218) (xy 110.541278 -269.088867) (xy 110.582949 -269.122098)
			(xy 110.619201 -269.161169) (xy 110.649225 -269.205206) (xy 110.672351 -269.253227) (xy 110.688061 -269.304157)
			(xy 110.696004 -269.356861) (xy 110.696502 -269.38351) (xy 110.696004 -269.410159) (xy 110.688061 -269.462863)
			(xy 110.672351 -269.513793) (xy 110.649225 -269.561814) (xy 110.619201 -269.605851) (xy 110.582949 -269.644922)
			(xy 110.541278 -269.678153) (xy 110.49512 -269.704802) (xy 110.445506 -269.724274) (xy 110.393544 -269.736134)
			(xy 110.340394 -269.740118) (xy 110.287244 -269.736134) (xy 110.235282 -269.724274) (xy 110.185668 -269.704802)
			(xy 110.13951 -269.678153) (xy 110.097839 -269.644922) (xy 110.061587 -269.605851) (xy 110.031563 -269.561814)
			(xy 110.008437 -269.513793) (xy 109.992727 -269.462863) (xy 109.984784 -269.410159) (xy 109.756204 -269.410159)
			(xy 109.748261 -269.462863) (xy 109.732551 -269.513793) (xy 109.709425 -269.561814) (xy 109.679401 -269.605851)
			(xy 109.643149 -269.644922) (xy 109.601478 -269.678153) (xy 109.55532 -269.704802) (xy 109.505706 -269.724274)
			(xy 109.453744 -269.736134) (xy 109.400594 -269.740118) (xy 109.347444 -269.736134) (xy 109.295482 -269.724274)
			(xy 109.245868 -269.704802) (xy 109.19971 -269.678153) (xy 109.158039 -269.644922) (xy 109.121787 -269.605851)
			(xy 109.091763 -269.561814) (xy 109.068637 -269.513793) (xy 109.052927 -269.462863) (xy 109.044984 -269.410159)
			(xy 108.816402 -269.410159) (xy 108.816402 -269.410811) (xy 108.808061 -269.464791) (xy 108.791575 -269.516865)
			(xy 108.767331 -269.56581) (xy 108.735898 -269.610479) (xy 108.698012 -269.649825) (xy 108.654562 -269.682924)
			(xy 108.606567 -269.709) (xy 108.555154 -269.727441) (xy 108.501527 -269.737816) (xy 108.474256 -269.739364)
			(xy 108.458666 -269.740509) (xy 108.429253 -269.751046) (xy 108.404401 -269.769982) (xy 108.386436 -269.795544)
			(xy 108.377039 -269.825341) (xy 108.376466 -269.840964) (xy 108.376466 -270.224229) (xy 108.575084 -270.224229)
			(xy 108.575084 -270.170931) (xy 108.583027 -270.118227) (xy 108.598737 -270.067297) (xy 108.621863 -270.019276)
			(xy 108.651887 -269.975239) (xy 108.688139 -269.936168) (xy 108.72981 -269.902937) (xy 108.775968 -269.876288)
			(xy 108.825582 -269.856816) (xy 108.877544 -269.844956) (xy 108.930694 -269.840973) (xy 108.983844 -269.844956)
			(xy 109.035806 -269.856816) (xy 109.08542 -269.876288) (xy 109.131578 -269.902937) (xy 109.173249 -269.936168)
			(xy 109.209501 -269.975239) (xy 109.239525 -270.019276) (xy 109.262651 -270.067297) (xy 109.278361 -270.118227)
			(xy 109.286304 -270.170931) (xy 109.286802 -270.19758) (xy 109.286304 -270.224229) (xy 109.278361 -270.276933)
			(xy 109.262651 -270.327863) (xy 109.239525 -270.375884) (xy 109.209501 -270.419921) (xy 109.173249 -270.458992)
			(xy 109.131578 -270.492223) (xy 109.08542 -270.518872) (xy 109.035806 -270.538344) (xy 108.983844 -270.550204)
			(xy 108.930694 -270.554188) (xy 108.877544 -270.550204) (xy 108.825582 -270.538344) (xy 108.775968 -270.518872)
			(xy 108.72981 -270.492223) (xy 108.688139 -270.458992) (xy 108.651887 -270.419921) (xy 108.621863 -270.375884)
			(xy 108.598737 -270.327863) (xy 108.583027 -270.276933) (xy 108.575084 -270.224229) (xy 108.376466 -270.224229)
			(xy 108.376466 -270.553942) (xy 108.377037 -270.569559) (xy 108.386468 -270.599336) (xy 108.40444 -270.624883)
			(xy 108.429278 -270.643821) (xy 108.458672 -270.654388) (xy 108.474256 -270.655542) (xy 108.501529 -270.65707)
			(xy 108.555158 -270.667445) (xy 108.606573 -270.685887) (xy 108.65457 -270.711964) (xy 108.698021 -270.745065)
			(xy 108.735909 -270.784412) (xy 108.767343 -270.829083) (xy 108.791588 -270.87803) (xy 108.808075 -270.930106)
			(xy 108.816416 -270.984088) (xy 108.816416 -271.038045) (xy 109.044984 -271.038045) (xy 109.044984 -270.984747)
			(xy 109.052927 -270.932043) (xy 109.068637 -270.881113) (xy 109.091763 -270.833092) (xy 109.121787 -270.789055)
			(xy 109.158039 -270.749984) (xy 109.19971 -270.716753) (xy 109.245868 -270.690104) (xy 109.295482 -270.670632)
			(xy 109.347444 -270.658772) (xy 109.400594 -270.654789) (xy 109.453744 -270.658772) (xy 109.505706 -270.670632)
			(xy 109.55532 -270.690104) (xy 109.601478 -270.716753) (xy 109.643149 -270.749984) (xy 109.679401 -270.789055)
			(xy 109.709425 -270.833092) (xy 109.732551 -270.881113) (xy 109.748261 -270.932043) (xy 109.756204 -270.984747)
			(xy 109.756702 -271.011396) (xy 109.756204 -271.038045) (xy 109.984784 -271.038045) (xy 109.984784 -270.984747)
			(xy 109.992727 -270.932043) (xy 110.008437 -270.881113) (xy 110.031563 -270.833092) (xy 110.061587 -270.789055)
			(xy 110.097839 -270.749984) (xy 110.13951 -270.716753) (xy 110.185668 -270.690104) (xy 110.235282 -270.670632)
			(xy 110.287244 -270.658772) (xy 110.340394 -270.654789) (xy 110.393544 -270.658772) (xy 110.445506 -270.670632)
			(xy 110.49512 -270.690104) (xy 110.541278 -270.716753) (xy 110.582949 -270.749984) (xy 110.619201 -270.789055)
			(xy 110.649225 -270.833092) (xy 110.672351 -270.881113) (xy 110.688061 -270.932043) (xy 110.696004 -270.984747)
			(xy 110.696502 -271.011396) (xy 110.696004 -271.038045) (xy 110.688061 -271.090749) (xy 110.672351 -271.141679)
			(xy 110.649225 -271.1897) (xy 110.619201 -271.233737) (xy 110.582949 -271.272808) (xy 110.541278 -271.306039)
			(xy 110.49512 -271.332688) (xy 110.445506 -271.35216) (xy 110.393544 -271.36402) (xy 110.340394 -271.368004)
			(xy 110.287244 -271.36402) (xy 110.235282 -271.35216) (xy 110.185668 -271.332688) (xy 110.13951 -271.306039)
			(xy 110.097839 -271.272808) (xy 110.061587 -271.233737) (xy 110.031563 -271.1897) (xy 110.008437 -271.141679)
			(xy 109.992727 -271.090749) (xy 109.984784 -271.038045) (xy 109.756204 -271.038045) (xy 109.748261 -271.090749)
			(xy 109.732551 -271.141679) (xy 109.709425 -271.1897) (xy 109.679401 -271.233737) (xy 109.643149 -271.272808)
			(xy 109.601478 -271.306039) (xy 109.55532 -271.332688) (xy 109.505706 -271.35216) (xy 109.453744 -271.36402)
			(xy 109.400594 -271.368004) (xy 109.347444 -271.36402) (xy 109.295482 -271.35216) (xy 109.245868 -271.332688)
			(xy 109.19971 -271.306039) (xy 109.158039 -271.272808) (xy 109.121787 -271.233737) (xy 109.091763 -271.1897)
			(xy 109.068637 -271.141679) (xy 109.052927 -271.090749) (xy 109.044984 -271.038045) (xy 108.816416 -271.038045)
			(xy 108.816416 -271.038711) (xy 108.808075 -271.092694) (xy 108.791588 -271.144769) (xy 108.767344 -271.193717)
			(xy 108.735909 -271.238388) (xy 108.698021 -271.277735) (xy 108.65457 -271.310835) (xy 108.606574 -271.336913)
			(xy 108.555158 -271.355355) (xy 108.501529 -271.36573) (xy 108.474256 -271.36725) (xy 108.458665 -271.368395)
			(xy 108.42925 -271.378932) (xy 108.404396 -271.397867) (xy 108.386428 -271.423429) (xy 108.377027 -271.453227)
			(xy 108.376466 -271.46885) (xy 108.376466 -271.851861) (xy 108.575338 -271.851861) (xy 108.575338 -271.798563)
			(xy 108.583281 -271.745859) (xy 108.598991 -271.694929) (xy 108.622117 -271.646908) (xy 108.652141 -271.602871)
			(xy 108.688393 -271.5638) (xy 108.730064 -271.530569) (xy 108.776222 -271.50392) (xy 108.825836 -271.484448)
			(xy 108.877798 -271.472588) (xy 108.930948 -271.468605) (xy 108.984098 -271.472588) (xy 109.03606 -271.484448)
			(xy 109.085674 -271.50392) (xy 109.131832 -271.530569) (xy 109.173503 -271.5638) (xy 109.209755 -271.602871)
			(xy 109.239779 -271.646908) (xy 109.262905 -271.694929) (xy 109.278615 -271.745859) (xy 109.286558 -271.798563)
			(xy 109.287056 -271.825212) (xy 109.286558 -271.851861) (xy 109.51463 -271.851861) (xy 109.51463 -271.798563)
			(xy 109.522573 -271.745859) (xy 109.538283 -271.694929) (xy 109.561409 -271.646908) (xy 109.591433 -271.602871)
			(xy 109.627685 -271.5638) (xy 109.669356 -271.530569) (xy 109.715514 -271.50392) (xy 109.765128 -271.484448)
			(xy 109.81709 -271.472588) (xy 109.87024 -271.468605) (xy 109.92339 -271.472588) (xy 109.975352 -271.484448)
			(xy 110.024966 -271.50392) (xy 110.071124 -271.530569) (xy 110.112795 -271.5638) (xy 110.149047 -271.602871)
			(xy 110.179071 -271.646908) (xy 110.202197 -271.694929) (xy 110.217907 -271.745859) (xy 110.22585 -271.798563)
			(xy 110.226348 -271.825212) (xy 110.22585 -271.851861) (xy 110.217907 -271.904565) (xy 110.202197 -271.955495)
			(xy 110.179071 -272.003516) (xy 110.149047 -272.047553) (xy 110.112795 -272.086624) (xy 110.071124 -272.119855)
			(xy 110.024966 -272.146504) (xy 109.975352 -272.165976) (xy 109.92339 -272.177836) (xy 109.87024 -272.18182)
			(xy 109.81709 -272.177836) (xy 109.765128 -272.165976) (xy 109.715514 -272.146504) (xy 109.669356 -272.119855)
			(xy 109.627685 -272.086624) (xy 109.591433 -272.047553) (xy 109.561409 -272.003516) (xy 109.538283 -271.955495)
			(xy 109.522573 -271.904565) (xy 109.51463 -271.851861) (xy 109.286558 -271.851861) (xy 109.278615 -271.904565)
			(xy 109.262905 -271.955495) (xy 109.239779 -272.003516) (xy 109.209755 -272.047553) (xy 109.173503 -272.086624)
			(xy 109.131832 -272.119855) (xy 109.085674 -272.146504) (xy 109.03606 -272.165976) (xy 108.984098 -272.177836)
			(xy 108.930948 -272.18182) (xy 108.877798 -272.177836) (xy 108.825836 -272.165976) (xy 108.776222 -272.146504)
			(xy 108.730064 -272.119855) (xy 108.688393 -272.086624) (xy 108.652141 -272.047553) (xy 108.622117 -272.003516)
			(xy 108.598991 -271.955495) (xy 108.583281 -271.904565) (xy 108.575338 -271.851861) (xy 108.376466 -271.851861)
			(xy 108.376466 -272.181828) (xy 108.377035 -272.197447) (xy 108.386464 -272.227227) (xy 108.404434 -272.252778)
			(xy 108.429274 -272.271719) (xy 108.45867 -272.282288) (xy 108.474256 -272.283428) (xy 108.50153 -272.284956)
			(xy 108.555161 -272.295331) (xy 108.606578 -272.313774) (xy 108.654577 -272.339852) (xy 108.69803 -272.372954)
			(xy 108.735919 -272.412303) (xy 108.767355 -272.456975) (xy 108.791601 -272.505925) (xy 108.808088 -272.558002)
			(xy 108.816429 -272.611987) (xy 108.81643 -272.665931) (xy 109.044984 -272.665931) (xy 109.044984 -272.612633)
			(xy 109.052927 -272.559929) (xy 109.068637 -272.508999) (xy 109.091763 -272.460978) (xy 109.121787 -272.416941)
			(xy 109.158039 -272.37787) (xy 109.19971 -272.344639) (xy 109.245868 -272.31799) (xy 109.295482 -272.298518)
			(xy 109.347444 -272.286658) (xy 109.400594 -272.282675) (xy 109.453744 -272.286658) (xy 109.505706 -272.298518)
			(xy 109.55532 -272.31799) (xy 109.601478 -272.344639) (xy 109.643149 -272.37787) (xy 109.679401 -272.416941)
			(xy 109.709425 -272.460978) (xy 109.732551 -272.508999) (xy 109.748261 -272.559929) (xy 109.756204 -272.612633)
			(xy 109.756702 -272.639282) (xy 109.756204 -272.665931) (xy 109.984784 -272.665931) (xy 109.984784 -272.612633)
			(xy 109.992727 -272.559929) (xy 110.008437 -272.508999) (xy 110.031563 -272.460978) (xy 110.061587 -272.416941)
			(xy 110.097839 -272.37787) (xy 110.13951 -272.344639) (xy 110.185668 -272.31799) (xy 110.235282 -272.298518)
			(xy 110.287244 -272.286658) (xy 110.340394 -272.282675) (xy 110.393544 -272.286658) (xy 110.445506 -272.298518)
			(xy 110.49512 -272.31799) (xy 110.541278 -272.344639) (xy 110.582949 -272.37787) (xy 110.619201 -272.416941)
			(xy 110.649225 -272.460978) (xy 110.672351 -272.508999) (xy 110.688061 -272.559929) (xy 110.696004 -272.612633)
			(xy 110.696502 -272.639282) (xy 110.696004 -272.665931) (xy 110.688061 -272.718635) (xy 110.672351 -272.769565)
			(xy 110.649225 -272.817586) (xy 110.619201 -272.861623) (xy 110.582949 -272.900694) (xy 110.541278 -272.933925)
			(xy 110.49512 -272.960574) (xy 110.445506 -272.980046) (xy 110.393544 -272.991906) (xy 110.340394 -272.99589)
			(xy 110.287244 -272.991906) (xy 110.235282 -272.980046) (xy 110.185668 -272.960574) (xy 110.13951 -272.933925)
			(xy 110.097839 -272.900694) (xy 110.061587 -272.861623) (xy 110.031563 -272.817586) (xy 110.008437 -272.769565)
			(xy 109.992727 -272.718635) (xy 109.984784 -272.665931) (xy 109.756204 -272.665931) (xy 109.748261 -272.718635)
			(xy 109.732551 -272.769565) (xy 109.709425 -272.817586) (xy 109.679401 -272.861623) (xy 109.643149 -272.900694)
			(xy 109.601478 -272.933925) (xy 109.55532 -272.960574) (xy 109.505706 -272.980046) (xy 109.453744 -272.991906)
			(xy 109.400594 -272.99589) (xy 109.347444 -272.991906) (xy 109.295482 -272.980046) (xy 109.245868 -272.960574)
			(xy 109.19971 -272.933925) (xy 109.158039 -272.900694) (xy 109.121787 -272.861623) (xy 109.091763 -272.817586)
			(xy 109.068637 -272.769565) (xy 109.052927 -272.718635) (xy 109.044984 -272.665931) (xy 108.81643 -272.665931)
			(xy 108.81643 -272.666612) (xy 108.808088 -272.720596) (xy 108.791602 -272.772674) (xy 108.767356 -272.821623)
			(xy 108.73592 -272.866296) (xy 108.698031 -272.905645) (xy 108.654578 -272.938747) (xy 108.60658 -272.964825)
			(xy 108.555162 -272.983268) (xy 108.501532 -272.993643) (xy 108.474256 -272.995136) (xy 108.458664 -272.99628)
			(xy 108.429247 -273.006817) (xy 108.40439 -273.025751) (xy 108.386419 -273.051313) (xy 108.377015 -273.081112)
			(xy 108.376466 -273.096736) (xy 108.376466 -273.453098) (xy 108.574586 -273.453098) (xy 108.575084 -273.426449)
			(xy 108.583027 -273.373745) (xy 108.598737 -273.322815) (xy 108.621863 -273.274794) (xy 108.651887 -273.230757)
			(xy 108.688139 -273.191686) (xy 108.72981 -273.158455) (xy 108.775968 -273.131806) (xy 108.825582 -273.112334)
			(xy 108.877544 -273.100474) (xy 108.930694 -273.096491) (xy 108.983844 -273.100474) (xy 109.035806 -273.112334)
			(xy 109.08542 -273.131806) (xy 109.131578 -273.158455) (xy 109.173249 -273.191686) (xy 109.209501 -273.230757)
			(xy 109.239525 -273.274794) (xy 109.262651 -273.322815) (xy 109.278361 -273.373745) (xy 109.286304 -273.426449)
			(xy 109.286802 -273.453098) (xy 109.28642 -273.476301) (xy 109.285967 -273.479747) (xy 109.514884 -273.479747)
			(xy 109.514884 -273.426449) (xy 109.522827 -273.373745) (xy 109.538537 -273.322815) (xy 109.561663 -273.274794)
			(xy 109.591687 -273.230757) (xy 109.627939 -273.191686) (xy 109.66961 -273.158455) (xy 109.715768 -273.131806)
			(xy 109.765382 -273.112334) (xy 109.817344 -273.100474) (xy 109.870494 -273.096491) (xy 109.923644 -273.100474)
			(xy 109.975606 -273.112334) (xy 110.02522 -273.131806) (xy 110.071378 -273.158455) (xy 110.113049 -273.191686)
			(xy 110.149301 -273.230757) (xy 110.179325 -273.274794) (xy 110.202451 -273.322815) (xy 110.218161 -273.373745)
			(xy 110.226104 -273.426449) (xy 110.226602 -273.453098) (xy 110.226104 -273.479747) (xy 110.218161 -273.532451)
			(xy 110.202451 -273.583381) (xy 110.179325 -273.631402) (xy 110.149301 -273.675439) (xy 110.113049 -273.71451)
			(xy 110.071378 -273.747741) (xy 110.02522 -273.77439) (xy 109.975606 -273.793862) (xy 109.923644 -273.805722)
			(xy 109.870494 -273.809706) (xy 109.817344 -273.805722) (xy 109.765382 -273.793862) (xy 109.715768 -273.77439)
			(xy 109.66961 -273.747741) (xy 109.627939 -273.71451) (xy 109.591687 -273.675439) (xy 109.561663 -273.631402)
			(xy 109.538537 -273.583381) (xy 109.522827 -273.532451) (xy 109.514884 -273.479747) (xy 109.285967 -273.479747)
			(xy 109.280371 -273.522312) (xy 109.268388 -273.567144) (xy 109.259878 -273.588734) (xy 109.25048 -273.611848)
			(xy 109.422946 -273.910552) (xy 109.447584 -273.913854) (xy 109.472915 -273.91775) (xy 109.522217 -273.931732)
			(xy 109.569006 -273.952635) (xy 109.612317 -273.980028) (xy 109.651256 -274.013345) (xy 109.685018 -274.051897)
			(xy 109.712907 -274.094891) (xy 109.734346 -274.141437) (xy 109.748895 -274.190575) (xy 109.756251 -274.241291)
			(xy 109.756702 -274.266914) (xy 109.756204 -274.293563) (xy 109.984784 -274.293563) (xy 109.984784 -274.240265)
			(xy 109.992727 -274.187561) (xy 110.008437 -274.136631) (xy 110.031563 -274.08861) (xy 110.061587 -274.044573)
			(xy 110.097839 -274.005502) (xy 110.13951 -273.972271) (xy 110.185668 -273.945622) (xy 110.235282 -273.92615)
			(xy 110.287244 -273.91429) (xy 110.340394 -273.910307) (xy 110.393544 -273.91429) (xy 110.445506 -273.92615)
			(xy 110.49512 -273.945622) (xy 110.541278 -273.972271) (xy 110.582949 -274.005502) (xy 110.619201 -274.044573)
			(xy 110.649225 -274.08861) (xy 110.672351 -274.136631) (xy 110.688061 -274.187561) (xy 110.696004 -274.240265)
			(xy 110.696502 -274.266914) (xy 110.696004 -274.293563) (xy 110.688061 -274.346267) (xy 110.672351 -274.397197)
			(xy 110.649225 -274.445218) (xy 110.619201 -274.489255) (xy 110.582949 -274.528326) (xy 110.541278 -274.561557)
			(xy 110.49512 -274.588206) (xy 110.445506 -274.607678) (xy 110.393544 -274.619538) (xy 110.340394 -274.623522)
			(xy 110.287244 -274.619538) (xy 110.235282 -274.607678) (xy 110.185668 -274.588206) (xy 110.13951 -274.561557)
			(xy 110.097839 -274.528326) (xy 110.061587 -274.489255) (xy 110.031563 -274.445218) (xy 110.008437 -274.397197)
			(xy 109.992727 -274.346267) (xy 109.984784 -274.293563) (xy 109.756204 -274.293563) (xy 109.748261 -274.346267)
			(xy 109.732551 -274.397197) (xy 109.709425 -274.445218) (xy 109.679401 -274.489255) (xy 109.643149 -274.528326)
			(xy 109.601478 -274.561557) (xy 109.55532 -274.588206) (xy 109.505706 -274.607678) (xy 109.453744 -274.619538)
			(xy 109.400594 -274.623522) (xy 109.347444 -274.619538) (xy 109.295482 -274.607678) (xy 109.245868 -274.588206)
			(xy 109.19971 -274.561557) (xy 109.158039 -274.528326) (xy 109.121787 -274.489255) (xy 109.091763 -274.445218)
			(xy 109.068637 -274.397197) (xy 109.052927 -274.346267) (xy 109.044984 -274.293563) (xy 109.044486 -274.266914)
			(xy 109.04486 -274.243669) (xy 109.050905 -274.197574) (xy 109.062893 -274.152656) (xy 109.07141 -274.131024)
			(xy 109.081062 -274.10791) (xy 108.908596 -273.80946) (xy 108.883704 -273.806158) (xy 108.858374 -273.80226)
			(xy 108.809073 -273.788277) (xy 108.762284 -273.767373) (xy 108.718974 -273.73998) (xy 108.680036 -273.706664)
			(xy 108.646274 -273.668111) (xy 108.618385 -273.625119) (xy 108.596945 -273.578573) (xy 108.582396 -273.529436)
			(xy 108.575038 -273.478721) (xy 108.574586 -273.453098) (xy 108.376466 -273.453098) (xy 108.376466 -273.80946)
			(xy 108.377039 -273.825075) (xy 108.386474 -273.854848) (xy 108.404446 -273.88039) (xy 108.429283 -273.899324)
			(xy 108.458674 -273.909889) (xy 108.474256 -273.91106) (xy 108.501538 -273.912574) (xy 108.555188 -273.922925)
			(xy 108.606626 -273.94135) (xy 108.654647 -273.967415) (xy 108.698122 -274.000511) (xy 108.736032 -274.039859)
			(xy 108.767486 -274.084536) (xy 108.791746 -274.133494) (xy 108.808243 -274.185583) (xy 108.816589 -274.239581)
			(xy 108.816589 -274.29422) (xy 108.808243 -274.348218) (xy 108.791746 -274.400307) (xy 108.767486 -274.449264)
			(xy 108.736031 -274.493942) (xy 108.698122 -274.53329) (xy 108.654646 -274.566385) (xy 108.606625 -274.592451)
			(xy 108.555187 -274.610875) (xy 108.501537 -274.621226) (xy 108.474256 -274.622768) (xy 108.458666 -274.623913)
			(xy 108.429253 -274.63445) (xy 108.404402 -274.653386) (xy 108.386438 -274.678948) (xy 108.377042 -274.708745)
			(xy 108.376466 -274.724368) (xy 108.376466 -275.107379) (xy 108.575084 -275.107379) (xy 108.575084 -275.054081)
			(xy 108.583027 -275.001377) (xy 108.598737 -274.950447) (xy 108.621863 -274.902426) (xy 108.651887 -274.858389)
			(xy 108.688139 -274.819318) (xy 108.72981 -274.786087) (xy 108.775968 -274.759438) (xy 108.825582 -274.739966)
			(xy 108.877544 -274.728106) (xy 108.930694 -274.724123) (xy 108.983844 -274.728106) (xy 109.035806 -274.739966)
			(xy 109.08542 -274.759438) (xy 109.131578 -274.786087) (xy 109.173249 -274.819318) (xy 109.209501 -274.858389)
			(xy 109.239525 -274.902426) (xy 109.262651 -274.950447) (xy 109.278361 -275.001377) (xy 109.286304 -275.054081)
			(xy 109.286802 -275.08073) (xy 109.286304 -275.107379) (xy 109.514884 -275.107379) (xy 109.514884 -275.054081)
			(xy 109.522827 -275.001377) (xy 109.538537 -274.950447) (xy 109.561663 -274.902426) (xy 109.591687 -274.858389)
			(xy 109.627939 -274.819318) (xy 109.66961 -274.786087) (xy 109.715768 -274.759438) (xy 109.765382 -274.739966)
			(xy 109.817344 -274.728106) (xy 109.870494 -274.724123) (xy 109.923644 -274.728106) (xy 109.975606 -274.739966)
			(xy 110.02522 -274.759438) (xy 110.071378 -274.786087) (xy 110.113049 -274.819318) (xy 110.149301 -274.858389)
			(xy 110.179325 -274.902426) (xy 110.202451 -274.950447) (xy 110.218161 -275.001377) (xy 110.226104 -275.054081)
			(xy 110.226602 -275.08073) (xy 110.226104 -275.107379) (xy 110.218161 -275.160083) (xy 110.202451 -275.211013)
			(xy 110.179325 -275.259034) (xy 110.149301 -275.303071) (xy 110.113049 -275.342142) (xy 110.071378 -275.375373)
			(xy 110.02522 -275.402022) (xy 109.975606 -275.421494) (xy 109.923644 -275.433354) (xy 109.870494 -275.437338)
			(xy 109.817344 -275.433354) (xy 109.765382 -275.421494) (xy 109.715768 -275.402022) (xy 109.66961 -275.375373)
			(xy 109.627939 -275.342142) (xy 109.591687 -275.303071) (xy 109.561663 -275.259034) (xy 109.538537 -275.211013)
			(xy 109.522827 -275.160083) (xy 109.514884 -275.107379) (xy 109.286304 -275.107379) (xy 109.278361 -275.160083)
			(xy 109.262651 -275.211013) (xy 109.239525 -275.259034) (xy 109.209501 -275.303071) (xy 109.173249 -275.342142)
			(xy 109.131578 -275.375373) (xy 109.08542 -275.402022) (xy 109.035806 -275.421494) (xy 108.983844 -275.433354)
			(xy 108.930694 -275.437338) (xy 108.877544 -275.433354) (xy 108.825582 -275.421494) (xy 108.775968 -275.402022)
			(xy 108.72981 -275.375373) (xy 108.688139 -275.342142) (xy 108.651887 -275.303071) (xy 108.621863 -275.259034)
			(xy 108.598737 -275.211013) (xy 108.583027 -275.160083) (xy 108.575084 -275.107379) (xy 108.376466 -275.107379)
			(xy 108.376466 -275.353526) (xy 108.4834 -275.538438) (xy 108.508038 -275.54174) (xy 108.533384 -275.545561)
			(xy 108.582701 -275.559534) (xy 108.629504 -275.580434) (xy 108.672827 -275.607829) (xy 108.711773 -275.641153)
			(xy 108.745539 -275.679718) (xy 108.773426 -275.722725) (xy 108.794858 -275.769287) (xy 108.809393 -275.818441)
			(xy 108.816728 -275.869171) (xy 108.817156 -275.8948) (xy 108.816658 -275.922122) (xy 108.80831 -275.976125)
			(xy 108.791808 -276.028218) (xy 108.767541 -276.077178) (xy 108.736079 -276.121856) (xy 108.69816 -276.161203)
			(xy 108.654675 -276.194294) (xy 108.606645 -276.220353) (xy 108.555197 -276.238768) (xy 108.50154 -276.249106)
			(xy 108.474256 -276.250654) (xy 108.458665 -276.251799) (xy 108.429251 -276.262336) (xy 108.404397 -276.281271)
			(xy 108.38643 -276.306833) (xy 108.377031 -276.336631) (xy 108.376466 -276.352254) (xy 108.376466 -276.708616)
			(xy 108.574586 -276.708616) (xy 108.574992 -276.682986) (xy 108.582327 -276.632253) (xy 108.596861 -276.583097)
			(xy 108.618294 -276.536532) (xy 108.646183 -276.493523) (xy 108.679952 -276.454958) (xy 108.718902 -276.421634)
			(xy 108.762229 -276.394241) (xy 108.809036 -276.373343) (xy 108.858356 -276.359374) (xy 108.883704 -276.355556)
			(xy 108.908342 -276.352254) (xy 109.080808 -276.053804) (xy 109.071156 -276.03069) (xy 109.062641 -276.009057)
			(xy 109.050653 -275.96414) (xy 109.044608 -275.918045) (xy 109.044232 -275.8948) (xy 109.04473 -275.868151)
			(xy 109.052673 -275.815447) (xy 109.068383 -275.764517) (xy 109.091509 -275.716496) (xy 109.121533 -275.672459)
			(xy 109.157785 -275.633388) (xy 109.199456 -275.600157) (xy 109.245614 -275.573508) (xy 109.295228 -275.554036)
			(xy 109.34719 -275.542176) (xy 109.40034 -275.538193) (xy 109.45349 -275.542176) (xy 109.505452 -275.554036)
			(xy 109.555066 -275.573508) (xy 109.601224 -275.600157) (xy 109.642895 -275.633388) (xy 109.679147 -275.672459)
			(xy 109.709171 -275.716496) (xy 109.732297 -275.764517) (xy 109.748007 -275.815447) (xy 109.75595 -275.868151)
			(xy 109.756448 -275.8948) (xy 109.755969 -275.920416) (xy 109.75582 -275.921449) (xy 109.984784 -275.921449)
			(xy 109.984784 -275.868151) (xy 109.992727 -275.815447) (xy 110.008437 -275.764517) (xy 110.031563 -275.716496)
			(xy 110.061587 -275.672459) (xy 110.097839 -275.633388) (xy 110.13951 -275.600157) (xy 110.185668 -275.573508)
			(xy 110.235282 -275.554036) (xy 110.287244 -275.542176) (xy 110.340394 -275.538193) (xy 110.393544 -275.542176)
			(xy 110.445506 -275.554036) (xy 110.49512 -275.573508) (xy 110.541278 -275.600157) (xy 110.582949 -275.633388)
			(xy 110.619201 -275.672459) (xy 110.649225 -275.716496) (xy 110.672351 -275.764517) (xy 110.688061 -275.815447)
			(xy 110.696004 -275.868151) (xy 110.696502 -275.8948) (xy 110.696004 -275.921449) (xy 110.688061 -275.974153)
			(xy 110.672351 -276.025083) (xy 110.649225 -276.073104) (xy 110.619201 -276.117141) (xy 110.582949 -276.156212)
			(xy 110.541278 -276.189443) (xy 110.49512 -276.216092) (xy 110.445506 -276.235564) (xy 110.393544 -276.247424)
			(xy 110.340394 -276.251408) (xy 110.287244 -276.247424) (xy 110.235282 -276.235564) (xy 110.185668 -276.216092)
			(xy 110.13951 -276.189443) (xy 110.097839 -276.156212) (xy 110.061587 -276.117141) (xy 110.031563 -276.073104)
			(xy 110.008437 -276.025083) (xy 109.992727 -275.974153) (xy 109.984784 -275.921449) (xy 109.75582 -275.921449)
			(xy 109.748654 -275.971124) (xy 109.734145 -276.020259) (xy 109.712743 -276.066807) (xy 109.684889 -276.109806)
			(xy 109.651159 -276.148368) (xy 109.61225 -276.181697) (xy 109.568965 -276.209104) (xy 109.522198 -276.230024)
			(xy 109.472915 -276.244023) (xy 109.447584 -276.24786) (xy 109.422692 -276.251162) (xy 109.250226 -276.549612)
			(xy 109.259878 -276.572726) (xy 109.268399 -276.594356) (xy 109.280385 -276.639275) (xy 109.286428 -276.685371)
			(xy 109.286802 -276.708616) (xy 109.286304 -276.735265) (xy 109.514884 -276.735265) (xy 109.514884 -276.681967)
			(xy 109.522827 -276.629263) (xy 109.538537 -276.578333) (xy 109.561663 -276.530312) (xy 109.591687 -276.486275)
			(xy 109.627939 -276.447204) (xy 109.66961 -276.413973) (xy 109.715768 -276.387324) (xy 109.765382 -276.367852)
			(xy 109.817344 -276.355992) (xy 109.870494 -276.352009) (xy 109.923644 -276.355992) (xy 109.975606 -276.367852)
			(xy 110.02522 -276.387324) (xy 110.071378 -276.413973) (xy 110.113049 -276.447204) (xy 110.149301 -276.486275)
			(xy 110.179325 -276.530312) (xy 110.202451 -276.578333) (xy 110.218161 -276.629263) (xy 110.226104 -276.681967)
			(xy 110.226602 -276.708616) (xy 110.226104 -276.735265) (xy 110.218161 -276.787969) (xy 110.202451 -276.838899)
			(xy 110.179325 -276.88692) (xy 110.149301 -276.930957) (xy 110.113049 -276.970028) (xy 110.071378 -277.003259)
			(xy 110.02522 -277.029908) (xy 109.975606 -277.04938) (xy 109.923644 -277.06124) (xy 109.870494 -277.065224)
			(xy 109.817344 -277.06124) (xy 109.765382 -277.04938) (xy 109.715768 -277.029908) (xy 109.66961 -277.003259)
			(xy 109.627939 -276.970028) (xy 109.591687 -276.930957) (xy 109.561663 -276.88692) (xy 109.538537 -276.838899)
			(xy 109.522827 -276.787969) (xy 109.514884 -276.735265) (xy 109.286304 -276.735265) (xy 109.278361 -276.787969)
			(xy 109.262651 -276.838899) (xy 109.239525 -276.88692) (xy 109.209501 -276.930957) (xy 109.173249 -276.970028)
			(xy 109.131578 -277.003259) (xy 109.08542 -277.029908) (xy 109.035806 -277.04938) (xy 108.983844 -277.06124)
			(xy 108.930694 -277.065224) (xy 108.877544 -277.06124) (xy 108.825582 -277.04938) (xy 108.775968 -277.029908)
			(xy 108.72981 -277.003259) (xy 108.688139 -276.970028) (xy 108.651887 -276.930957) (xy 108.621863 -276.88692)
			(xy 108.598737 -276.838899) (xy 108.583027 -276.787969) (xy 108.575084 -276.735265) (xy 108.574586 -276.708616)
			(xy 108.376466 -276.708616) (xy 108.376466 -277.064978) (xy 108.377042 -277.080592) (xy 108.386479 -277.110359)
			(xy 108.404453 -277.135897) (xy 108.429289 -277.154827) (xy 108.458676 -277.165389) (xy 108.474256 -277.166578)
			(xy 108.502284 -277.168143) (xy 108.557359 -277.178999) (xy 108.610046 -277.198367) (xy 108.659039 -277.225767)
			(xy 108.703123 -277.260518) (xy 108.741204 -277.301759) (xy 108.757212 -277.32482) (xy 109.104176 -277.32482)
			(xy 109.118414 -277.304249) (xy 109.151736 -277.266933) (xy 109.18995 -277.234645) (xy 109.232305 -277.208021)
			(xy 109.277968 -277.187585) (xy 109.326042 -277.173737) (xy 109.37558 -277.166751) (xy 109.400594 -277.166324)
			(xy 109.427243 -277.166797) (xy 109.479946 -277.17474) (xy 109.530876 -277.190449) (xy 109.578897 -277.213573)
			(xy 109.622934 -277.243597) (xy 109.662004 -277.279848) (xy 109.695235 -277.321518) (xy 109.721885 -277.367676)
			(xy 109.741357 -277.417289) (xy 109.753217 -277.469251) (xy 109.7572 -277.5224) (xy 109.755201 -277.549081)
			(xy 109.984784 -277.549081) (xy 109.984784 -277.495783) (xy 109.992727 -277.443079) (xy 110.008437 -277.392149)
			(xy 110.031563 -277.344128) (xy 110.061587 -277.300091) (xy 110.097839 -277.26102) (xy 110.13951 -277.227789)
			(xy 110.185668 -277.20114) (xy 110.235282 -277.181668) (xy 110.287244 -277.169808) (xy 110.340394 -277.165825)
			(xy 110.393544 -277.169808) (xy 110.445506 -277.181668) (xy 110.49512 -277.20114) (xy 110.541278 -277.227789)
			(xy 110.582949 -277.26102) (xy 110.619201 -277.300091) (xy 110.649225 -277.344128) (xy 110.672351 -277.392149)
			(xy 110.688061 -277.443079) (xy 110.696004 -277.495783) (xy 110.696502 -277.522432) (xy 110.696004 -277.549081)
			(xy 110.688061 -277.601785) (xy 110.672351 -277.652715) (xy 110.649225 -277.700736) (xy 110.619201 -277.744773)
			(xy 110.582949 -277.783844) (xy 110.541278 -277.817075) (xy 110.49512 -277.843724) (xy 110.445506 -277.863196)
			(xy 110.393544 -277.875056) (xy 110.340394 -277.87904) (xy 110.287244 -277.875056) (xy 110.235282 -277.863196)
			(xy 110.185668 -277.843724) (xy 110.13951 -277.817075) (xy 110.097839 -277.783844) (xy 110.061587 -277.744773)
			(xy 110.031563 -277.700736) (xy 110.008437 -277.652715) (xy 109.992727 -277.601785) (xy 109.984784 -277.549081)
			(xy 109.755201 -277.549081) (xy 109.753217 -277.575549) (xy 109.741357 -277.627511) (xy 109.721885 -277.677124)
			(xy 109.695235 -277.723282) (xy 109.662004 -277.764952) (xy 109.622934 -277.801203) (xy 109.578897 -277.831227)
			(xy 109.530876 -277.854351) (xy 109.479946 -277.87006) (xy 109.427243 -277.878003) (xy 109.400594 -277.87854)
			(xy 109.375581 -277.878117) (xy 109.326045 -277.871121) (xy 109.277975 -277.857267) (xy 109.232314 -277.836828)
			(xy 109.18996 -277.810205) (xy 109.151744 -277.777922) (xy 109.118418 -277.740611) (xy 109.104176 -277.720044)
			(xy 108.757212 -277.720044) (xy 108.741192 -277.743091) (xy 108.703094 -277.784304) (xy 108.659005 -277.819034)
			(xy 108.610016 -277.846423) (xy 108.55734 -277.865792) (xy 108.502277 -277.876663) (xy 108.474256 -277.878286)
			(xy 108.458661 -277.87943) (xy 108.429238 -277.889965) (xy 108.404372 -277.908898) (xy 108.38639 -277.934459)
			(xy 108.376972 -277.964259) (xy 108.376466 -277.979886) (xy 108.376466 -278.363151) (xy 108.575084 -278.363151)
			(xy 108.575084 -278.309853) (xy 108.583027 -278.257149) (xy 108.598737 -278.206219) (xy 108.621863 -278.158198)
			(xy 108.651887 -278.114161) (xy 108.688139 -278.07509) (xy 108.72981 -278.041859) (xy 108.775968 -278.01521)
			(xy 108.825582 -277.995738) (xy 108.877544 -277.983878) (xy 108.930694 -277.979895) (xy 108.983844 -277.983878)
			(xy 109.035806 -277.995738) (xy 109.08542 -278.01521) (xy 109.131578 -278.041859) (xy 109.173249 -278.07509)
			(xy 109.209501 -278.114161) (xy 109.239525 -278.158198) (xy 109.262651 -278.206219) (xy 109.278361 -278.257149)
			(xy 109.286304 -278.309853) (xy 109.286802 -278.336502) (xy 109.286304 -278.363151) (xy 109.514884 -278.363151)
			(xy 109.514884 -278.309853) (xy 109.522827 -278.257149) (xy 109.538537 -278.206219) (xy 109.561663 -278.158198)
			(xy 109.591687 -278.114161) (xy 109.627939 -278.07509) (xy 109.66961 -278.041859) (xy 109.715768 -278.01521)
			(xy 109.765382 -277.995738) (xy 109.817344 -277.983878) (xy 109.870494 -277.979895) (xy 109.923644 -277.983878)
			(xy 109.975606 -277.995738) (xy 110.02522 -278.01521) (xy 110.071378 -278.041859) (xy 110.113049 -278.07509)
			(xy 110.149301 -278.114161) (xy 110.179325 -278.158198) (xy 110.202451 -278.206219) (xy 110.218161 -278.257149)
			(xy 110.226104 -278.309853) (xy 110.226602 -278.336502) (xy 110.226104 -278.363151) (xy 114.214138 -278.363151)
			(xy 114.214138 -278.309853) (xy 114.222081 -278.257149) (xy 114.237791 -278.206219) (xy 114.260917 -278.158198)
			(xy 114.290941 -278.114161) (xy 114.327193 -278.07509) (xy 114.368864 -278.041859) (xy 114.415022 -278.01521)
			(xy 114.464636 -277.995738) (xy 114.516598 -277.983878) (xy 114.569748 -277.979895) (xy 114.622898 -277.983878)
			(xy 114.67486 -277.995738) (xy 114.724474 -278.01521) (xy 114.770632 -278.041859) (xy 114.812303 -278.07509)
			(xy 114.848555 -278.114161) (xy 114.878579 -278.158198) (xy 114.901705 -278.206219) (xy 114.917415 -278.257149)
			(xy 114.925358 -278.309853) (xy 114.925856 -278.336502) (xy 114.925358 -278.363151) (xy 114.917415 -278.415855)
			(xy 114.901705 -278.466785) (xy 114.878579 -278.514806) (xy 114.848555 -278.558843) (xy 114.812303 -278.597914)
			(xy 114.770632 -278.631145) (xy 114.724474 -278.657794) (xy 114.67486 -278.677266) (xy 114.622898 -278.689126)
			(xy 114.569748 -278.69311) (xy 114.516598 -278.689126) (xy 114.464636 -278.677266) (xy 114.415022 -278.657794)
			(xy 114.368864 -278.631145) (xy 114.327193 -278.597914) (xy 114.290941 -278.558843) (xy 114.260917 -278.514806)
			(xy 114.237791 -278.466785) (xy 114.222081 -278.415855) (xy 114.214138 -278.363151) (xy 110.226104 -278.363151)
			(xy 110.218161 -278.415855) (xy 110.202451 -278.466785) (xy 110.179325 -278.514806) (xy 110.149301 -278.558843)
			(xy 110.113049 -278.597914) (xy 110.071378 -278.631145) (xy 110.02522 -278.657794) (xy 109.975606 -278.677266)
			(xy 109.923644 -278.689126) (xy 109.870494 -278.69311) (xy 109.817344 -278.689126) (xy 109.765382 -278.677266)
			(xy 109.715768 -278.657794) (xy 109.66961 -278.631145) (xy 109.627939 -278.597914) (xy 109.591687 -278.558843)
			(xy 109.561663 -278.514806) (xy 109.538537 -278.466785) (xy 109.522827 -278.415855) (xy 109.514884 -278.363151)
			(xy 109.286304 -278.363151) (xy 109.278361 -278.415855) (xy 109.262651 -278.466785) (xy 109.239525 -278.514806)
			(xy 109.209501 -278.558843) (xy 109.173249 -278.597914) (xy 109.131578 -278.631145) (xy 109.08542 -278.657794)
			(xy 109.035806 -278.677266) (xy 108.983844 -278.689126) (xy 108.930694 -278.69311) (xy 108.877544 -278.689126)
			(xy 108.825582 -278.677266) (xy 108.775968 -278.657794) (xy 108.72981 -278.631145) (xy 108.688139 -278.597914)
			(xy 108.651887 -278.558843) (xy 108.621863 -278.514806) (xy 108.598737 -278.466785) (xy 108.583027 -278.415855)
			(xy 108.575084 -278.363151) (xy 108.376466 -278.363151) (xy 108.376466 -278.692864) (xy 108.37704 -278.708479)
			(xy 108.386475 -278.73825) (xy 108.404448 -278.763791) (xy 108.429285 -278.782725) (xy 108.458674 -278.793289)
			(xy 108.474256 -278.794464) (xy 108.501528 -278.795992) (xy 108.555153 -278.806367) (xy 108.606565 -278.824808)
			(xy 108.654558 -278.850883) (xy 108.698007 -278.883982) (xy 108.735892 -278.923327) (xy 108.767325 -278.967995)
			(xy 108.791568 -279.016939) (xy 108.808053 -279.069012) (xy 108.816394 -279.122991) (xy 108.816394 -279.176967)
			(xy 114.683784 -279.176967) (xy 114.683784 -279.123669) (xy 114.691727 -279.070965) (xy 114.707437 -279.020035)
			(xy 114.730563 -278.972014) (xy 114.760587 -278.927977) (xy 114.796839 -278.888906) (xy 114.83851 -278.855675)
			(xy 114.884668 -278.829026) (xy 114.934282 -278.809554) (xy 114.986244 -278.797694) (xy 115.039394 -278.793711)
			(xy 115.092544 -278.797694) (xy 115.144506 -278.809554) (xy 115.19412 -278.829026) (xy 115.240278 -278.855675)
			(xy 115.281949 -278.888906) (xy 115.318201 -278.927977) (xy 115.348225 -278.972014) (xy 115.371351 -279.020035)
			(xy 115.387061 -279.070965) (xy 115.395004 -279.123669) (xy 115.395502 -279.150318) (xy 115.395004 -279.176967)
			(xy 115.387061 -279.229671) (xy 115.371351 -279.280601) (xy 115.348225 -279.328622) (xy 115.318201 -279.372659)
			(xy 115.281949 -279.41173) (xy 115.240278 -279.444961) (xy 115.19412 -279.47161) (xy 115.144506 -279.491082)
			(xy 115.092544 -279.502942) (xy 115.039394 -279.506926) (xy 114.986244 -279.502942) (xy 114.934282 -279.491082)
			(xy 114.884668 -279.47161) (xy 114.83851 -279.444961) (xy 114.796839 -279.41173) (xy 114.760587 -279.372659)
			(xy 114.730563 -279.328622) (xy 114.707437 -279.280601) (xy 114.691727 -279.229671) (xy 114.683784 -279.176967)
			(xy 108.816394 -279.176967) (xy 108.816394 -279.17761) (xy 108.808053 -279.231589) (xy 108.791568 -279.283662)
			(xy 108.767324 -279.332606) (xy 108.735891 -279.377275) (xy 108.698006 -279.416619) (xy 108.654557 -279.449717)
			(xy 108.606564 -279.475793) (xy 108.555151 -279.494234) (xy 108.501526 -279.504608) (xy 108.474256 -279.506172)
			(xy 108.458666 -279.507317) (xy 108.429254 -279.517854) (xy 108.404404 -279.53679) (xy 108.386441 -279.562353)
			(xy 108.377046 -279.59215) (xy 108.376466 -279.607772) (xy 108.376466 -279.822148) (xy 108.334048 -279.864566)
			(xy 108.339636 -279.89149) (xy 108.343122 -279.909447) (xy 108.346813 -279.945843) (xy 108.347002 -279.964134)
			(xy 108.346476 -279.990783) (xy 113.274084 -279.990783) (xy 113.274084 -279.937485) (xy 113.282027 -279.884781)
			(xy 113.297737 -279.833851) (xy 113.320863 -279.78583) (xy 113.350887 -279.741793) (xy 113.387139 -279.702722)
			(xy 113.42881 -279.669491) (xy 113.474968 -279.642842) (xy 113.524582 -279.62337) (xy 113.576544 -279.61151)
			(xy 113.629694 -279.607527) (xy 113.682844 -279.61151) (xy 113.734806 -279.62337) (xy 113.78442 -279.642842)
			(xy 113.830578 -279.669491) (xy 113.872249 -279.702722) (xy 113.908501 -279.741793) (xy 113.938525 -279.78583)
			(xy 113.961651 -279.833851) (xy 113.977361 -279.884781) (xy 113.985304 -279.937485) (xy 113.985802 -279.964134)
			(xy 113.985304 -279.990783) (xy 113.977361 -280.043487) (xy 113.961651 -280.094417) (xy 113.938525 -280.142438)
			(xy 113.908501 -280.186475) (xy 113.872249 -280.225546) (xy 113.830578 -280.258777) (xy 113.78442 -280.285426)
			(xy 113.734806 -280.304898) (xy 113.682844 -280.316758) (xy 113.629694 -280.320742) (xy 113.576544 -280.316758)
			(xy 113.524582 -280.304898) (xy 113.474968 -280.285426) (xy 113.42881 -280.258777) (xy 113.387139 -280.225546)
			(xy 113.350887 -280.186475) (xy 113.320863 -280.142438) (xy 113.297737 -280.094417) (xy 113.282027 -280.043487)
			(xy 113.274084 -279.990783) (xy 108.346476 -279.990783) (xy 108.34645 -279.992115) (xy 108.337691 -280.047388)
			(xy 108.320394 -280.10061) (xy 108.294984 -280.150471) (xy 108.262087 -280.195744) (xy 108.222513 -280.235313)
			(xy 108.177237 -280.268205) (xy 108.127373 -280.293609) (xy 108.074149 -280.310901) (xy 108.018875 -280.319654)
			(xy 107.990894 -280.320242) (xy 107.972604 -280.320032) (xy 107.936211 -280.316338) (xy 107.91825 -280.312876)
			(xy 107.891326 -280.307288) (xy 107.793536 -280.405078) (xy 107.78306 -280.416271) (xy 107.768768 -280.443378)
			(xy 107.763164 -280.473505) (xy 107.766753 -280.503938) (xy 107.779212 -280.531935) (xy 107.788964 -280.543762)
			(xy 107.805501 -280.563319) (xy 107.833372 -280.606284) (xy 107.854796 -280.652803) (xy 107.869329 -280.701912)
			(xy 107.876671 -280.752597) (xy 107.877102 -280.778204) (xy 107.876606 -280.804853) (xy 109.984784 -280.804853)
			(xy 109.984784 -280.751555) (xy 109.992727 -280.698851) (xy 110.008437 -280.647921) (xy 110.031563 -280.5999)
			(xy 110.061587 -280.555863) (xy 110.097839 -280.516792) (xy 110.13951 -280.483561) (xy 110.185668 -280.456912)
			(xy 110.235282 -280.43744) (xy 110.287244 -280.42558) (xy 110.340394 -280.421597) (xy 110.393544 -280.42558)
			(xy 110.445506 -280.43744) (xy 110.49512 -280.456912) (xy 110.541278 -280.483561) (xy 110.582949 -280.516792)
			(xy 110.619201 -280.555863) (xy 110.649225 -280.5999) (xy 110.672351 -280.647921) (xy 110.688061 -280.698851)
			(xy 110.696004 -280.751555) (xy 110.696502 -280.778204) (xy 110.696004 -280.804853) (xy 110.688061 -280.857557)
			(xy 110.672351 -280.908487) (xy 110.649225 -280.956508) (xy 110.619201 -281.000545) (xy 110.582949 -281.039616)
			(xy 110.541278 -281.072847) (xy 110.49512 -281.099496) (xy 110.445506 -281.118968) (xy 110.393544 -281.130828)
			(xy 110.340394 -281.134812) (xy 110.287244 -281.130828) (xy 110.235282 -281.118968) (xy 110.185668 -281.099496)
			(xy 110.13951 -281.072847) (xy 110.097839 -281.039616) (xy 110.061587 -281.000545) (xy 110.031563 -280.956508)
			(xy 110.008437 -280.908487) (xy 109.992727 -280.857557) (xy 109.984784 -280.804853) (xy 107.876606 -280.804853)
			(xy 107.876581 -280.806189) (xy 107.867825 -280.86147) (xy 107.850529 -280.9147) (xy 107.825118 -280.964569)
			(xy 107.792219 -281.00985) (xy 107.752642 -281.049426) (xy 107.707361 -281.082323) (xy 107.657491 -281.107732)
			(xy 107.60426 -281.125027) (xy 107.548979 -281.133782) (xy 107.520994 -281.134312) (xy 107.495387 -281.133866)
			(xy 107.444703 -281.126525) (xy 107.395595 -281.111995) (xy 107.349076 -281.090577) (xy 107.306107 -281.062712)
			(xy 107.286552 -281.046174) (xy 107.274677 -281.036511) (xy 107.246694 -281.024123) (xy 107.2163 -281.020557)
			(xy 107.186209 -281.026132) (xy 107.15911 -281.04035) (xy 107.147868 -281.050746) (xy 107.115356 -281.083258)
			(xy 107.105213 -281.094194) (xy 107.091188 -281.120503) (xy 107.085355 -281.149741) (xy 107.088209 -281.179418)
			(xy 107.09951 -281.207007) (xy 107.118293 -281.23016) (xy 107.14296 -281.246905) (xy 107.157012 -281.251914)
			(xy 107.183852 -281.260821) (xy 107.234522 -281.285921) (xy 107.280588 -281.318716) (xy 107.320891 -281.35838)
			(xy 107.354417 -281.403917) (xy 107.380323 -281.45418) (xy 107.397958 -281.507907) (xy 107.406878 -281.563746)
			(xy 107.407456 -281.59202) (xy 107.406932 -281.618669) (xy 113.274084 -281.618669) (xy 113.274084 -281.565371)
			(xy 113.282027 -281.512667) (xy 113.297737 -281.461737) (xy 113.320863 -281.413716) (xy 113.350887 -281.369679)
			(xy 113.387139 -281.330608) (xy 113.42881 -281.297377) (xy 113.474968 -281.270728) (xy 113.524582 -281.251256)
			(xy 113.576544 -281.239396) (xy 113.629694 -281.235413) (xy 113.682844 -281.239396) (xy 113.734806 -281.251256)
			(xy 113.78442 -281.270728) (xy 113.830578 -281.297377) (xy 113.872249 -281.330608) (xy 113.908501 -281.369679)
			(xy 113.938525 -281.413716) (xy 113.961651 -281.461737) (xy 113.977361 -281.512667) (xy 113.985304 -281.565371)
			(xy 113.985802 -281.59202) (xy 113.985304 -281.618669) (xy 113.977361 -281.671373) (xy 113.961651 -281.722303)
			(xy 113.938525 -281.770324) (xy 113.908501 -281.814361) (xy 113.872249 -281.853432) (xy 113.830578 -281.886663)
			(xy 113.78442 -281.913312) (xy 113.734806 -281.932784) (xy 113.682844 -281.944644) (xy 113.629694 -281.948628)
			(xy 113.576544 -281.944644) (xy 113.524582 -281.932784) (xy 113.474968 -281.913312) (xy 113.42881 -281.886663)
			(xy 113.387139 -281.853432) (xy 113.350887 -281.814361) (xy 113.320863 -281.770324) (xy 113.297737 -281.722303)
			(xy 113.282027 -281.671373) (xy 113.274084 -281.618669) (xy 107.406932 -281.618669) (xy 107.406906 -281.620003)
			(xy 107.398148 -281.675281) (xy 107.380853 -281.728508) (xy 107.355444 -281.778375) (xy 107.322549 -281.823654)
			(xy 107.282976 -281.86323) (xy 107.237699 -281.89613) (xy 107.187834 -281.921542) (xy 107.134608 -281.938842)
			(xy 107.079331 -281.947603) (xy 107.051348 -281.948128) (xy 107.023075 -281.947581) (xy 106.967241 -281.93864)
			(xy 106.91352 -281.920991) (xy 106.863262 -281.895076) (xy 106.817729 -281.861547) (xy 106.778065 -281.821246)
			(xy 106.745266 -281.775185) (xy 106.720155 -281.724521) (xy 106.711242 -281.697684) (xy 106.706313 -281.683584)
			(xy 106.689585 -281.658854) (xy 106.666419 -281.640021) (xy 106.638794 -281.628696) (xy 106.609074 -281.625848)
			(xy 106.579801 -281.63172) (xy 106.553479 -281.64581) (xy 106.542586 -281.656028) (xy 106.437176 -281.761438)
			(xy 106.603546 -282.049474) (xy 106.628184 -282.052776) (xy 106.653532 -282.056594) (xy 106.702852 -282.070562)
			(xy 106.749659 -282.091458) (xy 106.792986 -282.118852) (xy 106.831936 -282.152176) (xy 106.865704 -282.190742)
			(xy 106.893592 -282.233751) (xy 106.915024 -282.280316) (xy 106.929556 -282.329473) (xy 106.936888 -282.380206)
			(xy 106.937302 -282.405836) (xy 106.936804 -282.432485) (xy 107.165384 -282.432485) (xy 107.165384 -282.379187)
			(xy 107.173327 -282.326483) (xy 107.189037 -282.275553) (xy 107.212163 -282.227532) (xy 107.242187 -282.183495)
			(xy 107.278439 -282.144424) (xy 107.32011 -282.111193) (xy 107.366268 -282.084544) (xy 107.415882 -282.065072)
			(xy 107.467844 -282.053212) (xy 107.520994 -282.049229) (xy 107.574144 -282.053212) (xy 107.626106 -282.065072)
			(xy 107.67572 -282.084544) (xy 107.721878 -282.111193) (xy 107.763549 -282.144424) (xy 107.799801 -282.183495)
			(xy 107.829825 -282.227532) (xy 107.852951 -282.275553) (xy 107.868661 -282.326483) (xy 107.876604 -282.379187)
			(xy 107.877102 -282.405836) (xy 107.876604 -282.432485) (xy 109.984784 -282.432485) (xy 109.984784 -282.379187)
			(xy 109.992727 -282.326483) (xy 110.008437 -282.275553) (xy 110.031563 -282.227532) (xy 110.061587 -282.183495)
			(xy 110.097839 -282.144424) (xy 110.13951 -282.111193) (xy 110.185668 -282.084544) (xy 110.235282 -282.065072)
			(xy 110.287244 -282.053212) (xy 110.340394 -282.049229) (xy 110.393544 -282.053212) (xy 110.445506 -282.065072)
			(xy 110.49512 -282.084544) (xy 110.541278 -282.111193) (xy 110.582949 -282.144424) (xy 110.619201 -282.183495)
			(xy 110.649225 -282.227532) (xy 110.672351 -282.275553) (xy 110.688061 -282.326483) (xy 110.696004 -282.379187)
			(xy 110.696502 -282.405836) (xy 110.696004 -282.432485) (xy 110.688061 -282.485189) (xy 110.672351 -282.536119)
			(xy 110.649225 -282.58414) (xy 110.619201 -282.628177) (xy 110.582949 -282.667248) (xy 110.541278 -282.700479)
			(xy 110.49512 -282.727128) (xy 110.445506 -282.7466) (xy 110.393544 -282.75846) (xy 110.340394 -282.762444)
			(xy 110.287244 -282.75846) (xy 110.235282 -282.7466) (xy 110.185668 -282.727128) (xy 110.13951 -282.700479)
			(xy 110.097839 -282.667248) (xy 110.061587 -282.628177) (xy 110.031563 -282.58414) (xy 110.008437 -282.536119)
			(xy 109.992727 -282.485189) (xy 109.984784 -282.432485) (xy 107.876604 -282.432485) (xy 107.868661 -282.485189)
			(xy 107.852951 -282.536119) (xy 107.829825 -282.58414) (xy 107.799801 -282.628177) (xy 107.763549 -282.667248)
			(xy 107.721878 -282.700479) (xy 107.67572 -282.727128) (xy 107.626106 -282.7466) (xy 107.574144 -282.75846)
			(xy 107.520994 -282.762444) (xy 107.467844 -282.75846) (xy 107.415882 -282.7466) (xy 107.366268 -282.727128)
			(xy 107.32011 -282.700479) (xy 107.278439 -282.667248) (xy 107.242187 -282.628177) (xy 107.212163 -282.58414)
			(xy 107.189037 -282.536119) (xy 107.173327 -282.485189) (xy 107.165384 -282.432485) (xy 106.936804 -282.432485)
			(xy 106.928861 -282.485189) (xy 106.913151 -282.536119) (xy 106.890025 -282.58414) (xy 106.860001 -282.628177)
			(xy 106.823749 -282.667248) (xy 106.782078 -282.700479) (xy 106.73592 -282.727128) (xy 106.686306 -282.7466)
			(xy 106.634344 -282.75846) (xy 106.581194 -282.762444) (xy 106.528044 -282.75846) (xy 106.476082 -282.7466)
			(xy 106.426468 -282.727128) (xy 106.38031 -282.700479) (xy 106.338639 -282.667248) (xy 106.302387 -282.628177)
			(xy 106.272363 -282.58414) (xy 106.249237 -282.536119) (xy 106.233527 -282.485189) (xy 106.225584 -282.432485)
			(xy 106.225086 -282.405836) (xy 106.225459 -282.382591) (xy 106.231499 -282.336494) (xy 106.243482 -282.291574)
			(xy 106.25201 -282.269946) (xy 106.261662 -282.246832) (xy 106.214418 -282.165044) (xy 106.207376 -282.153742)
			(xy 106.18854 -282.134934) (xy 106.165485 -282.121631) (xy 106.139775 -282.114737) (xy 106.113156 -282.114719)
			(xy 106.087437 -282.12158) (xy 106.064364 -282.134854) (xy 106.054652 -282.143962) (xy 105.958386 -282.240228)
			(xy 105.971086 -282.27147) (xy 105.979438 -282.292876) (xy 105.991187 -282.337297) (xy 105.997122 -282.382862)
			(xy 105.997502 -282.405836) (xy 105.997055 -282.431451) (xy 105.989713 -282.482152) (xy 105.975185 -282.531279)
			(xy 105.95377 -282.577819) (xy 105.925911 -282.620812) (xy 105.892182 -282.659372) (xy 105.853278 -282.692704)
			(xy 105.810001 -282.72012) (xy 105.763244 -282.741055) (xy 105.71397 -282.755078) (xy 105.688638 -282.758896)
			(xy 105.664 -282.762198) (xy 105.49128 -283.060902) (xy 105.500932 -283.084016) (xy 105.50945 -283.105648)
			(xy 105.521441 -283.150565) (xy 105.527488 -283.196661) (xy 105.527856 -283.219906) (xy 105.527333 -283.246555)
			(xy 105.755684 -283.246555) (xy 105.755684 -283.193257) (xy 105.763627 -283.140553) (xy 105.779337 -283.089623)
			(xy 105.802463 -283.041602) (xy 105.832487 -282.997565) (xy 105.868739 -282.958494) (xy 105.91041 -282.925263)
			(xy 105.956568 -282.898614) (xy 106.006182 -282.879142) (xy 106.058144 -282.867282) (xy 106.111294 -282.863299)
			(xy 106.164444 -282.867282) (xy 106.216406 -282.879142) (xy 106.26602 -282.898614) (xy 106.312178 -282.925263)
			(xy 106.353849 -282.958494) (xy 106.390101 -282.997565) (xy 106.420125 -283.041602) (xy 106.443251 -283.089623)
			(xy 106.458961 -283.140553) (xy 106.466904 -283.193257) (xy 106.467402 -283.219906) (xy 106.466904 -283.246555)
			(xy 106.695738 -283.246555) (xy 106.695738 -283.193257) (xy 106.703681 -283.140553) (xy 106.719391 -283.089623)
			(xy 106.742517 -283.041602) (xy 106.772541 -282.997565) (xy 106.808793 -282.958494) (xy 106.850464 -282.925263)
			(xy 106.896622 -282.898614) (xy 106.946236 -282.879142) (xy 106.998198 -282.867282) (xy 107.051348 -282.863299)
			(xy 107.104498 -282.867282) (xy 107.15646 -282.879142) (xy 107.206074 -282.898614) (xy 107.252232 -282.925263)
			(xy 107.293903 -282.958494) (xy 107.330155 -282.997565) (xy 107.360179 -283.041602) (xy 107.383305 -283.089623)
			(xy 107.399015 -283.140553) (xy 107.406958 -283.193257) (xy 107.407456 -283.219906) (xy 107.406958 -283.246555)
			(xy 113.274084 -283.246555) (xy 113.274084 -283.193257) (xy 113.282027 -283.140553) (xy 113.297737 -283.089623)
			(xy 113.320863 -283.041602) (xy 113.350887 -282.997565) (xy 113.387139 -282.958494) (xy 113.42881 -282.925263)
			(xy 113.474968 -282.898614) (xy 113.524582 -282.879142) (xy 113.576544 -282.867282) (xy 113.629694 -282.863299)
			(xy 113.682844 -282.867282) (xy 113.734806 -282.879142) (xy 113.78442 -282.898614) (xy 113.830578 -282.925263)
			(xy 113.872249 -282.958494) (xy 113.908501 -282.997565) (xy 113.938525 -283.041602) (xy 113.961651 -283.089623)
			(xy 113.977361 -283.140553) (xy 113.985304 -283.193257) (xy 113.985802 -283.219906) (xy 113.985304 -283.246555)
			(xy 116.093738 -283.246555) (xy 116.093738 -283.193257) (xy 116.101681 -283.140553) (xy 116.117391 -283.089623)
			(xy 116.140517 -283.041602) (xy 116.170541 -282.997565) (xy 116.206793 -282.958494) (xy 116.248464 -282.925263)
			(xy 116.294622 -282.898614) (xy 116.344236 -282.879142) (xy 116.396198 -282.867282) (xy 116.449348 -282.863299)
			(xy 116.502498 -282.867282) (xy 116.55446 -282.879142) (xy 116.604074 -282.898614) (xy 116.650232 -282.925263)
			(xy 116.691903 -282.958494) (xy 116.728155 -282.997565) (xy 116.758179 -283.041602) (xy 116.781305 -283.089623)
			(xy 116.797015 -283.140553) (xy 116.804958 -283.193257) (xy 116.805456 -283.219906) (xy 116.804958 -283.246555)
			(xy 116.797015 -283.299259) (xy 116.781305 -283.350189) (xy 116.758179 -283.39821) (xy 116.728155 -283.442247)
			(xy 116.691903 -283.481318) (xy 116.650232 -283.514549) (xy 116.604074 -283.541198) (xy 116.55446 -283.56067)
			(xy 116.502498 -283.57253) (xy 116.449348 -283.576514) (xy 116.396198 -283.57253) (xy 116.344236 -283.56067)
			(xy 116.294622 -283.541198) (xy 116.248464 -283.514549) (xy 116.206793 -283.481318) (xy 116.170541 -283.442247)
			(xy 116.140517 -283.39821) (xy 116.117391 -283.350189) (xy 116.101681 -283.299259) (xy 116.093738 -283.246555)
			(xy 113.985304 -283.246555) (xy 113.977361 -283.299259) (xy 113.961651 -283.350189) (xy 113.938525 -283.39821)
			(xy 113.908501 -283.442247) (xy 113.872249 -283.481318) (xy 113.830578 -283.514549) (xy 113.78442 -283.541198)
			(xy 113.734806 -283.56067) (xy 113.682844 -283.57253) (xy 113.629694 -283.576514) (xy 113.576544 -283.57253)
			(xy 113.524582 -283.56067) (xy 113.474968 -283.541198) (xy 113.42881 -283.514549) (xy 113.387139 -283.481318)
			(xy 113.350887 -283.442247) (xy 113.320863 -283.39821) (xy 113.297737 -283.350189) (xy 113.282027 -283.299259)
			(xy 113.274084 -283.246555) (xy 107.406958 -283.246555) (xy 107.399015 -283.299259) (xy 107.383305 -283.350189)
			(xy 107.360179 -283.39821) (xy 107.330155 -283.442247) (xy 107.293903 -283.481318) (xy 107.252232 -283.514549)
			(xy 107.206074 -283.541198) (xy 107.15646 -283.56067) (xy 107.104498 -283.57253) (xy 107.051348 -283.576514)
			(xy 106.998198 -283.57253) (xy 106.946236 -283.56067) (xy 106.896622 -283.541198) (xy 106.850464 -283.514549)
			(xy 106.808793 -283.481318) (xy 106.772541 -283.442247) (xy 106.742517 -283.39821) (xy 106.719391 -283.350189)
			(xy 106.703681 -283.299259) (xy 106.695738 -283.246555) (xy 106.466904 -283.246555) (xy 106.458961 -283.299259)
			(xy 106.443251 -283.350189) (xy 106.420125 -283.39821) (xy 106.390101 -283.442247) (xy 106.353849 -283.481318)
			(xy 106.312178 -283.514549) (xy 106.26602 -283.541198) (xy 106.216406 -283.56067) (xy 106.164444 -283.57253)
			(xy 106.111294 -283.576514) (xy 106.058144 -283.57253) (xy 106.006182 -283.56067) (xy 105.956568 -283.541198)
			(xy 105.91041 -283.514549) (xy 105.868739 -283.481318) (xy 105.832487 -283.442247) (xy 105.802463 -283.39821)
			(xy 105.779337 -283.350189) (xy 105.763627 -283.299259) (xy 105.755684 -283.246555) (xy 105.527333 -283.246555)
			(xy 105.527307 -283.24789) (xy 105.518551 -283.303169) (xy 105.501257 -283.356399) (xy 105.475849 -283.406268)
			(xy 105.442954 -283.451548) (xy 105.40338 -283.491126) (xy 105.358103 -283.524027) (xy 105.308238 -283.549441)
			(xy 105.25501 -283.566741) (xy 105.199732 -283.575503) (xy 105.171748 -283.576014) (xy 105.146168 -283.575568)
			(xy 105.095535 -283.56824) (xy 105.046472 -283.553741) (xy 104.999989 -283.532371) (xy 104.957043 -283.504568)
			(xy 104.918516 -283.470906) (xy 104.901492 -283.451808) (xy 104.892085 -283.441478) (xy 104.868858 -283.425969)
			(xy 104.842293 -283.417347) (xy 104.814385 -283.416257) (xy 104.78723 -283.422782) (xy 104.762864 -283.436433)
			(xy 104.752648 -283.445966) (xy 104.690418 -283.508196) (xy 104.680737 -283.518516) (xy 104.666978 -283.54323)
			(xy 104.660537 -283.570772) (xy 104.661909 -283.599025) (xy 104.670988 -283.625813) (xy 104.687077 -283.649078)
			(xy 104.708937 -283.667028) (xy 104.734886 -283.678283) (xy 104.748838 -283.680662) (xy 104.774171 -283.684496)
			(xy 104.823457 -283.698491) (xy 104.870228 -283.719408) (xy 104.913517 -283.746813) (xy 104.95243 -283.780142)
			(xy 104.986163 -283.818705) (xy 105.014018 -283.861706) (xy 105.035421 -283.908256) (xy 105.049929 -283.957394)
			(xy 105.057243 -284.008104) (xy 105.057702 -284.033722) (xy 105.057177 -284.060371) (xy 105.285784 -284.060371)
			(xy 105.285784 -284.007073) (xy 105.293727 -283.954369) (xy 105.309437 -283.903439) (xy 105.332563 -283.855418)
			(xy 105.362587 -283.811381) (xy 105.398839 -283.77231) (xy 105.44051 -283.739079) (xy 105.486668 -283.71243)
			(xy 105.536282 -283.692958) (xy 105.588244 -283.681098) (xy 105.641394 -283.677115) (xy 105.694544 -283.681098)
			(xy 105.746506 -283.692958) (xy 105.79612 -283.71243) (xy 105.842278 -283.739079) (xy 105.883949 -283.77231)
			(xy 105.920201 -283.811381) (xy 105.950225 -283.855418) (xy 105.973351 -283.903439) (xy 105.989061 -283.954369)
			(xy 105.997004 -284.007073) (xy 105.997502 -284.033722) (xy 105.997004 -284.060371) (xy 107.165384 -284.060371)
			(xy 107.165384 -284.007073) (xy 107.173327 -283.954369) (xy 107.189037 -283.903439) (xy 107.212163 -283.855418)
			(xy 107.242187 -283.811381) (xy 107.278439 -283.77231) (xy 107.32011 -283.739079) (xy 107.366268 -283.71243)
			(xy 107.415882 -283.692958) (xy 107.467844 -283.681098) (xy 107.520994 -283.677115) (xy 107.574144 -283.681098)
			(xy 107.626106 -283.692958) (xy 107.67572 -283.71243) (xy 107.721878 -283.739079) (xy 107.763549 -283.77231)
			(xy 107.799801 -283.811381) (xy 107.829825 -283.855418) (xy 107.852951 -283.903439) (xy 107.868661 -283.954369)
			(xy 107.876604 -284.007073) (xy 107.877102 -284.033722) (xy 107.876604 -284.060371) (xy 109.984784 -284.060371)
			(xy 109.984784 -284.007073) (xy 109.992727 -283.954369) (xy 110.008437 -283.903439) (xy 110.031563 -283.855418)
			(xy 110.061587 -283.811381) (xy 110.097839 -283.77231) (xy 110.13951 -283.739079) (xy 110.185668 -283.71243)
			(xy 110.235282 -283.692958) (xy 110.287244 -283.681098) (xy 110.340394 -283.677115) (xy 110.393544 -283.681098)
			(xy 110.445506 -283.692958) (xy 110.49512 -283.71243) (xy 110.541278 -283.739079) (xy 110.582949 -283.77231)
			(xy 110.619201 -283.811381) (xy 110.649225 -283.855418) (xy 110.672351 -283.903439) (xy 110.688061 -283.954369)
			(xy 110.696004 -284.007073) (xy 110.696502 -284.033722) (xy 110.696004 -284.060371) (xy 110.688061 -284.113075)
			(xy 110.672351 -284.164005) (xy 110.649225 -284.212026) (xy 110.619201 -284.256063) (xy 110.582949 -284.295134)
			(xy 110.541278 -284.328365) (xy 110.49512 -284.355014) (xy 110.445506 -284.374486) (xy 110.393544 -284.386346)
			(xy 110.340394 -284.39033) (xy 110.287244 -284.386346) (xy 110.235282 -284.374486) (xy 110.185668 -284.355014)
			(xy 110.13951 -284.328365) (xy 110.097839 -284.295134) (xy 110.061587 -284.256063) (xy 110.031563 -284.212026)
			(xy 110.008437 -284.164005) (xy 109.992727 -284.113075) (xy 109.984784 -284.060371) (xy 107.876604 -284.060371)
			(xy 107.868661 -284.113075) (xy 107.852951 -284.164005) (xy 107.829825 -284.212026) (xy 107.799801 -284.256063)
			(xy 107.763549 -284.295134) (xy 107.721878 -284.328365) (xy 107.67572 -284.355014) (xy 107.626106 -284.374486)
			(xy 107.574144 -284.386346) (xy 107.520994 -284.39033) (xy 107.467844 -284.386346) (xy 107.415882 -284.374486)
			(xy 107.366268 -284.355014) (xy 107.32011 -284.328365) (xy 107.278439 -284.295134) (xy 107.242187 -284.256063)
			(xy 107.212163 -284.212026) (xy 107.189037 -284.164005) (xy 107.173327 -284.113075) (xy 107.165384 -284.060371)
			(xy 105.997004 -284.060371) (xy 105.989061 -284.113075) (xy 105.973351 -284.164005) (xy 105.950225 -284.212026)
			(xy 105.920201 -284.256063) (xy 105.883949 -284.295134) (xy 105.842278 -284.328365) (xy 105.79612 -284.355014)
			(xy 105.746506 -284.374486) (xy 105.694544 -284.386346) (xy 105.641394 -284.39033) (xy 105.588244 -284.386346)
			(xy 105.536282 -284.374486) (xy 105.486668 -284.355014) (xy 105.44051 -284.328365) (xy 105.398839 -284.295134)
			(xy 105.362587 -284.256063) (xy 105.332563 -284.212026) (xy 105.309437 -284.164005) (xy 105.293727 -284.113075)
			(xy 105.285784 -284.060371) (xy 105.057177 -284.060371) (xy 105.057151 -284.061704) (xy 105.048394 -284.116978)
			(xy 105.031097 -284.170202) (xy 105.005688 -284.220064) (xy 104.972791 -284.265339) (xy 104.933217 -284.304909)
			(xy 104.887941 -284.337802) (xy 104.838076 -284.363208) (xy 104.784851 -284.3805) (xy 104.729576 -284.389254)
			(xy 104.701594 -284.38983) (xy 104.675432 -284.388814) (xy 104.6615 -284.388241) (xy 104.63419 -284.393824)
			(xy 104.609409 -284.406588) (xy 104.589005 -284.425579) (xy 104.5745 -284.449383) (xy 104.566975 -284.476222)
			(xy 104.566466 -284.49016) (xy 104.566466 -284.72511) (xy 104.56926 -284.732984) (xy 104.578071 -284.760798)
			(xy 104.587518 -284.818367) (xy 104.588056 -284.847538) (xy 104.587542 -284.874187) (xy 104.815884 -284.874187)
			(xy 104.815884 -284.820889) (xy 104.823827 -284.768185) (xy 104.839537 -284.717255) (xy 104.862663 -284.669234)
			(xy 104.892687 -284.625197) (xy 104.928939 -284.586126) (xy 104.97061 -284.552895) (xy 105.016768 -284.526246)
			(xy 105.066382 -284.506774) (xy 105.118344 -284.494914) (xy 105.171494 -284.490931) (xy 105.224644 -284.494914)
			(xy 105.276606 -284.506774) (xy 105.32622 -284.526246) (xy 105.372378 -284.552895) (xy 105.414049 -284.586126)
			(xy 105.450301 -284.625197) (xy 105.480325 -284.669234) (xy 105.503451 -284.717255) (xy 105.519161 -284.768185)
			(xy 105.527104 -284.820889) (xy 105.527602 -284.847538) (xy 105.527104 -284.874187) (xy 113.274084 -284.874187)
			(xy 113.274084 -284.820889) (xy 113.282027 -284.768185) (xy 113.297737 -284.717255) (xy 113.320863 -284.669234)
			(xy 113.350887 -284.625197) (xy 113.387139 -284.586126) (xy 113.42881 -284.552895) (xy 113.474968 -284.526246)
			(xy 113.524582 -284.506774) (xy 113.576544 -284.494914) (xy 113.629694 -284.490931) (xy 113.682844 -284.494914)
			(xy 113.734806 -284.506774) (xy 113.78442 -284.526246) (xy 113.830578 -284.552895) (xy 113.872249 -284.586126)
			(xy 113.908501 -284.625197) (xy 113.938525 -284.669234) (xy 113.961651 -284.717255) (xy 113.977361 -284.768185)
			(xy 113.985304 -284.820889) (xy 113.985802 -284.847538) (xy 113.985304 -284.874187) (xy 116.093738 -284.874187)
			(xy 116.093738 -284.820889) (xy 116.101681 -284.768185) (xy 116.117391 -284.717255) (xy 116.140517 -284.669234)
			(xy 116.170541 -284.625197) (xy 116.206793 -284.586126) (xy 116.248464 -284.552895) (xy 116.294622 -284.526246)
			(xy 116.344236 -284.506774) (xy 116.396198 -284.494914) (xy 116.449348 -284.490931) (xy 116.502498 -284.494914)
			(xy 116.55446 -284.506774) (xy 116.604074 -284.526246) (xy 116.650232 -284.552895) (xy 116.691903 -284.586126)
			(xy 116.728155 -284.625197) (xy 116.758179 -284.669234) (xy 116.781305 -284.717255) (xy 116.797015 -284.768185)
			(xy 116.804958 -284.820889) (xy 116.805456 -284.847538) (xy 116.804958 -284.874187) (xy 117.973338 -284.874187)
			(xy 117.973338 -284.820889) (xy 117.981281 -284.768185) (xy 117.996991 -284.717255) (xy 118.020117 -284.669234)
			(xy 118.050141 -284.625197) (xy 118.086393 -284.586126) (xy 118.128064 -284.552895) (xy 118.174222 -284.526246)
			(xy 118.223836 -284.506774) (xy 118.275798 -284.494914) (xy 118.328948 -284.490931) (xy 118.382098 -284.494914)
			(xy 118.43406 -284.506774) (xy 118.483674 -284.526246) (xy 118.529832 -284.552895) (xy 118.571503 -284.586126)
			(xy 118.607755 -284.625197) (xy 118.637779 -284.669234) (xy 118.660905 -284.717255) (xy 118.676615 -284.768185)
			(xy 118.684558 -284.820889) (xy 118.685056 -284.847538) (xy 118.684558 -284.874187) (xy 118.676615 -284.926891)
			(xy 118.660905 -284.977821) (xy 118.637779 -285.025842) (xy 118.607755 -285.069879) (xy 118.571503 -285.10895)
			(xy 118.529832 -285.142181) (xy 118.483674 -285.16883) (xy 118.43406 -285.188302) (xy 118.382098 -285.200162)
			(xy 118.328948 -285.204146) (xy 118.275798 -285.200162) (xy 118.223836 -285.188302) (xy 118.174222 -285.16883)
			(xy 118.128064 -285.142181) (xy 118.086393 -285.10895) (xy 118.050141 -285.069879) (xy 118.020117 -285.025842)
			(xy 117.996991 -284.977821) (xy 117.981281 -284.926891) (xy 117.973338 -284.874187) (xy 116.804958 -284.874187)
			(xy 116.797015 -284.926891) (xy 116.781305 -284.977821) (xy 116.758179 -285.025842) (xy 116.728155 -285.069879)
			(xy 116.691903 -285.10895) (xy 116.650232 -285.142181) (xy 116.604074 -285.16883) (xy 116.55446 -285.188302)
			(xy 116.502498 -285.200162) (xy 116.449348 -285.204146) (xy 116.396198 -285.200162) (xy 116.344236 -285.188302)
			(xy 116.294622 -285.16883) (xy 116.248464 -285.142181) (xy 116.206793 -285.10895) (xy 116.170541 -285.069879)
			(xy 116.140517 -285.025842) (xy 116.117391 -284.977821) (xy 116.101681 -284.926891) (xy 116.093738 -284.874187)
			(xy 113.985304 -284.874187) (xy 113.977361 -284.926891) (xy 113.961651 -284.977821) (xy 113.938525 -285.025842)
			(xy 113.908501 -285.069879) (xy 113.872249 -285.10895) (xy 113.830578 -285.142181) (xy 113.78442 -285.16883)
			(xy 113.734806 -285.188302) (xy 113.682844 -285.200162) (xy 113.629694 -285.204146) (xy 113.576544 -285.200162)
			(xy 113.524582 -285.188302) (xy 113.474968 -285.16883) (xy 113.42881 -285.142181) (xy 113.387139 -285.10895)
			(xy 113.350887 -285.069879) (xy 113.320863 -285.025842) (xy 113.297737 -284.977821) (xy 113.282027 -284.926891)
			(xy 113.274084 -284.874187) (xy 105.527104 -284.874187) (xy 105.519161 -284.926891) (xy 105.503451 -284.977821)
			(xy 105.480325 -285.025842) (xy 105.450301 -285.069879) (xy 105.414049 -285.10895) (xy 105.372378 -285.142181)
			(xy 105.32622 -285.16883) (xy 105.276606 -285.188302) (xy 105.224644 -285.200162) (xy 105.171494 -285.204146)
			(xy 105.118344 -285.200162) (xy 105.066382 -285.188302) (xy 105.016768 -285.16883) (xy 104.97061 -285.142181)
			(xy 104.928939 -285.10895) (xy 104.892687 -285.069879) (xy 104.862663 -285.025842) (xy 104.839537 -284.977821)
			(xy 104.823827 -284.926891) (xy 104.815884 -284.874187) (xy 104.587542 -284.874187) (xy 104.587493 -284.876707)
			(xy 104.578054 -284.934275) (xy 104.56926 -284.962092) (xy 104.566466 -284.969966) (xy 104.566466 -285.204916)
			(xy 104.566902 -285.218858) (xy 104.574446 -285.245702) (xy 104.588967 -285.269506) (xy 104.609385 -285.288497)
			(xy 104.634176 -285.301259) (xy 104.661496 -285.306843) (xy 104.675432 -285.306262) (xy 104.701594 -285.305246)
			(xy 104.728249 -285.305719) (xy 104.780963 -285.313664) (xy 104.831905 -285.329376) (xy 104.879936 -285.352506)
			(xy 104.923982 -285.382536) (xy 104.963062 -285.418795) (xy 104.9963 -285.460474) (xy 105.022955 -285.506642)
			(xy 105.042431 -285.556266) (xy 105.054294 -285.608239) (xy 105.058278 -285.6614) (xy 105.056284 -285.688003)
			(xy 107.165384 -285.688003) (xy 107.165384 -285.634705) (xy 107.173327 -285.582001) (xy 107.189037 -285.531071)
			(xy 107.212163 -285.48305) (xy 107.242187 -285.439013) (xy 107.278439 -285.399942) (xy 107.32011 -285.366711)
			(xy 107.366268 -285.340062) (xy 107.415882 -285.32059) (xy 107.467844 -285.30873) (xy 107.520994 -285.304747)
			(xy 107.574144 -285.30873) (xy 107.626106 -285.32059) (xy 107.67572 -285.340062) (xy 107.721878 -285.366711)
			(xy 107.763549 -285.399942) (xy 107.799801 -285.439013) (xy 107.829825 -285.48305) (xy 107.852951 -285.531071)
			(xy 107.868661 -285.582001) (xy 107.876604 -285.634705) (xy 107.877102 -285.661354) (xy 107.876604 -285.688003)
			(xy 109.984784 -285.688003) (xy 109.984784 -285.634705) (xy 109.992727 -285.582001) (xy 110.008437 -285.531071)
			(xy 110.031563 -285.48305) (xy 110.061587 -285.439013) (xy 110.097839 -285.399942) (xy 110.13951 -285.366711)
			(xy 110.185668 -285.340062) (xy 110.235282 -285.32059) (xy 110.287244 -285.30873) (xy 110.340394 -285.304747)
			(xy 110.393544 -285.30873) (xy 110.445506 -285.32059) (xy 110.49512 -285.340062) (xy 110.541278 -285.366711)
			(xy 110.582949 -285.399942) (xy 110.619201 -285.439013) (xy 110.649225 -285.48305) (xy 110.672351 -285.531071)
			(xy 110.688061 -285.582001) (xy 110.696004 -285.634705) (xy 110.696502 -285.661354) (xy 110.696004 -285.688003)
			(xy 118.443238 -285.688003) (xy 118.443238 -285.634705) (xy 118.451181 -285.582001) (xy 118.466891 -285.531071)
			(xy 118.490017 -285.48305) (xy 118.520041 -285.439013) (xy 118.556293 -285.399942) (xy 118.597964 -285.366711)
			(xy 118.644122 -285.340062) (xy 118.693736 -285.32059) (xy 118.745698 -285.30873) (xy 118.798848 -285.304747)
			(xy 118.851998 -285.30873) (xy 118.90396 -285.32059) (xy 118.953574 -285.340062) (xy 118.999732 -285.366711)
			(xy 119.041403 -285.399942) (xy 119.077655 -285.439013) (xy 119.107679 -285.48305) (xy 119.130805 -285.531071)
			(xy 119.146515 -285.582001) (xy 119.154458 -285.634705) (xy 119.154956 -285.661354) (xy 119.154458 -285.688003)
			(xy 119.146515 -285.740707) (xy 119.130805 -285.791637) (xy 119.107679 -285.839658) (xy 119.077655 -285.883695)
			(xy 119.041403 -285.922766) (xy 118.999732 -285.955997) (xy 118.953574 -285.982646) (xy 118.90396 -286.002118)
			(xy 118.851998 -286.013978) (xy 118.798848 -286.017962) (xy 118.745698 -286.013978) (xy 118.693736 -286.002118)
			(xy 118.644122 -285.982646) (xy 118.597964 -285.955997) (xy 118.556293 -285.922766) (xy 118.520041 -285.883695)
			(xy 118.490017 -285.839658) (xy 118.466891 -285.791637) (xy 118.451181 -285.740707) (xy 118.443238 -285.688003)
			(xy 110.696004 -285.688003) (xy 110.688061 -285.740707) (xy 110.672351 -285.791637) (xy 110.649225 -285.839658)
			(xy 110.619201 -285.883695) (xy 110.582949 -285.922766) (xy 110.541278 -285.955997) (xy 110.49512 -285.982646)
			(xy 110.445506 -286.002118) (xy 110.393544 -286.013978) (xy 110.340394 -286.017962) (xy 110.287244 -286.013978)
			(xy 110.235282 -286.002118) (xy 110.185668 -285.982646) (xy 110.13951 -285.955997) (xy 110.097839 -285.922766)
			(xy 110.061587 -285.883695) (xy 110.031563 -285.839658) (xy 110.008437 -285.791637) (xy 109.992727 -285.740707)
			(xy 109.984784 -285.688003) (xy 107.876604 -285.688003) (xy 107.868661 -285.740707) (xy 107.852951 -285.791637)
			(xy 107.829825 -285.839658) (xy 107.799801 -285.883695) (xy 107.763549 -285.922766) (xy 107.721878 -285.955997)
			(xy 107.67572 -285.982646) (xy 107.626106 -286.002118) (xy 107.574144 -286.013978) (xy 107.520994 -286.017962)
			(xy 107.467844 -286.013978) (xy 107.415882 -286.002118) (xy 107.366268 -285.982646) (xy 107.32011 -285.955997)
			(xy 107.278439 -285.922766) (xy 107.242187 -285.883695) (xy 107.212163 -285.839658) (xy 107.189037 -285.791637)
			(xy 107.173327 -285.740707) (xy 107.165384 -285.688003) (xy 105.056284 -285.688003) (xy 105.054294 -285.714561)
			(xy 105.042431 -285.766534) (xy 105.022955 -285.816158) (xy 104.9963 -285.862326) (xy 104.963062 -285.904005)
			(xy 104.923982 -285.940264) (xy 104.879936 -285.970294) (xy 104.831905 -285.993424) (xy 104.780963 -286.009136)
			(xy 104.728249 -286.017081) (xy 104.701594 -286.017462) (xy 104.675432 -286.016446) (xy 104.661496 -286.015872)
			(xy 104.63418 -286.021455) (xy 104.609391 -286.034217) (xy 104.588976 -286.053207) (xy 104.574457 -286.077009)
			(xy 104.566916 -286.103851) (xy 104.566466 -286.117792) (xy 104.566466 -286.353758) (xy 104.569006 -286.361632)
			(xy 104.577744 -286.389266) (xy 104.587185 -286.446447) (xy 104.587802 -286.475424) (xy 104.587263 -286.502073)
			(xy 104.816138 -286.502073) (xy 104.816138 -286.448775) (xy 104.824081 -286.396071) (xy 104.839791 -286.345141)
			(xy 104.862917 -286.29712) (xy 104.892941 -286.253083) (xy 104.929193 -286.214012) (xy 104.970864 -286.180781)
			(xy 105.017022 -286.154132) (xy 105.066636 -286.13466) (xy 105.118598 -286.1228) (xy 105.171748 -286.118817)
			(xy 105.224898 -286.1228) (xy 105.27686 -286.13466) (xy 105.326474 -286.154132) (xy 105.372632 -286.180781)
			(xy 105.414303 -286.214012) (xy 105.450555 -286.253083) (xy 105.480579 -286.29712) (xy 105.503705 -286.345141)
			(xy 105.519415 -286.396071) (xy 105.527358 -286.448775) (xy 105.527856 -286.475424) (xy 105.527358 -286.502073)
			(xy 113.274084 -286.502073) (xy 113.274084 -286.448775) (xy 113.282027 -286.396071) (xy 113.297737 -286.345141)
			(xy 113.320863 -286.29712) (xy 113.350887 -286.253083) (xy 113.387139 -286.214012) (xy 113.42881 -286.180781)
			(xy 113.474968 -286.154132) (xy 113.524582 -286.13466) (xy 113.576544 -286.1228) (xy 113.629694 -286.118817)
			(xy 113.682844 -286.1228) (xy 113.734806 -286.13466) (xy 113.78442 -286.154132) (xy 113.830578 -286.180781)
			(xy 113.872249 -286.214012) (xy 113.908501 -286.253083) (xy 113.938525 -286.29712) (xy 113.961651 -286.345141)
			(xy 113.977361 -286.396071) (xy 113.985304 -286.448775) (xy 113.985802 -286.475424) (xy 113.985304 -286.502073)
			(xy 116.093738 -286.502073) (xy 116.093738 -286.448775) (xy 116.101681 -286.396071) (xy 116.117391 -286.345141)
			(xy 116.140517 -286.29712) (xy 116.170541 -286.253083) (xy 116.206793 -286.214012) (xy 116.248464 -286.180781)
			(xy 116.294622 -286.154132) (xy 116.344236 -286.13466) (xy 116.396198 -286.1228) (xy 116.449348 -286.118817)
			(xy 116.502498 -286.1228) (xy 116.55446 -286.13466) (xy 116.604074 -286.154132) (xy 116.650232 -286.180781)
			(xy 116.691903 -286.214012) (xy 116.728155 -286.253083) (xy 116.758179 -286.29712) (xy 116.781305 -286.345141)
			(xy 116.797015 -286.396071) (xy 116.804958 -286.448775) (xy 116.805456 -286.475424) (xy 116.804958 -286.502073)
			(xy 116.797015 -286.554777) (xy 116.781305 -286.605707) (xy 116.758179 -286.653728) (xy 116.728155 -286.697765)
			(xy 116.691903 -286.736836) (xy 116.650232 -286.770067) (xy 116.604074 -286.796716) (xy 116.55446 -286.816188)
			(xy 116.502498 -286.828048) (xy 116.449348 -286.832032) (xy 116.396198 -286.828048) (xy 116.344236 -286.816188)
			(xy 116.294622 -286.796716) (xy 116.248464 -286.770067) (xy 116.206793 -286.736836) (xy 116.170541 -286.697765)
			(xy 116.140517 -286.653728) (xy 116.117391 -286.605707) (xy 116.101681 -286.554777) (xy 116.093738 -286.502073)
			(xy 113.985304 -286.502073) (xy 113.977361 -286.554777) (xy 113.961651 -286.605707) (xy 113.938525 -286.653728)
			(xy 113.908501 -286.697765) (xy 113.872249 -286.736836) (xy 113.830578 -286.770067) (xy 113.78442 -286.796716)
			(xy 113.734806 -286.816188) (xy 113.682844 -286.828048) (xy 113.629694 -286.832032) (xy 113.576544 -286.828048)
			(xy 113.524582 -286.816188) (xy 113.474968 -286.796716) (xy 113.42881 -286.770067) (xy 113.387139 -286.736836)
			(xy 113.350887 -286.697765) (xy 113.320863 -286.653728) (xy 113.297737 -286.605707) (xy 113.282027 -286.554777)
			(xy 113.274084 -286.502073) (xy 105.527358 -286.502073) (xy 105.519415 -286.554777) (xy 105.503705 -286.605707)
			(xy 105.480579 -286.653728) (xy 105.450555 -286.697765) (xy 105.414303 -286.736836) (xy 105.372632 -286.770067)
			(xy 105.326474 -286.796716) (xy 105.27686 -286.816188) (xy 105.224898 -286.828048) (xy 105.171748 -286.832032)
			(xy 105.118598 -286.828048) (xy 105.066636 -286.816188) (xy 105.017022 -286.796716) (xy 104.970864 -286.770067)
			(xy 104.929193 -286.736836) (xy 104.892941 -286.697765) (xy 104.862917 -286.653728) (xy 104.839791 -286.605707)
			(xy 104.824081 -286.554777) (xy 104.816138 -286.502073) (xy 104.587263 -286.502073) (xy 104.587216 -286.504403)
			(xy 104.577773 -286.561588) (xy 104.569006 -286.589216) (xy 104.566466 -286.59709) (xy 104.566466 -286.832802)
			(xy 104.5669 -286.846745) (xy 104.574441 -286.873593) (xy 104.588962 -286.8974) (xy 104.60938 -286.916394)
			(xy 104.634174 -286.929158) (xy 104.661495 -286.934743) (xy 104.675432 -286.934148) (xy 104.701848 -286.933132)
			(xy 104.728492 -286.933633) (xy 104.781184 -286.941582) (xy 104.832103 -286.957295) (xy 104.880111 -286.98042)
			(xy 104.924137 -287.010442) (xy 104.963198 -287.04669) (xy 104.99642 -287.088354) (xy 105.023062 -287.134504)
			(xy 105.042528 -287.184109) (xy 105.054385 -287.236061) (xy 105.058367 -287.2892) (xy 105.056367 -287.315889)
			(xy 107.165384 -287.315889) (xy 107.165384 -287.262591) (xy 107.173327 -287.209887) (xy 107.189037 -287.158957)
			(xy 107.212163 -287.110936) (xy 107.242187 -287.066899) (xy 107.278439 -287.027828) (xy 107.32011 -286.994597)
			(xy 107.366268 -286.967948) (xy 107.415882 -286.948476) (xy 107.467844 -286.936616) (xy 107.520994 -286.932633)
			(xy 107.574144 -286.936616) (xy 107.626106 -286.948476) (xy 107.67572 -286.967948) (xy 107.721878 -286.994597)
			(xy 107.763549 -287.027828) (xy 107.799801 -287.066899) (xy 107.829825 -287.110936) (xy 107.852951 -287.158957)
			(xy 107.868661 -287.209887) (xy 107.876604 -287.262591) (xy 107.877102 -287.28924) (xy 107.876604 -287.315889)
			(xy 109.984784 -287.315889) (xy 109.984784 -287.262591) (xy 109.992727 -287.209887) (xy 110.008437 -287.158957)
			(xy 110.031563 -287.110936) (xy 110.061587 -287.066899) (xy 110.097839 -287.027828) (xy 110.13951 -286.994597)
			(xy 110.185668 -286.967948) (xy 110.235282 -286.948476) (xy 110.287244 -286.936616) (xy 110.340394 -286.932633)
			(xy 110.393544 -286.936616) (xy 110.445506 -286.948476) (xy 110.49512 -286.967948) (xy 110.541278 -286.994597)
			(xy 110.582949 -287.027828) (xy 110.619201 -287.066899) (xy 110.649225 -287.110936) (xy 110.672351 -287.158957)
			(xy 110.688061 -287.209887) (xy 110.696004 -287.262591) (xy 110.696502 -287.28924) (xy 110.696004 -287.315889)
			(xy 110.688061 -287.368593) (xy 110.672351 -287.419523) (xy 110.649225 -287.467544) (xy 110.619201 -287.511581)
			(xy 110.582949 -287.550652) (xy 110.541278 -287.583883) (xy 110.49512 -287.610532) (xy 110.445506 -287.630004)
			(xy 110.393544 -287.641864) (xy 110.340394 -287.645848) (xy 110.287244 -287.641864) (xy 110.235282 -287.630004)
			(xy 110.185668 -287.610532) (xy 110.13951 -287.583883) (xy 110.097839 -287.550652) (xy 110.061587 -287.511581)
			(xy 110.031563 -287.467544) (xy 110.008437 -287.419523) (xy 109.992727 -287.368593) (xy 109.984784 -287.315889)
			(xy 107.876604 -287.315889) (xy 107.868661 -287.368593) (xy 107.852951 -287.419523) (xy 107.829825 -287.467544)
			(xy 107.799801 -287.511581) (xy 107.763549 -287.550652) (xy 107.721878 -287.583883) (xy 107.67572 -287.610532)
			(xy 107.626106 -287.630004) (xy 107.574144 -287.641864) (xy 107.520994 -287.645848) (xy 107.467844 -287.641864)
			(xy 107.415882 -287.630004) (xy 107.366268 -287.610532) (xy 107.32011 -287.583883) (xy 107.278439 -287.550652)
			(xy 107.242187 -287.511581) (xy 107.212163 -287.467544) (xy 107.189037 -287.419523) (xy 107.173327 -287.368593)
			(xy 107.165384 -287.315889) (xy 105.056367 -287.315889) (xy 105.054385 -287.342339) (xy 105.042528 -287.394291)
			(xy 105.023062 -287.443896) (xy 104.99642 -287.490046) (xy 104.963198 -287.53171) (xy 104.924137 -287.567958)
			(xy 104.880111 -287.59798) (xy 104.832103 -287.621105) (xy 104.781184 -287.636818) (xy 104.728492 -287.644767)
			(xy 104.701848 -287.645348) (xy 104.675432 -287.644332) (xy 104.661496 -287.643758) (xy 104.634178 -287.649341)
			(xy 104.609387 -287.662103) (xy 104.58897 -287.681092) (xy 104.574448 -287.704894) (xy 104.566903 -287.731737)
			(xy 104.566466 -287.745678) (xy 104.566466 -287.980628) (xy 104.56926 -287.988502) (xy 104.57807 -288.016316)
			(xy 104.587514 -288.073885) (xy 104.588056 -288.103056) (xy 104.587541 -288.129705) (xy 104.816138 -288.129705)
			(xy 104.816138 -288.076407) (xy 104.824081 -288.023703) (xy 104.839791 -287.972773) (xy 104.862917 -287.924752)
			(xy 104.892941 -287.880715) (xy 104.929193 -287.841644) (xy 104.970864 -287.808413) (xy 105.017022 -287.781764)
			(xy 105.066636 -287.762292) (xy 105.118598 -287.750432) (xy 105.171748 -287.746449) (xy 105.224898 -287.750432)
			(xy 105.27686 -287.762292) (xy 105.326474 -287.781764) (xy 105.372632 -287.808413) (xy 105.414303 -287.841644)
			(xy 105.450555 -287.880715) (xy 105.480579 -287.924752) (xy 105.503705 -287.972773) (xy 105.519415 -288.023703)
			(xy 105.527358 -288.076407) (xy 105.527856 -288.103056) (xy 105.527358 -288.129705) (xy 113.274084 -288.129705)
			(xy 113.274084 -288.076407) (xy 113.282027 -288.023703) (xy 113.297737 -287.972773) (xy 113.320863 -287.924752)
			(xy 113.350887 -287.880715) (xy 113.387139 -287.841644) (xy 113.42881 -287.808413) (xy 113.474968 -287.781764)
			(xy 113.524582 -287.762292) (xy 113.576544 -287.750432) (xy 113.629694 -287.746449) (xy 113.682844 -287.750432)
			(xy 113.734806 -287.762292) (xy 113.78442 -287.781764) (xy 113.830578 -287.808413) (xy 113.872249 -287.841644)
			(xy 113.908501 -287.880715) (xy 113.938525 -287.924752) (xy 113.961651 -287.972773) (xy 113.977361 -288.023703)
			(xy 113.985304 -288.076407) (xy 113.985802 -288.103056) (xy 113.985304 -288.129705) (xy 116.093738 -288.129705)
			(xy 116.093738 -288.076407) (xy 116.101681 -288.023703) (xy 116.117391 -287.972773) (xy 116.140517 -287.924752)
			(xy 116.170541 -287.880715) (xy 116.206793 -287.841644) (xy 116.248464 -287.808413) (xy 116.294622 -287.781764)
			(xy 116.344236 -287.762292) (xy 116.396198 -287.750432) (xy 116.449348 -287.746449) (xy 116.502498 -287.750432)
			(xy 116.55446 -287.762292) (xy 116.604074 -287.781764) (xy 116.650232 -287.808413) (xy 116.691903 -287.841644)
			(xy 116.728155 -287.880715) (xy 116.758179 -287.924752) (xy 116.781305 -287.972773) (xy 116.797015 -288.023703)
			(xy 116.804958 -288.076407) (xy 116.805456 -288.103056) (xy 116.804958 -288.129705) (xy 116.797015 -288.182409)
			(xy 116.781305 -288.233339) (xy 116.758179 -288.28136) (xy 116.728155 -288.325397) (xy 116.691903 -288.364468)
			(xy 116.650232 -288.397699) (xy 116.604074 -288.424348) (xy 116.55446 -288.44382) (xy 116.502498 -288.45568)
			(xy 116.449348 -288.459664) (xy 116.396198 -288.45568) (xy 116.344236 -288.44382) (xy 116.294622 -288.424348)
			(xy 116.248464 -288.397699) (xy 116.206793 -288.364468) (xy 116.170541 -288.325397) (xy 116.140517 -288.28136)
			(xy 116.117391 -288.233339) (xy 116.101681 -288.182409) (xy 116.093738 -288.129705) (xy 113.985304 -288.129705)
			(xy 113.977361 -288.182409) (xy 113.961651 -288.233339) (xy 113.938525 -288.28136) (xy 113.908501 -288.325397)
			(xy 113.872249 -288.364468) (xy 113.830578 -288.397699) (xy 113.78442 -288.424348) (xy 113.734806 -288.44382)
			(xy 113.682844 -288.45568) (xy 113.629694 -288.459664) (xy 113.576544 -288.45568) (xy 113.524582 -288.44382)
			(xy 113.474968 -288.424348) (xy 113.42881 -288.397699) (xy 113.387139 -288.364468) (xy 113.350887 -288.325397)
			(xy 113.320863 -288.28136) (xy 113.297737 -288.233339) (xy 113.282027 -288.182409) (xy 113.274084 -288.129705)
			(xy 105.527358 -288.129705) (xy 105.519415 -288.182409) (xy 105.503705 -288.233339) (xy 105.480579 -288.28136)
			(xy 105.450555 -288.325397) (xy 105.414303 -288.364468) (xy 105.372632 -288.397699) (xy 105.326474 -288.424348)
			(xy 105.27686 -288.44382) (xy 105.224898 -288.45568) (xy 105.171748 -288.459664) (xy 105.118598 -288.45568)
			(xy 105.066636 -288.44382) (xy 105.017022 -288.424348) (xy 104.970864 -288.397699) (xy 104.929193 -288.364468)
			(xy 104.892941 -288.325397) (xy 104.862917 -288.28136) (xy 104.839791 -288.233339) (xy 104.824081 -288.182409)
			(xy 104.816138 -288.129705) (xy 104.587541 -288.129705) (xy 104.587492 -288.132225) (xy 104.57805 -288.189792)
			(xy 104.56926 -288.21761) (xy 104.566466 -288.225484) (xy 104.566466 -288.460688) (xy 104.566898 -288.474633)
			(xy 104.574437 -288.501483) (xy 104.588957 -288.525294) (xy 104.609376 -288.544291) (xy 104.634171 -288.557058)
			(xy 104.661495 -288.562643) (xy 104.675432 -288.562034) (xy 104.701848 -288.561018) (xy 104.728493 -288.561519)
			(xy 104.781187 -288.569468) (xy 104.832108 -288.585181) (xy 104.880118 -288.608308) (xy 104.924146 -288.638331)
			(xy 104.963208 -288.67458) (xy 104.996431 -288.716246) (xy 105.023074 -288.762398) (xy 105.042542 -288.812005)
			(xy 105.054399 -288.863959) (xy 105.058381 -288.9171) (xy 105.056382 -288.943775) (xy 107.165638 -288.943775)
			(xy 107.165638 -288.890477) (xy 107.173581 -288.837773) (xy 107.189291 -288.786843) (xy 107.212417 -288.738822)
			(xy 107.242441 -288.694785) (xy 107.278693 -288.655714) (xy 107.320364 -288.622483) (xy 107.366522 -288.595834)
			(xy 107.416136 -288.576362) (xy 107.468098 -288.564502) (xy 107.521248 -288.560519) (xy 107.574398 -288.564502)
			(xy 107.62636 -288.576362) (xy 107.675974 -288.595834) (xy 107.722132 -288.622483) (xy 107.763803 -288.655714)
			(xy 107.800055 -288.694785) (xy 107.830079 -288.738822) (xy 107.853205 -288.786843) (xy 107.868915 -288.837773)
			(xy 107.876858 -288.890477) (xy 107.877356 -288.917126) (xy 107.876858 -288.943775) (xy 107.868915 -288.996479)
			(xy 107.861667 -289.019975) (xy 109.985038 -289.019975) (xy 109.985038 -288.966677) (xy 109.992981 -288.913973)
			(xy 110.008691 -288.863043) (xy 110.031817 -288.815022) (xy 110.061841 -288.770985) (xy 110.098093 -288.731914)
			(xy 110.139764 -288.698683) (xy 110.185922 -288.672034) (xy 110.235536 -288.652562) (xy 110.287498 -288.640702)
			(xy 110.340648 -288.636719) (xy 110.393798 -288.640702) (xy 110.44576 -288.652562) (xy 110.495374 -288.672034)
			(xy 110.541532 -288.698683) (xy 110.583203 -288.731914) (xy 110.619455 -288.770985) (xy 110.649479 -288.815022)
			(xy 110.672605 -288.863043) (xy 110.688315 -288.913973) (xy 110.692806 -288.943775) (xy 119.383038 -288.943775)
			(xy 119.383038 -288.890477) (xy 119.390981 -288.837773) (xy 119.406691 -288.786843) (xy 119.429817 -288.738822)
			(xy 119.459841 -288.694785) (xy 119.496093 -288.655714) (xy 119.537764 -288.622483) (xy 119.583922 -288.595834)
			(xy 119.633536 -288.576362) (xy 119.685498 -288.564502) (xy 119.738648 -288.560519) (xy 119.791798 -288.564502)
			(xy 119.84376 -288.576362) (xy 119.893374 -288.595834) (xy 119.939532 -288.622483) (xy 119.981203 -288.655714)
			(xy 120.017455 -288.694785) (xy 120.047479 -288.738822) (xy 120.070605 -288.786843) (xy 120.086315 -288.837773)
			(xy 120.094258 -288.890477) (xy 120.094756 -288.917126) (xy 120.094258 -288.943775) (xy 120.086315 -288.996479)
			(xy 120.070605 -289.047409) (xy 120.047479 -289.09543) (xy 120.017455 -289.139467) (xy 119.981203 -289.178538)
			(xy 119.939532 -289.211769) (xy 119.893374 -289.238418) (xy 119.84376 -289.25789) (xy 119.791798 -289.26975)
			(xy 119.738648 -289.273734) (xy 119.685498 -289.26975) (xy 119.633536 -289.25789) (xy 119.583922 -289.238418)
			(xy 119.537764 -289.211769) (xy 119.496093 -289.178538) (xy 119.459841 -289.139467) (xy 119.429817 -289.09543)
			(xy 119.406691 -289.047409) (xy 119.390981 -288.996479) (xy 119.383038 -288.943775) (xy 110.692806 -288.943775)
			(xy 110.696258 -288.966677) (xy 110.696756 -288.993326) (xy 110.696258 -289.019975) (xy 110.688315 -289.072679)
			(xy 110.672605 -289.123609) (xy 110.649479 -289.17163) (xy 110.619455 -289.215667) (xy 110.583203 -289.254738)
			(xy 110.541532 -289.287969) (xy 110.495374 -289.314618) (xy 110.44576 -289.33409) (xy 110.393798 -289.34595)
			(xy 110.340648 -289.349934) (xy 110.287498 -289.34595) (xy 110.235536 -289.33409) (xy 110.185922 -289.314618)
			(xy 110.139764 -289.287969) (xy 110.098093 -289.254738) (xy 110.061841 -289.215667) (xy 110.031817 -289.17163)
			(xy 110.008691 -289.123609) (xy 109.992981 -289.072679) (xy 109.985038 -289.019975) (xy 107.861667 -289.019975)
			(xy 107.853205 -289.047409) (xy 107.830079 -289.09543) (xy 107.800055 -289.139467) (xy 107.763803 -289.178538)
			(xy 107.722132 -289.211769) (xy 107.675974 -289.238418) (xy 107.62636 -289.25789) (xy 107.574398 -289.26975)
			(xy 107.521248 -289.273734) (xy 107.468098 -289.26975) (xy 107.416136 -289.25789) (xy 107.366522 -289.238418)
			(xy 107.320364 -289.211769) (xy 107.278693 -289.178538) (xy 107.242441 -289.139467) (xy 107.212417 -289.09543)
			(xy 107.189291 -289.047409) (xy 107.173581 -288.996479) (xy 107.165638 -288.943775) (xy 105.056382 -288.943775)
			(xy 105.054399 -288.970241) (xy 105.042542 -289.022195) (xy 105.023074 -289.071802) (xy 104.996431 -289.117954)
			(xy 104.963208 -289.15962) (xy 104.924146 -289.195869) (xy 104.880118 -289.225892) (xy 104.832108 -289.249019)
			(xy 104.781187 -289.264732) (xy 104.728493 -289.272681) (xy 104.701848 -289.273234) (xy 104.677705 -289.272828)
			(xy 104.629864 -289.266293) (xy 104.583345 -289.253351) (xy 104.539003 -289.234238) (xy 104.497652 -289.209307)
			(xy 104.478582 -289.194494) (xy 104.443022 -289.165792) (xy 104.306878 -289.301936) (xy 104.296833 -289.312733)
			(xy 104.282871 -289.338695) (xy 104.276903 -289.367562) (xy 104.279424 -289.396932) (xy 104.290225 -289.42436)
			(xy 104.308406 -289.447563) (xy 104.332455 -289.46461) (xy 104.346248 -289.46983) (xy 104.372292 -289.47925)
			(xy 104.421327 -289.504993) (xy 104.46579 -289.53801) (xy 104.50461 -289.577509) (xy 104.536852 -289.622537)
			(xy 104.561741 -289.67201) (xy 104.578677 -289.724738) (xy 104.587253 -289.779451) (xy 104.587802 -289.807142)
			(xy 104.587276 -289.833791) (xy 118.912884 -289.833791) (xy 118.912884 -289.780493) (xy 118.920827 -289.727789)
			(xy 118.936537 -289.676859) (xy 118.959663 -289.628838) (xy 118.989687 -289.584801) (xy 119.025939 -289.54573)
			(xy 119.06761 -289.512499) (xy 119.113768 -289.48585) (xy 119.163382 -289.466378) (xy 119.215344 -289.454518)
			(xy 119.268494 -289.450535) (xy 119.321644 -289.454518) (xy 119.373606 -289.466378) (xy 119.42322 -289.48585)
			(xy 119.469378 -289.512499) (xy 119.511049 -289.54573) (xy 119.547301 -289.584801) (xy 119.577325 -289.628838)
			(xy 119.600451 -289.676859) (xy 119.616161 -289.727789) (xy 119.624104 -289.780493) (xy 119.624602 -289.807142)
			(xy 119.852186 -289.807142) (xy 119.852644 -289.781504) (xy 119.859993 -289.730756) (xy 119.874544 -289.681588)
			(xy 119.895998 -289.635015) (xy 119.923909 -289.592) (xy 119.957702 -289.553434) (xy 119.996676 -289.520113)
			(xy 120.040027 -289.492727) (xy 120.086858 -289.471842) (xy 120.1362 -289.45789) (xy 120.161558 -289.454082)
			(xy 120.187466 -289.45078) (xy 120.372378 -289.101022) (xy 120.36044 -289.077654) (xy 120.348406 -289.052627)
			(xy 120.331423 -288.999757) (xy 120.32285 -288.944892) (xy 120.32234 -288.917126) (xy 120.322838 -288.890477)
			(xy 120.330781 -288.837773) (xy 120.346491 -288.786843) (xy 120.369617 -288.738822) (xy 120.399641 -288.694785)
			(xy 120.435893 -288.655714) (xy 120.477564 -288.622483) (xy 120.523722 -288.595834) (xy 120.573336 -288.576362)
			(xy 120.625298 -288.564502) (xy 120.678448 -288.560519) (xy 120.731598 -288.564502) (xy 120.78356 -288.576362)
			(xy 120.833174 -288.595834) (xy 120.879332 -288.622483) (xy 120.921003 -288.655714) (xy 120.957255 -288.694785)
			(xy 120.987279 -288.738822) (xy 121.010405 -288.786843) (xy 121.026115 -288.837773) (xy 121.034058 -288.890477)
			(xy 121.034556 -288.917126) (xy 121.034118 -288.942766) (xy 121.026772 -288.993516) (xy 121.012222 -289.042688)
			(xy 120.990768 -289.089264) (xy 120.962855 -289.132281) (xy 120.92906 -289.170848) (xy 120.890081 -289.204169)
			(xy 120.846726 -289.231553) (xy 120.79989 -289.252434) (xy 120.750544 -289.266381) (xy 120.725184 -289.270186)
			(xy 120.699276 -289.273488) (xy 120.514364 -289.623246) (xy 120.526302 -289.646614) (xy 120.53832 -289.671648)
			(xy 120.55531 -289.724515) (xy 120.563889 -289.779377) (xy 120.564402 -289.807142) (xy 120.563904 -289.833791)
			(xy 120.792484 -289.833791) (xy 120.792484 -289.780493) (xy 120.800427 -289.727789) (xy 120.816137 -289.676859)
			(xy 120.839263 -289.628838) (xy 120.869287 -289.584801) (xy 120.905539 -289.54573) (xy 120.94721 -289.512499)
			(xy 120.993368 -289.48585) (xy 121.042982 -289.466378) (xy 121.094944 -289.454518) (xy 121.148094 -289.450535)
			(xy 121.201244 -289.454518) (xy 121.253206 -289.466378) (xy 121.30282 -289.48585) (xy 121.348978 -289.512499)
			(xy 121.390649 -289.54573) (xy 121.426901 -289.584801) (xy 121.456925 -289.628838) (xy 121.480051 -289.676859)
			(xy 121.495761 -289.727789) (xy 121.503704 -289.780493) (xy 121.504202 -289.807142) (xy 121.503704 -289.833791)
			(xy 121.495761 -289.886495) (xy 121.480051 -289.937425) (xy 121.456925 -289.985446) (xy 121.426901 -290.029483)
			(xy 121.390649 -290.068554) (xy 121.348978 -290.101785) (xy 121.30282 -290.128434) (xy 121.253206 -290.147906)
			(xy 121.201244 -290.159766) (xy 121.148094 -290.16375) (xy 121.094944 -290.159766) (xy 121.042982 -290.147906)
			(xy 120.993368 -290.128434) (xy 120.94721 -290.101785) (xy 120.905539 -290.068554) (xy 120.869287 -290.029483)
			(xy 120.839263 -289.985446) (xy 120.816137 -289.937425) (xy 120.800427 -289.886495) (xy 120.792484 -289.833791)
			(xy 120.563904 -289.833791) (xy 120.555961 -289.886495) (xy 120.540251 -289.937425) (xy 120.517125 -289.985446)
			(xy 120.487101 -290.029483) (xy 120.450849 -290.068554) (xy 120.409178 -290.101785) (xy 120.36302 -290.128434)
			(xy 120.313406 -290.147906) (xy 120.261444 -290.159766) (xy 120.208294 -290.16375) (xy 120.155144 -290.159766)
			(xy 120.103182 -290.147906) (xy 120.053568 -290.128434) (xy 120.00741 -290.101785) (xy 119.965739 -290.068554)
			(xy 119.929487 -290.029483) (xy 119.899463 -289.985446) (xy 119.876337 -289.937425) (xy 119.860627 -289.886495)
			(xy 119.852684 -289.833791) (xy 119.852186 -289.807142) (xy 119.624602 -289.807142) (xy 119.624104 -289.833791)
			(xy 119.616161 -289.886495) (xy 119.600451 -289.937425) (xy 119.577325 -289.985446) (xy 119.547301 -290.029483)
			(xy 119.511049 -290.068554) (xy 119.469378 -290.101785) (xy 119.42322 -290.128434) (xy 119.373606 -290.147906)
			(xy 119.321644 -290.159766) (xy 119.268494 -290.16375) (xy 119.215344 -290.159766) (xy 119.163382 -290.147906)
			(xy 119.113768 -290.128434) (xy 119.06761 -290.101785) (xy 119.025939 -290.068554) (xy 118.989687 -290.029483)
			(xy 118.959663 -289.985446) (xy 118.936537 -289.937425) (xy 118.920827 -289.886495) (xy 118.912884 -289.833791)
			(xy 104.587276 -289.833791) (xy 104.58725 -289.835123) (xy 104.57849 -289.890395) (xy 104.561191 -289.943616)
			(xy 104.535781 -289.993476) (xy 104.502884 -290.038747) (xy 104.46331 -290.078315) (xy 104.418035 -290.111206)
			(xy 104.368171 -290.13661) (xy 104.314948 -290.153901) (xy 104.259675 -290.162654) (xy 104.231694 -290.16325)
			(xy 104.204002 -290.162724) (xy 104.149287 -290.154153) (xy 104.096557 -290.137217) (xy 104.047083 -290.112325)
			(xy 104.002057 -290.080077) (xy 103.962564 -290.041249) (xy 103.929555 -289.996777) (xy 103.903826 -289.947733)
			(xy 103.894382 -289.921696) (xy 103.889199 -289.907874) (xy 103.872172 -289.883774) (xy 103.848964 -289.865552)
			(xy 103.821512 -289.854731) (xy 103.792112 -289.852215) (xy 103.763221 -289.858214) (xy 103.737254 -289.872227)
			(xy 103.726488 -289.882326) (xy 103.067866 -290.540948) (xy 87.243666 -290.540948) (xy 86.100666 -291.683948)
			(xy 86.100666 -292.983252) (xy 103.237758 -292.983252) (xy 103.237758 -292.928748) (xy 103.245515 -292.874798)
			(xy 103.26087 -292.822501) (xy 103.283512 -292.772922) (xy 103.312979 -292.727069) (xy 103.348671 -292.685877)
			(xy 103.389863 -292.650184) (xy 103.435715 -292.620716) (xy 103.485293 -292.598073) (xy 103.53759 -292.582716)
			(xy 103.59154 -292.574958) (xy 103.618792 -292.574472) (xy 103.646868 -292.574976) (xy 103.702416 -292.583189)
			(xy 103.756161 -292.599453) (xy 103.806942 -292.623417) (xy 103.853664 -292.654564) (xy 103.874824 -292.673024)
			(xy 103.886451 -292.682837) (xy 103.913985 -292.695741) (xy 103.9441 -292.699951) (xy 103.974118 -292.695092)
			(xy 104.001367 -292.681597) (xy 104.012746 -292.6715) (xy 104.034133 -292.651991) (xy 104.081698 -292.619001)
			(xy 104.133705 -292.593584) (xy 104.188957 -292.576325) (xy 104.246185 -292.56762) (xy 104.275128 -292.567106)
			(xy 104.302379 -292.567566) (xy 104.356326 -292.575326) (xy 104.408619 -292.590684) (xy 104.458194 -292.613327)
			(xy 104.504043 -292.642796) (xy 104.545231 -292.678488) (xy 104.580921 -292.719679) (xy 104.610386 -292.76553)
			(xy 104.633026 -292.815107) (xy 104.64838 -292.867402) (xy 104.656136 -292.921349) (xy 104.656136 -292.975851)
			(xy 104.655072 -292.983252) (xy 109.276358 -292.983252) (xy 109.276358 -292.928748) (xy 109.284114 -292.874798)
			(xy 109.29947 -292.822502) (xy 109.322111 -292.772923) (xy 109.351578 -292.727071) (xy 109.38727 -292.685878)
			(xy 109.428461 -292.650185) (xy 109.474312 -292.620717) (xy 109.523891 -292.598074) (xy 109.576187 -292.582717)
			(xy 109.630136 -292.574959) (xy 109.657388 -292.574472) (xy 109.685428 -292.574974) (xy 109.740905 -292.583173)
			(xy 109.794587 -292.599397) (xy 109.84532 -292.623297) (xy 109.892012 -292.654359) (xy 109.913166 -292.67277)
			(xy 109.924608 -292.682415) (xy 109.951651 -292.695195) (xy 109.981238 -292.699581) (xy 110.010825 -292.695195)
			(xy 110.037868 -292.682415) (xy 110.04931 -292.67277) (xy 110.070435 -292.654319) (xy 110.11712 -292.62323)
			(xy 110.167857 -292.599321) (xy 110.221552 -292.583108) (xy 110.277043 -292.574941) (xy 110.305088 -292.574472)
			(xy 110.333128 -292.574974) (xy 110.388605 -292.583173) (xy 110.442287 -292.599397) (xy 110.49302 -292.623297)
			(xy 110.539712 -292.654359) (xy 110.560866 -292.67277) (xy 110.572308 -292.682415) (xy 110.599351 -292.695195)
			(xy 110.628938 -292.699581) (xy 110.658525 -292.695195) (xy 110.685568 -292.682415) (xy 110.69701 -292.67277)
			(xy 110.718135 -292.654319) (xy 110.76482 -292.62323) (xy 110.815557 -292.599321) (xy 110.869252 -292.583108)
			(xy 110.924743 -292.574941) (xy 110.952788 -292.574472) (xy 110.98004 -292.574974) (xy 111.033989 -292.58273)
			(xy 111.086286 -292.598084) (xy 111.135865 -292.620724) (xy 111.181717 -292.650191) (xy 111.222909 -292.685882)
			(xy 111.258602 -292.727073) (xy 111.28807 -292.772924) (xy 111.310712 -292.822503) (xy 111.326068 -292.874799)
			(xy 111.333825 -292.928748) (xy 111.333825 -292.983252) (xy 115.746758 -292.983252) (xy 115.746758 -292.928748)
			(xy 115.754514 -292.874799) (xy 115.769869 -292.822503) (xy 115.792511 -292.772924) (xy 115.821977 -292.727072)
			(xy 115.857669 -292.68588) (xy 115.898859 -292.650187) (xy 115.94471 -292.620718) (xy 115.994288 -292.598075)
			(xy 116.046583 -292.582718) (xy 116.100532 -292.574959) (xy 116.127784 -292.574472) (xy 116.155155 -292.57493)
			(xy 116.209335 -292.582747) (xy 116.261839 -292.598237) (xy 116.311586 -292.621081) (xy 116.357551 -292.650809)
			(xy 116.378482 -292.668452) (xy 116.38981 -292.677688) (xy 116.416367 -292.689864) (xy 116.445284 -292.694037)
			(xy 116.474201 -292.689864) (xy 116.500758 -292.677688) (xy 116.512086 -292.668452) (xy 116.533019 -292.650811)
			(xy 116.578987 -292.621087) (xy 116.628733 -292.598241) (xy 116.681235 -292.582745) (xy 116.735413 -292.574916)
			(xy 116.790155 -292.574916) (xy 116.844333 -292.582745) (xy 116.896835 -292.598241) (xy 116.946581 -292.621087)
			(xy 116.992549 -292.650811) (xy 117.013482 -292.668452) (xy 117.02481 -292.677688) (xy 117.051367 -292.689864)
			(xy 117.080284 -292.694037) (xy 117.109201 -292.689864) (xy 117.135758 -292.677688) (xy 117.147086 -292.668452)
			(xy 117.168019 -292.650814) (xy 117.213991 -292.6211) (xy 117.263738 -292.598263) (xy 117.316239 -292.582772)
			(xy 117.370415 -292.574945) (xy 117.397784 -292.574472) (xy 117.425036 -292.574974) (xy 117.478986 -292.582729)
			(xy 117.531283 -292.598083) (xy 117.580863 -292.620723) (xy 117.626715 -292.650189) (xy 117.667908 -292.685881)
			(xy 117.703601 -292.727072) (xy 117.733069 -292.772923) (xy 117.755712 -292.822502) (xy 117.771068 -292.874798)
			(xy 117.778825 -292.928748) (xy 117.778825 -292.95598) (xy 122.307602 -292.95598) (xy 122.311673 -292.900358)
			(xy 122.323799 -292.845921) (xy 122.343722 -292.79383) (xy 122.371018 -292.745195) (xy 122.405104 -292.701052)
			(xy 122.445253 -292.662343) (xy 122.490611 -292.629892) (xy 122.540211 -292.604391) (xy 122.592995 -292.586384)
			(xy 122.647838 -292.576254) (xy 122.703572 -292.574217) (xy 122.759009 -292.580317) (xy 122.812966 -292.594423)
			(xy 122.864295 -292.616235) (xy 122.911901 -292.645289) (xy 122.954769 -292.680964) (xy 122.991986 -292.722501)
			(xy 123.022759 -292.769014) (xy 123.046431 -292.819511) (xy 123.062499 -292.872918) (xy 123.070619 -292.928094)
			(xy 123.071128 -292.95598) (xy 123.070619 -292.983866) (xy 123.062499 -293.039042) (xy 123.046431 -293.092449)
			(xy 123.022759 -293.142946) (xy 122.991986 -293.189459) (xy 122.954769 -293.230996) (xy 122.911901 -293.266671)
			(xy 122.864295 -293.295725) (xy 122.812966 -293.317537) (xy 122.759009 -293.331643) (xy 122.703572 -293.337743)
			(xy 122.647838 -293.335706) (xy 122.592995 -293.325576) (xy 122.540211 -293.307569) (xy 122.490611 -293.282068)
			(xy 122.445253 -293.249617) (xy 122.405104 -293.210908) (xy 122.371018 -293.166765) (xy 122.343722 -293.11813)
			(xy 122.323799 -293.066039) (xy 122.311673 -293.011602) (xy 122.307602 -292.95598) (xy 117.778825 -292.95598)
			(xy 117.778825 -292.983252) (xy 117.771068 -293.037202) (xy 117.755712 -293.089498) (xy 117.733069 -293.139077)
			(xy 117.703601 -293.184928) (xy 117.667908 -293.226119) (xy 117.626715 -293.261811) (xy 117.580863 -293.291277)
			(xy 117.531283 -293.313917) (xy 117.478986 -293.329271) (xy 117.425036 -293.337026) (xy 117.397784 -293.337488)
			(xy 117.370413 -293.337034) (xy 117.316234 -293.329214) (xy 117.26373 -293.313722) (xy 117.213984 -293.290878)
			(xy 117.168017 -293.26115) (xy 117.147086 -293.243508) (xy 117.135758 -293.234272) (xy 117.109201 -293.222096)
			(xy 117.080284 -293.217923) (xy 117.051367 -293.222096) (xy 117.02481 -293.234272) (xy 117.013482 -293.243508)
			(xy 116.992549 -293.261149) (xy 116.946581 -293.290873) (xy 116.896835 -293.313719) (xy 116.844333 -293.329215)
			(xy 116.790155 -293.337044) (xy 116.735413 -293.337044) (xy 116.681235 -293.329215) (xy 116.628733 -293.313719)
			(xy 116.578987 -293.290873) (xy 116.533019 -293.261149) (xy 116.512086 -293.243508) (xy 116.500758 -293.234272)
			(xy 116.474201 -293.222096) (xy 116.445284 -293.217923) (xy 116.416367 -293.222096) (xy 116.38981 -293.234272)
			(xy 116.378482 -293.243508) (xy 116.357531 -293.261123) (xy 116.311563 -293.290838) (xy 116.26182 -293.313679)
			(xy 116.209324 -293.329176) (xy 116.155152 -293.33701) (xy 116.127784 -293.337488) (xy 116.100532 -293.337041)
			(xy 116.046583 -293.329282) (xy 115.994288 -293.313925) (xy 115.94471 -293.291282) (xy 115.898859 -293.261813)
			(xy 115.857669 -293.22612) (xy 115.821977 -293.184928) (xy 115.792511 -293.139076) (xy 115.769869 -293.089497)
			(xy 115.754514 -293.037201) (xy 115.746758 -292.983252) (xy 111.333825 -292.983252) (xy 111.326068 -293.037201)
			(xy 111.310712 -293.089497) (xy 111.28807 -293.139076) (xy 111.258602 -293.184927) (xy 111.222909 -293.226118)
			(xy 111.181717 -293.261809) (xy 111.135865 -293.291276) (xy 111.086286 -293.313916) (xy 111.033989 -293.32927)
			(xy 110.98004 -293.337026) (xy 110.952788 -293.337488) (xy 110.924747 -293.337011) (xy 110.869268 -293.328807)
			(xy 110.815585 -293.312578) (xy 110.764853 -293.288672) (xy 110.718163 -293.257604) (xy 110.69701 -293.23919)
			(xy 110.685568 -293.229545) (xy 110.658525 -293.216765) (xy 110.628938 -293.212379) (xy 110.599351 -293.216765)
			(xy 110.572308 -293.229545) (xy 110.560866 -293.23919) (xy 110.539705 -293.257598) (xy 110.493031 -293.288695)
			(xy 110.442303 -293.312613) (xy 110.388616 -293.328836) (xy 110.333131 -293.337013) (xy 110.305088 -293.337488)
			(xy 110.277047 -293.337011) (xy 110.221568 -293.328807) (xy 110.167885 -293.312578) (xy 110.117153 -293.288672)
			(xy 110.070463 -293.257604) (xy 110.04931 -293.23919) (xy 110.037868 -293.229545) (xy 110.010825 -293.216765)
			(xy 109.981238 -293.212379) (xy 109.951651 -293.216765) (xy 109.924608 -293.229545) (xy 109.913166 -293.23919)
			(xy 109.892005 -293.257598) (xy 109.845331 -293.288695) (xy 109.794603 -293.312613) (xy 109.740916 -293.328836)
			(xy 109.685431 -293.337013) (xy 109.657388 -293.337488) (xy 109.630136 -293.337041) (xy 109.576187 -293.329283)
			(xy 109.523891 -293.313926) (xy 109.474312 -293.291283) (xy 109.428461 -293.261815) (xy 109.38727 -293.226122)
			(xy 109.351578 -293.184929) (xy 109.322111 -293.139077) (xy 109.29947 -293.089498) (xy 109.284114 -293.037202)
			(xy 109.276358 -292.983252) (xy 104.655072 -292.983252) (xy 104.64838 -293.029798) (xy 104.633026 -293.082093)
			(xy 104.610386 -293.13167) (xy 104.580921 -293.177521) (xy 104.545231 -293.218712) (xy 104.504043 -293.254404)
			(xy 104.458194 -293.283873) (xy 104.408619 -293.306516) (xy 104.356326 -293.321874) (xy 104.302379 -293.329634)
			(xy 104.275128 -293.330122) (xy 104.247052 -293.329608) (xy 104.191505 -293.321398) (xy 104.13776 -293.305136)
			(xy 104.086978 -293.281174) (xy 104.040256 -293.250029) (xy 104.019096 -293.23157) (xy 104.00753 -293.221678)
			(xy 103.979974 -293.208784) (xy 103.94984 -293.20459) (xy 103.91981 -293.209469) (xy 103.892553 -293.222986)
			(xy 103.881174 -293.233094) (xy 103.859778 -293.252592) (xy 103.812216 -293.285584) (xy 103.760211 -293.311003)
			(xy 103.70496 -293.328265) (xy 103.647735 -293.336973) (xy 103.618792 -293.337488) (xy 103.59154 -293.337042)
			(xy 103.53759 -293.329284) (xy 103.485293 -293.313927) (xy 103.435715 -293.291284) (xy 103.389863 -293.261816)
			(xy 103.348671 -293.226123) (xy 103.312979 -293.184931) (xy 103.283512 -293.139078) (xy 103.26087 -293.089499)
			(xy 103.245515 -293.037202) (xy 103.237758 -292.983252) (xy 86.100666 -292.983252) (xy 86.100666 -295.066052)
			(xy 103.237758 -295.066052) (xy 103.237758 -295.011548) (xy 103.245515 -294.957598) (xy 103.26087 -294.905301)
			(xy 103.283512 -294.855722) (xy 103.312979 -294.809869) (xy 103.348671 -294.768677) (xy 103.389863 -294.732984)
			(xy 103.435715 -294.703516) (xy 103.485293 -294.680873) (xy 103.53759 -294.665516) (xy 103.59154 -294.657758)
			(xy 103.618792 -294.657272) (xy 103.646868 -294.657776) (xy 103.702416 -294.665989) (xy 103.756161 -294.682253)
			(xy 103.806942 -294.706217) (xy 103.853664 -294.737364) (xy 103.874824 -294.755824) (xy 103.886451 -294.765637)
			(xy 103.913985 -294.778541) (xy 103.9441 -294.782751) (xy 103.974118 -294.777892) (xy 104.001367 -294.764397)
			(xy 104.012746 -294.7543) (xy 104.034133 -294.734791) (xy 104.081698 -294.701801) (xy 104.133705 -294.676384)
			(xy 104.188957 -294.659125) (xy 104.246185 -294.65042) (xy 104.275128 -294.649906) (xy 104.302379 -294.650366)
			(xy 104.356326 -294.658126) (xy 104.408619 -294.673484) (xy 104.458194 -294.696127) (xy 104.504043 -294.725596)
			(xy 104.545231 -294.761288) (xy 104.580921 -294.802479) (xy 104.610386 -294.84833) (xy 104.633026 -294.897907)
			(xy 104.64838 -294.950202) (xy 104.656136 -295.004149) (xy 104.656136 -295.058651) (xy 104.655072 -295.066052)
			(xy 109.276358 -295.066052) (xy 109.276358 -295.011548) (xy 109.284114 -294.957598) (xy 109.29947 -294.905302)
			(xy 109.322111 -294.855723) (xy 109.351578 -294.809871) (xy 109.38727 -294.768678) (xy 109.428461 -294.732985)
			(xy 109.474312 -294.703517) (xy 109.523891 -294.680874) (xy 109.576187 -294.665517) (xy 109.630136 -294.657759)
			(xy 109.657388 -294.657272) (xy 109.685428 -294.657774) (xy 109.740905 -294.665973) (xy 109.794587 -294.682197)
			(xy 109.84532 -294.706097) (xy 109.892012 -294.737159) (xy 109.913166 -294.75557) (xy 109.924608 -294.765215)
			(xy 109.951651 -294.777995) (xy 109.981238 -294.782381) (xy 110.010825 -294.777995) (xy 110.037868 -294.765215)
			(xy 110.04931 -294.75557) (xy 110.070435 -294.737119) (xy 110.11712 -294.70603) (xy 110.167857 -294.682121)
			(xy 110.221552 -294.665908) (xy 110.277043 -294.657741) (xy 110.305088 -294.657272) (xy 110.333128 -294.657774)
			(xy 110.388605 -294.665973) (xy 110.442287 -294.682197) (xy 110.49302 -294.706097) (xy 110.539712 -294.737159)
			(xy 110.560866 -294.75557) (xy 110.572308 -294.765215) (xy 110.599351 -294.777995) (xy 110.628938 -294.782381)
			(xy 110.658525 -294.777995) (xy 110.685568 -294.765215) (xy 110.69701 -294.75557) (xy 110.718135 -294.737119)
			(xy 110.76482 -294.70603) (xy 110.815557 -294.682121) (xy 110.869252 -294.665908) (xy 110.924743 -294.657741)
			(xy 110.952788 -294.657272) (xy 110.98004 -294.657774) (xy 111.033989 -294.66553) (xy 111.086286 -294.680884)
			(xy 111.135865 -294.703524) (xy 111.181717 -294.732991) (xy 111.222909 -294.768682) (xy 111.258602 -294.809873)
			(xy 111.28807 -294.855724) (xy 111.310712 -294.905303) (xy 111.326068 -294.957599) (xy 111.333825 -295.011548)
			(xy 111.333825 -295.066052) (xy 115.746758 -295.066052) (xy 115.746758 -295.011548) (xy 115.754514 -294.957599)
			(xy 115.769869 -294.905303) (xy 115.792511 -294.855724) (xy 115.821977 -294.809872) (xy 115.857669 -294.76868)
			(xy 115.898859 -294.732987) (xy 115.94471 -294.703518) (xy 115.994288 -294.680875) (xy 116.046583 -294.665518)
			(xy 116.100532 -294.657759) (xy 116.127784 -294.657272) (xy 116.155155 -294.65773) (xy 116.209335 -294.665547)
			(xy 116.261839 -294.681037) (xy 116.311586 -294.703881) (xy 116.357551 -294.733609) (xy 116.378482 -294.751252)
			(xy 116.38981 -294.760488) (xy 116.416367 -294.772664) (xy 116.445284 -294.776837) (xy 116.474201 -294.772664)
			(xy 116.500758 -294.760488) (xy 116.512086 -294.751252) (xy 116.533019 -294.733611) (xy 116.578987 -294.703887)
			(xy 116.628733 -294.681041) (xy 116.681235 -294.665545) (xy 116.735413 -294.657716) (xy 116.790155 -294.657716)
			(xy 116.844333 -294.665545) (xy 116.896835 -294.681041) (xy 116.946581 -294.703887) (xy 116.992549 -294.733611)
			(xy 117.013482 -294.751252) (xy 117.02481 -294.760488) (xy 117.051367 -294.772664) (xy 117.080284 -294.776837)
			(xy 117.109201 -294.772664) (xy 117.135758 -294.760488) (xy 117.147086 -294.751252) (xy 117.168019 -294.733614)
			(xy 117.213991 -294.7039) (xy 117.263738 -294.681063) (xy 117.316239 -294.665572) (xy 117.370415 -294.657745)
			(xy 117.397784 -294.657272) (xy 117.425036 -294.657774) (xy 117.478986 -294.665529) (xy 117.531283 -294.680883)
			(xy 117.580863 -294.703523) (xy 117.626715 -294.732989) (xy 117.667908 -294.768681) (xy 117.703601 -294.809872)
			(xy 117.733069 -294.855723) (xy 117.755712 -294.905302) (xy 117.771068 -294.957598) (xy 117.778825 -295.011548)
			(xy 117.778825 -295.03878) (xy 122.307602 -295.03878) (xy 122.311673 -294.983158) (xy 122.323799 -294.928721)
			(xy 122.343722 -294.87663) (xy 122.371018 -294.827995) (xy 122.405104 -294.783852) (xy 122.445253 -294.745143)
			(xy 122.490611 -294.712692) (xy 122.540211 -294.687191) (xy 122.592995 -294.669184) (xy 122.647838 -294.659054)
			(xy 122.703572 -294.657017) (xy 122.759009 -294.663117) (xy 122.812966 -294.677223) (xy 122.864295 -294.699035)
			(xy 122.911901 -294.728089) (xy 122.954769 -294.763764) (xy 122.991986 -294.805301) (xy 123.022759 -294.851814)
			(xy 123.046431 -294.902311) (xy 123.062499 -294.955718) (xy 123.070619 -295.010894) (xy 123.071128 -295.03878)
			(xy 123.070619 -295.066666) (xy 123.062499 -295.121842) (xy 123.046431 -295.175249) (xy 123.022759 -295.225746)
			(xy 122.991986 -295.272259) (xy 122.954769 -295.313796) (xy 122.911901 -295.349471) (xy 122.864295 -295.378525)
			(xy 122.812966 -295.400337) (xy 122.759009 -295.414443) (xy 122.703572 -295.420543) (xy 122.647838 -295.418506)
			(xy 122.592995 -295.408376) (xy 122.540211 -295.390369) (xy 122.490611 -295.364868) (xy 122.445253 -295.332417)
			(xy 122.405104 -295.293708) (xy 122.371018 -295.249565) (xy 122.343722 -295.20093) (xy 122.323799 -295.148839)
			(xy 122.311673 -295.094402) (xy 122.307602 -295.03878) (xy 117.778825 -295.03878) (xy 117.778825 -295.066052)
			(xy 117.771068 -295.120002) (xy 117.755712 -295.172298) (xy 117.733069 -295.221877) (xy 117.703601 -295.267728)
			(xy 117.667908 -295.308919) (xy 117.626715 -295.344611) (xy 117.580863 -295.374077) (xy 117.531283 -295.396717)
			(xy 117.478986 -295.412071) (xy 117.425036 -295.419826) (xy 117.397784 -295.420288) (xy 117.370413 -295.419834)
			(xy 117.316234 -295.412014) (xy 117.26373 -295.396522) (xy 117.213984 -295.373678) (xy 117.168017 -295.34395)
			(xy 117.147086 -295.326308) (xy 117.135758 -295.317072) (xy 117.109201 -295.304896) (xy 117.080284 -295.300723)
			(xy 117.051367 -295.304896) (xy 117.02481 -295.317072) (xy 117.013482 -295.326308) (xy 116.992549 -295.343949)
			(xy 116.946581 -295.373673) (xy 116.896835 -295.396519) (xy 116.844333 -295.412015) (xy 116.790155 -295.419844)
			(xy 116.735413 -295.419844) (xy 116.681235 -295.412015) (xy 116.628733 -295.396519) (xy 116.578987 -295.373673)
			(xy 116.533019 -295.343949) (xy 116.512086 -295.326308) (xy 116.500758 -295.317072) (xy 116.474201 -295.304896)
			(xy 116.445284 -295.300723) (xy 116.416367 -295.304896) (xy 116.38981 -295.317072) (xy 116.378482 -295.326308)
			(xy 116.357531 -295.343923) (xy 116.311563 -295.373638) (xy 116.26182 -295.396479) (xy 116.209324 -295.411976)
			(xy 116.155152 -295.41981) (xy 116.127784 -295.420288) (xy 116.100532 -295.419841) (xy 116.046583 -295.412082)
			(xy 115.994288 -295.396725) (xy 115.94471 -295.374082) (xy 115.898859 -295.344613) (xy 115.857669 -295.30892)
			(xy 115.821977 -295.267728) (xy 115.792511 -295.221876) (xy 115.769869 -295.172297) (xy 115.754514 -295.120001)
			(xy 115.746758 -295.066052) (xy 111.333825 -295.066052) (xy 111.326068 -295.120001) (xy 111.310712 -295.172297)
			(xy 111.28807 -295.221876) (xy 111.258602 -295.267727) (xy 111.222909 -295.308918) (xy 111.181717 -295.344609)
			(xy 111.135865 -295.374076) (xy 111.086286 -295.396716) (xy 111.033989 -295.41207) (xy 110.98004 -295.419826)
			(xy 110.952788 -295.420288) (xy 110.924747 -295.419811) (xy 110.869268 -295.411607) (xy 110.815585 -295.395378)
			(xy 110.764853 -295.371472) (xy 110.718163 -295.340404) (xy 110.69701 -295.32199) (xy 110.685568 -295.312345)
			(xy 110.658525 -295.299565) (xy 110.628938 -295.295179) (xy 110.599351 -295.299565) (xy 110.572308 -295.312345)
			(xy 110.560866 -295.32199) (xy 110.539705 -295.340398) (xy 110.493031 -295.371495) (xy 110.442303 -295.395413)
			(xy 110.388616 -295.411636) (xy 110.333131 -295.419813) (xy 110.305088 -295.420288) (xy 110.277047 -295.419811)
			(xy 110.221568 -295.411607) (xy 110.167885 -295.395378) (xy 110.117153 -295.371472) (xy 110.070463 -295.340404)
			(xy 110.04931 -295.32199) (xy 110.037868 -295.312345) (xy 110.010825 -295.299565) (xy 109.981238 -295.295179)
			(xy 109.951651 -295.299565) (xy 109.924608 -295.312345) (xy 109.913166 -295.32199) (xy 109.892005 -295.340398)
			(xy 109.845331 -295.371495) (xy 109.794603 -295.395413) (xy 109.740916 -295.411636) (xy 109.685431 -295.419813)
			(xy 109.657388 -295.420288) (xy 109.630136 -295.419841) (xy 109.576187 -295.412083) (xy 109.523891 -295.396726)
			(xy 109.474312 -295.374083) (xy 109.428461 -295.344615) (xy 109.38727 -295.308922) (xy 109.351578 -295.267729)
			(xy 109.322111 -295.221877) (xy 109.29947 -295.172298) (xy 109.284114 -295.120002) (xy 109.276358 -295.066052)
			(xy 104.655072 -295.066052) (xy 104.64838 -295.112598) (xy 104.633026 -295.164893) (xy 104.610386 -295.21447)
			(xy 104.580921 -295.260321) (xy 104.545231 -295.301512) (xy 104.504043 -295.337204) (xy 104.458194 -295.366673)
			(xy 104.408619 -295.389316) (xy 104.356326 -295.404674) (xy 104.302379 -295.412434) (xy 104.275128 -295.412922)
			(xy 104.247052 -295.412408) (xy 104.191505 -295.404198) (xy 104.13776 -295.387936) (xy 104.086978 -295.363974)
			(xy 104.040256 -295.332829) (xy 104.019096 -295.31437) (xy 104.00753 -295.304478) (xy 103.979974 -295.291584)
			(xy 103.94984 -295.28739) (xy 103.91981 -295.292269) (xy 103.892553 -295.305786) (xy 103.881174 -295.315894)
			(xy 103.859778 -295.335392) (xy 103.812216 -295.368384) (xy 103.760211 -295.393803) (xy 103.70496 -295.411065)
			(xy 103.647735 -295.419773) (xy 103.618792 -295.420288) (xy 103.59154 -295.419842) (xy 103.53759 -295.412084)
			(xy 103.485293 -295.396727) (xy 103.435715 -295.374084) (xy 103.389863 -295.344616) (xy 103.348671 -295.308923)
			(xy 103.312979 -295.267731) (xy 103.283512 -295.221878) (xy 103.26087 -295.172299) (xy 103.245515 -295.120002)
			(xy 103.237758 -295.066052) (xy 86.100666 -295.066052) (xy 86.100666 -297.515026) (xy 88.21548 -297.515026)
			(xy 88.219461 -297.382006) (xy 88.23139 -297.249461) (xy 88.251225 -297.117868) (xy 88.278894 -296.987696)
			(xy 88.314298 -296.859411) (xy 88.357311 -296.733474) (xy 88.407778 -296.610335) (xy 88.465519 -296.490434)
			(xy 88.530328 -296.374201) (xy 88.601972 -296.262051) (xy 88.680194 -296.154387) (xy 88.764715 -296.051594)
			(xy 88.855233 -295.954039) (xy 88.951422 -295.862073) (xy 89.05294 -295.776023) (xy 89.159421 -295.696199)
			(xy 89.270486 -295.622886) (xy 89.385737 -295.556346) (xy 89.504761 -295.496817) (xy 89.627132 -295.444513)
			(xy 89.752411 -295.399621) (xy 89.880152 -295.362302) (xy 90.009895 -295.332689) (xy 90.141177 -295.310888)
			(xy 90.273528 -295.296978) (xy 90.406474 -295.291007) (xy 90.539539 -295.292998) (xy 90.672247 -295.302943)
			(xy 90.804123 -295.320807) (xy 90.934694 -295.346525) (xy 91.063494 -295.380006) (xy 91.19006 -295.42113)
			(xy 91.313941 -295.46975) (xy 91.434692 -295.525691) (xy 91.551882 -295.588753) (xy 91.665091 -295.658711)
			(xy 91.773913 -295.735315) (xy 91.877959 -295.818289) (xy 91.976857 -295.907337) (xy 92.070252 -296.00214)
			(xy 92.15781 -296.102358) (xy 92.239219 -296.207634) (xy 92.314185 -296.31759) (xy 92.382442 -296.431832)
			(xy 92.443744 -296.549952) (xy 92.497873 -296.671527) (xy 92.544634 -296.796121) (xy 92.58386 -296.923289)
			(xy 92.61541 -297.052575) (xy 92.624896 -297.104848) (xy 103.237816 -297.104848) (xy 103.237816 -297.050352)
			(xy 103.245572 -296.99641) (xy 103.260925 -296.944121) (xy 103.283563 -296.89455) (xy 103.313026 -296.848704)
			(xy 103.348713 -296.807518) (xy 103.389898 -296.771831) (xy 103.435743 -296.742367) (xy 103.485314 -296.719728)
			(xy 103.537602 -296.704373) (xy 103.591544 -296.696617) (xy 103.618792 -296.69613) (xy 103.647293 -296.696651)
			(xy 103.703661 -296.705141) (xy 103.758134 -296.721932) (xy 103.809499 -296.74665) (xy 103.856609 -296.778743)
			(xy 103.877872 -296.79773) (xy 103.889426 -296.807651) (xy 103.916861 -296.820834) (xy 103.94696 -296.825361)
			(xy 103.977059 -296.820834) (xy 104.004494 -296.807651) (xy 104.016048 -296.79773) (xy 104.037326 -296.778766)
			(xy 104.08445 -296.746708) (xy 104.135814 -296.722005) (xy 104.190277 -296.705207) (xy 104.246631 -296.696685)
			(xy 104.275128 -296.69613) (xy 104.302381 -296.696542) (xy 104.356331 -296.704302) (xy 104.408627 -296.719661)
			(xy 104.458206 -296.742306) (xy 104.504057 -296.771776) (xy 104.545248 -296.807471) (xy 104.58094 -296.848665)
			(xy 104.610407 -296.894519) (xy 104.633048 -296.944099) (xy 104.648404 -296.996397) (xy 104.65616 -297.050347)
			(xy 104.65616 -297.104853) (xy 104.648404 -297.158803) (xy 104.633048 -297.211101) (xy 104.626677 -297.225052)
			(xy 109.276358 -297.225052) (xy 109.276358 -297.170548) (xy 109.284114 -297.116598) (xy 109.29947 -297.064302)
			(xy 109.322111 -297.014723) (xy 109.351578 -296.968871) (xy 109.38727 -296.927678) (xy 109.428461 -296.891985)
			(xy 109.474312 -296.862517) (xy 109.523891 -296.839874) (xy 109.576187 -296.824517) (xy 109.630136 -296.816759)
			(xy 109.657388 -296.816272) (xy 109.685428 -296.816774) (xy 109.740905 -296.824973) (xy 109.794587 -296.841197)
			(xy 109.84532 -296.865097) (xy 109.892012 -296.896159) (xy 109.913166 -296.91457) (xy 109.924608 -296.924215)
			(xy 109.951651 -296.936995) (xy 109.981238 -296.941381) (xy 110.010825 -296.936995) (xy 110.037868 -296.924215)
			(xy 110.04931 -296.91457) (xy 110.070435 -296.896119) (xy 110.11712 -296.86503) (xy 110.167857 -296.841121)
			(xy 110.221552 -296.824908) (xy 110.277043 -296.816741) (xy 110.305088 -296.816272) (xy 110.333128 -296.816774)
			(xy 110.388605 -296.824973) (xy 110.442287 -296.841197) (xy 110.49302 -296.865097) (xy 110.539712 -296.896159)
			(xy 110.560866 -296.91457) (xy 110.572308 -296.924215) (xy 110.599351 -296.936995) (xy 110.628938 -296.941381)
			(xy 110.658525 -296.936995) (xy 110.685568 -296.924215) (xy 110.69701 -296.91457) (xy 110.718135 -296.896119)
			(xy 110.76482 -296.86503) (xy 110.815557 -296.841121) (xy 110.869252 -296.824908) (xy 110.924743 -296.816741)
			(xy 110.952788 -296.816272) (xy 110.98004 -296.816774) (xy 111.033989 -296.82453) (xy 111.086286 -296.839884)
			(xy 111.135865 -296.862524) (xy 111.181717 -296.891991) (xy 111.222909 -296.927682) (xy 111.258602 -296.968873)
			(xy 111.28807 -297.014724) (xy 111.310712 -297.064303) (xy 111.326068 -297.116599) (xy 111.333825 -297.170548)
			(xy 111.333825 -297.225052) (xy 115.746758 -297.225052) (xy 115.746758 -297.170548) (xy 115.754514 -297.116599)
			(xy 115.769869 -297.064303) (xy 115.792511 -297.014724) (xy 115.821977 -296.968872) (xy 115.857669 -296.92768)
			(xy 115.898859 -296.891987) (xy 115.94471 -296.862518) (xy 115.994288 -296.839875) (xy 116.046583 -296.824518)
			(xy 116.100532 -296.816759) (xy 116.127784 -296.816272) (xy 116.155155 -296.81673) (xy 116.209335 -296.824547)
			(xy 116.261839 -296.840037) (xy 116.311586 -296.862881) (xy 116.357551 -296.892609) (xy 116.378482 -296.910252)
			(xy 116.38981 -296.919488) (xy 116.416367 -296.931664) (xy 116.445284 -296.935837) (xy 116.474201 -296.931664)
			(xy 116.500758 -296.919488) (xy 116.512086 -296.910252) (xy 116.533019 -296.892611) (xy 116.578987 -296.862887)
			(xy 116.628733 -296.840041) (xy 116.681235 -296.824545) (xy 116.735413 -296.816716) (xy 116.790155 -296.816716)
			(xy 116.844333 -296.824545) (xy 116.896835 -296.840041) (xy 116.946581 -296.862887) (xy 116.992549 -296.892611)
			(xy 117.013482 -296.910252) (xy 117.02481 -296.919488) (xy 117.051367 -296.931664) (xy 117.080284 -296.935837)
			(xy 117.109201 -296.931664) (xy 117.135758 -296.919488) (xy 117.147086 -296.910252) (xy 117.168019 -296.892614)
			(xy 117.213991 -296.8629) (xy 117.263738 -296.840063) (xy 117.316239 -296.824572) (xy 117.370415 -296.816745)
			(xy 117.397784 -296.816272) (xy 117.425036 -296.816774) (xy 117.478986 -296.824529) (xy 117.531283 -296.839883)
			(xy 117.580863 -296.862523) (xy 117.626715 -296.891989) (xy 117.667908 -296.927681) (xy 117.703601 -296.968872)
			(xy 117.733069 -297.014723) (xy 117.755712 -297.064302) (xy 117.771068 -297.116598) (xy 117.778825 -297.170548)
			(xy 117.778825 -297.19778) (xy 122.307602 -297.19778) (xy 122.311673 -297.142158) (xy 122.323799 -297.087721)
			(xy 122.343722 -297.03563) (xy 122.371018 -296.986995) (xy 122.405104 -296.942852) (xy 122.445253 -296.904143)
			(xy 122.490611 -296.871692) (xy 122.540211 -296.846191) (xy 122.592995 -296.828184) (xy 122.647838 -296.818054)
			(xy 122.703572 -296.816017) (xy 122.759009 -296.822117) (xy 122.812966 -296.836223) (xy 122.864295 -296.858035)
			(xy 122.911901 -296.887089) (xy 122.954769 -296.922764) (xy 122.991986 -296.964301) (xy 123.022759 -297.010814)
			(xy 123.046431 -297.061311) (xy 123.062499 -297.114718) (xy 123.070619 -297.169894) (xy 123.071128 -297.19778)
			(xy 123.070619 -297.225666) (xy 123.062499 -297.280842) (xy 123.046431 -297.334249) (xy 123.022759 -297.384746)
			(xy 122.991986 -297.431259) (xy 122.954769 -297.472796) (xy 122.911901 -297.508471) (xy 122.90116 -297.515026)
			(xy 131.195582 -297.515026) (xy 131.199563 -297.382006) (xy 131.211492 -297.249461) (xy 131.231327 -297.117868)
			(xy 131.258996 -296.987696) (xy 131.2944 -296.859411) (xy 131.337413 -296.733474) (xy 131.38788 -296.610335)
			(xy 131.445621 -296.490434) (xy 131.51043 -296.374201) (xy 131.582074 -296.262051) (xy 131.660296 -296.154387)
			(xy 131.744817 -296.051594) (xy 131.835335 -295.954039) (xy 131.931524 -295.862073) (xy 132.033042 -295.776023)
			(xy 132.139523 -295.696199) (xy 132.250588 -295.622886) (xy 132.365839 -295.556346) (xy 132.484863 -295.496817)
			(xy 132.607234 -295.444513) (xy 132.732513 -295.399621) (xy 132.860254 -295.362302) (xy 132.989997 -295.332689)
			(xy 133.121279 -295.310888) (xy 133.25363 -295.296978) (xy 133.386576 -295.291007) (xy 133.519641 -295.292998)
			(xy 133.652349 -295.302943) (xy 133.784225 -295.320807) (xy 133.914796 -295.346525) (xy 134.043596 -295.380006)
			(xy 134.170162 -295.42113) (xy 134.294043 -295.46975) (xy 134.414794 -295.525691) (xy 134.531984 -295.588753)
			(xy 134.645193 -295.658711) (xy 134.754015 -295.735315) (xy 134.858061 -295.818289) (xy 134.956959 -295.907337)
			(xy 135.050354 -296.00214) (xy 135.137912 -296.102358) (xy 135.219321 -296.207634) (xy 135.294287 -296.31759)
			(xy 135.362544 -296.431832) (xy 135.423846 -296.549952) (xy 135.477975 -296.671527) (xy 135.524736 -296.796121)
			(xy 135.563962 -296.923289) (xy 135.595512 -297.052575) (xy 135.619275 -297.183516) (xy 135.635164 -297.315644)
			(xy 135.643122 -297.448486) (xy 135.64362 -297.515026) (xy 135.643122 -297.581566) (xy 135.635164 -297.714408)
			(xy 135.619275 -297.846536) (xy 135.595512 -297.977477) (xy 135.563962 -298.106763) (xy 135.524736 -298.233931)
			(xy 135.477975 -298.358525) (xy 135.423846 -298.4801) (xy 135.362544 -298.59822) (xy 135.294287 -298.712462)
			(xy 135.219321 -298.822418) (xy 135.137912 -298.927694) (xy 135.050354 -299.027912) (xy 134.956959 -299.122715)
			(xy 134.858061 -299.211763) (xy 134.754015 -299.294737) (xy 134.645193 -299.371341) (xy 134.531984 -299.441299)
			(xy 134.414794 -299.504361) (xy 134.294043 -299.560302) (xy 134.170162 -299.608922) (xy 134.043596 -299.650046)
			(xy 133.914796 -299.683527) (xy 133.784225 -299.709245) (xy 133.652349 -299.727109) (xy 133.519641 -299.737054)
			(xy 133.386576 -299.739045) (xy 133.25363 -299.733074) (xy 133.121279 -299.719164) (xy 132.989997 -299.697363)
			(xy 132.860254 -299.66775) (xy 132.732513 -299.630431) (xy 132.607234 -299.585539) (xy 132.484863 -299.533235)
			(xy 132.365839 -299.473706) (xy 132.250588 -299.407166) (xy 132.139523 -299.333853) (xy 132.033042 -299.254029)
			(xy 131.931524 -299.167979) (xy 131.835335 -299.076013) (xy 131.744817 -298.978458) (xy 131.660296 -298.875665)
			(xy 131.582074 -298.768001) (xy 131.51043 -298.655851) (xy 131.445621 -298.539618) (xy 131.38788 -298.419717)
			(xy 131.337413 -298.296578) (xy 131.2944 -298.170641) (xy 131.258996 -298.042356) (xy 131.231327 -297.912184)
			(xy 131.211492 -297.780591) (xy 131.199563 -297.648046) (xy 131.195582 -297.515026) (xy 122.90116 -297.515026)
			(xy 122.864295 -297.537525) (xy 122.812966 -297.559337) (xy 122.759009 -297.573443) (xy 122.703572 -297.579543)
			(xy 122.647838 -297.577506) (xy 122.592995 -297.567376) (xy 122.540211 -297.549369) (xy 122.490611 -297.523868)
			(xy 122.445253 -297.491417) (xy 122.405104 -297.452708) (xy 122.371018 -297.408565) (xy 122.343722 -297.35993)
			(xy 122.323799 -297.307839) (xy 122.311673 -297.253402) (xy 122.307602 -297.19778) (xy 117.778825 -297.19778)
			(xy 117.778825 -297.225052) (xy 117.771068 -297.279002) (xy 117.755712 -297.331298) (xy 117.733069 -297.380877)
			(xy 117.703601 -297.426728) (xy 117.667908 -297.467919) (xy 117.626715 -297.503611) (xy 117.580863 -297.533077)
			(xy 117.531283 -297.555717) (xy 117.478986 -297.571071) (xy 117.425036 -297.578826) (xy 117.397784 -297.579288)
			(xy 117.370413 -297.578834) (xy 117.316234 -297.571014) (xy 117.26373 -297.555522) (xy 117.213984 -297.532678)
			(xy 117.168017 -297.50295) (xy 117.147086 -297.485308) (xy 117.135758 -297.476072) (xy 117.109201 -297.463896)
			(xy 117.080284 -297.459723) (xy 117.051367 -297.463896) (xy 117.02481 -297.476072) (xy 117.013482 -297.485308)
			(xy 116.992549 -297.502949) (xy 116.946581 -297.532673) (xy 116.896835 -297.555519) (xy 116.844333 -297.571015)
			(xy 116.790155 -297.578844) (xy 116.735413 -297.578844) (xy 116.681235 -297.571015) (xy 116.628733 -297.555519)
			(xy 116.578987 -297.532673) (xy 116.533019 -297.502949) (xy 116.512086 -297.485308) (xy 116.500758 -297.476072)
			(xy 116.474201 -297.463896) (xy 116.445284 -297.459723) (xy 116.416367 -297.463896) (xy 116.38981 -297.476072)
			(xy 116.378482 -297.485308) (xy 116.357531 -297.502923) (xy 116.311563 -297.532638) (xy 116.26182 -297.555479)
			(xy 116.209324 -297.570976) (xy 116.155152 -297.57881) (xy 116.127784 -297.579288) (xy 116.100532 -297.578841)
			(xy 116.046583 -297.571082) (xy 115.994288 -297.555725) (xy 115.94471 -297.533082) (xy 115.898859 -297.503613)
			(xy 115.857669 -297.46792) (xy 115.821977 -297.426728) (xy 115.792511 -297.380876) (xy 115.769869 -297.331297)
			(xy 115.754514 -297.279001) (xy 115.746758 -297.225052) (xy 111.333825 -297.225052) (xy 111.326068 -297.279001)
			(xy 111.310712 -297.331297) (xy 111.28807 -297.380876) (xy 111.258602 -297.426727) (xy 111.222909 -297.467918)
			(xy 111.181717 -297.503609) (xy 111.135865 -297.533076) (xy 111.086286 -297.555716) (xy 111.033989 -297.57107)
			(xy 110.98004 -297.578826) (xy 110.952788 -297.579288) (xy 110.924747 -297.578811) (xy 110.869268 -297.570607)
			(xy 110.815585 -297.554378) (xy 110.764853 -297.530472) (xy 110.718163 -297.499404) (xy 110.69701 -297.48099)
			(xy 110.685568 -297.471345) (xy 110.658525 -297.458565) (xy 110.628938 -297.454179) (xy 110.599351 -297.458565)
			(xy 110.572308 -297.471345) (xy 110.560866 -297.48099) (xy 110.539705 -297.499398) (xy 110.493031 -297.530495)
			(xy 110.442303 -297.554413) (xy 110.388616 -297.570636) (xy 110.333131 -297.578813) (xy 110.305088 -297.579288)
			(xy 110.277047 -297.578811) (xy 110.221568 -297.570607) (xy 110.167885 -297.554378) (xy 110.117153 -297.530472)
			(xy 110.070463 -297.499404) (xy 110.04931 -297.48099) (xy 110.037868 -297.471345) (xy 110.010825 -297.458565)
			(xy 109.981238 -297.454179) (xy 109.951651 -297.458565) (xy 109.924608 -297.471345) (xy 109.913166 -297.48099)
			(xy 109.892005 -297.499398) (xy 109.845331 -297.530495) (xy 109.794603 -297.554413) (xy 109.740916 -297.570636)
			(xy 109.685431 -297.578813) (xy 109.657388 -297.579288) (xy 109.630136 -297.578841) (xy 109.576187 -297.571083)
			(xy 109.523891 -297.555726) (xy 109.474312 -297.533083) (xy 109.428461 -297.503615) (xy 109.38727 -297.467922)
			(xy 109.351578 -297.426729) (xy 109.322111 -297.380877) (xy 109.29947 -297.331298) (xy 109.284114 -297.279002)
			(xy 109.276358 -297.225052) (xy 104.626677 -297.225052) (xy 104.610407 -297.260681) (xy 104.58094 -297.306535)
			(xy 104.545248 -297.347729) (xy 104.504057 -297.383424) (xy 104.458206 -297.412894) (xy 104.408627 -297.435539)
			(xy 104.356331 -297.450898) (xy 104.302381 -297.458658) (xy 104.275128 -297.459146) (xy 104.246627 -297.458619)
			(xy 104.19026 -297.450131) (xy 104.135786 -297.433342) (xy 104.084421 -297.408625) (xy 104.037311 -297.376532)
			(xy 104.016048 -297.357546) (xy 104.004494 -297.347625) (xy 103.977059 -297.334442) (xy 103.94696 -297.329915)
			(xy 103.916861 -297.334442) (xy 103.889426 -297.347625) (xy 103.877872 -297.357546) (xy 103.856582 -297.376496)
			(xy 103.809462 -297.408558) (xy 103.758101 -297.433263) (xy 103.703641 -297.450065) (xy 103.647288 -297.458589)
			(xy 103.618792 -297.459146) (xy 103.591544 -297.458583) (xy 103.537602 -297.450827) (xy 103.485314 -297.435472)
			(xy 103.435743 -297.412833) (xy 103.389898 -297.383369) (xy 103.348713 -297.347682) (xy 103.313026 -297.306496)
			(xy 103.283563 -297.26065) (xy 103.260925 -297.211079) (xy 103.245572 -297.15879) (xy 103.237816 -297.104848)
			(xy 92.624896 -297.104848) (xy 92.639173 -297.183516) (xy 92.655062 -297.315644) (xy 92.66302 -297.448486)
			(xy 92.663518 -297.515026) (xy 92.66302 -297.581566) (xy 92.655062 -297.714408) (xy 92.639173 -297.846536)
			(xy 92.61541 -297.977477) (xy 92.58386 -298.106763) (xy 92.544634 -298.233931) (xy 92.497873 -298.358525)
			(xy 92.443744 -298.4801) (xy 92.382442 -298.59822) (xy 92.314185 -298.712462) (xy 92.239219 -298.822418)
			(xy 92.15781 -298.927694) (xy 92.070252 -299.027912) (xy 91.976857 -299.122715) (xy 91.877959 -299.211763)
			(xy 91.773913 -299.294737) (xy 91.665091 -299.371341) (xy 91.551882 -299.441299) (xy 91.434692 -299.504361)
			(xy 91.313941 -299.560302) (xy 91.19006 -299.608922) (xy 91.063494 -299.650046) (xy 90.934694 -299.683527)
			(xy 90.804123 -299.709245) (xy 90.672247 -299.727109) (xy 90.539539 -299.737054) (xy 90.406474 -299.739045)
			(xy 90.273528 -299.733074) (xy 90.141177 -299.719164) (xy 90.009895 -299.697363) (xy 89.880152 -299.66775)
			(xy 89.752411 -299.630431) (xy 89.627132 -299.585539) (xy 89.504761 -299.533235) (xy 89.385737 -299.473706)
			(xy 89.270486 -299.407166) (xy 89.159421 -299.333853) (xy 89.05294 -299.254029) (xy 88.951422 -299.167979)
			(xy 88.855233 -299.076013) (xy 88.764715 -298.978458) (xy 88.680194 -298.875665) (xy 88.601972 -298.768001)
			(xy 88.530328 -298.655851) (xy 88.465519 -298.539618) (xy 88.407778 -298.419717) (xy 88.357311 -298.296578)
			(xy 88.314298 -298.170641) (xy 88.278894 -298.042356) (xy 88.251225 -297.912184) (xy 88.23139 -297.780591)
			(xy 88.219461 -297.648046) (xy 88.21548 -297.515026) (xy 86.100666 -297.515026) (xy 86.100666 -312.740548)
			(xy 85.540522 -315.709738) (xy 97.636834 -315.709738) (xy 97.636834 -315.625042) (xy 97.644885 -315.540728)
			(xy 97.660914 -315.457562) (xy 97.684775 -315.376295) (xy 97.716254 -315.297665) (xy 97.755065 -315.222384)
			(xy 97.800855 -315.151132) (xy 97.853211 -315.084556) (xy 97.911659 -315.023258) (xy 97.975669 -314.967793)
			(xy 98.044661 -314.918664) (xy 98.118011 -314.876315) (xy 98.195054 -314.841131) (xy 98.275093 -314.813429)
			(xy 98.357402 -314.793461) (xy 98.441237 -314.781408) (xy 98.525838 -314.777378) (xy 98.610439 -314.781408)
			(xy 98.694274 -314.793461) (xy 98.776583 -314.813429) (xy 98.856622 -314.841131) (xy 98.933665 -314.876315)
			(xy 99.007015 -314.918664) (xy 99.076007 -314.967793) (xy 99.140017 -315.023258) (xy 99.198465 -315.084556)
			(xy 99.250821 -315.151132) (xy 99.296611 -315.222384) (xy 99.335422 -315.297665) (xy 99.366901 -315.376295)
			(xy 99.390762 -315.457562) (xy 99.406791 -315.540728) (xy 99.414842 -315.625042) (xy 99.415346 -315.66739)
			(xy 99.610423 -315.66739) (xy 99.614445 -315.58167) (xy 99.626476 -315.496702) (xy 99.646412 -315.413235)
			(xy 99.674075 -315.332001) (xy 99.709224 -315.253715) (xy 99.75155 -315.179064) (xy 99.800679 -315.108705)
			(xy 99.856182 -315.043255) (xy 99.917569 -314.983291) (xy 99.984302 -314.929338) (xy 100.055794 -314.881871)
			(xy 100.131416 -314.841307) (xy 100.210505 -314.808003) (xy 100.292365 -314.782251) (xy 100.376276 -314.764278)
			(xy 100.461502 -314.754242) (xy 100.547294 -314.75223) (xy 100.632896 -314.758261) (xy 100.717558 -314.772281)
			(xy 100.800535 -314.794167) (xy 100.881098 -314.823728) (xy 100.958538 -314.860702) (xy 101.032177 -314.904766)
			(xy 101.101365 -314.955532) (xy 101.165496 -315.012553) (xy 101.224005 -315.075329) (xy 101.276378 -315.143309)
			(xy 101.322156 -315.215894) (xy 101.360936 -315.292446) (xy 101.392377 -315.372294) (xy 101.416203 -315.454735)
			(xy 101.432204 -315.539045) (xy 101.440239 -315.624483) (xy 101.440742 -315.66739) (xy 101.440246 -315.709738)
			(xy 103.834434 -315.709738) (xy 103.834434 -315.625042) (xy 103.842485 -315.540728) (xy 103.858514 -315.457562)
			(xy 103.882375 -315.376295) (xy 103.913854 -315.297665) (xy 103.952665 -315.222384) (xy 103.998455 -315.151132)
			(xy 104.050811 -315.084556) (xy 104.109259 -315.023258) (xy 104.173269 -314.967793) (xy 104.242261 -314.918664)
			(xy 104.315611 -314.876315) (xy 104.392654 -314.841131) (xy 104.472693 -314.813429) (xy 104.555002 -314.793461)
			(xy 104.638837 -314.781408) (xy 104.723438 -314.777378) (xy 104.808039 -314.781408) (xy 104.891874 -314.793461)
			(xy 104.974183 -314.813429) (xy 105.054222 -314.841131) (xy 105.131265 -314.876315) (xy 105.204615 -314.918664)
			(xy 105.273607 -314.967793) (xy 105.337617 -315.023258) (xy 105.396065 -315.084556) (xy 105.448421 -315.151132)
			(xy 105.494211 -315.222384) (xy 105.533022 -315.297665) (xy 105.564501 -315.376295) (xy 105.588362 -315.457562)
			(xy 105.604391 -315.540728) (xy 105.612442 -315.625042) (xy 105.612946 -315.66739) (xy 105.808023 -315.66739)
			(xy 105.812045 -315.58167) (xy 105.824076 -315.496702) (xy 105.844012 -315.413235) (xy 105.871675 -315.332001)
			(xy 105.906824 -315.253715) (xy 105.94915 -315.179064) (xy 105.998279 -315.108705) (xy 106.053782 -315.043255)
			(xy 106.115169 -314.983291) (xy 106.181902 -314.929338) (xy 106.253394 -314.881871) (xy 106.329016 -314.841307)
			(xy 106.408105 -314.808003) (xy 106.489965 -314.782251) (xy 106.573876 -314.764278) (xy 106.659102 -314.754242)
			(xy 106.744894 -314.75223) (xy 106.830496 -314.758261) (xy 106.915158 -314.772281) (xy 106.998135 -314.794167)
			(xy 107.078698 -314.823728) (xy 107.156138 -314.860702) (xy 107.229777 -314.904766) (xy 107.298965 -314.955532)
			(xy 107.363096 -315.012553) (xy 107.421605 -315.075329) (xy 107.473978 -315.143309) (xy 107.519756 -315.215894)
			(xy 107.558536 -315.292446) (xy 107.589977 -315.372294) (xy 107.613803 -315.454735) (xy 107.629804 -315.539045)
			(xy 107.637839 -315.624483) (xy 107.638342 -315.66739) (xy 107.637846 -315.709738) (xy 110.012222 -315.709738)
			(xy 110.012222 -315.625042) (xy 110.020273 -315.540728) (xy 110.036302 -315.457562) (xy 110.060163 -315.376295)
			(xy 110.091642 -315.297665) (xy 110.130453 -315.222384) (xy 110.176243 -315.151132) (xy 110.228599 -315.084556)
			(xy 110.287047 -315.023258) (xy 110.351057 -314.967793) (xy 110.420049 -314.918664) (xy 110.493399 -314.876315)
			(xy 110.570442 -314.841131) (xy 110.650481 -314.813429) (xy 110.73279 -314.793461) (xy 110.816625 -314.781408)
			(xy 110.901226 -314.777378) (xy 110.985827 -314.781408) (xy 111.069662 -314.793461) (xy 111.151971 -314.813429)
			(xy 111.23201 -314.841131) (xy 111.309053 -314.876315) (xy 111.382403 -314.918664) (xy 111.451395 -314.967793)
			(xy 111.515405 -315.023258) (xy 111.573853 -315.084556) (xy 111.626209 -315.151132) (xy 111.671999 -315.222384)
			(xy 111.71081 -315.297665) (xy 111.742289 -315.376295) (xy 111.76615 -315.457562) (xy 111.782179 -315.540728)
			(xy 111.79023 -315.625042) (xy 111.790734 -315.66739) (xy 111.985811 -315.66739) (xy 111.989833 -315.58167)
			(xy 112.001864 -315.496702) (xy 112.0218 -315.413235) (xy 112.049463 -315.332001) (xy 112.084612 -315.253715)
			(xy 112.126938 -315.179064) (xy 112.176067 -315.108705) (xy 112.23157 -315.043255) (xy 112.292957 -314.983291)
			(xy 112.35969 -314.929338) (xy 112.431182 -314.881871) (xy 112.506804 -314.841307) (xy 112.585893 -314.808003)
			(xy 112.667753 -314.782251) (xy 112.751664 -314.764278) (xy 112.83689 -314.754242) (xy 112.922682 -314.75223)
			(xy 113.008284 -314.758261) (xy 113.092946 -314.772281) (xy 113.175923 -314.794167) (xy 113.256486 -314.823728)
			(xy 113.333926 -314.860702) (xy 113.407565 -314.904766) (xy 113.476753 -314.955532) (xy 113.540884 -315.012553)
			(xy 113.599393 -315.075329) (xy 113.651766 -315.143309) (xy 113.697544 -315.215894) (xy 113.736324 -315.292446)
			(xy 113.767765 -315.372294) (xy 113.791591 -315.454735) (xy 113.807592 -315.539045) (xy 113.815627 -315.624483)
			(xy 113.81613 -315.66739) (xy 113.815634 -315.709738) (xy 116.209822 -315.709738) (xy 116.209822 -315.625042)
			(xy 116.217873 -315.540728) (xy 116.233902 -315.457562) (xy 116.257763 -315.376295) (xy 116.289242 -315.297665)
			(xy 116.328053 -315.222384) (xy 116.373843 -315.151132) (xy 116.426199 -315.084556) (xy 116.484647 -315.023258)
			(xy 116.548657 -314.967793) (xy 116.617649 -314.918664) (xy 116.690999 -314.876315) (xy 116.768042 -314.841131)
			(xy 116.848081 -314.813429) (xy 116.93039 -314.793461) (xy 117.014225 -314.781408) (xy 117.098826 -314.777378)
			(xy 117.183427 -314.781408) (xy 117.267262 -314.793461) (xy 117.349571 -314.813429) (xy 117.42961 -314.841131)
			(xy 117.506653 -314.876315) (xy 117.580003 -314.918664) (xy 117.648995 -314.967793) (xy 117.713005 -315.023258)
			(xy 117.771453 -315.084556) (xy 117.823809 -315.151132) (xy 117.869599 -315.222384) (xy 117.90841 -315.297665)
			(xy 117.939889 -315.376295) (xy 117.96375 -315.457562) (xy 117.979779 -315.540728) (xy 117.98783 -315.625042)
			(xy 117.988334 -315.66739) (xy 118.183411 -315.66739) (xy 118.187433 -315.58167) (xy 118.199464 -315.496702)
			(xy 118.2194 -315.413235) (xy 118.247063 -315.332001) (xy 118.282212 -315.253715) (xy 118.324538 -315.179064)
			(xy 118.373667 -315.108705) (xy 118.42917 -315.043255) (xy 118.490557 -314.983291) (xy 118.55729 -314.929338)
			(xy 118.628782 -314.881871) (xy 118.704404 -314.841307) (xy 118.783493 -314.808003) (xy 118.865353 -314.782251)
			(xy 118.949264 -314.764278) (xy 119.03449 -314.754242) (xy 119.120282 -314.75223) (xy 119.205884 -314.758261)
			(xy 119.290546 -314.772281) (xy 119.373523 -314.794167) (xy 119.454086 -314.823728) (xy 119.531526 -314.860702)
			(xy 119.605165 -314.904766) (xy 119.674353 -314.955532) (xy 119.738484 -315.012553) (xy 119.796993 -315.075329)
			(xy 119.849366 -315.143309) (xy 119.895144 -315.215894) (xy 119.933924 -315.292446) (xy 119.965365 -315.372294)
			(xy 119.989191 -315.454735) (xy 120.005192 -315.539045) (xy 120.013227 -315.624483) (xy 120.01373 -315.66739)
			(xy 120.013234 -315.709738) (xy 122.407422 -315.709738) (xy 122.407422 -315.625042) (xy 122.415473 -315.540728)
			(xy 122.431502 -315.457562) (xy 122.455363 -315.376295) (xy 122.486842 -315.297665) (xy 122.525653 -315.222384)
			(xy 122.571443 -315.151132) (xy 122.623799 -315.084556) (xy 122.682247 -315.023258) (xy 122.746257 -314.967793)
			(xy 122.815249 -314.918664) (xy 122.888599 -314.876315) (xy 122.965642 -314.841131) (xy 123.045681 -314.813429)
			(xy 123.12799 -314.793461) (xy 123.211825 -314.781408) (xy 123.296426 -314.777378) (xy 123.381027 -314.781408)
			(xy 123.464862 -314.793461) (xy 123.547171 -314.813429) (xy 123.62721 -314.841131) (xy 123.704253 -314.876315)
			(xy 123.777603 -314.918664) (xy 123.846595 -314.967793) (xy 123.910605 -315.023258) (xy 123.969053 -315.084556)
			(xy 124.021409 -315.151132) (xy 124.067199 -315.222384) (xy 124.10601 -315.297665) (xy 124.137489 -315.376295)
			(xy 124.16135 -315.457562) (xy 124.177379 -315.540728) (xy 124.18543 -315.625042) (xy 124.185934 -315.66739)
			(xy 124.381011 -315.66739) (xy 124.385033 -315.58167) (xy 124.397064 -315.496702) (xy 124.417 -315.413235)
			(xy 124.444663 -315.332001) (xy 124.479812 -315.253715) (xy 124.522138 -315.179064) (xy 124.571267 -315.108705)
			(xy 124.62677 -315.043255) (xy 124.688157 -314.983291) (xy 124.75489 -314.929338) (xy 124.826382 -314.881871)
			(xy 124.902004 -314.841307) (xy 124.981093 -314.808003) (xy 125.062953 -314.782251) (xy 125.146864 -314.764278)
			(xy 125.23209 -314.754242) (xy 125.317882 -314.75223) (xy 125.403484 -314.758261) (xy 125.488146 -314.772281)
			(xy 125.571123 -314.794167) (xy 125.651686 -314.823728) (xy 125.729126 -314.860702) (xy 125.802765 -314.904766)
			(xy 125.871953 -314.955532) (xy 125.936084 -315.012553) (xy 125.994593 -315.075329) (xy 126.046966 -315.143309)
			(xy 126.092744 -315.215894) (xy 126.131524 -315.292446) (xy 126.162965 -315.372294) (xy 126.186791 -315.454735)
			(xy 126.202792 -315.539045) (xy 126.210827 -315.624483) (xy 126.21133 -315.66739) (xy 126.210827 -315.710297)
			(xy 126.202792 -315.795735) (xy 126.186791 -315.880045) (xy 126.162965 -315.962486) (xy 126.131524 -316.042334)
			(xy 126.092744 -316.118886) (xy 126.046966 -316.191471) (xy 125.994593 -316.259451) (xy 125.936084 -316.322227)
			(xy 125.871953 -316.379248) (xy 125.802765 -316.430014) (xy 125.729126 -316.474078) (xy 125.651686 -316.511052)
			(xy 125.571123 -316.540613) (xy 125.488146 -316.562499) (xy 125.403484 -316.576519) (xy 125.317882 -316.58255)
			(xy 125.23209 -316.580538) (xy 125.146864 -316.570502) (xy 125.062953 -316.552529) (xy 124.981093 -316.526777)
			(xy 124.902004 -316.493473) (xy 124.826382 -316.452909) (xy 124.75489 -316.405442) (xy 124.688157 -316.351489)
			(xy 124.62677 -316.291525) (xy 124.571267 -316.226075) (xy 124.522138 -316.155716) (xy 124.479812 -316.081065)
			(xy 124.444663 -316.002779) (xy 124.417 -315.921545) (xy 124.397064 -315.838078) (xy 124.385033 -315.75311)
			(xy 124.381011 -315.66739) (xy 124.185934 -315.66739) (xy 124.18543 -315.709738) (xy 124.177379 -315.794052)
			(xy 124.16135 -315.877218) (xy 124.137489 -315.958485) (xy 124.10601 -316.037115) (xy 124.067199 -316.112396)
			(xy 124.021409 -316.183648) (xy 123.969053 -316.250224) (xy 123.910605 -316.311522) (xy 123.846595 -316.366987)
			(xy 123.777603 -316.416116) (xy 123.704253 -316.458465) (xy 123.62721 -316.493649) (xy 123.547171 -316.521351)
			(xy 123.464862 -316.541319) (xy 123.381027 -316.553372) (xy 123.296426 -316.557403) (xy 123.211825 -316.553372)
			(xy 123.12799 -316.541319) (xy 123.045681 -316.521351) (xy 122.965642 -316.493649) (xy 122.888599 -316.458465)
			(xy 122.815249 -316.416116) (xy 122.746257 -316.366987) (xy 122.682247 -316.311522) (xy 122.623799 -316.250224)
			(xy 122.571443 -316.183648) (xy 122.525653 -316.112396) (xy 122.486842 -316.037115) (xy 122.455363 -315.958485)
			(xy 122.431502 -315.877218) (xy 122.415473 -315.794052) (xy 122.407422 -315.709738) (xy 120.013234 -315.709738)
			(xy 120.013227 -315.710297) (xy 120.005192 -315.795735) (xy 119.989191 -315.880045) (xy 119.965365 -315.962486)
			(xy 119.933924 -316.042334) (xy 119.895144 -316.118886) (xy 119.849366 -316.191471) (xy 119.796993 -316.259451)
			(xy 119.738484 -316.322227) (xy 119.674353 -316.379248) (xy 119.605165 -316.430014) (xy 119.531526 -316.474078)
			(xy 119.454086 -316.511052) (xy 119.373523 -316.540613) (xy 119.290546 -316.562499) (xy 119.205884 -316.576519)
			(xy 119.120282 -316.58255) (xy 119.03449 -316.580538) (xy 118.949264 -316.570502) (xy 118.865353 -316.552529)
			(xy 118.783493 -316.526777) (xy 118.704404 -316.493473) (xy 118.628782 -316.452909) (xy 118.55729 -316.405442)
			(xy 118.490557 -316.351489) (xy 118.42917 -316.291525) (xy 118.373667 -316.226075) (xy 118.324538 -316.155716)
			(xy 118.282212 -316.081065) (xy 118.247063 -316.002779) (xy 118.2194 -315.921545) (xy 118.199464 -315.838078)
			(xy 118.187433 -315.75311) (xy 118.183411 -315.66739) (xy 117.988334 -315.66739) (xy 117.98783 -315.709738)
			(xy 117.979779 -315.794052) (xy 117.96375 -315.877218) (xy 117.939889 -315.958485) (xy 117.90841 -316.037115)
			(xy 117.869599 -316.112396) (xy 117.823809 -316.183648) (xy 117.771453 -316.250224) (xy 117.713005 -316.311522)
			(xy 117.648995 -316.366987) (xy 117.580003 -316.416116) (xy 117.506653 -316.458465) (xy 117.42961 -316.493649)
			(xy 117.349571 -316.521351) (xy 117.267262 -316.541319) (xy 117.183427 -316.553372) (xy 117.098826 -316.557403)
			(xy 117.014225 -316.553372) (xy 116.93039 -316.541319) (xy 116.848081 -316.521351) (xy 116.768042 -316.493649)
			(xy 116.690999 -316.458465) (xy 116.617649 -316.416116) (xy 116.548657 -316.366987) (xy 116.484647 -316.311522)
			(xy 116.426199 -316.250224) (xy 116.373843 -316.183648) (xy 116.328053 -316.112396) (xy 116.289242 -316.037115)
			(xy 116.257763 -315.958485) (xy 116.233902 -315.877218) (xy 116.217873 -315.794052) (xy 116.209822 -315.709738)
			(xy 113.815634 -315.709738) (xy 113.815627 -315.710297) (xy 113.807592 -315.795735) (xy 113.791591 -315.880045)
			(xy 113.767765 -315.962486) (xy 113.736324 -316.042334) (xy 113.697544 -316.118886) (xy 113.651766 -316.191471)
			(xy 113.599393 -316.259451) (xy 113.540884 -316.322227) (xy 113.476753 -316.379248) (xy 113.407565 -316.430014)
			(xy 113.333926 -316.474078) (xy 113.256486 -316.511052) (xy 113.175923 -316.540613) (xy 113.092946 -316.562499)
			(xy 113.008284 -316.576519) (xy 112.922682 -316.58255) (xy 112.83689 -316.580538) (xy 112.751664 -316.570502)
			(xy 112.667753 -316.552529) (xy 112.585893 -316.526777) (xy 112.506804 -316.493473) (xy 112.431182 -316.452909)
			(xy 112.35969 -316.405442) (xy 112.292957 -316.351489) (xy 112.23157 -316.291525) (xy 112.176067 -316.226075)
			(xy 112.126938 -316.155716) (xy 112.084612 -316.081065) (xy 112.049463 -316.002779) (xy 112.0218 -315.921545)
			(xy 112.001864 -315.838078) (xy 111.989833 -315.75311) (xy 111.985811 -315.66739) (xy 111.790734 -315.66739)
			(xy 111.79023 -315.709738) (xy 111.782179 -315.794052) (xy 111.76615 -315.877218) (xy 111.742289 -315.958485)
			(xy 111.71081 -316.037115) (xy 111.671999 -316.112396) (xy 111.626209 -316.183648) (xy 111.573853 -316.250224)
			(xy 111.515405 -316.311522) (xy 111.451395 -316.366987) (xy 111.382403 -316.416116) (xy 111.309053 -316.458465)
			(xy 111.23201 -316.493649) (xy 111.151971 -316.521351) (xy 111.069662 -316.541319) (xy 110.985827 -316.553372)
			(xy 110.901226 -316.557403) (xy 110.816625 -316.553372) (xy 110.73279 -316.541319) (xy 110.650481 -316.521351)
			(xy 110.570442 -316.493649) (xy 110.493399 -316.458465) (xy 110.420049 -316.416116) (xy 110.351057 -316.366987)
			(xy 110.287047 -316.311522) (xy 110.228599 -316.250224) (xy 110.176243 -316.183648) (xy 110.130453 -316.112396)
			(xy 110.091642 -316.037115) (xy 110.060163 -315.958485) (xy 110.036302 -315.877218) (xy 110.020273 -315.794052)
			(xy 110.012222 -315.709738) (xy 107.637846 -315.709738) (xy 107.637839 -315.710297) (xy 107.629804 -315.795735)
			(xy 107.613803 -315.880045) (xy 107.589977 -315.962486) (xy 107.558536 -316.042334) (xy 107.519756 -316.118886)
			(xy 107.473978 -316.191471) (xy 107.421605 -316.259451) (xy 107.363096 -316.322227) (xy 107.298965 -316.379248)
			(xy 107.229777 -316.430014) (xy 107.156138 -316.474078) (xy 107.078698 -316.511052) (xy 106.998135 -316.540613)
			(xy 106.915158 -316.562499) (xy 106.830496 -316.576519) (xy 106.744894 -316.58255) (xy 106.659102 -316.580538)
			(xy 106.573876 -316.570502) (xy 106.489965 -316.552529) (xy 106.408105 -316.526777) (xy 106.329016 -316.493473)
			(xy 106.253394 -316.452909) (xy 106.181902 -316.405442) (xy 106.115169 -316.351489) (xy 106.053782 -316.291525)
			(xy 105.998279 -316.226075) (xy 105.94915 -316.155716) (xy 105.906824 -316.081065) (xy 105.871675 -316.002779)
			(xy 105.844012 -315.921545) (xy 105.824076 -315.838078) (xy 105.812045 -315.75311) (xy 105.808023 -315.66739)
			(xy 105.612946 -315.66739) (xy 105.612442 -315.709738) (xy 105.604391 -315.794052) (xy 105.588362 -315.877218)
			(xy 105.564501 -315.958485) (xy 105.533022 -316.037115) (xy 105.494211 -316.112396) (xy 105.448421 -316.183648)
			(xy 105.396065 -316.250224) (xy 105.337617 -316.311522) (xy 105.273607 -316.366987) (xy 105.204615 -316.416116)
			(xy 105.131265 -316.458465) (xy 105.054222 -316.493649) (xy 104.974183 -316.521351) (xy 104.891874 -316.541319)
			(xy 104.808039 -316.553372) (xy 104.723438 -316.557403) (xy 104.638837 -316.553372) (xy 104.555002 -316.541319)
			(xy 104.472693 -316.521351) (xy 104.392654 -316.493649) (xy 104.315611 -316.458465) (xy 104.242261 -316.416116)
			(xy 104.173269 -316.366987) (xy 104.109259 -316.311522) (xy 104.050811 -316.250224) (xy 103.998455 -316.183648)
			(xy 103.952665 -316.112396) (xy 103.913854 -316.037115) (xy 103.882375 -315.958485) (xy 103.858514 -315.877218)
			(xy 103.842485 -315.794052) (xy 103.834434 -315.709738) (xy 101.440246 -315.709738) (xy 101.440239 -315.710297)
			(xy 101.432204 -315.795735) (xy 101.416203 -315.880045) (xy 101.392377 -315.962486) (xy 101.360936 -316.042334)
			(xy 101.322156 -316.118886) (xy 101.276378 -316.191471) (xy 101.224005 -316.259451) (xy 101.165496 -316.322227)
			(xy 101.101365 -316.379248) (xy 101.032177 -316.430014) (xy 100.958538 -316.474078) (xy 100.881098 -316.511052)
			(xy 100.800535 -316.540613) (xy 100.717558 -316.562499) (xy 100.632896 -316.576519) (xy 100.547294 -316.58255)
			(xy 100.461502 -316.580538) (xy 100.376276 -316.570502) (xy 100.292365 -316.552529) (xy 100.210505 -316.526777)
			(xy 100.131416 -316.493473) (xy 100.055794 -316.452909) (xy 99.984302 -316.405442) (xy 99.917569 -316.351489)
			(xy 99.856182 -316.291525) (xy 99.800679 -316.226075) (xy 99.75155 -316.155716) (xy 99.709224 -316.081065)
			(xy 99.674075 -316.002779) (xy 99.646412 -315.921545) (xy 99.626476 -315.838078) (xy 99.614445 -315.75311)
			(xy 99.610423 -315.66739) (xy 99.415346 -315.66739) (xy 99.414842 -315.709738) (xy 99.406791 -315.794052)
			(xy 99.390762 -315.877218) (xy 99.366901 -315.958485) (xy 99.335422 -316.037115) (xy 99.296611 -316.112396)
			(xy 99.250821 -316.183648) (xy 99.198465 -316.250224) (xy 99.140017 -316.311522) (xy 99.076007 -316.366987)
			(xy 99.007015 -316.416116) (xy 98.933665 -316.458465) (xy 98.856622 -316.493649) (xy 98.776583 -316.521351)
			(xy 98.694274 -316.541319) (xy 98.610439 -316.553372) (xy 98.525838 -316.557403) (xy 98.441237 -316.553372)
			(xy 98.357402 -316.541319) (xy 98.275093 -316.521351) (xy 98.195054 -316.493649) (xy 98.118011 -316.458465)
			(xy 98.044661 -316.416116) (xy 97.975669 -316.366987) (xy 97.911659 -316.311522) (xy 97.853211 -316.250224)
			(xy 97.800855 -316.183648) (xy 97.755065 -316.112396) (xy 97.716254 -316.037115) (xy 97.684775 -315.958485)
			(xy 97.660914 -315.877218) (xy 97.644885 -315.794052) (xy 97.636834 -315.709738) (xy 85.540522 -315.709738)
			(xy 84.371942 -321.904106) (xy 80.309466 -327.472548) (xy 80.309466 -332.273402) (xy 80.614266 -332.578202)
			(xy 83.769962 -332.578202)
		)
		(stroke
			(width 0)
			(type solid)
		)
		(fill yes)
		(layer "In13.Cu")
		(net "PVCCIN_CPU1")
	)
	(gr_poly
		(pts
			(xy 94.639892 -373.771668) (xy 94.639892 -363.296708) (xy 94.640362 -363.267579) (xy 94.647999 -363.209824)
			(xy 94.663117 -363.153562) (xy 94.685457 -363.099758) (xy 94.714635 -363.049334) (xy 94.750152 -363.003155)
			(xy 94.770448 -362.982256) (xy 97.158048 -360.594656) (xy 97.178966 -360.574384) (xy 97.225154 -360.538892)
			(xy 97.275579 -360.50973) (xy 97.329377 -360.487397) (xy 97.38563 -360.472275) (xy 97.443375 -360.464622)
			(xy 97.4725 -360.4641) (xy 98.064828 -360.4641) (xy 98.074704 -360.463638) (xy 98.093 -360.456192)
			(xy 98.100388 -360.449622) (xy 99.165156 -359.384854) (xy 99.14382 -359.252266) (xy 99.120452 -359.240582)
			(xy 99.097133 -359.22832) (xy 99.053808 -359.198344) (xy 99.015017 -359.162694) (xy 98.981497 -359.122048)
			(xy 98.953886 -359.077178) (xy 98.932708 -359.028937) (xy 98.918366 -358.978242) (xy 98.911132 -358.926056)
			(xy 98.910648 -358.899714) (xy 98.911152 -358.871978) (xy 98.919195 -358.817093) (xy 98.935099 -358.763949)
			(xy 98.958529 -358.713669) (xy 98.988991 -358.667309) (xy 99.025844 -358.625849) (xy 99.068311 -358.59016)
			(xy 99.115497 -358.560995) (xy 99.166408 -358.538968) (xy 99.219972 -358.524544) (xy 99.247452 -358.520746)
			(xy 99.262184 -358.518968) (xy 99.292156 -358.517952) (xy 99.318498 -358.518398) (xy 99.370681 -358.525649)
			(xy 99.421371 -358.540004) (xy 99.469607 -358.561192) (xy 99.514472 -358.58881) (xy 99.555114 -358.622333)
			(xy 99.590761 -358.661126) (xy 99.620737 -358.70445) (xy 99.633024 -358.727756) (xy 99.644454 -358.751124)
			(xy 99.777296 -358.772714) (xy 100.159312 -358.390698) (xy 100.159312 -356.065328) (xy 100.15978 -356.036199)
			(xy 100.167415 -355.978443) (xy 100.182532 -355.92218) (xy 100.204871 -355.868375) (xy 100.234049 -355.81795)
			(xy 100.269566 -355.77177) (xy 100.289868 -355.750876) (xy 100.956364 -355.08438) (xy 100.977282 -355.064107)
			(xy 101.02347 -355.028612) (xy 101.073894 -354.999446) (xy 101.127692 -354.977107) (xy 101.183945 -354.961977)
			(xy 101.241691 -354.954315) (xy 101.270816 -354.953824) (xy 101.874066 -354.953824) (xy 101.904471 -354.954317)
			(xy 101.964715 -354.962593) (xy 102.02327 -354.978995) (xy 102.079047 -355.003219) (xy 102.131005 -355.034812)
			(xy 102.178178 -355.073186) (xy 102.219685 -355.117627) (xy 102.249289 -355.159564) (xy 111.223296 -355.159564)
			(xy 111.227367 -355.103942) (xy 111.239493 -355.049505) (xy 111.259416 -354.997414) (xy 111.286712 -354.948779)
			(xy 111.320798 -354.904636) (xy 111.360947 -354.865927) (xy 111.406305 -354.833476) (xy 111.455905 -354.807975)
			(xy 111.508689 -354.789968) (xy 111.563532 -354.779838) (xy 111.619266 -354.777801) (xy 111.674703 -354.783901)
			(xy 111.72866 -354.798007) (xy 111.779989 -354.819819) (xy 111.827595 -354.848873) (xy 111.870463 -354.884548)
			(xy 111.90768 -354.926085) (xy 111.938453 -354.972598) (xy 111.962125 -355.023095) (xy 111.972845 -355.058726)
			(xy 112.247678 -355.058726) (xy 112.251749 -355.003104) (xy 112.263875 -354.948667) (xy 112.283798 -354.896576)
			(xy 112.311094 -354.847941) (xy 112.34518 -354.803798) (xy 112.385329 -354.765089) (xy 112.430687 -354.732638)
			(xy 112.480287 -354.707137) (xy 112.533071 -354.68913) (xy 112.587914 -354.679) (xy 112.643648 -354.676963)
			(xy 112.699085 -354.683063) (xy 112.753042 -354.697169) (xy 112.804371 -354.718981) (xy 112.851977 -354.748035)
			(xy 112.894845 -354.78371) (xy 112.900703 -354.790248) (xy 113.438938 -354.790248) (xy 113.443009 -354.734626)
			(xy 113.455135 -354.680189) (xy 113.475058 -354.628098) (xy 113.502354 -354.579463) (xy 113.53644 -354.53532)
			(xy 113.576589 -354.496611) (xy 113.621947 -354.46416) (xy 113.671547 -354.438659) (xy 113.724331 -354.420652)
			(xy 113.779174 -354.410522) (xy 113.834908 -354.408485) (xy 113.890345 -354.414585) (xy 113.944302 -354.428691)
			(xy 113.995631 -354.450503) (xy 114.043237 -354.479557) (xy 114.086105 -354.515232) (xy 114.123322 -354.556769)
			(xy 114.154095 -354.603282) (xy 114.177767 -354.653779) (xy 114.188028 -354.687886) (xy 116.286026 -354.687886)
			(xy 116.286472 -354.661506) (xy 116.293727 -354.609248) (xy 116.30811 -354.558488) (xy 116.329348 -354.510192)
			(xy 116.357036 -354.465282) (xy 116.390646 -354.424613) (xy 116.429536 -354.388961) (xy 116.472967 -354.359006)
			(xy 116.496338 -354.346764) (xy 116.508712 -354.340085) (xy 116.529447 -354.321108) (xy 116.544213 -354.29719)
			(xy 116.551887 -354.270148) (xy 116.551885 -354.242039) (xy 116.544208 -354.214999) (xy 116.529439 -354.191082)
			(xy 116.508701 -354.172108) (xy 116.496338 -354.165408) (xy 116.472948 -354.153203) (xy 116.429525 -354.123234)
			(xy 116.390642 -354.087572) (xy 116.357039 -354.046897) (xy 116.329355 -354.001983) (xy 116.308118 -353.953686)
			(xy 116.293731 -353.902924) (xy 116.28647 -353.850666) (xy 116.286026 -353.824286) (xy 116.286512 -353.797035)
			(xy 116.294268 -353.743087) (xy 116.309623 -353.690792) (xy 116.332265 -353.641215) (xy 116.361731 -353.595365)
			(xy 116.397422 -353.554174) (xy 116.438613 -353.518483) (xy 116.484463 -353.489017) (xy 116.53404 -353.466375)
			(xy 116.586335 -353.45102) (xy 116.640283 -353.443264) (xy 116.694785 -353.443264) (xy 116.748733 -353.45102)
			(xy 116.801028 -353.466375) (xy 116.850605 -353.489017) (xy 116.896455 -353.518483) (xy 116.937646 -353.554174)
			(xy 116.973337 -353.595365) (xy 117.002803 -353.641215) (xy 117.025445 -353.690792) (xy 117.0408 -353.743087)
			(xy 117.048556 -353.797035) (xy 117.049042 -353.824286) (xy 117.048618 -353.850666) (xy 117.041355 -353.902923)
			(xy 117.026965 -353.953683) (xy 117.005723 -354.001977) (xy 116.978032 -354.046886) (xy 116.944421 -354.087554)
			(xy 116.90553 -354.123207) (xy 116.862101 -354.153164) (xy 116.83873 -354.165408) (xy 116.826384 -354.172131)
			(xy 116.805657 -354.191103) (xy 116.790897 -354.215013) (xy 116.783225 -354.242044) (xy 116.783223 -354.270143)
			(xy 116.790892 -354.297175) (xy 116.805649 -354.321087) (xy 116.826374 -354.340062) (xy 116.83873 -354.346764)
			(xy 116.862101 -354.359004) (xy 116.905524 -354.388967) (xy 116.944409 -354.424623) (xy 116.978014 -354.465293)
			(xy 117.005701 -354.510202) (xy 117.026941 -354.558495) (xy 117.041331 -354.609252) (xy 117.048596 -354.661507)
			(xy 117.049042 -354.687886) (xy 117.048556 -354.715137) (xy 117.0408 -354.769085) (xy 117.025445 -354.82138)
			(xy 117.002803 -354.870957) (xy 116.973337 -354.916807) (xy 116.937646 -354.957998) (xy 116.896455 -354.993689)
			(xy 116.850605 -355.023155) (xy 116.801028 -355.045797) (xy 116.748733 -355.061152) (xy 116.694785 -355.068908)
			(xy 116.640283 -355.068908) (xy 116.586335 -355.061152) (xy 116.53404 -355.045797) (xy 116.484463 -355.023155)
			(xy 116.438613 -354.993689) (xy 116.397422 -354.957998) (xy 116.361731 -354.916807) (xy 116.332265 -354.870957)
			(xy 116.309623 -354.82138) (xy 116.294268 -354.769085) (xy 116.286512 -354.715137) (xy 116.286026 -354.687886)
			(xy 114.188028 -354.687886) (xy 114.193835 -354.707186) (xy 114.201955 -354.762362) (xy 114.202464 -354.790248)
			(xy 114.201955 -354.818134) (xy 114.193835 -354.87331) (xy 114.177767 -354.926717) (xy 114.154095 -354.977214)
			(xy 114.123322 -355.023727) (xy 114.086105 -355.065264) (xy 114.043237 -355.100939) (xy 113.995631 -355.129993)
			(xy 113.944302 -355.151805) (xy 113.890345 -355.165911) (xy 113.834908 -355.172011) (xy 113.779174 -355.169974)
			(xy 113.724331 -355.159844) (xy 113.671547 -355.141837) (xy 113.621947 -355.116336) (xy 113.576589 -355.083885)
			(xy 113.53644 -355.045176) (xy 113.502354 -355.001033) (xy 113.475058 -354.952398) (xy 113.455135 -354.900307)
			(xy 113.443009 -354.84587) (xy 113.438938 -354.790248) (xy 112.900703 -354.790248) (xy 112.932062 -354.825247)
			(xy 112.962835 -354.87176) (xy 112.986507 -354.922257) (xy 113.002575 -354.975664) (xy 113.010695 -355.03084)
			(xy 113.011204 -355.058726) (xy 113.010695 -355.086612) (xy 113.002575 -355.141788) (xy 112.990426 -355.18217)
			(xy 117.96852 -355.18217) (xy 117.972591 -355.126548) (xy 117.984717 -355.072111) (xy 118.00464 -355.02002)
			(xy 118.031936 -354.971385) (xy 118.066022 -354.927242) (xy 118.106171 -354.888533) (xy 118.151529 -354.856082)
			(xy 118.201129 -354.830581) (xy 118.253913 -354.812574) (xy 118.308756 -354.802444) (xy 118.36449 -354.800407)
			(xy 118.419927 -354.806507) (xy 118.473884 -354.820613) (xy 118.525213 -354.842425) (xy 118.572819 -354.871479)
			(xy 118.615687 -354.907154) (xy 118.652904 -354.948691) (xy 118.683677 -354.995204) (xy 118.707349 -355.045701)
			(xy 118.723417 -355.099108) (xy 118.731537 -355.154284) (xy 118.732046 -355.18217) (xy 118.731537 -355.210056)
			(xy 118.723417 -355.265232) (xy 118.707349 -355.318639) (xy 118.683677 -355.369136) (xy 118.652904 -355.415649)
			(xy 118.615687 -355.457186) (xy 118.572819 -355.492861) (xy 118.525213 -355.521915) (xy 118.473884 -355.543727)
			(xy 118.419927 -355.557833) (xy 118.36449 -355.563933) (xy 118.308756 -355.561896) (xy 118.253913 -355.551766)
			(xy 118.201129 -355.533759) (xy 118.151529 -355.508258) (xy 118.106171 -355.475807) (xy 118.066022 -355.437098)
			(xy 118.031936 -355.392955) (xy 118.00464 -355.34432) (xy 117.984717 -355.292229) (xy 117.972591 -355.237792)
			(xy 117.96852 -355.18217) (xy 112.990426 -355.18217) (xy 112.986507 -355.195195) (xy 112.962835 -355.245692)
			(xy 112.932062 -355.292205) (xy 112.894845 -355.333742) (xy 112.851977 -355.369417) (xy 112.804371 -355.398471)
			(xy 112.753042 -355.420283) (xy 112.699085 -355.434389) (xy 112.643648 -355.440489) (xy 112.587914 -355.438452)
			(xy 112.533071 -355.428322) (xy 112.480287 -355.410315) (xy 112.430687 -355.384814) (xy 112.385329 -355.352363)
			(xy 112.34518 -355.313654) (xy 112.311094 -355.269511) (xy 112.283798 -355.220876) (xy 112.263875 -355.168785)
			(xy 112.251749 -355.114348) (xy 112.247678 -355.058726) (xy 111.972845 -355.058726) (xy 111.978193 -355.076502)
			(xy 111.986313 -355.131678) (xy 111.986822 -355.159564) (xy 111.986313 -355.18745) (xy 111.978193 -355.242626)
			(xy 111.962125 -355.296033) (xy 111.938453 -355.34653) (xy 111.90768 -355.393043) (xy 111.870463 -355.43458)
			(xy 111.827595 -355.470255) (xy 111.779989 -355.499309) (xy 111.72866 -355.521121) (xy 111.674703 -355.535227)
			(xy 111.619266 -355.541327) (xy 111.563532 -355.53929) (xy 111.508689 -355.52916) (xy 111.455905 -355.511153)
			(xy 111.406305 -355.485652) (xy 111.360947 -355.453201) (xy 111.320798 -355.414492) (xy 111.286712 -355.370349)
			(xy 111.259416 -355.321714) (xy 111.239493 -355.269623) (xy 111.227367 -355.215186) (xy 111.223296 -355.159564)
			(xy 102.249289 -355.159564) (xy 102.254754 -355.167305) (xy 102.282732 -355.221296) (xy 102.303097 -355.278595)
			(xy 102.31547 -355.338132) (xy 102.31962 -355.3988) (xy 102.31547 -355.459468) (xy 102.303097 -355.519005)
			(xy 102.282732 -355.576304) (xy 102.254754 -355.630295) (xy 102.219685 -355.679973) (xy 102.178178 -355.724414)
			(xy 102.131005 -355.762788) (xy 102.079047 -355.794381) (xy 102.02327 -355.818605) (xy 101.964715 -355.835007)
			(xy 101.904471 -355.843283) (xy 101.874066 -355.84384) (xy 101.454966 -355.84384) (xy 101.049328 -356.249478)
			(xy 101.049328 -356.261924) (xy 103.482392 -356.261924) (xy 103.486463 -356.206302) (xy 103.498589 -356.151865)
			(xy 103.518512 -356.099774) (xy 103.545808 -356.051139) (xy 103.579894 -356.006996) (xy 103.620043 -355.968287)
			(xy 103.665401 -355.935836) (xy 103.715001 -355.910335) (xy 103.767785 -355.892328) (xy 103.822628 -355.882198)
			(xy 103.878362 -355.880161) (xy 103.933799 -355.886261) (xy 103.987756 -355.900367) (xy 104.039085 -355.922179)
			(xy 104.086691 -355.951233) (xy 104.129559 -355.986908) (xy 104.166776 -356.028445) (xy 104.197549 -356.074958)
			(xy 104.221221 -356.125455) (xy 104.228884 -356.150926) (xy 110.986314 -356.150926) (xy 110.990385 -356.095304)
			(xy 111.002511 -356.040867) (xy 111.022434 -355.988776) (xy 111.04973 -355.940141) (xy 111.083816 -355.895998)
			(xy 111.123965 -355.857289) (xy 111.169323 -355.824838) (xy 111.218923 -355.799337) (xy 111.271707 -355.78133)
			(xy 111.32655 -355.7712) (xy 111.382284 -355.769163) (xy 111.437721 -355.775263) (xy 111.491678 -355.789369)
			(xy 111.543007 -355.811181) (xy 111.590613 -355.840235) (xy 111.633481 -355.87591) (xy 111.670698 -355.917447)
			(xy 111.687202 -355.942392) (xy 116.343682 -355.942392) (xy 116.347753 -355.88677) (xy 116.359879 -355.832333)
			(xy 116.379802 -355.780242) (xy 116.407098 -355.731607) (xy 116.441184 -355.687464) (xy 116.481333 -355.648755)
			(xy 116.526691 -355.616304) (xy 116.576291 -355.590803) (xy 116.629075 -355.572796) (xy 116.683918 -355.562666)
			(xy 116.739652 -355.560629) (xy 116.795089 -355.566729) (xy 116.849046 -355.580835) (xy 116.900375 -355.602647)
			(xy 116.947981 -355.631701) (xy 116.990849 -355.667376) (xy 117.0181 -355.69779) (xy 120.263664 -355.69779)
			(xy 120.267735 -355.642168) (xy 120.279861 -355.587731) (xy 120.299784 -355.53564) (xy 120.32708 -355.487005)
			(xy 120.361166 -355.442862) (xy 120.401315 -355.404153) (xy 120.446673 -355.371702) (xy 120.496273 -355.346201)
			(xy 120.549057 -355.328194) (xy 120.6039 -355.318064) (xy 120.659634 -355.316027) (xy 120.715071 -355.322127)
			(xy 120.769028 -355.336233) (xy 120.820357 -355.358045) (xy 120.867963 -355.387099) (xy 120.910831 -355.422774)
			(xy 120.948048 -355.464311) (xy 120.978821 -355.510824) (xy 121.002493 -355.561321) (xy 121.018561 -355.614728)
			(xy 121.026681 -355.669904) (xy 121.02719 -355.69779) (xy 121.026681 -355.725676) (xy 121.018561 -355.780852)
			(xy 121.002493 -355.834259) (xy 120.978821 -355.884756) (xy 120.948048 -355.931269) (xy 120.910831 -355.972806)
			(xy 120.867963 -356.008481) (xy 120.82476 -356.034848) (xy 122.442222 -356.034848) (xy 122.446293 -355.979226)
			(xy 122.458419 -355.924789) (xy 122.478342 -355.872698) (xy 122.505638 -355.824063) (xy 122.539724 -355.77992)
			(xy 122.579873 -355.741211) (xy 122.625231 -355.70876) (xy 122.674831 -355.683259) (xy 122.727615 -355.665252)
			(xy 122.782458 -355.655122) (xy 122.838192 -355.653085) (xy 122.893629 -355.659185) (xy 122.947586 -355.673291)
			(xy 122.998915 -355.695103) (xy 123.046521 -355.724157) (xy 123.089389 -355.759832) (xy 123.126606 -355.801369)
			(xy 123.157379 -355.847882) (xy 123.181051 -355.898379) (xy 123.197119 -355.951786) (xy 123.205239 -356.006962)
			(xy 123.205748 -356.034848) (xy 123.205239 -356.062734) (xy 123.197119 -356.11791) (xy 123.181051 -356.171317)
			(xy 123.157379 -356.221814) (xy 123.126606 -356.268327) (xy 123.089389 -356.309864) (xy 123.046521 -356.345539)
			(xy 122.998915 -356.374593) (xy 122.947586 -356.396405) (xy 122.893629 -356.410511) (xy 122.838192 -356.416611)
			(xy 122.782458 -356.414574) (xy 122.727615 -356.404444) (xy 122.674831 -356.386437) (xy 122.625231 -356.360936)
			(xy 122.579873 -356.328485) (xy 122.539724 -356.289776) (xy 122.505638 -356.245633) (xy 122.478342 -356.196998)
			(xy 122.458419 -356.144907) (xy 122.446293 -356.09047) (xy 122.442222 -356.034848) (xy 120.82476 -356.034848)
			(xy 120.820357 -356.037535) (xy 120.769028 -356.059347) (xy 120.715071 -356.073453) (xy 120.659634 -356.079553)
			(xy 120.6039 -356.077516) (xy 120.549057 -356.067386) (xy 120.496273 -356.049379) (xy 120.446673 -356.023878)
			(xy 120.401315 -355.991427) (xy 120.361166 -355.952718) (xy 120.32708 -355.908575) (xy 120.299784 -355.85994)
			(xy 120.279861 -355.807849) (xy 120.267735 -355.753412) (xy 120.263664 -355.69779) (xy 117.0181 -355.69779)
			(xy 117.028066 -355.708913) (xy 117.058839 -355.755426) (xy 117.082511 -355.805923) (xy 117.098579 -355.85933)
			(xy 117.106699 -355.914506) (xy 117.107208 -355.942392) (xy 117.106699 -355.970278) (xy 117.098579 -356.025454)
			(xy 117.082511 -356.078861) (xy 117.058839 -356.129358) (xy 117.028066 -356.175871) (xy 116.990849 -356.217408)
			(xy 116.947981 -356.253083) (xy 116.900375 -356.282137) (xy 116.849046 -356.303949) (xy 116.795089 -356.318055)
			(xy 116.739652 -356.324155) (xy 116.683918 -356.322118) (xy 116.629075 -356.311988) (xy 116.576291 -356.293981)
			(xy 116.526691 -356.26848) (xy 116.481333 -356.236029) (xy 116.441184 -356.19732) (xy 116.407098 -356.153177)
			(xy 116.379802 -356.104542) (xy 116.359879 -356.052451) (xy 116.347753 -355.998014) (xy 116.343682 -355.942392)
			(xy 111.687202 -355.942392) (xy 111.701471 -355.96396) (xy 111.725143 -356.014457) (xy 111.741211 -356.067864)
			(xy 111.749331 -356.12304) (xy 111.74984 -356.150926) (xy 111.749331 -356.178812) (xy 111.741211 -356.233988)
			(xy 111.725143 -356.287395) (xy 111.701471 -356.337892) (xy 111.670698 -356.384405) (xy 111.633481 -356.425942)
			(xy 111.590613 -356.461617) (xy 111.543007 -356.490671) (xy 111.491678 -356.512483) (xy 111.437721 -356.526589)
			(xy 111.382284 -356.532689) (xy 111.32655 -356.530652) (xy 111.271707 -356.520522) (xy 111.218923 -356.502515)
			(xy 111.169323 -356.477014) (xy 111.123965 -356.444563) (xy 111.083816 -356.405854) (xy 111.04973 -356.361711)
			(xy 111.022434 -356.313076) (xy 111.002511 -356.260985) (xy 110.990385 -356.206548) (xy 110.986314 -356.150926)
			(xy 104.228884 -356.150926) (xy 104.237289 -356.178862) (xy 104.245409 -356.234038) (xy 104.245918 -356.261924)
			(xy 104.245409 -356.28981) (xy 104.237289 -356.344986) (xy 104.221221 -356.398393) (xy 104.197549 -356.44889)
			(xy 104.166776 -356.495403) (xy 104.129559 -356.53694) (xy 104.091938 -356.568248) (xy 113.183922 -356.568248)
			(xy 113.187993 -356.512626) (xy 113.200119 -356.458189) (xy 113.220042 -356.406098) (xy 113.247338 -356.357463)
			(xy 113.281424 -356.31332) (xy 113.321573 -356.274611) (xy 113.366931 -356.24216) (xy 113.416531 -356.216659)
			(xy 113.469315 -356.198652) (xy 113.524158 -356.188522) (xy 113.579892 -356.186485) (xy 113.635329 -356.192585)
			(xy 113.689286 -356.206691) (xy 113.740615 -356.228503) (xy 113.788221 -356.257557) (xy 113.831089 -356.293232)
			(xy 113.868306 -356.334769) (xy 113.899079 -356.381282) (xy 113.922751 -356.431779) (xy 113.938819 -356.485186)
			(xy 113.946939 -356.540362) (xy 113.947448 -356.568248) (xy 113.946939 -356.596134) (xy 113.938819 -356.65131)
			(xy 113.922751 -356.704717) (xy 113.899079 -356.755214) (xy 113.868306 -356.801727) (xy 113.831089 -356.843264)
			(xy 113.825211 -356.848156) (xy 114.184174 -356.848156) (xy 114.188245 -356.792534) (xy 114.200371 -356.738097)
			(xy 114.220294 -356.686006) (xy 114.24759 -356.637371) (xy 114.281676 -356.593228) (xy 114.321825 -356.554519)
			(xy 114.367183 -356.522068) (xy 114.416783 -356.496567) (xy 114.469567 -356.47856) (xy 114.52441 -356.46843)
			(xy 114.580144 -356.466393) (xy 114.635581 -356.472493) (xy 114.689538 -356.486599) (xy 114.740867 -356.508411)
			(xy 114.788473 -356.537465) (xy 114.831341 -356.57314) (xy 114.868558 -356.614677) (xy 114.899331 -356.66119)
			(xy 114.923003 -356.711687) (xy 114.939071 -356.765094) (xy 114.947191 -356.82027) (xy 114.9477 -356.848156)
			(xy 114.947191 -356.876042) (xy 114.939071 -356.931218) (xy 114.924629 -356.97922) (xy 122.843796 -356.97922)
			(xy 122.847867 -356.923598) (xy 122.859993 -356.869161) (xy 122.879916 -356.81707) (xy 122.907212 -356.768435)
			(xy 122.941298 -356.724292) (xy 122.981447 -356.685583) (xy 123.026805 -356.653132) (xy 123.076405 -356.627631)
			(xy 123.129189 -356.609624) (xy 123.184032 -356.599494) (xy 123.239766 -356.597457) (xy 123.295203 -356.603557)
			(xy 123.34916 -356.617663) (xy 123.400489 -356.639475) (xy 123.448095 -356.668529) (xy 123.490963 -356.704204)
			(xy 123.52818 -356.745741) (xy 123.558953 -356.792254) (xy 123.582625 -356.842751) (xy 123.598693 -356.896158)
			(xy 123.606813 -356.951334) (xy 123.607322 -356.97922) (xy 123.606813 -357.007106) (xy 123.598693 -357.062282)
			(xy 123.582625 -357.115689) (xy 123.558953 -357.166186) (xy 123.52818 -357.212699) (xy 123.490963 -357.254236)
			(xy 123.448095 -357.289911) (xy 123.400489 -357.318965) (xy 123.34916 -357.340777) (xy 123.295203 -357.354883)
			(xy 123.239766 -357.360983) (xy 123.184032 -357.358946) (xy 123.129189 -357.348816) (xy 123.076405 -357.330809)
			(xy 123.026805 -357.305308) (xy 122.981447 -357.272857) (xy 122.941298 -357.234148) (xy 122.907212 -357.190005)
			(xy 122.879916 -357.14137) (xy 122.859993 -357.089279) (xy 122.847867 -357.034842) (xy 122.843796 -356.97922)
			(xy 114.924629 -356.97922) (xy 114.923003 -356.984625) (xy 114.899331 -357.035122) (xy 114.868558 -357.081635)
			(xy 114.831341 -357.123172) (xy 114.788473 -357.158847) (xy 114.740867 -357.187901) (xy 114.689538 -357.209713)
			(xy 114.635581 -357.223819) (xy 114.580144 -357.229919) (xy 114.52441 -357.227882) (xy 114.469567 -357.217752)
			(xy 114.416783 -357.199745) (xy 114.367183 -357.174244) (xy 114.321825 -357.141793) (xy 114.281676 -357.103084)
			(xy 114.24759 -357.058941) (xy 114.220294 -357.010306) (xy 114.200371 -356.958215) (xy 114.188245 -356.903778)
			(xy 114.184174 -356.848156) (xy 113.825211 -356.848156) (xy 113.788221 -356.878939) (xy 113.740615 -356.907993)
			(xy 113.689286 -356.929805) (xy 113.635329 -356.943911) (xy 113.579892 -356.950011) (xy 113.524158 -356.947974)
			(xy 113.469315 -356.937844) (xy 113.416531 -356.919837) (xy 113.366931 -356.894336) (xy 113.321573 -356.861885)
			(xy 113.281424 -356.823176) (xy 113.247338 -356.779033) (xy 113.220042 -356.730398) (xy 113.200119 -356.678307)
			(xy 113.187993 -356.62387) (xy 113.183922 -356.568248) (xy 104.091938 -356.568248) (xy 104.086691 -356.572615)
			(xy 104.039085 -356.601669) (xy 103.987756 -356.623481) (xy 103.933799 -356.637587) (xy 103.878362 -356.643687)
			(xy 103.822628 -356.64165) (xy 103.767785 -356.63152) (xy 103.715001 -356.613513) (xy 103.665401 -356.588012)
			(xy 103.620043 -356.555561) (xy 103.579894 -356.516852) (xy 103.545808 -356.472709) (xy 103.518512 -356.424074)
			(xy 103.498589 -356.371983) (xy 103.486463 -356.317546) (xy 103.482392 -356.261924) (xy 101.049328 -356.261924)
			(xy 101.049328 -356.432612) (xy 101.049847 -356.447589) (xy 101.058519 -356.47626) (xy 101.075143 -356.501178)
			(xy 101.098286 -356.520195) (xy 101.125953 -356.531674) (xy 101.155761 -356.534624) (xy 101.185142 -356.528793)
			(xy 101.211563 -356.514682) (xy 101.222556 -356.504494) (xy 101.246178 -356.481126) (xy 101.267084 -356.46085)
			(xy 101.313278 -356.425384) (xy 101.363709 -356.396256) (xy 101.417513 -356.373967) (xy 101.473769 -356.358897)
			(xy 101.531511 -356.351305) (xy 101.56063 -356.350824) (xy 101.835204 -356.350824) (xy 101.864329 -356.3513)
			(xy 101.92208 -356.358901) (xy 101.978345 -356.373973) (xy 102.032163 -356.396257) (xy 102.082613 -356.425374)
			(xy 102.128833 -356.460825) (xy 102.170032 -356.502003) (xy 102.205505 -356.548205) (xy 102.234646 -356.598641)
			(xy 102.256957 -356.652448) (xy 102.272056 -356.708706) (xy 102.279686 -356.766454) (xy 102.280212 -356.795578)
			(xy 102.279776 -356.823226) (xy 102.272896 -356.878093) (xy 102.259275 -356.931685) (xy 102.239123 -356.983179)
			(xy 102.212751 -357.031782) (xy 102.180564 -357.076745) (xy 102.162102 -357.09733) (xy 102.142798 -357.118158)
			(xy 102.169468 -357.215694) (xy 102.171356 -357.221867) (xy 102.17778 -357.233058) (xy 102.182168 -357.237792)
			(xy 102.206806 -357.263192) (xy 102.21849 -357.267256) (xy 102.251092 -357.278756) (xy 102.312547 -357.310413)
			(xy 102.368352 -357.351212) (xy 102.393242 -357.375206) (xy 103.332026 -358.313736) (xy 103.36149 -358.32288)
			(xy 103.495602 -358.26954) (xy 103.496618 -358.236266) (xy 103.49792 -358.209599) (xy 103.507054 -358.156996)
			(xy 103.523431 -358.10618) (xy 103.546732 -358.058143) (xy 103.576502 -358.013824) (xy 103.612159 -357.974087)
			(xy 103.653007 -357.939708) (xy 103.698249 -357.911359) (xy 103.747001 -357.889594) (xy 103.798311 -357.874837)
			(xy 103.851177 -357.867377) (xy 103.877872 -357.86695) (xy 103.878634 -357.86695) (xy 103.893559 -357.867133)
			(xy 103.923312 -357.869547) (xy 103.93807 -357.871776) (xy 103.94188 -357.872284) (xy 103.942134 -357.872284)
			(xy 103.95458 -357.874316) (xy 103.97871 -357.866442) (xy 104.064054 -357.777796) (xy 104.05872 -357.751634)
			(xy 104.054932 -357.732298) (xy 104.05086 -357.693104) (xy 104.050592 -357.673402) (xy 104.051055 -357.646149)
			(xy 104.058812 -357.592198) (xy 104.074168 -357.5399) (xy 104.09681 -357.49032) (xy 104.126278 -357.444467)
			(xy 104.161971 -357.403274) (xy 104.203164 -357.36758) (xy 104.249017 -357.338112) (xy 104.298597 -357.315469)
			(xy 104.350895 -357.300113) (xy 104.404846 -357.292355) (xy 104.459352 -357.292355) (xy 104.513303 -357.300112)
			(xy 104.5656 -357.315468) (xy 104.615181 -357.33811) (xy 104.661034 -357.367578) (xy 104.702227 -357.403272)
			(xy 104.737921 -357.444464) (xy 104.767389 -357.490317) (xy 104.790031 -357.539898) (xy 104.796342 -357.561388)
			(xy 112.960402 -357.561388) (xy 112.964473 -357.505766) (xy 112.976599 -357.451329) (xy 112.996522 -357.399238)
			(xy 113.023818 -357.350603) (xy 113.057904 -357.30646) (xy 113.098053 -357.267751) (xy 113.143411 -357.2353)
			(xy 113.193011 -357.209799) (xy 113.245795 -357.191792) (xy 113.300638 -357.181662) (xy 113.356372 -357.179625)
			(xy 113.411809 -357.185725) (xy 113.465766 -357.199831) (xy 113.517095 -357.221643) (xy 113.564701 -357.250697)
			(xy 113.607569 -357.286372) (xy 113.644786 -357.327909) (xy 113.675559 -357.374422) (xy 113.699231 -357.424919)
			(xy 113.715299 -357.478326) (xy 113.723419 -357.533502) (xy 113.723928 -357.561388) (xy 113.723419 -357.589274)
			(xy 113.715299 -357.64445) (xy 113.699231 -357.697857) (xy 113.675559 -357.748354) (xy 113.644786 -357.794867)
			(xy 113.607569 -357.836404) (xy 113.564701 -357.872079) (xy 113.517095 -357.901133) (xy 113.465766 -357.922945)
			(xy 113.411809 -357.937051) (xy 113.356372 -357.943151) (xy 113.300638 -357.941114) (xy 113.245795 -357.930984)
			(xy 113.193011 -357.912977) (xy 113.143411 -357.887476) (xy 113.098053 -357.855025) (xy 113.057904 -357.816316)
			(xy 113.023818 -357.772173) (xy 112.996522 -357.723538) (xy 112.976599 -357.671447) (xy 112.964473 -357.61701)
			(xy 112.960402 -357.561388) (xy 104.796342 -357.561388) (xy 104.805388 -357.592195) (xy 104.813145 -357.646146)
			(xy 104.813145 -357.700652) (xy 104.805388 -357.754603) (xy 104.790032 -357.806901) (xy 104.767389 -357.856481)
			(xy 104.737921 -357.902335) (xy 104.702228 -357.943527) (xy 104.661035 -357.979221) (xy 104.615182 -358.008689)
			(xy 104.565602 -358.031332) (xy 104.513304 -358.046688) (xy 104.459353 -358.054445) (xy 104.4321 -358.05491)
			(xy 104.431338 -358.05491) (xy 104.416413 -358.054726) (xy 104.386661 -358.05231) (xy 104.371902 -358.050084)
			(xy 104.368092 -358.049576) (xy 104.367838 -358.049576) (xy 104.355392 -358.047544) (xy 104.331262 -358.055418)
			(xy 104.258389 -358.13111) (xy 119.248426 -358.13111) (xy 119.252499 -358.075451) (xy 119.264634 -358.020978)
			(xy 119.28457 -357.968852) (xy 119.311884 -357.920184) (xy 119.345992 -357.876012) (xy 119.386169 -357.837277)
			(xy 119.431557 -357.804805) (xy 119.481189 -357.779287) (xy 119.534009 -357.761268) (xy 119.588888 -357.751131)
			(xy 119.644659 -357.749093) (xy 119.700133 -357.755196) (xy 119.754126 -357.769312) (xy 119.805489 -357.791139)
			(xy 119.853127 -357.820212) (xy 119.896023 -357.855911) (xy 119.933265 -357.897475) (xy 119.964059 -357.944019)
			(xy 119.987747 -357.99455) (xy 120.003825 -358.047992) (xy 120.011951 -358.103206) (xy 120.012414 -358.12857)
			(xy 122.04522 -358.12857) (xy 122.049291 -358.072948) (xy 122.061417 -358.018511) (xy 122.08134 -357.96642)
			(xy 122.108636 -357.917785) (xy 122.142722 -357.873642) (xy 122.182871 -357.834933) (xy 122.228229 -357.802482)
			(xy 122.277829 -357.776981) (xy 122.330613 -357.758974) (xy 122.385456 -357.748844) (xy 122.44119 -357.746807)
			(xy 122.496627 -357.752907) (xy 122.550584 -357.767013) (xy 122.601913 -357.788825) (xy 122.649519 -357.817879)
			(xy 122.692387 -357.853554) (xy 122.729604 -357.895091) (xy 122.760377 -357.941604) (xy 122.784049 -357.992101)
			(xy 122.800117 -358.045508) (xy 122.808237 -358.100684) (xy 122.808746 -358.12857) (xy 122.808237 -358.156456)
			(xy 122.800117 -358.211632) (xy 122.784049 -358.265039) (xy 122.760377 -358.315536) (xy 122.729604 -358.362049)
			(xy 122.692387 -358.403586) (xy 122.649519 -358.439261) (xy 122.601913 -358.468315) (xy 122.550584 -358.490127)
			(xy 122.496627 -358.504233) (xy 122.44119 -358.510333) (xy 122.385456 -358.508296) (xy 122.330613 -358.498166)
			(xy 122.277829 -358.480159) (xy 122.228229 -358.454658) (xy 122.182871 -358.422207) (xy 122.142722 -358.383498)
			(xy 122.108636 -358.339355) (xy 122.08134 -358.29072) (xy 122.061417 -358.238629) (xy 122.049291 -358.184192)
			(xy 122.04522 -358.12857) (xy 120.012414 -358.12857) (xy 120.01246 -358.13111) (xy 120.011951 -358.159014)
			(xy 120.003825 -358.214228) (xy 119.987747 -358.26767) (xy 119.964059 -358.318201) (xy 119.933265 -358.364745)
			(xy 119.896023 -358.406309) (xy 119.853127 -358.442008) (xy 119.805489 -358.471081) (xy 119.754126 -358.492908)
			(xy 119.700133 -358.507024) (xy 119.644659 -358.513127) (xy 119.588888 -358.511089) (xy 119.534009 -358.500952)
			(xy 119.481189 -358.482933) (xy 119.431557 -358.457415) (xy 119.386169 -358.424943) (xy 119.345992 -358.386208)
			(xy 119.311884 -358.342036) (xy 119.28457 -358.293368) (xy 119.264634 -358.241242) (xy 119.252499 -358.186769)
			(xy 119.248426 -358.13111) (xy 104.258389 -358.13111) (xy 104.245918 -358.144064) (xy 104.251252 -358.170226)
			(xy 104.255043 -358.189562) (xy 104.259119 -358.228756) (xy 104.25938 -358.248458) (xy 104.25892 -358.275712)
			(xy 104.251167 -358.329666) (xy 104.235815 -358.381967) (xy 104.213174 -358.431551) (xy 104.183707 -358.477407)
			(xy 104.148013 -358.518603) (xy 104.106819 -358.554298) (xy 104.072075 -358.576626) (xy 112.706402 -358.576626)
			(xy 112.710473 -358.521004) (xy 112.722599 -358.466567) (xy 112.742522 -358.414476) (xy 112.769818 -358.365841)
			(xy 112.803904 -358.321698) (xy 112.844053 -358.282989) (xy 112.889411 -358.250538) (xy 112.939011 -358.225037)
			(xy 112.991795 -358.20703) (xy 113.046638 -358.1969) (xy 113.102372 -358.194863) (xy 113.157809 -358.200963)
			(xy 113.211766 -358.215069) (xy 113.263095 -358.236881) (xy 113.310701 -358.265935) (xy 113.353569 -358.30161)
			(xy 113.390786 -358.343147) (xy 113.421559 -358.38966) (xy 113.445231 -358.440157) (xy 113.461299 -358.493564)
			(xy 113.469419 -358.54874) (xy 113.469928 -358.576626) (xy 113.469419 -358.604512) (xy 113.461299 -358.659688)
			(xy 113.445231 -358.713095) (xy 113.421559 -358.763592) (xy 113.390786 -358.810105) (xy 113.353569 -358.851642)
			(xy 113.310701 -358.887317) (xy 113.263095 -358.916371) (xy 113.211766 -358.938183) (xy 113.157809 -358.952289)
			(xy 113.102372 -358.958389) (xy 113.046638 -358.956352) (xy 112.991795 -358.946222) (xy 112.939011 -358.928215)
			(xy 112.889411 -358.902714) (xy 112.844053 -358.870263) (xy 112.803904 -358.831554) (xy 112.769818 -358.787411)
			(xy 112.742522 -358.738776) (xy 112.722599 -358.686685) (xy 112.710473 -358.632248) (xy 112.706402 -358.576626)
			(xy 104.072075 -358.576626) (xy 104.060963 -358.583767) (xy 104.01138 -358.60641) (xy 103.95908 -358.621764)
			(xy 103.905126 -358.629519) (xy 103.877872 -358.629966) (xy 103.853751 -358.629578) (xy 103.805896 -358.623465)
			(xy 103.759191 -358.611378) (xy 103.736648 -358.602788) (xy 103.70947 -358.59212) (xy 103.593646 -358.68229)
			(xy 103.597545 -358.703475) (xy 103.601745 -358.746349) (xy 103.602028 -358.767888) (xy 103.602028 -359.188004)
			(xy 104.05313 -359.188004) (xy 104.057201 -359.132382) (xy 104.069327 -359.077945) (xy 104.08925 -359.025854)
			(xy 104.116546 -358.977219) (xy 104.150632 -358.933076) (xy 104.190781 -358.894367) (xy 104.236139 -358.861916)
			(xy 104.285739 -358.836415) (xy 104.338523 -358.818408) (xy 104.393366 -358.808278) (xy 104.4491 -358.806241)
			(xy 104.504537 -358.812341) (xy 104.558494 -358.826447) (xy 104.609823 -358.848259) (xy 104.657429 -358.877313)
			(xy 104.700297 -358.912988) (xy 104.737514 -358.954525) (xy 104.744103 -358.964484) (xy 122.787916 -358.964484)
			(xy 122.791987 -358.908862) (xy 122.804113 -358.854425) (xy 122.824036 -358.802334) (xy 122.851332 -358.753699)
			(xy 122.885418 -358.709556) (xy 122.925567 -358.670847) (xy 122.970925 -358.638396) (xy 123.020525 -358.612895)
			(xy 123.073309 -358.594888) (xy 123.128152 -358.584758) (xy 123.183886 -358.582721) (xy 123.239323 -358.588821)
			(xy 123.29328 -358.602927) (xy 123.344609 -358.624739) (xy 123.392215 -358.653793) (xy 123.435083 -358.689468)
			(xy 123.4723 -358.731005) (xy 123.503073 -358.777518) (xy 123.526745 -358.828015) (xy 123.542813 -358.881422)
			(xy 123.550933 -358.936598) (xy 123.551442 -358.964484) (xy 123.550933 -358.99237) (xy 123.542813 -359.047546)
			(xy 123.526745 -359.100953) (xy 123.503073 -359.15145) (xy 123.4723 -359.197963) (xy 123.435083 -359.2395)
			(xy 123.392215 -359.275175) (xy 123.344609 -359.304229) (xy 123.29328 -359.326041) (xy 123.239323 -359.340147)
			(xy 123.183886 -359.346247) (xy 123.128152 -359.34421) (xy 123.073309 -359.33408) (xy 123.020525 -359.316073)
			(xy 122.970925 -359.290572) (xy 122.925567 -359.258121) (xy 122.885418 -359.219412) (xy 122.851332 -359.175269)
			(xy 122.824036 -359.126634) (xy 122.804113 -359.074543) (xy 122.791987 -359.020106) (xy 122.787916 -358.964484)
			(xy 104.744103 -358.964484) (xy 104.768287 -359.001038) (xy 104.791959 -359.051535) (xy 104.808027 -359.104942)
			(xy 104.816147 -359.160118) (xy 104.816656 -359.188004) (xy 104.816147 -359.21589) (xy 104.808027 -359.271066)
			(xy 104.791959 -359.324473) (xy 104.768287 -359.37497) (xy 104.737514 -359.421483) (xy 104.700297 -359.46302)
			(xy 104.657429 -359.498695) (xy 104.609823 -359.527749) (xy 104.558494 -359.549561) (xy 104.504537 -359.563667)
			(xy 104.4491 -359.569767) (xy 104.393366 -359.56773) (xy 104.338523 -359.5576) (xy 104.285739 -359.539593)
			(xy 104.236139 -359.514092) (xy 104.190781 -359.481641) (xy 104.150632 -359.442932) (xy 104.116546 -359.398789)
			(xy 104.08925 -359.350154) (xy 104.069327 -359.298063) (xy 104.057201 -359.243626) (xy 104.05313 -359.188004)
			(xy 103.602028 -359.188004) (xy 103.602028 -359.595674) (xy 112.734088 -359.595674) (xy 112.738159 -359.540052)
			(xy 112.750285 -359.485615) (xy 112.770208 -359.433524) (xy 112.797504 -359.384889) (xy 112.83159 -359.340746)
			(xy 112.871739 -359.302037) (xy 112.917097 -359.269586) (xy 112.966697 -359.244085) (xy 113.019481 -359.226078)
			(xy 113.074324 -359.215948) (xy 113.130058 -359.213911) (xy 113.185495 -359.220011) (xy 113.239452 -359.234117)
			(xy 113.290781 -359.255929) (xy 113.338387 -359.284983) (xy 113.381255 -359.320658) (xy 113.418472 -359.362195)
			(xy 113.432119 -359.382822) (xy 116.061996 -359.382822) (xy 116.066067 -359.3272) (xy 116.078193 -359.272763)
			(xy 116.098116 -359.220672) (xy 116.125412 -359.172037) (xy 116.159498 -359.127894) (xy 116.199647 -359.089185)
			(xy 116.245005 -359.056734) (xy 116.294605 -359.031233) (xy 116.347389 -359.013226) (xy 116.402232 -359.003096)
			(xy 116.457966 -359.001059) (xy 116.513403 -359.007159) (xy 116.56736 -359.021265) (xy 116.618689 -359.043077)
			(xy 116.666295 -359.072131) (xy 116.709163 -359.107806) (xy 116.74638 -359.149343) (xy 116.777153 -359.195856)
			(xy 116.800825 -359.246353) (xy 116.816893 -359.29976) (xy 116.825013 -359.354936) (xy 116.825522 -359.382822)
			(xy 116.825013 -359.410708) (xy 116.816893 -359.465884) (xy 116.800825 -359.519291) (xy 116.777153 -359.569788)
			(xy 116.74638 -359.616301) (xy 116.709163 -359.657838) (xy 116.666295 -359.693513) (xy 116.618689 -359.722567)
			(xy 116.56736 -359.744379) (xy 116.513403 -359.758485) (xy 116.457966 -359.764585) (xy 116.402232 -359.762548)
			(xy 116.347389 -359.752418) (xy 116.294605 -359.734411) (xy 116.245005 -359.70891) (xy 116.199647 -359.676459)
			(xy 116.159498 -359.63775) (xy 116.125412 -359.593607) (xy 116.098116 -359.544972) (xy 116.078193 -359.492881)
			(xy 116.066067 -359.438444) (xy 116.061996 -359.382822) (xy 113.432119 -359.382822) (xy 113.449245 -359.408708)
			(xy 113.472917 -359.459205) (xy 113.488985 -359.512612) (xy 113.497105 -359.567788) (xy 113.497614 -359.595674)
			(xy 113.497105 -359.62356) (xy 113.488985 -359.678736) (xy 113.472917 -359.732143) (xy 113.449245 -359.78264)
			(xy 113.418472 -359.829153) (xy 113.381255 -359.87069) (xy 113.338387 -359.906365) (xy 113.290781 -359.935419)
			(xy 113.239452 -359.957231) (xy 113.185495 -359.971337) (xy 113.130058 -359.977437) (xy 113.074324 -359.9754)
			(xy 113.019481 -359.96527) (xy 112.966697 -359.947263) (xy 112.917097 -359.921762) (xy 112.871739 -359.889311)
			(xy 112.83159 -359.850602) (xy 112.797504 -359.806459) (xy 112.770208 -359.757824) (xy 112.750285 -359.705733)
			(xy 112.738159 -359.651296) (xy 112.734088 -359.595674) (xy 103.602028 -359.595674) (xy 103.602028 -359.999788)
			(xy 103.601559 -360.028917) (xy 103.593922 -360.086672) (xy 103.578805 -360.142935) (xy 103.556466 -360.19674)
			(xy 103.544767 -360.216958) (xy 103.98963 -360.216958) (xy 103.993701 -360.161336) (xy 104.005827 -360.106899)
			(xy 104.02575 -360.054808) (xy 104.053046 -360.006173) (xy 104.087132 -359.96203) (xy 104.127281 -359.923321)
			(xy 104.172639 -359.89087) (xy 104.222239 -359.865369) (xy 104.275023 -359.847362) (xy 104.329866 -359.837232)
			(xy 104.3856 -359.835195) (xy 104.441037 -359.841295) (xy 104.494994 -359.855401) (xy 104.546323 -359.877213)
			(xy 104.593929 -359.906267) (xy 104.636797 -359.941942) (xy 104.674014 -359.983479) (xy 104.704787 -360.029992)
			(xy 104.728459 -360.080489) (xy 104.744527 -360.133896) (xy 104.752647 -360.189072) (xy 104.753156 -360.216958)
			(xy 104.752647 -360.244844) (xy 104.744527 -360.30002) (xy 104.728459 -360.353427) (xy 104.704787 -360.403924)
			(xy 104.674014 -360.450437) (xy 104.636797 -360.491974) (xy 104.593929 -360.527649) (xy 104.546323 -360.556703)
			(xy 104.494994 -360.578515) (xy 104.441037 -360.592621) (xy 104.3856 -360.598721) (xy 104.329866 -360.596684)
			(xy 104.275023 -360.586554) (xy 104.222239 -360.568547) (xy 104.172639 -360.543046) (xy 104.127281 -360.510595)
			(xy 104.087132 -360.471886) (xy 104.053046 -360.427743) (xy 104.02575 -360.379108) (xy 104.005827 -360.327017)
			(xy 103.993701 -360.27258) (xy 103.98963 -360.216958) (xy 103.544767 -360.216958) (xy 103.527289 -360.247165)
			(xy 103.491774 -360.293346) (xy 103.471472 -360.31424) (xy 103.24846 -360.537252) (xy 103.24846 -360.61142)
			(xy 112.831624 -360.61142) (xy 112.835695 -360.555798) (xy 112.847821 -360.501361) (xy 112.867744 -360.44927)
			(xy 112.89504 -360.400635) (xy 112.929126 -360.356492) (xy 112.969275 -360.317783) (xy 113.014633 -360.285332)
			(xy 113.064233 -360.259831) (xy 113.117017 -360.241824) (xy 113.17186 -360.231694) (xy 113.227594 -360.229657)
			(xy 113.283031 -360.235757) (xy 113.336988 -360.249863) (xy 113.388317 -360.271675) (xy 113.391471 -360.2736)
			(xy 118.713248 -360.2736) (xy 118.717321 -360.217941) (xy 118.729456 -360.163468) (xy 118.749392 -360.111342)
			(xy 118.776706 -360.062674) (xy 118.810814 -360.018502) (xy 118.850991 -359.979767) (xy 118.896379 -359.947295)
			(xy 118.946011 -359.921777) (xy 118.998831 -359.903758) (xy 119.05371 -359.893621) (xy 119.109481 -359.891583)
			(xy 119.164955 -359.897686) (xy 119.218948 -359.911802) (xy 119.270311 -359.933629) (xy 119.317949 -359.962702)
			(xy 119.360845 -359.998401) (xy 119.398087 -360.039965) (xy 119.428881 -360.086509) (xy 119.452569 -360.13704)
			(xy 119.468647 -360.190482) (xy 119.476773 -360.245696) (xy 119.477282 -360.2736) (xy 119.476773 -360.301504)
			(xy 119.468647 -360.356718) (xy 119.452569 -360.41016) (xy 119.428881 -360.460691) (xy 119.398087 -360.507235)
			(xy 119.360845 -360.548799) (xy 119.317949 -360.584498) (xy 119.270311 -360.613571) (xy 119.218948 -360.635398)
			(xy 119.164955 -360.649514) (xy 119.109481 -360.655617) (xy 119.05371 -360.653579) (xy 118.998831 -360.643442)
			(xy 118.946011 -360.625423) (xy 118.896379 -360.599905) (xy 118.850991 -360.567433) (xy 118.810814 -360.528698)
			(xy 118.776706 -360.484526) (xy 118.749392 -360.435858) (xy 118.729456 -360.383732) (xy 118.717321 -360.329259)
			(xy 118.713248 -360.2736) (xy 113.391471 -360.2736) (xy 113.435923 -360.300729) (xy 113.478791 -360.336404)
			(xy 113.516008 -360.377941) (xy 113.546781 -360.424454) (xy 113.570453 -360.474951) (xy 113.586521 -360.528358)
			(xy 113.594641 -360.583534) (xy 113.59515 -360.61142) (xy 113.594641 -360.639306) (xy 113.588577 -360.680508)
			(xy 128.966466 -360.680508) (xy 128.970537 -360.624886) (xy 128.982663 -360.570449) (xy 129.002586 -360.518358)
			(xy 129.029882 -360.469723) (xy 129.063968 -360.42558) (xy 129.104117 -360.386871) (xy 129.149475 -360.35442)
			(xy 129.199075 -360.328919) (xy 129.251859 -360.310912) (xy 129.306702 -360.300782) (xy 129.362436 -360.298745)
			(xy 129.417873 -360.304845) (xy 129.47183 -360.318951) (xy 129.523159 -360.340763) (xy 129.570765 -360.369817)
			(xy 129.613633 -360.405492) (xy 129.65085 -360.447029) (xy 129.681623 -360.493542) (xy 129.705295 -360.544039)
			(xy 129.721363 -360.597446) (xy 129.729483 -360.652622) (xy 129.729992 -360.680508) (xy 129.729483 -360.708394)
			(xy 129.721363 -360.76357) (xy 129.705295 -360.816977) (xy 129.681623 -360.867474) (xy 129.65085 -360.913987)
			(xy 129.613633 -360.955524) (xy 129.570765 -360.991199) (xy 129.523159 -361.020253) (xy 129.47183 -361.042065)
			(xy 129.417873 -361.056171) (xy 129.362436 -361.062271) (xy 129.306702 -361.060234) (xy 129.251859 -361.050104)
			(xy 129.199075 -361.032097) (xy 129.149475 -361.006596) (xy 129.104117 -360.974145) (xy 129.063968 -360.935436)
			(xy 129.029882 -360.891293) (xy 129.002586 -360.842658) (xy 128.982663 -360.790567) (xy 128.970537 -360.73613)
			(xy 128.966466 -360.680508) (xy 113.588577 -360.680508) (xy 113.586521 -360.694482) (xy 113.570453 -360.747889)
			(xy 113.546781 -360.798386) (xy 113.516008 -360.844899) (xy 113.478791 -360.886436) (xy 113.435923 -360.922111)
			(xy 113.388317 -360.951165) (xy 113.336988 -360.972977) (xy 113.283031 -360.987083) (xy 113.227594 -360.993183)
			(xy 113.17186 -360.991146) (xy 113.117017 -360.981016) (xy 113.064233 -360.963009) (xy 113.014633 -360.937508)
			(xy 112.969275 -360.905057) (xy 112.929126 -360.866348) (xy 112.89504 -360.822205) (xy 112.867744 -360.77357)
			(xy 112.847821 -360.721479) (xy 112.835695 -360.667042) (xy 112.831624 -360.61142) (xy 103.24846 -360.61142)
			(xy 103.24846 -361.133136) (xy 121.446286 -361.133136) (xy 121.450375 -361.077254) (xy 121.462558 -361.022564)
			(xy 121.482574 -360.97023) (xy 121.509997 -360.921368) (xy 121.544242 -360.87702) (xy 121.584578 -360.83813)
			(xy 121.630148 -360.805528) (xy 121.679979 -360.779909) (xy 121.733009 -360.761817) (xy 121.788107 -360.75164)
			(xy 121.844101 -360.749594) (xy 121.899796 -360.755722) (xy 121.954005 -360.769894) (xy 122.005573 -360.791808)
			(xy 122.053401 -360.820997) (xy 122.096469 -360.856838) (xy 122.133859 -360.898568) (xy 122.164775 -360.945298)
			(xy 122.188558 -360.996031) (xy 122.2047 -361.049687) (xy 122.212859 -361.105121) (xy 122.21337 -361.133136)
			(xy 122.212859 -361.161151) (xy 122.2047 -361.216585) (xy 122.188558 -361.270241) (xy 122.164775 -361.320974)
			(xy 122.133859 -361.367704) (xy 122.096469 -361.409434) (xy 122.053401 -361.445275) (xy 122.005573 -361.474464)
			(xy 121.954005 -361.496378) (xy 121.899796 -361.51055) (xy 121.844101 -361.516678) (xy 121.788107 -361.514632)
			(xy 121.733009 -361.504455) (xy 121.679979 -361.486363) (xy 121.630148 -361.460744) (xy 121.584578 -361.428142)
			(xy 121.544242 -361.389252) (xy 121.509997 -361.344904) (xy 121.482574 -361.296042) (xy 121.462558 -361.243708)
			(xy 121.450375 -361.189018) (xy 121.446286 -361.133136) (xy 103.24846 -361.133136) (xy 103.24846 -361.544616)
			(xy 112.355882 -361.544616) (xy 112.359953 -361.488994) (xy 112.372079 -361.434557) (xy 112.392002 -361.382466)
			(xy 112.419298 -361.333831) (xy 112.453384 -361.289688) (xy 112.493533 -361.250979) (xy 112.538891 -361.218528)
			(xy 112.588491 -361.193027) (xy 112.641275 -361.17502) (xy 112.696118 -361.16489) (xy 112.751852 -361.162853)
			(xy 112.807289 -361.168953) (xy 112.861246 -361.183059) (xy 112.912575 -361.204871) (xy 112.960181 -361.233925)
			(xy 113.003049 -361.2696) (xy 113.040266 -361.311137) (xy 113.071039 -361.35765) (xy 113.094711 -361.408147)
			(xy 113.110779 -361.461554) (xy 113.118899 -361.51673) (xy 113.119408 -361.544616) (xy 113.118899 -361.572502)
			(xy 113.110779 -361.627678) (xy 113.094711 -361.681085) (xy 113.071039 -361.731582) (xy 113.040266 -361.778095)
			(xy 113.003049 -361.819632) (xy 112.960181 -361.855307) (xy 112.912575 -361.884361) (xy 112.861246 -361.906173)
			(xy 112.807289 -361.920279) (xy 112.751852 -361.926379) (xy 112.696118 -361.924342) (xy 112.641275 -361.914212)
			(xy 112.588491 -361.896205) (xy 112.538891 -361.870704) (xy 112.493533 -361.838253) (xy 112.453384 -361.799544)
			(xy 112.419298 -361.755401) (xy 112.392002 -361.706766) (xy 112.372079 -361.654675) (xy 112.359953 -361.600238)
			(xy 112.355882 -361.544616) (xy 103.24846 -361.544616) (xy 103.24846 -361.948222) (xy 103.776778 -361.948222)
			(xy 103.780849 -361.8926) (xy 103.792975 -361.838163) (xy 103.812898 -361.786072) (xy 103.840194 -361.737437)
			(xy 103.87428 -361.693294) (xy 103.914429 -361.654585) (xy 103.959787 -361.622134) (xy 104.009387 -361.596633)
			(xy 104.062171 -361.578626) (xy 104.117014 -361.568496) (xy 104.172748 -361.566459) (xy 104.228185 -361.572559)
			(xy 104.282142 -361.586665) (xy 104.333471 -361.608477) (xy 104.381077 -361.637531) (xy 104.423945 -361.673206)
			(xy 104.461162 -361.714743) (xy 104.491935 -361.761256) (xy 104.515607 -361.811753) (xy 104.531675 -361.86516)
			(xy 104.539795 -361.920336) (xy 104.540304 -361.948222) (xy 104.539795 -361.976108) (xy 104.531675 -362.031284)
			(xy 104.515607 -362.084691) (xy 104.491935 -362.135188) (xy 104.461162 -362.181701) (xy 104.423945 -362.223238)
			(xy 104.381077 -362.258913) (xy 104.333471 -362.287967) (xy 104.282142 -362.309779) (xy 104.229145 -362.323634)
			(xy 105.517186 -362.323634) (xy 105.521257 -362.268012) (xy 105.533383 -362.213575) (xy 105.553306 -362.161484)
			(xy 105.580602 -362.112849) (xy 105.614688 -362.068706) (xy 105.654837 -362.029997) (xy 105.700195 -361.997546)
			(xy 105.749795 -361.972045) (xy 105.802579 -361.954038) (xy 105.857422 -361.943908) (xy 105.913156 -361.941871)
			(xy 105.968593 -361.947971) (xy 106.02255 -361.962077) (xy 106.073879 -361.983889) (xy 106.121485 -362.012943)
			(xy 106.164353 -362.048618) (xy 106.20157 -362.090155) (xy 106.232343 -362.136668) (xy 106.256015 -362.187165)
			(xy 106.272083 -362.240572) (xy 106.280203 -362.295748) (xy 106.280712 -362.323634) (xy 106.280203 -362.35152)
			(xy 106.272083 -362.406696) (xy 106.265054 -362.43006) (xy 111.033812 -362.43006) (xy 111.037883 -362.374438)
			(xy 111.050009 -362.320001) (xy 111.069932 -362.26791) (xy 111.097228 -362.219275) (xy 111.131314 -362.175132)
			(xy 111.171463 -362.136423) (xy 111.216821 -362.103972) (xy 111.266421 -362.078471) (xy 111.319205 -362.060464)
			(xy 111.374048 -362.050334) (xy 111.429782 -362.048297) (xy 111.485219 -362.054397) (xy 111.539176 -362.068503)
			(xy 111.590505 -362.090315) (xy 111.601567 -362.097066) (xy 128.08534 -362.097066) (xy 128.089411 -362.041444)
			(xy 128.101537 -361.987007) (xy 128.12146 -361.934916) (xy 128.148756 -361.886281) (xy 128.182842 -361.842138)
			(xy 128.222991 -361.803429) (xy 128.268349 -361.770978) (xy 128.317949 -361.745477) (xy 128.370733 -361.72747)
			(xy 128.425576 -361.71734) (xy 128.48131 -361.715303) (xy 128.536747 -361.721403) (xy 128.590704 -361.735509)
			(xy 128.642033 -361.757321) (xy 128.689639 -361.786375) (xy 128.731207 -361.820968) (xy 144.809462 -361.820968)
			(xy 144.813533 -361.765346) (xy 144.825659 -361.710909) (xy 144.845582 -361.658818) (xy 144.872878 -361.610183)
			(xy 144.906964 -361.56604) (xy 144.947113 -361.527331) (xy 144.992471 -361.49488) (xy 145.042071 -361.469379)
			(xy 145.094855 -361.451372) (xy 145.149698 -361.441242) (xy 145.205432 -361.439205) (xy 145.260869 -361.445305)
			(xy 145.314826 -361.459411) (xy 145.366155 -361.481223) (xy 145.413761 -361.510277) (xy 145.456629 -361.545952)
			(xy 145.493846 -361.587489) (xy 145.524619 -361.634002) (xy 145.548291 -361.684499) (xy 145.564359 -361.737906)
			(xy 145.572479 -361.793082) (xy 145.572988 -361.820968) (xy 145.572479 -361.848854) (xy 145.564359 -361.90403)
			(xy 145.548291 -361.957437) (xy 145.524619 -362.007934) (xy 145.493846 -362.054447) (xy 145.456629 -362.095984)
			(xy 145.413761 -362.131659) (xy 145.366155 -362.160713) (xy 145.314826 -362.182525) (xy 145.260869 -362.196631)
			(xy 145.205432 -362.202731) (xy 145.149698 -362.200694) (xy 145.094855 -362.190564) (xy 145.042071 -362.172557)
			(xy 144.992471 -362.147056) (xy 144.947113 -362.114605) (xy 144.906964 -362.075896) (xy 144.872878 -362.031753)
			(xy 144.845582 -361.983118) (xy 144.825659 -361.931027) (xy 144.813533 -361.87659) (xy 144.809462 -361.820968)
			(xy 128.731207 -361.820968) (xy 128.732507 -361.82205) (xy 128.769724 -361.863587) (xy 128.800497 -361.9101)
			(xy 128.824169 -361.960597) (xy 128.840237 -362.014004) (xy 128.848357 -362.06918) (xy 128.848866 -362.097066)
			(xy 128.848357 -362.124952) (xy 128.840237 -362.180128) (xy 128.824169 -362.233535) (xy 128.800497 -362.284032)
			(xy 128.769724 -362.330545) (xy 128.732507 -362.372082) (xy 128.689639 -362.407757) (xy 128.642033 -362.436811)
			(xy 128.590704 -362.458623) (xy 128.536747 -362.472729) (xy 128.48131 -362.478829) (xy 128.425576 -362.476792)
			(xy 128.370733 -362.466662) (xy 128.317949 -362.448655) (xy 128.268349 -362.423154) (xy 128.222991 -362.390703)
			(xy 128.182842 -362.351994) (xy 128.148756 -362.307851) (xy 128.12146 -362.259216) (xy 128.101537 -362.207125)
			(xy 128.089411 -362.152688) (xy 128.08534 -362.097066) (xy 111.601567 -362.097066) (xy 111.638111 -362.119369)
			(xy 111.680979 -362.155044) (xy 111.718196 -362.196581) (xy 111.748969 -362.243094) (xy 111.772641 -362.293591)
			(xy 111.788709 -362.346998) (xy 111.796829 -362.402174) (xy 111.797338 -362.43006) (xy 111.796829 -362.457946)
			(xy 111.788709 -362.513122) (xy 111.772641 -362.566529) (xy 111.748969 -362.617026) (xy 111.718196 -362.663539)
			(xy 111.680979 -362.705076) (xy 111.638111 -362.740751) (xy 111.590505 -362.769805) (xy 111.539176 -362.791617)
			(xy 111.485219 -362.805723) (xy 111.429782 -362.811823) (xy 111.374048 -362.809786) (xy 111.319205 -362.799656)
			(xy 111.266421 -362.781649) (xy 111.216821 -362.756148) (xy 111.171463 -362.723697) (xy 111.131314 -362.684988)
			(xy 111.097228 -362.640845) (xy 111.069932 -362.59221) (xy 111.050009 -362.540119) (xy 111.037883 -362.485682)
			(xy 111.033812 -362.43006) (xy 106.265054 -362.43006) (xy 106.256015 -362.460103) (xy 106.232343 -362.5106)
			(xy 106.20157 -362.557113) (xy 106.164353 -362.59865) (xy 106.121485 -362.634325) (xy 106.073879 -362.663379)
			(xy 106.02255 -362.685191) (xy 105.968593 -362.699297) (xy 105.913156 -362.705397) (xy 105.857422 -362.70336)
			(xy 105.802579 -362.69323) (xy 105.749795 -362.675223) (xy 105.700195 -362.649722) (xy 105.654837 -362.617271)
			(xy 105.614688 -362.578562) (xy 105.580602 -362.534419) (xy 105.553306 -362.485784) (xy 105.533383 -362.433693)
			(xy 105.521257 -362.379256) (xy 105.517186 -362.323634) (xy 104.229145 -362.323634) (xy 104.228185 -362.323885)
			(xy 104.172748 -362.329985) (xy 104.117014 -362.327948) (xy 104.062171 -362.317818) (xy 104.009387 -362.299811)
			(xy 103.959787 -362.27431) (xy 103.914429 -362.241859) (xy 103.87428 -362.20315) (xy 103.840194 -362.159007)
			(xy 103.812898 -362.110372) (xy 103.792975 -362.058281) (xy 103.780849 -362.003844) (xy 103.776778 -361.948222)
			(xy 103.24846 -361.948222) (xy 103.24846 -362.46308) (xy 103.933752 -363.148372) (xy 106.262676 -363.148372)
			(xy 106.266747 -363.09275) (xy 106.278873 -363.038313) (xy 106.298796 -362.986222) (xy 106.326092 -362.937587)
			(xy 106.360178 -362.893444) (xy 106.400327 -362.854735) (xy 106.445685 -362.822284) (xy 106.495285 -362.796783)
			(xy 106.548069 -362.778776) (xy 106.602912 -362.768646) (xy 106.658646 -362.766609) (xy 106.714083 -362.772709)
			(xy 106.76804 -362.786815) (xy 106.819369 -362.808627) (xy 106.866975 -362.837681) (xy 106.909843 -362.873356)
			(xy 106.94706 -362.914893) (xy 106.977833 -362.961406) (xy 107.001505 -363.011903) (xy 107.017573 -363.06531)
			(xy 107.025693 -363.120486) (xy 107.026202 -363.148372) (xy 107.025693 -363.176258) (xy 107.017573 -363.231434)
			(xy 107.001505 -363.284841) (xy 106.977833 -363.335338) (xy 106.951128 -363.375702) (xy 109.736888 -363.375702)
			(xy 109.740959 -363.32008) (xy 109.753085 -363.265643) (xy 109.773008 -363.213552) (xy 109.800304 -363.164917)
			(xy 109.83439 -363.120774) (xy 109.874539 -363.082065) (xy 109.919897 -363.049614) (xy 109.969497 -363.024113)
			(xy 110.022281 -363.006106) (xy 110.077124 -362.995976) (xy 110.132858 -362.993939) (xy 110.188295 -363.000039)
			(xy 110.242252 -363.014145) (xy 110.293581 -363.035957) (xy 110.341187 -363.065011) (xy 110.384055 -363.100686)
			(xy 110.421272 -363.142223) (xy 110.452045 -363.188736) (xy 110.475717 -363.239233) (xy 110.491785 -363.29264)
			(xy 110.496608 -363.32541) (xy 112.722658 -363.32541) (xy 112.726729 -363.269788) (xy 112.738855 -363.215351)
			(xy 112.758778 -363.16326) (xy 112.786074 -363.114625) (xy 112.82016 -363.070482) (xy 112.860309 -363.031773)
			(xy 112.905667 -362.999322) (xy 112.955267 -362.973821) (xy 113.008051 -362.955814) (xy 113.062894 -362.945684)
			(xy 113.118628 -362.943647) (xy 113.174065 -362.949747) (xy 113.228022 -362.963853) (xy 113.279351 -362.985665)
			(xy 113.326957 -363.014719) (xy 113.369825 -363.050394) (xy 113.407042 -363.091931) (xy 113.437815 -363.138444)
			(xy 113.461487 -363.188941) (xy 113.477555 -363.242348) (xy 113.485675 -363.297524) (xy 113.486184 -363.32541)
			(xy 113.485675 -363.353296) (xy 113.477555 -363.408472) (xy 113.461487 -363.461879) (xy 113.437815 -363.512376)
			(xy 113.431444 -363.522006) (xy 115.599208 -363.522006) (xy 115.603279 -363.466384) (xy 115.615405 -363.411947)
			(xy 115.635328 -363.359856) (xy 115.662624 -363.311221) (xy 115.69671 -363.267078) (xy 115.736859 -363.228369)
			(xy 115.782217 -363.195918) (xy 115.831817 -363.170417) (xy 115.884601 -363.15241) (xy 115.939444 -363.14228)
			(xy 115.995178 -363.140243) (xy 116.050615 -363.146343) (xy 116.104572 -363.160449) (xy 116.155901 -363.182261)
			(xy 116.203507 -363.211315) (xy 116.246375 -363.24699) (xy 116.283592 -363.288527) (xy 116.314365 -363.33504)
			(xy 116.338037 -363.385537) (xy 116.354105 -363.438944) (xy 116.362225 -363.49412) (xy 116.362734 -363.522006)
			(xy 116.362225 -363.549892) (xy 116.354105 -363.605068) (xy 116.338037 -363.658475) (xy 116.314365 -363.708972)
			(xy 116.283592 -363.755485) (xy 116.246375 -363.797022) (xy 116.203507 -363.832697) (xy 116.155901 -363.861751)
			(xy 116.104572 -363.883563) (xy 116.050615 -363.897669) (xy 115.995178 -363.903769) (xy 115.939444 -363.901732)
			(xy 115.884601 -363.891602) (xy 115.831817 -363.873595) (xy 115.782217 -363.848094) (xy 115.736859 -363.815643)
			(xy 115.69671 -363.776934) (xy 115.662624 -363.732791) (xy 115.635328 -363.684156) (xy 115.615405 -363.632065)
			(xy 115.603279 -363.577628) (xy 115.599208 -363.522006) (xy 113.431444 -363.522006) (xy 113.407042 -363.558889)
			(xy 113.369825 -363.600426) (xy 113.326957 -363.636101) (xy 113.279351 -363.665155) (xy 113.228022 -363.686967)
			(xy 113.174065 -363.701073) (xy 113.118628 -363.707173) (xy 113.062894 -363.705136) (xy 113.008051 -363.695006)
			(xy 112.955267 -363.676999) (xy 112.905667 -363.651498) (xy 112.860309 -363.619047) (xy 112.82016 -363.580338)
			(xy 112.786074 -363.536195) (xy 112.758778 -363.48756) (xy 112.738855 -363.435469) (xy 112.726729 -363.381032)
			(xy 112.722658 -363.32541) (xy 110.496608 -363.32541) (xy 110.499905 -363.347816) (xy 110.500414 -363.375702)
			(xy 110.499905 -363.403588) (xy 110.491785 -363.458764) (xy 110.475717 -363.512171) (xy 110.452045 -363.562668)
			(xy 110.421272 -363.609181) (xy 110.384055 -363.650718) (xy 110.341187 -363.686393) (xy 110.293581 -363.715447)
			(xy 110.242252 -363.737259) (xy 110.188295 -363.751365) (xy 110.132858 -363.757465) (xy 110.077124 -363.755428)
			(xy 110.022281 -363.745298) (xy 109.969497 -363.727291) (xy 109.919897 -363.70179) (xy 109.874539 -363.669339)
			(xy 109.83439 -363.63063) (xy 109.800304 -363.586487) (xy 109.773008 -363.537852) (xy 109.753085 -363.485761)
			(xy 109.740959 -363.431324) (xy 109.736888 -363.375702) (xy 106.951128 -363.375702) (xy 106.94706 -363.381851)
			(xy 106.909843 -363.423388) (xy 106.866975 -363.459063) (xy 106.819369 -363.488117) (xy 106.76804 -363.509929)
			(xy 106.714083 -363.524035) (xy 106.658646 -363.530135) (xy 106.602912 -363.528098) (xy 106.548069 -363.517968)
			(xy 106.495285 -363.499961) (xy 106.445685 -363.47446) (xy 106.400327 -363.442009) (xy 106.360178 -363.4033)
			(xy 106.326092 -363.359157) (xy 106.298796 -363.310522) (xy 106.278873 -363.258431) (xy 106.266747 -363.203994)
			(xy 106.262676 -363.148372) (xy 103.933752 -363.148372) (xy 104.259888 -363.474508) (xy 104.269668 -363.48372)
			(xy 104.292949 -363.49711) (xy 104.318919 -363.503957) (xy 104.345775 -363.503785) (xy 104.371656 -363.496606)
			(xy 104.394763 -363.482919) (xy 104.413496 -363.463673) (xy 104.420416 -363.452156) (xy 104.434987 -363.427117)
			(xy 104.470513 -363.381359) (xy 104.512549 -363.341498) (xy 104.560127 -363.30845) (xy 104.612155 -363.282974)
			(xy 104.667435 -363.265655) (xy 104.724699 -363.256892) (xy 104.753664 -363.256322) (xy 104.780916 -363.256783)
			(xy 104.834867 -363.264535) (xy 104.887165 -363.279887) (xy 104.936746 -363.302525) (xy 104.9826 -363.33199)
			(xy 105.023794 -363.367681) (xy 105.059488 -363.408871) (xy 105.088957 -363.454723) (xy 105.111601 -363.504301)
			(xy 105.126957 -363.556598) (xy 105.134715 -363.610548) (xy 105.134715 -363.665052) (xy 105.126957 -363.719002)
			(xy 105.111601 -363.771299) (xy 105.088957 -363.820877) (xy 105.059488 -363.866729) (xy 105.023794 -363.907919)
			(xy 104.9826 -363.94361) (xy 104.936746 -363.973075) (xy 104.887165 -363.995713) (xy 104.834867 -364.011065)
			(xy 104.780916 -364.018817) (xy 104.753664 -364.019338) (xy 104.723358 -364.01876) (xy 104.663508 -364.009184)
			(xy 104.605925 -363.990265) (xy 104.552059 -363.962477) (xy 104.503266 -363.92652) (xy 104.48163 -363.905292)
			(xy 104.470702 -363.894972) (xy 104.4443 -363.88064) (xy 104.41487 -363.874609) (xy 104.384958 -363.877399)
			(xy 104.357152 -363.888771) (xy 104.333857 -363.907741) (xy 104.317088 -363.932666) (xy 104.308295 -363.961392)
			(xy 104.30764 -363.976412) (xy 104.30764 -364.4138) (xy 106.12069 -364.4138) (xy 106.124761 -364.358178)
			(xy 106.136887 -364.303741) (xy 106.15681 -364.25165) (xy 106.184106 -364.203015) (xy 106.218192 -364.158872)
			(xy 106.258341 -364.120163) (xy 106.303699 -364.087712) (xy 106.353299 -364.062211) (xy 106.406083 -364.044204)
			(xy 106.460926 -364.034074) (xy 106.51666 -364.032037) (xy 106.572097 -364.038137) (xy 106.626054 -364.052243)
			(xy 106.677383 -364.074055) (xy 106.724989 -364.103109) (xy 106.767857 -364.138784) (xy 106.805074 -364.180321)
			(xy 106.835847 -364.226834) (xy 106.859519 -364.277331) (xy 106.869398 -364.310168) (xy 107.575602 -364.310168)
			(xy 107.579673 -364.254546) (xy 107.591799 -364.200109) (xy 107.611722 -364.148018) (xy 107.639018 -364.099383)
			(xy 107.673104 -364.05524) (xy 107.713253 -364.016531) (xy 107.758611 -363.98408) (xy 107.808211 -363.958579)
			(xy 107.860995 -363.940572) (xy 107.915838 -363.930442) (xy 107.971572 -363.928405) (xy 108.027009 -363.934505)
			(xy 108.080966 -363.948611) (xy 108.132295 -363.970423) (xy 108.179901 -363.999477) (xy 108.222769 -364.035152)
			(xy 108.259986 -364.076689) (xy 108.290759 -364.123202) (xy 108.314431 -364.173699) (xy 108.330499 -364.227106)
			(xy 108.338619 -364.282282) (xy 108.339128 -364.310168) (xy 108.338619 -364.338054) (xy 108.330499 -364.39323)
			(xy 108.326603 -364.40618) (xy 109.82782 -364.40618) (xy 109.831891 -364.350558) (xy 109.844017 -364.296121)
			(xy 109.86394 -364.24403) (xy 109.891236 -364.195395) (xy 109.925322 -364.151252) (xy 109.965471 -364.112543)
			(xy 110.010829 -364.080092) (xy 110.060429 -364.054591) (xy 110.113213 -364.036584) (xy 110.168056 -364.026454)
			(xy 110.22379 -364.024417) (xy 110.279227 -364.030517) (xy 110.333184 -364.044623) (xy 110.384513 -364.066435)
			(xy 110.432119 -364.095489) (xy 110.474987 -364.131164) (xy 110.512204 -364.172701) (xy 110.542977 -364.219214)
			(xy 110.548703 -364.231428) (xy 111.419638 -364.231428) (xy 111.423709 -364.175806) (xy 111.435835 -364.121369)
			(xy 111.455758 -364.069278) (xy 111.483054 -364.020643) (xy 111.51714 -363.9765) (xy 111.557289 -363.937791)
			(xy 111.602647 -363.90534) (xy 111.652247 -363.879839) (xy 111.705031 -363.861832) (xy 111.759874 -363.851702)
			(xy 111.815608 -363.849665) (xy 111.871045 -363.855765) (xy 111.925002 -363.869871) (xy 111.976331 -363.891683)
			(xy 112.023937 -363.920737) (xy 112.066805 -363.956412) (xy 112.104022 -363.997949) (xy 112.134795 -364.044462)
			(xy 112.158467 -364.094959) (xy 112.174535 -364.148366) (xy 112.177713 -364.16996) (xy 114.192048 -364.16996)
			(xy 114.196121 -364.114301) (xy 114.208256 -364.059828) (xy 114.228192 -364.007702) (xy 114.255506 -363.959034)
			(xy 114.289614 -363.914862) (xy 114.329791 -363.876127) (xy 114.375179 -363.843655) (xy 114.424811 -363.818137)
			(xy 114.477631 -363.800118) (xy 114.53251 -363.789981) (xy 114.588281 -363.787943) (xy 114.643755 -363.794046)
			(xy 114.697748 -363.808162) (xy 114.749111 -363.829989) (xy 114.796749 -363.859062) (xy 114.839645 -363.894761)
			(xy 114.876887 -363.936325) (xy 114.907681 -363.982869) (xy 114.931369 -364.0334) (xy 114.947447 -364.086842)
			(xy 114.955573 -364.142056) (xy 114.956082 -364.16996) (xy 114.955573 -364.197864) (xy 114.947447 -364.253078)
			(xy 114.931369 -364.30652) (xy 114.907681 -364.357051) (xy 114.876887 -364.403595) (xy 114.839645 -364.445159)
			(xy 114.796749 -364.480858) (xy 114.749111 -364.509931) (xy 114.697748 -364.531758) (xy 114.643755 -364.545874)
			(xy 114.588281 -364.551977) (xy 114.53251 -364.549939) (xy 114.477631 -364.539802) (xy 114.424811 -364.521783)
			(xy 114.375179 -364.496265) (xy 114.329791 -364.463793) (xy 114.289614 -364.425058) (xy 114.255506 -364.380886)
			(xy 114.228192 -364.332218) (xy 114.208256 -364.280092) (xy 114.196121 -364.225619) (xy 114.192048 -364.16996)
			(xy 112.177713 -364.16996) (xy 112.182655 -364.203542) (xy 112.183164 -364.231428) (xy 112.182655 -364.259314)
			(xy 112.174535 -364.31449) (xy 112.158467 -364.367897) (xy 112.134795 -364.418394) (xy 112.104022 -364.464907)
			(xy 112.066805 -364.506444) (xy 112.023937 -364.542119) (xy 111.976331 -364.571173) (xy 111.925002 -364.592985)
			(xy 111.871045 -364.607091) (xy 111.815608 -364.613191) (xy 111.759874 -364.611154) (xy 111.705031 -364.601024)
			(xy 111.652247 -364.583017) (xy 111.602647 -364.557516) (xy 111.557289 -364.525065) (xy 111.51714 -364.486356)
			(xy 111.483054 -364.442213) (xy 111.455758 -364.393578) (xy 111.435835 -364.341487) (xy 111.423709 -364.28705)
			(xy 111.419638 -364.231428) (xy 110.548703 -364.231428) (xy 110.566649 -364.269711) (xy 110.582717 -364.323118)
			(xy 110.590837 -364.378294) (xy 110.591346 -364.40618) (xy 110.590837 -364.434066) (xy 110.582717 -364.489242)
			(xy 110.566649 -364.542649) (xy 110.542977 -364.593146) (xy 110.512204 -364.639659) (xy 110.474987 -364.681196)
			(xy 110.432119 -364.716871) (xy 110.384513 -364.745925) (xy 110.333184 -364.767737) (xy 110.279227 -364.781843)
			(xy 110.22379 -364.787943) (xy 110.168056 -364.785906) (xy 110.113213 -364.775776) (xy 110.060429 -364.757769)
			(xy 110.010829 -364.732268) (xy 109.965471 -364.699817) (xy 109.925322 -364.661108) (xy 109.891236 -364.616965)
			(xy 109.86394 -364.56833) (xy 109.844017 -364.516239) (xy 109.831891 -364.461802) (xy 109.82782 -364.40618)
			(xy 108.326603 -364.40618) (xy 108.314431 -364.446637) (xy 108.290759 -364.497134) (xy 108.259986 -364.543647)
			(xy 108.222769 -364.585184) (xy 108.179901 -364.620859) (xy 108.132295 -364.649913) (xy 108.080966 -364.671725)
			(xy 108.027009 -364.685831) (xy 107.971572 -364.691931) (xy 107.915838 -364.689894) (xy 107.860995 -364.679764)
			(xy 107.808211 -364.661757) (xy 107.758611 -364.636256) (xy 107.713253 -364.603805) (xy 107.673104 -364.565096)
			(xy 107.639018 -364.520953) (xy 107.611722 -364.472318) (xy 107.591799 -364.420227) (xy 107.579673 -364.36579)
			(xy 107.575602 -364.310168) (xy 106.869398 -364.310168) (xy 106.875587 -364.330738) (xy 106.883707 -364.385914)
			(xy 106.884216 -364.4138) (xy 106.883707 -364.441686) (xy 106.875587 -364.496862) (xy 106.859519 -364.550269)
			(xy 106.835847 -364.600766) (xy 106.805074 -364.647279) (xy 106.767857 -364.688816) (xy 106.724989 -364.724491)
			(xy 106.677383 -364.753545) (xy 106.626054 -364.775357) (xy 106.572097 -364.789463) (xy 106.51666 -364.795563)
			(xy 106.460926 -364.793526) (xy 106.406083 -364.783396) (xy 106.353299 -364.765389) (xy 106.303699 -364.739888)
			(xy 106.258341 -364.707437) (xy 106.218192 -364.668728) (xy 106.184106 -364.624585) (xy 106.15681 -364.57595)
			(xy 106.136887 -364.523859) (xy 106.124761 -364.469422) (xy 106.12069 -364.4138) (xy 104.30764 -364.4138)
			(xy 104.30764 -365.14024) (xy 106.985814 -365.14024) (xy 106.989885 -365.084618) (xy 107.002011 -365.030181)
			(xy 107.021934 -364.97809) (xy 107.04923 -364.929455) (xy 107.083316 -364.885312) (xy 107.123465 -364.846603)
			(xy 107.168823 -364.814152) (xy 107.218423 -364.788651) (xy 107.271207 -364.770644) (xy 107.32605 -364.760514)
			(xy 107.381784 -364.758477) (xy 107.437221 -364.764577) (xy 107.491178 -364.778683) (xy 107.542507 -364.800495)
			(xy 107.590113 -364.829549) (xy 107.632981 -364.865224) (xy 107.670198 -364.906761) (xy 107.692583 -364.940596)
			(xy 110.691928 -364.940596) (xy 110.695999 -364.884974) (xy 110.708125 -364.830537) (xy 110.728048 -364.778446)
			(xy 110.755344 -364.729811) (xy 110.78943 -364.685668) (xy 110.829579 -364.646959) (xy 110.874937 -364.614508)
			(xy 110.924537 -364.589007) (xy 110.977321 -364.571) (xy 111.032164 -364.56087) (xy 111.087898 -364.558833)
			(xy 111.143335 -364.564933) (xy 111.197292 -364.579039) (xy 111.248621 -364.600851) (xy 111.296227 -364.629905)
			(xy 111.339095 -364.66558) (xy 111.376312 -364.707117) (xy 111.407085 -364.75363) (xy 111.408762 -364.757208)
			(xy 112.321592 -364.757208) (xy 112.325663 -364.701586) (xy 112.337789 -364.647149) (xy 112.357712 -364.595058)
			(xy 112.385008 -364.546423) (xy 112.419094 -364.50228) (xy 112.459243 -364.463571) (xy 112.504601 -364.43112)
			(xy 112.554201 -364.405619) (xy 112.606985 -364.387612) (xy 112.661828 -364.377482) (xy 112.717562 -364.375445)
			(xy 112.772999 -364.381545) (xy 112.826956 -364.395651) (xy 112.878285 -364.417463) (xy 112.925891 -364.446517)
			(xy 112.968759 -364.482192) (xy 113.005976 -364.523729) (xy 113.036749 -364.570242) (xy 113.060421 -364.620739)
			(xy 113.076489 -364.674146) (xy 113.080714 -364.702852) (xy 119.224042 -364.702852) (xy 119.228113 -364.64723)
			(xy 119.240239 -364.592793) (xy 119.260162 -364.540702) (xy 119.287458 -364.492067) (xy 119.321544 -364.447924)
			(xy 119.361693 -364.409215) (xy 119.407051 -364.376764) (xy 119.456651 -364.351263) (xy 119.509435 -364.333256)
			(xy 119.564278 -364.323126) (xy 119.620012 -364.321089) (xy 119.675449 -364.327189) (xy 119.729406 -364.341295)
			(xy 119.780735 -364.363107) (xy 119.828341 -364.392161) (xy 119.871209 -364.427836) (xy 119.908426 -364.469373)
			(xy 119.939199 -364.515886) (xy 119.962871 -364.566383) (xy 119.978939 -364.61979) (xy 119.987059 -364.674966)
			(xy 119.987568 -364.702852) (xy 119.987059 -364.730738) (xy 119.978939 -364.785914) (xy 119.962871 -364.839321)
			(xy 119.939199 -364.889818) (xy 119.908426 -364.936331) (xy 119.871209 -364.977868) (xy 119.828341 -365.013543)
			(xy 119.780735 -365.042597) (xy 119.729406 -365.064409) (xy 119.675449 -365.078515) (xy 119.620012 -365.084615)
			(xy 119.564278 -365.082578) (xy 119.509435 -365.072448) (xy 119.456651 -365.054441) (xy 119.407051 -365.02894)
			(xy 119.361693 -364.996489) (xy 119.321544 -364.95778) (xy 119.287458 -364.913637) (xy 119.260162 -364.865002)
			(xy 119.240239 -364.812911) (xy 119.228113 -364.758474) (xy 119.224042 -364.702852) (xy 113.080714 -364.702852)
			(xy 113.084609 -364.729322) (xy 113.085118 -364.757208) (xy 113.084609 -364.785094) (xy 113.076489 -364.84027)
			(xy 113.060421 -364.893677) (xy 113.036749 -364.944174) (xy 113.005976 -364.990687) (xy 112.968759 -365.032224)
			(xy 112.925891 -365.067899) (xy 112.878285 -365.096953) (xy 112.826956 -365.118765) (xy 112.772999 -365.132871)
			(xy 112.717562 -365.138971) (xy 112.661828 -365.136934) (xy 112.606985 -365.126804) (xy 112.554201 -365.108797)
			(xy 112.504601 -365.083296) (xy 112.459243 -365.050845) (xy 112.419094 -365.012136) (xy 112.385008 -364.967993)
			(xy 112.357712 -364.919358) (xy 112.337789 -364.867267) (xy 112.325663 -364.81283) (xy 112.321592 -364.757208)
			(xy 111.408762 -364.757208) (xy 111.430757 -364.804127) (xy 111.446825 -364.857534) (xy 111.454945 -364.91271)
			(xy 111.455454 -364.940596) (xy 111.454945 -364.968482) (xy 111.446825 -365.023658) (xy 111.430757 -365.077065)
			(xy 111.407085 -365.127562) (xy 111.376312 -365.174075) (xy 111.339095 -365.215612) (xy 111.296227 -365.251287)
			(xy 111.248621 -365.280341) (xy 111.197292 -365.302153) (xy 111.143335 -365.316259) (xy 111.087898 -365.322359)
			(xy 111.032164 -365.320322) (xy 110.977321 -365.310192) (xy 110.924537 -365.292185) (xy 110.874937 -365.266684)
			(xy 110.829579 -365.234233) (xy 110.78943 -365.195524) (xy 110.755344 -365.151381) (xy 110.728048 -365.102746)
			(xy 110.708125 -365.050655) (xy 110.695999 -364.996218) (xy 110.691928 -364.940596) (xy 107.692583 -364.940596)
			(xy 107.700971 -364.953274) (xy 107.724643 -365.003771) (xy 107.740711 -365.057178) (xy 107.748831 -365.112354)
			(xy 107.74934 -365.14024) (xy 107.748831 -365.168126) (xy 107.740711 -365.223302) (xy 107.724643 -365.276709)
			(xy 107.700971 -365.327206) (xy 107.670198 -365.373719) (xy 107.632981 -365.415256) (xy 107.590113 -365.450931)
			(xy 107.542507 -365.479985) (xy 107.491178 -365.501797) (xy 107.446925 -365.513366) (xy 109.842298 -365.513366)
			(xy 109.846369 -365.457744) (xy 109.858495 -365.403307) (xy 109.878418 -365.351216) (xy 109.905714 -365.302581)
			(xy 109.9398 -365.258438) (xy 109.979949 -365.219729) (xy 110.025307 -365.187278) (xy 110.074907 -365.161777)
			(xy 110.127691 -365.14377) (xy 110.182534 -365.13364) (xy 110.238268 -365.131603) (xy 110.293705 -365.137703)
			(xy 110.347662 -365.151809) (xy 110.398991 -365.173621) (xy 110.446597 -365.202675) (xy 110.489465 -365.23835)
			(xy 110.526682 -365.279887) (xy 110.557455 -365.3264) (xy 110.581127 -365.376897) (xy 110.597195 -365.430304)
			(xy 110.605315 -365.48548) (xy 110.605824 -365.513366) (xy 110.605315 -365.541252) (xy 110.597195 -365.596428)
			(xy 110.581127 -365.649835) (xy 110.557455 -365.700332) (xy 110.526682 -365.746845) (xy 110.525819 -365.747808)
			(xy 132.860799 -365.747808) (xy 132.864835 -365.664361) (xy 132.876907 -365.581693) (xy 132.8969 -365.500576)
			(xy 132.924629 -365.421767) (xy 132.959835 -365.346002) (xy 133.002189 -365.273989) (xy 133.051295 -365.2064)
			(xy 133.106696 -365.143866) (xy 133.167873 -365.086971) (xy 133.234256 -365.036245) (xy 133.305224 -364.992164)
			(xy 133.380116 -364.955138) (xy 133.458232 -364.925512) (xy 133.538842 -364.903564) (xy 133.621194 -364.889499)
			(xy 133.70452 -364.883447) (xy 133.78804 -364.885466) (xy 133.870976 -364.895536) (xy 133.952552 -364.913564)
			(xy 134.032008 -364.939381) (xy 134.108601 -364.972746) (xy 134.181617 -365.013347) (xy 134.250373 -365.060806)
			(xy 134.314227 -365.114679) (xy 134.372584 -365.174464) (xy 134.424899 -365.239601) (xy 134.470682 -365.309484)
			(xy 134.509507 -365.383459) (xy 134.541012 -365.460836) (xy 134.564901 -365.540893) (xy 134.580952 -365.622881)
			(xy 134.589015 -365.706036) (xy 134.58952 -365.747808) (xy 134.589015 -365.78958) (xy 134.580952 -365.872735)
			(xy 134.564901 -365.954723) (xy 134.541012 -366.03478) (xy 134.528065 -366.066578) (xy 138.60324 -366.066578)
			(xy 138.607206 -365.982047) (xy 138.619071 -365.89826) (xy 138.638729 -365.815951) (xy 138.666009 -365.735845)
			(xy 138.70067 -365.658646) (xy 138.742408 -365.585031) (xy 138.790855 -365.515648) (xy 138.845587 -365.451107)
			(xy 138.906123 -365.391975) (xy 138.971929 -365.338771) (xy 139.042429 -365.291963) (xy 139.117001 -365.251962)
			(xy 139.194992 -365.21912) (xy 139.275716 -365.193726) (xy 139.358463 -365.176003) (xy 139.442505 -365.166105)
			(xy 139.527106 -365.164122) (xy 139.61152 -365.170069) (xy 139.695007 -365.183894) (xy 139.776832 -365.205477)
			(xy 139.856276 -365.234627) (xy 139.932642 -365.271088) (xy 140.005258 -365.31454) (xy 140.073486 -365.364601)
			(xy 140.136726 -365.420831) (xy 140.194423 -365.482736) (xy 140.24607 -365.549772) (xy 140.291212 -365.621349)
			(xy 140.329454 -365.696839) (xy 140.360458 -365.775578) (xy 140.383953 -365.856875) (xy 140.399732 -365.940014)
			(xy 140.407656 -366.024266) (xy 140.408152 -366.066578) (xy 140.407656 -366.10889) (xy 140.399732 -366.193142)
			(xy 140.383953 -366.276281) (xy 140.360458 -366.357578) (xy 140.329454 -366.436317) (xy 140.291212 -366.511807)
			(xy 140.24607 -366.583384) (xy 140.194423 -366.65042) (xy 140.136726 -366.712325) (xy 140.073486 -366.768555)
			(xy 140.005258 -366.818616) (xy 139.932642 -366.862068) (xy 139.856276 -366.898529) (xy 139.776832 -366.927679)
			(xy 139.695007 -366.949262) (xy 139.61152 -366.963087) (xy 139.527106 -366.969034) (xy 139.442505 -366.967051)
			(xy 139.358463 -366.957153) (xy 139.275716 -366.93943) (xy 139.194992 -366.914036) (xy 139.117001 -366.881194)
			(xy 139.042429 -366.841193) (xy 138.971929 -366.794385) (xy 138.906123 -366.741181) (xy 138.845587 -366.682049)
			(xy 138.790855 -366.617508) (xy 138.742408 -366.548125) (xy 138.70067 -366.47451) (xy 138.666009 -366.397311)
			(xy 138.638729 -366.317205) (xy 138.619071 -366.234896) (xy 138.607206 -366.151109) (xy 138.60324 -366.066578)
			(xy 134.528065 -366.066578) (xy 134.509507 -366.112157) (xy 134.470682 -366.186132) (xy 134.424899 -366.256015)
			(xy 134.372584 -366.321152) (xy 134.314227 -366.380937) (xy 134.250373 -366.43481) (xy 134.181617 -366.482269)
			(xy 134.108601 -366.52287) (xy 134.032008 -366.556235) (xy 133.952552 -366.582052) (xy 133.870976 -366.60008)
			(xy 133.78804 -366.61015) (xy 133.70452 -366.612169) (xy 133.621194 -366.606117) (xy 133.538842 -366.592052)
			(xy 133.458232 -366.570104) (xy 133.380116 -366.540478) (xy 133.305224 -366.503452) (xy 133.234256 -366.459371)
			(xy 133.167873 -366.408645) (xy 133.106696 -366.35175) (xy 133.051295 -366.289216) (xy 133.002189 -366.221627)
			(xy 132.959835 -366.149614) (xy 132.924629 -366.073849) (xy 132.8969 -365.99504) (xy 132.876907 -365.913923)
			(xy 132.864835 -365.831255) (xy 132.860799 -365.747808) (xy 110.525819 -365.747808) (xy 110.489465 -365.788382)
			(xy 110.446597 -365.824057) (xy 110.398991 -365.853111) (xy 110.347662 -365.874923) (xy 110.293705 -365.889029)
			(xy 110.238268 -365.895129) (xy 110.182534 -365.893092) (xy 110.127691 -365.882962) (xy 110.074907 -365.864955)
			(xy 110.025307 -365.839454) (xy 109.979949 -365.807003) (xy 109.9398 -365.768294) (xy 109.905714 -365.724151)
			(xy 109.878418 -365.675516) (xy 109.858495 -365.623425) (xy 109.846369 -365.568988) (xy 109.842298 -365.513366)
			(xy 107.446925 -365.513366) (xy 107.437221 -365.515903) (xy 107.381784 -365.522003) (xy 107.32605 -365.519966)
			(xy 107.271207 -365.509836) (xy 107.218423 -365.491829) (xy 107.168823 -365.466328) (xy 107.123465 -365.433877)
			(xy 107.083316 -365.395168) (xy 107.04923 -365.351025) (xy 107.021934 -365.30239) (xy 107.002011 -365.250299)
			(xy 106.989885 -365.195862) (xy 106.985814 -365.14024) (xy 104.30764 -365.14024) (xy 104.30764 -366.271853)
			(xy 104.673087 -366.271853) (xy 104.673087 -366.217347) (xy 104.680845 -366.163397) (xy 104.696202 -366.1111)
			(xy 104.718846 -366.061521) (xy 104.748316 -366.015669) (xy 104.784011 -365.974479) (xy 104.825206 -365.938788)
			(xy 104.871061 -365.909324) (xy 104.920643 -365.886686) (xy 104.972942 -365.871335) (xy 105.026893 -365.863584)
			(xy 105.054146 -365.863124) (xy 105.080526 -365.863544) (xy 105.132786 -365.870804) (xy 105.183547 -365.885191)
			(xy 105.231843 -365.906433) (xy 105.276753 -365.934124) (xy 105.317421 -365.967737) (xy 105.353072 -366.006631)
			(xy 105.383026 -366.050064) (xy 105.395268 -366.073436) (xy 105.40197 -366.085795) (xy 105.420945 -366.106523)
			(xy 105.444859 -366.121285) (xy 105.471895 -366.128957) (xy 105.499997 -366.128957) (xy 105.527033 -366.121285)
			(xy 105.550947 -366.106523) (xy 105.569922 -366.085795) (xy 105.576624 -366.073436) (xy 105.588879 -366.050073)
			(xy 105.618842 -366.006652) (xy 105.654497 -365.967769) (xy 105.695164 -365.934164) (xy 105.740071 -365.906477)
			(xy 105.788361 -365.885234) (xy 105.839116 -365.870842) (xy 105.891368 -365.863572) (xy 105.917746 -365.863124)
			(xy 105.944997 -365.863549) (xy 105.998945 -365.871311) (xy 106.051238 -365.886672) (xy 106.100814 -365.909318)
			(xy 106.146662 -365.938788) (xy 106.187851 -365.974482) (xy 106.22354 -366.015675) (xy 106.253005 -366.061527)
			(xy 106.275644 -366.111105) (xy 106.290998 -366.1634) (xy 106.298754 -366.217349) (xy 106.298754 -366.271851)
			(xy 106.290998 -366.3258) (xy 106.275644 -366.378095) (xy 106.253005 -366.427673) (xy 106.22354 -366.473525)
			(xy 106.187851 -366.514718) (xy 106.146662 -366.550412) (xy 106.100814 -366.579882) (xy 106.051238 -366.602528)
			(xy 105.998945 -366.617889) (xy 105.944997 -366.625651) (xy 105.917746 -366.62614) (xy 105.891367 -366.625691)
			(xy 105.839111 -366.618432) (xy 105.788352 -366.604046) (xy 105.740058 -366.582807) (xy 105.695148 -366.55512)
			(xy 105.65448 -366.521513) (xy 105.618826 -366.482625) (xy 105.588868 -366.439197) (xy 105.576624 -366.415828)
			(xy 105.569922 -366.403469) (xy 105.550947 -366.382741) (xy 105.527033 -366.367979) (xy 105.499997 -366.360307)
			(xy 105.471895 -366.360307) (xy 105.444859 -366.367979) (xy 105.420945 -366.382741) (xy 105.40197 -366.403469)
			(xy 105.395268 -366.415828) (xy 105.383003 -366.439186) (xy 105.353043 -366.482608) (xy 105.317391 -366.521493)
			(xy 105.276725 -366.555099) (xy 105.231819 -366.582787) (xy 105.18353 -366.60403) (xy 105.132776 -366.618423)
			(xy 105.080524 -366.625692) (xy 105.054146 -366.62614) (xy 105.026893 -366.625616) (xy 104.972942 -366.617865)
			(xy 104.920643 -366.602514) (xy 104.871061 -366.579876) (xy 104.825206 -366.550412) (xy 104.784011 -366.514721)
			(xy 104.748316 -366.473531) (xy 104.718846 -366.427679) (xy 104.696202 -366.3781) (xy 104.680845 -366.325803)
			(xy 104.673087 -366.271853) (xy 104.30764 -366.271853) (xy 104.30764 -366.653651) (xy 107.352072 -366.653651)
			(xy 107.352072 -366.599149) (xy 107.359828 -366.545202) (xy 107.375183 -366.492908) (xy 107.397823 -366.443331)
			(xy 107.427288 -366.39748) (xy 107.462978 -366.35629) (xy 107.504167 -366.320598) (xy 107.550017 -366.291131)
			(xy 107.599593 -366.268488) (xy 107.651886 -366.253131) (xy 107.705833 -366.245373) (xy 107.733084 -366.244886)
			(xy 107.759465 -366.245296) (xy 107.811723 -366.252559) (xy 107.862484 -366.26695) (xy 107.910779 -366.288195)
			(xy 107.955688 -366.315887) (xy 107.996356 -366.3495) (xy 108.032008 -366.388394) (xy 108.061963 -366.431826)
			(xy 108.074206 -366.455198) (xy 108.080908 -366.467557) (xy 108.099883 -366.488285) (xy 108.123797 -366.503047)
			(xy 108.150833 -366.510719) (xy 108.178935 -366.510719) (xy 108.205971 -366.503047) (xy 108.229885 -366.488285)
			(xy 108.24886 -366.467557) (xy 108.255562 -366.455198) (xy 108.267815 -366.431834) (xy 108.297776 -366.38841)
			(xy 108.333429 -366.349524) (xy 108.374097 -366.315917) (xy 108.419004 -366.28823) (xy 108.467296 -366.266988)
			(xy 108.518052 -366.252598) (xy 108.570306 -366.245332) (xy 108.596684 -366.244886) (xy 108.623937 -366.24536)
			(xy 108.677889 -366.253115) (xy 108.730188 -366.26847) (xy 108.779769 -366.291111) (xy 108.825624 -366.320578)
			(xy 108.866818 -366.356271) (xy 108.902512 -366.397463) (xy 108.931981 -366.443317) (xy 108.954625 -366.492897)
			(xy 108.969981 -366.545195) (xy 108.977739 -366.599147) (xy 108.977739 -366.653653) (xy 108.969981 -366.707605)
			(xy 108.954625 -366.759903) (xy 108.931981 -366.809483) (xy 108.902512 -366.855337) (xy 108.866818 -366.896529)
			(xy 108.825624 -366.932222) (xy 108.779769 -366.961689) (xy 108.730188 -366.98433) (xy 108.677889 -366.999685)
			(xy 108.623937 -367.00744) (xy 108.596684 -367.007902) (xy 108.570305 -367.007443) (xy 108.518048 -367.000188)
			(xy 108.467289 -366.985805) (xy 108.418994 -366.964569) (xy 108.374084 -366.936883) (xy 108.333415 -366.903276)
			(xy 108.297762 -366.864388) (xy 108.267805 -366.82096) (xy 108.255562 -366.79759) (xy 108.24886 -366.785231)
			(xy 108.229885 -366.764503) (xy 108.205971 -366.749741) (xy 108.178935 -366.742069) (xy 108.150833 -366.742069)
			(xy 108.123797 -366.749741) (xy 108.099883 -366.764503) (xy 108.080908 -366.785231) (xy 108.074206 -366.79759)
			(xy 108.061972 -366.820965) (xy 108.032009 -366.86439) (xy 107.996354 -366.903276) (xy 107.955683 -366.936882)
			(xy 107.910773 -366.964569) (xy 107.862479 -366.985808) (xy 107.81172 -367.000196) (xy 107.759463 -367.007458)
			(xy 107.733084 -367.007902) (xy 107.705833 -367.007427) (xy 107.651886 -366.999669) (xy 107.599593 -366.984312)
			(xy 107.550017 -366.961669) (xy 107.504167 -366.932202) (xy 107.462978 -366.89651) (xy 107.427288 -366.85532)
			(xy 107.397823 -366.809469) (xy 107.375183 -366.759892) (xy 107.359828 -366.707598) (xy 107.352072 -366.653651)
			(xy 104.30764 -366.653651) (xy 104.30764 -367.832132) (xy 121.144028 -367.832132) (xy 121.148099 -367.77651)
			(xy 121.160225 -367.722073) (xy 121.180148 -367.669982) (xy 121.207444 -367.621347) (xy 121.24153 -367.577204)
			(xy 121.281679 -367.538495) (xy 121.327037 -367.506044) (xy 121.376637 -367.480543) (xy 121.429421 -367.462536)
			(xy 121.484264 -367.452406) (xy 121.539998 -367.450369) (xy 121.595435 -367.456469) (xy 121.649392 -367.470575)
			(xy 121.700721 -367.492387) (xy 121.748327 -367.521441) (xy 121.791195 -367.557116) (xy 121.828412 -367.598653)
			(xy 121.859185 -367.645166) (xy 121.882857 -367.695663) (xy 121.898925 -367.74907) (xy 121.907045 -367.804246)
			(xy 121.907554 -367.832132) (xy 121.907045 -367.860018) (xy 121.898925 -367.915194) (xy 121.882857 -367.968601)
			(xy 121.859185 -368.019098) (xy 121.828412 -368.065611) (xy 121.825273 -368.069114) (xy 122.207274 -368.069114)
			(xy 122.207774 -368.040196) (xy 122.216503 -367.983023) (xy 122.233763 -367.927822) (xy 122.259158 -367.87586)
			(xy 122.292106 -367.828327) (xy 122.331852 -367.786312) (xy 122.35434 -367.768124) (xy 122.366136 -367.758214)
			(xy 122.383662 -367.732896) (xy 122.392843 -367.703505) (xy 122.392846 -367.672712) (xy 122.383669 -367.64332)
			(xy 122.366148 -367.617999) (xy 122.35434 -367.608104) (xy 122.331867 -367.589901) (xy 122.292129 -367.547885)
			(xy 122.259188 -367.500353) (xy 122.233797 -367.448394) (xy 122.216539 -367.393198) (xy 122.207809 -367.336029)
			(xy 122.207274 -367.307114) (xy 122.20776 -367.279863) (xy 122.215516 -367.225915) (xy 122.230871 -367.17362)
			(xy 122.253513 -367.124043) (xy 122.282979 -367.078193) (xy 122.31867 -367.037002) (xy 122.359861 -367.001311)
			(xy 122.405711 -366.971845) (xy 122.455288 -366.949203) (xy 122.507583 -366.933848) (xy 122.561531 -366.926092)
			(xy 122.616033 -366.926092) (xy 122.669981 -366.933848) (xy 122.722276 -366.949203) (xy 122.771853 -366.971845)
			(xy 122.817703 -367.001311) (xy 122.858894 -367.037002) (xy 122.894585 -367.078193) (xy 122.924051 -367.124043)
			(xy 122.946693 -367.17362) (xy 122.962048 -367.225915) (xy 122.969804 -367.279863) (xy 122.97029 -367.307114)
			(xy 122.969714 -367.336029) (xy 122.960997 -367.393198) (xy 122.943751 -367.448395) (xy 122.91837 -367.500357)
			(xy 122.885437 -367.547893) (xy 122.845705 -367.589912) (xy 122.823224 -367.608104) (xy 122.811404 -367.617986)
			(xy 122.793885 -367.643313) (xy 122.784709 -367.672711) (xy 122.784712 -367.703507) (xy 122.793892 -367.732903)
			(xy 122.811416 -367.758227) (xy 122.823224 -367.768124) (xy 122.845724 -367.786295) (xy 122.885457 -367.82832)
			(xy 122.918393 -367.875859) (xy 122.943779 -367.927824) (xy 122.961032 -367.983025) (xy 122.969757 -368.040197)
			(xy 122.97029 -368.069114) (xy 124.355098 -368.069114) (xy 124.355627 -368.040198) (xy 124.364354 -367.983027)
			(xy 124.38161 -367.927828) (xy 124.407 -367.875867) (xy 124.439941 -367.828332) (xy 124.47968 -367.786315)
			(xy 124.502164 -367.768124) (xy 124.513957 -367.758212) (xy 124.531479 -367.732894) (xy 124.540659 -367.703504)
			(xy 124.540661 -367.672713) (xy 124.531487 -367.643322) (xy 124.513969 -367.618) (xy 124.502164 -367.608104)
			(xy 124.479675 -367.58992) (xy 124.439942 -367.547898) (xy 124.407004 -367.500361) (xy 124.381617 -367.448398)
			(xy 124.364362 -367.3932) (xy 124.355633 -367.33603) (xy 124.355098 -367.307114) (xy 124.355584 -367.279863)
			(xy 124.36334 -367.225915) (xy 124.378695 -367.17362) (xy 124.401337 -367.124043) (xy 124.430803 -367.078193)
			(xy 124.466494 -367.037002) (xy 124.507685 -367.001311) (xy 124.553535 -366.971845) (xy 124.603112 -366.949203)
			(xy 124.655407 -366.933848) (xy 124.709355 -366.926092) (xy 124.763857 -366.926092) (xy 124.817805 -366.933848)
			(xy 124.8701 -366.949203) (xy 124.919677 -366.971845) (xy 124.965527 -367.001311) (xy 125.006718 -367.037002)
			(xy 125.042409 -367.078193) (xy 125.071875 -367.124043) (xy 125.094517 -367.17362) (xy 125.109872 -367.225915)
			(xy 125.117628 -367.279863) (xy 125.118114 -367.307114) (xy 125.117566 -367.33603) (xy 125.108848 -367.393202)
			(xy 125.091598 -367.448401) (xy 125.066212 -367.500364) (xy 125.033272 -367.547898) (xy 124.993533 -367.589914)
			(xy 124.971048 -367.608104) (xy 124.959226 -367.617984) (xy 124.941702 -367.643311) (xy 124.932525 -367.67271)
			(xy 124.932527 -367.703508) (xy 124.94171 -367.732905) (xy 124.959237 -367.758228) (xy 124.971048 -367.768124)
			(xy 124.993553 -367.786289) (xy 125.033285 -367.828316) (xy 125.06622 -367.875857) (xy 125.091604 -367.927823)
			(xy 125.108856 -367.983024) (xy 125.117581 -368.040197) (xy 125.118114 -368.069114) (xy 126.488698 -368.069114)
			(xy 126.489227 -368.040198) (xy 126.497954 -367.983027) (xy 126.51521 -367.927828) (xy 126.5406 -367.875867)
			(xy 126.573541 -367.828332) (xy 126.61328 -367.786315) (xy 126.635764 -367.768124) (xy 126.647557 -367.758212)
			(xy 126.665079 -367.732894) (xy 126.674259 -367.703504) (xy 126.674261 -367.672713) (xy 126.665087 -367.643322)
			(xy 126.647569 -367.618) (xy 126.635764 -367.608104) (xy 126.613275 -367.58992) (xy 126.573542 -367.547898)
			(xy 126.540604 -367.500361) (xy 126.515217 -367.448398) (xy 126.497962 -367.3932) (xy 126.489233 -367.33603)
			(xy 126.488698 -367.307114) (xy 126.489184 -367.279863) (xy 126.49694 -367.225915) (xy 126.512295 -367.17362)
			(xy 126.534937 -367.124043) (xy 126.564403 -367.078193) (xy 126.600094 -367.037002) (xy 126.641285 -367.001311)
			(xy 126.687135 -366.971845) (xy 126.736712 -366.949203) (xy 126.789007 -366.933848) (xy 126.842955 -366.926092)
			(xy 126.897457 -366.926092) (xy 126.951405 -366.933848) (xy 127.0037 -366.949203) (xy 127.053277 -366.971845)
			(xy 127.099127 -367.001311) (xy 127.140318 -367.037002) (xy 127.176009 -367.078193) (xy 127.205475 -367.124043)
			(xy 127.228117 -367.17362) (xy 127.243472 -367.225915) (xy 127.251228 -367.279863) (xy 127.251714 -367.307114)
			(xy 127.251166 -367.33603) (xy 127.242448 -367.393202) (xy 127.225198 -367.448401) (xy 127.199812 -367.500364)
			(xy 127.166872 -367.547898) (xy 127.127133 -367.589914) (xy 127.104648 -367.608104) (xy 127.092826 -367.617984)
			(xy 127.075302 -367.643311) (xy 127.066125 -367.67271) (xy 127.066127 -367.703508) (xy 127.07531 -367.732905)
			(xy 127.092837 -367.758228) (xy 127.104648 -367.768124) (xy 127.127153 -367.786289) (xy 127.166885 -367.828316)
			(xy 127.19982 -367.875857) (xy 127.225204 -367.927823) (xy 127.242456 -367.983024) (xy 127.251181 -368.040197)
			(xy 127.25119 -368.040666) (xy 128.641348 -368.040666) (xy 128.641896 -368.01175) (xy 128.650616 -367.954579)
			(xy 128.667867 -367.89938) (xy 128.693253 -367.847418) (xy 128.726193 -367.799884) (xy 128.76593 -367.757867)
			(xy 128.788414 -367.739676) (xy 128.800251 -367.729814) (xy 128.817763 -367.70448) (xy 128.826932 -367.675078)
			(xy 128.826926 -367.64428) (xy 128.817744 -367.614882) (xy 128.800222 -367.589555) (xy 128.788414 -367.579656)
			(xy 128.765912 -367.561486) (xy 128.726178 -367.519463) (xy 128.69324 -367.471923) (xy 128.667855 -367.419958)
			(xy 128.650603 -367.364756) (xy 128.64188 -367.307583) (xy 128.641348 -367.278666) (xy 128.641834 -367.251415)
			(xy 128.64959 -367.197467) (xy 128.664945 -367.145172) (xy 128.687587 -367.095595) (xy 128.717053 -367.049745)
			(xy 128.752744 -367.008554) (xy 128.793935 -366.972863) (xy 128.839785 -366.943397) (xy 128.889362 -366.920755)
			(xy 128.941657 -366.9054) (xy 128.995605 -366.897644) (xy 129.050107 -366.897644) (xy 129.104055 -366.9054)
			(xy 129.15635 -366.920755) (xy 129.205927 -366.943397) (xy 129.251777 -366.972863) (xy 129.292968 -367.008554)
			(xy 129.328659 -367.049745) (xy 129.358125 -367.095595) (xy 129.380767 -367.145172) (xy 129.396122 -367.197467)
			(xy 129.403878 -367.251415) (xy 129.404364 -367.278666) (xy 129.403835 -367.307583) (xy 129.39511 -367.364754)
			(xy 129.377855 -367.419953) (xy 129.352466 -367.471915) (xy 129.319523 -367.519449) (xy 129.279783 -367.561466)
			(xy 129.257298 -367.579656) (xy 129.245528 -367.589592) (xy 129.228013 -367.614905) (xy 129.218835 -367.644288)
			(xy 129.218829 -367.675071) (xy 129.227994 -367.704457) (xy 129.2455 -367.729778) (xy 129.257298 -367.739676)
			(xy 129.27977 -367.757881) (xy 129.319506 -367.799898) (xy 129.352446 -367.84743) (xy 129.377836 -367.899388)
			(xy 129.395095 -367.954583) (xy 129.403827 -368.011751) (xy 129.404364 -368.040666) (xy 129.403878 -368.067917)
			(xy 129.396122 -368.121865) (xy 129.380767 -368.17416) (xy 129.358125 -368.223737) (xy 129.328659 -368.269587)
			(xy 129.310731 -368.290278) (xy 132.836408 -368.290278) (xy 132.836408 -368.205582) (xy 132.844459 -368.121268)
			(xy 132.860488 -368.038102) (xy 132.884349 -367.956835) (xy 132.915828 -367.878205) (xy 132.954639 -367.802924)
			(xy 133.000429 -367.731672) (xy 133.052785 -367.665096) (xy 133.111233 -367.603798) (xy 133.175243 -367.548333)
			(xy 133.244235 -367.499204) (xy 133.317585 -367.456855) (xy 133.394628 -367.421671) (xy 133.474667 -367.393969)
			(xy 133.556976 -367.374001) (xy 133.640811 -367.361948) (xy 133.725412 -367.357918) (xy 133.810013 -367.361948)
			(xy 133.893848 -367.374001) (xy 133.976157 -367.393969) (xy 134.056196 -367.421671) (xy 134.133239 -367.456855)
			(xy 134.206589 -367.499204) (xy 134.275581 -367.548333) (xy 134.339591 -367.603798) (xy 134.398039 -367.665096)
			(xy 134.450395 -367.731672) (xy 134.496185 -367.802924) (xy 134.534996 -367.878205) (xy 134.566475 -367.956835)
			(xy 134.590336 -368.038102) (xy 134.606365 -368.121268) (xy 134.614416 -368.205582) (xy 134.61492 -368.24793)
			(xy 134.614416 -368.290278) (xy 134.606365 -368.374592) (xy 134.590336 -368.457758) (xy 134.566475 -368.539025)
			(xy 134.534996 -368.617655) (xy 134.496185 -368.692936) (xy 134.450395 -368.764188) (xy 134.398039 -368.830764)
			(xy 134.339591 -368.892062) (xy 134.275581 -368.947527) (xy 134.206589 -368.996656) (xy 134.133239 -369.039005)
			(xy 134.056196 -369.074189) (xy 133.976157 -369.101891) (xy 133.893848 -369.121859) (xy 133.810013 -369.133912)
			(xy 133.725412 -369.137943) (xy 133.640811 -369.133912) (xy 133.556976 -369.121859) (xy 133.474667 -369.101891)
			(xy 133.394628 -369.074189) (xy 133.317585 -369.039005) (xy 133.244235 -368.996656) (xy 133.175243 -368.947527)
			(xy 133.111233 -368.892062) (xy 133.052785 -368.830764) (xy 133.000429 -368.764188) (xy 132.954639 -368.692936)
			(xy 132.915828 -368.617655) (xy 132.884349 -368.539025) (xy 132.860488 -368.457758) (xy 132.844459 -368.374592)
			(xy 132.836408 -368.290278) (xy 129.310731 -368.290278) (xy 129.292968 -368.310778) (xy 129.251777 -368.346469)
			(xy 129.205927 -368.375935) (xy 129.15635 -368.398577) (xy 129.104055 -368.413932) (xy 129.050107 -368.421688)
			(xy 128.995605 -368.421688) (xy 128.941657 -368.413932) (xy 128.889362 -368.398577) (xy 128.839785 -368.375935)
			(xy 128.793935 -368.346469) (xy 128.752744 -368.310778) (xy 128.717053 -368.269587) (xy 128.687587 -368.223737)
			(xy 128.664945 -368.17416) (xy 128.64959 -368.121865) (xy 128.641834 -368.067917) (xy 128.641348 -368.040666)
			(xy 127.25119 -368.040666) (xy 127.251714 -368.069114) (xy 127.251228 -368.096365) (xy 127.243472 -368.150313)
			(xy 127.228117 -368.202608) (xy 127.205475 -368.252185) (xy 127.176009 -368.298035) (xy 127.140318 -368.339226)
			(xy 127.099127 -368.374917) (xy 127.053277 -368.404383) (xy 127.0037 -368.427025) (xy 126.951405 -368.44238)
			(xy 126.897457 -368.450136) (xy 126.842955 -368.450136) (xy 126.789007 -368.44238) (xy 126.736712 -368.427025)
			(xy 126.687135 -368.404383) (xy 126.641285 -368.374917) (xy 126.600094 -368.339226) (xy 126.564403 -368.298035)
			(xy 126.534937 -368.252185) (xy 126.512295 -368.202608) (xy 126.49694 -368.150313) (xy 126.489184 -368.096365)
			(xy 126.488698 -368.069114) (xy 125.118114 -368.069114) (xy 125.117628 -368.096365) (xy 125.109872 -368.150313)
			(xy 125.094517 -368.202608) (xy 125.071875 -368.252185) (xy 125.042409 -368.298035) (xy 125.006718 -368.339226)
			(xy 124.965527 -368.374917) (xy 124.919677 -368.404383) (xy 124.8701 -368.427025) (xy 124.817805 -368.44238)
			(xy 124.763857 -368.450136) (xy 124.709355 -368.450136) (xy 124.655407 -368.44238) (xy 124.603112 -368.427025)
			(xy 124.553535 -368.404383) (xy 124.507685 -368.374917) (xy 124.466494 -368.339226) (xy 124.430803 -368.298035)
			(xy 124.401337 -368.252185) (xy 124.378695 -368.202608) (xy 124.36334 -368.150313) (xy 124.355584 -368.096365)
			(xy 124.355098 -368.069114) (xy 122.97029 -368.069114) (xy 122.969804 -368.096365) (xy 122.962048 -368.150313)
			(xy 122.946693 -368.202608) (xy 122.924051 -368.252185) (xy 122.894585 -368.298035) (xy 122.858894 -368.339226)
			(xy 122.817703 -368.374917) (xy 122.771853 -368.404383) (xy 122.722276 -368.427025) (xy 122.669981 -368.44238)
			(xy 122.616033 -368.450136) (xy 122.561531 -368.450136) (xy 122.507583 -368.44238) (xy 122.455288 -368.427025)
			(xy 122.405711 -368.404383) (xy 122.359861 -368.374917) (xy 122.31867 -368.339226) (xy 122.282979 -368.298035)
			(xy 122.253513 -368.252185) (xy 122.230871 -368.202608) (xy 122.215516 -368.150313) (xy 122.20776 -368.096365)
			(xy 122.207274 -368.069114) (xy 121.825273 -368.069114) (xy 121.791195 -368.107148) (xy 121.748327 -368.142823)
			(xy 121.700721 -368.171877) (xy 121.649392 -368.193689) (xy 121.595435 -368.207795) (xy 121.539998 -368.213895)
			(xy 121.484264 -368.211858) (xy 121.429421 -368.201728) (xy 121.376637 -368.183721) (xy 121.327037 -368.15822)
			(xy 121.281679 -368.125769) (xy 121.24153 -368.08706) (xy 121.207444 -368.042917) (xy 121.180148 -367.994282)
			(xy 121.160225 -367.942191) (xy 121.148099 -367.887754) (xy 121.144028 -367.832132) (xy 104.30764 -367.832132)
			(xy 104.30764 -368.696748) (xy 117.255542 -368.696748) (xy 117.259613 -368.641126) (xy 117.271739 -368.586689)
			(xy 117.291662 -368.534598) (xy 117.318958 -368.485963) (xy 117.353044 -368.44182) (xy 117.393193 -368.403111)
			(xy 117.438551 -368.37066) (xy 117.488151 -368.345159) (xy 117.540935 -368.327152) (xy 117.595778 -368.317022)
			(xy 117.651512 -368.314985) (xy 117.706949 -368.321085) (xy 117.760906 -368.335191) (xy 117.812235 -368.357003)
			(xy 117.859841 -368.386057) (xy 117.902709 -368.421732) (xy 117.939926 -368.463269) (xy 117.970699 -368.509782)
			(xy 117.994371 -368.560279) (xy 118.010439 -368.613686) (xy 118.018559 -368.668862) (xy 118.019068 -368.696748)
			(xy 118.018559 -368.724634) (xy 118.010439 -368.77981) (xy 117.994371 -368.833217) (xy 117.970699 -368.883714)
			(xy 117.939926 -368.930227) (xy 117.902709 -368.971764) (xy 117.859841 -369.007439) (xy 117.812235 -369.036493)
			(xy 117.760906 -369.058305) (xy 117.706949 -369.072411) (xy 117.651512 -369.078511) (xy 117.595778 -369.076474)
			(xy 117.540935 -369.066344) (xy 117.488151 -369.048337) (xy 117.438551 -369.022836) (xy 117.393193 -368.990385)
			(xy 117.353044 -368.951676) (xy 117.318958 -368.907533) (xy 117.291662 -368.858898) (xy 117.271739 -368.806807)
			(xy 117.259613 -368.75237) (xy 117.255542 -368.696748) (xy 104.30764 -368.696748) (xy 104.30764 -369.69446)
			(xy 105.09758 -370.4844) (xy 137.2362 -370.4844) (xy 140.377164 -367.343436) (xy 142.328138 -367.343436)
			(xy 142.536418 -367.011458) (xy 142.543705 -366.998942) (xy 142.551647 -366.971105) (xy 142.551455 -366.942158)
			(xy 142.543146 -366.914428) (xy 142.527387 -366.890146) (xy 142.505445 -366.871263) (xy 142.479085 -366.859299)
			(xy 142.450427 -366.855215) (xy 142.421774 -366.85934) (xy 142.408402 -366.8649) (xy 142.365617 -366.883685)
			(xy 142.276913 -366.913075) (xy 142.185583 -366.932855) (xy 142.092667 -366.942798) (xy 142.045944 -366.943386)
			(xy 142.004199 -366.942907) (xy 141.921087 -366.934975) (xy 141.839105 -366.919178) (xy 141.758997 -366.895659)
			(xy 141.681486 -366.864632) (xy 141.607276 -366.826377) (xy 141.537039 -366.781242) (xy 141.47141 -366.729634)
			(xy 141.410984 -366.672021) (xy 141.356308 -366.608925) (xy 141.307878 -366.540917) (xy 141.266132 -366.468613)
			(xy 141.231448 -366.392669) (xy 141.204141 -366.313771) (xy 141.184456 -366.232635) (xy 141.172574 -366.149995)
			(xy 141.168601 -366.0666) (xy 141.172574 -365.983205) (xy 141.184456 -365.900565) (xy 141.204141 -365.819429)
			(xy 141.231448 -365.740531) (xy 141.266132 -365.664587) (xy 141.307878 -365.592283) (xy 141.356308 -365.524275)
			(xy 141.410984 -365.461179) (xy 141.47141 -365.403566) (xy 141.537039 -365.351958) (xy 141.607276 -365.306823)
			(xy 141.681486 -365.268568) (xy 141.758997 -365.237541) (xy 141.839105 -365.214022) (xy 141.921087 -365.198225)
			(xy 142.004199 -365.190293) (xy 142.045944 -365.18977) (xy 142.088341 -365.190269) (xy 142.17274 -365.198458)
			(xy 142.255953 -365.214757) (xy 142.337204 -365.239013) (xy 142.415735 -365.270999) (xy 142.490811 -365.310417)
			(xy 142.561731 -365.356898) (xy 142.627832 -365.410008) (xy 142.688499 -365.469252) (xy 142.743162 -365.534075)
			(xy 142.791313 -365.603872) (xy 142.832501 -365.677991) (xy 142.866342 -365.75574) (xy 142.892518 -365.836393)
			(xy 142.910787 -365.919197) (xy 142.920978 -366.003377) (xy 142.922498 -366.04575) (xy 142.923366 -366.060187)
			(xy 142.932158 -366.087726) (xy 142.948313 -366.1117) (xy 142.970536 -366.130188) (xy 142.997049 -366.14171)
			(xy 143.025729 -366.145344) (xy 143.054278 -366.140797) (xy 143.08041 -366.128436) (xy 143.102033 -366.109249)
			(xy 143.110204 -366.097312) (xy 147.522692 -359.065068) (xy 147.522692 -356.907338) (xy 147.52317 -356.864314)
			(xy 147.530675 -356.778595) (xy 147.537678 -356.736142) (xy 147.839938 -355.021388) (xy 147.839938 -339.639402)
			(xy 139.891262 -331.690726) (xy 133.516878 -331.690726) (xy 133.506809 -331.6903) (xy 133.488208 -331.682583)
			(xy 133.48081 -331.67574) (xy 131.635246 -329.830176) (xy 127.139192 -329.830176) (xy 127.129123 -329.829751)
			(xy 127.110523 -329.822032) (xy 127.103124 -329.81519) (xy 123.497086 -326.209152) (xy 95.379286 -326.209152)
			(xy 92.148152 -329.440286) (xy 92.140752 -329.447127) (xy 92.122153 -329.454846) (xy 92.112084 -329.455272)
			(xy 86.514686 -329.455272) (xy 84.945728 -331.02423) (xy 84.945728 -332.384146) (xy 84.945297 -332.394213)
			(xy 84.937574 -332.412808) (xy 84.930742 -332.420214) (xy 84.289138 -333.061818) (xy 84.28174 -333.068663)
			(xy 84.263141 -333.076388) (xy 84.25307 -333.076804) (xy 76.531724 -333.076804) (xy 76.426568 -333.18196)
			(xy 76.426568 -334.541368) (xy 93.012768 -334.541368) (xy 93.013254 -334.514117) (xy 93.02101 -334.460169)
			(xy 93.036365 -334.407874) (xy 93.059007 -334.358297) (xy 93.088473 -334.312447) (xy 93.124164 -334.271256)
			(xy 93.165355 -334.235565) (xy 93.211205 -334.206099) (xy 93.260782 -334.183457) (xy 93.313077 -334.168102)
			(xy 93.367025 -334.160346) (xy 93.421527 -334.160346) (xy 93.475475 -334.168102) (xy 93.52777 -334.183457)
			(xy 93.577347 -334.206099) (xy 93.623197 -334.235565) (xy 93.664388 -334.271256) (xy 93.700079 -334.312447)
			(xy 93.729545 -334.358297) (xy 93.752187 -334.407874) (xy 93.767542 -334.460169) (xy 93.775298 -334.514117)
			(xy 93.775784 -334.541368) (xy 93.775371 -334.567043) (xy 93.768491 -334.61793) (xy 93.75485 -334.667435)
			(xy 93.734695 -334.714664) (xy 93.70839 -334.758764) (xy 93.692726 -334.779112) (xy 93.683994 -334.790855)
			(xy 93.672944 -334.817938) (xy 93.670019 -334.847042) (xy 93.675461 -334.875781) (xy 93.688821 -334.901802)
			(xy 93.698568 -334.912716) (xy 93.718314 -334.934136) (xy 93.751715 -334.981866) (xy 93.777482 -335.034113)
			(xy 93.795016 -335.089668) (xy 93.803912 -335.147241) (xy 93.804486 -335.176368) (xy 101.201982 -335.176368)
			(xy 101.202409 -335.148996) (xy 101.210233 -335.094815) (xy 101.22573 -335.04231) (xy 101.248581 -334.992564)
			(xy 101.278316 -334.9466) (xy 101.295962 -334.92567) (xy 101.305233 -334.914367) (xy 101.317411 -334.887801)
			(xy 101.321579 -334.858876) (xy 101.317397 -334.829952) (xy 101.305206 -334.803392) (xy 101.295962 -334.792066)
			(xy 101.278334 -334.771125) (xy 101.248622 -334.725154) (xy 101.225784 -334.675409) (xy 101.21029 -334.62291)
			(xy 101.202458 -334.568736) (xy 101.201982 -334.541368) (xy 101.202468 -334.514117) (xy 101.210224 -334.460169)
			(xy 101.225579 -334.407874) (xy 101.248221 -334.358297) (xy 101.277687 -334.312447) (xy 101.313378 -334.271256)
			(xy 101.354569 -334.235565) (xy 101.400419 -334.206099) (xy 101.449996 -334.183457) (xy 101.502291 -334.168102)
			(xy 101.556239 -334.160346) (xy 101.610741 -334.160346) (xy 101.664689 -334.168102) (xy 101.716984 -334.183457)
			(xy 101.766561 -334.206099) (xy 101.812411 -334.235565) (xy 101.853602 -334.271256) (xy 101.889293 -334.312447)
			(xy 101.918759 -334.358297) (xy 101.941401 -334.407874) (xy 101.956756 -334.460169) (xy 101.964512 -334.514117)
			(xy 101.964998 -334.541368) (xy 101.964514 -334.568738) (xy 101.9567 -334.622916) (xy 101.941216 -334.675419)
			(xy 101.918378 -334.725166) (xy 101.888657 -334.771134) (xy 101.871018 -334.792066) (xy 101.861811 -334.803416)
			(xy 101.849628 -334.829965) (xy 101.845448 -334.858876) (xy 101.849614 -334.887788) (xy 101.861785 -334.914343)
			(xy 101.871018 -334.92567) (xy 101.888659 -334.9466) (xy 101.91837 -334.992574) (xy 101.941205 -335.042322)
			(xy 101.956696 -335.094823) (xy 101.964524 -335.148999) (xy 101.964998 -335.176368) (xy 109.362494 -335.176368)
			(xy 109.362943 -335.148997) (xy 109.370765 -335.094817) (xy 109.386258 -335.042314) (xy 109.409104 -334.992568)
			(xy 109.438831 -334.946601) (xy 109.456474 -334.92567) (xy 109.465744 -334.914367) (xy 109.477921 -334.887801)
			(xy 109.482088 -334.858876) (xy 109.477907 -334.829953) (xy 109.465717 -334.803393) (xy 109.456474 -334.792066)
			(xy 109.438848 -334.771123) (xy 109.409135 -334.725153) (xy 109.386297 -334.675408) (xy 109.370803 -334.62291)
			(xy 109.362971 -334.568736) (xy 109.362494 -334.541368) (xy 109.36298 -334.514117) (xy 109.370736 -334.460169)
			(xy 109.386091 -334.407874) (xy 109.408733 -334.358297) (xy 109.438199 -334.312447) (xy 109.47389 -334.271256)
			(xy 109.515081 -334.235565) (xy 109.560931 -334.206099) (xy 109.610508 -334.183457) (xy 109.662803 -334.168102)
			(xy 109.716751 -334.160346) (xy 109.771253 -334.160346) (xy 109.825201 -334.168102) (xy 109.877496 -334.183457)
			(xy 109.927073 -334.206099) (xy 109.972923 -334.235565) (xy 110.014114 -334.271256) (xy 110.049805 -334.312447)
			(xy 110.079271 -334.358297) (xy 110.101913 -334.407874) (xy 110.117268 -334.460169) (xy 110.125024 -334.514117)
			(xy 110.12551 -334.541368) (xy 110.125023 -334.568737) (xy 110.11721 -334.622916) (xy 110.101725 -334.675418)
			(xy 110.078888 -334.725165) (xy 110.049169 -334.771133) (xy 110.03153 -334.792066) (xy 110.022322 -334.803415)
			(xy 110.010137 -334.829965) (xy 110.005957 -334.858876) (xy 110.010123 -334.887789) (xy 110.022296 -334.914344)
			(xy 110.03153 -334.92567) (xy 110.049173 -334.946599) (xy 110.078883 -334.992573) (xy 110.101718 -335.042321)
			(xy 110.117208 -335.094823) (xy 110.125036 -335.148999) (xy 110.12551 -335.176368) (xy 117.523006 -335.176368)
			(xy 117.523452 -335.148997) (xy 117.531274 -335.094817) (xy 117.546768 -335.042314) (xy 117.569614 -334.992567)
			(xy 117.599343 -334.946601) (xy 117.616986 -334.92567) (xy 117.626255 -334.914366) (xy 117.63843 -334.8878)
			(xy 117.642597 -334.858876) (xy 117.638416 -334.829953) (xy 117.626228 -334.803393) (xy 117.616986 -334.792066)
			(xy 117.599362 -334.771122) (xy 117.569649 -334.725152) (xy 117.54681 -334.675408) (xy 117.531315 -334.62291)
			(xy 117.523483 -334.568736) (xy 117.523006 -334.541368) (xy 117.523492 -334.514117) (xy 117.531248 -334.460169)
			(xy 117.546603 -334.407874) (xy 117.569245 -334.358297) (xy 117.598711 -334.312447) (xy 117.634402 -334.271256)
			(xy 117.675593 -334.235565) (xy 117.721443 -334.206099) (xy 117.77102 -334.183457) (xy 117.823315 -334.168102)
			(xy 117.877263 -334.160346) (xy 117.931765 -334.160346) (xy 117.985713 -334.168102) (xy 118.038008 -334.183457)
			(xy 118.087585 -334.206099) (xy 118.133435 -334.235565) (xy 118.174626 -334.271256) (xy 118.210317 -334.312447)
			(xy 118.239783 -334.358297) (xy 118.262425 -334.407874) (xy 118.27778 -334.460169) (xy 118.285536 -334.514117)
			(xy 118.286022 -334.541368) (xy 118.285556 -334.568738) (xy 118.277741 -334.622918) (xy 118.262253 -334.675422)
			(xy 118.239411 -334.725169) (xy 118.209684 -334.771135) (xy 118.192042 -334.792066) (xy 118.182841 -334.803418)
			(xy 118.170666 -334.829968) (xy 118.16649 -334.858876) (xy 118.170653 -334.887785) (xy 118.182814 -334.914341)
			(xy 118.192042 -334.92567) (xy 118.209687 -334.946597) (xy 118.239397 -334.992572) (xy 118.262231 -335.042321)
			(xy 118.277721 -335.094822) (xy 118.285549 -335.148999) (xy 118.286022 -335.176368) (xy 118.285536 -335.203619)
			(xy 118.27778 -335.257567) (xy 118.262425 -335.309862) (xy 118.239783 -335.359439) (xy 118.210317 -335.405289)
			(xy 118.174626 -335.44648) (xy 118.133435 -335.482171) (xy 118.087585 -335.511637) (xy 118.038008 -335.534279)
			(xy 117.985713 -335.549634) (xy 117.931765 -335.55739) (xy 117.877263 -335.55739) (xy 117.823315 -335.549634)
			(xy 117.77102 -335.534279) (xy 117.721443 -335.511637) (xy 117.675593 -335.482171) (xy 117.634402 -335.44648)
			(xy 117.598711 -335.405289) (xy 117.569245 -335.359439) (xy 117.546603 -335.309862) (xy 117.531248 -335.257567)
			(xy 117.523492 -335.203619) (xy 117.523006 -335.176368) (xy 110.12551 -335.176368) (xy 110.125024 -335.203619)
			(xy 110.117268 -335.257567) (xy 110.101913 -335.309862) (xy 110.079271 -335.359439) (xy 110.049805 -335.405289)
			(xy 110.014114 -335.44648) (xy 109.972923 -335.482171) (xy 109.927073 -335.511637) (xy 109.877496 -335.534279)
			(xy 109.825201 -335.549634) (xy 109.771253 -335.55739) (xy 109.716751 -335.55739) (xy 109.662803 -335.549634)
			(xy 109.610508 -335.534279) (xy 109.560931 -335.511637) (xy 109.515081 -335.482171) (xy 109.47389 -335.44648)
			(xy 109.438199 -335.405289) (xy 109.408733 -335.359439) (xy 109.386091 -335.309862) (xy 109.370736 -335.257567)
			(xy 109.36298 -335.203619) (xy 109.362494 -335.176368) (xy 101.964998 -335.176368) (xy 101.964512 -335.203619)
			(xy 101.956756 -335.257567) (xy 101.941401 -335.309862) (xy 101.918759 -335.359439) (xy 101.889293 -335.405289)
			(xy 101.853602 -335.44648) (xy 101.812411 -335.482171) (xy 101.766561 -335.511637) (xy 101.716984 -335.534279)
			(xy 101.664689 -335.549634) (xy 101.610741 -335.55739) (xy 101.556239 -335.55739) (xy 101.502291 -335.549634)
			(xy 101.449996 -335.534279) (xy 101.400419 -335.511637) (xy 101.354569 -335.482171) (xy 101.313378 -335.44648)
			(xy 101.277687 -335.405289) (xy 101.248221 -335.359439) (xy 101.225579 -335.309862) (xy 101.210224 -335.257567)
			(xy 101.202468 -335.203619) (xy 101.201982 -335.176368) (xy 93.804486 -335.176368) (xy 93.804 -335.203619)
			(xy 93.796244 -335.257567) (xy 93.780889 -335.309862) (xy 93.758247 -335.359439) (xy 93.728781 -335.405289)
			(xy 93.69309 -335.44648) (xy 93.651899 -335.482171) (xy 93.606049 -335.511637) (xy 93.556472 -335.534279)
			(xy 93.504177 -335.549634) (xy 93.450229 -335.55739) (xy 93.395727 -335.55739) (xy 93.341779 -335.549634)
			(xy 93.289484 -335.534279) (xy 93.239907 -335.511637) (xy 93.194057 -335.482171) (xy 93.152866 -335.44648)
			(xy 93.117175 -335.405289) (xy 93.087709 -335.359439) (xy 93.065067 -335.309862) (xy 93.049712 -335.257567)
			(xy 93.041956 -335.203619) (xy 93.04147 -335.176368) (xy 93.041913 -335.150694) (xy 93.048788 -335.099809)
			(xy 93.062422 -335.050305) (xy 93.08257 -335.003075) (xy 93.108868 -334.958973) (xy 93.124528 -334.938624)
			(xy 93.133329 -334.926927) (xy 93.144376 -334.899827) (xy 93.147289 -334.870708) (xy 93.14183 -334.841957)
			(xy 93.128445 -334.815933) (xy 93.118686 -334.80502) (xy 93.098966 -334.783577) (xy 93.065559 -334.735854)
			(xy 93.039787 -334.683613) (xy 93.022246 -334.628063) (xy 93.013345 -334.570494) (xy 93.012768 -334.541368)
			(xy 76.426568 -334.541368) (xy 76.426568 -335.579) (xy 97.290117 -335.579) (xy 97.294285 -335.523384)
			(xy 97.306694 -335.469011) (xy 97.327068 -335.417094) (xy 97.354952 -335.368793) (xy 97.389723 -335.325188)
			(xy 97.430604 -335.287251) (xy 97.476682 -335.25583) (xy 97.526928 -335.231627) (xy 97.580221 -335.215183)
			(xy 97.635368 -335.206864) (xy 97.663254 -335.20634) (xy 97.690586 -335.206812) (xy 97.744666 -335.214781)
			(xy 97.797 -335.230569) (xy 97.846465 -335.253837) (xy 97.891997 -335.284084) (xy 97.932619 -335.320663)
			(xy 97.967459 -335.362786) (xy 97.982024 -335.385918) (xy 97.989942 -335.398145) (xy 98.011416 -335.417814)
			(xy 98.03757 -335.430618) (xy 98.066276 -335.435512) (xy 98.095196 -335.4321) (xy 98.10877 -335.426812)
			(xy 98.131987 -335.41734) (xy 98.180316 -335.403982) (xy 98.230003 -335.397247) (xy 98.255074 -335.39684)
			(xy 98.280144 -335.397251) (xy 98.329827 -335.404006) (xy 98.378161 -335.417343) (xy 98.401378 -335.426812)
			(xy 98.414951 -335.43207) (xy 98.443854 -335.435432) (xy 98.472533 -335.430519) (xy 98.498669 -335.417728)
			(xy 98.520144 -335.398094) (xy 98.528124 -335.385918) (xy 98.542693 -335.362787) (xy 98.577536 -335.320666)
			(xy 98.618159 -335.284087) (xy 98.66369 -335.253836) (xy 98.713152 -335.23056) (xy 98.765483 -335.21476)
			(xy 98.819562 -335.206774) (xy 98.874226 -335.206774) (xy 98.928305 -335.21476) (xy 98.980636 -335.23056)
			(xy 99.030098 -335.253836) (xy 99.075629 -335.284087) (xy 99.116252 -335.320666) (xy 99.151095 -335.362787)
			(xy 99.165664 -335.385918) (xy 99.173544 -335.398173) (xy 99.195028 -335.417842) (xy 99.221193 -335.430641)
			(xy 99.249908 -335.435529) (xy 99.278834 -335.432106) (xy 99.29241 -335.426812) (xy 99.315622 -335.417328)
			(xy 99.363954 -335.403974) (xy 99.413643 -335.397244) (xy 99.438714 -335.39684) (xy 99.465556 -335.397321)
			(xy 99.518683 -335.405026) (xy 99.570155 -335.420275) (xy 99.618906 -335.442752) (xy 99.663928 -335.471992)
			(xy 99.704287 -335.50739) (xy 99.73915 -335.548213) (xy 99.767794 -335.593616) (xy 99.789627 -335.642659)
			(xy 99.797362 -335.668366) (xy 99.802083 -335.682841) (xy 99.818592 -335.708398) (xy 99.841895 -335.72796)
			(xy 99.869926 -335.739792) (xy 99.900198 -335.742845) (xy 99.930026 -335.736849) (xy 99.943666 -335.730088)
			(xy 99.97181 -335.715451) (xy 100.031762 -335.694725) (xy 100.094321 -335.684228) (xy 100.126038 -335.683606)
			(xy 100.144057 -335.683825) (xy 100.179932 -335.687261) (xy 100.197666 -335.690464) (xy 100.212879 -335.692764)
			(xy 100.243427 -335.689245) (xy 100.271544 -335.676793) (xy 100.294679 -335.656537) (xy 100.310737 -335.630312)
			(xy 100.315014 -335.615534) (xy 100.3224 -335.588487) (xy 100.344032 -335.536761) (xy 100.372998 -335.488756)
			(xy 100.408676 -335.445505) (xy 100.450296 -335.407938) (xy 100.496965 -335.376865) (xy 100.547677 -335.352952)
			(xy 100.601342 -335.336716) (xy 100.656805 -335.328505) (xy 100.684838 -335.328006) (xy 100.712091 -335.328443)
			(xy 100.766041 -335.336205) (xy 100.818338 -335.351565) (xy 100.867916 -335.374212) (xy 100.913767 -335.403683)
			(xy 100.954957 -335.43938) (xy 100.990648 -335.480575) (xy 101.020113 -335.52643) (xy 101.042753 -335.576011)
			(xy 101.043631 -335.579) (xy 105.450617 -335.579) (xy 105.454785 -335.523383) (xy 105.467195 -335.469009)
			(xy 105.48757 -335.417091) (xy 105.515455 -335.36879) (xy 105.550227 -335.325183) (xy 105.591109 -335.287246)
			(xy 105.637189 -335.255826) (xy 105.687437 -335.231624) (xy 105.740731 -335.21518) (xy 105.79588 -335.206863)
			(xy 105.823766 -335.20634) (xy 105.851098 -335.206803) (xy 105.905179 -335.214774) (xy 105.957513 -335.230563)
			(xy 106.006978 -335.253832) (xy 106.05251 -335.284081) (xy 106.093132 -335.320661) (xy 106.127971 -335.362785)
			(xy 106.142536 -335.385918) (xy 106.150443 -335.398154) (xy 106.17192 -335.417823) (xy 106.198077 -335.430625)
			(xy 106.226786 -335.435517) (xy 106.255707 -335.432101) (xy 106.269282 -335.426812) (xy 106.292497 -335.417336)
			(xy 106.340827 -335.40398) (xy 106.390515 -335.397246) (xy 106.415586 -335.39684) (xy 106.440655 -335.397279)
			(xy 106.490337 -335.404022) (xy 106.538672 -335.417349) (xy 106.56189 -335.426812) (xy 106.575495 -335.431977)
			(xy 106.604381 -335.435359) (xy 106.63305 -335.430467) (xy 106.65918 -335.417697) (xy 106.680654 -335.398084)
			(xy 106.688636 -335.385918) (xy 106.703205 -335.362787) (xy 106.738048 -335.320666) (xy 106.778671 -335.284087)
			(xy 106.824202 -335.253836) (xy 106.873664 -335.23056) (xy 106.925995 -335.21476) (xy 106.980074 -335.206774)
			(xy 107.034738 -335.206774) (xy 107.088817 -335.21476) (xy 107.141148 -335.23056) (xy 107.19061 -335.253836)
			(xy 107.236141 -335.284087) (xy 107.276764 -335.320666) (xy 107.311607 -335.362787) (xy 107.326176 -335.385918)
			(xy 107.33414 -335.398113) (xy 107.355601 -335.417782) (xy 107.381743 -335.430589) (xy 107.410438 -335.435492)
			(xy 107.43935 -335.432092) (xy 107.452922 -335.426812) (xy 107.476132 -335.417324) (xy 107.524465 -335.403972)
			(xy 107.574154 -335.397244) (xy 107.599226 -335.39684) (xy 107.626068 -335.39731) (xy 107.679196 -335.405017)
			(xy 107.730668 -335.420268) (xy 107.779419 -335.442746) (xy 107.824441 -335.471988) (xy 107.8648 -335.507387)
			(xy 107.899663 -335.548211) (xy 107.928307 -335.593614) (xy 107.950139 -335.642658) (xy 107.957874 -335.668366)
			(xy 107.962579 -335.682847) (xy 107.979091 -335.708406) (xy 108.002398 -335.727968) (xy 108.030432 -335.7398)
			(xy 108.060707 -335.742851) (xy 108.090538 -335.736851) (xy 108.104178 -335.730088) (xy 108.13232 -335.715447)
			(xy 108.192273 -335.694722) (xy 108.254833 -335.684227) (xy 108.28655 -335.683606) (xy 108.304569 -335.683824)
			(xy 108.340444 -335.68726) (xy 108.358178 -335.690464) (xy 108.37339 -335.692776) (xy 108.403939 -335.689254)
			(xy 108.432056 -335.676799) (xy 108.455192 -335.65654) (xy 108.471249 -335.630313) (xy 108.475526 -335.615534)
			(xy 108.482901 -335.588483) (xy 108.504534 -335.536757) (xy 108.533502 -335.488751) (xy 108.56918 -335.4455)
			(xy 108.610802 -335.407934) (xy 108.657472 -335.37686) (xy 108.708186 -335.352949) (xy 108.761852 -335.336714)
			(xy 108.817316 -335.328504) (xy 108.84535 -335.328006) (xy 108.872602 -335.328502) (xy 108.926553 -335.336252)
			(xy 108.978851 -335.351603) (xy 109.028432 -335.37424) (xy 109.074286 -335.403705) (xy 109.115479 -335.439395)
			(xy 109.151174 -335.480585) (xy 109.180642 -335.526437) (xy 109.203285 -335.576015) (xy 109.204161 -335.579)
			(xy 113.611117 -335.579) (xy 113.615285 -335.523382) (xy 113.627696 -335.469007) (xy 113.648071 -335.417088)
			(xy 113.675957 -335.368786) (xy 113.710731 -335.325179) (xy 113.751615 -335.287242) (xy 113.797696 -335.255822)
			(xy 113.847945 -335.23162) (xy 113.901241 -335.215178) (xy 113.956391 -335.206863) (xy 113.984278 -335.20634)
			(xy 114.011611 -335.206794) (xy 114.065691 -335.214766) (xy 114.118026 -335.230557) (xy 114.167491 -335.253828)
			(xy 114.213023 -335.284078) (xy 114.253644 -335.320659) (xy 114.288483 -335.362784) (xy 114.303048 -335.385918)
			(xy 114.310943 -335.398162) (xy 114.332423 -335.417831) (xy 114.358584 -335.430632) (xy 114.387295 -335.435522)
			(xy 114.416219 -335.432103) (xy 114.429794 -335.426812) (xy 114.453008 -335.417333) (xy 114.501339 -335.403978)
			(xy 114.551027 -335.397245) (xy 114.576098 -335.39684) (xy 114.601167 -335.397276) (xy 114.65085 -335.40402)
			(xy 114.699184 -335.417348) (xy 114.722402 -335.426812) (xy 114.736003 -335.43199) (xy 114.764891 -335.435369)
			(xy 114.793561 -335.430474) (xy 114.819692 -335.417701) (xy 114.841166 -335.398085) (xy 114.849148 -335.385918)
			(xy 114.863717 -335.362787) (xy 114.89856 -335.320666) (xy 114.939183 -335.284087) (xy 114.984714 -335.253836)
			(xy 115.034176 -335.23056) (xy 115.086507 -335.21476) (xy 115.140586 -335.206774) (xy 115.19525 -335.206774)
			(xy 115.249329 -335.21476) (xy 115.30166 -335.23056) (xy 115.351122 -335.253836) (xy 115.396653 -335.284087)
			(xy 115.437276 -335.320666) (xy 115.472119 -335.362787) (xy 115.486688 -335.385918) (xy 115.49464 -335.398121)
			(xy 115.516105 -335.41779) (xy 115.54225 -335.430596) (xy 115.570948 -335.435497) (xy 115.599861 -335.432094)
			(xy 115.613434 -335.426812) (xy 115.636643 -335.41732) (xy 115.684976 -335.40397) (xy 115.734666 -335.397243)
			(xy 115.759738 -335.39684) (xy 115.78658 -335.3973) (xy 115.839709 -335.405008) (xy 115.891181 -335.420261)
			(xy 115.939933 -335.442741) (xy 115.984954 -335.471983) (xy 116.025313 -335.507383) (xy 116.060175 -335.548208)
			(xy 116.088819 -335.593613) (xy 116.110651 -335.642658) (xy 116.118386 -335.668366) (xy 116.123076 -335.682853)
			(xy 116.13959 -335.708413) (xy 116.1629 -335.727976) (xy 116.190938 -335.739807) (xy 116.221216 -335.742856)
			(xy 116.251049 -335.736853) (xy 116.26469 -335.730088) (xy 116.29283 -335.715442) (xy 116.352784 -335.69472)
			(xy 116.415345 -335.684226) (xy 116.447062 -335.683606) (xy 116.465081 -335.683822) (xy 116.500956 -335.687259)
			(xy 116.51869 -335.690464) (xy 116.5339 -335.692788) (xy 116.564451 -335.689263) (xy 116.592569 -335.676805)
			(xy 116.615704 -335.656543) (xy 116.631761 -335.630314) (xy 116.636038 -335.615534) (xy 116.643402 -335.58848)
			(xy 116.665036 -335.536753) (xy 116.694005 -335.488747) (xy 116.729685 -335.445495) (xy 116.771308 -335.407929)
			(xy 116.81798 -335.376856) (xy 116.868695 -335.352946) (xy 116.922362 -335.336711) (xy 116.977827 -335.328503)
			(xy 117.005862 -335.328006) (xy 117.033115 -335.328491) (xy 117.087065 -335.336243) (xy 117.139364 -335.351595)
			(xy 117.188945 -335.374234) (xy 117.234799 -335.403699) (xy 117.275992 -335.439391) (xy 117.311686 -335.480582)
			(xy 117.341155 -335.526434) (xy 117.363797 -335.576014) (xy 117.364674 -335.579) (xy 121.771617 -335.579)
			(xy 121.775785 -335.523381) (xy 121.788196 -335.469004) (xy 121.808573 -335.417085) (xy 121.83646 -335.368782)
			(xy 121.871235 -335.325175) (xy 121.91212 -335.287238) (xy 121.958203 -335.255818) (xy 122.008454 -335.231617)
			(xy 122.061751 -335.215176) (xy 122.116903 -335.206862) (xy 122.14479 -335.20634) (xy 122.172123 -335.206784)
			(xy 122.226204 -335.214758) (xy 122.278539 -335.230551) (xy 122.328004 -335.253823) (xy 122.373536 -335.284075)
			(xy 122.414157 -335.320657) (xy 122.448995 -335.362784) (xy 122.46356 -335.385918) (xy 122.471444 -335.39817)
			(xy 122.492927 -335.417839) (xy 122.519091 -335.430639) (xy 122.547805 -335.435527) (xy 122.57673 -335.432105)
			(xy 122.590306 -335.426812) (xy 122.613518 -335.417329) (xy 122.66185 -335.403975) (xy 122.711539 -335.397245)
			(xy 122.73661 -335.39684) (xy 122.761679 -335.397272) (xy 122.811362 -335.404018) (xy 122.859696 -335.417347)
			(xy 122.882914 -335.426812) (xy 122.89651 -335.432003) (xy 122.925401 -335.435379) (xy 122.954073 -335.430481)
			(xy 122.980204 -335.417706) (xy 123.001678 -335.398087) (xy 123.00966 -335.385918) (xy 123.024229 -335.362787)
			(xy 123.059072 -335.320666) (xy 123.099695 -335.284087) (xy 123.145226 -335.253836) (xy 123.194688 -335.23056)
			(xy 123.247019 -335.21476) (xy 123.301098 -335.206774) (xy 123.355762 -335.206774) (xy 123.409841 -335.21476)
			(xy 123.462172 -335.23056) (xy 123.511634 -335.253836) (xy 123.557165 -335.284087) (xy 123.597788 -335.320666)
			(xy 123.632631 -335.362787) (xy 123.6472 -335.385918) (xy 123.655141 -335.398129) (xy 123.676608 -335.417798)
			(xy 123.702757 -335.430603) (xy 123.731457 -335.435502) (xy 123.760373 -335.432096) (xy 123.773946 -335.426812)
			(xy 123.797154 -335.417317) (xy 123.845488 -335.403968) (xy 123.895178 -335.397242) (xy 123.92025 -335.39684)
			(xy 123.948136 -335.397416) (xy 124.003286 -335.405721) (xy 124.056582 -335.422155) (xy 124.106833 -335.446348)
			(xy 124.152917 -335.477762) (xy 124.193803 -335.515694) (xy 124.228579 -335.559296) (xy 124.256467 -335.607595)
			(xy 124.276844 -335.659511) (xy 124.289256 -335.713884) (xy 124.293424 -335.7695) (xy 124.289256 -335.825116)
			(xy 124.276844 -335.879489) (xy 124.256467 -335.931405) (xy 124.228579 -335.979704) (xy 124.193803 -336.023306)
			(xy 124.152917 -336.061238) (xy 124.106833 -336.092652) (xy 124.056582 -336.116845) (xy 124.003286 -336.133279)
			(xy 123.948136 -336.141584) (xy 123.92025 -336.142076) (xy 123.892918 -336.141593) (xy 123.838839 -336.133625)
			(xy 123.786506 -336.117839) (xy 123.737042 -336.094572) (xy 123.691509 -336.064327) (xy 123.650887 -336.02775)
			(xy 123.616046 -335.985629) (xy 123.60148 -335.962498) (xy 123.593554 -335.950276) (xy 123.572084 -335.930605)
			(xy 123.545931 -335.9178) (xy 123.517226 -335.912904) (xy 123.488308 -335.916316) (xy 123.474734 -335.921604)
			(xy 123.451517 -335.931076) (xy 123.403188 -335.944433) (xy 123.353501 -335.951169) (xy 123.32843 -335.951576)
			(xy 123.30336 -335.951163) (xy 123.253677 -335.944409) (xy 123.205343 -335.931072) (xy 123.182126 -335.921604)
			(xy 123.168553 -335.916343) (xy 123.13965 -335.912979) (xy 123.110969 -335.917892) (xy 123.084834 -335.930685)
			(xy 123.063359 -335.950321) (xy 123.05538 -335.962498) (xy 123.040811 -335.985629) (xy 123.005968 -336.02775)
			(xy 122.965345 -336.064329) (xy 122.919814 -336.09458) (xy 122.870352 -336.117856) (xy 122.818021 -336.133656)
			(xy 122.763942 -336.141642) (xy 122.709278 -336.141642) (xy 122.655199 -336.133656) (xy 122.602868 -336.117856)
			(xy 122.553406 -336.09458) (xy 122.507875 -336.064329) (xy 122.467252 -336.02775) (xy 122.432409 -335.985629)
			(xy 122.41784 -335.962498) (xy 122.409952 -335.950248) (xy 122.388471 -335.930577) (xy 122.362308 -335.917776)
			(xy 122.333594 -335.912888) (xy 122.304669 -335.91631) (xy 122.291094 -335.921604) (xy 122.267882 -335.931088)
			(xy 122.21955 -335.944441) (xy 122.169861 -335.951171) (xy 122.14479 -335.951576) (xy 122.116903 -335.951138)
			(xy 122.061751 -335.942824) (xy 122.008454 -335.926383) (xy 121.958203 -335.902182) (xy 121.91212 -335.870762)
			(xy 121.871235 -335.832825) (xy 121.83646 -335.789218) (xy 121.808573 -335.740915) (xy 121.788196 -335.688996)
			(xy 121.775785 -335.634619) (xy 121.771617 -335.579) (xy 117.364674 -335.579) (xy 117.379152 -335.628311)
			(xy 117.386908 -335.682261) (xy 117.38737 -335.709514) (xy 117.386856 -335.737087) (xy 117.378914 -335.791658)
			(xy 117.3632 -335.844517) (xy 117.340039 -335.894564) (xy 117.309915 -335.940755) (xy 117.273454 -335.982127)
			(xy 117.25275 -336.000344) (xy 117.241835 -336.010226) (xy 117.225755 -336.034879) (xy 117.217369 -336.063092)
			(xy 117.217371 -336.092526) (xy 117.225763 -336.120737) (xy 117.241847 -336.145388) (xy 117.25275 -336.155284)
			(xy 117.273472 -336.173483) (xy 117.30994 -336.214855) (xy 117.34007 -336.261046) (xy 117.363235 -336.311095)
			(xy 117.378951 -336.363959) (xy 117.386892 -336.418534) (xy 117.38689 -336.473684) (xy 117.378947 -336.528259)
			(xy 117.363229 -336.581121) (xy 117.340061 -336.631169) (xy 117.331207 -336.644742) (xy 118.31396 -336.644742)
			(xy 118.318031 -336.58912) (xy 118.330157 -336.534683) (xy 118.35008 -336.482592) (xy 118.377376 -336.433957)
			(xy 118.411462 -336.389814) (xy 118.451611 -336.351105) (xy 118.496969 -336.318654) (xy 118.546569 -336.293153)
			(xy 118.599353 -336.275146) (xy 118.654196 -336.265016) (xy 118.70993 -336.262979) (xy 118.765367 -336.269079)
			(xy 118.819324 -336.283185) (xy 118.870653 -336.304997) (xy 118.918259 -336.334051) (xy 118.961127 -336.369726)
			(xy 118.998344 -336.411263) (xy 119.029117 -336.457776) (xy 119.052789 -336.508273) (xy 119.068857 -336.56168)
			(xy 119.076977 -336.616856) (xy 119.077486 -336.644742) (xy 119.076977 -336.672628) (xy 119.068857 -336.727804)
			(xy 119.052789 -336.781211) (xy 119.029117 -336.831708) (xy 118.998344 -336.878221) (xy 118.961127 -336.919758)
			(xy 118.918259 -336.955433) (xy 118.870653 -336.984487) (xy 118.819324 -337.006299) (xy 118.765367 -337.020405)
			(xy 118.70993 -337.026505) (xy 118.654196 -337.024468) (xy 118.599353 -337.014338) (xy 118.546569 -336.996331)
			(xy 118.496969 -336.97083) (xy 118.451611 -336.938379) (xy 118.411462 -336.89967) (xy 118.377376 -336.855527)
			(xy 118.35008 -336.806892) (xy 118.330157 -336.754801) (xy 118.318031 -336.700364) (xy 118.31396 -336.644742)
			(xy 117.331207 -336.644742) (xy 117.309929 -336.67736) (xy 117.273459 -336.71873) (xy 117.25275 -336.736944)
			(xy 117.241835 -336.746826) (xy 117.225755 -336.771479) (xy 117.217369 -336.799692) (xy 117.217371 -336.829126)
			(xy 117.225763 -336.857337) (xy 117.241847 -336.881988) (xy 117.25275 -336.891884) (xy 117.273467 -336.910089)
			(xy 117.309934 -336.95146) (xy 117.340065 -336.997652) (xy 117.363229 -337.047701) (xy 117.378945 -337.100564)
			(xy 117.386884 -337.155139) (xy 117.38737 -337.182714) (xy 117.386958 -337.209969) (xy 117.379845 -337.259422)
			(xy 117.522496 -337.259422) (xy 117.526567 -337.2038) (xy 117.538693 -337.149363) (xy 117.558616 -337.097272)
			(xy 117.585912 -337.048637) (xy 117.619998 -337.004494) (xy 117.660147 -336.965785) (xy 117.705505 -336.933334)
			(xy 117.755105 -336.907833) (xy 117.807889 -336.889826) (xy 117.862732 -336.879696) (xy 117.918466 -336.877659)
			(xy 117.973903 -336.883759) (xy 118.02786 -336.897865) (xy 118.079189 -336.919677) (xy 118.126795 -336.948731)
			(xy 118.169663 -336.984406) (xy 118.20688 -337.025943) (xy 118.237653 -337.072456) (xy 118.261325 -337.122953)
			(xy 118.277393 -337.17636) (xy 118.285513 -337.231536) (xy 118.286022 -337.259422) (xy 118.285513 -337.287308)
			(xy 118.277393 -337.342484) (xy 118.261325 -337.395891) (xy 118.237653 -337.446388) (xy 118.20688 -337.492901)
			(xy 118.169663 -337.534438) (xy 118.126795 -337.570113) (xy 118.079189 -337.599167) (xy 118.02786 -337.620979)
			(xy 117.973903 -337.635085) (xy 117.918466 -337.641185) (xy 117.862732 -337.639148) (xy 117.807889 -337.629018)
			(xy 117.755105 -337.611011) (xy 117.705505 -337.58551) (xy 117.660147 -337.553059) (xy 117.619998 -337.51435)
			(xy 117.585912 -337.470207) (xy 117.558616 -337.421572) (xy 117.538693 -337.369481) (xy 117.526567 -337.315044)
			(xy 117.522496 -337.259422) (xy 117.379845 -337.259422) (xy 117.379198 -337.263924) (xy 117.363838 -337.316225)
			(xy 117.341192 -337.365808) (xy 117.311718 -337.411663) (xy 117.276019 -337.452856) (xy 117.234821 -337.48855)
			(xy 117.188962 -337.518016) (xy 117.139376 -337.540657) (xy 117.087073 -337.556009) (xy 117.033117 -337.563762)
			(xy 117.005862 -337.564222) (xy 116.978006 -337.563717) (xy 116.922891 -337.555588) (xy 116.869541 -337.539539)
			(xy 116.819089 -337.515909) (xy 116.772605 -337.4852) (xy 116.731076 -337.448063) (xy 116.695383 -337.405287)
			(xy 116.666284 -337.357779) (xy 116.644395 -337.306547) (xy 116.6368 -337.279742) (xy 116.632472 -337.265645)
			(xy 116.617096 -337.240501) (xy 116.595191 -337.220783) (xy 116.568575 -337.208127) (xy 116.539455 -337.203582)
			(xy 116.524786 -337.205066) (xy 116.511769 -337.206735) (xy 116.485585 -337.208515) (xy 116.472462 -337.208622)
			(xy 116.458313 -337.208532) (xy 116.43009 -337.206495) (xy 116.416074 -337.204558) (xy 116.402721 -337.203043)
			(xy 116.376039 -337.206134) (xy 116.351092 -337.216091) (xy 116.329615 -337.232222) (xy 116.313101 -337.253406)
			(xy 116.302698 -337.27817) (xy 116.300504 -337.291426) (xy 116.296414 -337.318579) (xy 116.281442 -337.37141)
			(xy 116.259052 -337.42155) (xy 116.229705 -337.467961) (xy 116.194009 -337.509686) (xy 116.152699 -337.545863)
			(xy 116.106629 -337.575744) (xy 116.056752 -337.598712) (xy 116.004098 -337.614293) (xy 115.949754 -337.622165)
			(xy 115.922298 -337.622642) (xy 115.895048 -337.622124) (xy 115.841103 -337.614368) (xy 115.788811 -337.599015)
			(xy 115.739236 -337.576376) (xy 115.693388 -337.546912) (xy 115.652198 -337.511224) (xy 115.616507 -337.470038)
			(xy 115.58704 -337.424192) (xy 115.564397 -337.374619) (xy 115.549039 -337.322328) (xy 115.541278 -337.268384)
			(xy 115.54079 -337.241134) (xy 115.541283 -337.21356) (xy 115.54923 -337.158989) (xy 115.56495 -337.10613)
			(xy 115.588115 -337.056084) (xy 115.618243 -337.009893) (xy 115.654705 -336.968521) (xy 115.67541 -336.950304)
			(xy 115.686272 -336.94037) (xy 115.702343 -336.915729) (xy 115.71073 -336.887531) (xy 115.710736 -336.858113)
			(xy 115.702362 -336.829911) (xy 115.686301 -336.805263) (xy 115.67541 -336.795364) (xy 115.65468 -336.777173)
			(xy 115.618211 -336.7358) (xy 115.588081 -336.689606) (xy 115.564918 -336.639554) (xy 115.549206 -336.586688)
			(xy 115.541272 -336.53211) (xy 115.54079 -336.504534) (xy 115.541227 -336.478032) (xy 115.548576 -336.425541)
			(xy 115.563125 -336.374573) (xy 115.584592 -336.326111) (xy 115.612563 -336.281089) (xy 115.629182 -336.26044)
			(xy 115.638623 -336.248295) (xy 115.650406 -336.219894) (xy 115.653226 -336.189276) (xy 115.646829 -336.159201)
			(xy 115.631793 -336.13238) (xy 115.609472 -336.111232) (xy 115.595908 -336.103976) (xy 115.572209 -336.091892)
			(xy 115.528229 -336.061964) (xy 115.48895 -336.026088) (xy 115.45517 -335.984993) (xy 115.440968 -335.962498)
			(xy 115.433053 -335.950267) (xy 115.41158 -335.930597) (xy 115.385424 -335.917793) (xy 115.356717 -335.912899)
			(xy 115.327796 -335.916314) (xy 115.314222 -335.921604) (xy 115.291007 -335.931079) (xy 115.242677 -335.944436)
			(xy 115.192989 -335.95117) (xy 115.167918 -335.951576) (xy 115.142849 -335.951134) (xy 115.093167 -335.944392)
			(xy 115.044832 -335.931067) (xy 115.021614 -335.921604) (xy 115.008009 -335.916436) (xy 114.979123 -335.913053)
			(xy 114.950453 -335.917945) (xy 114.924323 -335.930716) (xy 114.902849 -335.950331) (xy 114.894868 -335.962498)
			(xy 114.880299 -335.985629) (xy 114.845456 -336.02775) (xy 114.804833 -336.064329) (xy 114.759302 -336.09458)
			(xy 114.70984 -336.117856) (xy 114.657509 -336.133656) (xy 114.60343 -336.141642) (xy 114.548766 -336.141642)
			(xy 114.494687 -336.133656) (xy 114.442356 -336.117856) (xy 114.392894 -336.09458) (xy 114.347363 -336.064329)
			(xy 114.30674 -336.02775) (xy 114.271897 -335.985629) (xy 114.257328 -335.962498) (xy 114.249451 -335.95024)
			(xy 114.227967 -335.930569) (xy 114.201801 -335.917769) (xy 114.173085 -335.912883) (xy 114.144158 -335.916308)
			(xy 114.130582 -335.921604) (xy 114.107371 -335.931092) (xy 114.059039 -335.944443) (xy 114.00935 -335.951172)
			(xy 113.984278 -335.951576) (xy 113.956391 -335.951137) (xy 113.901241 -335.942822) (xy 113.847945 -335.92638)
			(xy 113.797696 -335.902178) (xy 113.751615 -335.870758) (xy 113.710731 -335.832821) (xy 113.675957 -335.789214)
			(xy 113.648071 -335.740912) (xy 113.627696 -335.688993) (xy 113.615285 -335.634618) (xy 113.611117 -335.579)
			(xy 109.204161 -335.579) (xy 109.21864 -335.628312) (xy 109.226396 -335.682262) (xy 109.226858 -335.709514)
			(xy 109.226348 -335.737087) (xy 109.218406 -335.791659) (xy 109.202691 -335.844518) (xy 109.17953 -335.894565)
			(xy 109.149404 -335.940755) (xy 109.112943 -335.982128) (xy 109.092238 -336.000344) (xy 109.081324 -336.010227)
			(xy 109.065246 -336.03488) (xy 109.056861 -336.063093) (xy 109.056864 -336.092525) (xy 109.065254 -336.120737)
			(xy 109.081336 -336.145387) (xy 109.092238 -336.155284) (xy 109.11296 -336.173483) (xy 109.149429 -336.214854)
			(xy 109.179561 -336.261046) (xy 109.202726 -336.311095) (xy 109.218443 -336.363958) (xy 109.226384 -336.418534)
			(xy 109.226383 -336.473684) (xy 109.218439 -336.52826) (xy 109.20272 -336.581122) (xy 109.179552 -336.63117)
			(xy 109.170698 -336.644742) (xy 110.153448 -336.644742) (xy 110.157519 -336.58912) (xy 110.169645 -336.534683)
			(xy 110.189568 -336.482592) (xy 110.216864 -336.433957) (xy 110.25095 -336.389814) (xy 110.291099 -336.351105)
			(xy 110.336457 -336.318654) (xy 110.386057 -336.293153) (xy 110.438841 -336.275146) (xy 110.493684 -336.265016)
			(xy 110.549418 -336.262979) (xy 110.604855 -336.269079) (xy 110.658812 -336.283185) (xy 110.710141 -336.304997)
			(xy 110.757747 -336.334051) (xy 110.800615 -336.369726) (xy 110.837832 -336.411263) (xy 110.868605 -336.457776)
			(xy 110.892277 -336.508273) (xy 110.908345 -336.56168) (xy 110.916465 -336.616856) (xy 110.916974 -336.644742)
			(xy 110.916465 -336.672628) (xy 110.908345 -336.727804) (xy 110.892277 -336.781211) (xy 110.868605 -336.831708)
			(xy 110.837832 -336.878221) (xy 110.800615 -336.919758) (xy 110.757747 -336.955433) (xy 110.710141 -336.984487)
			(xy 110.658812 -337.006299) (xy 110.604855 -337.020405) (xy 110.549418 -337.026505) (xy 110.493684 -337.024468)
			(xy 110.438841 -337.014338) (xy 110.386057 -336.996331) (xy 110.336457 -336.97083) (xy 110.291099 -336.938379)
			(xy 110.25095 -336.89967) (xy 110.216864 -336.855527) (xy 110.189568 -336.806892) (xy 110.169645 -336.754801)
			(xy 110.157519 -336.700364) (xy 110.153448 -336.644742) (xy 109.170698 -336.644742) (xy 109.149418 -336.677361)
			(xy 109.112947 -336.71873) (xy 109.092238 -336.736944) (xy 109.081324 -336.746827) (xy 109.065246 -336.77148)
			(xy 109.056861 -336.799693) (xy 109.056864 -336.829125) (xy 109.065254 -336.857337) (xy 109.081336 -336.881987)
			(xy 109.092238 -336.891884) (xy 109.112952 -336.910092) (xy 109.149421 -336.951462) (xy 109.179551 -336.997653)
			(xy 109.202716 -337.047702) (xy 109.218433 -337.100564) (xy 109.226372 -337.155139) (xy 109.226858 -337.182714)
			(xy 109.226458 -337.20997) (xy 109.218698 -337.263925) (xy 109.216141 -337.27263) (xy 109.505494 -337.27263)
			(xy 109.509565 -337.217008) (xy 109.521691 -337.162571) (xy 109.541614 -337.11048) (xy 109.56891 -337.061845)
			(xy 109.602996 -337.017702) (xy 109.643145 -336.978993) (xy 109.688503 -336.946542) (xy 109.738103 -336.921041)
			(xy 109.790887 -336.903034) (xy 109.84573 -336.892904) (xy 109.901464 -336.890867) (xy 109.956901 -336.896967)
			(xy 110.010858 -336.911073) (xy 110.062187 -336.932885) (xy 110.109793 -336.961939) (xy 110.152661 -336.997614)
			(xy 110.189878 -337.039151) (xy 110.220651 -337.085664) (xy 110.244323 -337.136161) (xy 110.260391 -337.189568)
			(xy 110.268511 -337.244744) (xy 110.26902 -337.27263) (xy 110.268511 -337.300516) (xy 110.260391 -337.355692)
			(xy 110.244323 -337.409099) (xy 110.220651 -337.459596) (xy 110.189878 -337.506109) (xy 110.152661 -337.547646)
			(xy 110.109793 -337.583321) (xy 110.062187 -337.612375) (xy 110.010858 -337.634187) (xy 109.956901 -337.648293)
			(xy 109.901464 -337.654393) (xy 109.84573 -337.652356) (xy 109.790887 -337.642226) (xy 109.738103 -337.624219)
			(xy 109.688503 -337.598718) (xy 109.643145 -337.566267) (xy 109.602996 -337.527558) (xy 109.56891 -337.483415)
			(xy 109.541614 -337.43478) (xy 109.521691 -337.382689) (xy 109.509565 -337.328252) (xy 109.505494 -337.27263)
			(xy 109.216141 -337.27263) (xy 109.203337 -337.316227) (xy 109.18069 -337.365811) (xy 109.151216 -337.411667)
			(xy 109.115515 -337.45286) (xy 109.074315 -337.488554) (xy 109.028455 -337.51802) (xy 108.978867 -337.54066)
			(xy 108.926563 -337.556011) (xy 108.872606 -337.563763) (xy 108.84535 -337.564222) (xy 108.817494 -337.563728)
			(xy 108.762378 -337.555598) (xy 108.709028 -337.539546) (xy 108.658576 -337.515915) (xy 108.612092 -337.485204)
			(xy 108.570563 -337.448066) (xy 108.534871 -337.405289) (xy 108.505771 -337.35778) (xy 108.483883 -337.306548)
			(xy 108.476288 -337.279742) (xy 108.471972 -337.26564) (xy 108.456594 -337.240496) (xy 108.434686 -337.220778)
			(xy 108.408067 -337.208123) (xy 108.378944 -337.20358) (xy 108.364274 -337.205066) (xy 108.351258 -337.206736)
			(xy 108.325073 -337.208515) (xy 108.31195 -337.208622) (xy 108.297801 -337.208523) (xy 108.269578 -337.206492)
			(xy 108.255562 -337.204558) (xy 108.24221 -337.203031) (xy 108.215527 -337.206124) (xy 108.19058 -337.216084)
			(xy 108.169103 -337.232218) (xy 108.152589 -337.253404) (xy 108.142186 -337.278169) (xy 108.139992 -337.291426)
			(xy 108.135913 -337.318581) (xy 108.120941 -337.371413) (xy 108.09855 -337.421553) (xy 108.069202 -337.467965)
			(xy 108.033504 -337.509691) (xy 107.992193 -337.545867) (xy 107.946122 -337.575748) (xy 107.896244 -337.598716)
			(xy 107.843588 -337.614295) (xy 107.789242 -337.622166) (xy 107.761786 -337.622642) (xy 107.734536 -337.622135)
			(xy 107.680591 -337.614378) (xy 107.628298 -337.599023) (xy 107.578723 -337.576382) (xy 107.532875 -337.546918)
			(xy 107.491686 -337.511229) (xy 107.455994 -337.470041) (xy 107.426527 -337.424194) (xy 107.403884 -337.37462)
			(xy 107.388526 -337.322329) (xy 107.380766 -337.268384) (xy 107.380278 -337.241134) (xy 107.380775 -337.213561)
			(xy 107.388722 -337.15899) (xy 107.404441 -337.106131) (xy 107.427606 -337.056085) (xy 107.457732 -337.009894)
			(xy 107.494194 -336.968521) (xy 107.514898 -336.950304) (xy 107.525761 -336.940371) (xy 107.541834 -336.91573)
			(xy 107.550222 -336.887532) (xy 107.550228 -336.858112) (xy 107.541853 -336.82991) (xy 107.52579 -336.805262)
			(xy 107.514898 -336.795364) (xy 107.494166 -336.777176) (xy 107.457697 -336.735802) (xy 107.427568 -336.689607)
			(xy 107.404406 -336.639555) (xy 107.388694 -336.586688) (xy 107.38076 -336.53211) (xy 107.380278 -336.504534)
			(xy 107.380717 -336.478032) (xy 107.388067 -336.425541) (xy 107.402615 -336.374573) (xy 107.424081 -336.326111)
			(xy 107.452052 -336.281089) (xy 107.46867 -336.26044) (xy 107.478115 -336.248298) (xy 107.489899 -336.219896)
			(xy 107.49272 -336.189276) (xy 107.486322 -336.1592) (xy 107.471284 -336.132379) (xy 107.448961 -336.111232)
			(xy 107.435396 -336.103976) (xy 107.411695 -336.091896) (xy 107.367716 -336.061966) (xy 107.328437 -336.026089)
			(xy 107.294658 -335.984993) (xy 107.280456 -335.962498) (xy 107.272553 -335.950259) (xy 107.251076 -335.930588)
			(xy 107.224917 -335.917786) (xy 107.196207 -335.912894) (xy 107.167285 -335.916313) (xy 107.15371 -335.921604)
			(xy 107.130496 -335.931083) (xy 107.082165 -335.944438) (xy 107.032477 -335.95117) (xy 107.007406 -335.951576)
			(xy 106.982337 -335.951138) (xy 106.932655 -335.944394) (xy 106.88432 -335.931067) (xy 106.861102 -335.921604)
			(xy 106.847502 -335.916424) (xy 106.818613 -335.913043) (xy 106.789942 -335.917938) (xy 106.763811 -335.930712)
			(xy 106.742337 -335.95033) (xy 106.734356 -335.962498) (xy 106.719787 -335.985629) (xy 106.684944 -336.02775)
			(xy 106.644321 -336.064329) (xy 106.59879 -336.09458) (xy 106.549328 -336.117856) (xy 106.496997 -336.133656)
			(xy 106.442918 -336.141642) (xy 106.388254 -336.141642) (xy 106.334175 -336.133656) (xy 106.281844 -336.117856)
			(xy 106.232382 -336.09458) (xy 106.186851 -336.064329) (xy 106.146228 -336.02775) (xy 106.111385 -335.985629)
			(xy 106.096816 -335.962498) (xy 106.088856 -335.9503) (xy 106.067395 -335.930629) (xy 106.041251 -335.917821)
			(xy 106.012555 -335.912919) (xy 105.983642 -335.916322) (xy 105.97007 -335.921604) (xy 105.946861 -335.931095)
			(xy 105.898528 -335.944446) (xy 105.848838 -335.951173) (xy 105.823766 -335.951576) (xy 105.79588 -335.951137)
			(xy 105.740731 -335.94282) (xy 105.687437 -335.926376) (xy 105.637189 -335.902174) (xy 105.591109 -335.870754)
			(xy 105.550227 -335.832817) (xy 105.515455 -335.78921) (xy 105.48757 -335.740909) (xy 105.467195 -335.688991)
			(xy 105.454785 -335.634617) (xy 105.450617 -335.579) (xy 101.043631 -335.579) (xy 101.058107 -335.62831)
			(xy 101.065861 -335.682261) (xy 101.066346 -335.709514) (xy 101.06584 -335.737087) (xy 101.057898 -335.791659)
			(xy 101.042183 -335.844519) (xy 101.01902 -335.894566) (xy 100.988894 -335.940756) (xy 100.952431 -335.982128)
			(xy 100.931726 -336.000344) (xy 100.920813 -336.010227) (xy 100.904737 -336.034881) (xy 100.896353 -336.063093)
			(xy 100.896356 -336.092525) (xy 100.904745 -336.120736) (xy 100.920825 -336.145386) (xy 100.931726 -336.155284)
			(xy 100.952444 -336.173485) (xy 100.988906 -336.214859) (xy 101.01903 -336.261052) (xy 101.04219 -336.311101)
			(xy 101.057903 -336.363962) (xy 101.065842 -336.418535) (xy 101.06584 -336.473683) (xy 101.057899 -336.528256)
			(xy 101.042184 -336.581116) (xy 101.019021 -336.631164) (xy 101.010165 -336.644742) (xy 101.992936 -336.644742)
			(xy 101.997007 -336.58912) (xy 102.009133 -336.534683) (xy 102.029056 -336.482592) (xy 102.056352 -336.433957)
			(xy 102.090438 -336.389814) (xy 102.130587 -336.351105) (xy 102.175945 -336.318654) (xy 102.225545 -336.293153)
			(xy 102.278329 -336.275146) (xy 102.333172 -336.265016) (xy 102.388906 -336.262979) (xy 102.444343 -336.269079)
			(xy 102.4983 -336.283185) (xy 102.549629 -336.304997) (xy 102.597235 -336.334051) (xy 102.640103 -336.369726)
			(xy 102.67732 -336.411263) (xy 102.708093 -336.457776) (xy 102.731765 -336.508273) (xy 102.747833 -336.56168)
			(xy 102.755953 -336.616856) (xy 102.756462 -336.644742) (xy 102.755953 -336.672628) (xy 102.747833 -336.727804)
			(xy 102.731765 -336.781211) (xy 102.708093 -336.831708) (xy 102.67732 -336.878221) (xy 102.640103 -336.919758)
			(xy 102.597235 -336.955433) (xy 102.549629 -336.984487) (xy 102.4983 -337.006299) (xy 102.444343 -337.020405)
			(xy 102.388906 -337.026505) (xy 102.333172 -337.024468) (xy 102.278329 -337.014338) (xy 102.225545 -336.996331)
			(xy 102.175945 -336.97083) (xy 102.130587 -336.938379) (xy 102.090438 -336.89967) (xy 102.056352 -336.855527)
			(xy 102.029056 -336.806892) (xy 102.009133 -336.754801) (xy 101.997007 -336.700364) (xy 101.992936 -336.644742)
			(xy 101.010165 -336.644742) (xy 100.988895 -336.677355) (xy 100.952431 -336.718728) (xy 100.931726 -336.736944)
			(xy 100.920813 -336.746827) (xy 100.904737 -336.771481) (xy 100.896353 -336.799693) (xy 100.896356 -336.829125)
			(xy 100.904745 -336.857336) (xy 100.920825 -336.881986) (xy 100.931726 -336.891884) (xy 100.952438 -336.910094)
			(xy 100.988907 -336.951464) (xy 101.019038 -336.997654) (xy 101.042204 -337.047702) (xy 101.05792 -337.100565)
			(xy 101.06586 -337.155139) (xy 101.066346 -337.182714) (xy 101.065835 -337.209964) (xy 101.063837 -337.223862)
			(xy 101.236524 -337.223862) (xy 101.240595 -337.16824) (xy 101.252721 -337.113803) (xy 101.272644 -337.061712)
			(xy 101.29994 -337.013077) (xy 101.334026 -336.968934) (xy 101.374175 -336.930225) (xy 101.419533 -336.897774)
			(xy 101.469133 -336.872273) (xy 101.521917 -336.854266) (xy 101.57676 -336.844136) (xy 101.632494 -336.842099)
			(xy 101.687931 -336.848199) (xy 101.741888 -336.862305) (xy 101.793217 -336.884117) (xy 101.840823 -336.913171)
			(xy 101.883691 -336.948846) (xy 101.920908 -336.990383) (xy 101.951681 -337.036896) (xy 101.975353 -337.087393)
			(xy 101.991421 -337.1408) (xy 101.999541 -337.195976) (xy 102.00005 -337.223862) (xy 101.999541 -337.251748)
			(xy 101.991421 -337.306924) (xy 101.975353 -337.360331) (xy 101.951681 -337.410828) (xy 101.920908 -337.457341)
			(xy 101.883691 -337.498878) (xy 101.840823 -337.534553) (xy 101.793217 -337.563607) (xy 101.741888 -337.585419)
			(xy 101.687931 -337.599525) (xy 101.632494 -337.605625) (xy 101.57676 -337.603588) (xy 101.521917 -337.593458)
			(xy 101.469133 -337.575451) (xy 101.419533 -337.54995) (xy 101.374175 -337.517499) (xy 101.334026 -337.47879)
			(xy 101.29994 -337.434647) (xy 101.272644 -337.386012) (xy 101.252721 -337.333921) (xy 101.240595 -337.279484)
			(xy 101.236524 -337.223862) (xy 101.063837 -337.223862) (xy 101.058078 -337.263909) (xy 101.042723 -337.316201)
			(xy 101.020083 -337.365775) (xy 100.990619 -337.411624) (xy 100.95493 -337.452813) (xy 100.913743 -337.488504)
			(xy 100.867897 -337.517971) (xy 100.818323 -337.540615) (xy 100.766032 -337.555973) (xy 100.712088 -337.563734)
			(xy 100.684838 -337.564222) (xy 100.656985 -337.563648) (xy 100.601872 -337.555531) (xy 100.548524 -337.539491)
			(xy 100.498072 -337.515871) (xy 100.451588 -337.48517) (xy 100.410058 -337.448041) (xy 100.374364 -337.405272)
			(xy 100.345263 -337.357771) (xy 100.323372 -337.306545) (xy 100.315776 -337.279742) (xy 100.311472 -337.265636)
			(xy 100.296091 -337.24049) (xy 100.274181 -337.220772) (xy 100.247558 -337.208119) (xy 100.218433 -337.203579)
			(xy 100.203762 -337.205066) (xy 100.190746 -337.206737) (xy 100.164561 -337.208516) (xy 100.151438 -337.208622)
			(xy 100.137289 -337.208524) (xy 100.109066 -337.206493) (xy 100.09505 -337.204558) (xy 100.081699 -337.203018)
			(xy 100.055015 -337.206115) (xy 100.030067 -337.216077) (xy 100.00859 -337.232213) (xy 99.992076 -337.253401)
			(xy 99.981673 -337.278168) (xy 99.97948 -337.291426) (xy 99.975413 -337.318584) (xy 99.96044 -337.371416)
			(xy 99.938048 -337.421557) (xy 99.908699 -337.46797) (xy 99.873 -337.509695) (xy 99.831687 -337.545872)
			(xy 99.785615 -337.575752) (xy 99.735735 -337.598719) (xy 99.683078 -337.614298) (xy 99.628731 -337.622166)
			(xy 99.601274 -337.622642) (xy 99.574024 -337.622146) (xy 99.520078 -337.614387) (xy 99.467786 -337.599031)
			(xy 99.418211 -337.576389) (xy 99.372362 -337.546923) (xy 99.331173 -337.511233) (xy 99.295482 -337.470045)
			(xy 99.266015 -337.424197) (xy 99.243372 -337.374622) (xy 99.228014 -337.32233) (xy 99.220254 -337.268384)
			(xy 99.219766 -337.241134) (xy 99.220232 -337.213559) (xy 99.228181 -337.158985) (xy 99.243905 -337.106124)
			(xy 99.267075 -337.056078) (xy 99.297208 -337.009889) (xy 99.333678 -336.968519) (xy 99.354386 -336.950304)
			(xy 99.36525 -336.940371) (xy 99.381326 -336.915731) (xy 99.389714 -336.887532) (xy 99.389721 -336.858112)
			(xy 99.381344 -336.829909) (xy 99.365279 -336.805262) (xy 99.354386 -336.795364) (xy 99.333651 -336.777178)
			(xy 99.297184 -336.735804) (xy 99.267055 -336.689609) (xy 99.243893 -336.639556) (xy 99.228182 -336.586689)
			(xy 99.220248 -336.53211) (xy 99.219766 -336.504534) (xy 99.220208 -336.478033) (xy 99.227557 -336.425541)
			(xy 99.242105 -336.374574) (xy 99.26357 -336.326112) (xy 99.29154 -336.281089) (xy 99.308158 -336.26044)
			(xy 99.317607 -336.2483) (xy 99.329393 -336.219898) (xy 99.332214 -336.189277) (xy 99.325816 -336.159199)
			(xy 99.310776 -336.132377) (xy 99.28845 -336.111231) (xy 99.274884 -336.103976) (xy 99.251197 -336.091869)
			(xy 99.207215 -336.061949) (xy 99.167932 -336.026079) (xy 99.134148 -335.98499) (xy 99.119944 -335.962498)
			(xy 99.112052 -335.950251) (xy 99.090572 -335.93058) (xy 99.06441 -335.917779) (xy 99.035698 -335.912889)
			(xy 99.006773 -335.916311) (xy 98.993198 -335.921604) (xy 98.969986 -335.931087) (xy 98.921654 -335.94444)
			(xy 98.871965 -335.951171) (xy 98.846894 -335.951576) (xy 98.821825 -335.951142) (xy 98.772142 -335.944396)
			(xy 98.723808 -335.931068) (xy 98.70059 -335.921604) (xy 98.686994 -335.916411) (xy 98.658103 -335.913032)
			(xy 98.62943 -335.91793) (xy 98.603298 -335.930707) (xy 98.581825 -335.950328) (xy 98.573844 -335.962498)
			(xy 98.559275 -335.985629) (xy 98.524432 -336.02775) (xy 98.483809 -336.064329) (xy 98.438278 -336.09458)
			(xy 98.388816 -336.117856) (xy 98.336485 -336.133656) (xy 98.282406 -336.141642) (xy 98.227742 -336.141642)
			(xy 98.173663 -336.133656) (xy 98.121332 -336.117856) (xy 98.07187 -336.09458) (xy 98.026339 -336.064329)
			(xy 97.985716 -336.02775) (xy 97.950873 -335.985629) (xy 97.936304 -335.962498) (xy 97.928355 -335.950292)
			(xy 97.906891 -335.930621) (xy 97.880744 -335.917814) (xy 97.852045 -335.912914) (xy 97.823131 -335.91632)
			(xy 97.809558 -335.921604) (xy 97.78635 -335.931099) (xy 97.738016 -335.944448) (xy 97.688326 -335.951174)
			(xy 97.663254 -335.951576) (xy 97.635368 -335.951136) (xy 97.580221 -335.942817) (xy 97.526928 -335.926373)
			(xy 97.476682 -335.90217) (xy 97.430604 -335.870749) (xy 97.389723 -335.832812) (xy 97.354952 -335.789207)
			(xy 97.327068 -335.740906) (xy 97.306694 -335.688989) (xy 97.294285 -335.634616) (xy 97.290117 -335.579)
			(xy 76.426568 -335.579) (xy 76.426568 -336.644742) (xy 93.832424 -336.644742) (xy 93.836495 -336.58912)
			(xy 93.848621 -336.534683) (xy 93.868544 -336.482592) (xy 93.89584 -336.433957) (xy 93.929926 -336.389814)
			(xy 93.970075 -336.351105) (xy 94.015433 -336.318654) (xy 94.065033 -336.293153) (xy 94.117817 -336.275146)
			(xy 94.17266 -336.265016) (xy 94.228394 -336.262979) (xy 94.283831 -336.269079) (xy 94.337788 -336.283185)
			(xy 94.389117 -336.304997) (xy 94.436723 -336.334051) (xy 94.479591 -336.369726) (xy 94.516808 -336.411263)
			(xy 94.547581 -336.457776) (xy 94.571253 -336.508273) (xy 94.587321 -336.56168) (xy 94.595441 -336.616856)
			(xy 94.59595 -336.644742) (xy 94.595441 -336.672628) (xy 94.587321 -336.727804) (xy 94.571253 -336.781211)
			(xy 94.547581 -336.831708) (xy 94.516808 -336.878221) (xy 94.479591 -336.919758) (xy 94.436723 -336.955433)
			(xy 94.389117 -336.984487) (xy 94.337788 -337.006299) (xy 94.283831 -337.020405) (xy 94.228394 -337.026505)
			(xy 94.17266 -337.024468) (xy 94.117817 -337.014338) (xy 94.065033 -336.996331) (xy 94.015433 -336.97083)
			(xy 93.970075 -336.938379) (xy 93.929926 -336.89967) (xy 93.89584 -336.855527) (xy 93.868544 -336.806892)
			(xy 93.848621 -336.754801) (xy 93.836495 -336.700364) (xy 93.832424 -336.644742) (xy 76.426568 -336.644742)
			(xy 76.426568 -337.352894) (xy 93.189296 -337.352894) (xy 93.193367 -337.297272) (xy 93.205493 -337.242835)
			(xy 93.225416 -337.190744) (xy 93.252712 -337.142109) (xy 93.286798 -337.097966) (xy 93.326947 -337.059257)
			(xy 93.372305 -337.026806) (xy 93.421905 -337.001305) (xy 93.474689 -336.983298) (xy 93.529532 -336.973168)
			(xy 93.585266 -336.971131) (xy 93.640703 -336.977231) (xy 93.69466 -336.991337) (xy 93.745989 -337.013149)
			(xy 93.793595 -337.042203) (xy 93.836463 -337.077878) (xy 93.87368 -337.119415) (xy 93.904453 -337.165928)
			(xy 93.928125 -337.216425) (xy 93.944193 -337.269832) (xy 93.952313 -337.325008) (xy 93.952822 -337.352894)
			(xy 93.952313 -337.38078) (xy 93.944193 -337.435956) (xy 93.928125 -337.489363) (xy 93.904453 -337.53986)
			(xy 93.87368 -337.586373) (xy 93.836463 -337.62791) (xy 93.793595 -337.663585) (xy 93.745989 -337.692639)
			(xy 93.69466 -337.714451) (xy 93.640703 -337.728557) (xy 93.585266 -337.734657) (xy 93.529532 -337.73262)
			(xy 93.474689 -337.72249) (xy 93.421905 -337.704483) (xy 93.372305 -337.678982) (xy 93.326947 -337.646531)
			(xy 93.286798 -337.607822) (xy 93.252712 -337.563679) (xy 93.225416 -337.515044) (xy 93.205493 -337.462953)
			(xy 93.193367 -337.408516) (xy 93.189296 -337.352894) (xy 76.426568 -337.352894) (xy 76.426568 -338.671662)
			(xy 84.701634 -338.671662) (xy 84.70209 -338.644953) (xy 84.709554 -338.592057) (xy 84.724317 -338.540718)
			(xy 84.746092 -338.491938) (xy 84.774452 -338.446669) (xy 84.808845 -338.405794) (xy 84.848599 -338.370111)
			(xy 84.892938 -338.340318) (xy 84.916772 -338.328254) (xy 84.929938 -338.321345) (xy 84.951847 -338.301262)
			(xy 84.967048 -338.275722) (xy 84.974254 -338.246888) (xy 84.972856 -338.2172) (xy 84.962971 -338.189171)
			(xy 84.954618 -338.17687) (xy 84.937282 -338.152202) (xy 84.909765 -338.098558) (xy 84.891027 -338.041254)
			(xy 84.881534 -337.981717) (xy 84.880958 -337.951572) (xy 84.881444 -337.924321) (xy 84.8892 -337.870373)
			(xy 84.904555 -337.818078) (xy 84.927197 -337.768501) (xy 84.956663 -337.722651) (xy 84.992354 -337.68146)
			(xy 85.033545 -337.645769) (xy 85.079395 -337.616303) (xy 85.128972 -337.593661) (xy 85.181267 -337.578306)
			(xy 85.235215 -337.57055) (xy 85.289717 -337.57055) (xy 85.343665 -337.578306) (xy 85.39596 -337.593661)
			(xy 85.445537 -337.616303) (xy 85.491387 -337.645769) (xy 85.532578 -337.68146) (xy 85.568269 -337.722651)
			(xy 85.597735 -337.768501) (xy 85.620377 -337.818078) (xy 85.635732 -337.870373) (xy 85.643488 -337.924321)
			(xy 85.643974 -337.951572) (xy 85.643543 -337.978282) (xy 85.636074 -338.031178) (xy 85.621306 -338.082518)
			(xy 85.599528 -338.131298) (xy 85.571165 -338.176567) (xy 85.536769 -338.217441) (xy 85.513487 -338.238338)
			(xy 94.63913 -338.238338) (xy 94.639701 -338.20865) (xy 94.648894 -338.149991) (xy 94.667066 -338.093465)
			(xy 94.693776 -338.040437) (xy 94.72838 -337.992188) (xy 94.770042 -337.949884) (xy 94.793562 -337.93176)
			(xy 94.804147 -337.923306) (xy 94.820861 -337.902002) (xy 94.831386 -337.877054) (xy 94.834982 -337.850216)
			(xy 94.831395 -337.823376) (xy 94.820877 -337.798425) (xy 94.80417 -337.777116) (xy 94.793562 -337.768692)
			(xy 94.77004 -337.750571) (xy 94.728382 -337.708263) (xy 94.69378 -337.660013) (xy 94.667069 -337.606985)
			(xy 94.648895 -337.55046) (xy 94.639696 -337.491801) (xy 94.63913 -337.462114) (xy 94.639616 -337.434863)
			(xy 94.647372 -337.380915) (xy 94.662727 -337.32862) (xy 94.685369 -337.279043) (xy 94.714835 -337.233193)
			(xy 94.750526 -337.192002) (xy 94.791717 -337.156311) (xy 94.837567 -337.126845) (xy 94.887144 -337.104203)
			(xy 94.939439 -337.088848) (xy 94.993387 -337.081092) (xy 95.047889 -337.081092) (xy 95.101837 -337.088848)
			(xy 95.154132 -337.104203) (xy 95.203709 -337.126845) (xy 95.249559 -337.156311) (xy 95.29075 -337.192002)
			(xy 95.326441 -337.233193) (xy 95.355907 -337.279043) (xy 95.378549 -337.32862) (xy 95.393904 -337.380915)
			(xy 95.40166 -337.434863) (xy 95.402146 -337.462114) (xy 95.401623 -337.491804) (xy 95.39242 -337.550465)
			(xy 95.37424 -337.606993) (xy 95.347521 -337.66002) (xy 95.335442 -337.676857) (xy 95.655521 -337.676857)
			(xy 95.655521 -337.622343) (xy 95.66328 -337.568384) (xy 95.678639 -337.516078) (xy 95.701286 -337.466491)
			(xy 95.730761 -337.420632) (xy 95.766462 -337.379435) (xy 95.807662 -337.343738) (xy 95.853524 -337.314268)
			(xy 95.903114 -337.291626) (xy 95.955421 -337.276272) (xy 96.009381 -337.268518) (xy 96.036638 -337.268058)
			(xy 96.061874 -337.268444) (xy 96.111908 -337.275066) (xy 96.160628 -337.288243) (xy 96.20718 -337.307742)
			(xy 96.22917 -337.320128) (xy 96.24216 -337.327118) (xy 96.270787 -337.334163) (xy 96.300234 -337.332729)
			(xy 96.328041 -337.322936) (xy 96.351888 -337.305602) (xy 96.369784 -337.282173) (xy 96.375474 -337.268566)
			(xy 96.386157 -337.241784) (xy 96.414448 -337.191543) (xy 96.44998 -337.146135) (xy 96.491944 -337.106593)
			(xy 96.539383 -337.07382) (xy 96.591215 -337.048563) (xy 96.64626 -337.031398) (xy 96.703261 -337.022716)
			(xy 96.73209 -337.022186) (xy 96.759342 -337.022665) (xy 96.813292 -337.03042) (xy 96.86559 -337.045775)
			(xy 96.915169 -337.068415) (xy 96.961022 -337.097882) (xy 97.002215 -337.133574) (xy 97.037909 -337.174765)
			(xy 97.067377 -337.220617) (xy 97.09002 -337.270195) (xy 97.105377 -337.322492) (xy 97.113134 -337.376442)
			(xy 97.113598 -337.403694) (xy 97.113073 -337.433599) (xy 97.103754 -337.492678) (xy 97.095056 -337.521296)
			(xy 97.091124 -337.53523) (xy 97.090201 -337.564145) (xy 97.097449 -337.592153) (xy 97.112281 -337.616992)
			(xy 97.1335 -337.636657) (xy 97.159394 -337.64956) (xy 97.173542 -337.652614) (xy 97.199616 -337.657777)
			(xy 97.25012 -337.674349) (xy 97.297832 -337.697774) (xy 97.34183 -337.727597) (xy 97.38126 -337.763241)
			(xy 97.415359 -337.804014) (xy 97.443465 -337.849128) (xy 97.465035 -337.897707) (xy 97.47965 -337.948811)
			(xy 97.487027 -338.00145) (xy 97.487486 -338.028026) (xy 97.487 -338.055277) (xy 97.479244 -338.109225)
			(xy 97.463889 -338.16152) (xy 97.441247 -338.211097) (xy 97.42374 -338.238338) (xy 102.799642 -338.238338)
			(xy 102.800208 -338.20865) (xy 102.809402 -338.149991) (xy 102.827574 -338.093464) (xy 102.854285 -338.040436)
			(xy 102.88889 -337.992187) (xy 102.930553 -337.949883) (xy 102.954074 -337.93176) (xy 102.964658 -337.923305)
			(xy 102.98137 -337.902001) (xy 102.991894 -337.877053) (xy 102.995489 -337.850216) (xy 102.991902 -337.823377)
			(xy 102.981386 -337.798426) (xy 102.964681 -337.777116) (xy 102.954074 -337.768692) (xy 102.930554 -337.750568)
			(xy 102.888895 -337.708261) (xy 102.854293 -337.660011) (xy 102.827582 -337.606984) (xy 102.809407 -337.550459)
			(xy 102.800208 -337.491801) (xy 102.799642 -337.462114) (xy 102.800128 -337.434863) (xy 102.807884 -337.380915)
			(xy 102.823239 -337.32862) (xy 102.845881 -337.279043) (xy 102.875347 -337.233193) (xy 102.911038 -337.192002)
			(xy 102.952229 -337.156311) (xy 102.998079 -337.126845) (xy 103.047656 -337.104203) (xy 103.099951 -337.088848)
			(xy 103.153899 -337.081092) (xy 103.208401 -337.081092) (xy 103.262349 -337.088848) (xy 103.314644 -337.104203)
			(xy 103.364221 -337.126845) (xy 103.410071 -337.156311) (xy 103.451262 -337.192002) (xy 103.486953 -337.233193)
			(xy 103.516419 -337.279043) (xy 103.539061 -337.32862) (xy 103.554416 -337.380915) (xy 103.562172 -337.434863)
			(xy 103.562658 -337.462114) (xy 103.56213 -337.491803) (xy 103.552928 -337.550464) (xy 103.534748 -337.606992)
			(xy 103.50803 -337.660019) (xy 103.495955 -337.676851) (xy 103.816144 -337.676851) (xy 103.816144 -337.622349)
			(xy 103.8239 -337.5684) (xy 103.839254 -337.516105) (xy 103.861893 -337.466527) (xy 103.891357 -337.420675)
			(xy 103.927047 -337.379482) (xy 103.968235 -337.343787) (xy 104.014083 -337.314317) (xy 104.063658 -337.291671)
			(xy 104.115952 -337.27631) (xy 104.169899 -337.268547) (xy 104.19715 -337.268058) (xy 104.222386 -337.268439)
			(xy 104.27242 -337.275063) (xy 104.32114 -337.288241) (xy 104.367692 -337.307741) (xy 104.389682 -337.320128)
			(xy 104.402665 -337.327132) (xy 104.431295 -337.334175) (xy 104.460744 -337.332738) (xy 104.488552 -337.322943)
			(xy 104.5124 -337.305606) (xy 104.530296 -337.282174) (xy 104.535986 -337.268566) (xy 104.546659 -337.24178)
			(xy 104.574951 -337.191539) (xy 104.610485 -337.14613) (xy 104.65245 -337.106588) (xy 104.699891 -337.073816)
			(xy 104.751724 -337.04856) (xy 104.80677 -337.031396) (xy 104.863772 -337.022715) (xy 104.892602 -337.022186)
			(xy 104.919853 -337.022676) (xy 104.9738 -337.030433) (xy 105.026095 -337.045788) (xy 105.075671 -337.068429)
			(xy 105.121522 -337.097894) (xy 105.162712 -337.133586) (xy 105.198403 -337.174775) (xy 105.22787 -337.220625)
			(xy 105.250511 -337.270202) (xy 105.265867 -337.322496) (xy 105.273624 -337.376443) (xy 105.27411 -337.403694)
			(xy 105.273584 -337.433599) (xy 105.264265 -337.492678) (xy 105.255568 -337.521296) (xy 105.251626 -337.535228)
			(xy 105.250703 -337.564145) (xy 105.257952 -337.592155) (xy 105.272786 -337.616995) (xy 105.294008 -337.63666)
			(xy 105.319904 -337.649562) (xy 105.334054 -337.652614) (xy 105.36013 -337.657768) (xy 105.410633 -337.674342)
			(xy 105.458346 -337.697768) (xy 105.502343 -337.727592) (xy 105.541773 -337.763237) (xy 105.575872 -337.804012)
			(xy 105.603978 -337.849126) (xy 105.625547 -337.897706) (xy 105.640162 -337.948811) (xy 105.647539 -338.001449)
			(xy 105.647998 -338.028026) (xy 105.647512 -338.055277) (xy 105.639756 -338.109225) (xy 105.624401 -338.16152)
			(xy 105.601759 -338.211097) (xy 105.584252 -338.238338) (xy 110.960154 -338.238338) (xy 110.960715 -338.20865)
			(xy 110.969909 -338.14999) (xy 110.988082 -338.093463) (xy 111.014794 -338.040435) (xy 111.0494 -337.992187)
			(xy 111.091064 -337.949883) (xy 111.114586 -337.93176) (xy 111.125169 -337.923305) (xy 111.141879 -337.902)
			(xy 111.152402 -337.877052) (xy 111.155996 -337.850216) (xy 111.15241 -337.823378) (xy 111.141895 -337.798427)
			(xy 111.125192 -337.777117) (xy 111.114586 -337.768692) (xy 111.091069 -337.750565) (xy 111.049409 -337.708259)
			(xy 111.014806 -337.66001) (xy 110.988095 -337.606983) (xy 110.96992 -337.550459) (xy 110.96072 -337.491801)
			(xy 110.960154 -337.462114) (xy 110.96064 -337.434863) (xy 110.968396 -337.380915) (xy 110.983751 -337.32862)
			(xy 111.006393 -337.279043) (xy 111.035859 -337.233193) (xy 111.07155 -337.192002) (xy 111.112741 -337.156311)
			(xy 111.158591 -337.126845) (xy 111.208168 -337.104203) (xy 111.260463 -337.088848) (xy 111.314411 -337.081092)
			(xy 111.368913 -337.081092) (xy 111.422861 -337.088848) (xy 111.475156 -337.104203) (xy 111.524733 -337.126845)
			(xy 111.570583 -337.156311) (xy 111.611774 -337.192002) (xy 111.647465 -337.233193) (xy 111.676931 -337.279043)
			(xy 111.699573 -337.32862) (xy 111.714928 -337.380915) (xy 111.722684 -337.434863) (xy 111.72317 -337.462114)
			(xy 111.722637 -337.491803) (xy 111.713435 -337.550464) (xy 111.695256 -337.606991) (xy 111.668539 -337.660018)
			(xy 111.656463 -337.676852) (xy 111.976644 -337.676852) (xy 111.976644 -337.622348) (xy 111.9844 -337.568399)
			(xy 111.999755 -337.516102) (xy 112.022395 -337.466523) (xy 112.05186 -337.420671) (xy 112.087551 -337.379478)
			(xy 112.12874 -337.343783) (xy 112.17459 -337.314313) (xy 112.224167 -337.291668) (xy 112.276462 -337.276308)
			(xy 112.33041 -337.268546) (xy 112.357662 -337.268058) (xy 112.382898 -337.268433) (xy 112.432933 -337.275059)
			(xy 112.481653 -337.288238) (xy 112.528204 -337.307741) (xy 112.550194 -337.320128) (xy 112.56317 -337.327146)
			(xy 112.591803 -337.334187) (xy 112.621253 -337.332748) (xy 112.649064 -337.322949) (xy 112.672912 -337.30561)
			(xy 112.690808 -337.282176) (xy 112.696498 -337.268566) (xy 112.707161 -337.241776) (xy 112.735454 -337.191534)
			(xy 112.770989 -337.146125) (xy 112.812956 -337.106583) (xy 112.860398 -337.073812) (xy 112.912233 -337.048556)
			(xy 112.96728 -337.031393) (xy 113.024284 -337.022714) (xy 113.053114 -337.022186) (xy 113.080365 -337.022665)
			(xy 113.134313 -337.030423) (xy 113.186608 -337.04578) (xy 113.236184 -337.068422) (xy 113.282034 -337.097889)
			(xy 113.323224 -337.133581) (xy 113.358916 -337.174772) (xy 113.388382 -337.220623) (xy 113.411023 -337.2702)
			(xy 113.426379 -337.322495) (xy 113.434136 -337.376443) (xy 113.434622 -337.403694) (xy 113.434096 -337.433599)
			(xy 113.424777 -337.492678) (xy 113.41608 -337.521296) (xy 113.412129 -337.535225) (xy 113.411206 -337.564145)
			(xy 113.418455 -337.592157) (xy 113.433291 -337.616998) (xy 113.454516 -337.636663) (xy 113.480415 -337.649563)
			(xy 113.494566 -337.652614) (xy 113.520644 -337.657759) (xy 113.571147 -337.674334) (xy 113.61886 -337.697762)
			(xy 113.662857 -337.727588) (xy 113.702286 -337.763233) (xy 113.736384 -337.804009) (xy 113.76449 -337.849124)
			(xy 113.78606 -337.897705) (xy 113.800674 -337.94881) (xy 113.808051 -338.001449) (xy 113.80851 -338.028026)
			(xy 113.808024 -338.055277) (xy 113.800268 -338.109225) (xy 113.784913 -338.16152) (xy 113.762271 -338.211097)
			(xy 113.744764 -338.238338) (xy 119.120666 -338.238338) (xy 119.121223 -338.20865) (xy 119.130417 -338.149989)
			(xy 119.148591 -338.093463) (xy 119.175304 -338.040434) (xy 119.209911 -337.992186) (xy 119.251576 -337.949883)
			(xy 119.275098 -337.93176) (xy 119.28568 -337.923304) (xy 119.302388 -337.901999) (xy 119.312909 -337.877051)
			(xy 119.316503 -337.850216) (xy 119.312918 -337.823379) (xy 119.302404 -337.798428) (xy 119.285703 -337.777118)
			(xy 119.275098 -337.768692) (xy 119.251583 -337.750562) (xy 119.209923 -337.708256) (xy 119.175319 -337.660008)
			(xy 119.148607 -337.606982) (xy 119.130432 -337.550458) (xy 119.121232 -337.491801) (xy 119.120666 -337.462114)
			(xy 119.121152 -337.434863) (xy 119.128908 -337.380915) (xy 119.144263 -337.32862) (xy 119.166905 -337.279043)
			(xy 119.196371 -337.233193) (xy 119.232062 -337.192002) (xy 119.273253 -337.156311) (xy 119.319103 -337.126845)
			(xy 119.36868 -337.104203) (xy 119.420975 -337.088848) (xy 119.474923 -337.081092) (xy 119.529425 -337.081092)
			(xy 119.583373 -337.088848) (xy 119.635668 -337.104203) (xy 119.685245 -337.126845) (xy 119.731095 -337.156311)
			(xy 119.772286 -337.192002) (xy 119.807977 -337.233193) (xy 119.837443 -337.279043) (xy 119.860085 -337.32862)
			(xy 119.87544 -337.380915) (xy 119.883196 -337.434863) (xy 119.883682 -337.462114) (xy 119.883144 -337.491803)
			(xy 119.873943 -337.550463) (xy 119.855765 -337.60699) (xy 119.829048 -337.660017) (xy 119.816972 -337.676852)
			(xy 120.137144 -337.676852) (xy 120.137144 -337.622348) (xy 120.1449 -337.568397) (xy 120.160255 -337.5161)
			(xy 120.182897 -337.46652) (xy 120.212363 -337.420667) (xy 120.248055 -337.379474) (xy 120.289246 -337.343779)
			(xy 120.335097 -337.314309) (xy 120.384676 -337.291665) (xy 120.436972 -337.276306) (xy 120.490922 -337.268546)
			(xy 120.518174 -337.268058) (xy 120.54341 -337.268428) (xy 120.593445 -337.275055) (xy 120.642165 -337.288236)
			(xy 120.688716 -337.30774) (xy 120.710706 -337.320128) (xy 120.723675 -337.32716) (xy 120.75231 -337.334199)
			(xy 120.781763 -337.332757) (xy 120.809575 -337.322956) (xy 120.833424 -337.305614) (xy 120.85132 -337.282177)
			(xy 120.85701 -337.268566) (xy 120.867663 -337.241771) (xy 120.895957 -337.191529) (xy 120.931494 -337.14612)
			(xy 120.973462 -337.106579) (xy 121.020905 -337.073807) (xy 121.072742 -337.048553) (xy 121.127791 -337.031391)
			(xy 121.184795 -337.022713) (xy 121.213626 -337.022186) (xy 121.240878 -337.022654) (xy 121.294826 -337.030413)
			(xy 121.34712 -337.045772) (xy 121.396697 -337.068415) (xy 121.442547 -337.097884) (xy 121.483737 -337.133577)
			(xy 121.519428 -337.174769) (xy 121.548894 -337.22062) (xy 121.571535 -337.270198) (xy 121.586891 -337.322494)
			(xy 121.594648 -337.376442) (xy 121.595134 -337.403694) (xy 121.594607 -337.433599) (xy 121.586865 -337.482688)
			(xy 123.707398 -337.482688) (xy 123.707925 -337.455116) (xy 123.715865 -337.400546) (xy 123.731578 -337.347687)
			(xy 123.754737 -337.297641) (xy 123.784858 -337.251449) (xy 123.821316 -337.210076) (xy 123.842018 -337.191858)
			(xy 123.852925 -337.18197) (xy 123.868994 -337.157316) (xy 123.877374 -337.129106) (xy 123.877372 -337.099678)
			(xy 123.868987 -337.071469) (xy 123.852915 -337.046818) (xy 123.842018 -337.036918) (xy 123.821316 -337.018697)
			(xy 123.784844 -336.977331) (xy 123.75471 -336.931143) (xy 123.731543 -336.881097) (xy 123.715825 -336.828236)
			(xy 123.707884 -336.773662) (xy 123.707398 -336.746088) (xy 123.707867 -336.718836) (xy 123.715625 -336.664888)
			(xy 123.730982 -336.612592) (xy 123.753625 -336.563014) (xy 123.783093 -336.517164) (xy 123.818786 -336.475974)
			(xy 123.859978 -336.440282) (xy 123.90583 -336.410816) (xy 123.955409 -336.388176) (xy 124.007705 -336.372821)
			(xy 124.061654 -336.365065) (xy 124.088906 -336.36458) (xy 124.101067 -336.364674) (xy 124.125343 -336.366197)
			(xy 124.13742 -336.367628) (xy 124.151183 -336.36885) (xy 124.178509 -336.364881) (xy 124.203774 -336.353739)
			(xy 124.225132 -336.336237) (xy 124.241022 -336.313655) (xy 124.250284 -336.287641) (xy 124.25172 -336.273902)
			(xy 124.254288 -336.245371) (xy 124.26677 -336.189468) (xy 124.287472 -336.136059) (xy 124.315929 -336.086348)
			(xy 124.351502 -336.041452) (xy 124.393389 -336.002382) (xy 124.440649 -335.970016) (xy 124.492218 -335.945083)
			(xy 124.546936 -335.928143) (xy 124.603572 -335.919578) (xy 124.632212 -335.919064) (xy 124.650231 -335.919288)
			(xy 124.686106 -335.92272) (xy 124.70384 -335.925922) (xy 124.719042 -335.928328) (xy 124.749605 -335.924788)
			(xy 124.77773 -335.912312) (xy 124.800866 -335.89203) (xy 124.816917 -335.865781) (xy 124.821188 -335.850992)
			(xy 124.828636 -335.823962) (xy 124.850258 -335.772237) (xy 124.879215 -335.724232) (xy 124.914884 -335.68098)
			(xy 124.956497 -335.643411) (xy 125.003158 -335.612335) (xy 125.053864 -335.588419) (xy 125.107523 -335.57218)
			(xy 125.162981 -335.563965) (xy 125.191012 -335.563464) (xy 125.218262 -335.563967) (xy 125.272208 -335.571724)
			(xy 125.324501 -335.587079) (xy 125.374076 -335.60972) (xy 125.419925 -335.639185) (xy 125.461114 -335.674874)
			(xy 125.496806 -335.716062) (xy 125.526273 -335.76191) (xy 125.548915 -335.811484) (xy 125.564273 -335.863776)
			(xy 125.572032 -335.917722) (xy 125.57252 -335.944972) (xy 125.572028 -335.972546) (xy 125.56408 -336.027117)
			(xy 125.54836 -336.079976) (xy 125.525194 -336.130022) (xy 125.495067 -336.176212) (xy 125.458605 -336.217585)
			(xy 125.4379 -336.235802) (xy 125.427031 -336.245729) (xy 125.410958 -336.270371) (xy 125.402572 -336.298572)
			(xy 125.402566 -336.327992) (xy 125.410943 -336.356195) (xy 125.427007 -336.380843) (xy 125.4379 -336.390742)
			(xy 125.458577 -336.408988) (xy 125.495041 -336.450356) (xy 125.525168 -336.496542) (xy 125.548331 -336.546585)
			(xy 125.564048 -336.599441) (xy 125.57199 -336.65401) (xy 125.571993 -336.709154) (xy 125.564056 -336.763723)
			(xy 125.548344 -336.816581) (xy 125.525186 -336.866626) (xy 125.495063 -336.912816) (xy 125.458603 -336.954186)
			(xy 125.4379 -336.972402) (xy 125.427031 -336.982329) (xy 125.410958 -337.006971) (xy 125.402572 -337.035172)
			(xy 125.402566 -337.064592) (xy 125.410943 -337.092795) (xy 125.427007 -337.117443) (xy 125.4379 -337.127342)
			(xy 125.458586 -337.14558) (xy 125.495059 -337.186943) (xy 125.525194 -337.233127) (xy 125.548364 -337.28317)
			(xy 125.564086 -337.336028) (xy 125.572031 -337.390599) (xy 125.57252 -337.418172) (xy 125.572019 -337.445424)
			(xy 125.564266 -337.499373) (xy 125.548914 -337.551669) (xy 125.526276 -337.601248) (xy 125.496812 -337.647101)
			(xy 125.461122 -337.688294) (xy 125.419933 -337.723988) (xy 125.374083 -337.753456) (xy 125.324506 -337.7761)
			(xy 125.272212 -337.791457) (xy 125.218264 -337.799216) (xy 125.191012 -337.79968) (xy 125.163156 -337.799161)
			(xy 125.10804 -337.791038) (xy 125.054689 -337.774993) (xy 125.004235 -337.751367) (xy 124.95775 -337.720659)
			(xy 124.916221 -337.683523) (xy 124.880528 -337.640747) (xy 124.85143 -337.593238) (xy 124.829543 -337.542006)
			(xy 124.82195 -337.5152) (xy 124.817696 -337.501077) (xy 124.802301 -337.475931) (xy 124.780378 -337.456216)
			(xy 124.753745 -337.443567) (xy 124.724611 -337.439033) (xy 124.709936 -337.440524) (xy 124.69692 -337.442198)
			(xy 124.670735 -337.443975) (xy 124.657612 -337.44408) (xy 124.639981 -337.443844) (xy 124.604873 -337.440538)
			(xy 124.587508 -337.437476) (xy 124.573734 -337.435253) (xy 124.545948 -337.437699) (xy 124.519864 -337.447584)
			(xy 124.497434 -337.464166) (xy 124.480337 -337.486207) (xy 124.469852 -337.512055) (xy 124.467874 -337.525868)
			(xy 124.464232 -337.553444) (xy 124.450001 -337.607215) (xy 124.428107 -337.658348) (xy 124.399017 -337.705757)
			(xy 124.363347 -337.748436) (xy 124.321855 -337.78548) (xy 124.27542 -337.816102) (xy 124.225029 -337.839652)
			(xy 124.171752 -337.85563) (xy 124.116717 -337.863699) (xy 124.088906 -337.864196) (xy 124.061653 -337.863739)
			(xy 124.007701 -337.855983) (xy 123.955402 -337.840627) (xy 123.905821 -337.817984) (xy 123.859968 -337.788516)
			(xy 123.818775 -337.752821) (xy 123.783081 -337.711628) (xy 123.753613 -337.665773) (xy 123.730971 -337.616192)
			(xy 123.715616 -337.563893) (xy 123.707861 -337.509941) (xy 123.707398 -337.482688) (xy 121.586865 -337.482688)
			(xy 121.585289 -337.492678) (xy 121.576592 -337.521296) (xy 121.572631 -337.535223) (xy 121.571708 -337.564145)
			(xy 121.578958 -337.592158) (xy 121.593796 -337.617001) (xy 121.615023 -337.636665) (xy 121.640926 -337.649564)
			(xy 121.655078 -337.652614) (xy 121.681143 -337.657824) (xy 121.731646 -337.674388) (xy 121.779359 -337.697805)
			(xy 121.823358 -337.727622) (xy 121.86279 -337.76326) (xy 121.89689 -337.804029) (xy 121.924998 -337.849138)
			(xy 121.94657 -337.897714) (xy 121.961186 -337.948815) (xy 121.968563 -338.001451) (xy 121.969022 -338.028026)
			(xy 121.968536 -338.055277) (xy 121.96078 -338.109225) (xy 121.945425 -338.16152) (xy 121.922783 -338.211097)
			(xy 121.893317 -338.256947) (xy 121.857626 -338.298138) (xy 121.816435 -338.333829) (xy 121.770585 -338.363295)
			(xy 121.721008 -338.385937) (xy 121.668713 -338.401292) (xy 121.614765 -338.409048) (xy 121.560263 -338.409048)
			(xy 121.506315 -338.401292) (xy 121.45402 -338.385937) (xy 121.404443 -338.363295) (xy 121.358593 -338.333829)
			(xy 121.317402 -338.298138) (xy 121.281711 -338.256947) (xy 121.252245 -338.211097) (xy 121.229603 -338.16152)
			(xy 121.214248 -338.109225) (xy 121.206492 -338.055277) (xy 121.206006 -338.028026) (xy 121.206536 -337.998121)
			(xy 121.215852 -337.939042) (xy 121.224548 -337.910424) (xy 121.228568 -337.896513) (xy 121.229471 -337.867586)
			(xy 121.222206 -337.83957) (xy 121.207357 -337.814728) (xy 121.186123 -337.795062) (xy 121.160217 -337.782159)
			(xy 121.146062 -337.779106) (xy 121.113226 -337.77251) (xy 121.050372 -337.749396) (xy 121.021094 -337.733132)
			(xy 121.008116 -337.72612) (xy 120.979485 -337.719086) (xy 120.950038 -337.720528) (xy 120.92223 -337.730325)
			(xy 120.898382 -337.74766) (xy 120.880483 -337.771087) (xy 120.87479 -337.784694) (xy 120.864116 -337.81148)
			(xy 120.835826 -337.861723) (xy 120.800294 -337.907134) (xy 120.758329 -337.946677) (xy 120.710889 -337.97945)
			(xy 120.659054 -338.004706) (xy 120.604007 -338.021869) (xy 120.547004 -338.030547) (xy 120.518174 -338.031074)
			(xy 120.490922 -338.030654) (xy 120.436972 -338.022894) (xy 120.384676 -338.007535) (xy 120.335097 -337.984891)
			(xy 120.289246 -337.955421) (xy 120.248055 -337.919726) (xy 120.212363 -337.878533) (xy 120.182897 -337.83268)
			(xy 120.160255 -337.7831) (xy 120.1449 -337.730803) (xy 120.137144 -337.676852) (xy 119.816972 -337.676852)
			(xy 119.794439 -337.708265) (xy 119.752772 -337.750569) (xy 119.72925 -337.768692) (xy 119.718621 -337.77709)
			(xy 119.701921 -337.798411) (xy 119.691409 -337.823371) (xy 119.687823 -337.850216) (xy 119.691417 -337.877059)
			(xy 119.701936 -337.902015) (xy 119.718643 -337.923331) (xy 119.72925 -337.93176) (xy 119.7528 -337.949847)
			(xy 119.794456 -337.992163) (xy 119.829054 -338.04042) (xy 119.85576 -338.093455) (xy 119.873928 -338.149986)
			(xy 119.88312 -338.208649) (xy 119.883682 -338.238338) (xy 119.883196 -338.265589) (xy 119.87544 -338.319537)
			(xy 119.860085 -338.371832) (xy 119.837443 -338.421409) (xy 119.807977 -338.467259) (xy 119.772286 -338.50845)
			(xy 119.731095 -338.544141) (xy 119.685245 -338.573607) (xy 119.642953 -338.592922) (xy 125.683518 -338.592922)
			(xy 125.684014 -338.564882) (xy 125.692213 -338.509403) (xy 125.708438 -338.455721) (xy 125.732339 -338.404989)
			(xy 125.763403 -338.358298) (xy 125.781816 -338.337144) (xy 125.791486 -338.325722) (xy 125.804259 -338.298671)
			(xy 125.808638 -338.269079) (xy 125.804246 -338.239489) (xy 125.791463 -338.212443) (xy 125.781816 -338.201)
			(xy 125.763361 -338.179878) (xy 125.732274 -338.133192) (xy 125.708366 -338.082454) (xy 125.692154 -338.028759)
			(xy 125.683988 -337.973267) (xy 125.683518 -337.945222) (xy 125.684004 -337.917971) (xy 125.69176 -337.864023)
			(xy 125.707115 -337.811728) (xy 125.729757 -337.762151) (xy 125.759223 -337.716301) (xy 125.794914 -337.67511)
			(xy 125.836105 -337.639419) (xy 125.881955 -337.609953) (xy 125.931532 -337.587311) (xy 125.983827 -337.571956)
			(xy 126.037775 -337.5642) (xy 126.092277 -337.5642) (xy 126.146225 -337.571956) (xy 126.19852 -337.587311)
			(xy 126.248097 -337.609953) (xy 126.293947 -337.639419) (xy 126.335138 -337.67511) (xy 126.370829 -337.716301)
			(xy 126.400295 -337.762151) (xy 126.422937 -337.811728) (xy 126.438292 -337.864023) (xy 126.446048 -337.917971)
			(xy 126.446534 -337.945222) (xy 126.446051 -337.973263) (xy 126.437847 -338.028741) (xy 126.421619 -338.082423)
			(xy 126.397715 -338.133155) (xy 126.366649 -338.179846) (xy 126.348236 -338.201) (xy 126.338617 -338.212462)
			(xy 126.325831 -338.239497) (xy 126.321439 -338.269079) (xy 126.325819 -338.298663) (xy 126.338594 -338.325703)
			(xy 126.348236 -338.337144) (xy 126.366656 -338.358295) (xy 126.39775 -338.404972) (xy 126.421665 -338.455703)
			(xy 126.437885 -338.509392) (xy 126.44606 -338.564879) (xy 126.446534 -338.592922) (xy 126.446048 -338.620173)
			(xy 126.438292 -338.674121) (xy 126.422937 -338.726416) (xy 126.400295 -338.775993) (xy 126.370829 -338.821843)
			(xy 126.335138 -338.863034) (xy 126.293947 -338.898725) (xy 126.248097 -338.928191) (xy 126.19852 -338.950833)
			(xy 126.146225 -338.966188) (xy 126.092277 -338.973944) (xy 126.037775 -338.973944) (xy 125.983827 -338.966188)
			(xy 125.931532 -338.950833) (xy 125.881955 -338.928191) (xy 125.836105 -338.898725) (xy 125.794914 -338.863034)
			(xy 125.759223 -338.821843) (xy 125.729757 -338.775993) (xy 125.707115 -338.726416) (xy 125.69176 -338.674121)
			(xy 125.684004 -338.620173) (xy 125.683518 -338.592922) (xy 119.642953 -338.592922) (xy 119.635668 -338.596249)
			(xy 119.583373 -338.611604) (xy 119.529425 -338.61936) (xy 119.474923 -338.61936) (xy 119.420975 -338.611604)
			(xy 119.36868 -338.596249) (xy 119.319103 -338.573607) (xy 119.273253 -338.544141) (xy 119.232062 -338.50845)
			(xy 119.196371 -338.467259) (xy 119.166905 -338.421409) (xy 119.144263 -338.371832) (xy 119.128908 -338.319537)
			(xy 119.121152 -338.265589) (xy 119.120666 -338.238338) (xy 113.744764 -338.238338) (xy 113.732805 -338.256947)
			(xy 113.697114 -338.298138) (xy 113.655923 -338.333829) (xy 113.610073 -338.363295) (xy 113.560496 -338.385937)
			(xy 113.508201 -338.401292) (xy 113.454253 -338.409048) (xy 113.399751 -338.409048) (xy 113.345803 -338.401292)
			(xy 113.293508 -338.385937) (xy 113.243931 -338.363295) (xy 113.198081 -338.333829) (xy 113.15689 -338.298138)
			(xy 113.121199 -338.256947) (xy 113.091733 -338.211097) (xy 113.069091 -338.16152) (xy 113.053736 -338.109225)
			(xy 113.04598 -338.055277) (xy 113.045494 -338.028026) (xy 113.046024 -337.998121) (xy 113.05534 -337.939042)
			(xy 113.064036 -337.910424) (xy 113.068065 -337.896515) (xy 113.068969 -337.867586) (xy 113.061702 -337.839569)
			(xy 113.046852 -337.814725) (xy 113.025615 -337.79506) (xy 112.999706 -337.782158) (xy 112.98555 -337.779106)
			(xy 112.952713 -337.772512) (xy 112.889859 -337.749397) (xy 112.860582 -337.733132) (xy 112.847611 -337.726106)
			(xy 112.818977 -337.719074) (xy 112.789528 -337.720518) (xy 112.761719 -337.730318) (xy 112.73787 -337.747656)
			(xy 112.719971 -337.771086) (xy 112.714278 -337.784694) (xy 112.70353 -337.811448) (xy 112.67525 -337.861689)
			(xy 112.639727 -337.907098) (xy 112.597773 -337.946642) (xy 112.550343 -337.979418) (xy 112.498519 -338.00468)
			(xy 112.443483 -338.021851) (xy 112.386488 -338.030541) (xy 112.357662 -338.031074) (xy 112.33041 -338.030654)
			(xy 112.276462 -338.022892) (xy 112.224167 -338.007532) (xy 112.17459 -337.984887) (xy 112.12874 -337.955417)
			(xy 112.087551 -337.919722) (xy 112.05186 -337.878529) (xy 112.022395 -337.832677) (xy 111.999755 -337.783098)
			(xy 111.9844 -337.730801) (xy 111.976644 -337.676852) (xy 111.656463 -337.676852) (xy 111.633929 -337.708266)
			(xy 111.592261 -337.750569) (xy 111.568738 -337.768692) (xy 111.558101 -337.777085) (xy 111.541386 -337.798403)
			(xy 111.530865 -337.823365) (xy 111.527276 -337.850216) (xy 111.530873 -337.877065) (xy 111.541402 -337.902024)
			(xy 111.558123 -337.923336) (xy 111.568738 -337.93176) (xy 111.592285 -337.94985) (xy 111.633942 -337.992165)
			(xy 111.668541 -338.040422) (xy 111.695247 -338.093455) (xy 111.713416 -338.149986) (xy 111.722608 -338.208649)
			(xy 111.72317 -338.238338) (xy 111.722684 -338.265589) (xy 111.714928 -338.319537) (xy 111.699573 -338.371832)
			(xy 111.676931 -338.421409) (xy 111.647465 -338.467259) (xy 111.611774 -338.50845) (xy 111.570583 -338.544141)
			(xy 111.524733 -338.573607) (xy 111.475156 -338.596249) (xy 111.422861 -338.611604) (xy 111.368913 -338.61936)
			(xy 111.314411 -338.61936) (xy 111.260463 -338.611604) (xy 111.208168 -338.596249) (xy 111.158591 -338.573607)
			(xy 111.112741 -338.544141) (xy 111.07155 -338.50845) (xy 111.035859 -338.467259) (xy 111.006393 -338.421409)
			(xy 110.983751 -338.371832) (xy 110.968396 -338.319537) (xy 110.96064 -338.265589) (xy 110.960154 -338.238338)
			(xy 105.584252 -338.238338) (xy 105.572293 -338.256947) (xy 105.536602 -338.298138) (xy 105.495411 -338.333829)
			(xy 105.449561 -338.363295) (xy 105.399984 -338.385937) (xy 105.347689 -338.401292) (xy 105.293741 -338.409048)
			(xy 105.239239 -338.409048) (xy 105.185291 -338.401292) (xy 105.132996 -338.385937) (xy 105.083419 -338.363295)
			(xy 105.037569 -338.333829) (xy 104.996378 -338.298138) (xy 104.960687 -338.256947) (xy 104.931221 -338.211097)
			(xy 104.908579 -338.16152) (xy 104.893224 -338.109225) (xy 104.885468 -338.055277) (xy 104.884982 -338.028026)
			(xy 104.885513 -337.998121) (xy 104.894828 -337.939042) (xy 104.903524 -337.910424) (xy 104.907562 -337.896517)
			(xy 104.908467 -337.867586) (xy 104.901199 -337.839567) (xy 104.886347 -337.814723) (xy 104.865107 -337.795057)
			(xy 104.839195 -337.782157) (xy 104.825038 -337.779106) (xy 104.7922 -337.772515) (xy 104.729347 -337.749398)
			(xy 104.70007 -337.733132) (xy 104.687106 -337.726092) (xy 104.65847 -337.719062) (xy 104.629018 -337.720509)
			(xy 104.601208 -337.730311) (xy 104.577358 -337.747652) (xy 104.559459 -337.771085) (xy 104.553766 -337.784694)
			(xy 104.543028 -337.811453) (xy 104.514746 -337.861693) (xy 104.479223 -337.907103) (xy 104.437267 -337.946647)
			(xy 104.389836 -337.979422) (xy 104.33801 -338.004683) (xy 104.282973 -338.021854) (xy 104.225977 -338.030542)
			(xy 104.19715 -338.031074) (xy 104.169899 -338.030653) (xy 104.115952 -338.02289) (xy 104.063658 -338.007529)
			(xy 104.014083 -337.984883) (xy 103.968235 -337.955413) (xy 103.927047 -337.919718) (xy 103.891357 -337.878525)
			(xy 103.861893 -337.832673) (xy 103.839254 -337.783095) (xy 103.8239 -337.7308) (xy 103.816144 -337.676851)
			(xy 103.495955 -337.676851) (xy 103.473419 -337.708267) (xy 103.43175 -337.75057) (xy 103.408226 -337.768692)
			(xy 103.39759 -337.777086) (xy 103.380877 -337.798404) (xy 103.370357 -337.823366) (xy 103.366769 -337.850216)
			(xy 103.370365 -337.877064) (xy 103.380893 -337.902023) (xy 103.397612 -337.923336) (xy 103.408226 -337.93176)
			(xy 103.43177 -337.949853) (xy 103.473428 -337.992167) (xy 103.508028 -338.040423) (xy 103.534735 -338.093456)
			(xy 103.552903 -338.149986) (xy 103.562096 -338.208649) (xy 103.562658 -338.238338) (xy 103.562172 -338.265589)
			(xy 103.554416 -338.319537) (xy 103.539061 -338.371832) (xy 103.516419 -338.421409) (xy 103.486953 -338.467259)
			(xy 103.451262 -338.50845) (xy 103.410071 -338.544141) (xy 103.364221 -338.573607) (xy 103.314644 -338.596249)
			(xy 103.262349 -338.611604) (xy 103.208401 -338.61936) (xy 103.153899 -338.61936) (xy 103.099951 -338.611604)
			(xy 103.047656 -338.596249) (xy 102.998079 -338.573607) (xy 102.952229 -338.544141) (xy 102.911038 -338.50845)
			(xy 102.875347 -338.467259) (xy 102.845881 -338.421409) (xy 102.823239 -338.371832) (xy 102.807884 -338.319537)
			(xy 102.800128 -338.265589) (xy 102.799642 -338.238338) (xy 97.42374 -338.238338) (xy 97.411781 -338.256947)
			(xy 97.37609 -338.298138) (xy 97.334899 -338.333829) (xy 97.289049 -338.363295) (xy 97.239472 -338.385937)
			(xy 97.187177 -338.401292) (xy 97.133229 -338.409048) (xy 97.078727 -338.409048) (xy 97.024779 -338.401292)
			(xy 96.972484 -338.385937) (xy 96.922907 -338.363295) (xy 96.877057 -338.333829) (xy 96.835866 -338.298138)
			(xy 96.800175 -338.256947) (xy 96.770709 -338.211097) (xy 96.748067 -338.16152) (xy 96.732712 -338.109225)
			(xy 96.724956 -338.055277) (xy 96.72447 -338.028026) (xy 96.725001 -337.998121) (xy 96.734316 -337.939042)
			(xy 96.743012 -337.910424) (xy 96.74706 -337.896519) (xy 96.747965 -337.867586) (xy 96.740696 -337.839565)
			(xy 96.725842 -337.81472) (xy 96.704599 -337.795054) (xy 96.678684 -337.782155) (xy 96.664526 -337.779106)
			(xy 96.631688 -337.772518) (xy 96.568835 -337.749399) (xy 96.539558 -337.733132) (xy 96.526602 -337.726078)
			(xy 96.497962 -337.71905) (xy 96.468508 -337.720499) (xy 96.440696 -337.730304) (xy 96.416846 -337.747648)
			(xy 96.398947 -337.771083) (xy 96.393254 -337.784694) (xy 96.382526 -337.811457) (xy 96.354243 -337.861698)
			(xy 96.318718 -337.907108) (xy 96.276761 -337.946651) (xy 96.229328 -337.979427) (xy 96.177501 -338.004687)
			(xy 96.122462 -338.021856) (xy 96.065465 -338.030542) (xy 96.036638 -338.031074) (xy 96.009381 -338.030682)
			(xy 95.955421 -338.022928) (xy 95.903114 -338.007574) (xy 95.853525 -337.984932) (xy 95.807662 -337.955462)
			(xy 95.766462 -337.919765) (xy 95.730761 -337.878568) (xy 95.701286 -337.832709) (xy 95.678639 -337.783122)
			(xy 95.66328 -337.730816) (xy 95.655521 -337.676857) (xy 95.335442 -337.676857) (xy 95.312908 -337.708268)
			(xy 95.271238 -337.75057) (xy 95.247714 -337.768692) (xy 95.237079 -337.777087) (xy 95.220368 -337.798405)
			(xy 95.209849 -337.823367) (xy 95.206262 -337.850216) (xy 95.209858 -337.877063) (xy 95.220384 -337.902021)
			(xy 95.237101 -337.923335) (xy 95.247714 -337.93176) (xy 95.271256 -337.949857) (xy 95.312914 -337.992169)
			(xy 95.347515 -338.040424) (xy 95.374222 -338.093457) (xy 95.392391 -338.149987) (xy 95.401584 -338.208649)
			(xy 95.402146 -338.238338) (xy 95.40166 -338.265589) (xy 95.393904 -338.319537) (xy 95.378549 -338.371832)
			(xy 95.355907 -338.421409) (xy 95.326441 -338.467259) (xy 95.29075 -338.50845) (xy 95.249559 -338.544141)
			(xy 95.203709 -338.573607) (xy 95.154132 -338.596249) (xy 95.101837 -338.611604) (xy 95.047889 -338.61936)
			(xy 94.993387 -338.61936) (xy 94.939439 -338.611604) (xy 94.887144 -338.596249) (xy 94.837567 -338.573607)
			(xy 94.791717 -338.544141) (xy 94.750526 -338.50845) (xy 94.714835 -338.467259) (xy 94.685369 -338.421409)
			(xy 94.662727 -338.371832) (xy 94.647372 -338.319537) (xy 94.639616 -338.265589) (xy 94.63913 -338.238338)
			(xy 85.513487 -338.238338) (xy 85.497013 -338.253124) (xy 85.452672 -338.282917) (xy 85.428836 -338.29498)
			(xy 85.415646 -338.301849) (xy 85.393733 -338.32194) (xy 85.378532 -338.347489) (xy 85.371329 -338.376332)
			(xy 85.372735 -338.406028) (xy 85.382631 -338.434062) (xy 85.39099 -338.446364) (xy 85.408342 -338.471021)
			(xy 85.435855 -338.524669) (xy 85.454589 -338.581976) (xy 85.464077 -338.641516) (xy 85.46465 -338.671662)
			(xy 85.464164 -338.698913) (xy 85.456408 -338.752861) (xy 85.441053 -338.805156) (xy 85.418411 -338.854733)
			(xy 85.388945 -338.900583) (xy 85.353254 -338.941774) (xy 85.312063 -338.977465) (xy 85.293803 -338.9892)
			(xy 89.129495 -338.9892) (xy 89.133664 -338.933573) (xy 89.146078 -338.879188) (xy 89.16646 -338.827262)
			(xy 89.194353 -338.778953) (xy 89.229135 -338.735342) (xy 89.27003 -338.697402) (xy 89.316122 -338.665981)
			(xy 89.366383 -338.641782) (xy 89.419689 -338.625344) (xy 89.47485 -338.617036) (xy 89.502742 -338.616544)
			(xy 89.530074 -338.617024) (xy 89.584153 -338.624991) (xy 89.636488 -338.640777) (xy 89.685952 -338.664044)
			(xy 89.731485 -338.69429) (xy 89.772107 -338.730868) (xy 89.806946 -338.77299) (xy 89.821512 -338.796122)
			(xy 89.829441 -338.808342) (xy 89.850912 -338.82801) (xy 89.877063 -338.840814) (xy 89.905767 -338.845711)
			(xy 89.934684 -338.842302) (xy 89.948258 -338.837016) (xy 89.971464 -338.827517) (xy 90.019799 -338.814169)
			(xy 90.06949 -338.807445) (xy 90.094562 -338.807044) (xy 90.119632 -338.807458) (xy 90.169315 -338.814212)
			(xy 90.217649 -338.827548) (xy 90.240866 -338.837016) (xy 90.254444 -338.84226) (xy 90.283344 -338.845625)
			(xy 90.312022 -338.840714) (xy 90.338156 -338.827926) (xy 90.359631 -338.808296) (xy 90.367612 -338.796122)
			(xy 90.382181 -338.772991) (xy 90.417024 -338.73087) (xy 90.457647 -338.694291) (xy 90.503178 -338.66404)
			(xy 90.55264 -338.640764) (xy 90.604971 -338.624964) (xy 90.65905 -338.616978) (xy 90.713714 -338.616978)
			(xy 90.767793 -338.624964) (xy 90.820124 -338.640764) (xy 90.869586 -338.66404) (xy 90.915117 -338.694291)
			(xy 90.95574 -338.73087) (xy 90.990583 -338.772991) (xy 91.005152 -338.796122) (xy 91.013043 -338.808369)
			(xy 91.034524 -338.828038) (xy 91.060686 -338.840838) (xy 91.089398 -338.845727) (xy 91.118322 -338.842308)
			(xy 91.131898 -338.837016) (xy 91.155111 -338.827536) (xy 91.203442 -338.814181) (xy 91.253131 -338.807449)
			(xy 91.278202 -338.807044) (xy 91.30584 -338.807554) (xy 91.360507 -338.815747) (xy 91.413365 -338.831923)
			(xy 91.463254 -338.855727) (xy 91.509081 -338.886638) (xy 91.549841 -338.923978) (xy 91.584639 -338.966928)
			(xy 91.612713 -339.014545) (xy 91.633448 -339.065787) (xy 91.640406 -339.09254) (xy 91.644031 -339.105642)
			(xy 91.657168 -339.129428) (xy 91.676113 -339.148908) (xy 91.699525 -339.162702) (xy 91.725746 -339.169834)
			(xy 91.752919 -339.169798) (xy 91.779121 -339.162598) (xy 91.791028 -339.15604) (xy 91.813174 -339.143407)
			(xy 91.860126 -339.123531) (xy 91.909309 -339.110095) (xy 91.959845 -339.103339) (xy 91.985338 -339.102954)
			(xy 91.993466 -339.102954) (xy 92.008325 -339.102719) (xy 92.036942 -339.094758) (xy 92.062067 -339.078913)
			(xy 92.081582 -339.056521) (xy 92.093844 -339.029466) (xy 92.096336 -339.014816) (xy 92.100451 -338.987679)
			(xy 92.115458 -338.934885) (xy 92.137872 -338.884785) (xy 92.167232 -338.838412) (xy 92.202933 -338.796724)
			(xy 92.244237 -338.76058) (xy 92.290293 -338.730725) (xy 92.34015 -338.707776) (xy 92.392781 -338.692205)
			(xy 92.447099 -338.684334) (xy 92.474542 -338.683854) (xy 92.501793 -338.684339) (xy 92.555738 -338.6921)
			(xy 92.608031 -338.707458) (xy 92.657606 -338.730102) (xy 92.703454 -338.759569) (xy 92.744643 -338.79526)
			(xy 92.780334 -338.836449) (xy 92.8098 -338.882298) (xy 92.832443 -338.931873) (xy 92.847801 -338.984166)
			(xy 92.848525 -338.9892) (xy 129.932095 -338.9892) (xy 129.936264 -338.933577) (xy 129.948676 -338.879196)
			(xy 129.969055 -338.827272) (xy 129.996944 -338.778966) (xy 130.031722 -338.735356) (xy 130.072612 -338.697416)
			(xy 130.118699 -338.665995) (xy 130.168955 -338.641793) (xy 130.222256 -338.625352) (xy 130.277412 -338.617039)
			(xy 130.305302 -338.616544) (xy 130.332635 -338.616977) (xy 130.386717 -338.624953) (xy 130.439052 -338.640747)
			(xy 130.488517 -338.664021) (xy 130.534049 -338.694275) (xy 130.57467 -338.730859) (xy 130.609508 -338.772987)
			(xy 130.624072 -338.796122) (xy 130.631944 -338.808383) (xy 130.65343 -338.828052) (xy 130.679597 -338.84085)
			(xy 130.708314 -338.845736) (xy 130.737242 -338.842311) (xy 130.750818 -338.837016) (xy 130.774029 -338.827529)
			(xy 130.822361 -338.814177) (xy 130.87205 -338.807448) (xy 130.897122 -338.807044) (xy 130.922191 -338.807471)
			(xy 130.971874 -338.814219) (xy 131.020209 -338.82755) (xy 131.043426 -338.837016) (xy 131.057019 -338.842218)
			(xy 131.085911 -338.845591) (xy 131.114584 -338.840691) (xy 131.140716 -338.827912) (xy 131.16219 -338.808292)
			(xy 131.170172 -338.796122) (xy 131.184741 -338.772991) (xy 131.219584 -338.73087) (xy 131.260207 -338.694291)
			(xy 131.305738 -338.66404) (xy 131.3552 -338.640764) (xy 131.407531 -338.624964) (xy 131.46161 -338.616978)
			(xy 131.516274 -338.616978) (xy 131.570353 -338.624964) (xy 131.622684 -338.640764) (xy 131.672146 -338.66404)
			(xy 131.717677 -338.694291) (xy 131.7583 -338.73087) (xy 131.793143 -338.772991) (xy 131.807712 -338.796122)
			(xy 131.815641 -338.808342) (xy 131.837112 -338.82801) (xy 131.863263 -338.840814) (xy 131.891967 -338.845711)
			(xy 131.920884 -338.842302) (xy 131.934458 -338.837016) (xy 131.957664 -338.827517) (xy 132.005999 -338.814169)
			(xy 132.05569 -338.807445) (xy 132.080762 -338.807044) (xy 132.105703 -338.807423) (xy 132.15514 -338.81407)
			(xy 132.203249 -338.827251) (xy 132.249171 -338.84673) (xy 132.292085 -338.872159) (xy 132.311902 -338.887308)
			(xy 132.3234 -338.89589) (xy 132.34993 -338.906786) (xy 132.378445 -338.909859) (xy 132.406688 -338.904866)
			(xy 132.432421 -338.892202) (xy 132.453607 -338.87287) (xy 132.461508 -338.860892) (xy 132.476508 -338.837421)
			(xy 132.512171 -338.794638) (xy 132.553678 -338.757497) (xy 132.600146 -338.726789) (xy 132.650587 -338.703166)
			(xy 132.703928 -338.687133) (xy 132.759033 -338.679028) (xy 132.786882 -338.67852) (xy 132.815037 -338.678965)
			(xy 132.870737 -338.687226) (xy 132.924618 -338.703587) (xy 132.975508 -338.727691) (xy 133.0223 -338.759016)
			(xy 133.06398 -338.796879) (xy 133.099639 -338.840459) (xy 133.128504 -338.888807) (xy 133.149947 -338.940874)
			(xy 133.157214 -338.96808) (xy 133.161562 -338.983021) (xy 133.177813 -339.009536) (xy 133.201287 -339.029935)
			(xy 133.229809 -339.042329) (xy 133.260739 -339.04557) (xy 133.276086 -339.04301) (xy 133.294869 -339.03944)
			(xy 133.332914 -339.035624) (xy 133.352032 -339.03539) (xy 133.379282 -339.035882) (xy 133.433226 -339.043642)
			(xy 133.485516 -339.059) (xy 133.535089 -339.081643) (xy 133.580935 -339.11111) (xy 133.622122 -339.146801)
			(xy 133.657809 -339.18799) (xy 133.687273 -339.233839) (xy 133.709911 -339.283414) (xy 133.725265 -339.335706)
			(xy 133.73302 -339.38965) (xy 133.73302 -339.44415) (xy 133.725265 -339.498094) (xy 133.709911 -339.550386)
			(xy 133.687273 -339.599961) (xy 133.657809 -339.64581) (xy 133.622122 -339.686999) (xy 133.580935 -339.72269)
			(xy 133.535089 -339.752157) (xy 133.485516 -339.7748) (xy 133.433226 -339.790158) (xy 133.379282 -339.797918)
			(xy 133.352032 -339.798406) (xy 133.323878 -339.797929) (xy 133.26818 -339.78967) (xy 133.214302 -339.773313)
			(xy 133.163413 -339.749212) (xy 133.116621 -339.717892) (xy 133.074942 -339.680033) (xy 133.039281 -339.636457)
			(xy 133.010414 -339.588113) (xy 132.988968 -339.53605) (xy 132.9817 -339.508846) (xy 132.977428 -339.493877)
			(xy 132.961165 -339.467351) (xy 132.937673 -339.446949) (xy 132.909129 -339.434563) (xy 132.878181 -339.431342)
			(xy 132.862828 -339.433916) (xy 132.844045 -339.437484) (xy 132.806 -339.441301) (xy 132.786882 -339.441536)
			(xy 132.760716 -339.441097) (xy 132.708871 -339.433986) (xy 132.658488 -339.419844) (xy 132.610515 -339.398938)
			(xy 132.565855 -339.371661) (xy 132.545328 -339.35543) (xy 132.533921 -339.346707) (xy 132.507553 -339.33537)
			(xy 132.47907 -339.331838) (xy 132.450732 -339.336391) (xy 132.424788 -339.348667) (xy 132.403298 -339.367692)
			(xy 132.395214 -339.37956) (xy 132.389483 -339.388432) (xy 132.377156 -339.405587) (xy 132.370576 -339.41385)
			(xy 132.361312 -339.426139) (xy 132.349909 -339.454705) (xy 132.347517 -339.485371) (xy 132.354353 -339.515361)
			(xy 132.369797 -339.541961) (xy 132.392453 -339.562764) (xy 132.406136 -339.569806) (xy 132.429267 -339.581168)
			(xy 132.472506 -339.609205) (xy 132.51157 -339.642817) (xy 132.545746 -339.681389) (xy 132.574408 -339.724217)
			(xy 132.597033 -339.770519) (xy 132.605526 -339.79485) (xy 132.610638 -339.808596) (xy 132.627402 -339.832642)
			(xy 132.650295 -339.850949) (xy 132.67744 -339.862015) (xy 132.706607 -339.864932) (xy 132.721096 -339.862668)
			(xy 132.739021 -339.859459) (xy 132.775277 -339.85602) (xy 132.793486 -339.85581) (xy 132.820739 -339.856268)
			(xy 132.874691 -339.864024) (xy 132.92699 -339.879379) (xy 132.976572 -339.902021) (xy 133.022426 -339.931489)
			(xy 133.063619 -339.967184) (xy 133.099313 -340.008377) (xy 133.128781 -340.054232) (xy 133.151422 -340.103813)
			(xy 133.166777 -340.156113) (xy 133.174532 -340.210065) (xy 133.174994 -340.237318) (xy 133.17474 -340.247732)
			(xy 133.174877 -340.262098) (xy 133.18214 -340.28988) (xy 133.196844 -340.314545) (xy 133.21783 -340.334145)
			(xy 133.24344 -340.347133) (xy 133.271652 -340.352484) (xy 133.285992 -340.351618) (xy 133.322568 -340.34984)
			(xy 133.349826 -340.350205) (xy 133.403787 -340.357959) (xy 133.456095 -340.373314) (xy 133.505686 -340.395958)
			(xy 133.551549 -340.425429) (xy 133.59275 -340.461127) (xy 133.628452 -340.502326) (xy 133.657927 -340.548186)
			(xy 133.680575 -340.597775) (xy 133.695934 -340.650082) (xy 133.703693 -340.704042) (xy 133.703693 -340.758558)
			(xy 133.695934 -340.812518) (xy 133.680575 -340.864825) (xy 133.657927 -340.914414) (xy 133.628452 -340.960274)
			(xy 133.59275 -341.001473) (xy 133.551549 -341.037171) (xy 133.505686 -341.066642) (xy 133.456095 -341.089286)
			(xy 133.403787 -341.104641) (xy 133.349826 -341.112395) (xy 133.322568 -341.112856) (xy 133.311557 -341.112774)
			(xy 133.289572 -341.111506) (xy 133.278626 -341.110316) (xy 133.263768 -341.109077) (xy 133.234433 -341.114331)
			(xy 133.207865 -341.127834) (xy 133.18633 -341.148435) (xy 133.171663 -341.174379) (xy 133.167882 -341.188802)
			(xy 133.161046 -341.216549) (xy 133.140188 -341.269751) (xy 133.111632 -341.31925) (xy 133.076016 -341.363938)
			(xy 133.034138 -341.402819) (xy 132.986931 -341.435023) (xy 132.935451 -341.45983) (xy 132.880849 -341.476686)
			(xy 132.824344 -341.485215) (xy 132.795772 -341.485728) (xy 132.766784 -341.485202) (xy 132.709477 -341.476427)
			(xy 132.654157 -341.459083) (xy 132.602097 -341.433569) (xy 132.554497 -341.400472) (xy 132.512452 -341.360556)
			(xy 132.476929 -341.314737) (xy 132.448748 -341.264073) (xy 132.428556 -341.209727) (xy 132.416818 -341.152952)
			(xy 132.414772 -341.124032) (xy 132.413612 -341.109956) (xy 132.40452 -341.083227) (xy 132.388444 -341.060018)
			(xy 132.366618 -341.042109) (xy 132.340716 -341.030875) (xy 132.312727 -341.027177) (xy 132.298694 -341.028782)
			(xy 132.28493 -341.030679) (xy 132.257216 -341.032711) (xy 132.243322 -341.032846) (xy 132.216073 -341.032301)
			(xy 132.162129 -341.024549) (xy 132.109838 -341.009198) (xy 132.060264 -340.986563) (xy 132.014415 -340.957102)
			(xy 131.973226 -340.921417) (xy 131.937534 -340.880233) (xy 131.908066 -340.834389) (xy 131.885423 -340.784818)
			(xy 131.870064 -340.732529) (xy 131.862303 -340.678587) (xy 131.861814 -340.651338) (xy 131.862301 -340.623764)
			(xy 131.870248 -340.569192) (xy 131.885969 -340.516332) (xy 131.909135 -340.466286) (xy 131.939264 -340.420096)
			(xy 131.975728 -340.378724) (xy 131.996434 -340.360508) (xy 132.00729 -340.350569) (xy 132.023358 -340.325929)
			(xy 132.031742 -340.297733) (xy 132.03175 -340.268316) (xy 132.023378 -340.240116) (xy 132.007322 -340.215468)
			(xy 131.996434 -340.205568) (xy 131.975711 -340.18737) (xy 131.93924 -340.145999) (xy 131.909109 -340.099807)
			(xy 131.885945 -340.049756) (xy 131.870231 -339.996891) (xy 131.862296 -339.942314) (xy 131.861814 -339.914738)
			(xy 131.862248 -339.888236) (xy 131.869597 -339.835744) (xy 131.884146 -339.784776) (xy 131.905614 -339.736314)
			(xy 131.933586 -339.691292) (xy 131.950206 -339.670644) (xy 131.959669 -339.658512) (xy 131.971464 -339.630107)
			(xy 131.974288 -339.599481) (xy 131.967888 -339.569398) (xy 131.95284 -339.542574) (xy 131.930504 -339.521431)
			(xy 131.916932 -339.51418) (xy 131.893237 -339.502088) (xy 131.849257 -339.472162) (xy 131.809977 -339.436289)
			(xy 131.776195 -339.395196) (xy 131.761992 -339.372702) (xy 131.754054 -339.360488) (xy 131.732587 -339.340817)
			(xy 131.706437 -339.328011) (xy 131.677736 -339.323113) (xy 131.648819 -339.326522) (xy 131.635246 -339.331808)
			(xy 131.61204 -339.341307) (xy 131.563705 -339.354654) (xy 131.514014 -339.361379) (xy 131.488942 -339.36178)
			(xy 131.463872 -339.361362) (xy 131.414189 -339.35461) (xy 131.365855 -339.341275) (xy 131.342638 -339.331808)
			(xy 131.329062 -339.326558) (xy 131.30016 -339.323191) (xy 131.27148 -339.328102) (xy 131.245345 -339.340892)
			(xy 131.223871 -339.360526) (xy 131.215892 -339.372702) (xy 131.201323 -339.395833) (xy 131.16648 -339.437954)
			(xy 131.125857 -339.474533) (xy 131.080326 -339.504784) (xy 131.030864 -339.52806) (xy 130.978533 -339.54386)
			(xy 130.924454 -339.551846) (xy 130.86979 -339.551846) (xy 130.815711 -339.54386) (xy 130.76338 -339.52806)
			(xy 130.713918 -339.504784) (xy 130.668387 -339.474533) (xy 130.627764 -339.437954) (xy 130.592921 -339.395833)
			(xy 130.578352 -339.372702) (xy 130.570452 -339.360461) (xy 130.548974 -339.34079) (xy 130.522815 -339.327987)
			(xy 130.494104 -339.323096) (xy 130.465181 -339.326516) (xy 130.451606 -339.331808) (xy 130.428393 -339.341288)
			(xy 130.380061 -339.354643) (xy 130.330373 -339.361375) (xy 130.305302 -339.36178) (xy 130.277412 -339.361361)
			(xy 130.222256 -339.353048) (xy 130.168955 -339.336607) (xy 130.118699 -339.312405) (xy 130.072612 -339.280984)
			(xy 130.031722 -339.243044) (xy 129.996944 -339.199434) (xy 129.969055 -339.151128) (xy 129.948676 -339.099204)
			(xy 129.936264 -339.044823) (xy 129.932095 -338.9892) (xy 92.848525 -338.9892) (xy 92.855562 -339.038111)
			(xy 92.85605 -339.065362) (xy 92.855523 -339.093963) (xy 92.846994 -339.150525) (xy 92.83012 -339.205182)
			(xy 92.80528 -339.256709) (xy 92.77303 -339.303952) (xy 92.734092 -339.345855) (xy 92.712032 -339.364066)
			(xy 92.701416 -339.373139) (xy 92.685125 -339.395806) (xy 92.675581 -339.422039) (xy 92.6735 -339.449875)
			(xy 92.679035 -339.477235) (xy 92.691773 -339.502074) (xy 92.710763 -339.522534) (xy 92.722446 -339.530182)
			(xy 92.746065 -339.545126) (xy 92.789079 -339.580814) (xy 92.826427 -339.622394) (xy 92.857311 -339.668977)
			(xy 92.881071 -339.719566) (xy 92.897198 -339.773079) (xy 92.905347 -339.828373) (xy 92.905834 -339.856318)
			(xy 92.905414 -339.882211) (xy 92.898413 -339.933522) (xy 92.884529 -339.983413) (xy 92.864018 -340.030964)
			(xy 92.849543 -340.054946) (xy 126.474472 -340.054946) (xy 126.478543 -339.999324) (xy 126.490669 -339.944887)
			(xy 126.510592 -339.892796) (xy 126.537888 -339.844161) (xy 126.571974 -339.800018) (xy 126.612123 -339.761309)
			(xy 126.657481 -339.728858) (xy 126.707081 -339.703357) (xy 126.759865 -339.68535) (xy 126.814708 -339.67522)
			(xy 126.870442 -339.673183) (xy 126.925879 -339.679283) (xy 126.979836 -339.693389) (xy 127.031165 -339.715201)
			(xy 127.078771 -339.744255) (xy 127.121639 -339.77993) (xy 127.158856 -339.821467) (xy 127.189629 -339.86798)
			(xy 127.213301 -339.918477) (xy 127.229369 -339.971884) (xy 127.237489 -340.02706) (xy 127.237998 -340.054946)
			(xy 127.237489 -340.082832) (xy 127.229369 -340.138008) (xy 127.213301 -340.191415) (xy 127.189629 -340.241912)
			(xy 127.158856 -340.288425) (xy 127.121639 -340.329962) (xy 127.078771 -340.365637) (xy 127.031165 -340.394691)
			(xy 126.979836 -340.416503) (xy 126.925879 -340.430609) (xy 126.870442 -340.436709) (xy 126.814708 -340.434672)
			(xy 126.759865 -340.424542) (xy 126.707081 -340.406535) (xy 126.657481 -340.381034) (xy 126.612123 -340.348583)
			(xy 126.571974 -340.309874) (xy 126.537888 -340.265731) (xy 126.510592 -340.217096) (xy 126.490669 -340.165005)
			(xy 126.478543 -340.110568) (xy 126.474472 -340.054946) (xy 92.849543 -340.054946) (xy 92.837257 -340.075301)
			(xy 92.80474 -340.115605) (xy 92.7862 -340.133686) (xy 92.776099 -340.143826) (xy 92.761486 -340.16842)
			(xy 92.754279 -340.196106) (xy 92.755045 -340.224704) (xy 92.763725 -340.251964) (xy 92.779634 -340.27574)
			(xy 92.790264 -340.285324) (xy 92.811084 -340.303523) (xy 92.847757 -340.344909) (xy 92.878062 -340.391161)
			(xy 92.901364 -340.441308) (xy 92.917173 -340.494297) (xy 92.925157 -340.549014) (xy 92.925646 -340.576662)
			(xy 92.925087 -340.603911) (xy 92.917336 -340.657854) (xy 92.910526 -340.681056) (xy 125.683008 -340.681056)
			(xy 125.687079 -340.625434) (xy 125.699205 -340.570997) (xy 125.719128 -340.518906) (xy 125.746424 -340.470271)
			(xy 125.78051 -340.426128) (xy 125.820659 -340.387419) (xy 125.866017 -340.354968) (xy 125.915617 -340.329467)
			(xy 125.968401 -340.31146) (xy 126.023244 -340.30133) (xy 126.078978 -340.299293) (xy 126.134415 -340.305393)
			(xy 126.188372 -340.319499) (xy 126.239701 -340.341311) (xy 126.287307 -340.370365) (xy 126.330175 -340.40604)
			(xy 126.367392 -340.447577) (xy 126.398165 -340.49409) (xy 126.421837 -340.544587) (xy 126.437905 -340.597994)
			(xy 126.446025 -340.65317) (xy 126.446534 -340.681056) (xy 126.446025 -340.708942) (xy 126.437905 -340.764118)
			(xy 126.421837 -340.817525) (xy 126.398165 -340.868022) (xy 126.367392 -340.914535) (xy 126.330175 -340.956072)
			(xy 126.287307 -340.991747) (xy 126.239701 -341.020801) (xy 126.188372 -341.042613) (xy 126.134415 -341.056719)
			(xy 126.078978 -341.062819) (xy 126.023244 -341.060782) (xy 125.968401 -341.050652) (xy 125.915617 -341.032645)
			(xy 125.866017 -341.007144) (xy 125.820659 -340.974693) (xy 125.78051 -340.935984) (xy 125.746424 -340.891841)
			(xy 125.719128 -340.843206) (xy 125.699205 -340.791115) (xy 125.687079 -340.736678) (xy 125.683008 -340.681056)
			(xy 92.910526 -340.681056) (xy 92.901988 -340.710145) (xy 92.879354 -340.759719) (xy 92.849895 -340.805568)
			(xy 92.814211 -340.846757) (xy 92.773029 -340.88245) (xy 92.727186 -340.911917) (xy 92.677616 -340.934561)
			(xy 92.625328 -340.94992) (xy 92.571386 -340.957681) (xy 92.544138 -340.95817) (xy 92.515061 -340.957651)
			(xy 92.45758 -340.948831) (xy 92.402103 -340.931388) (xy 92.349916 -340.905728) (xy 92.302229 -340.872445)
			(xy 92.260145 -340.83231) (xy 92.22464 -340.786252) (xy 92.196536 -340.73534) (xy 92.185998 -340.708234)
			(xy 92.180456 -340.694696) (xy 92.162994 -340.671244) (xy 92.1396 -340.653705) (xy 92.112194 -340.643518)
			(xy 92.083024 -340.641518) (xy 92.06865 -340.644226) (xy 92.048091 -340.648521) (xy 92.006339 -340.653098)
			(xy 91.985338 -340.65337) (xy 91.971122 -340.65321) (xy 91.942772 -340.65105) (xy 91.928696 -340.649052)
			(xy 91.913365 -340.647367) (xy 91.882917 -340.652173) (xy 91.855285 -340.665837) (xy 91.832982 -340.687116)
			(xy 91.818036 -340.714076) (xy 91.814396 -340.729062) (xy 91.807912 -340.757296) (xy 91.787671 -340.811571)
			(xy 91.759458 -340.862163) (xy 91.723922 -340.907908) (xy 91.68188 -340.947757) (xy 91.634297 -340.980792)
			(xy 91.582268 -341.006255) (xy 91.526987 -341.023561) (xy 91.469725 -341.032311) (xy 91.440762 -341.032846)
			(xy 91.413512 -341.032358) (xy 91.359566 -341.024597) (xy 91.307274 -341.009239) (xy 91.257699 -340.986596)
			(xy 91.21185 -340.957129) (xy 91.170662 -340.921438) (xy 91.134971 -340.88025) (xy 91.105504 -340.834401)
			(xy 91.082861 -340.784826) (xy 91.067503 -340.732534) (xy 91.059742 -340.678588) (xy 91.059254 -340.651338)
			(xy 91.059727 -340.623764) (xy 91.067675 -340.56919) (xy 91.083398 -340.51633) (xy 91.106566 -340.466283)
			(xy 91.136698 -340.420094) (xy 91.173166 -340.378723) (xy 91.193874 -340.360508) (xy 91.204735 -340.350572)
			(xy 91.220813 -340.325933) (xy 91.229203 -340.297735) (xy 91.22921 -340.268314) (xy 91.220833 -340.240112)
			(xy 91.204768 -340.215465) (xy 91.193874 -340.205568) (xy 91.173139 -340.187383) (xy 91.136672 -340.146008)
			(xy 91.106543 -340.099812) (xy 91.083382 -340.049759) (xy 91.06767 -339.996893) (xy 91.059736 -339.942314)
			(xy 91.059254 -339.914738) (xy 91.059701 -339.888237) (xy 91.06705 -339.835746) (xy 91.081596 -339.784778)
			(xy 91.10306 -339.736316) (xy 91.131029 -339.691293) (xy 91.147646 -339.670644) (xy 91.157095 -339.658503)
			(xy 91.168883 -339.630101) (xy 91.171706 -339.59948) (xy 91.165308 -339.569401) (xy 91.150267 -339.542579)
			(xy 91.127939 -339.521434) (xy 91.114372 -339.51418) (xy 91.090684 -339.502075) (xy 91.046702 -339.472154)
			(xy 91.00742 -339.436284) (xy 90.973636 -339.395194) (xy 90.959432 -339.372702) (xy 90.951551 -339.360448)
			(xy 90.930068 -339.340776) (xy 90.903903 -339.327975) (xy 90.875188 -339.323088) (xy 90.846262 -339.326513)
			(xy 90.832686 -339.331808) (xy 90.809475 -339.341295) (xy 90.761143 -339.354647) (xy 90.711454 -339.361376)
			(xy 90.686382 -339.36178) (xy 90.661313 -339.361349) (xy 90.61163 -339.354603) (xy 90.563296 -339.341273)
			(xy 90.540078 -339.331808) (xy 90.526487 -339.3266) (xy 90.497593 -339.323225) (xy 90.468919 -339.328125)
			(xy 90.442786 -339.340906) (xy 90.421312 -339.36053) (xy 90.413332 -339.372702) (xy 90.398763 -339.395833)
			(xy 90.36392 -339.437954) (xy 90.323297 -339.474533) (xy 90.277766 -339.504784) (xy 90.228304 -339.52806)
			(xy 90.175973 -339.54386) (xy 90.121894 -339.551846) (xy 90.06723 -339.551846) (xy 90.013151 -339.54386)
			(xy 89.96082 -339.52806) (xy 89.911358 -339.504784) (xy 89.865827 -339.474533) (xy 89.825204 -339.437954)
			(xy 89.790361 -339.395833) (xy 89.775792 -339.372702) (xy 89.767854 -339.360488) (xy 89.746387 -339.340817)
			(xy 89.720237 -339.328011) (xy 89.691536 -339.323113) (xy 89.662619 -339.326522) (xy 89.649046 -339.331808)
			(xy 89.62584 -339.341307) (xy 89.577505 -339.354654) (xy 89.527814 -339.361379) (xy 89.502742 -339.36178)
			(xy 89.47485 -339.361364) (xy 89.419689 -339.353056) (xy 89.366383 -339.336618) (xy 89.316122 -339.312419)
			(xy 89.27003 -339.280998) (xy 89.229135 -339.243058) (xy 89.194353 -339.199447) (xy 89.16646 -339.151138)
			(xy 89.146078 -339.099212) (xy 89.133664 -339.044827) (xy 89.129495 -338.9892) (xy 85.293803 -338.9892)
			(xy 85.266213 -339.006931) (xy 85.216636 -339.029573) (xy 85.164341 -339.044928) (xy 85.110393 -339.052684)
			(xy 85.055891 -339.052684) (xy 85.001943 -339.044928) (xy 84.949648 -339.029573) (xy 84.900071 -339.006931)
			(xy 84.854221 -338.977465) (xy 84.81303 -338.941774) (xy 84.777339 -338.900583) (xy 84.747873 -338.854733)
			(xy 84.725231 -338.805156) (xy 84.709876 -338.752861) (xy 84.70212 -338.698913) (xy 84.701634 -338.671662)
			(xy 76.426568 -338.671662) (xy 76.426568 -340.054946) (xy 85.671912 -340.054946) (xy 85.675983 -339.999324)
			(xy 85.688109 -339.944887) (xy 85.708032 -339.892796) (xy 85.735328 -339.844161) (xy 85.769414 -339.800018)
			(xy 85.809563 -339.761309) (xy 85.854921 -339.728858) (xy 85.904521 -339.703357) (xy 85.957305 -339.68535)
			(xy 86.012148 -339.67522) (xy 86.067882 -339.673183) (xy 86.123319 -339.679283) (xy 86.177276 -339.693389)
			(xy 86.228605 -339.715201) (xy 86.276211 -339.744255) (xy 86.319079 -339.77993) (xy 86.356296 -339.821467)
			(xy 86.387069 -339.86798) (xy 86.410741 -339.918477) (xy 86.426809 -339.971884) (xy 86.434929 -340.02706)
			(xy 86.435438 -340.054946) (xy 86.434929 -340.082832) (xy 86.426809 -340.138008) (xy 86.410741 -340.191415)
			(xy 86.387069 -340.241912) (xy 86.356296 -340.288425) (xy 86.319079 -340.329962) (xy 86.276211 -340.365637)
			(xy 86.228605 -340.394691) (xy 86.177276 -340.416503) (xy 86.123319 -340.430609) (xy 86.067882 -340.436709)
			(xy 86.012148 -340.434672) (xy 85.957305 -340.424542) (xy 85.904521 -340.406535) (xy 85.854921 -340.381034)
			(xy 85.809563 -340.348583) (xy 85.769414 -340.309874) (xy 85.735328 -340.265731) (xy 85.708032 -340.217096)
			(xy 85.688109 -340.165005) (xy 85.675983 -340.110568) (xy 85.671912 -340.054946) (xy 76.426568 -340.054946)
			(xy 76.426568 -341.059262) (xy 85.007448 -341.059262) (xy 85.011519 -341.00364) (xy 85.023645 -340.949203)
			(xy 85.043568 -340.897112) (xy 85.070864 -340.848477) (xy 85.10495 -340.804334) (xy 85.145099 -340.765625)
			(xy 85.190457 -340.733174) (xy 85.240057 -340.707673) (xy 85.292841 -340.689666) (xy 85.347684 -340.679536)
			(xy 85.403418 -340.677499) (xy 85.458855 -340.683599) (xy 85.512812 -340.697705) (xy 85.564141 -340.719517)
			(xy 85.611747 -340.748571) (xy 85.654615 -340.784246) (xy 85.691832 -340.825783) (xy 85.722605 -340.872296)
			(xy 85.746277 -340.922793) (xy 85.762345 -340.9762) (xy 85.770465 -341.031376) (xy 85.770974 -341.059262)
			(xy 85.770465 -341.087148) (xy 85.762345 -341.142324) (xy 85.746277 -341.195731) (xy 85.722605 -341.246228)
			(xy 85.691832 -341.292741) (xy 85.654615 -341.334278) (xy 85.611747 -341.369953) (xy 85.564141 -341.399007)
			(xy 85.512812 -341.420819) (xy 85.458855 -341.434925) (xy 85.403418 -341.441025) (xy 85.347684 -341.438988)
			(xy 85.292841 -341.428858) (xy 85.240057 -341.410851) (xy 85.190457 -341.38535) (xy 85.145099 -341.352899)
			(xy 85.10495 -341.31419) (xy 85.070864 -341.270047) (xy 85.043568 -341.221412) (xy 85.023645 -341.169321)
			(xy 85.011519 -341.114884) (xy 85.007448 -341.059262) (xy 76.426568 -341.059262) (xy 76.426568 -341.648542)
			(xy 86.478618 -341.648542) (xy 86.479196 -341.618855) (xy 86.488389 -341.560196) (xy 86.506559 -341.503671)
			(xy 86.533268 -341.450643) (xy 86.56787 -341.402394) (xy 86.609531 -341.360088) (xy 86.63305 -341.341964)
			(xy 86.643624 -341.333501) (xy 86.660324 -341.312195) (xy 86.670839 -341.28725) (xy 86.674432 -341.260418)
			(xy 86.670849 -341.233585) (xy 86.660342 -341.208636) (xy 86.64365 -341.187324) (xy 86.63305 -341.178896)
			(xy 86.609527 -341.160776) (xy 86.56787 -341.118467) (xy 86.533268 -341.070217) (xy 86.506558 -341.017189)
			(xy 86.488384 -340.960663) (xy 86.479184 -340.902005) (xy 86.478618 -340.872318) (xy 86.479104 -340.845067)
			(xy 86.48686 -340.791119) (xy 86.502215 -340.738824) (xy 86.524857 -340.689247) (xy 86.554323 -340.643397)
			(xy 86.590014 -340.602206) (xy 86.631205 -340.566515) (xy 86.677055 -340.537049) (xy 86.726632 -340.514407)
			(xy 86.778927 -340.499052) (xy 86.832875 -340.491296) (xy 86.887377 -340.491296) (xy 86.941325 -340.499052)
			(xy 86.99362 -340.514407) (xy 87.043197 -340.537049) (xy 87.089047 -340.566515) (xy 87.130238 -340.602206)
			(xy 87.165929 -340.643397) (xy 87.195395 -340.689247) (xy 87.218037 -340.738824) (xy 87.233392 -340.791119)
			(xy 87.241148 -340.845067) (xy 87.241634 -340.872318) (xy 87.241119 -340.902008) (xy 87.231915 -340.96067)
			(xy 87.213734 -341.017198) (xy 87.187013 -341.070226) (xy 87.174939 -341.087056) (xy 87.495025 -341.087056)
			(xy 87.495025 -341.032544) (xy 87.502783 -340.978586) (xy 87.518142 -340.926282) (xy 87.540788 -340.876696)
			(xy 87.570261 -340.830838) (xy 87.60596 -340.789642) (xy 87.647159 -340.753945) (xy 87.693019 -340.724476)
			(xy 87.742607 -340.701833) (xy 87.794912 -340.686478) (xy 87.84887 -340.678723) (xy 87.876126 -340.678262)
			(xy 87.901361 -340.678653) (xy 87.951396 -340.685273) (xy 88.000116 -340.698449) (xy 88.046667 -340.717947)
			(xy 88.068658 -340.730332) (xy 88.081597 -340.737424) (xy 88.110245 -340.744453) (xy 88.139706 -340.743)
			(xy 88.167523 -340.733188) (xy 88.191376 -340.715834) (xy 88.209273 -340.692386) (xy 88.214962 -340.67877)
			(xy 88.225657 -340.651993) (xy 88.253946 -340.601753) (xy 88.289477 -340.556344) (xy 88.331439 -340.516802)
			(xy 88.378876 -340.484029) (xy 88.430707 -340.458771) (xy 88.48575 -340.441604) (xy 88.542749 -340.43292)
			(xy 88.571578 -340.43239) (xy 88.59883 -340.432876) (xy 88.65278 -340.44063) (xy 88.705078 -340.455983)
			(xy 88.754657 -340.478623) (xy 88.800511 -340.508088) (xy 88.841703 -340.54378) (xy 88.877397 -340.58497)
			(xy 88.906866 -340.630821) (xy 88.929509 -340.6804) (xy 88.944865 -340.732696) (xy 88.952623 -340.786646)
			(xy 88.953086 -340.813898) (xy 88.952562 -340.843803) (xy 88.943242 -340.902883) (xy 88.934544 -340.9315)
			(xy 88.930537 -340.945417) (xy 88.929613 -340.974348) (xy 88.936868 -341.00237) (xy 88.951716 -341.027217)
			(xy 88.972956 -341.046881) (xy 88.998872 -341.059774) (xy 89.01303 -341.062818) (xy 89.039103 -341.067986)
			(xy 89.089607 -341.084557) (xy 89.13732 -341.107981) (xy 89.181318 -341.137803) (xy 89.220748 -341.173446)
			(xy 89.254847 -341.214219) (xy 89.282954 -341.259332) (xy 89.304524 -341.307912) (xy 89.319139 -341.359015)
			(xy 89.326516 -341.411654) (xy 89.326974 -341.43823) (xy 89.326488 -341.465481) (xy 89.318732 -341.519429)
			(xy 89.303377 -341.571724) (xy 89.280735 -341.621301) (xy 89.263228 -341.648542) (xy 127.281178 -341.648542)
			(xy 127.281772 -341.618856) (xy 127.290964 -341.560199) (xy 127.309132 -341.503674) (xy 127.335838 -341.450647)
			(xy 127.370437 -341.402397) (xy 127.412093 -341.360089) (xy 127.43561 -341.341964) (xy 127.446187 -341.333503)
			(xy 127.462893 -341.312198) (xy 127.473413 -341.287252) (xy 127.477007 -341.260418) (xy 127.473423 -341.233583)
			(xy 127.462912 -341.208633) (xy 127.446213 -341.187322) (xy 127.43561 -341.178896) (xy 127.4121 -341.16076)
			(xy 127.370439 -341.118456) (xy 127.335834 -341.07021) (xy 127.309121 -341.017184) (xy 127.290945 -340.960661)
			(xy 127.281744 -340.902005) (xy 127.281178 -340.872318) (xy 127.281664 -340.845067) (xy 127.28942 -340.791119)
			(xy 127.304775 -340.738824) (xy 127.327417 -340.689247) (xy 127.356883 -340.643397) (xy 127.392574 -340.602206)
			(xy 127.433765 -340.566515) (xy 127.479615 -340.537049) (xy 127.529192 -340.514407) (xy 127.581487 -340.499052)
			(xy 127.635435 -340.491296) (xy 127.689937 -340.491296) (xy 127.743885 -340.499052) (xy 127.79618 -340.514407)
			(xy 127.845757 -340.537049) (xy 127.891607 -340.566515) (xy 127.932798 -340.602206) (xy 127.968489 -340.643397)
			(xy 127.997955 -340.689247) (xy 128.020597 -340.738824) (xy 128.035952 -340.791119) (xy 128.043708 -340.845067)
			(xy 128.044194 -340.872318) (xy 128.043654 -340.902007) (xy 128.034453 -340.960667) (xy 128.016274 -341.017193)
			(xy 127.989558 -341.07022) (xy 127.977484 -341.087053) (xy 128.297648 -341.087053) (xy 128.297648 -341.032547)
			(xy 128.305405 -340.978597) (xy 128.32076 -340.926299) (xy 128.343402 -340.876719) (xy 128.372869 -340.830865)
			(xy 128.408562 -340.789672) (xy 128.449754 -340.753978) (xy 128.495606 -340.724509) (xy 128.545186 -340.701865)
			(xy 128.597483 -340.686508) (xy 128.651433 -340.678749) (xy 128.678686 -340.678262) (xy 128.703921 -340.67867)
			(xy 128.753954 -340.685286) (xy 128.802675 -340.698456) (xy 128.849227 -340.717949) (xy 128.871218 -340.730332)
			(xy 128.88418 -340.737377) (xy 128.912819 -340.744413) (xy 128.942273 -340.742969) (xy 128.970086 -340.733165)
			(xy 128.993936 -340.715821) (xy 129.011832 -340.692382) (xy 129.017522 -340.67877) (xy 129.02825 -340.652008)
			(xy 129.056536 -340.601769) (xy 129.092062 -340.556361) (xy 129.134019 -340.516818) (xy 129.181451 -340.484043)
			(xy 129.233277 -340.458783) (xy 129.288315 -340.441612) (xy 129.345311 -340.432923) (xy 129.374138 -340.43239)
			(xy 129.40139 -340.432842) (xy 129.455339 -340.440604) (xy 129.507634 -340.455964) (xy 129.557211 -340.478609)
			(xy 129.603061 -340.508079) (xy 129.644251 -340.543774) (xy 129.679942 -340.584967) (xy 129.709408 -340.63082)
			(xy 129.732049 -340.6804) (xy 129.747404 -340.732696) (xy 129.75516 -340.786646) (xy 129.755646 -340.813898)
			(xy 129.75512 -340.843803) (xy 129.745801 -340.902882) (xy 129.737104 -340.9315) (xy 129.733129 -340.945424)
			(xy 129.732206 -340.974348) (xy 129.739458 -341.002364) (xy 129.754299 -341.027207) (xy 129.77553 -341.046872)
			(xy 129.801436 -341.05977) (xy 129.81559 -341.062818) (xy 129.841657 -341.068015) (xy 129.892161 -341.084581)
			(xy 129.939874 -341.108) (xy 129.983873 -341.137818) (xy 130.023305 -341.173458) (xy 130.057405 -341.214228)
			(xy 130.085512 -341.259339) (xy 130.107083 -341.307916) (xy 130.121698 -341.359018) (xy 130.129076 -341.411654)
			(xy 130.129534 -341.43823) (xy 130.129048 -341.465481) (xy 130.121292 -341.519429) (xy 130.105937 -341.571724)
			(xy 130.083295 -341.621301) (xy 130.053829 -341.667151) (xy 130.018138 -341.708342) (xy 129.976947 -341.744033)
			(xy 129.931097 -341.773499) (xy 129.88152 -341.796141) (xy 129.829225 -341.811496) (xy 129.775277 -341.819252)
			(xy 129.720775 -341.819252) (xy 129.666827 -341.811496) (xy 129.614532 -341.796141) (xy 129.564955 -341.773499)
			(xy 129.519105 -341.744033) (xy 129.477914 -341.708342) (xy 129.442223 -341.667151) (xy 129.412757 -341.621301)
			(xy 129.390115 -341.571724) (xy 129.37476 -341.519429) (xy 129.367004 -341.465481) (xy 129.366518 -341.43823)
			(xy 129.367048 -341.408325) (xy 129.376364 -341.349246) (xy 129.38506 -341.320628) (xy 129.389144 -341.306731)
			(xy 129.390052 -341.27779) (xy 129.382781 -341.249762) (xy 129.367918 -341.224911) (xy 129.346665 -341.205246)
			(xy 129.320738 -341.192354) (xy 129.306574 -341.18931) (xy 129.273733 -341.182734) (xy 129.210882 -341.159606)
			(xy 129.181606 -341.143336) (xy 129.168622 -341.136337) (xy 129.139993 -341.1293) (xy 129.110547 -341.130739)
			(xy 129.082741 -341.140534) (xy 129.058894 -341.157867) (xy 129.040995 -341.181292) (xy 129.035302 -341.194898)
			(xy 129.02462 -341.22168) (xy 128.996331 -341.271923) (xy 128.9608 -341.317334) (xy 128.918836 -341.356877)
			(xy 128.871397 -341.38965) (xy 128.819563 -341.414906) (xy 128.764518 -341.43207) (xy 128.707516 -341.44075)
			(xy 128.678686 -341.441278) (xy 128.651433 -341.440851) (xy 128.597483 -341.433092) (xy 128.545186 -341.417735)
			(xy 128.495606 -341.395091) (xy 128.449754 -341.365622) (xy 128.408562 -341.329928) (xy 128.372869 -341.288735)
			(xy 128.343402 -341.242881) (xy 128.32076 -341.193301) (xy 128.305405 -341.141003) (xy 128.297648 -341.087053)
			(xy 127.977484 -341.087053) (xy 127.95495 -341.118469) (xy 127.913284 -341.160773) (xy 127.889762 -341.178896)
			(xy 127.879128 -341.187289) (xy 127.862426 -341.208611) (xy 127.851913 -341.233572) (xy 127.848327 -341.260418)
			(xy 127.851922 -341.287263) (xy 127.862444 -341.31222) (xy 127.879153 -341.333536) (xy 127.889762 -341.341964)
			(xy 127.913247 -341.360131) (xy 127.954911 -341.402427) (xy 127.989519 -341.450668) (xy 128.016237 -341.503687)
			(xy 128.034418 -341.560205) (xy 128.043625 -341.618857) (xy 128.044194 -341.648542) (xy 128.043708 -341.675793)
			(xy 128.035952 -341.729741) (xy 128.020597 -341.782036) (xy 127.997955 -341.831613) (xy 127.968489 -341.877463)
			(xy 127.932798 -341.918654) (xy 127.891607 -341.954345) (xy 127.845757 -341.983811) (xy 127.79618 -342.006453)
			(xy 127.743885 -342.021808) (xy 127.689937 -342.029564) (xy 127.635435 -342.029564) (xy 127.581487 -342.021808)
			(xy 127.529192 -342.006453) (xy 127.479615 -341.983811) (xy 127.433765 -341.954345) (xy 127.392574 -341.918654)
			(xy 127.356883 -341.877463) (xy 127.327417 -341.831613) (xy 127.304775 -341.782036) (xy 127.28942 -341.729741)
			(xy 127.281664 -341.675793) (xy 127.281178 -341.648542) (xy 89.263228 -341.648542) (xy 89.251269 -341.667151)
			(xy 89.215578 -341.708342) (xy 89.174387 -341.744033) (xy 89.128537 -341.773499) (xy 89.07896 -341.796141)
			(xy 89.026665 -341.811496) (xy 88.972717 -341.819252) (xy 88.918215 -341.819252) (xy 88.864267 -341.811496)
			(xy 88.811972 -341.796141) (xy 88.762395 -341.773499) (xy 88.716545 -341.744033) (xy 88.675354 -341.708342)
			(xy 88.639663 -341.667151) (xy 88.610197 -341.621301) (xy 88.587555 -341.571724) (xy 88.5722 -341.519429)
			(xy 88.564444 -341.465481) (xy 88.563958 -341.43823) (xy 88.564491 -341.408325) (xy 88.573805 -341.349246)
			(xy 88.5825 -341.320628) (xy 88.586553 -341.306724) (xy 88.587459 -341.277789) (xy 88.580191 -341.249768)
			(xy 88.565335 -341.224921) (xy 88.544091 -341.205255) (xy 88.518173 -341.192358) (xy 88.504014 -341.18931)
			(xy 88.471175 -341.182725) (xy 88.408323 -341.159603) (xy 88.379046 -341.143336) (xy 88.366097 -341.136266)
			(xy 88.337454 -341.12924) (xy 88.307998 -341.130691) (xy 88.280185 -341.140499) (xy 88.256334 -341.157846)
			(xy 88.238434 -341.181286) (xy 88.232742 -341.194898) (xy 88.222026 -341.221666) (xy 88.193742 -341.271908)
			(xy 88.158215 -341.317317) (xy 88.116256 -341.356861) (xy 88.068821 -341.389635) (xy 88.016993 -341.414895)
			(xy 87.961952 -341.432062) (xy 87.904954 -341.440747) (xy 87.876126 -341.441278) (xy 87.84887 -341.440877)
			(xy 87.794912 -341.433122) (xy 87.742607 -341.417767) (xy 87.693019 -341.395124) (xy 87.647159 -341.365655)
			(xy 87.60596 -341.329958) (xy 87.570261 -341.288762) (xy 87.540788 -341.242904) (xy 87.518142 -341.193318)
			(xy 87.502783 -341.141014) (xy 87.495025 -341.087056) (xy 87.174939 -341.087056) (xy 87.152399 -341.118473)
			(xy 87.110727 -341.160775) (xy 87.087202 -341.178896) (xy 87.076564 -341.187287) (xy 87.059855 -341.208607)
			(xy 87.049338 -341.233569) (xy 87.045751 -341.260418) (xy 87.049347 -341.287266) (xy 87.059874 -341.312224)
			(xy 87.07659 -341.333538) (xy 87.087202 -341.341964) (xy 87.110696 -341.36012) (xy 87.152357 -341.40242)
			(xy 87.186963 -341.450663) (xy 87.213679 -341.503684) (xy 87.231859 -341.560203) (xy 87.241065 -341.618856)
			(xy 87.241634 -341.648542) (xy 87.241148 -341.675793) (xy 87.233392 -341.729741) (xy 87.218037 -341.782036)
			(xy 87.195395 -341.831613) (xy 87.165929 -341.877463) (xy 87.130238 -341.918654) (xy 87.089047 -341.954345)
			(xy 87.043197 -341.983811) (xy 86.99362 -342.006453) (xy 86.941325 -342.021808) (xy 86.887377 -342.029564)
			(xy 86.832875 -342.029564) (xy 86.778927 -342.021808) (xy 86.726632 -342.006453) (xy 86.677055 -341.983811)
			(xy 86.631205 -341.954345) (xy 86.590014 -341.918654) (xy 86.554323 -341.877463) (xy 86.524857 -341.831613)
			(xy 86.502215 -341.782036) (xy 86.48686 -341.729741) (xy 86.479104 -341.675793) (xy 86.478618 -341.648542)
			(xy 76.426568 -341.648542) (xy 76.426568 -344.386662) (xy 76.764134 -344.386662) (xy 76.76463 -344.358787)
			(xy 76.772738 -344.30363) (xy 76.78879 -344.250241) (xy 76.812445 -344.199758) (xy 76.843197 -344.153257)
			(xy 76.861416 -344.132154) (xy 76.870999 -344.120785) (xy 76.883633 -344.093879) (xy 76.887962 -344.064472)
			(xy 76.883617 -344.035068) (xy 76.870968 -344.008169) (xy 76.861416 -343.996772) (xy 76.843231 -343.975642)
			(xy 76.812482 -343.929145) (xy 76.788826 -343.878668) (xy 76.772767 -343.825287) (xy 76.764646 -343.770136)
			(xy 76.764134 -343.742264) (xy 76.76462 -343.715013) (xy 76.772376 -343.661065) (xy 76.787731 -343.60877)
			(xy 76.810373 -343.559193) (xy 76.839839 -343.513343) (xy 76.87553 -343.472152) (xy 76.916721 -343.436461)
			(xy 76.962571 -343.406995) (xy 77.012148 -343.384353) (xy 77.064443 -343.368998) (xy 77.118391 -343.361242)
			(xy 77.172893 -343.361242) (xy 77.226841 -343.368998) (xy 77.279136 -343.384353) (xy 77.328713 -343.406995)
			(xy 77.374563 -343.436461) (xy 77.415754 -343.472152) (xy 77.451445 -343.513343) (xy 77.480911 -343.559193)
			(xy 77.503553 -343.60877) (xy 77.518908 -343.661065) (xy 77.526664 -343.715013) (xy 77.52715 -343.742264)
			(xy 77.526649 -343.770139) (xy 77.518539 -343.825295) (xy 77.502486 -343.878683) (xy 77.478834 -343.929165)
			(xy 77.448085 -343.975667) (xy 77.429868 -343.996772) (xy 77.420413 -344.008221) (xy 77.407861 -344.035111)
			(xy 77.403551 -344.064472) (xy 77.404598 -344.071632) (xy 96.449892 -344.071632) (xy 96.449892 -343.986936)
			(xy 96.457943 -343.902622) (xy 96.473972 -343.819456) (xy 96.497833 -343.738189) (xy 96.529312 -343.659559)
			(xy 96.568123 -343.584278) (xy 96.613913 -343.513026) (xy 96.666269 -343.44645) (xy 96.724717 -343.385152)
			(xy 96.788727 -343.329687) (xy 96.857719 -343.280558) (xy 96.931069 -343.238209) (xy 97.008112 -343.203025)
			(xy 97.088151 -343.175323) (xy 97.17046 -343.155355) (xy 97.254295 -343.143302) (xy 97.338896 -343.139272)
			(xy 97.423497 -343.143302) (xy 97.507332 -343.155355) (xy 97.589641 -343.175323) (xy 97.66968 -343.203025)
			(xy 97.746723 -343.238209) (xy 97.820073 -343.280558) (xy 97.889065 -343.329687) (xy 97.953075 -343.385152)
			(xy 98.011523 -343.44645) (xy 98.063879 -343.513026) (xy 98.109669 -343.584278) (xy 98.14848 -343.659559)
			(xy 98.179959 -343.738189) (xy 98.20382 -343.819456) (xy 98.219849 -343.902622) (xy 98.2279 -343.986936)
			(xy 98.228404 -344.029284) (xy 98.974405 -344.029284) (xy 98.978441 -343.945837) (xy 98.990513 -343.863169)
			(xy 99.010506 -343.782052) (xy 99.038235 -343.703243) (xy 99.073441 -343.627478) (xy 99.115795 -343.555465)
			(xy 99.164901 -343.487876) (xy 99.220302 -343.425342) (xy 99.281479 -343.368447) (xy 99.347862 -343.317721)
			(xy 99.41883 -343.27364) (xy 99.493722 -343.236614) (xy 99.571838 -343.206988) (xy 99.652448 -343.18504)
			(xy 99.7348 -343.170975) (xy 99.818126 -343.164923) (xy 99.901646 -343.166942) (xy 99.984582 -343.177012)
			(xy 100.066158 -343.19504) (xy 100.145614 -343.220857) (xy 100.222207 -343.254222) (xy 100.295223 -343.294823)
			(xy 100.363979 -343.342282) (xy 100.427833 -343.396155) (xy 100.48619 -343.45594) (xy 100.538505 -343.521077)
			(xy 100.584288 -343.59096) (xy 100.623113 -343.664935) (xy 100.654618 -343.742312) (xy 100.678507 -343.822369)
			(xy 100.694558 -343.904357) (xy 100.702621 -343.987512) (xy 100.703126 -344.029284) (xy 100.702621 -344.071056)
			(xy 100.702565 -344.071632) (xy 104.010456 -344.071632) (xy 104.010456 -343.986936) (xy 104.018507 -343.902622)
			(xy 104.034536 -343.819456) (xy 104.058397 -343.738189) (xy 104.089876 -343.659559) (xy 104.128687 -343.584278)
			(xy 104.174477 -343.513026) (xy 104.226833 -343.44645) (xy 104.285281 -343.385152) (xy 104.349291 -343.329687)
			(xy 104.418283 -343.280558) (xy 104.491633 -343.238209) (xy 104.568676 -343.203025) (xy 104.648715 -343.175323)
			(xy 104.731024 -343.155355) (xy 104.814859 -343.143302) (xy 104.89946 -343.139272) (xy 104.984061 -343.143302)
			(xy 105.067896 -343.155355) (xy 105.150205 -343.175323) (xy 105.230244 -343.203025) (xy 105.307287 -343.238209)
			(xy 105.380637 -343.280558) (xy 105.449629 -343.329687) (xy 105.513639 -343.385152) (xy 105.572087 -343.44645)
			(xy 105.624443 -343.513026) (xy 105.670233 -343.584278) (xy 105.709044 -343.659559) (xy 105.740523 -343.738189)
			(xy 105.764384 -343.819456) (xy 105.780413 -343.902622) (xy 105.788464 -343.986936) (xy 105.788968 -344.029284)
			(xy 106.534969 -344.029284) (xy 106.539005 -343.945837) (xy 106.551077 -343.863169) (xy 106.57107 -343.782052)
			(xy 106.598799 -343.703243) (xy 106.634005 -343.627478) (xy 106.676359 -343.555465) (xy 106.725465 -343.487876)
			(xy 106.780866 -343.425342) (xy 106.842043 -343.368447) (xy 106.908426 -343.317721) (xy 106.979394 -343.27364)
			(xy 107.054286 -343.236614) (xy 107.132402 -343.206988) (xy 107.213012 -343.18504) (xy 107.295364 -343.170975)
			(xy 107.37869 -343.164923) (xy 107.46221 -343.166942) (xy 107.545146 -343.177012) (xy 107.626722 -343.19504)
			(xy 107.706178 -343.220857) (xy 107.782771 -343.254222) (xy 107.855787 -343.294823) (xy 107.924543 -343.342282)
			(xy 107.988397 -343.396155) (xy 108.046754 -343.45594) (xy 108.099069 -343.521077) (xy 108.144852 -343.59096)
			(xy 108.183677 -343.664935) (xy 108.215182 -343.742312) (xy 108.239071 -343.822369) (xy 108.255122 -343.904357)
			(xy 108.263185 -343.987512) (xy 108.26369 -344.029284) (xy 108.263185 -344.071056) (xy 108.263129 -344.071632)
			(xy 111.7158 -344.071632) (xy 111.7158 -343.986936) (xy 111.723851 -343.902622) (xy 111.73988 -343.819456)
			(xy 111.763741 -343.738189) (xy 111.79522 -343.659559) (xy 111.834031 -343.584278) (xy 111.879821 -343.513026)
			(xy 111.932177 -343.44645) (xy 111.990625 -343.385152) (xy 112.054635 -343.329687) (xy 112.123627 -343.280558)
			(xy 112.196977 -343.238209) (xy 112.27402 -343.203025) (xy 112.354059 -343.175323) (xy 112.436368 -343.155355)
			(xy 112.520203 -343.143302) (xy 112.604804 -343.139272) (xy 112.689405 -343.143302) (xy 112.77324 -343.155355)
			(xy 112.855549 -343.175323) (xy 112.935588 -343.203025) (xy 113.012631 -343.238209) (xy 113.085981 -343.280558)
			(xy 113.154973 -343.329687) (xy 113.218983 -343.385152) (xy 113.277431 -343.44645) (xy 113.329787 -343.513026)
			(xy 113.375577 -343.584278) (xy 113.414388 -343.659559) (xy 113.445867 -343.738189) (xy 113.469728 -343.819456)
			(xy 113.485757 -343.902622) (xy 113.493808 -343.986936) (xy 113.494312 -344.029284) (xy 114.240313 -344.029284)
			(xy 114.244349 -343.945837) (xy 114.256421 -343.863169) (xy 114.276414 -343.782052) (xy 114.304143 -343.703243)
			(xy 114.339349 -343.627478) (xy 114.381703 -343.555465) (xy 114.430809 -343.487876) (xy 114.48621 -343.425342)
			(xy 114.547387 -343.368447) (xy 114.61377 -343.317721) (xy 114.684738 -343.27364) (xy 114.75963 -343.236614)
			(xy 114.837746 -343.206988) (xy 114.918356 -343.18504) (xy 115.000708 -343.170975) (xy 115.084034 -343.164923)
			(xy 115.167554 -343.166942) (xy 115.25049 -343.177012) (xy 115.332066 -343.19504) (xy 115.411522 -343.220857)
			(xy 115.488115 -343.254222) (xy 115.561131 -343.294823) (xy 115.629887 -343.342282) (xy 115.693741 -343.396155)
			(xy 115.752098 -343.45594) (xy 115.804413 -343.521077) (xy 115.850196 -343.59096) (xy 115.889021 -343.664935)
			(xy 115.920526 -343.742312) (xy 115.944415 -343.822369) (xy 115.960466 -343.904357) (xy 115.964765 -343.948696)
			(xy 119.176796 -343.948696) (xy 119.176796 -343.864) (xy 119.184847 -343.779686) (xy 119.200876 -343.69652)
			(xy 119.224737 -343.615253) (xy 119.256216 -343.536623) (xy 119.295027 -343.461342) (xy 119.340817 -343.39009)
			(xy 119.393173 -343.323514) (xy 119.451621 -343.262216) (xy 119.515631 -343.206751) (xy 119.584623 -343.157622)
			(xy 119.657973 -343.115273) (xy 119.735016 -343.080089) (xy 119.815055 -343.052387) (xy 119.897364 -343.032419)
			(xy 119.981199 -343.020366) (xy 120.0658 -343.016336) (xy 120.150401 -343.020366) (xy 120.234236 -343.032419)
			(xy 120.316545 -343.052387) (xy 120.396584 -343.080089) (xy 120.473627 -343.115273) (xy 120.546977 -343.157622)
			(xy 120.615969 -343.206751) (xy 120.679979 -343.262216) (xy 120.738427 -343.323514) (xy 120.790783 -343.39009)
			(xy 120.836573 -343.461342) (xy 120.875384 -343.536623) (xy 120.906863 -343.615253) (xy 120.930724 -343.69652)
			(xy 120.946753 -343.779686) (xy 120.954804 -343.864) (xy 120.955308 -343.906348) (xy 121.701309 -343.906348)
			(xy 121.705345 -343.822901) (xy 121.717417 -343.740233) (xy 121.73741 -343.659116) (xy 121.765139 -343.580307)
			(xy 121.800345 -343.504542) (xy 121.842699 -343.432529) (xy 121.891805 -343.36494) (xy 121.947206 -343.302406)
			(xy 122.008383 -343.245511) (xy 122.074766 -343.194785) (xy 122.145734 -343.150704) (xy 122.220626 -343.113678)
			(xy 122.298742 -343.084052) (xy 122.379352 -343.062104) (xy 122.461704 -343.048039) (xy 122.54503 -343.041987)
			(xy 122.62855 -343.044006) (xy 122.711486 -343.054076) (xy 122.793062 -343.072104) (xy 122.872518 -343.097921)
			(xy 122.949111 -343.131286) (xy 123.022127 -343.171887) (xy 123.090883 -343.219346) (xy 123.154737 -343.273219)
			(xy 123.213094 -343.333004) (xy 123.265409 -343.398141) (xy 123.311192 -343.468024) (xy 123.350017 -343.541999)
			(xy 123.381522 -343.619376) (xy 123.405411 -343.699433) (xy 123.421462 -343.781421) (xy 123.429525 -343.864576)
			(xy 123.43003 -343.906348) (xy 123.429525 -343.94812) (xy 123.421462 -344.031275) (xy 123.405411 -344.113263)
			(xy 123.381522 -344.19332) (xy 123.350017 -344.270697) (xy 123.311192 -344.344672) (xy 123.28984 -344.377264)
			(xy 133.84403 -344.377264) (xy 133.844468 -344.349893) (xy 133.852291 -344.295712) (xy 133.867787 -344.243208)
			(xy 133.890635 -344.193462) (xy 133.920366 -344.147497) (xy 133.93801 -344.126566) (xy 133.947281 -344.115264)
			(xy 133.959453 -344.088697) (xy 133.963618 -344.059773) (xy 133.959437 -344.030851) (xy 133.947251 -344.00429)
			(xy 133.93801 -343.992962) (xy 133.920388 -343.972016) (xy 133.890673 -343.926047) (xy 133.867834 -343.876303)
			(xy 133.852339 -343.823806) (xy 133.844506 -343.769632) (xy 133.84403 -343.742264) (xy 133.844516 -343.715013)
			(xy 133.852272 -343.661065) (xy 133.867627 -343.60877) (xy 133.890269 -343.559193) (xy 133.919735 -343.513343)
			(xy 133.955426 -343.472152) (xy 133.996617 -343.436461) (xy 134.042467 -343.406995) (xy 134.092044 -343.384353)
			(xy 134.144339 -343.368998) (xy 134.198287 -343.361242) (xy 134.252789 -343.361242) (xy 134.306737 -343.368998)
			(xy 134.359032 -343.384353) (xy 134.408609 -343.406995) (xy 134.454459 -343.436461) (xy 134.485224 -343.463118)
			(xy 143.511522 -343.463118) (xy 143.515593 -343.407496) (xy 143.527719 -343.353059) (xy 143.547642 -343.300968)
			(xy 143.574938 -343.252333) (xy 143.609024 -343.20819) (xy 143.649173 -343.169481) (xy 143.694531 -343.13703)
			(xy 143.744131 -343.111529) (xy 143.796915 -343.093522) (xy 143.851758 -343.083392) (xy 143.907492 -343.081355)
			(xy 143.962929 -343.087455) (xy 144.016886 -343.101561) (xy 144.068215 -343.123373) (xy 144.115821 -343.152427)
			(xy 144.158689 -343.188102) (xy 144.195906 -343.229639) (xy 144.226679 -343.276152) (xy 144.250351 -343.326649)
			(xy 144.266419 -343.380056) (xy 144.274539 -343.435232) (xy 144.275048 -343.463118) (xy 144.274539 -343.491004)
			(xy 144.26855 -343.531698) (xy 144.792952 -343.531698) (xy 144.797023 -343.476076) (xy 144.809149 -343.421639)
			(xy 144.829072 -343.369548) (xy 144.856368 -343.320913) (xy 144.890454 -343.27677) (xy 144.930603 -343.238061)
			(xy 144.975961 -343.20561) (xy 145.025561 -343.180109) (xy 145.078345 -343.162102) (xy 145.133188 -343.151972)
			(xy 145.188922 -343.149935) (xy 145.244359 -343.156035) (xy 145.298316 -343.170141) (xy 145.349645 -343.191953)
			(xy 145.397251 -343.221007) (xy 145.440119 -343.256682) (xy 145.477336 -343.298219) (xy 145.508109 -343.344732)
			(xy 145.531781 -343.395229) (xy 145.547849 -343.448636) (xy 145.555969 -343.503812) (xy 145.556478 -343.531698)
			(xy 145.555969 -343.559584) (xy 145.547849 -343.61476) (xy 145.531781 -343.668167) (xy 145.508109 -343.718664)
			(xy 145.477336 -343.765177) (xy 145.440119 -343.806714) (xy 145.397251 -343.842389) (xy 145.349645 -343.871443)
			(xy 145.298316 -343.893255) (xy 145.244359 -343.907361) (xy 145.188922 -343.913461) (xy 145.133188 -343.911424)
			(xy 145.078345 -343.901294) (xy 145.025561 -343.883287) (xy 144.975961 -343.857786) (xy 144.930603 -343.825335)
			(xy 144.890454 -343.786626) (xy 144.856368 -343.742483) (xy 144.829072 -343.693848) (xy 144.809149 -343.641757)
			(xy 144.797023 -343.58732) (xy 144.792952 -343.531698) (xy 144.26855 -343.531698) (xy 144.266419 -343.54618)
			(xy 144.250351 -343.599587) (xy 144.226679 -343.650084) (xy 144.195906 -343.696597) (xy 144.158689 -343.738134)
			(xy 144.115821 -343.773809) (xy 144.068215 -343.802863) (xy 144.016886 -343.824675) (xy 143.962929 -343.838781)
			(xy 143.907492 -343.844881) (xy 143.851758 -343.842844) (xy 143.796915 -343.832714) (xy 143.744131 -343.814707)
			(xy 143.694531 -343.789206) (xy 143.649173 -343.756755) (xy 143.609024 -343.718046) (xy 143.574938 -343.673903)
			(xy 143.547642 -343.625268) (xy 143.527719 -343.573177) (xy 143.515593 -343.51874) (xy 143.511522 -343.463118)
			(xy 134.485224 -343.463118) (xy 134.49565 -343.472152) (xy 134.531341 -343.513343) (xy 134.560807 -343.559193)
			(xy 134.583449 -343.60877) (xy 134.598804 -343.661065) (xy 134.60656 -343.715013) (xy 134.607046 -343.742264)
			(xy 134.606572 -343.769634) (xy 134.598758 -343.823813) (xy 134.583272 -343.876317) (xy 134.560431 -343.926064)
			(xy 134.530707 -343.972031) (xy 134.513066 -343.992962) (xy 134.503867 -344.004316) (xy 134.491689 -344.030865)
			(xy 134.487511 -344.059773) (xy 134.491674 -344.088683) (xy 134.503837 -344.115238) (xy 134.513066 -344.126566)
			(xy 134.530697 -344.147504) (xy 134.560411 -344.193475) (xy 134.583249 -344.243221) (xy 134.598742 -344.29572)
			(xy 134.606572 -344.349895) (xy 134.607046 -344.377264) (xy 134.60656 -344.404515) (xy 134.598804 -344.458463)
			(xy 134.583449 -344.510758) (xy 134.560807 -344.560335) (xy 134.531341 -344.606185) (xy 134.49565 -344.647376)
			(xy 134.454459 -344.683067) (xy 134.408609 -344.712533) (xy 134.359032 -344.735175) (xy 134.306737 -344.75053)
			(xy 134.252789 -344.758286) (xy 134.198287 -344.758286) (xy 134.144339 -344.75053) (xy 134.092044 -344.735175)
			(xy 134.042467 -344.712533) (xy 133.996617 -344.683067) (xy 133.955426 -344.647376) (xy 133.919735 -344.606185)
			(xy 133.890269 -344.560335) (xy 133.867627 -344.510758) (xy 133.852272 -344.458463) (xy 133.844516 -344.404515)
			(xy 133.84403 -344.377264) (xy 123.28984 -344.377264) (xy 123.265409 -344.414555) (xy 123.213094 -344.479692)
			(xy 123.154737 -344.539477) (xy 123.090883 -344.59335) (xy 123.022127 -344.640809) (xy 122.949111 -344.68141)
			(xy 122.872518 -344.714775) (xy 122.793062 -344.740592) (xy 122.711486 -344.75862) (xy 122.62855 -344.76869)
			(xy 122.54503 -344.770709) (xy 122.461704 -344.764657) (xy 122.379352 -344.750592) (xy 122.298742 -344.728644)
			(xy 122.220626 -344.699018) (xy 122.145734 -344.661992) (xy 122.074766 -344.617911) (xy 122.008383 -344.567185)
			(xy 121.947206 -344.51029) (xy 121.891805 -344.447756) (xy 121.842699 -344.380167) (xy 121.800345 -344.308154)
			(xy 121.765139 -344.232389) (xy 121.73741 -344.15358) (xy 121.717417 -344.072463) (xy 121.705345 -343.989795)
			(xy 121.701309 -343.906348) (xy 120.955308 -343.906348) (xy 120.954804 -343.948696) (xy 120.946753 -344.03301)
			(xy 120.930724 -344.116176) (xy 120.906863 -344.197443) (xy 120.875384 -344.276073) (xy 120.836573 -344.351354)
			(xy 120.790783 -344.422606) (xy 120.738427 -344.489182) (xy 120.679979 -344.55048) (xy 120.615969 -344.605945)
			(xy 120.546977 -344.655074) (xy 120.473627 -344.697423) (xy 120.396584 -344.732607) (xy 120.316545 -344.760309)
			(xy 120.23579 -344.7799) (xy 138.092587 -344.7799) (xy 138.096756 -344.724274) (xy 138.109169 -344.669891)
			(xy 138.129549 -344.617966) (xy 138.15744 -344.569658) (xy 138.19222 -344.526046) (xy 138.233112 -344.488106)
			(xy 138.279202 -344.456684) (xy 138.32946 -344.432482) (xy 138.382764 -344.416042) (xy 138.437923 -344.40773)
			(xy 138.465814 -344.407236) (xy 138.493148 -344.407663) (xy 138.547229 -344.41564) (xy 138.599565 -344.431436)
			(xy 138.649029 -344.454711) (xy 138.694561 -344.484966) (xy 138.735182 -344.52155) (xy 138.77002 -344.563679)
			(xy 138.784584 -344.586814) (xy 138.792541 -344.599014) (xy 138.814004 -344.618683) (xy 138.840148 -344.63149)
			(xy 138.868845 -344.636392) (xy 138.897758 -344.63299) (xy 138.91133 -344.627708) (xy 138.934539 -344.618217)
			(xy 138.982873 -344.604867) (xy 139.032562 -344.598139) (xy 139.057634 -344.597736) (xy 139.082703 -344.59816)
			(xy 139.132386 -344.604909) (xy 139.180721 -344.618242) (xy 139.203938 -344.627708) (xy 139.217525 -344.632926)
			(xy 139.246421 -344.636297) (xy 139.275096 -344.631393) (xy 139.301229 -344.618611) (xy 139.322703 -344.598986)
			(xy 139.330684 -344.586814) (xy 139.345253 -344.563683) (xy 139.380096 -344.521562) (xy 139.420719 -344.484983)
			(xy 139.46625 -344.454732) (xy 139.515712 -344.431456) (xy 139.568043 -344.415656) (xy 139.622122 -344.40767)
			(xy 139.676786 -344.40767) (xy 139.730865 -344.415656) (xy 139.783196 -344.431456) (xy 139.832658 -344.454732)
			(xy 139.878189 -344.484983) (xy 139.918812 -344.521562) (xy 139.953655 -344.563683) (xy 139.968224 -344.586814)
			(xy 139.976143 -344.599041) (xy 139.997616 -344.61871) (xy 140.023771 -344.631514) (xy 140.052476 -344.636408)
			(xy 140.081396 -344.632996) (xy 140.09497 -344.627708) (xy 140.118187 -344.618236) (xy 140.166516 -344.604878)
			(xy 140.216203 -344.598143) (xy 140.241274 -344.597736) (xy 140.268118 -344.598183) (xy 140.32125 -344.605885)
			(xy 140.372727 -344.621134) (xy 140.421482 -344.643612) (xy 140.466505 -344.672856) (xy 140.506866 -344.70826)
			(xy 140.541726 -344.74909) (xy 140.570366 -344.7945) (xy 140.592192 -344.843551) (xy 140.599922 -344.869262)
			(xy 140.604566 -344.883766) (xy 140.621088 -344.909332) (xy 140.644408 -344.928897) (xy 140.672456 -344.940726)
			(xy 140.702743 -344.943768) (xy 140.732583 -344.937755) (xy 140.746226 -344.930984) (xy 140.774377 -344.916361)
			(xy 140.834326 -344.89563) (xy 140.896882 -344.885128) (xy 140.928598 -344.884502) (xy 140.946617 -344.884727)
			(xy 140.982492 -344.888158) (xy 141.000226 -344.89136) (xy 141.015432 -344.893723) (xy 141.045988 -344.890188)
			(xy 141.074107 -344.877721) (xy 141.097243 -344.85745) (xy 141.113299 -344.831213) (xy 141.117574 -344.81643)
			(xy 141.124994 -344.789393) (xy 141.146623 -344.737669) (xy 141.175586 -344.689666) (xy 141.21126 -344.646416)
			(xy 141.252876 -344.608849) (xy 141.29954 -344.577774) (xy 141.350247 -344.55386) (xy 141.403907 -344.53762)
			(xy 141.459366 -344.529404) (xy 141.487398 -344.528902) (xy 141.514651 -344.529357) (xy 141.568603 -344.537114)
			(xy 141.620902 -344.55247) (xy 141.670482 -344.575113) (xy 141.716336 -344.604582) (xy 141.757529 -344.640277)
			(xy 141.793223 -344.68147) (xy 141.82269 -344.727325) (xy 141.845332 -344.776906) (xy 141.860688 -344.829205)
			(xy 141.868443 -344.883157) (xy 141.868906 -344.91041) (xy 141.868376 -344.937982) (xy 141.860437 -344.992552)
			(xy 141.844724 -345.045411) (xy 141.821566 -345.095457) (xy 141.791445 -345.141648) (xy 141.754988 -345.183022)
			(xy 141.734286 -345.20124) (xy 141.72338 -345.211129) (xy 141.707311 -345.235783) (xy 141.69893 -345.263992)
			(xy 141.698932 -345.293421) (xy 141.707317 -345.321629) (xy 141.723389 -345.34628) (xy 141.734286 -345.35618)
			(xy 141.755002 -345.374385) (xy 141.791467 -345.415757) (xy 141.821594 -345.461948) (xy 141.844757 -345.511997)
			(xy 141.860472 -345.564859) (xy 141.868412 -345.619432) (xy 141.868411 -345.674581) (xy 141.860469 -345.729154)
			(xy 141.844752 -345.782016) (xy 141.843402 -345.784932) (xy 144.561812 -345.784932) (xy 144.565883 -345.72931)
			(xy 144.578009 -345.674873) (xy 144.597932 -345.622782) (xy 144.625228 -345.574147) (xy 144.659314 -345.530004)
			(xy 144.699463 -345.491295) (xy 144.744821 -345.458844) (xy 144.794421 -345.433343) (xy 144.847205 -345.415336)
			(xy 144.902048 -345.405206) (xy 144.957782 -345.403169) (xy 145.013219 -345.409269) (xy 145.067176 -345.423375)
			(xy 145.118505 -345.445187) (xy 145.166111 -345.474241) (xy 145.208979 -345.509916) (xy 145.246196 -345.551453)
			(xy 145.276969 -345.597966) (xy 145.300641 -345.648463) (xy 145.316709 -345.70187) (xy 145.324829 -345.757046)
			(xy 145.325338 -345.784932) (xy 145.324829 -345.812818) (xy 145.316709 -345.867994) (xy 145.300641 -345.921401)
			(xy 145.276969 -345.971898) (xy 145.246196 -346.018411) (xy 145.208979 -346.059948) (xy 145.166111 -346.095623)
			(xy 145.118505 -346.124677) (xy 145.067176 -346.146489) (xy 145.013219 -346.160595) (xy 144.957782 -346.166695)
			(xy 144.902048 -346.164658) (xy 144.847205 -346.154528) (xy 144.794421 -346.136521) (xy 144.744821 -346.11102)
			(xy 144.699463 -346.078569) (xy 144.659314 -346.03986) (xy 144.625228 -345.995717) (xy 144.597932 -345.947082)
			(xy 144.578009 -345.894991) (xy 144.565883 -345.840554) (xy 144.561812 -345.784932) (xy 141.843402 -345.784932)
			(xy 141.821588 -345.832063) (xy 141.791459 -345.878254) (xy 141.754993 -345.919625) (xy 141.734286 -345.93784)
			(xy 141.72338 -345.947729) (xy 141.707311 -345.972383) (xy 141.69893 -346.000592) (xy 141.698932 -346.030021)
			(xy 141.707317 -346.058229) (xy 141.723389 -346.08288) (xy 141.734286 -346.09278) (xy 141.754988 -346.111001)
			(xy 141.791459 -346.152368) (xy 141.821593 -346.198555) (xy 141.844761 -346.248601) (xy 141.860479 -346.301462)
			(xy 141.86842 -346.356036) (xy 141.868906 -346.38361) (xy 141.868432 -346.410862) (xy 141.860674 -346.46481)
			(xy 141.845317 -346.517105) (xy 141.822675 -346.566682) (xy 141.793207 -346.612533) (xy 141.757514 -346.653723)
			(xy 141.716323 -346.689414) (xy 141.670472 -346.71888) (xy 141.620894 -346.741521) (xy 141.568598 -346.756876)
			(xy 141.51465 -346.764632) (xy 141.487398 -346.765118) (xy 141.459543 -346.764584) (xy 141.404429 -346.75646)
			(xy 141.35108 -346.740415) (xy 141.300628 -346.716789) (xy 141.254143 -346.686084) (xy 141.212614 -346.64895)
			(xy 141.17692 -346.606177) (xy 141.14782 -346.558672) (xy 141.125931 -346.507442) (xy 141.118336 -346.480638)
			(xy 141.114074 -346.466517) (xy 141.098685 -346.441368) (xy 141.076764 -346.42165) (xy 141.050131 -346.409)
			(xy 141.020997 -346.404469) (xy 141.006322 -346.405962) (xy 140.993305 -346.407627) (xy 140.967121 -346.40941)
			(xy 140.953998 -346.409518) (xy 140.939849 -346.409424) (xy 140.911626 -346.40739) (xy 140.89761 -346.405454)
			(xy 140.884268 -346.403791) (xy 140.857565 -346.406899) (xy 140.832604 -346.416882) (xy 140.811121 -346.433043)
			(xy 140.794611 -346.454258) (xy 140.784222 -346.479052) (xy 140.78204 -346.492322) (xy 140.777912 -346.519469)
			(xy 140.762943 -346.572297) (xy 140.740556 -346.622434) (xy 140.711213 -346.668844) (xy 140.67552 -346.710569)
			(xy 140.634215 -346.746746) (xy 140.588151 -346.776628) (xy 140.538278 -346.799598) (xy 140.485628 -346.815183)
			(xy 140.431288 -346.823058) (xy 140.403834 -346.823538) (xy 140.376583 -346.823013) (xy 140.322636 -346.815262)
			(xy 140.270341 -346.799911) (xy 140.220763 -346.777275) (xy 140.174911 -346.747813) (xy 140.133719 -346.712126)
			(xy 140.098025 -346.67094) (xy 140.068556 -346.625093) (xy 140.045911 -346.575519) (xy 140.030552 -346.523226)
			(xy 140.022791 -346.469281) (xy 140.022326 -346.44203) (xy 140.022803 -346.414456) (xy 140.030752 -346.359883)
			(xy 140.046474 -346.307023) (xy 140.069642 -346.256977) (xy 140.099773 -346.210787) (xy 140.136239 -346.169416)
			(xy 140.156946 -346.1512) (xy 140.167817 -346.141273) (xy 140.183899 -346.116633) (xy 140.192291 -346.088431)
			(xy 140.192296 -346.059007) (xy 140.183915 -346.030802) (xy 140.167843 -346.006156) (xy 140.156946 -345.99626)
			(xy 140.13627 -345.978011) (xy 140.099795 -345.936651) (xy 140.069657 -345.89047) (xy 140.046485 -345.840429)
			(xy 140.030762 -345.787573) (xy 140.022815 -345.733003) (xy 140.022326 -345.70543) (xy 140.022752 -345.678928)
			(xy 140.030103 -345.626435) (xy 140.044654 -345.575467) (xy 140.066123 -345.527005) (xy 140.094098 -345.481984)
			(xy 140.110718 -345.461336) (xy 140.120186 -345.449208) (xy 140.131978 -345.420802) (xy 140.1348 -345.390175)
			(xy 140.128399 -345.360092) (xy 140.113351 -345.333268) (xy 140.091015 -345.312124) (xy 140.077444 -345.304872)
			(xy 140.05375 -345.292778) (xy 140.009769 -345.262853) (xy 139.970489 -345.22698) (xy 139.936707 -345.185888)
			(xy 139.922504 -345.163394) (xy 139.914556 -345.151187) (xy 139.893091 -345.131517) (xy 139.866945 -345.11871)
			(xy 139.838245 -345.11381) (xy 139.809331 -345.117216) (xy 139.795758 -345.1225) (xy 139.77255 -345.131995)
			(xy 139.724216 -345.145344) (xy 139.674526 -345.15207) (xy 139.649454 -345.152472) (xy 139.624385 -345.152051)
			(xy 139.574701 -345.1453) (xy 139.526367 -345.131967) (xy 139.50315 -345.1225) (xy 139.489568 -345.117266)
			(xy 139.46067 -345.113897) (xy 139.431992 -345.118804) (xy 139.405858 -345.13159) (xy 139.384384 -345.15122)
			(xy 139.376404 -345.163394) (xy 139.361835 -345.186525) (xy 139.326992 -345.228646) (xy 139.286369 -345.265225)
			(xy 139.240838 -345.295476) (xy 139.191376 -345.318752) (xy 139.139045 -345.334552) (xy 139.084966 -345.342538)
			(xy 139.030302 -345.342538) (xy 138.976223 -345.334552) (xy 138.923892 -345.318752) (xy 138.87443 -345.295476)
			(xy 138.828899 -345.265225) (xy 138.788276 -345.228646) (xy 138.753433 -345.186525) (xy 138.738864 -345.163394)
			(xy 138.730954 -345.15116) (xy 138.709479 -345.13149) (xy 138.683322 -345.118687) (xy 138.654614 -345.113794)
			(xy 138.625692 -345.11721) (xy 138.612118 -345.1225) (xy 138.588903 -345.131976) (xy 138.540573 -345.145332)
			(xy 138.490885 -345.152066) (xy 138.465814 -345.152472) (xy 138.437923 -345.15207) (xy 138.382764 -345.143758)
			(xy 138.32946 -345.127318) (xy 138.279202 -345.103116) (xy 138.233112 -345.071694) (xy 138.19222 -345.033754)
			(xy 138.15744 -344.990143) (xy 138.129549 -344.941834) (xy 138.109169 -344.889909) (xy 138.096756 -344.835526)
			(xy 138.092587 -344.7799) (xy 120.23579 -344.7799) (xy 120.234236 -344.780277) (xy 120.150401 -344.79233)
			(xy 120.0658 -344.796361) (xy 119.981199 -344.79233) (xy 119.897364 -344.780277) (xy 119.815055 -344.760309)
			(xy 119.735016 -344.732607) (xy 119.657973 -344.697423) (xy 119.584623 -344.655074) (xy 119.515631 -344.605945)
			(xy 119.451621 -344.55048) (xy 119.393173 -344.489182) (xy 119.340817 -344.422606) (xy 119.295027 -344.351354)
			(xy 119.256216 -344.276073) (xy 119.224737 -344.197443) (xy 119.200876 -344.116176) (xy 119.184847 -344.03301)
			(xy 119.176796 -343.948696) (xy 115.964765 -343.948696) (xy 115.968529 -343.987512) (xy 115.969034 -344.029284)
			(xy 115.968529 -344.071056) (xy 115.960466 -344.154211) (xy 115.944415 -344.236199) (xy 115.920526 -344.316256)
			(xy 115.889021 -344.393633) (xy 115.850196 -344.467608) (xy 115.804413 -344.537491) (xy 115.752098 -344.602628)
			(xy 115.693741 -344.662413) (xy 115.629887 -344.716286) (xy 115.561131 -344.763745) (xy 115.488115 -344.804346)
			(xy 115.411522 -344.837711) (xy 115.332066 -344.863528) (xy 115.25049 -344.881556) (xy 115.167554 -344.891626)
			(xy 115.084034 -344.893645) (xy 115.000708 -344.887593) (xy 114.918356 -344.873528) (xy 114.837746 -344.85158)
			(xy 114.75963 -344.821954) (xy 114.684738 -344.784928) (xy 114.61377 -344.740847) (xy 114.547387 -344.690121)
			(xy 114.48621 -344.633226) (xy 114.430809 -344.570692) (xy 114.381703 -344.503103) (xy 114.339349 -344.43109)
			(xy 114.304143 -344.355325) (xy 114.276414 -344.276516) (xy 114.256421 -344.195399) (xy 114.244349 -344.112731)
			(xy 114.240313 -344.029284) (xy 113.494312 -344.029284) (xy 113.493808 -344.071632) (xy 113.485757 -344.155946)
			(xy 113.469728 -344.239112) (xy 113.445867 -344.320379) (xy 113.414388 -344.399009) (xy 113.375577 -344.47429)
			(xy 113.329787 -344.545542) (xy 113.277431 -344.612118) (xy 113.218983 -344.673416) (xy 113.154973 -344.728881)
			(xy 113.085981 -344.77801) (xy 113.012631 -344.820359) (xy 112.935588 -344.855543) (xy 112.855549 -344.883245)
			(xy 112.77324 -344.903213) (xy 112.689405 -344.915266) (xy 112.604804 -344.919297) (xy 112.520203 -344.915266)
			(xy 112.436368 -344.903213) (xy 112.354059 -344.883245) (xy 112.27402 -344.855543) (xy 112.196977 -344.820359)
			(xy 112.123627 -344.77801) (xy 112.054635 -344.728881) (xy 111.990625 -344.673416) (xy 111.932177 -344.612118)
			(xy 111.879821 -344.545542) (xy 111.834031 -344.47429) (xy 111.79522 -344.399009) (xy 111.763741 -344.320379)
			(xy 111.73988 -344.239112) (xy 111.723851 -344.155946) (xy 111.7158 -344.071632) (xy 108.263129 -344.071632)
			(xy 108.255122 -344.154211) (xy 108.239071 -344.236199) (xy 108.215182 -344.316256) (xy 108.183677 -344.393633)
			(xy 108.144852 -344.467608) (xy 108.099069 -344.537491) (xy 108.046754 -344.602628) (xy 107.988397 -344.662413)
			(xy 107.924543 -344.716286) (xy 107.855787 -344.763745) (xy 107.782771 -344.804346) (xy 107.706178 -344.837711)
			(xy 107.626722 -344.863528) (xy 107.545146 -344.881556) (xy 107.46221 -344.891626) (xy 107.37869 -344.893645)
			(xy 107.295364 -344.887593) (xy 107.213012 -344.873528) (xy 107.132402 -344.85158) (xy 107.054286 -344.821954)
			(xy 106.979394 -344.784928) (xy 106.908426 -344.740847) (xy 106.842043 -344.690121) (xy 106.780866 -344.633226)
			(xy 106.725465 -344.570692) (xy 106.676359 -344.503103) (xy 106.634005 -344.43109) (xy 106.598799 -344.355325)
			(xy 106.57107 -344.276516) (xy 106.551077 -344.195399) (xy 106.539005 -344.112731) (xy 106.534969 -344.029284)
			(xy 105.788968 -344.029284) (xy 105.788464 -344.071632) (xy 105.780413 -344.155946) (xy 105.764384 -344.239112)
			(xy 105.740523 -344.320379) (xy 105.709044 -344.399009) (xy 105.670233 -344.47429) (xy 105.624443 -344.545542)
			(xy 105.572087 -344.612118) (xy 105.513639 -344.673416) (xy 105.449629 -344.728881) (xy 105.380637 -344.77801)
			(xy 105.307287 -344.820359) (xy 105.230244 -344.855543) (xy 105.150205 -344.883245) (xy 105.067896 -344.903213)
			(xy 104.984061 -344.915266) (xy 104.89946 -344.919297) (xy 104.814859 -344.915266) (xy 104.731024 -344.903213)
			(xy 104.648715 -344.883245) (xy 104.568676 -344.855543) (xy 104.491633 -344.820359) (xy 104.418283 -344.77801)
			(xy 104.349291 -344.728881) (xy 104.285281 -344.673416) (xy 104.226833 -344.612118) (xy 104.174477 -344.545542)
			(xy 104.128687 -344.47429) (xy 104.089876 -344.399009) (xy 104.058397 -344.320379) (xy 104.034536 -344.239112)
			(xy 104.018507 -344.155946) (xy 104.010456 -344.071632) (xy 100.702565 -344.071632) (xy 100.694558 -344.154211)
			(xy 100.678507 -344.236199) (xy 100.654618 -344.316256) (xy 100.623113 -344.393633) (xy 100.584288 -344.467608)
			(xy 100.538505 -344.537491) (xy 100.48619 -344.602628) (xy 100.427833 -344.662413) (xy 100.363979 -344.716286)
			(xy 100.295223 -344.763745) (xy 100.222207 -344.804346) (xy 100.145614 -344.837711) (xy 100.066158 -344.863528)
			(xy 99.984582 -344.881556) (xy 99.901646 -344.891626) (xy 99.818126 -344.893645) (xy 99.7348 -344.887593)
			(xy 99.652448 -344.873528) (xy 99.571838 -344.85158) (xy 99.493722 -344.821954) (xy 99.41883 -344.784928)
			(xy 99.347862 -344.740847) (xy 99.281479 -344.690121) (xy 99.220302 -344.633226) (xy 99.164901 -344.570692)
			(xy 99.115795 -344.503103) (xy 99.073441 -344.43109) (xy 99.038235 -344.355325) (xy 99.010506 -344.276516)
			(xy 98.990513 -344.195399) (xy 98.978441 -344.112731) (xy 98.974405 -344.029284) (xy 98.228404 -344.029284)
			(xy 98.2279 -344.071632) (xy 98.219849 -344.155946) (xy 98.20382 -344.239112) (xy 98.179959 -344.320379)
			(xy 98.14848 -344.399009) (xy 98.109669 -344.47429) (xy 98.063879 -344.545542) (xy 98.011523 -344.612118)
			(xy 97.953075 -344.673416) (xy 97.889065 -344.728881) (xy 97.820073 -344.77801) (xy 97.746723 -344.820359)
			(xy 97.66968 -344.855543) (xy 97.589641 -344.883245) (xy 97.507332 -344.903213) (xy 97.423497 -344.915266)
			(xy 97.338896 -344.919297) (xy 97.254295 -344.915266) (xy 97.17046 -344.903213) (xy 97.088151 -344.883245)
			(xy 97.008112 -344.855543) (xy 96.931069 -344.820359) (xy 96.857719 -344.77801) (xy 96.788727 -344.728881)
			(xy 96.724717 -344.673416) (xy 96.666269 -344.612118) (xy 96.613913 -344.545542) (xy 96.568123 -344.47429)
			(xy 96.529312 -344.399009) (xy 96.497833 -344.320379) (xy 96.473972 -344.239112) (xy 96.457943 -344.155946)
			(xy 96.449892 -344.071632) (xy 77.404598 -344.071632) (xy 77.407845 -344.093836) (xy 77.420383 -344.120733)
			(xy 77.429868 -344.132154) (xy 77.448078 -344.153263) (xy 77.478821 -344.199767) (xy 77.50247 -344.250249)
			(xy 77.518524 -344.303635) (xy 77.52664 -344.358788) (xy 77.52715 -344.386662) (xy 77.526664 -344.413913)
			(xy 77.518908 -344.467861) (xy 77.503553 -344.520156) (xy 77.480911 -344.569733) (xy 77.451445 -344.615583)
			(xy 77.415754 -344.656774) (xy 77.374563 -344.692465) (xy 77.328713 -344.721931) (xy 77.279136 -344.744573)
			(xy 77.226841 -344.759928) (xy 77.172893 -344.767684) (xy 77.118391 -344.767684) (xy 77.064443 -344.759928)
			(xy 77.012148 -344.744573) (xy 76.962571 -344.721931) (xy 76.916721 -344.692465) (xy 76.87553 -344.656774)
			(xy 76.839839 -344.615583) (xy 76.810373 -344.569733) (xy 76.787731 -344.520156) (xy 76.772376 -344.467861)
			(xy 76.76462 -344.413913) (xy 76.764134 -344.386662) (xy 76.426568 -344.386662) (xy 76.426568 -344.7799)
			(xy 80.968987 -344.7799) (xy 80.973156 -344.724273) (xy 80.98557 -344.669888) (xy 81.005951 -344.617961)
			(xy 81.033844 -344.569652) (xy 81.068626 -344.526041) (xy 81.109519 -344.4881) (xy 81.155611 -344.456678)
			(xy 81.205871 -344.432478) (xy 81.259178 -344.416039) (xy 81.314338 -344.407729) (xy 81.34223 -344.407236)
			(xy 81.369561 -344.407729) (xy 81.42364 -344.415694) (xy 81.475974 -344.431479) (xy 81.525438 -344.454743)
			(xy 81.570971 -344.484988) (xy 81.611594 -344.521563) (xy 81.646434 -344.563683) (xy 81.661 -344.586814)
			(xy 81.668942 -344.599025) (xy 81.690409 -344.618694) (xy 81.716557 -344.631499) (xy 81.745257 -344.636399)
			(xy 81.774173 -344.632992) (xy 81.787746 -344.627708) (xy 81.810954 -344.618212) (xy 81.859288 -344.604863)
			(xy 81.908978 -344.598138) (xy 81.93405 -344.597736) (xy 81.95912 -344.598155) (xy 82.008803 -344.604906)
			(xy 82.057137 -344.618241) (xy 82.080354 -344.627708) (xy 82.093935 -344.632943) (xy 82.122834 -344.63631)
			(xy 82.151511 -344.631403) (xy 82.177645 -344.618617) (xy 82.199119 -344.598987) (xy 82.2071 -344.586814)
			(xy 82.221669 -344.563683) (xy 82.256512 -344.521562) (xy 82.297135 -344.484983) (xy 82.342666 -344.454732)
			(xy 82.392128 -344.431456) (xy 82.444459 -344.415656) (xy 82.498538 -344.40767) (xy 82.553202 -344.40767)
			(xy 82.607281 -344.415656) (xy 82.659612 -344.431456) (xy 82.709074 -344.454732) (xy 82.754605 -344.484983)
			(xy 82.795228 -344.521562) (xy 82.830071 -344.563683) (xy 82.84464 -344.586814) (xy 82.852544 -344.599052)
			(xy 82.874021 -344.618721) (xy 82.90018 -344.631523) (xy 82.928889 -344.636415) (xy 82.957811 -344.632998)
			(xy 82.971386 -344.627708) (xy 82.994601 -344.618231) (xy 83.042931 -344.604875) (xy 83.092619 -344.598142)
			(xy 83.11769 -344.597736) (xy 83.144534 -344.598169) (xy 83.197667 -344.605873) (xy 83.249144 -344.621124)
			(xy 83.297899 -344.643605) (xy 83.342923 -344.67285) (xy 83.383283 -344.708255) (xy 83.418143 -344.749087)
			(xy 83.446783 -344.794498) (xy 83.468608 -344.843551) (xy 83.476338 -344.869262) (xy 83.480962 -344.883774)
			(xy 83.497487 -344.909342) (xy 83.520811 -344.928908) (xy 83.548863 -344.940736) (xy 83.579155 -344.943775)
			(xy 83.608998 -344.937758) (xy 83.622642 -344.930984) (xy 83.65079 -344.916355) (xy 83.71074 -344.895627)
			(xy 83.773298 -344.885126) (xy 83.805014 -344.884502) (xy 83.828133 -344.884836) (xy 83.874034 -344.890404)
			(xy 83.918922 -344.901491) (xy 83.94065 -344.909394) (xy 83.954434 -344.914181) (xy 83.983516 -344.916438)
			(xy 84.012051 -344.910385) (xy 84.037712 -344.896514) (xy 84.058407 -344.875956) (xy 84.072448 -344.850388)
			(xy 84.076032 -344.836242) (xy 84.082655 -344.808282) (xy 84.103249 -344.754639) (xy 84.131655 -344.704692)
			(xy 84.167231 -344.65957) (xy 84.209172 -344.620294) (xy 84.25653 -344.587753) (xy 84.308232 -344.562682)
			(xy 84.363109 -344.545649) (xy 84.41992 -344.537039) (xy 84.44865 -344.536522) (xy 84.475903 -344.537002)
			(xy 84.529855 -344.544753) (xy 84.582154 -344.560104) (xy 84.631736 -344.582743) (xy 84.677591 -344.612208)
			(xy 84.718785 -344.647901) (xy 84.75448 -344.689093) (xy 84.783947 -344.734946) (xy 84.806589 -344.784527)
			(xy 84.821943 -344.836826) (xy 84.829697 -344.890777) (xy 84.830158 -344.91803) (xy 84.82972 -344.945401)
			(xy 84.821897 -344.999582) (xy 84.806402 -345.052086) (xy 84.783554 -345.101832) (xy 84.753822 -345.147798)
			(xy 84.736178 -345.168728) (xy 84.726914 -345.180034) (xy 84.714743 -345.2066) (xy 84.710577 -345.235523)
			(xy 84.714756 -345.264444) (xy 84.726939 -345.291004) (xy 84.736178 -345.302332) (xy 84.753795 -345.323282)
			(xy 84.783511 -345.369249) (xy 84.806352 -345.418992) (xy 84.821848 -345.471489) (xy 84.829681 -345.525662)
			(xy 84.830158 -345.55303) (xy 84.829659 -345.580604) (xy 84.821715 -345.635176) (xy 84.805998 -345.688035)
			(xy 84.782834 -345.738082) (xy 84.752707 -345.784272) (xy 84.716243 -345.825644) (xy 84.695538 -345.84386)
			(xy 84.693568 -345.845638) (xy 134.634984 -345.845638) (xy 134.639055 -345.790016) (xy 134.651181 -345.735579)
			(xy 134.671104 -345.683488) (xy 134.6984 -345.634853) (xy 134.732486 -345.59071) (xy 134.772635 -345.552001)
			(xy 134.817993 -345.51955) (xy 134.867593 -345.494049) (xy 134.920377 -345.476042) (xy 134.97522 -345.465912)
			(xy 135.030954 -345.463875) (xy 135.086391 -345.469975) (xy 135.140348 -345.484081) (xy 135.191677 -345.505893)
			(xy 135.239283 -345.534947) (xy 135.282151 -345.570622) (xy 135.319368 -345.612159) (xy 135.350141 -345.658672)
			(xy 135.373813 -345.709169) (xy 135.389881 -345.762576) (xy 135.398001 -345.817752) (xy 135.39851 -345.845638)
			(xy 135.398001 -345.873524) (xy 135.389881 -345.9287) (xy 135.373813 -345.982107) (xy 135.350141 -346.032604)
			(xy 135.319368 -346.079117) (xy 135.282151 -346.120654) (xy 135.239283 -346.156329) (xy 135.191677 -346.185383)
			(xy 135.140348 -346.207195) (xy 135.086391 -346.221301) (xy 135.030954 -346.227401) (xy 134.97522 -346.225364)
			(xy 134.920377 -346.215234) (xy 134.867593 -346.197227) (xy 134.817993 -346.171726) (xy 134.772635 -346.139275)
			(xy 134.732486 -346.100566) (xy 134.6984 -346.056423) (xy 134.671104 -346.007788) (xy 134.651181 -345.955697)
			(xy 134.639055 -345.90126) (xy 134.634984 -345.845638) (xy 84.693568 -345.845638) (xy 84.684608 -345.853726)
			(xy 84.668531 -345.878384) (xy 84.660147 -345.906601) (xy 84.660153 -345.936037) (xy 84.668547 -345.964251)
			(xy 84.684633 -345.988903) (xy 84.695538 -345.9988) (xy 84.71626 -346.016999) (xy 84.752728 -346.058371)
			(xy 84.782858 -346.104564) (xy 84.806021 -346.154614) (xy 84.821736 -346.207479) (xy 84.829674 -346.262055)
			(xy 84.830158 -346.28963) (xy 84.829773 -346.316886) (xy 84.822011 -346.370842) (xy 84.806648 -346.423145)
			(xy 84.783998 -346.472728) (xy 84.760138 -346.509848) (xy 133.965948 -346.509848) (xy 133.970019 -346.454226)
			(xy 133.982145 -346.399789) (xy 134.002068 -346.347698) (xy 134.029364 -346.299063) (xy 134.06345 -346.25492)
			(xy 134.103599 -346.216211) (xy 134.148957 -346.18376) (xy 134.198557 -346.158259) (xy 134.251341 -346.140252)
			(xy 134.306184 -346.130122) (xy 134.361918 -346.128085) (xy 134.417355 -346.134185) (xy 134.471312 -346.148291)
			(xy 134.522641 -346.170103) (xy 134.570247 -346.199157) (xy 134.613115 -346.234832) (xy 134.650332 -346.276369)
			(xy 134.681105 -346.322882) (xy 134.704777 -346.373379) (xy 134.720845 -346.426786) (xy 134.728965 -346.481962)
			(xy 134.729474 -346.509848) (xy 134.728965 -346.537734) (xy 134.720845 -346.59291) (xy 134.704777 -346.646317)
			(xy 134.681105 -346.696814) (xy 134.650332 -346.743327) (xy 134.613115 -346.784864) (xy 134.570247 -346.820539)
			(xy 134.522641 -346.849593) (xy 134.471312 -346.871405) (xy 134.417355 -346.885511) (xy 134.361918 -346.891611)
			(xy 134.306184 -346.889574) (xy 134.251341 -346.879444) (xy 134.198557 -346.861437) (xy 134.148957 -346.835936)
			(xy 134.103599 -346.803485) (xy 134.06345 -346.764776) (xy 134.029364 -346.720633) (xy 134.002068 -346.671998)
			(xy 133.982145 -346.619907) (xy 133.970019 -346.56547) (xy 133.965948 -346.509848) (xy 84.760138 -346.509848)
			(xy 84.754523 -346.518584) (xy 84.718821 -346.559777) (xy 84.67762 -346.595471) (xy 84.631758 -346.624937)
			(xy 84.58217 -346.647576) (xy 84.529864 -346.662928) (xy 84.475906 -346.670679) (xy 84.44865 -346.671138)
			(xy 84.420776 -346.670626) (xy 84.365624 -346.662506) (xy 84.31224 -346.646446) (xy 84.261761 -346.622788)
			(xy 84.215263 -346.592036) (xy 84.173735 -346.554845) (xy 84.138062 -346.512006) (xy 84.109002 -346.464432)
			(xy 84.097622 -346.438982) (xy 84.090901 -346.424856) (xy 84.070496 -346.40117) (xy 84.043891 -346.384752)
			(xy 84.013571 -346.377136) (xy 83.982366 -346.379032) (xy 83.967574 -346.384118) (xy 83.945612 -346.392165)
			(xy 83.900228 -346.403485) (xy 83.853801 -346.409176) (xy 83.830414 -346.409518) (xy 83.816265 -346.409423)
			(xy 83.788042 -346.407389) (xy 83.774026 -346.405454) (xy 83.760682 -346.403807) (xy 83.733981 -346.406912)
			(xy 83.709021 -346.41689) (xy 83.687538 -346.433048) (xy 83.671028 -346.454261) (xy 83.660638 -346.479053)
			(xy 83.658456 -346.492322) (xy 83.654312 -346.519466) (xy 83.639344 -346.572293) (xy 83.616959 -346.622429)
			(xy 83.587617 -346.668838) (xy 83.551926 -346.710563) (xy 83.510623 -346.74674) (xy 83.464561 -346.776623)
			(xy 83.41469 -346.799594) (xy 83.362042 -346.81518) (xy 83.307703 -346.823057) (xy 83.28025 -346.823538)
			(xy 83.253 -346.822998) (xy 83.199053 -346.815249) (xy 83.146759 -346.799901) (xy 83.097181 -346.777266)
			(xy 83.051329 -346.747806) (xy 83.010136 -346.71212) (xy 82.974442 -346.670935) (xy 82.944972 -346.62509)
			(xy 82.922327 -346.575517) (xy 82.906968 -346.523225) (xy 82.899207 -346.46928) (xy 82.898742 -346.44203)
			(xy 82.899214 -346.414456) (xy 82.907163 -346.359882) (xy 82.922886 -346.307022) (xy 82.946055 -346.256976)
			(xy 82.976187 -346.210786) (xy 83.012655 -346.169415) (xy 83.033362 -346.1512) (xy 83.044232 -346.141273)
			(xy 83.060311 -346.116632) (xy 83.068702 -346.088431) (xy 83.068707 -346.059008) (xy 83.060328 -346.030803)
			(xy 83.044258 -346.006157) (xy 83.033362 -345.99626) (xy 83.012669 -345.978029) (xy 82.976199 -345.936664)
			(xy 82.946066 -345.890478) (xy 82.922897 -345.840434) (xy 82.907176 -345.787575) (xy 82.899231 -345.733003)
			(xy 82.898742 -345.70543) (xy 82.899165 -345.678928) (xy 82.906516 -345.626435) (xy 82.921067 -345.575466)
			(xy 82.942537 -345.527005) (xy 82.970513 -345.481984) (xy 82.987134 -345.461336) (xy 82.996597 -345.449205)
			(xy 83.008386 -345.420799) (xy 83.011207 -345.390174) (xy 83.004807 -345.360093) (xy 82.989762 -345.33327)
			(xy 82.96743 -345.312125) (xy 82.95386 -345.304872) (xy 82.930169 -345.292774) (xy 82.886187 -345.26285)
			(xy 82.846906 -345.226979) (xy 82.813123 -345.185887) (xy 82.79892 -345.163394) (xy 82.790957 -345.151198)
			(xy 82.769496 -345.131528) (xy 82.743354 -345.11872) (xy 82.714658 -345.113817) (xy 82.685746 -345.117219)
			(xy 82.672174 -345.1225) (xy 82.648964 -345.13199) (xy 82.600631 -345.145341) (xy 82.550942 -345.152069)
			(xy 82.52587 -345.152472) (xy 82.500801 -345.152046) (xy 82.451118 -345.145297) (xy 82.402783 -345.131966)
			(xy 82.379566 -345.1225) (xy 82.365978 -345.117283) (xy 82.337083 -345.11391) (xy 82.308408 -345.118814)
			(xy 82.282275 -345.131596) (xy 82.2608 -345.151222) (xy 82.25282 -345.163394) (xy 82.238251 -345.186525)
			(xy 82.203408 -345.228646) (xy 82.162785 -345.265225) (xy 82.117254 -345.295476) (xy 82.067792 -345.318752)
			(xy 82.015461 -345.334552) (xy 81.961382 -345.342538) (xy 81.906718 -345.342538) (xy 81.852639 -345.334552)
			(xy 81.800308 -345.318752) (xy 81.750846 -345.295476) (xy 81.705315 -345.265225) (xy 81.664692 -345.228646)
			(xy 81.629849 -345.186525) (xy 81.61528 -345.163394) (xy 81.607355 -345.151171) (xy 81.585884 -345.131501)
			(xy 81.559731 -345.118696) (xy 81.531026 -345.113801) (xy 81.502108 -345.117212) (xy 81.488534 -345.1225)
			(xy 81.465317 -345.131971) (xy 81.416988 -345.145329) (xy 81.367301 -345.152065) (xy 81.34223 -345.152472)
			(xy 81.314338 -345.152071) (xy 81.259178 -345.143761) (xy 81.205871 -345.127322) (xy 81.155611 -345.103122)
			(xy 81.109519 -345.0717) (xy 81.068626 -345.033759) (xy 81.033844 -344.990148) (xy 81.005951 -344.941839)
			(xy 80.98557 -344.889912) (xy 80.973156 -344.835527) (xy 80.968987 -344.7799) (xy 76.426568 -344.7799)
			(xy 76.426568 -345.845638) (xy 77.5114 -345.845638) (xy 77.515471 -345.790016) (xy 77.527597 -345.735579)
			(xy 77.54752 -345.683488) (xy 77.574816 -345.634853) (xy 77.608902 -345.59071) (xy 77.649051 -345.552001)
			(xy 77.694409 -345.51955) (xy 77.744009 -345.494049) (xy 77.796793 -345.476042) (xy 77.851636 -345.465912)
			(xy 77.90737 -345.463875) (xy 77.962807 -345.469975) (xy 78.016764 -345.484081) (xy 78.068093 -345.505893)
			(xy 78.115699 -345.534947) (xy 78.158567 -345.570622) (xy 78.195784 -345.612159) (xy 78.226557 -345.658672)
			(xy 78.250229 -345.709169) (xy 78.266297 -345.762576) (xy 78.274417 -345.817752) (xy 78.274926 -345.845638)
			(xy 78.274417 -345.873524) (xy 78.266297 -345.9287) (xy 78.250229 -345.982107) (xy 78.226557 -346.032604)
			(xy 78.195784 -346.079117) (xy 78.158567 -346.120654) (xy 78.115699 -346.156329) (xy 78.068093 -346.185383)
			(xy 78.016764 -346.207195) (xy 77.962807 -346.221301) (xy 77.90737 -346.227401) (xy 77.851636 -346.225364)
			(xy 77.796793 -346.215234) (xy 77.744009 -346.197227) (xy 77.694409 -346.171726) (xy 77.649051 -346.139275)
			(xy 77.608902 -346.100566) (xy 77.574816 -346.056423) (xy 77.54752 -346.007788) (xy 77.527597 -345.955697)
			(xy 77.515471 -345.90126) (xy 77.5114 -345.845638) (xy 76.426568 -345.845638) (xy 76.426568 -346.310966)
			(xy 76.508093 -346.825062) (xy 76.846936 -346.825062) (xy 76.851007 -346.76944) (xy 76.863133 -346.715003)
			(xy 76.883056 -346.662912) (xy 76.910352 -346.614277) (xy 76.944438 -346.570134) (xy 76.984587 -346.531425)
			(xy 77.029945 -346.498974) (xy 77.079545 -346.473473) (xy 77.132329 -346.455466) (xy 77.187172 -346.445336)
			(xy 77.242906 -346.443299) (xy 77.298343 -346.449399) (xy 77.3523 -346.463505) (xy 77.403629 -346.485317)
			(xy 77.451235 -346.514371) (xy 77.494103 -346.550046) (xy 77.53132 -346.591583) (xy 77.562093 -346.638096)
			(xy 77.585765 -346.688593) (xy 77.601833 -346.742) (xy 77.609953 -346.797176) (xy 77.610462 -346.825062)
			(xy 77.609953 -346.852948) (xy 77.601833 -346.908124) (xy 77.585765 -346.961531) (xy 77.562093 -347.012028)
			(xy 77.53132 -347.058541) (xy 77.494103 -347.100078) (xy 77.451235 -347.135753) (xy 77.403629 -347.164807)
			(xy 77.3523 -347.186619) (xy 77.298343 -347.200725) (xy 77.242906 -347.206825) (xy 77.187172 -347.204788)
			(xy 77.132329 -347.194658) (xy 77.079545 -347.176651) (xy 77.029945 -347.15115) (xy 76.984587 -347.118699)
			(xy 76.944438 -347.07999) (xy 76.910352 -347.035847) (xy 76.883056 -346.987212) (xy 76.863133 -346.935121)
			(xy 76.851007 -346.880684) (xy 76.846936 -346.825062) (xy 76.508093 -346.825062) (xy 76.605488 -347.439234)
			(xy 78.318106 -347.439234) (xy 78.318683 -347.409547) (xy 78.327877 -347.350889) (xy 78.346048 -347.294363)
			(xy 78.372757 -347.241335) (xy 78.407359 -347.193086) (xy 78.449019 -347.15078) (xy 78.472538 -347.132656)
			(xy 78.483121 -347.124203) (xy 78.499823 -347.102895) (xy 78.510339 -347.077947) (xy 78.513931 -347.051113)
			(xy 78.510346 -347.024278) (xy 78.499836 -346.999328) (xy 78.48314 -346.978016) (xy 78.472538 -346.969588)
			(xy 78.44903 -346.951449) (xy 78.407367 -346.909147) (xy 78.372762 -346.860901) (xy 78.346048 -346.807876)
			(xy 78.327872 -346.751353) (xy 78.318672 -346.692697) (xy 78.318106 -346.66301) (xy 78.318592 -346.635759)
			(xy 78.326348 -346.581811) (xy 78.341703 -346.529516) (xy 78.364345 -346.479939) (xy 78.393811 -346.434089)
			(xy 78.429502 -346.392898) (xy 78.470693 -346.357207) (xy 78.516543 -346.327741) (xy 78.56612 -346.305099)
			(xy 78.618415 -346.289744) (xy 78.672363 -346.281988) (xy 78.726865 -346.281988) (xy 78.780813 -346.289744)
			(xy 78.833108 -346.305099) (xy 78.882685 -346.327741) (xy 78.928535 -346.357207) (xy 78.969726 -346.392898)
			(xy 79.005417 -346.434089) (xy 79.034883 -346.479939) (xy 79.057525 -346.529516) (xy 79.07288 -346.581811)
			(xy 79.080636 -346.635759) (xy 79.081122 -346.66301) (xy 79.080565 -346.692698) (xy 79.071366 -346.751356)
			(xy 79.05319 -346.807882) (xy 79.026477 -346.860909) (xy 79.014394 -346.877756) (xy 79.334517 -346.877756)
			(xy 79.334517 -346.823244) (xy 79.342275 -346.769286) (xy 79.357633 -346.716982) (xy 79.380279 -346.667396)
			(xy 79.409751 -346.621537) (xy 79.44545 -346.58034) (xy 79.486649 -346.544643) (xy 79.532508 -346.515172)
			(xy 79.582095 -346.492528) (xy 79.6344 -346.477172) (xy 79.688358 -346.469416) (xy 79.715614 -346.468954)
			(xy 79.740849 -346.469351) (xy 79.790883 -346.47597) (xy 79.839603 -346.489143) (xy 79.886155 -346.50864)
			(xy 79.908146 -346.521024) (xy 79.92109 -346.528106) (xy 79.949736 -346.535138) (xy 79.979196 -346.533688)
			(xy 80.007013 -346.523877) (xy 80.030865 -346.506525) (xy 80.048761 -346.483078) (xy 80.05445 -346.469462)
			(xy 80.065151 -346.442688) (xy 80.09344 -346.392448) (xy 80.12897 -346.34704) (xy 80.170931 -346.307498)
			(xy 80.218368 -346.274725) (xy 80.270197 -346.249466) (xy 80.325239 -346.232299) (xy 80.382238 -346.223613)
			(xy 80.411066 -346.223082) (xy 80.438318 -346.223587) (xy 80.492266 -346.231339) (xy 80.544563 -346.24669)
			(xy 80.594142 -346.269328) (xy 80.639995 -346.298792) (xy 80.681188 -346.334481) (xy 80.716882 -346.37567)
			(xy 80.746351 -346.421519) (xy 80.768994 -346.471096) (xy 80.784352 -346.52339) (xy 80.79211 -346.577338)
			(xy 80.792574 -346.60459) (xy 80.792049 -346.634495) (xy 80.782729 -346.693574) (xy 80.774032 -346.722192)
			(xy 80.769931 -346.736084) (xy 80.769028 -346.765028) (xy 80.776304 -346.793057) (xy 80.791169 -346.817907)
			(xy 80.812425 -346.837573) (xy 80.838354 -346.850466) (xy 80.852518 -346.85351) (xy 80.878588 -346.858694)
			(xy 80.929091 -346.875263) (xy 80.976803 -346.898685) (xy 81.020801 -346.928505) (xy 81.060232 -346.964146)
			(xy 81.094332 -347.004918) (xy 81.122439 -347.050029) (xy 81.144009 -347.098607) (xy 81.158625 -347.149709)
			(xy 81.166003 -347.202346) (xy 81.166462 -347.228922) (xy 81.165976 -347.256173) (xy 81.15822 -347.310121)
			(xy 81.142865 -347.362416) (xy 81.120223 -347.411993) (xy 81.102716 -347.439234) (xy 135.44169 -347.439234)
			(xy 135.442274 -347.409547) (xy 135.451467 -347.35089) (xy 135.469637 -347.294364) (xy 135.496345 -347.241337)
			(xy 135.530946 -347.193087) (xy 135.572604 -347.150781) (xy 135.596122 -347.132656) (xy 135.606706 -347.124204)
			(xy 135.623411 -347.102896) (xy 135.633929 -347.077948) (xy 135.637521 -347.051113) (xy 135.633936 -347.024277)
			(xy 135.623424 -346.999326) (xy 135.606725 -346.978015) (xy 135.596122 -346.969588) (xy 135.572611 -346.951453)
			(xy 135.530949 -346.90915) (xy 135.496344 -346.860903) (xy 135.469631 -346.807878) (xy 135.451455 -346.751354)
			(xy 135.442256 -346.692697) (xy 135.44169 -346.66301) (xy 135.442176 -346.635759) (xy 135.449932 -346.581811)
			(xy 135.465287 -346.529516) (xy 135.487929 -346.479939) (xy 135.517395 -346.434089) (xy 135.553086 -346.392898)
			(xy 135.594277 -346.357207) (xy 135.640127 -346.327741) (xy 135.689704 -346.305099) (xy 135.741999 -346.289744)
			(xy 135.795947 -346.281988) (xy 135.850449 -346.281988) (xy 135.904397 -346.289744) (xy 135.956692 -346.305099)
			(xy 136.006269 -346.327741) (xy 136.052119 -346.357207) (xy 136.09331 -346.392898) (xy 136.129001 -346.434089)
			(xy 136.158467 -346.479939) (xy 136.181109 -346.529516) (xy 136.196464 -346.581811) (xy 136.20422 -346.635759)
			(xy 136.204706 -346.66301) (xy 136.204156 -346.692698) (xy 136.194956 -346.751357) (xy 136.176779 -346.807883)
			(xy 136.150065 -346.860911) (xy 136.137984 -346.877754) (xy 136.45814 -346.877754) (xy 136.45814 -346.823246)
			(xy 136.465897 -346.769293) (xy 136.481254 -346.716993) (xy 136.503897 -346.667411) (xy 136.533366 -346.621557)
			(xy 136.569061 -346.580362) (xy 136.610255 -346.544667) (xy 136.65611 -346.515198) (xy 136.705692 -346.492554)
			(xy 136.757991 -346.477198) (xy 136.811944 -346.46944) (xy 136.839198 -346.468954) (xy 136.864433 -346.469358)
			(xy 136.914467 -346.475975) (xy 136.963187 -346.489146) (xy 137.009739 -346.508641) (xy 137.03173 -346.521024)
			(xy 137.044684 -346.528087) (xy 137.073326 -346.535122) (xy 137.102783 -346.533675) (xy 137.130598 -346.523868)
			(xy 137.154449 -346.506519) (xy 137.172345 -346.483076) (xy 137.178034 -346.469462) (xy 137.188748 -346.442694)
			(xy 137.217036 -346.392454) (xy 137.252564 -346.347046) (xy 137.294524 -346.307505) (xy 137.341958 -346.27473)
			(xy 137.393785 -346.249471) (xy 137.448825 -346.232302) (xy 137.505822 -346.223614) (xy 137.53465 -346.223082)
			(xy 137.561901 -346.223602) (xy 137.61585 -346.231352) (xy 137.668146 -346.246701) (xy 137.717725 -346.269337)
			(xy 137.763578 -346.298799) (xy 137.804771 -346.334487) (xy 137.840465 -346.375674) (xy 137.869934 -346.421522)
			(xy 137.892578 -346.471098) (xy 137.907936 -346.523392) (xy 137.915694 -346.577339) (xy 137.916158 -346.60459)
			(xy 137.915629 -346.634495) (xy 137.906312 -346.693574) (xy 137.897616 -346.722192) (xy 137.893528 -346.736087)
			(xy 137.892626 -346.765028) (xy 137.8999 -346.793054) (xy 137.914763 -346.817903) (xy 137.936014 -346.837569)
			(xy 137.961939 -346.850464) (xy 137.976102 -346.85351) (xy 138.002169 -346.858706) (xy 138.052672 -346.875273)
			(xy 138.100385 -346.898693) (xy 138.144384 -346.928511) (xy 138.183815 -346.964151) (xy 138.217914 -347.004921)
			(xy 138.246022 -347.050032) (xy 138.267593 -347.098609) (xy 138.282209 -347.14971) (xy 138.289587 -347.202347)
			(xy 138.290046 -347.228922) (xy 138.28956 -347.256173) (xy 138.281804 -347.310121) (xy 138.266449 -347.362416)
			(xy 138.243807 -347.411993) (xy 138.214341 -347.457843) (xy 138.17865 -347.499034) (xy 138.137459 -347.534725)
			(xy 138.091609 -347.564191) (xy 138.042032 -347.586833) (xy 137.989737 -347.602188) (xy 137.935789 -347.609944)
			(xy 137.881287 -347.609944) (xy 137.827339 -347.602188) (xy 137.775044 -347.586833) (xy 137.725467 -347.564191)
			(xy 137.679617 -347.534725) (xy 137.638426 -347.499034) (xy 137.602735 -347.457843) (xy 137.573269 -347.411993)
			(xy 137.550627 -347.362416) (xy 137.535272 -347.310121) (xy 137.527516 -347.256173) (xy 137.52703 -347.228922)
			(xy 137.527558 -347.199017) (xy 137.536875 -347.139938) (xy 137.545572 -347.11132) (xy 137.549656 -347.097423)
			(xy 137.550561 -347.068483) (xy 137.543289 -347.040456) (xy 137.528427 -347.015606) (xy 137.507175 -346.995941)
			(xy 137.481249 -346.983047) (xy 137.467086 -346.980002) (xy 137.434246 -346.973424) (xy 137.371394 -346.950298)
			(xy 137.342118 -346.934028) (xy 137.329125 -346.927047) (xy 137.3005 -346.920009) (xy 137.271058 -346.921446)
			(xy 137.243253 -346.931237) (xy 137.219407 -346.948565) (xy 137.201508 -346.971986) (xy 137.195814 -346.98559)
			(xy 137.185117 -347.012366) (xy 137.156831 -347.062609) (xy 137.121302 -347.10802) (xy 137.07934 -347.147563)
			(xy 137.031903 -347.180337) (xy 136.980071 -347.205595) (xy 136.925028 -347.22276) (xy 136.868027 -347.231441)
			(xy 136.839198 -347.23197) (xy 136.811944 -347.23156) (xy 136.757991 -347.223802) (xy 136.705692 -347.208446)
			(xy 136.65611 -347.185802) (xy 136.610255 -347.156333) (xy 136.569061 -347.120638) (xy 136.533366 -347.079443)
			(xy 136.503897 -347.033589) (xy 136.481254 -346.984007) (xy 136.465897 -346.931707) (xy 136.45814 -346.877754)
			(xy 136.137984 -346.877754) (xy 136.115458 -346.909159) (xy 136.073795 -346.951464) (xy 136.050274 -346.969588)
			(xy 136.039646 -346.97799) (xy 136.022942 -346.999309) (xy 136.012428 -347.024268) (xy 136.008841 -347.051113)
			(xy 136.012435 -347.077957) (xy 136.022956 -347.102914) (xy 136.039665 -347.124229) (xy 136.050274 -347.132656)
			(xy 136.073806 -347.150766) (xy 136.115466 -347.193074) (xy 136.150069 -347.241326) (xy 136.176779 -347.294357)
			(xy 136.19495 -347.350885) (xy 136.204144 -347.409546) (xy 136.204706 -347.439234) (xy 136.20422 -347.466485)
			(xy 136.196464 -347.520433) (xy 136.181109 -347.572728) (xy 136.158467 -347.622305) (xy 136.129001 -347.668155)
			(xy 136.09331 -347.709346) (xy 136.052119 -347.745037) (xy 136.006269 -347.774503) (xy 135.956692 -347.797145)
			(xy 135.904397 -347.8125) (xy 135.850449 -347.820256) (xy 135.795947 -347.820256) (xy 135.741999 -347.8125)
			(xy 135.689704 -347.797145) (xy 135.640127 -347.774503) (xy 135.594277 -347.745037) (xy 135.553086 -347.709346)
			(xy 135.517395 -347.668155) (xy 135.487929 -347.622305) (xy 135.465287 -347.572728) (xy 135.449932 -347.520433)
			(xy 135.442176 -347.466485) (xy 135.44169 -347.439234) (xy 81.102716 -347.439234) (xy 81.090757 -347.457843)
			(xy 81.055066 -347.499034) (xy 81.013875 -347.534725) (xy 80.968025 -347.564191) (xy 80.918448 -347.586833)
			(xy 80.866153 -347.602188) (xy 80.812205 -347.609944) (xy 80.757703 -347.609944) (xy 80.703755 -347.602188)
			(xy 80.65146 -347.586833) (xy 80.601883 -347.564191) (xy 80.556033 -347.534725) (xy 80.514842 -347.499034)
			(xy 80.479151 -347.457843) (xy 80.449685 -347.411993) (xy 80.427043 -347.362416) (xy 80.411688 -347.310121)
			(xy 80.403932 -347.256173) (xy 80.403446 -347.228922) (xy 80.403977 -347.199017) (xy 80.413293 -347.139938)
			(xy 80.421988 -347.11132) (xy 80.426059 -347.097421) (xy 80.426964 -347.068483) (xy 80.419693 -347.040458)
			(xy 80.404833 -347.01561) (xy 80.383585 -346.995944) (xy 80.357663 -346.983049) (xy 80.343502 -346.980002)
			(xy 80.310662 -346.97342) (xy 80.24781 -346.950297) (xy 80.218534 -346.934028) (xy 80.205591 -346.926948)
			(xy 80.176946 -346.919925) (xy 80.147488 -346.921379) (xy 80.119674 -346.931189) (xy 80.095823 -346.948537)
			(xy 80.077923 -346.971977) (xy 80.07223 -346.98559) (xy 80.06152 -347.012361) (xy 80.033235 -347.062603)
			(xy 79.997708 -347.108013) (xy 79.955748 -347.147557) (xy 79.908313 -347.180331) (xy 79.856483 -347.20559)
			(xy 79.801441 -347.222757) (xy 79.744442 -347.23144) (xy 79.715614 -347.23197) (xy 79.688358 -347.231584)
			(xy 79.6344 -347.223828) (xy 79.582095 -347.208472) (xy 79.532508 -347.185828) (xy 79.486649 -347.156357)
			(xy 79.44545 -347.12066) (xy 79.409751 -347.079463) (xy 79.380279 -347.033604) (xy 79.357633 -346.984018)
			(xy 79.342275 -346.931714) (xy 79.334517 -346.877756) (xy 79.014394 -346.877756) (xy 78.991872 -346.909158)
			(xy 78.95021 -346.951464) (xy 78.92669 -346.969588) (xy 78.916061 -346.977989) (xy 78.899354 -346.999307)
			(xy 78.888838 -347.024267) (xy 78.885251 -347.051113) (xy 78.888845 -347.077958) (xy 78.899368 -347.102916)
			(xy 78.91608 -347.12423) (xy 78.92669 -347.132656) (xy 78.950225 -347.150762) (xy 78.991885 -347.193071)
			(xy 79.026487 -347.241324) (xy 79.053195 -347.294356) (xy 79.071366 -347.350884) (xy 79.08056 -347.409545)
			(xy 79.081122 -347.439234) (xy 79.080636 -347.466485) (xy 79.07288 -347.520433) (xy 79.057525 -347.572728)
			(xy 79.034883 -347.622305) (xy 79.005417 -347.668155) (xy 78.969726 -347.709346) (xy 78.928535 -347.745037)
			(xy 78.882685 -347.774503) (xy 78.833108 -347.797145) (xy 78.780813 -347.8125) (xy 78.726865 -347.820256)
			(xy 78.672363 -347.820256) (xy 78.618415 -347.8125) (xy 78.56612 -347.797145) (xy 78.516543 -347.774503)
			(xy 78.470693 -347.745037) (xy 78.429502 -347.709346) (xy 78.393811 -347.668155) (xy 78.364345 -347.622305)
			(xy 78.341703 -347.572728) (xy 78.326348 -347.520433) (xy 78.318592 -347.466485) (xy 78.318106 -347.439234)
			(xy 76.605488 -347.439234) (xy 76.893928 -349.258128) (xy 76.934822 -349.260668) (xy 76.963595 -349.262892)
			(xy 77.020036 -349.274919) (xy 77.074022 -349.295307) (xy 77.124323 -349.323592) (xy 77.169792 -349.359128)
			(xy 77.209391 -349.401106) (xy 77.242217 -349.448568) (xy 77.267523 -349.500432) (xy 77.284731 -349.555514)
			(xy 77.293448 -349.61256) (xy 77.293978 -349.641414) (xy 77.293527 -349.668255) (xy 77.286011 -349.721407)
			(xy 77.271116 -349.77298) (xy 77.249137 -349.821955) (xy 77.220507 -349.867363) (xy 77.185792 -349.908309)
			(xy 77.145679 -349.943982) (xy 77.123544 -349.959168) (xy 77.089 -349.982282) (xy 77.197458 -350.251014)
			(xy 77.202792 -350.257364) (xy 77.22235 -350.281255) (xy 77.254286 -350.334094) (xy 77.277305 -350.391382)
			(xy 77.290809 -350.451626) (xy 77.293216 -350.482408) (xy 77.293724 -350.49079) (xy 77.297099 -350.499172)
			(xy 88.330532 -350.499172) (xy 88.33109 -350.470256) (xy 88.339809 -350.413086) (xy 88.357058 -350.357888)
			(xy 88.382442 -350.305926) (xy 88.41538 -350.258391) (xy 88.455115 -350.216373) (xy 88.477598 -350.198182)
			(xy 88.48943 -350.188315) (xy 88.506945 -350.162982) (xy 88.516117 -350.133582) (xy 88.516112 -350.102784)
			(xy 88.50693 -350.073387) (xy 88.489406 -350.04806) (xy 88.477598 -350.038162) (xy 88.455096 -350.019993)
			(xy 88.415362 -349.977969) (xy 88.382425 -349.930429) (xy 88.35704 -349.878463) (xy 88.339788 -349.823262)
			(xy 88.331064 -349.766089) (xy 88.330532 -349.737172) (xy 88.330929 -349.709917) (xy 88.338691 -349.655961)
			(xy 88.354052 -349.60366) (xy 88.376701 -349.554077) (xy 88.406176 -349.508222) (xy 88.441876 -349.467028)
			(xy 88.483076 -349.431335) (xy 88.528936 -349.401868) (xy 88.578523 -349.379229) (xy 88.630828 -349.363876)
			(xy 88.684785 -349.356124) (xy 88.71204 -349.355664) (xy 88.738273 -349.356089) (xy 88.790245 -349.363261)
			(xy 88.840747 -349.377481) (xy 88.888827 -349.398478) (xy 88.91143 -349.411798) (xy 88.921042 -349.417123)
			(xy 88.942853 -349.419676) (xy 88.963746 -349.412914) (xy 88.979926 -349.398067) (xy 88.988453 -349.377831)
			(xy 88.988646 -349.36684) (xy 88.988392 -349.353632) (xy 88.988456 -349.342494) (xy 88.989728 -349.320255)
			(xy 88.990932 -349.309182) (xy 88.992189 -349.294211) (xy 88.986907 -349.264651) (xy 88.973257 -349.237904)
			(xy 88.952417 -349.216283) (xy 88.926191 -349.201657) (xy 88.896845 -349.19529) (xy 88.866916 -349.197734)
			(xy 88.852756 -349.202756) (xy 88.830293 -349.2113) (xy 88.78375 -349.223283) (xy 88.73607 -349.229319)
			(xy 88.71204 -349.22968) (xy 88.684783 -349.229276) (xy 88.630824 -349.221523) (xy 88.578517 -349.206169)
			(xy 88.528929 -349.183527) (xy 88.483067 -349.154058) (xy 88.441866 -349.118362) (xy 88.406166 -349.077165)
			(xy 88.376692 -349.031307) (xy 88.354045 -348.98172) (xy 88.338686 -348.929415) (xy 88.330927 -348.875457)
			(xy 88.330927 -348.820943) (xy 88.338686 -348.766985) (xy 88.354045 -348.71468) (xy 88.376692 -348.665093)
			(xy 88.406166 -348.619235) (xy 88.441866 -348.578038) (xy 88.483067 -348.542342) (xy 88.528929 -348.512873)
			(xy 88.578517 -348.490231) (xy 88.630824 -348.474877) (xy 88.684783 -348.467124) (xy 88.71204 -348.466664)
			(xy 88.736204 -348.467041) (xy 88.784147 -348.473135) (xy 88.830936 -348.485233) (xy 88.853518 -348.493842)
			(xy 88.868007 -348.499123) (xy 88.89874 -348.501541) (xy 88.928796 -348.494686) (xy 88.955441 -348.479182)
			(xy 88.976252 -348.456438) (xy 88.989334 -348.428524) (xy 88.991948 -348.413324) (xy 88.996023 -348.386221)
			(xy 89.011078 -348.333521) (xy 89.033522 -348.283519) (xy 89.062893 -348.237245) (xy 89.098585 -348.195651)
			(xy 89.139864 -348.159596) (xy 89.18588 -348.129821) (xy 89.235683 -348.106939) (xy 89.28825 -348.091423)
			(xy 89.342496 -348.083591) (xy 89.3699 -348.083124) (xy 89.398817 -348.083633) (xy 89.455989 -348.092363)
			(xy 89.511189 -348.109622) (xy 89.563151 -348.135015) (xy 89.610684 -348.167961) (xy 89.6527 -348.207704)
			(xy 89.67089 -348.23019) (xy 89.680787 -348.241995) (xy 89.706111 -348.259514) (xy 89.735504 -348.26869)
			(xy 89.766296 -348.26869) (xy 89.795689 -348.259514) (xy 89.821013 -348.241995) (xy 89.83091 -348.23019)
			(xy 89.849093 -348.2077) (xy 89.891115 -348.167965) (xy 89.938651 -348.135027) (xy 89.990614 -348.10964)
			(xy 90.045813 -348.092385) (xy 90.102984 -348.083658) (xy 90.1319 -348.083124) (xy 90.159154 -348.083546)
			(xy 90.213106 -348.091303) (xy 90.265405 -348.106659) (xy 90.314986 -348.129302) (xy 90.360841 -348.158771)
			(xy 90.402034 -348.194466) (xy 90.437729 -348.235659) (xy 90.467198 -348.281514) (xy 90.489841 -348.331095)
			(xy 90.505197 -348.383394) (xy 90.512954 -348.437346) (xy 90.512954 -348.491854) (xy 90.509949 -348.512757)
			(xy 90.715215 -348.512757) (xy 90.715215 -348.458243) (xy 90.722974 -348.404283) (xy 90.738333 -348.351976)
			(xy 90.760981 -348.302388) (xy 90.790456 -348.256528) (xy 90.826157 -348.21533) (xy 90.867359 -348.179633)
			(xy 90.913222 -348.150163) (xy 90.962812 -348.12752) (xy 91.01512 -348.112166) (xy 91.06908 -348.104412)
			(xy 91.096338 -348.103952) (xy 91.125254 -348.104495) (xy 91.182425 -348.113217) (xy 91.237624 -348.130468)
			(xy 91.289586 -348.155855) (xy 91.337121 -348.188795) (xy 91.379138 -348.228534) (xy 91.397328 -348.251018)
			(xy 91.407225 -348.262823) (xy 91.432549 -348.280342) (xy 91.461942 -348.289518) (xy 91.492734 -348.289518)
			(xy 91.522127 -348.280342) (xy 91.547451 -348.262823) (xy 91.557348 -348.251018) (xy 91.574101 -348.230235)
			(xy 91.612455 -348.193105) (xy 91.655609 -348.161683) (xy 91.702723 -348.136584) (xy 91.752875 -348.118298)
			(xy 91.805086 -348.107181) (xy 91.858338 -348.103451) (xy 91.91159 -348.107181) (xy 91.963801 -348.118298)
			(xy 92.013953 -348.136584) (xy 92.061067 -348.161683) (xy 92.104221 -348.193105) (xy 92.142575 -348.230235)
			(xy 92.159328 -348.251018) (xy 92.169225 -348.262823) (xy 92.194549 -348.280342) (xy 92.223942 -348.289518)
			(xy 92.254734 -348.289518) (xy 92.284127 -348.280342) (xy 92.309451 -348.262823) (xy 92.319348 -348.251018)
			(xy 92.336101 -348.230235) (xy 92.374455 -348.193105) (xy 92.417609 -348.161683) (xy 92.464723 -348.136584)
			(xy 92.514875 -348.118298) (xy 92.567086 -348.107181) (xy 92.620338 -348.103451) (xy 92.67359 -348.107181)
			(xy 92.725801 -348.118298) (xy 92.775953 -348.136584) (xy 92.823067 -348.161683) (xy 92.866221 -348.193105)
			(xy 92.904575 -348.230235) (xy 92.921328 -348.251018) (xy 92.931225 -348.262823) (xy 92.956549 -348.280342)
			(xy 92.985942 -348.289518) (xy 93.016734 -348.289518) (xy 93.046127 -348.280342) (xy 93.071451 -348.262823)
			(xy 93.081348 -348.251018) (xy 93.099573 -348.228563) (xy 93.141585 -348.188825) (xy 93.189113 -348.155882)
			(xy 93.241067 -348.130489) (xy 93.296259 -348.113227) (xy 93.353424 -348.104491) (xy 93.382338 -348.103952)
			(xy 93.410905 -348.104492) (xy 93.467399 -348.113024) (xy 93.521992 -348.129875) (xy 93.573466 -348.15467)
			(xy 93.620672 -348.186857) (xy 93.662557 -348.225716) (xy 93.680788 -348.247716) (xy 93.690372 -348.258945)
			(xy 93.714608 -348.275783) (xy 93.742643 -348.284996) (xy 93.772143 -348.285814) (xy 93.800646 -348.278172)
			(xy 93.825779 -348.262704) (xy 93.835982 -348.252034) (xy 93.854145 -348.232411) (xy 93.895029 -348.197953)
			(xy 93.940324 -348.16954) (xy 93.989143 -348.147728) (xy 94.040528 -348.132946) (xy 94.093473 -348.125482)
			(xy 94.120208 -348.125034) (xy 94.149123 -348.125606) (xy 94.206292 -348.134322) (xy 94.261491 -348.151568)
			(xy 94.313453 -348.17695) (xy 94.360988 -348.209885) (xy 94.403007 -348.249618) (xy 94.421198 -348.2721)
			(xy 94.431095 -348.283905) (xy 94.456419 -348.301424) (xy 94.485812 -348.3106) (xy 94.516604 -348.3106)
			(xy 94.545997 -348.301424) (xy 94.571321 -348.283905) (xy 94.581218 -348.2721) (xy 94.599399 -348.249608)
			(xy 94.641421 -348.209873) (xy 94.688958 -348.176935) (xy 94.740921 -348.151548) (xy 94.79612 -348.134294)
			(xy 94.853291 -348.125568) (xy 94.882208 -348.125034) (xy 94.909462 -348.125436) (xy 94.963415 -348.133195)
			(xy 95.015714 -348.148552) (xy 95.065296 -348.171196) (xy 95.11115 -348.200666) (xy 95.152344 -348.236362)
			(xy 95.188039 -348.277556) (xy 95.217508 -348.323411) (xy 95.240151 -348.372993) (xy 95.255507 -348.425293)
			(xy 95.263264 -348.479246) (xy 95.263264 -348.512752) (xy 95.383338 -348.512752) (xy 95.383338 -348.458248)
			(xy 95.391094 -348.404299) (xy 95.406448 -348.352003) (xy 95.429088 -348.302424) (xy 95.458553 -348.256571)
			(xy 95.494242 -348.215378) (xy 95.535431 -348.179683) (xy 95.58128 -348.150212) (xy 95.630856 -348.127565)
			(xy 95.68315 -348.112204) (xy 95.737098 -348.104441) (xy 95.76435 -348.103952) (xy 95.793267 -348.104486)
			(xy 95.850438 -348.113209) (xy 95.905637 -348.130463) (xy 95.9576 -348.155851) (xy 96.005134 -348.188793)
			(xy 96.04715 -348.228533) (xy 96.06534 -348.251018) (xy 96.075237 -348.262823) (xy 96.100561 -348.280342)
			(xy 96.129954 -348.289518) (xy 96.160746 -348.289518) (xy 96.190139 -348.280342) (xy 96.215463 -348.262823)
			(xy 96.22536 -348.251018) (xy 96.243578 -348.228557) (xy 96.285592 -348.18882) (xy 96.333121 -348.155878)
			(xy 96.385077 -348.130485) (xy 96.44027 -348.113224) (xy 96.497436 -348.10449) (xy 96.52635 -348.103952)
			(xy 96.553602 -348.104492) (xy 96.607553 -348.112242) (xy 96.659851 -348.127592) (xy 96.709433 -348.15023)
			(xy 96.755287 -348.179693) (xy 96.796482 -348.215383) (xy 96.832177 -348.256573) (xy 96.861646 -348.302423)
			(xy 96.88429 -348.352002) (xy 96.899647 -348.404298) (xy 96.907405 -348.458248) (xy 96.907405 -348.512752)
			(xy 96.899647 -348.566702) (xy 96.88429 -348.618998) (xy 96.861646 -348.668577) (xy 96.832177 -348.714427)
			(xy 96.796482 -348.755617) (xy 96.755287 -348.791307) (xy 96.709433 -348.82077) (xy 96.659851 -348.843408)
			(xy 96.607553 -348.858758) (xy 96.553602 -348.866508) (xy 96.52635 -348.866968) (xy 96.497434 -348.866426)
			(xy 96.440263 -348.857704) (xy 96.385064 -348.840451) (xy 96.333102 -348.815064) (xy 96.285568 -348.782124)
			(xy 96.24355 -348.742386) (xy 96.22536 -348.719902) (xy 96.215463 -348.708097) (xy 96.190139 -348.690578)
			(xy 96.160746 -348.681402) (xy 96.129954 -348.681402) (xy 96.100561 -348.690578) (xy 96.075237 -348.708097)
			(xy 96.06534 -348.719902) (xy 96.047127 -348.742367) (xy 96.005112 -348.782103) (xy 95.957581 -348.815044)
			(xy 95.905624 -348.840436) (xy 95.850431 -348.857696) (xy 95.793265 -348.86643) (xy 95.76435 -348.866968)
			(xy 95.737098 -348.866559) (xy 95.68315 -348.858796) (xy 95.630856 -348.843435) (xy 95.58128 -348.820788)
			(xy 95.535431 -348.791317) (xy 95.494242 -348.755622) (xy 95.458553 -348.714429) (xy 95.429088 -348.668576)
			(xy 95.406448 -348.618997) (xy 95.391094 -348.566701) (xy 95.383338 -348.512752) (xy 95.263264 -348.512752)
			(xy 95.263264 -348.533754) (xy 95.255507 -348.587707) (xy 95.240151 -348.640007) (xy 95.217508 -348.689589)
			(xy 95.188039 -348.735444) (xy 95.152344 -348.776638) (xy 95.11115 -348.812334) (xy 95.065296 -348.841804)
			(xy 95.015714 -348.864448) (xy 94.963415 -348.879805) (xy 94.909462 -348.887564) (xy 94.882208 -348.88805)
			(xy 94.85329 -348.887545) (xy 94.796118 -348.878816) (xy 94.740918 -348.861556) (xy 94.688956 -348.836162)
			(xy 94.641422 -348.803216) (xy 94.599407 -348.763471) (xy 94.581218 -348.740984) (xy 94.571321 -348.729179)
			(xy 94.545997 -348.71166) (xy 94.516604 -348.702484) (xy 94.485812 -348.702484) (xy 94.456419 -348.71166)
			(xy 94.431095 -348.729179) (xy 94.421198 -348.740984) (xy 94.403004 -348.763465) (xy 94.360985 -348.803201)
			(xy 94.313451 -348.836141) (xy 94.26149 -348.86153) (xy 94.206293 -348.878786) (xy 94.149124 -348.887515)
			(xy 94.120208 -348.88805) (xy 94.091642 -348.887476) (xy 94.03515 -348.878952) (xy 93.980557 -348.862107)
			(xy 93.929083 -348.837318) (xy 93.881876 -348.805137) (xy 93.83999 -348.766284) (xy 93.821758 -348.744286)
			(xy 93.812126 -348.733102) (xy 93.787903 -348.716262) (xy 93.75988 -348.707045) (xy 93.730391 -348.706217)
			(xy 93.701895 -348.713849) (xy 93.676767 -348.729304) (xy 93.666564 -348.739968) (xy 93.648379 -348.759569)
			(xy 93.607499 -348.794029) (xy 93.562209 -348.822445) (xy 93.513395 -348.84426) (xy 93.462014 -348.859047)
			(xy 93.409071 -348.866516) (xy 93.382338 -348.866968) (xy 93.353422 -348.866435) (xy 93.29625 -348.85771)
			(xy 93.241051 -348.840456) (xy 93.189089 -348.815068) (xy 93.141555 -348.782126) (xy 93.099538 -348.742387)
			(xy 93.081348 -348.719902) (xy 93.071451 -348.708097) (xy 93.046127 -348.690578) (xy 93.016734 -348.681402)
			(xy 92.985942 -348.681402) (xy 92.956549 -348.690578) (xy 92.931225 -348.708097) (xy 92.921328 -348.719902)
			(xy 92.904575 -348.740685) (xy 92.866221 -348.777815) (xy 92.823067 -348.809237) (xy 92.775953 -348.834336)
			(xy 92.725801 -348.852622) (xy 92.67359 -348.863739) (xy 92.620338 -348.867469) (xy 92.567086 -348.863739)
			(xy 92.514875 -348.852622) (xy 92.464723 -348.834336) (xy 92.417609 -348.809237) (xy 92.374455 -348.777815)
			(xy 92.336101 -348.740685) (xy 92.319348 -348.719902) (xy 92.309451 -348.708097) (xy 92.284127 -348.690578)
			(xy 92.254734 -348.681402) (xy 92.223942 -348.681402) (xy 92.194549 -348.690578) (xy 92.169225 -348.708097)
			(xy 92.159328 -348.719902) (xy 92.142575 -348.740685) (xy 92.104221 -348.777815) (xy 92.061067 -348.809237)
			(xy 92.013953 -348.834336) (xy 91.963801 -348.852622) (xy 91.91159 -348.863739) (xy 91.858338 -348.867469)
			(xy 91.805086 -348.863739) (xy 91.752875 -348.852622) (xy 91.702723 -348.834336) (xy 91.655609 -348.809237)
			(xy 91.612455 -348.777815) (xy 91.574101 -348.740685) (xy 91.557348 -348.719902) (xy 91.547451 -348.708097)
			(xy 91.522127 -348.690578) (xy 91.492734 -348.681402) (xy 91.461942 -348.681402) (xy 91.432549 -348.690578)
			(xy 91.407225 -348.708097) (xy 91.397328 -348.719902) (xy 91.379122 -348.742372) (xy 91.337105 -348.782108)
			(xy 91.289573 -348.815049) (xy 91.237615 -348.840439) (xy 91.18242 -348.857699) (xy 91.125253 -348.866431)
			(xy 91.096338 -348.866968) (xy 91.06908 -348.866588) (xy 91.01512 -348.858834) (xy 90.962812 -348.84348)
			(xy 90.913222 -348.820837) (xy 90.867359 -348.791367) (xy 90.826157 -348.75567) (xy 90.790456 -348.714472)
			(xy 90.760981 -348.668612) (xy 90.738333 -348.619024) (xy 90.722974 -348.566717) (xy 90.715215 -348.512757)
			(xy 90.509949 -348.512757) (xy 90.505197 -348.545806) (xy 90.489841 -348.598105) (xy 90.467198 -348.647686)
			(xy 90.437729 -348.693541) (xy 90.402034 -348.734734) (xy 90.360841 -348.770429) (xy 90.314986 -348.799898)
			(xy 90.265405 -348.822541) (xy 90.213106 -348.837897) (xy 90.159154 -348.845654) (xy 90.1319 -348.84614)
			(xy 90.102982 -348.845644) (xy 90.045809 -348.836914) (xy 89.990608 -348.819653) (xy 89.938646 -348.794257)
			(xy 89.891113 -348.761308) (xy 89.849098 -348.721562) (xy 89.83091 -348.699074) (xy 89.821013 -348.687269)
			(xy 89.795689 -348.66975) (xy 89.766296 -348.660574) (xy 89.735504 -348.660574) (xy 89.706111 -348.66975)
			(xy 89.680787 -348.687269) (xy 89.67089 -348.699074) (xy 89.652698 -348.721557) (xy 89.610679 -348.761293)
			(xy 89.563145 -348.794233) (xy 89.511184 -348.819622) (xy 89.455986 -348.836878) (xy 89.398816 -348.845606)
			(xy 89.3699 -348.84614) (xy 89.343668 -348.845697) (xy 89.291696 -348.838529) (xy 89.241195 -348.824316)
			(xy 89.193114 -348.803323) (xy 89.17051 -348.790006) (xy 89.160875 -348.784726) (xy 89.139075 -348.782162)
			(xy 89.118188 -348.788913) (xy 89.102011 -348.80375) (xy 89.093486 -348.823978) (xy 89.093294 -348.834964)
			(xy 89.093548 -348.848172) (xy 89.093485 -348.85931) (xy 89.092212 -348.881549) (xy 89.091008 -348.892622)
			(xy 89.089693 -348.907591) (xy 89.094978 -348.937162) (xy 89.108636 -348.963917) (xy 89.129485 -348.985543)
			(xy 89.155724 -349.000168) (xy 89.185082 -349.00653) (xy 89.215021 -349.004077) (xy 89.229184 -348.999048)
			(xy 89.251653 -348.990521) (xy 89.298193 -348.978532) (xy 89.34587 -348.972489) (xy 89.3699 -348.972124)
			(xy 89.398817 -348.972633) (xy 89.455989 -348.981363) (xy 89.511189 -348.998622) (xy 89.563151 -349.024015)
			(xy 89.610684 -349.056961) (xy 89.6527 -349.096704) (xy 89.67089 -349.11919) (xy 89.680787 -349.130995)
			(xy 89.706111 -349.148514) (xy 89.735504 -349.15769) (xy 89.766296 -349.15769) (xy 89.795689 -349.148514)
			(xy 89.821013 -349.130995) (xy 89.83091 -349.11919) (xy 89.849093 -349.0967) (xy 89.891115 -349.056965)
			(xy 89.938651 -349.024027) (xy 89.990614 -348.99864) (xy 90.045813 -348.981385) (xy 90.102984 -348.972658)
			(xy 90.1319 -348.972124) (xy 90.159154 -348.972555) (xy 90.213108 -348.980313) (xy 90.265408 -348.995671)
			(xy 90.314991 -349.018316) (xy 90.360845 -349.047787) (xy 90.402039 -349.083484) (xy 90.437733 -349.12468)
			(xy 90.4672 -349.170537) (xy 90.48984 -349.220122) (xy 90.505194 -349.272423) (xy 90.512947 -349.326378)
			(xy 90.513408 -349.353632) (xy 90.512876 -349.382549) (xy 90.504154 -349.439721) (xy 90.486902 -349.494921)
			(xy 90.461513 -349.546884) (xy 90.42857 -349.594417) (xy 90.388828 -349.636433) (xy 90.366342 -349.654622)
			(xy 90.354502 -349.664483) (xy 90.33698 -349.689815) (xy 90.327805 -349.719219) (xy 90.327811 -349.750021)
			(xy 90.336997 -349.779421) (xy 90.354529 -349.804746) (xy 90.366342 -349.814642) (xy 90.387156 -349.831358)
			(xy 90.424287 -349.869715) (xy 90.455708 -349.912875) (xy 90.480807 -349.959992) (xy 90.499092 -350.010149)
			(xy 90.510206 -350.062365) (xy 90.513933 -350.11562) (xy 90.512473 -350.13646) (xy 90.71483 -350.13646)
			(xy 90.71538 -350.107544) (xy 90.724101 -350.050374) (xy 90.741352 -349.995175) (xy 90.766737 -349.943213)
			(xy 90.799676 -349.895678) (xy 90.839412 -349.853661) (xy 90.861896 -349.83547) (xy 90.87374 -349.825616)
			(xy 90.891256 -349.80028) (xy 90.900426 -349.770876) (xy 90.900419 -349.740075) (xy 90.891234 -349.710676)
			(xy 90.873706 -349.685348) (xy 90.861896 -349.67545) (xy 90.839436 -349.657232) (xy 90.799699 -349.615218)
			(xy 90.766758 -349.567688) (xy 90.741365 -349.515732) (xy 90.724104 -349.46054) (xy 90.715369 -349.403374)
			(xy 90.71483 -349.37446) (xy 90.715241 -349.347206) (xy 90.723004 -349.293254) (xy 90.738366 -349.240955)
			(xy 90.761014 -349.191375) (xy 90.790488 -349.145523) (xy 90.826188 -349.104332) (xy 90.867386 -349.068642)
			(xy 90.913244 -349.039177) (xy 90.962828 -349.016538) (xy 91.01513 -349.001187) (xy 91.069084 -348.993435)
			(xy 91.096338 -348.992952) (xy 91.125254 -348.993495) (xy 91.182425 -349.002217) (xy 91.237624 -349.019468)
			(xy 91.289586 -349.044855) (xy 91.337121 -349.077795) (xy 91.379138 -349.117534) (xy 91.397328 -349.140018)
			(xy 91.407225 -349.151823) (xy 91.432549 -349.169342) (xy 91.461942 -349.178518) (xy 91.492734 -349.178518)
			(xy 91.522127 -349.169342) (xy 91.547451 -349.151823) (xy 91.557348 -349.140018) (xy 91.574101 -349.119235)
			(xy 91.612455 -349.082105) (xy 91.655609 -349.050683) (xy 91.702723 -349.025584) (xy 91.752875 -349.007298)
			(xy 91.805086 -348.996181) (xy 91.858338 -348.992451) (xy 91.91159 -348.996181) (xy 91.963801 -349.007298)
			(xy 92.013953 -349.025584) (xy 92.061067 -349.050683) (xy 92.104221 -349.082105) (xy 92.142575 -349.119235)
			(xy 92.159328 -349.140018) (xy 92.169225 -349.151823) (xy 92.194549 -349.169342) (xy 92.223942 -349.178518)
			(xy 92.254734 -349.178518) (xy 92.284127 -349.169342) (xy 92.309451 -349.151823) (xy 92.319348 -349.140018)
			(xy 92.336101 -349.119235) (xy 92.374455 -349.082105) (xy 92.417609 -349.050683) (xy 92.464723 -349.025584)
			(xy 92.514875 -349.007298) (xy 92.567086 -348.996181) (xy 92.620338 -348.992451) (xy 92.67359 -348.996181)
			(xy 92.725801 -349.007298) (xy 92.775953 -349.025584) (xy 92.823067 -349.050683) (xy 92.866221 -349.082105)
			(xy 92.904575 -349.119235) (xy 92.921328 -349.140018) (xy 92.931225 -349.151823) (xy 92.956549 -349.169342)
			(xy 92.985942 -349.178518) (xy 93.016734 -349.178518) (xy 93.046127 -349.169342) (xy 93.071451 -349.151823)
			(xy 93.081348 -349.140018) (xy 93.099573 -349.117563) (xy 93.141585 -349.077825) (xy 93.189113 -349.044882)
			(xy 93.241067 -349.019489) (xy 93.296259 -349.002227) (xy 93.353424 -348.993491) (xy 93.382338 -348.992952)
			(xy 93.410905 -348.993492) (xy 93.467399 -349.002024) (xy 93.521992 -349.018875) (xy 93.573466 -349.04367)
			(xy 93.620672 -349.075857) (xy 93.662557 -349.114716) (xy 93.680788 -349.136716) (xy 93.690372 -349.147945)
			(xy 93.714608 -349.164783) (xy 93.742643 -349.173996) (xy 93.772143 -349.174814) (xy 93.800646 -349.167172)
			(xy 93.825779 -349.151704) (xy 93.835982 -349.141034) (xy 93.854145 -349.121411) (xy 93.895029 -349.086953)
			(xy 93.940324 -349.05854) (xy 93.989143 -349.036728) (xy 94.040528 -349.021946) (xy 94.093473 -349.014482)
			(xy 94.120208 -349.014034) (xy 94.149123 -349.014606) (xy 94.206292 -349.023322) (xy 94.261491 -349.040568)
			(xy 94.313453 -349.06595) (xy 94.360988 -349.098885) (xy 94.403007 -349.138618) (xy 94.421198 -349.1611)
			(xy 94.431095 -349.172905) (xy 94.456419 -349.190424) (xy 94.485812 -349.1996) (xy 94.516604 -349.1996)
			(xy 94.545997 -349.190424) (xy 94.571321 -349.172905) (xy 94.581218 -349.1611) (xy 94.599399 -349.138608)
			(xy 94.641421 -349.098873) (xy 94.688958 -349.065935) (xy 94.740921 -349.040548) (xy 94.79612 -349.023294)
			(xy 94.853291 -349.014568) (xy 94.882208 -349.014034) (xy 94.909463 -349.014448) (xy 94.963418 -349.022207)
			(xy 95.015719 -349.037566) (xy 95.065302 -349.060213) (xy 95.111157 -349.089686) (xy 95.152351 -349.125385)
			(xy 95.188044 -349.166583) (xy 95.217511 -349.212442) (xy 95.240151 -349.262028) (xy 95.255503 -349.314331)
			(xy 95.263256 -349.368287) (xy 95.263716 -349.395542) (xy 95.26314 -349.424984) (xy 95.254075 -349.483167)
			(xy 95.236182 -349.539267) (xy 95.209886 -349.591954) (xy 95.17581 -349.639978) (xy 95.134764 -349.682198)
			(xy 95.11157 -349.700342) (xy 95.101069 -349.708669) (xy 95.084553 -349.729767) (xy 95.074096 -349.754435)
			(xy 95.070417 -349.780975) (xy 95.073771 -349.807558) (xy 95.083926 -349.832353) (xy 95.100182 -349.853651)
			(xy 95.110554 -349.86214) (xy 95.133163 -349.880342) (xy 95.173168 -349.922394) (xy 95.20634 -349.970022)
			(xy 95.231914 -350.022125) (xy 95.249298 -350.077501) (xy 95.258093 -350.134872) (xy 95.258123 -350.136475)
			(xy 95.382291 -350.136475) (xy 95.386025 -350.083218) (xy 95.397148 -350.031001) (xy 95.415441 -349.980845)
			(xy 95.440549 -349.933729) (xy 95.471979 -349.890574) (xy 95.50912 -349.852222) (xy 95.529908 -349.83547)
			(xy 95.541751 -349.825615) (xy 95.559264 -349.800279) (xy 95.568434 -349.770875) (xy 95.568426 -349.740076)
			(xy 95.559243 -349.710677) (xy 95.541717 -349.685349) (xy 95.529908 -349.67545) (xy 95.50745 -349.657229)
			(xy 95.467713 -349.615216) (xy 95.434771 -349.567687) (xy 95.409378 -349.515732) (xy 95.392116 -349.460539)
			(xy 95.383381 -349.403374) (xy 95.382842 -349.37446) (xy 95.383218 -349.347204) (xy 95.390982 -349.293247)
			(xy 95.406345 -349.240945) (xy 95.428996 -349.191361) (xy 95.458473 -349.145506) (xy 95.494176 -349.104312)
			(xy 95.535378 -349.068619) (xy 95.58124 -349.039153) (xy 95.630829 -349.016514) (xy 95.683135 -349.001162)
			(xy 95.737094 -348.993411) (xy 95.76435 -348.992952) (xy 95.793267 -348.993486) (xy 95.850438 -349.002209)
			(xy 95.905637 -349.019463) (xy 95.9576 -349.044851) (xy 96.005134 -349.077793) (xy 96.04715 -349.117533)
			(xy 96.06534 -349.140018) (xy 96.075237 -349.151823) (xy 96.100561 -349.169342) (xy 96.129954 -349.178518)
			(xy 96.160746 -349.178518) (xy 96.190139 -349.169342) (xy 96.215463 -349.151823) (xy 96.22536 -349.140018)
			(xy 96.243578 -349.117557) (xy 96.285592 -349.07782) (xy 96.333121 -349.044878) (xy 96.385077 -349.019485)
			(xy 96.44027 -349.002224) (xy 96.497436 -348.99349) (xy 96.52635 -348.992952) (xy 96.5536 -348.993502)
			(xy 96.607546 -349.001251) (xy 96.659839 -349.016598) (xy 96.709417 -349.039232) (xy 96.755268 -349.068691)
			(xy 96.79646 -349.104376) (xy 96.832155 -349.14556) (xy 96.861625 -349.191404) (xy 96.88427 -349.240976)
			(xy 96.89963 -349.293266) (xy 96.907392 -349.34721) (xy 96.907858 -349.37446) (xy 96.907327 -349.403377)
			(xy 96.898603 -349.460548) (xy 96.881348 -349.515747) (xy 96.855959 -349.567709) (xy 96.823017 -349.615243)
			(xy 96.783277 -349.65726) (xy 96.760792 -349.67545) (xy 96.749029 -349.685392) (xy 96.731514 -349.710704)
			(xy 96.722336 -349.740085) (xy 96.722329 -349.770866) (xy 96.731493 -349.800251) (xy 96.748995 -349.825572)
			(xy 96.760792 -349.83547) (xy 96.781538 -349.852269) (xy 96.818672 -349.890615) (xy 96.850097 -349.933763)
			(xy 96.875201 -349.980871) (xy 96.893491 -350.031019) (xy 96.904612 -350.083227) (xy 96.908345 -350.136475)
			(xy 96.904619 -350.189724) (xy 96.893505 -350.241934) (xy 96.875221 -350.292084) (xy 96.850124 -350.339195)
			(xy 96.818704 -350.382347) (xy 96.781574 -350.420698) (xy 96.760792 -350.43745) (xy 96.749029 -350.447392)
			(xy 96.731514 -350.472704) (xy 96.730329 -350.476496) (xy 115.595396 -350.476496) (xy 115.595396 -350.3918)
			(xy 115.603447 -350.307486) (xy 115.619476 -350.22432) (xy 115.643337 -350.143053) (xy 115.674816 -350.064423)
			(xy 115.713627 -349.989142) (xy 115.759417 -349.91789) (xy 115.811773 -349.851314) (xy 115.870221 -349.790016)
			(xy 115.934231 -349.734551) (xy 116.003223 -349.685422) (xy 116.076573 -349.643073) (xy 116.153616 -349.607889)
			(xy 116.233655 -349.580187) (xy 116.315964 -349.560219) (xy 116.399799 -349.548166) (xy 116.4844 -349.544136)
			(xy 116.569001 -349.548166) (xy 116.652836 -349.560219) (xy 116.735145 -349.580187) (xy 116.815184 -349.607889)
			(xy 116.892227 -349.643073) (xy 116.965577 -349.685422) (xy 117.034569 -349.734551) (xy 117.098579 -349.790016)
			(xy 117.157027 -349.851314) (xy 117.209383 -349.91789) (xy 117.255173 -349.989142) (xy 117.293984 -350.064423)
			(xy 117.325463 -350.143053) (xy 117.349324 -350.22432) (xy 117.365353 -350.307486) (xy 117.373404 -350.3918)
			(xy 117.373908 -350.434148) (xy 118.119909 -350.434148) (xy 118.123945 -350.350701) (xy 118.136017 -350.268033)
			(xy 118.15601 -350.186916) (xy 118.183739 -350.108107) (xy 118.218945 -350.032342) (xy 118.261299 -349.960329)
			(xy 118.310405 -349.89274) (xy 118.365806 -349.830206) (xy 118.426983 -349.773311) (xy 118.493366 -349.722585)
			(xy 118.564334 -349.678504) (xy 118.639226 -349.641478) (xy 118.717342 -349.611852) (xy 118.797952 -349.589904)
			(xy 118.880304 -349.575839) (xy 118.96363 -349.569787) (xy 119.04715 -349.571806) (xy 119.130086 -349.581876)
			(xy 119.211662 -349.599904) (xy 119.291118 -349.625721) (xy 119.367711 -349.659086) (xy 119.440727 -349.699687)
			(xy 119.509483 -349.747146) (xy 119.573337 -349.801019) (xy 119.631694 -349.860804) (xy 119.684009 -349.925941)
			(xy 119.729792 -349.995824) (xy 119.768617 -350.069799) (xy 119.800122 -350.147176) (xy 119.824011 -350.227233)
			(xy 119.840062 -350.309221) (xy 119.848125 -350.392376) (xy 119.84863 -350.434148) (xy 119.848125 -350.47592)
			(xy 119.840062 -350.559075) (xy 119.824011 -350.641063) (xy 119.800122 -350.72112) (xy 119.768617 -350.798497)
			(xy 119.729792 -350.872472) (xy 119.684009 -350.942355) (xy 119.631694 -351.007492) (xy 119.573337 -351.067277)
			(xy 119.509483 -351.12115) (xy 119.440727 -351.168609) (xy 119.367711 -351.20921) (xy 119.291118 -351.242575)
			(xy 119.211662 -351.268392) (xy 119.130086 -351.28642) (xy 119.04715 -351.29649) (xy 118.96363 -351.298509)
			(xy 118.880304 -351.292457) (xy 118.797952 -351.278392) (xy 118.717342 -351.256444) (xy 118.639226 -351.226818)
			(xy 118.564334 -351.189792) (xy 118.493366 -351.145711) (xy 118.426983 -351.094985) (xy 118.365806 -351.03809)
			(xy 118.310405 -350.975556) (xy 118.261299 -350.907967) (xy 118.218945 -350.835954) (xy 118.183739 -350.760189)
			(xy 118.15601 -350.68138) (xy 118.136017 -350.600263) (xy 118.123945 -350.517595) (xy 118.119909 -350.434148)
			(xy 117.373908 -350.434148) (xy 117.373404 -350.476496) (xy 117.365353 -350.56081) (xy 117.349324 -350.643976)
			(xy 117.325463 -350.725243) (xy 117.293984 -350.803873) (xy 117.255173 -350.879154) (xy 117.209383 -350.950406)
			(xy 117.157027 -351.016982) (xy 117.098579 -351.07828) (xy 117.034569 -351.133745) (xy 116.965577 -351.182874)
			(xy 116.892227 -351.225223) (xy 116.815184 -351.260407) (xy 116.735145 -351.288109) (xy 116.652836 -351.308077)
			(xy 116.569001 -351.32013) (xy 116.4844 -351.324161) (xy 116.399799 -351.32013) (xy 116.315964 -351.308077)
			(xy 116.233655 -351.288109) (xy 116.153616 -351.260407) (xy 116.076573 -351.225223) (xy 116.003223 -351.182874)
			(xy 115.934231 -351.133745) (xy 115.870221 -351.07828) (xy 115.811773 -351.016982) (xy 115.759417 -350.950406)
			(xy 115.713627 -350.879154) (xy 115.674816 -350.803873) (xy 115.643337 -350.725243) (xy 115.619476 -350.643976)
			(xy 115.603447 -350.56081) (xy 115.595396 -350.476496) (xy 96.730329 -350.476496) (xy 96.722336 -350.502085)
			(xy 96.722329 -350.532866) (xy 96.731493 -350.562251) (xy 96.748995 -350.587572) (xy 96.760792 -350.59747)
			(xy 96.783259 -350.61568) (xy 96.822996 -350.657696) (xy 96.855937 -350.705226) (xy 96.881328 -350.757184)
			(xy 96.898588 -350.812378) (xy 96.907321 -350.869545) (xy 96.907858 -350.89846) (xy 96.907407 -350.925714)
			(xy 96.899655 -350.979668) (xy 96.884301 -351.031969) (xy 96.86166 -351.081553) (xy 96.832191 -351.127408)
			(xy 96.796496 -351.168603) (xy 96.7553 -351.204297) (xy 96.709444 -351.233764) (xy 96.65986 -351.256405)
			(xy 96.607558 -351.271757) (xy 96.553604 -351.279508) (xy 96.52635 -351.279968) (xy 96.497434 -351.279426)
			(xy 96.440263 -351.270704) (xy 96.385064 -351.253451) (xy 96.333102 -351.228064) (xy 96.285568 -351.195124)
			(xy 96.24355 -351.155386) (xy 96.22536 -351.132902) (xy 96.215463 -351.121097) (xy 96.190139 -351.103578)
			(xy 96.160746 -351.094402) (xy 96.129954 -351.094402) (xy 96.100561 -351.103578) (xy 96.075237 -351.121097)
			(xy 96.06534 -351.132902) (xy 96.047127 -351.155367) (xy 96.005112 -351.195103) (xy 95.957581 -351.228044)
			(xy 95.905624 -351.253436) (xy 95.850431 -351.270696) (xy 95.793265 -351.27943) (xy 95.76435 -351.279968)
			(xy 95.737097 -351.279498) (xy 95.683144 -351.271747) (xy 95.630844 -351.256395) (xy 95.581261 -351.233756)
			(xy 95.535406 -351.204289) (xy 95.494211 -351.168596) (xy 95.458517 -351.127402) (xy 95.429049 -351.081548)
			(xy 95.406408 -351.031966) (xy 95.391055 -350.979666) (xy 95.383303 -350.925713) (xy 95.382842 -350.89846)
			(xy 95.383387 -350.869544) (xy 95.392108 -350.812373) (xy 95.40936 -350.757174) (xy 95.434746 -350.705212)
			(xy 95.467686 -350.657678) (xy 95.507424 -350.61566) (xy 95.529908 -350.59747) (xy 95.541751 -350.587615)
			(xy 95.559264 -350.562279) (xy 95.568434 -350.532875) (xy 95.568426 -350.502076) (xy 95.559243 -350.472677)
			(xy 95.541717 -350.447349) (xy 95.529908 -350.43745) (xy 95.509083 -350.420745) (xy 95.471948 -350.382388)
			(xy 95.440522 -350.339229) (xy 95.415421 -350.29211) (xy 95.397134 -350.241951) (xy 95.386018 -350.189733)
			(xy 95.382291 -350.136475) (xy 95.258123 -350.136475) (xy 95.258636 -350.163892) (xy 95.25815 -350.191143)
			(xy 95.250394 -350.245091) (xy 95.235039 -350.297386) (xy 95.212397 -350.346963) (xy 95.182931 -350.392813)
			(xy 95.14724 -350.434004) (xy 95.106049 -350.469695) (xy 95.060199 -350.499161) (xy 95.010622 -350.521803)
			(xy 94.958327 -350.537158) (xy 94.904379 -350.544914) (xy 94.849877 -350.544914) (xy 94.795929 -350.537158)
			(xy 94.743634 -350.521803) (xy 94.694057 -350.499161) (xy 94.648207 -350.469695) (xy 94.607016 -350.434004)
			(xy 94.571325 -350.392813) (xy 94.541859 -350.346963) (xy 94.519217 -350.297386) (xy 94.503862 -350.245091)
			(xy 94.496106 -350.191143) (xy 94.49562 -350.163892) (xy 94.496134 -350.134447) (xy 94.50521 -350.076261)
			(xy 94.523114 -350.020159) (xy 94.549422 -349.967472) (xy 94.583509 -349.91945) (xy 94.624567 -349.877233)
			(xy 94.647766 -349.859092) (xy 94.65823 -349.850724) (xy 94.67474 -349.829634) (xy 94.685196 -349.804975)
			(xy 94.688878 -349.778445) (xy 94.685532 -349.751871) (xy 94.675388 -349.727082) (xy 94.659146 -349.705784)
			(xy 94.648782 -349.697294) (xy 94.63008 -349.682385) (xy 94.596195 -349.648631) (xy 94.581218 -349.629984)
			(xy 94.571321 -349.618179) (xy 94.545997 -349.60066) (xy 94.516604 -349.591484) (xy 94.485812 -349.591484)
			(xy 94.456419 -349.60066) (xy 94.431095 -349.618179) (xy 94.421198 -349.629984) (xy 94.403004 -349.652465)
			(xy 94.360985 -349.692201) (xy 94.313451 -349.725141) (xy 94.26149 -349.75053) (xy 94.206293 -349.767786)
			(xy 94.149124 -349.776515) (xy 94.120208 -349.77705) (xy 94.091642 -349.776476) (xy 94.03515 -349.767952)
			(xy 93.980557 -349.751107) (xy 93.929083 -349.726318) (xy 93.881876 -349.694137) (xy 93.83999 -349.655284)
			(xy 93.821758 -349.633286) (xy 93.812126 -349.622102) (xy 93.787903 -349.605262) (xy 93.75988 -349.596045)
			(xy 93.730391 -349.595217) (xy 93.701895 -349.602849) (xy 93.676767 -349.618304) (xy 93.666564 -349.628968)
			(xy 93.648379 -349.648569) (xy 93.607499 -349.683029) (xy 93.562209 -349.711445) (xy 93.513395 -349.73326)
			(xy 93.462014 -349.748047) (xy 93.409071 -349.755516) (xy 93.382338 -349.755968) (xy 93.353422 -349.755435)
			(xy 93.29625 -349.74671) (xy 93.241051 -349.729456) (xy 93.189089 -349.704068) (xy 93.141555 -349.671126)
			(xy 93.099538 -349.631387) (xy 93.081348 -349.608902) (xy 93.071451 -349.597097) (xy 93.046127 -349.579578)
			(xy 93.016734 -349.570402) (xy 92.985942 -349.570402) (xy 92.956549 -349.579578) (xy 92.931225 -349.597097)
			(xy 92.921328 -349.608902) (xy 92.904575 -349.629685) (xy 92.866221 -349.666815) (xy 92.823067 -349.698237)
			(xy 92.775953 -349.723336) (xy 92.725801 -349.741622) (xy 92.67359 -349.752739) (xy 92.620338 -349.756469)
			(xy 92.567086 -349.752739) (xy 92.514875 -349.741622) (xy 92.464723 -349.723336) (xy 92.417609 -349.698237)
			(xy 92.374455 -349.666815) (xy 92.336101 -349.629685) (xy 92.319348 -349.608902) (xy 92.309451 -349.597097)
			(xy 92.284127 -349.579578) (xy 92.254734 -349.570402) (xy 92.223942 -349.570402) (xy 92.194549 -349.579578)
			(xy 92.169225 -349.597097) (xy 92.159328 -349.608902) (xy 92.142575 -349.629685) (xy 92.104221 -349.666815)
			(xy 92.061067 -349.698237) (xy 92.013953 -349.723336) (xy 91.963801 -349.741622) (xy 91.91159 -349.752739)
			(xy 91.858338 -349.756469) (xy 91.805086 -349.752739) (xy 91.752875 -349.741622) (xy 91.702723 -349.723336)
			(xy 91.655609 -349.698237) (xy 91.612455 -349.666815) (xy 91.574101 -349.629685) (xy 91.557348 -349.608902)
			(xy 91.547451 -349.597097) (xy 91.522127 -349.579578) (xy 91.492734 -349.570402) (xy 91.461942 -349.570402)
			(xy 91.432549 -349.579578) (xy 91.407225 -349.597097) (xy 91.397328 -349.608902) (xy 91.382552 -349.627303)
			(xy 91.34918 -349.660673) (xy 91.33078 -349.67545) (xy 91.319018 -349.685393) (xy 91.301506 -349.710705)
			(xy 91.292329 -349.740086) (xy 91.292321 -349.770865) (xy 91.301484 -349.80025) (xy 91.318984 -349.825571)
			(xy 91.33078 -349.83547) (xy 91.353245 -349.853683) (xy 91.392982 -349.895698) (xy 91.425924 -349.943228)
			(xy 91.451316 -349.995185) (xy 91.468576 -350.050379) (xy 91.477309 -350.107545) (xy 91.477846 -350.13646)
			(xy 91.47736 -350.163711) (xy 91.469604 -350.217659) (xy 91.454249 -350.269954) (xy 91.431607 -350.319531)
			(xy 91.402141 -350.365381) (xy 91.36645 -350.406572) (xy 91.325259 -350.442263) (xy 91.279409 -350.471729)
			(xy 91.229832 -350.494371) (xy 91.177537 -350.509726) (xy 91.123589 -350.517482) (xy 91.069087 -350.517482)
			(xy 91.015139 -350.509726) (xy 90.962844 -350.494371) (xy 90.913267 -350.471729) (xy 90.867417 -350.442263)
			(xy 90.826226 -350.406572) (xy 90.790535 -350.365381) (xy 90.761069 -350.319531) (xy 90.738427 -350.269954)
			(xy 90.723072 -350.217659) (xy 90.715316 -350.163711) (xy 90.71483 -350.13646) (xy 90.512473 -350.13646)
			(xy 90.510201 -350.168874) (xy 90.499081 -350.221089) (xy 90.480791 -350.271244) (xy 90.455688 -350.318359)
			(xy 90.424262 -350.361515) (xy 90.387127 -350.399869) (xy 90.366342 -350.416622) (xy 90.354502 -350.426483)
			(xy 90.33698 -350.451815) (xy 90.327805 -350.481219) (xy 90.327811 -350.512021) (xy 90.336997 -350.541421)
			(xy 90.354529 -350.566746) (xy 90.366342 -350.576642) (xy 90.388854 -350.594799) (xy 90.428586 -350.636827)
			(xy 90.46152 -350.684369) (xy 90.486903 -350.736337) (xy 90.504154 -350.79154) (xy 90.512876 -350.848714)
			(xy 90.513408 -350.877632) (xy 90.512952 -350.904884) (xy 90.505191 -350.958833) (xy 90.489832 -351.011128)
			(xy 90.467187 -351.060705) (xy 90.437717 -351.106556) (xy 90.402023 -351.147746) (xy 90.36083 -351.183437)
			(xy 90.314977 -351.212902) (xy 90.265398 -351.235543) (xy 90.213102 -351.250898) (xy 90.159152 -351.258654)
			(xy 90.1319 -351.25914) (xy 90.102982 -351.258644) (xy 90.045809 -351.249914) (xy 89.990608 -351.232653)
			(xy 89.938646 -351.207257) (xy 89.891113 -351.174308) (xy 89.849098 -351.134562) (xy 89.83091 -351.112074)
			(xy 89.821013 -351.100269) (xy 89.795689 -351.08275) (xy 89.766296 -351.073574) (xy 89.735504 -351.073574)
			(xy 89.706111 -351.08275) (xy 89.680787 -351.100269) (xy 89.67089 -351.112074) (xy 89.652698 -351.134557)
			(xy 89.610679 -351.174293) (xy 89.563145 -351.207233) (xy 89.511184 -351.232622) (xy 89.455986 -351.249878)
			(xy 89.398816 -351.258606) (xy 89.3699 -351.25914) (xy 89.342694 -351.258661) (xy 89.288835 -351.250917)
			(xy 89.236622 -351.235599) (xy 89.187116 -351.21302) (xy 89.141319 -351.183636) (xy 89.100161 -351.148044)
			(xy 89.064477 -351.106966) (xy 89.03499 -351.061235) (xy 89.0123 -351.011779) (xy 88.996866 -350.959601)
			(xy 88.992456 -350.93275) (xy 88.989721 -350.91765) (xy 88.976444 -350.889996) (xy 88.955567 -350.867522)
			(xy 88.928965 -350.852247) (xy 88.89903 -350.845546) (xy 88.868455 -350.84802) (xy 88.854026 -350.853248)
			(xy 88.831378 -350.861945) (xy 88.784423 -350.874154) (xy 88.736298 -350.880304) (xy 88.71204 -350.88068)
			(xy 88.684787 -350.880207) (xy 88.630835 -350.872455) (xy 88.578535 -350.857103) (xy 88.528954 -350.834463)
			(xy 88.483099 -350.804996) (xy 88.441905 -350.769303) (xy 88.406211 -350.728111) (xy 88.376743 -350.682257)
			(xy 88.354101 -350.632676) (xy 88.338747 -350.580377) (xy 88.330993 -350.526425) (xy 88.330532 -350.499172)
			(xy 77.297099 -350.499172) (xy 77.780787 -351.700592) (xy 103.994964 -351.700592) (xy 103.999035 -351.64497)
			(xy 104.011161 -351.590533) (xy 104.031084 -351.538442) (xy 104.05838 -351.489807) (xy 104.092466 -351.445664)
			(xy 104.132615 -351.406955) (xy 104.177973 -351.374504) (xy 104.227573 -351.349003) (xy 104.280357 -351.330996)
			(xy 104.3352 -351.320866) (xy 104.390934 -351.318829) (xy 104.446371 -351.324929) (xy 104.500328 -351.339035)
			(xy 104.551657 -351.360847) (xy 104.599263 -351.389901) (xy 104.642131 -351.425576) (xy 104.679348 -351.467113)
			(xy 104.710121 -351.513626) (xy 104.733793 -351.564123) (xy 104.749861 -351.61753) (xy 104.757981 -351.672706)
			(xy 104.75849 -351.700592) (xy 104.757981 -351.728478) (xy 104.749861 -351.783654) (xy 104.733793 -351.837061)
			(xy 104.721086 -351.864168) (xy 104.858564 -351.864168) (xy 104.862635 -351.808546) (xy 104.874761 -351.754109)
			(xy 104.894684 -351.702018) (xy 104.92198 -351.653383) (xy 104.956066 -351.60924) (xy 104.996215 -351.570531)
			(xy 105.041573 -351.53808) (xy 105.091173 -351.512579) (xy 105.143957 -351.494572) (xy 105.1988 -351.484442)
			(xy 105.254534 -351.482405) (xy 105.309971 -351.488505) (xy 105.357567 -351.500948) (xy 105.871262 -351.500948)
			(xy 105.875333 -351.445326) (xy 105.887459 -351.390889) (xy 105.907382 -351.338798) (xy 105.934678 -351.290163)
			(xy 105.968764 -351.24602) (xy 106.008913 -351.207311) (xy 106.054271 -351.17486) (xy 106.103871 -351.149359)
			(xy 106.156655 -351.131352) (xy 106.211498 -351.121222) (xy 106.267232 -351.119185) (xy 106.322669 -351.125285)
			(xy 106.376626 -351.139391) (xy 106.427955 -351.161203) (xy 106.475561 -351.190257) (xy 106.518429 -351.225932)
			(xy 106.555646 -351.267469) (xy 106.586419 -351.313982) (xy 106.610091 -351.364479) (xy 106.626159 -351.417886)
			(xy 106.634279 -351.473062) (xy 106.634788 -351.500948) (xy 106.887262 -351.500948) (xy 106.891333 -351.445326)
			(xy 106.903459 -351.390889) (xy 106.923382 -351.338798) (xy 106.950678 -351.290163) (xy 106.984764 -351.24602)
			(xy 107.024913 -351.207311) (xy 107.070271 -351.17486) (xy 107.119871 -351.149359) (xy 107.172655 -351.131352)
			(xy 107.227498 -351.121222) (xy 107.283232 -351.119185) (xy 107.338669 -351.125285) (xy 107.392626 -351.139391)
			(xy 107.443955 -351.161203) (xy 107.491561 -351.190257) (xy 107.534429 -351.225932) (xy 107.571646 -351.267469)
			(xy 107.602419 -351.313982) (xy 107.626091 -351.364479) (xy 107.642159 -351.417886) (xy 107.650279 -351.473062)
			(xy 107.650788 -351.500948) (xy 107.903262 -351.500948) (xy 107.907333 -351.445326) (xy 107.919459 -351.390889)
			(xy 107.939382 -351.338798) (xy 107.966678 -351.290163) (xy 108.000764 -351.24602) (xy 108.040913 -351.207311)
			(xy 108.086271 -351.17486) (xy 108.135871 -351.149359) (xy 108.188655 -351.131352) (xy 108.243498 -351.121222)
			(xy 108.299232 -351.119185) (xy 108.354669 -351.125285) (xy 108.408626 -351.139391) (xy 108.459955 -351.161203)
			(xy 108.507561 -351.190257) (xy 108.550429 -351.225932) (xy 108.587646 -351.267469) (xy 108.618419 -351.313982)
			(xy 108.642091 -351.364479) (xy 108.658159 -351.417886) (xy 108.666279 -351.473062) (xy 108.666788 -351.500948)
			(xy 108.919262 -351.500948) (xy 108.923333 -351.445326) (xy 108.935459 -351.390889) (xy 108.955382 -351.338798)
			(xy 108.982678 -351.290163) (xy 109.016764 -351.24602) (xy 109.056913 -351.207311) (xy 109.102271 -351.17486)
			(xy 109.151871 -351.149359) (xy 109.204655 -351.131352) (xy 109.259498 -351.121222) (xy 109.315232 -351.119185)
			(xy 109.370669 -351.125285) (xy 109.424626 -351.139391) (xy 109.475955 -351.161203) (xy 109.523561 -351.190257)
			(xy 109.566429 -351.225932) (xy 109.603646 -351.267469) (xy 109.634419 -351.313982) (xy 109.658091 -351.364479)
			(xy 109.674159 -351.417886) (xy 109.680028 -351.457768) (xy 111.131602 -351.457768) (xy 111.135673 -351.402146)
			(xy 111.147799 -351.347709) (xy 111.167722 -351.295618) (xy 111.195018 -351.246983) (xy 111.229104 -351.20284)
			(xy 111.269253 -351.164131) (xy 111.314611 -351.13168) (xy 111.364211 -351.106179) (xy 111.416995 -351.088172)
			(xy 111.471838 -351.078042) (xy 111.527572 -351.076005) (xy 111.583009 -351.082105) (xy 111.636966 -351.096211)
			(xy 111.688295 -351.118023) (xy 111.735901 -351.147077) (xy 111.778769 -351.182752) (xy 111.815986 -351.224289)
			(xy 111.846759 -351.270802) (xy 111.870431 -351.321299) (xy 111.886499 -351.374706) (xy 111.894619 -351.429882)
			(xy 111.895128 -351.457768) (xy 111.894619 -351.485654) (xy 111.886499 -351.54083) (xy 111.870431 -351.594237)
			(xy 111.846759 -351.644734) (xy 111.815986 -351.691247) (xy 111.778769 -351.732784) (xy 111.735901 -351.768459)
			(xy 111.688295 -351.797513) (xy 111.636966 -351.819325) (xy 111.583009 -351.833431) (xy 111.527572 -351.839531)
			(xy 111.471838 -351.837494) (xy 111.416995 -351.827364) (xy 111.364211 -351.809357) (xy 111.314611 -351.783856)
			(xy 111.269253 -351.751405) (xy 111.229104 -351.712696) (xy 111.195018 -351.668553) (xy 111.167722 -351.619918)
			(xy 111.147799 -351.567827) (xy 111.135673 -351.51339) (xy 111.131602 -351.457768) (xy 109.680028 -351.457768)
			(xy 109.682279 -351.473062) (xy 109.682788 -351.500948) (xy 109.682279 -351.528834) (xy 109.674159 -351.58401)
			(xy 109.658091 -351.637417) (xy 109.634419 -351.687914) (xy 109.603646 -351.734427) (xy 109.566429 -351.775964)
			(xy 109.523561 -351.811639) (xy 109.475955 -351.840693) (xy 109.424626 -351.862505) (xy 109.370669 -351.876611)
			(xy 109.315232 -351.882711) (xy 109.259498 -351.880674) (xy 109.204655 -351.870544) (xy 109.151871 -351.852537)
			(xy 109.102271 -351.827036) (xy 109.056913 -351.794585) (xy 109.016764 -351.755876) (xy 108.982678 -351.711733)
			(xy 108.955382 -351.663098) (xy 108.935459 -351.611007) (xy 108.923333 -351.55657) (xy 108.919262 -351.500948)
			(xy 108.666788 -351.500948) (xy 108.666279 -351.528834) (xy 108.658159 -351.58401) (xy 108.642091 -351.637417)
			(xy 108.618419 -351.687914) (xy 108.587646 -351.734427) (xy 108.550429 -351.775964) (xy 108.507561 -351.811639)
			(xy 108.459955 -351.840693) (xy 108.408626 -351.862505) (xy 108.354669 -351.876611) (xy 108.299232 -351.882711)
			(xy 108.243498 -351.880674) (xy 108.188655 -351.870544) (xy 108.135871 -351.852537) (xy 108.086271 -351.827036)
			(xy 108.040913 -351.794585) (xy 108.000764 -351.755876) (xy 107.966678 -351.711733) (xy 107.939382 -351.663098)
			(xy 107.919459 -351.611007) (xy 107.907333 -351.55657) (xy 107.903262 -351.500948) (xy 107.650788 -351.500948)
			(xy 107.650279 -351.528834) (xy 107.642159 -351.58401) (xy 107.626091 -351.637417) (xy 107.602419 -351.687914)
			(xy 107.571646 -351.734427) (xy 107.534429 -351.775964) (xy 107.491561 -351.811639) (xy 107.443955 -351.840693)
			(xy 107.392626 -351.862505) (xy 107.338669 -351.876611) (xy 107.283232 -351.882711) (xy 107.227498 -351.880674)
			(xy 107.172655 -351.870544) (xy 107.119871 -351.852537) (xy 107.070271 -351.827036) (xy 107.024913 -351.794585)
			(xy 106.984764 -351.755876) (xy 106.950678 -351.711733) (xy 106.923382 -351.663098) (xy 106.903459 -351.611007)
			(xy 106.891333 -351.55657) (xy 106.887262 -351.500948) (xy 106.634788 -351.500948) (xy 106.634279 -351.528834)
			(xy 106.626159 -351.58401) (xy 106.610091 -351.637417) (xy 106.586419 -351.687914) (xy 106.555646 -351.734427)
			(xy 106.518429 -351.775964) (xy 106.475561 -351.811639) (xy 106.427955 -351.840693) (xy 106.376626 -351.862505)
			(xy 106.322669 -351.876611) (xy 106.267232 -351.882711) (xy 106.211498 -351.880674) (xy 106.156655 -351.870544)
			(xy 106.103871 -351.852537) (xy 106.054271 -351.827036) (xy 106.008913 -351.794585) (xy 105.968764 -351.755876)
			(xy 105.934678 -351.711733) (xy 105.907382 -351.663098) (xy 105.887459 -351.611007) (xy 105.875333 -351.55657)
			(xy 105.871262 -351.500948) (xy 105.357567 -351.500948) (xy 105.363928 -351.502611) (xy 105.415257 -351.524423)
			(xy 105.462863 -351.553477) (xy 105.505731 -351.589152) (xy 105.542948 -351.630689) (xy 105.573721 -351.677202)
			(xy 105.597393 -351.727699) (xy 105.613461 -351.781106) (xy 105.621581 -351.836282) (xy 105.62209 -351.864168)
			(xy 105.621581 -351.892054) (xy 105.613461 -351.94723) (xy 105.597393 -352.000637) (xy 105.573721 -352.051134)
			(xy 105.542948 -352.097647) (xy 105.505731 -352.139184) (xy 105.462863 -352.174859) (xy 105.415257 -352.203913)
			(xy 105.363928 -352.225725) (xy 105.309971 -352.239831) (xy 105.254534 -352.245931) (xy 105.1988 -352.243894)
			(xy 105.143957 -352.233764) (xy 105.091173 -352.215757) (xy 105.041573 -352.190256) (xy 104.996215 -352.157805)
			(xy 104.956066 -352.119096) (xy 104.92198 -352.074953) (xy 104.894684 -352.026318) (xy 104.874761 -351.974227)
			(xy 104.862635 -351.91979) (xy 104.858564 -351.864168) (xy 104.721086 -351.864168) (xy 104.710121 -351.887558)
			(xy 104.679348 -351.934071) (xy 104.642131 -351.975608) (xy 104.599263 -352.011283) (xy 104.551657 -352.040337)
			(xy 104.500328 -352.062149) (xy 104.446371 -352.076255) (xy 104.390934 -352.082355) (xy 104.3352 -352.080318)
			(xy 104.280357 -352.070188) (xy 104.227573 -352.052181) (xy 104.177973 -352.02668) (xy 104.132615 -351.994229)
			(xy 104.092466 -351.95552) (xy 104.05838 -351.911377) (xy 104.031084 -351.862742) (xy 104.011161 -351.810651)
			(xy 103.999035 -351.756214) (xy 103.994964 -351.700592) (xy 77.780787 -351.700592) (xy 78.060876 -352.396298)
			(xy 110.560102 -352.396298) (xy 110.564173 -352.340676) (xy 110.576299 -352.286239) (xy 110.596222 -352.234148)
			(xy 110.623518 -352.185513) (xy 110.657604 -352.14137) (xy 110.697753 -352.102661) (xy 110.743111 -352.07021)
			(xy 110.792711 -352.044709) (xy 110.845495 -352.026702) (xy 110.900338 -352.016572) (xy 110.956072 -352.014535)
			(xy 111.011509 -352.020635) (xy 111.065466 -352.034741) (xy 111.116795 -352.056553) (xy 111.164401 -352.085607)
			(xy 111.207269 -352.121282) (xy 111.244486 -352.162819) (xy 111.275259 -352.209332) (xy 111.298931 -352.259829)
			(xy 111.314999 -352.313236) (xy 111.323119 -352.368412) (xy 111.323628 -352.396298) (xy 111.323119 -352.424184)
			(xy 111.314999 -352.47936) (xy 111.298931 -352.532767) (xy 111.275259 -352.583264) (xy 111.244486 -352.629777)
			(xy 111.207269 -352.671314) (xy 111.164401 -352.706989) (xy 111.116795 -352.736043) (xy 111.065466 -352.757855)
			(xy 111.011509 -352.771961) (xy 110.956072 -352.778061) (xy 110.900338 -352.776024) (xy 110.845495 -352.765894)
			(xy 110.792711 -352.747887) (xy 110.743111 -352.722386) (xy 110.697753 -352.689935) (xy 110.657604 -352.651226)
			(xy 110.623518 -352.607083) (xy 110.596222 -352.558448) (xy 110.576299 -352.506357) (xy 110.564173 -352.45192)
			(xy 110.560102 -352.396298) (xy 78.060876 -352.396298) (xy 78.23666 -352.832924) (xy 112.35385 -352.832924)
			(xy 112.357921 -352.777302) (xy 112.370047 -352.722865) (xy 112.38997 -352.670774) (xy 112.417266 -352.622139)
			(xy 112.451352 -352.577996) (xy 112.491501 -352.539287) (xy 112.536859 -352.506836) (xy 112.586459 -352.481335)
			(xy 112.639243 -352.463328) (xy 112.694086 -352.453198) (xy 112.74982 -352.451161) (xy 112.805257 -352.457261)
			(xy 112.859214 -352.471367) (xy 112.910543 -352.493179) (xy 112.958149 -352.522233) (xy 113.001017 -352.557908)
			(xy 113.038234 -352.599445) (xy 113.069007 -352.645958) (xy 113.092679 -352.696455) (xy 113.108747 -352.749862)
			(xy 113.116867 -352.805038) (xy 113.117376 -352.832924) (xy 113.116867 -352.86081) (xy 113.108747 -352.915986)
			(xy 113.092679 -352.969393) (xy 113.069007 -353.01989) (xy 113.038234 -353.066403) (xy 113.001017 -353.10794)
			(xy 112.958149 -353.143615) (xy 112.910543 -353.172669) (xy 112.859214 -353.194481) (xy 112.805257 -353.208587)
			(xy 112.74982 -353.214687) (xy 112.694086 -353.21265) (xy 112.639243 -353.20252) (xy 112.586459 -353.184513)
			(xy 112.536859 -353.159012) (xy 112.491501 -353.126561) (xy 112.451352 -353.087852) (xy 112.417266 -353.043709)
			(xy 112.38997 -352.995074) (xy 112.370047 -352.942983) (xy 112.357921 -352.888546) (xy 112.35385 -352.832924)
			(xy 78.23666 -352.832924) (xy 78.500592 -353.488498) (xy 110.4806 -353.488498) (xy 110.484671 -353.432876)
			(xy 110.496797 -353.378439) (xy 110.51672 -353.326348) (xy 110.544016 -353.277713) (xy 110.578102 -353.23357)
			(xy 110.618251 -353.194861) (xy 110.663609 -353.16241) (xy 110.713209 -353.136909) (xy 110.765993 -353.118902)
			(xy 110.820836 -353.108772) (xy 110.87657 -353.106735) (xy 110.932007 -353.112835) (xy 110.985964 -353.126941)
			(xy 111.037293 -353.148753) (xy 111.084899 -353.177807) (xy 111.127767 -353.213482) (xy 111.164984 -353.255019)
			(xy 111.195757 -353.301532) (xy 111.219429 -353.352029) (xy 111.235497 -353.405436) (xy 111.243617 -353.460612)
			(xy 111.244126 -353.488498) (xy 111.243617 -353.516384) (xy 111.241179 -353.532948) (xy 113.415062 -353.532948)
			(xy 113.419133 -353.477326) (xy 113.431259 -353.422889) (xy 113.451182 -353.370798) (xy 113.478478 -353.322163)
			(xy 113.512564 -353.27802) (xy 113.552713 -353.239311) (xy 113.598071 -353.20686) (xy 113.647671 -353.181359)
			(xy 113.700455 -353.163352) (xy 113.755298 -353.153222) (xy 113.811032 -353.151185) (xy 113.866469 -353.157285)
			(xy 113.920426 -353.171391) (xy 113.971755 -353.193203) (xy 114.019361 -353.222257) (xy 114.062229 -353.257932)
			(xy 114.099446 -353.299469) (xy 114.130219 -353.345982) (xy 114.153891 -353.396479) (xy 114.169959 -353.449886)
			(xy 114.178079 -353.505062) (xy 114.178588 -353.532948) (xy 114.178079 -353.560834) (xy 114.169959 -353.61601)
			(xy 114.153891 -353.669417) (xy 114.130219 -353.719914) (xy 114.099446 -353.766427) (xy 114.062229 -353.807964)
			(xy 114.019361 -353.843639) (xy 113.971755 -353.872693) (xy 113.920426 -353.894505) (xy 113.866469 -353.908611)
			(xy 113.811032 -353.914711) (xy 113.755298 -353.912674) (xy 113.700455 -353.902544) (xy 113.647671 -353.884537)
			(xy 113.598071 -353.859036) (xy 113.552713 -353.826585) (xy 113.512564 -353.787876) (xy 113.478478 -353.743733)
			(xy 113.451182 -353.695098) (xy 113.431259 -353.643007) (xy 113.419133 -353.58857) (xy 113.415062 -353.532948)
			(xy 111.241179 -353.532948) (xy 111.235497 -353.57156) (xy 111.219429 -353.624967) (xy 111.195757 -353.675464)
			(xy 111.164984 -353.721977) (xy 111.127767 -353.763514) (xy 111.084899 -353.799189) (xy 111.037293 -353.828243)
			(xy 110.985964 -353.850055) (xy 110.932007 -353.864161) (xy 110.87657 -353.870261) (xy 110.820836 -353.868224)
			(xy 110.765993 -353.858094) (xy 110.713209 -353.840087) (xy 110.663609 -353.814586) (xy 110.618251 -353.782135)
			(xy 110.578102 -353.743426) (xy 110.544016 -353.699283) (xy 110.51672 -353.650648) (xy 110.496797 -353.598557)
			(xy 110.484671 -353.54412) (xy 110.4806 -353.488498) (xy 78.500592 -353.488498) (xy 78.891326 -354.459032)
			(xy 101.443534 -354.459032) (xy 101.447605 -354.40341) (xy 101.459731 -354.348973) (xy 101.479654 -354.296882)
			(xy 101.50695 -354.248247) (xy 101.541036 -354.204104) (xy 101.581185 -354.165395) (xy 101.626543 -354.132944)
			(xy 101.676143 -354.107443) (xy 101.728927 -354.089436) (xy 101.78377 -354.079306) (xy 101.839504 -354.077269)
			(xy 101.894941 -354.083369) (xy 101.948898 -354.097475) (xy 102.000227 -354.119287) (xy 102.047833 -354.148341)
			(xy 102.090701 -354.184016) (xy 102.127918 -354.225553) (xy 102.158691 -354.272066) (xy 102.182363 -354.322563)
			(xy 102.198431 -354.37597) (xy 102.206551 -354.431146) (xy 102.20706 -354.459032) (xy 102.206551 -354.486918)
			(xy 102.205048 -354.497132) (xy 105.004868 -354.497132) (xy 105.008939 -354.44151) (xy 105.021065 -354.387073)
			(xy 105.040988 -354.334982) (xy 105.068284 -354.286347) (xy 105.10237 -354.242204) (xy 105.142519 -354.203495)
			(xy 105.187877 -354.171044) (xy 105.237477 -354.145543) (xy 105.290261 -354.127536) (xy 105.345104 -354.117406)
			(xy 105.400838 -354.115369) (xy 105.456275 -354.121469) (xy 105.510232 -354.135575) (xy 105.525446 -354.14204)
			(xy 111.725708 -354.14204) (xy 111.729779 -354.086418) (xy 111.741905 -354.031981) (xy 111.761828 -353.97989)
			(xy 111.789124 -353.931255) (xy 111.82321 -353.887112) (xy 111.863359 -353.848403) (xy 111.908717 -353.815952)
			(xy 111.958317 -353.790451) (xy 112.011101 -353.772444) (xy 112.065944 -353.762314) (xy 112.121678 -353.760277)
			(xy 112.177115 -353.766377) (xy 112.231072 -353.780483) (xy 112.282401 -353.802295) (xy 112.330007 -353.831349)
			(xy 112.372875 -353.867024) (xy 112.410092 -353.908561) (xy 112.440865 -353.955074) (xy 112.464537 -354.005571)
			(xy 112.480605 -354.058978) (xy 112.488725 -354.114154) (xy 112.489234 -354.14204) (xy 112.488725 -354.169926)
			(xy 112.480605 -354.225102) (xy 112.464537 -354.278509) (xy 112.440865 -354.329006) (xy 112.410092 -354.375519)
			(xy 112.372875 -354.417056) (xy 112.330007 -354.452731) (xy 112.282401 -354.481785) (xy 112.231072 -354.503597)
			(xy 112.177115 -354.517703) (xy 112.121678 -354.523803) (xy 112.065944 -354.521766) (xy 112.011101 -354.511636)
			(xy 111.958317 -354.493629) (xy 111.908717 -354.468128) (xy 111.863359 -354.435677) (xy 111.82321 -354.396968)
			(xy 111.789124 -354.352825) (xy 111.761828 -354.30419) (xy 111.741905 -354.252099) (xy 111.729779 -354.197662)
			(xy 111.725708 -354.14204) (xy 105.525446 -354.14204) (xy 105.561561 -354.157387) (xy 105.609167 -354.186441)
			(xy 105.652035 -354.222116) (xy 105.689252 -354.263653) (xy 105.720025 -354.310166) (xy 105.743697 -354.360663)
			(xy 105.759765 -354.41407) (xy 105.767885 -354.469246) (xy 105.768394 -354.497132) (xy 105.767885 -354.525018)
			(xy 105.759765 -354.580194) (xy 105.743697 -354.633601) (xy 105.720025 -354.684098) (xy 105.689252 -354.730611)
			(xy 105.652035 -354.772148) (xy 105.609167 -354.807823) (xy 105.561561 -354.836877) (xy 105.510232 -354.858689)
			(xy 105.456275 -354.872795) (xy 105.400838 -354.878895) (xy 105.345104 -354.876858) (xy 105.290261 -354.866728)
			(xy 105.237477 -354.848721) (xy 105.187877 -354.82322) (xy 105.142519 -354.790769) (xy 105.10237 -354.75206)
			(xy 105.068284 -354.707917) (xy 105.040988 -354.659282) (xy 105.021065 -354.607191) (xy 105.008939 -354.552754)
			(xy 105.004868 -354.497132) (xy 102.205048 -354.497132) (xy 102.198431 -354.542094) (xy 102.182363 -354.595501)
			(xy 102.158691 -354.645998) (xy 102.127918 -354.692511) (xy 102.090701 -354.734048) (xy 102.047833 -354.769723)
			(xy 102.000227 -354.798777) (xy 101.948898 -354.820589) (xy 101.894941 -354.834695) (xy 101.839504 -354.840795)
			(xy 101.78377 -354.838758) (xy 101.728927 -354.828628) (xy 101.676143 -354.810621) (xy 101.626543 -354.78512)
			(xy 101.581185 -354.752669) (xy 101.541036 -354.71396) (xy 101.50695 -354.669817) (xy 101.479654 -354.621182)
			(xy 101.459731 -354.569091) (xy 101.447605 -354.514654) (xy 101.443534 -354.459032) (xy 78.891326 -354.459032)
			(xy 79.128466 -355.048058) (xy 99.42652 -355.048058) (xy 99.430591 -354.992436) (xy 99.442717 -354.937999)
			(xy 99.46264 -354.885908) (xy 99.489936 -354.837273) (xy 99.524022 -354.79313) (xy 99.564171 -354.754421)
			(xy 99.609529 -354.72197) (xy 99.659129 -354.696469) (xy 99.711913 -354.678462) (xy 99.766756 -354.668332)
			(xy 99.82249 -354.666295) (xy 99.877927 -354.672395) (xy 99.931884 -354.686501) (xy 99.983213 -354.708313)
			(xy 100.030819 -354.737367) (xy 100.073687 -354.773042) (xy 100.110904 -354.814579) (xy 100.141677 -354.861092)
			(xy 100.165349 -354.911589) (xy 100.181417 -354.964996) (xy 100.189537 -355.020172) (xy 100.190046 -355.048058)
			(xy 100.189537 -355.075944) (xy 100.181417 -355.13112) (xy 100.165349 -355.184527) (xy 100.141677 -355.235024)
			(xy 100.110904 -355.281537) (xy 100.073687 -355.323074) (xy 100.030819 -355.358749) (xy 99.983213 -355.387803)
			(xy 99.931884 -355.409615) (xy 99.877927 -355.423721) (xy 99.82249 -355.429821) (xy 99.766756 -355.427784)
			(xy 99.711913 -355.417654) (xy 99.659129 -355.399647) (xy 99.609529 -355.374146) (xy 99.564171 -355.341695)
			(xy 99.524022 -355.302986) (xy 99.489936 -355.258843) (xy 99.46264 -355.210208) (xy 99.442717 -355.158117)
			(xy 99.430591 -355.10368) (xy 99.42652 -355.048058) (xy 79.128466 -355.048058) (xy 81.11987 -359.994454)
			(xy 87.567516 -359.994454) (xy 87.568039 -359.964944) (xy 87.577109 -359.906626) (xy 87.595057 -359.850402)
			(xy 87.621454 -359.797615) (xy 87.655669 -359.749525) (xy 87.696885 -359.707282) (xy 87.72017 -359.689146)
			(xy 87.731669 -359.679895) (xy 87.749252 -359.65621) (xy 87.759335 -359.628487) (xy 87.761075 -359.59904)
			(xy 87.754328 -359.570324) (xy 87.739657 -359.544732) (xy 87.729314 -359.534206) (xy 87.710907 -359.516162)
			(xy 87.678669 -359.475943) (xy 87.652144 -359.431746) (xy 87.631817 -359.384378) (xy 87.618058 -359.334703)
			(xy 87.611119 -359.283627) (xy 87.610696 -359.257854) (xy 87.611135 -359.230601) (xy 87.618898 -359.176652)
			(xy 87.634259 -359.124356) (xy 87.656906 -359.074778) (xy 87.686377 -359.028928) (xy 87.722074 -358.987738)
			(xy 87.763268 -358.952047) (xy 87.809122 -358.922582) (xy 87.858703 -358.899942) (xy 87.911001 -358.884587)
			(xy 87.964951 -358.876831) (xy 87.992204 -358.876346) (xy 88.020942 -358.876882) (xy 88.077768 -358.885504)
			(xy 88.132658 -358.902552) (xy 88.18437 -358.92764) (xy 88.231734 -358.960201) (xy 88.253062 -358.97947)
			(xy 88.264929 -358.989692) (xy 88.293199 -359.003124) (xy 88.324209 -359.007369) (xy 88.35505 -359.002028)
			(xy 88.382827 -358.987604) (xy 88.394286 -358.97693) (xy 88.403382 -358.96806) (xy 88.422574 -358.951408)
			(xy 88.43264 -358.943656) (xy 88.444447 -358.933923) (xy 88.462142 -358.908978) (xy 88.471662 -358.879914)
			(xy 88.472154 -358.849335) (xy 88.463574 -358.81998) (xy 88.44669 -358.794479) (xy 88.43518 -358.784398)
			(xy 88.413773 -358.766185) (xy 88.376036 -358.724534) (xy 88.344817 -358.677798) (xy 88.320791 -358.626987)
			(xy 88.30448 -358.573202) (xy 88.296234 -358.517606) (xy 88.295734 -358.489504) (xy 88.296173 -358.463163)
			(xy 88.303428 -358.410981) (xy 88.317788 -358.360293) (xy 88.338978 -358.31206) (xy 88.366598 -358.267197)
			(xy 88.400123 -358.226557) (xy 88.438915 -358.190911) (xy 88.460326 -358.17556) (xy 88.472459 -358.166357)
			(xy 88.491238 -358.142411) (xy 88.502137 -358.113999) (xy 88.504189 -358.083637) (xy 88.497214 -358.054017)
			(xy 88.481828 -358.027762) (xy 88.470994 -358.017064) (xy 88.451748 -357.998917) (xy 88.417965 -357.958213)
			(xy 88.390127 -357.913234) (xy 88.368767 -357.864841) (xy 88.354294 -357.813962) (xy 88.346986 -357.761573)
			(xy 88.346534 -357.735124) (xy 88.347047 -357.707644) (xy 88.354936 -357.653254) (xy 88.370553 -357.600559)
			(xy 88.393575 -357.550654) (xy 88.423525 -357.504572) (xy 88.459782 -357.463268) (xy 88.501594 -357.427598)
			(xy 88.524588 -357.412544) (xy 88.536216 -357.404727) (xy 88.554933 -357.383886) (xy 88.567286 -357.358745)
			(xy 88.572344 -357.331193) (xy 88.569727 -357.303304) (xy 88.559632 -357.277174) (xy 88.542819 -357.254769)
			(xy 88.531954 -357.24592) (xy 88.509103 -357.227703) (xy 88.468635 -357.185548) (xy 88.435063 -357.137719)
			(xy 88.409171 -357.085333) (xy 88.391564 -357.029614) (xy 88.382653 -356.971862) (xy 88.382094 -356.942644)
			(xy 88.382629 -356.913474) (xy 88.391536 -356.855819) (xy 88.409119 -356.800192) (xy 88.434968 -356.747892)
			(xy 88.468479 -356.700137) (xy 88.508871 -356.658042) (xy 88.5317 -356.639876) (xy 88.54349 -356.630122)
			(xy 88.561192 -356.605185) (xy 88.570719 -356.576125) (xy 88.571214 -356.545548) (xy 88.562635 -356.516195)
			(xy 88.54575 -356.490697) (xy 88.53424 -356.480618) (xy 88.512834 -356.462404) (xy 88.475099 -356.420752)
			(xy 88.443881 -356.374015) (xy 88.419855 -356.323205) (xy 88.403543 -356.269421) (xy 88.395295 -356.213826)
			(xy 88.394794 -356.185724) (xy 88.395234 -356.15908) (xy 88.40264 -356.106308) (xy 88.417325 -356.055083)
			(xy 88.439004 -356.006404) (xy 88.467252 -355.961219) (xy 88.50152 -355.920409) (xy 88.521032 -355.90226)
			(xy 88.530713 -355.892925) (xy 88.545327 -355.870366) (xy 88.553537 -355.844771) (xy 88.554773 -355.81792)
			(xy 88.548948 -355.791679) (xy 88.536467 -355.767873) (xy 88.527636 -355.757734) (xy 88.508665 -355.736462)
			(xy 88.476607 -355.689336) (xy 88.451906 -355.637971) (xy 88.435109 -355.583507) (xy 88.42659 -355.527151)
			(xy 88.426036 -355.498654) (xy 88.426435 -355.4714) (xy 88.434199 -355.417446) (xy 88.449562 -355.365147)
			(xy 88.472212 -355.315567) (xy 88.501687 -355.269715) (xy 88.537388 -355.228524) (xy 88.578587 -355.192833)
			(xy 88.624446 -355.163369) (xy 88.674032 -355.140731) (xy 88.726335 -355.12538) (xy 88.78029 -355.117629)
			(xy 88.807544 -355.117146) (xy 88.834954 -355.117634) (xy 88.889209 -355.125473) (xy 88.941784 -355.140999)
			(xy 88.991595 -355.163892) (xy 89.037615 -355.193679) (xy 89.078897 -355.229748) (xy 89.097104 -355.250242)
			(xy 89.106461 -355.260357) (xy 89.12933 -355.275699) (xy 89.155469 -355.284364) (xy 89.182974 -355.285721)
			(xy 89.20984 -355.279669) (xy 89.234107 -355.266652) (xy 89.254008 -355.247617) (xy 89.261442 -355.236018)
			(xy 89.276312 -355.212088) (xy 89.31195 -355.168457) (xy 89.353619 -355.130542) (xy 89.400412 -355.099171)
			(xy 89.451312 -355.075025) (xy 89.50521 -355.058629) (xy 89.560934 -355.050342) (xy 89.589102 -355.049836)
			(xy 89.61802 -355.050339) (xy 89.675192 -355.05907) (xy 89.730392 -355.07633) (xy 89.782354 -355.101724)
			(xy 89.829887 -355.134671) (xy 89.871903 -355.174415) (xy 89.890092 -355.196902) (xy 89.899989 -355.208707)
			(xy 89.925313 -355.226226) (xy 89.954706 -355.235402) (xy 89.985498 -355.235402) (xy 90.014891 -355.226226)
			(xy 90.040215 -355.208707) (xy 90.050112 -355.196902) (xy 90.066865 -355.176119) (xy 90.105219 -355.138989)
			(xy 90.148373 -355.107567) (xy 90.195487 -355.082468) (xy 90.245639 -355.064182) (xy 90.29785 -355.053065)
			(xy 90.351102 -355.049335) (xy 90.404354 -355.053065) (xy 90.456565 -355.064182) (xy 90.506717 -355.082468)
			(xy 90.553831 -355.107567) (xy 90.596985 -355.138989) (xy 90.635339 -355.176119) (xy 90.652092 -355.196902)
			(xy 90.661989 -355.208707) (xy 90.687313 -355.226226) (xy 90.716706 -355.235402) (xy 90.747498 -355.235402)
			(xy 90.776891 -355.226226) (xy 90.802215 -355.208707) (xy 90.812112 -355.196902) (xy 90.830297 -355.174413)
			(xy 90.872318 -355.134678) (xy 90.919854 -355.10174) (xy 90.971816 -355.076352) (xy 91.027015 -355.059097)
			(xy 91.084186 -355.05037) (xy 91.113102 -355.049836) (xy 91.142411 -355.05037) (xy 91.200337 -355.059342)
			(xy 91.256208 -355.077074) (xy 91.308707 -355.103148) (xy 91.356596 -355.13695) (xy 91.398748 -355.177684)
			(xy 91.416886 -355.200712) (xy 91.426627 -355.212609) (xy 91.451624 -355.230485) (xy 91.48081 -355.240107)
			(xy 91.511537 -355.240603) (xy 91.541018 -355.231927) (xy 91.566578 -355.214866) (xy 91.576652 -355.203252)
			(xy 91.594896 -355.181695) (xy 91.636601 -355.143621) (xy 91.683463 -355.112111) (xy 91.734459 -355.087854)
			(xy 91.788474 -355.07138) (xy 91.844327 -355.063049) (xy 91.872562 -355.062536) (xy 91.901479 -355.063068)
			(xy 91.95865 -355.071792) (xy 92.013849 -355.089047) (xy 92.065811 -355.114436) (xy 92.113345 -355.147377)
			(xy 92.155362 -355.187117) (xy 92.173552 -355.209602) (xy 92.183449 -355.221407) (xy 92.208773 -355.238926)
			(xy 92.238166 -355.248102) (xy 92.268958 -355.248102) (xy 92.298351 -355.238926) (xy 92.323675 -355.221407)
			(xy 92.333572 -355.209602) (xy 92.350325 -355.188819) (xy 92.388679 -355.151689) (xy 92.431833 -355.120267)
			(xy 92.478947 -355.095168) (xy 92.529099 -355.076882) (xy 92.58131 -355.065765) (xy 92.634562 -355.062035)
			(xy 92.687814 -355.065765) (xy 92.740025 -355.076882) (xy 92.790177 -355.095168) (xy 92.837291 -355.120267)
			(xy 92.880445 -355.151689) (xy 92.918799 -355.188819) (xy 92.935552 -355.209602) (xy 92.945449 -355.221407)
			(xy 92.970773 -355.238926) (xy 93.000166 -355.248102) (xy 93.030958 -355.248102) (xy 93.060351 -355.238926)
			(xy 93.085675 -355.221407) (xy 93.095572 -355.209602) (xy 93.112325 -355.188819) (xy 93.150679 -355.151689)
			(xy 93.193833 -355.120267) (xy 93.240947 -355.095168) (xy 93.291099 -355.076882) (xy 93.34331 -355.065765)
			(xy 93.396562 -355.062035) (xy 93.449814 -355.065765) (xy 93.502025 -355.076882) (xy 93.552177 -355.095168)
			(xy 93.599291 -355.120267) (xy 93.642445 -355.151689) (xy 93.680799 -355.188819) (xy 93.697552 -355.209602)
			(xy 93.707449 -355.221407) (xy 93.732773 -355.238926) (xy 93.762166 -355.248102) (xy 93.792958 -355.248102)
			(xy 93.822351 -355.238926) (xy 93.847675 -355.221407) (xy 93.857572 -355.209602) (xy 93.874325 -355.188819)
			(xy 93.912679 -355.151689) (xy 93.955833 -355.120267) (xy 94.002947 -355.095168) (xy 94.053099 -355.076882)
			(xy 94.10531 -355.065765) (xy 94.158562 -355.062035) (xy 94.211814 -355.065765) (xy 94.264025 -355.076882)
			(xy 94.314177 -355.095168) (xy 94.361291 -355.120267) (xy 94.404445 -355.151689) (xy 94.442799 -355.188819)
			(xy 94.459552 -355.209602) (xy 94.469449 -355.221407) (xy 94.494773 -355.238926) (xy 94.524166 -355.248102)
			(xy 94.554958 -355.248102) (xy 94.584351 -355.238926) (xy 94.609675 -355.221407) (xy 94.619572 -355.209602)
			(xy 94.637779 -355.187132) (xy 94.679796 -355.147396) (xy 94.727327 -355.114456) (xy 94.779285 -355.089065)
			(xy 94.83448 -355.071805) (xy 94.891647 -355.063073) (xy 94.920562 -355.062536) (xy 94.946814 -355.062978)
			(xy 94.998823 -355.070162) (xy 95.049354 -355.084412) (xy 95.097454 -355.10546) (xy 95.142211 -355.132907)
			(xy 95.182779 -355.166235) (xy 95.218392 -355.204813) (xy 95.233744 -355.226112) (xy 95.242108 -355.237325)
			(xy 95.263733 -355.255051) (xy 95.289357 -355.266248) (xy 95.317056 -355.270076) (xy 95.344755 -355.266248)
			(xy 95.370379 -355.255051) (xy 95.392004 -355.237325) (xy 95.400368 -355.226112) (xy 95.415735 -355.204826)
			(xy 95.451355 -355.166259) (xy 95.491925 -355.132939) (xy 95.536679 -355.105493) (xy 95.584773 -355.084441)
			(xy 95.635297 -355.070179) (xy 95.6873 -355.062976) (xy 95.71355 -355.062536) (xy 95.742466 -355.063076)
			(xy 95.799637 -355.071799) (xy 95.854836 -355.089052) (xy 95.906798 -355.114439) (xy 95.954333 -355.147379)
			(xy 95.99635 -355.187118) (xy 96.01454 -355.209602) (xy 96.024437 -355.221407) (xy 96.049761 -355.238926)
			(xy 96.079154 -355.248102) (xy 96.109946 -355.248102) (xy 96.139339 -355.238926) (xy 96.164663 -355.221407)
			(xy 96.17456 -355.209602) (xy 96.192774 -355.187138) (xy 96.234789 -355.147402) (xy 96.282319 -355.11446)
			(xy 96.334276 -355.089068) (xy 96.389469 -355.071808) (xy 96.446635 -355.063074) (xy 96.47555 -355.062536)
			(xy 96.502804 -355.063002) (xy 96.556757 -355.070753) (xy 96.609057 -355.086105) (xy 96.65864 -355.108745)
			(xy 96.704496 -355.138212) (xy 96.74569 -355.173906) (xy 96.781384 -355.2151) (xy 96.810852 -355.260955)
			(xy 96.833493 -355.310537) (xy 96.848845 -355.362837) (xy 96.856598 -355.41679) (xy 96.857058 -355.444044)
			(xy 96.856516 -355.47296) (xy 96.847794 -355.530131) (xy 96.830542 -355.58533) (xy 96.805155 -355.637292)
			(xy 96.772215 -355.684827) (xy 96.732476 -355.726844) (xy 96.709992 -355.745034) (xy 96.698145 -355.754885)
			(xy 96.680632 -355.780222) (xy 96.671463 -355.809627) (xy 96.671471 -355.840427) (xy 96.680655 -355.869827)
			(xy 96.698182 -355.895155) (xy 96.709992 -355.905054) (xy 96.730821 -355.921754) (xy 96.767956 -355.960111)
			(xy 96.799382 -356.003272) (xy 96.824483 -356.050391) (xy 96.84277 -356.10055) (xy 96.853885 -356.152769)
			(xy 96.857612 -356.206027) (xy 96.853878 -356.259285) (xy 96.842755 -356.311502) (xy 96.824461 -356.361658)
			(xy 96.799353 -356.408774) (xy 96.767921 -356.45193) (xy 96.73078 -356.490282) (xy 96.709992 -356.507034)
			(xy 96.698145 -356.516885) (xy 96.680632 -356.542222) (xy 96.671463 -356.571627) (xy 96.671471 -356.602427)
			(xy 96.680655 -356.631827) (xy 96.684643 -356.63759) (xy 98.915218 -356.63759) (xy 98.919289 -356.581968)
			(xy 98.931415 -356.527531) (xy 98.951338 -356.47544) (xy 98.978634 -356.426805) (xy 99.01272 -356.382662)
			(xy 99.052869 -356.343953) (xy 99.098227 -356.311502) (xy 99.147827 -356.286001) (xy 99.200611 -356.267994)
			(xy 99.255454 -356.257864) (xy 99.311188 -356.255827) (xy 99.366625 -356.261927) (xy 99.420582 -356.276033)
			(xy 99.471911 -356.297845) (xy 99.519517 -356.326899) (xy 99.562385 -356.362574) (xy 99.599602 -356.404111)
			(xy 99.630375 -356.450624) (xy 99.654047 -356.501121) (xy 99.670115 -356.554528) (xy 99.678235 -356.609704)
			(xy 99.678744 -356.63759) (xy 99.678235 -356.665476) (xy 99.670115 -356.720652) (xy 99.654047 -356.774059)
			(xy 99.630375 -356.824556) (xy 99.599602 -356.871069) (xy 99.562385 -356.912606) (xy 99.519517 -356.948281)
			(xy 99.471911 -356.977335) (xy 99.420582 -356.999147) (xy 99.366625 -357.013253) (xy 99.311188 -357.019353)
			(xy 99.255454 -357.017316) (xy 99.200611 -357.007186) (xy 99.147827 -356.989179) (xy 99.098227 -356.963678)
			(xy 99.052869 -356.931227) (xy 99.01272 -356.892518) (xy 98.978634 -356.848375) (xy 98.951338 -356.79974)
			(xy 98.931415 -356.747649) (xy 98.919289 -356.693212) (xy 98.915218 -356.63759) (xy 96.684643 -356.63759)
			(xy 96.698182 -356.657155) (xy 96.709992 -356.667054) (xy 96.730821 -356.683754) (xy 96.767956 -356.722111)
			(xy 96.799382 -356.765272) (xy 96.824483 -356.812391) (xy 96.84277 -356.86255) (xy 96.853885 -356.914769)
			(xy 96.857612 -356.968027) (xy 96.853878 -357.021285) (xy 96.842755 -357.073502) (xy 96.824461 -357.123658)
			(xy 96.799353 -357.170774) (xy 96.767921 -357.21393) (xy 96.73078 -357.252282) (xy 96.709992 -357.269034)
			(xy 96.698145 -357.278885) (xy 96.680632 -357.304222) (xy 96.671463 -357.333627) (xy 96.671471 -357.364427)
			(xy 96.680655 -357.393827) (xy 96.698182 -357.419155) (xy 96.709992 -357.429054) (xy 96.730821 -357.445754)
			(xy 96.767956 -357.484111) (xy 96.799382 -357.527272) (xy 96.801725 -357.53167) (xy 98.915218 -357.53167)
			(xy 98.919289 -357.476048) (xy 98.931415 -357.421611) (xy 98.951338 -357.36952) (xy 98.978634 -357.320885)
			(xy 99.01272 -357.276742) (xy 99.052869 -357.238033) (xy 99.098227 -357.205582) (xy 99.147827 -357.180081)
			(xy 99.200611 -357.162074) (xy 99.255454 -357.151944) (xy 99.311188 -357.149907) (xy 99.366625 -357.156007)
			(xy 99.420582 -357.170113) (xy 99.471911 -357.191925) (xy 99.519517 -357.220979) (xy 99.562385 -357.256654)
			(xy 99.599602 -357.298191) (xy 99.630375 -357.344704) (xy 99.654047 -357.395201) (xy 99.670115 -357.448608)
			(xy 99.678235 -357.503784) (xy 99.678744 -357.53167) (xy 99.678235 -357.559556) (xy 99.670115 -357.614732)
			(xy 99.654047 -357.668139) (xy 99.630375 -357.718636) (xy 99.599602 -357.765149) (xy 99.562385 -357.806686)
			(xy 99.519517 -357.842361) (xy 99.471911 -357.871415) (xy 99.420582 -357.893227) (xy 99.366625 -357.907333)
			(xy 99.311188 -357.913433) (xy 99.255454 -357.911396) (xy 99.200611 -357.901266) (xy 99.147827 -357.883259)
			(xy 99.098227 -357.857758) (xy 99.052869 -357.825307) (xy 99.01272 -357.786598) (xy 98.978634 -357.742455)
			(xy 98.951338 -357.69382) (xy 98.931415 -357.641729) (xy 98.919289 -357.587292) (xy 98.915218 -357.53167)
			(xy 96.801725 -357.53167) (xy 96.824483 -357.574391) (xy 96.84277 -357.62455) (xy 96.853885 -357.676769)
			(xy 96.857612 -357.730027) (xy 96.853878 -357.783285) (xy 96.842755 -357.835502) (xy 96.824461 -357.885658)
			(xy 96.799353 -357.932774) (xy 96.767921 -357.97593) (xy 96.73078 -358.014282) (xy 96.709992 -358.031034)
			(xy 96.698145 -358.040885) (xy 96.680632 -358.066222) (xy 96.671463 -358.095627) (xy 96.671471 -358.126427)
			(xy 96.680655 -358.155827) (xy 96.698182 -358.181155) (xy 96.709992 -358.191054) (xy 96.730821 -358.207754)
			(xy 96.767956 -358.246111) (xy 96.799382 -358.289272) (xy 96.824483 -358.336391) (xy 96.84277 -358.38655)
			(xy 96.853885 -358.438769) (xy 96.857612 -358.492027) (xy 96.853878 -358.545285) (xy 96.842755 -358.597502)
			(xy 96.824461 -358.647658) (xy 96.799353 -358.694774) (xy 96.767921 -358.73793) (xy 96.73078 -358.776282)
			(xy 96.709992 -358.793034) (xy 96.698145 -358.802885) (xy 96.680632 -358.828222) (xy 96.671463 -358.857627)
			(xy 96.671471 -358.888427) (xy 96.680655 -358.917827) (xy 96.698182 -358.943155) (xy 96.709992 -358.953054)
			(xy 96.732452 -358.971273) (xy 96.772189 -359.013287) (xy 96.805131 -359.060816) (xy 96.830523 -359.112772)
			(xy 96.847785 -359.167964) (xy 96.85652 -359.22513) (xy 96.857058 -359.254044) (xy 96.856686 -359.2813)
			(xy 96.848922 -359.335257) (xy 96.833557 -359.38756) (xy 96.810906 -359.437143) (xy 96.781429 -359.482999)
			(xy 96.745726 -359.524192) (xy 96.704523 -359.559885) (xy 96.658661 -359.589351) (xy 96.609072 -359.61199)
			(xy 96.556765 -359.627342) (xy 96.502806 -359.635093) (xy 96.47555 -359.635552) (xy 96.446634 -359.635016)
			(xy 96.389462 -359.626293) (xy 96.334263 -359.60904) (xy 96.282301 -359.583652) (xy 96.234767 -359.55071)
			(xy 96.19275 -359.510971) (xy 96.17456 -359.488486) (xy 96.164663 -359.476681) (xy 96.139339 -359.459162)
			(xy 96.109946 -359.449986) (xy 96.079154 -359.449986) (xy 96.049761 -359.459162) (xy 96.024437 -359.476681)
			(xy 96.01454 -359.488486) (xy 95.999762 -359.506885) (xy 95.966391 -359.540256) (xy 95.947992 -359.555034)
			(xy 95.936145 -359.564885) (xy 95.918632 -359.590222) (xy 95.909463 -359.619627) (xy 95.909471 -359.650427)
			(xy 95.918655 -359.679827) (xy 95.936182 -359.705155) (xy 95.947992 -359.715054) (xy 95.970452 -359.733273)
			(xy 96.010189 -359.775287) (xy 96.043131 -359.822816) (xy 96.068523 -359.874772) (xy 96.085785 -359.929964)
			(xy 96.09452 -359.98713) (xy 96.095058 -360.016044) (xy 96.094686 -360.0433) (xy 96.086922 -360.097257)
			(xy 96.071557 -360.14956) (xy 96.048906 -360.199143) (xy 96.019429 -360.244999) (xy 95.983726 -360.286192)
			(xy 95.942523 -360.321885) (xy 95.896661 -360.351351) (xy 95.847072 -360.37399) (xy 95.794765 -360.389342)
			(xy 95.740806 -360.397093) (xy 95.71355 -360.397552) (xy 95.687299 -360.397106) (xy 95.635289 -360.389924)
			(xy 95.584757 -360.375674) (xy 95.536658 -360.354627) (xy 95.491901 -360.32718) (xy 95.451332 -360.293853)
			(xy 95.415719 -360.255275) (xy 95.400368 -360.233976) (xy 95.392004 -360.222763) (xy 95.370379 -360.205037)
			(xy 95.344755 -360.19384) (xy 95.317056 -360.190012) (xy 95.289357 -360.19384) (xy 95.263733 -360.205037)
			(xy 95.242108 -360.222763) (xy 95.233744 -360.233976) (xy 95.218366 -360.255254) (xy 95.182748 -360.293821)
			(xy 95.14218 -360.327143) (xy 95.097428 -360.35459) (xy 95.049336 -360.375643) (xy 94.998813 -360.389907)
			(xy 94.946811 -360.397111) (xy 94.920562 -360.397552) (xy 94.892056 -360.397013) (xy 94.835678 -360.388524)
			(xy 94.781192 -360.37174) (xy 94.729809 -360.347035) (xy 94.682675 -360.31496) (xy 94.640838 -360.276228)
			(xy 94.62262 -360.254296) (xy 94.61269 -360.242603) (xy 94.587311 -360.225391) (xy 94.557967 -360.216484)
			(xy 94.527302 -360.216686) (xy 94.498078 -360.225979) (xy 94.472927 -360.243524) (xy 94.463108 -360.255312)
			(xy 94.444916 -360.277794) (xy 94.402896 -360.317529) (xy 94.355361 -360.350468) (xy 94.3034 -360.375856)
			(xy 94.248203 -360.393113) (xy 94.191034 -360.401843) (xy 94.162118 -360.402378) (xy 94.132824 -360.401817)
			(xy 94.074926 -360.392855) (xy 94.019076 -360.375156) (xy 93.966585 -360.349134) (xy 93.918685 -360.315399)
			(xy 93.876499 -360.274744) (xy 93.858334 -360.251756) (xy 93.849905 -360.241474) (xy 93.828885 -360.225217)
			(xy 93.804384 -360.214928) (xy 93.778059 -360.211303) (xy 93.751689 -360.214588) (xy 93.727058 -360.22456)
			(xy 93.70583 -360.240545) (xy 93.697298 -360.25074) (xy 93.679113 -360.27319) (xy 93.637118 -360.312862)
			(xy 93.589619 -360.345747) (xy 93.537703 -360.371091) (xy 93.482559 -360.388314) (xy 93.425448 -360.397022)
			(xy 93.396562 -360.397552) (xy 93.367646 -360.397008) (xy 93.310475 -360.388287) (xy 93.255276 -360.371035)
			(xy 93.203314 -360.345648) (xy 93.155779 -360.312709) (xy 93.113762 -360.27297) (xy 93.095572 -360.250486)
			(xy 93.085675 -360.238681) (xy 93.060351 -360.221162) (xy 93.030958 -360.211986) (xy 93.000166 -360.211986)
			(xy 92.970773 -360.221162) (xy 92.945449 -360.238681) (xy 92.935552 -360.250486) (xy 92.918799 -360.271269)
			(xy 92.880445 -360.308399) (xy 92.837291 -360.339821) (xy 92.790177 -360.36492) (xy 92.740025 -360.383206)
			(xy 92.687814 -360.394323) (xy 92.634562 -360.398053) (xy 92.58131 -360.394323) (xy 92.529099 -360.383206)
			(xy 92.478947 -360.36492) (xy 92.431833 -360.339821) (xy 92.388679 -360.308399) (xy 92.350325 -360.271269)
			(xy 92.333572 -360.250486) (xy 92.323675 -360.238681) (xy 92.298351 -360.221162) (xy 92.268958 -360.211986)
			(xy 92.238166 -360.211986) (xy 92.208773 -360.221162) (xy 92.183449 -360.238681) (xy 92.173552 -360.250486)
			(xy 92.156799 -360.271269) (xy 92.118445 -360.308399) (xy 92.075291 -360.339821) (xy 92.028177 -360.36492)
			(xy 91.978025 -360.383206) (xy 91.925814 -360.394323) (xy 91.872562 -360.398053) (xy 91.81931 -360.394323)
			(xy 91.767099 -360.383206) (xy 91.716947 -360.36492) (xy 91.669833 -360.339821) (xy 91.626679 -360.308399)
			(xy 91.588325 -360.271269) (xy 91.571572 -360.250486) (xy 91.561675 -360.238681) (xy 91.536351 -360.221162)
			(xy 91.506958 -360.211986) (xy 91.476166 -360.211986) (xy 91.446773 -360.221162) (xy 91.421449 -360.238681)
			(xy 91.411552 -360.250486) (xy 91.393328 -360.272942) (xy 91.351316 -360.312679) (xy 91.303788 -360.345622)
			(xy 91.251833 -360.371015) (xy 91.196641 -360.388277) (xy 91.139476 -360.397013) (xy 91.110562 -360.397552)
			(xy 91.084492 -360.397123) (xy 91.03284 -360.39001) (xy 90.982635 -360.375936) (xy 90.934812 -360.355161)
			(xy 90.890261 -360.328073) (xy 90.84981 -360.295175) (xy 90.81421 -360.25708) (xy 90.784126 -360.214495)
			(xy 90.771726 -360.191558) (xy 90.764913 -360.179441) (xy 90.745946 -360.159136) (xy 90.722205 -360.1447)
			(xy 90.695449 -360.137204) (xy 90.667663 -360.137204) (xy 90.640907 -360.1447) (xy 90.617166 -360.159136)
			(xy 90.598199 -360.179441) (xy 90.591386 -360.191558) (xy 90.578996 -360.214503) (xy 90.548924 -360.257102)
			(xy 90.51333 -360.295209) (xy 90.472879 -360.328114) (xy 90.428324 -360.355203) (xy 90.380494 -360.375973)
			(xy 90.330282 -360.390036) (xy 90.278622 -360.397131) (xy 90.25255 -360.397552) (xy 90.22617 -360.397098)
			(xy 90.173911 -360.389833) (xy 90.123153 -360.375435) (xy 90.074863 -360.354179) (xy 90.029964 -360.326471)
			(xy 89.989312 -360.292839) (xy 89.953683 -360.253925) (xy 89.938352 -360.232452) (xy 89.930165 -360.221296)
			(xy 89.908954 -360.203541) (xy 89.883751 -360.192138) (xy 89.856412 -360.187927) (xy 89.828946 -360.191218)
			(xy 89.803376 -360.201768) (xy 89.78158 -360.218802) (xy 89.772998 -360.229658) (xy 89.754877 -360.253141)
			(xy 89.712594 -360.294738) (xy 89.664381 -360.329286) (xy 89.6114 -360.355953) (xy 89.55493 -360.374095)
			(xy 89.496331 -360.383274) (xy 89.466674 -360.383836) (xy 89.440711 -360.38336) (xy 89.389265 -360.376319)
			(xy 89.339247 -360.36237) (xy 89.291582 -360.341771) (xy 89.247148 -360.314902) (xy 89.206765 -360.282259)
			(xy 89.17118 -360.244444) (xy 89.141048 -360.202155) (xy 89.1286 -360.179366) (xy 89.121978 -360.16751)
			(xy 89.103535 -360.147587) (xy 89.080488 -360.133238) (xy 89.054472 -360.12548) (xy 89.02733 -360.124862)
			(xy 89.000988 -360.131428) (xy 88.977312 -360.144712) (xy 88.95798 -360.163774) (xy 88.9508 -360.175302)
			(xy 88.936041 -360.199594) (xy 88.900425 -360.243892) (xy 88.858631 -360.282415) (xy 88.811584 -360.314311)
			(xy 88.760326 -360.338875) (xy 88.705991 -360.355562) (xy 88.649782 -360.364004) (xy 88.621362 -360.364532)
			(xy 88.592623 -360.364023) (xy 88.535795 -360.355395) (xy 88.480904 -360.338341) (xy 88.429193 -360.313247)
			(xy 88.381831 -360.28068) (xy 88.360504 -360.261408) (xy 88.348663 -360.251155) (xy 88.320383 -360.237729)
			(xy 88.289366 -360.233492) (xy 88.258521 -360.23884) (xy 88.23074 -360.253271) (xy 88.21928 -360.263948)
			(xy 88.197663 -360.284818) (xy 88.149082 -360.320173) (xy 88.095557 -360.347473) (xy 88.038414 -360.366042)
			(xy 87.979067 -360.375421) (xy 87.949024 -360.375962) (xy 87.92177 -360.375522) (xy 87.867815 -360.367767)
			(xy 87.815514 -360.352412) (xy 87.765931 -360.329769) (xy 87.720076 -360.300299) (xy 87.678882 -360.264603)
			(xy 87.643188 -360.223407) (xy 87.613721 -360.177549) (xy 87.59108 -360.127965) (xy 87.575728 -360.075663)
			(xy 87.567976 -360.021708) (xy 87.567516 -359.994454) (xy 81.11987 -359.994454) (xy 85.673184 -371.304312)
			(xy 88.19134 -373.822468) (xy 94.589092 -373.822468)
		)
		(stroke
			(width 0)
			(type solid)
		)
		(fill yes)
		(layer "In13.Cu")
		(net "GND")
	)
	(gr_poly
		(pts
			(xy 370.1796 -288.757868) (xy 370.191782 -288.734558) (xy 370.221967 -288.691486) (xy 370.258158 -288.653323)
			(xy 370.299569 -288.620898) (xy 370.345299 -288.594917) (xy 370.394353 -288.575944) (xy 370.445664 -288.564393)
			(xy 370.498116 -288.560514) (xy 370.550568 -288.564393) (xy 370.601879 -288.575944) (xy 370.650933 -288.594917)
			(xy 370.696663 -288.620898) (xy 370.738074 -288.653323) (xy 370.774265 -288.691486) (xy 370.80445 -288.734558)
			(xy 370.816632 -288.757868) (xy 370.942108 -288.757868) (xy 370.957334 -288.757288) (xy 370.986429 -288.748297)
			(xy 371.01159 -288.731142) (xy 371.03059 -288.707344) (xy 371.041746 -288.679009) (xy 371.044071 -288.648645)
			(xy 371.037359 -288.618941) (xy 371.030246 -288.605468) (xy 370.945918 -288.459418) (xy 370.921026 -288.456116)
			(xy 370.895683 -288.452293) (xy 370.846373 -288.438315) (xy 370.799577 -288.417412) (xy 370.756262 -288.390015)
			(xy 370.717324 -288.356689) (xy 370.683566 -288.318125) (xy 370.655687 -288.275118) (xy 370.634263 -288.228559)
			(xy 370.619736 -288.179408) (xy 370.612407 -288.128682) (xy 370.611908 -288.103056) (xy 370.612406 -288.076407)
			(xy 370.620349 -288.023703) (xy 370.636059 -287.972773) (xy 370.659185 -287.924752) (xy 370.689209 -287.880715)
			(xy 370.725461 -287.841644) (xy 370.767132 -287.808413) (xy 370.81329 -287.781764) (xy 370.862904 -287.762292)
			(xy 370.914866 -287.750432) (xy 370.968016 -287.746449) (xy 371.021166 -287.750432) (xy 371.073128 -287.762292)
			(xy 371.122742 -287.781764) (xy 371.1689 -287.808413) (xy 371.210571 -287.841644) (xy 371.246823 -287.880715)
			(xy 371.276847 -287.924752) (xy 371.299973 -287.972773) (xy 371.315683 -288.023703) (xy 371.323626 -288.076407)
			(xy 371.324124 -288.103056) (xy 371.323751 -288.126302) (xy 371.317712 -288.172399) (xy 371.305731 -288.217319)
			(xy 371.2972 -288.238946) (xy 371.287802 -288.261806) (xy 371.460268 -288.560764) (xy 371.484906 -288.564066)
			(xy 371.509443 -288.567762) (xy 371.557245 -288.58107) (xy 371.602736 -288.600888) (xy 371.645033 -288.626833)
			(xy 371.683316 -288.658401) (xy 371.716843 -288.694981) (xy 371.744964 -288.735863) (xy 371.756432 -288.757868)
			(xy 372.0592 -288.757868) (xy 372.071382 -288.734558) (xy 372.101567 -288.691486) (xy 372.137758 -288.653323)
			(xy 372.179169 -288.620898) (xy 372.224899 -288.594917) (xy 372.273953 -288.575944) (xy 372.325264 -288.564393)
			(xy 372.377716 -288.560514) (xy 372.430168 -288.564393) (xy 372.481479 -288.575944) (xy 372.530533 -288.594917)
			(xy 372.576263 -288.620898) (xy 372.617674 -288.653323) (xy 372.653865 -288.691486) (xy 372.68405 -288.734558)
			(xy 372.696232 -288.757868) (xy 372.821708 -288.757868) (xy 372.836934 -288.757288) (xy 372.866029 -288.748297)
			(xy 372.89119 -288.731142) (xy 372.91019 -288.707344) (xy 372.921346 -288.679009) (xy 372.923671 -288.648645)
			(xy 372.916959 -288.618941) (xy 372.909846 -288.605468) (xy 372.825518 -288.459418) (xy 372.800626 -288.456116)
			(xy 372.775283 -288.452293) (xy 372.725973 -288.438315) (xy 372.679177 -288.417412) (xy 372.635862 -288.390015)
			(xy 372.596924 -288.356689) (xy 372.563166 -288.318125) (xy 372.535287 -288.275118) (xy 372.513863 -288.228559)
			(xy 372.499336 -288.179408) (xy 372.492007 -288.128682) (xy 372.491508 -288.103056) (xy 372.492006 -288.076407)
			(xy 372.499949 -288.023703) (xy 372.515659 -287.972773) (xy 372.538785 -287.924752) (xy 372.568809 -287.880715)
			(xy 372.605061 -287.841644) (xy 372.646732 -287.808413) (xy 372.69289 -287.781764) (xy 372.742504 -287.762292)
			(xy 372.794466 -287.750432) (xy 372.847616 -287.746449) (xy 372.900766 -287.750432) (xy 372.952728 -287.762292)
			(xy 373.002342 -287.781764) (xy 373.0485 -287.808413) (xy 373.090171 -287.841644) (xy 373.126423 -287.880715)
			(xy 373.156447 -287.924752) (xy 373.179573 -287.972773) (xy 373.195283 -288.023703) (xy 373.203226 -288.076407)
			(xy 373.203724 -288.103056) (xy 373.203351 -288.126302) (xy 373.197312 -288.172399) (xy 373.185331 -288.217319)
			(xy 373.1768 -288.238946) (xy 373.167402 -288.261806) (xy 373.339868 -288.560764) (xy 373.364506 -288.564066)
			(xy 373.389043 -288.567762) (xy 373.436845 -288.58107) (xy 373.482336 -288.600888) (xy 373.524633 -288.626833)
			(xy 373.562916 -288.658401) (xy 373.596443 -288.694981) (xy 373.624564 -288.735863) (xy 373.636032 -288.757868)
			(xy 373.9388 -288.757868) (xy 373.950982 -288.734558) (xy 373.981167 -288.691486) (xy 374.017358 -288.653323)
			(xy 374.058769 -288.620898) (xy 374.104499 -288.594917) (xy 374.153553 -288.575944) (xy 374.204864 -288.564393)
			(xy 374.257316 -288.560514) (xy 374.309768 -288.564393) (xy 374.361079 -288.575944) (xy 374.410133 -288.594917)
			(xy 374.455863 -288.620898) (xy 374.497274 -288.653323) (xy 374.533465 -288.691486) (xy 374.56365 -288.734558)
			(xy 374.575832 -288.757868) (xy 374.701308 -288.757868) (xy 374.716534 -288.757288) (xy 374.745629 -288.748297)
			(xy 374.77079 -288.731142) (xy 374.78979 -288.707344) (xy 374.800946 -288.679009) (xy 374.803271 -288.648645)
			(xy 374.796559 -288.618941) (xy 374.789446 -288.605468) (xy 374.705118 -288.459418) (xy 374.680226 -288.456116)
			(xy 374.654883 -288.452293) (xy 374.605573 -288.438315) (xy 374.558777 -288.417412) (xy 374.515462 -288.390015)
			(xy 374.476524 -288.356689) (xy 374.442766 -288.318125) (xy 374.414887 -288.275118) (xy 374.393463 -288.228559)
			(xy 374.378936 -288.179408) (xy 374.371607 -288.128682) (xy 374.371108 -288.103056) (xy 374.371606 -288.076407)
			(xy 374.379549 -288.023703) (xy 374.395259 -287.972773) (xy 374.418385 -287.924752) (xy 374.448409 -287.880715)
			(xy 374.484661 -287.841644) (xy 374.526332 -287.808413) (xy 374.57249 -287.781764) (xy 374.622104 -287.762292)
			(xy 374.674066 -287.750432) (xy 374.727216 -287.746449) (xy 374.780366 -287.750432) (xy 374.832328 -287.762292)
			(xy 374.881942 -287.781764) (xy 374.9281 -287.808413) (xy 374.969771 -287.841644) (xy 375.006023 -287.880715)
			(xy 375.036047 -287.924752) (xy 375.059173 -287.972773) (xy 375.074883 -288.023703) (xy 375.082826 -288.076407)
			(xy 375.083324 -288.103056) (xy 375.082951 -288.126302) (xy 375.076912 -288.172399) (xy 375.064931 -288.217319)
			(xy 375.0564 -288.238946) (xy 375.047002 -288.261806) (xy 375.219468 -288.560764) (xy 375.244106 -288.564066)
			(xy 375.268643 -288.567762) (xy 375.316445 -288.58107) (xy 375.361936 -288.600888) (xy 375.404233 -288.626833)
			(xy 375.442516 -288.658401) (xy 375.476043 -288.694981) (xy 375.504164 -288.735863) (xy 375.515632 -288.757868)
			(xy 375.8184 -288.757868) (xy 375.830582 -288.734558) (xy 375.860767 -288.691486) (xy 375.896958 -288.653323)
			(xy 375.938369 -288.620898) (xy 375.984099 -288.594917) (xy 376.033153 -288.575944) (xy 376.084464 -288.564393)
			(xy 376.136916 -288.560514) (xy 376.189368 -288.564393) (xy 376.240679 -288.575944) (xy 376.289733 -288.594917)
			(xy 376.335463 -288.620898) (xy 376.376874 -288.653323) (xy 376.413065 -288.691486) (xy 376.44325 -288.734558)
			(xy 376.455432 -288.757868) (xy 376.580908 -288.757868) (xy 376.596134 -288.757288) (xy 376.625229 -288.748297)
			(xy 376.65039 -288.731142) (xy 376.66939 -288.707344) (xy 376.680546 -288.679009) (xy 376.682871 -288.648645)
			(xy 376.676159 -288.618941) (xy 376.669046 -288.605468) (xy 376.584718 -288.459418) (xy 376.559826 -288.456116)
			(xy 376.534483 -288.452293) (xy 376.485173 -288.438315) (xy 376.438377 -288.417412) (xy 376.395062 -288.390015)
			(xy 376.356124 -288.356689) (xy 376.322366 -288.318125) (xy 376.294487 -288.275118) (xy 376.273063 -288.228559)
			(xy 376.258536 -288.179408) (xy 376.251207 -288.128682) (xy 376.250708 -288.103056) (xy 376.251206 -288.076407)
			(xy 376.259149 -288.023703) (xy 376.274859 -287.972773) (xy 376.297985 -287.924752) (xy 376.328009 -287.880715)
			(xy 376.364261 -287.841644) (xy 376.405932 -287.808413) (xy 376.45209 -287.781764) (xy 376.501704 -287.762292)
			(xy 376.553666 -287.750432) (xy 376.606816 -287.746449) (xy 376.659966 -287.750432) (xy 376.711928 -287.762292)
			(xy 376.761542 -287.781764) (xy 376.8077 -287.808413) (xy 376.849371 -287.841644) (xy 376.885623 -287.880715)
			(xy 376.915647 -287.924752) (xy 376.938773 -287.972773) (xy 376.954483 -288.023703) (xy 376.962426 -288.076407)
			(xy 376.962924 -288.103056) (xy 376.962551 -288.126302) (xy 376.956512 -288.172399) (xy 376.944531 -288.217319)
			(xy 376.936 -288.238946) (xy 376.926602 -288.261806) (xy 377.099068 -288.560764) (xy 377.123706 -288.564066)
			(xy 377.148243 -288.567762) (xy 377.196045 -288.58107) (xy 377.241536 -288.600888) (xy 377.283833 -288.626833)
			(xy 377.322116 -288.658401) (xy 377.355643 -288.694981) (xy 377.383764 -288.735863) (xy 377.395232 -288.757868)
			(xy 377.698 -288.757868) (xy 377.710182 -288.734558) (xy 377.740367 -288.691486) (xy 377.776558 -288.653323)
			(xy 377.817969 -288.620898) (xy 377.863699 -288.594917) (xy 377.912753 -288.575944) (xy 377.964064 -288.564393)
			(xy 378.016516 -288.560514) (xy 378.068968 -288.564393) (xy 378.120279 -288.575944) (xy 378.169333 -288.594917)
			(xy 378.215063 -288.620898) (xy 378.256474 -288.653323) (xy 378.292665 -288.691486) (xy 378.32285 -288.734558)
			(xy 378.335032 -288.757868) (xy 378.460508 -288.757868) (xy 378.475734 -288.757288) (xy 378.504829 -288.748297)
			(xy 378.52999 -288.731142) (xy 378.54899 -288.707344) (xy 378.560146 -288.679009) (xy 378.562471 -288.648645)
			(xy 378.555759 -288.618941) (xy 378.548646 -288.605468) (xy 378.464318 -288.459418) (xy 378.439426 -288.456116)
			(xy 378.414083 -288.452293) (xy 378.364773 -288.438315) (xy 378.317977 -288.417412) (xy 378.274662 -288.390015)
			(xy 378.235724 -288.356689) (xy 378.201966 -288.318125) (xy 378.174087 -288.275118) (xy 378.152663 -288.228559)
			(xy 378.138136 -288.179408) (xy 378.130807 -288.128682) (xy 378.130308 -288.103056) (xy 378.130806 -288.076407)
			(xy 378.138749 -288.023703) (xy 378.154459 -287.972773) (xy 378.177585 -287.924752) (xy 378.207609 -287.880715)
			(xy 378.243861 -287.841644) (xy 378.285532 -287.808413) (xy 378.33169 -287.781764) (xy 378.381304 -287.762292)
			(xy 378.433266 -287.750432) (xy 378.486416 -287.746449) (xy 378.539566 -287.750432) (xy 378.591528 -287.762292)
			(xy 378.641142 -287.781764) (xy 378.6873 -287.808413) (xy 378.728971 -287.841644) (xy 378.765223 -287.880715)
			(xy 378.795247 -287.924752) (xy 378.818373 -287.972773) (xy 378.834083 -288.023703) (xy 378.842026 -288.076407)
			(xy 378.842524 -288.103056) (xy 378.842151 -288.126302) (xy 378.836112 -288.172399) (xy 378.824131 -288.217319)
			(xy 378.8156 -288.238946) (xy 378.806202 -288.261806) (xy 378.978668 -288.560764) (xy 379.003306 -288.564066)
			(xy 379.027843 -288.567762) (xy 379.075645 -288.58107) (xy 379.121136 -288.600888) (xy 379.163433 -288.626833)
			(xy 379.201716 -288.658401) (xy 379.235243 -288.694981) (xy 379.263364 -288.735863) (xy 379.274832 -288.757868)
			(xy 379.5776 -288.757868) (xy 379.589782 -288.734558) (xy 379.619967 -288.691486) (xy 379.656158 -288.653323)
			(xy 379.697569 -288.620898) (xy 379.743299 -288.594917) (xy 379.792353 -288.575944) (xy 379.843664 -288.564393)
			(xy 379.896116 -288.560514) (xy 379.948568 -288.564393) (xy 379.999879 -288.575944) (xy 380.048933 -288.594917)
			(xy 380.094663 -288.620898) (xy 380.136074 -288.653323) (xy 380.172265 -288.691486) (xy 380.20245 -288.734558)
			(xy 380.214632 -288.757868) (xy 380.340108 -288.757868) (xy 380.355334 -288.757288) (xy 380.384429 -288.748297)
			(xy 380.40959 -288.731142) (xy 380.42859 -288.707344) (xy 380.439746 -288.679009) (xy 380.442071 -288.648645)
			(xy 380.435359 -288.618941) (xy 380.428246 -288.605468) (xy 380.343918 -288.459418) (xy 380.319026 -288.456116)
			(xy 380.293683 -288.452293) (xy 380.244373 -288.438315) (xy 380.197577 -288.417412) (xy 380.154262 -288.390015)
			(xy 380.115324 -288.356689) (xy 380.081566 -288.318125) (xy 380.053687 -288.275118) (xy 380.032263 -288.228559)
			(xy 380.017736 -288.179408) (xy 380.010407 -288.128682) (xy 380.009908 -288.103056) (xy 380.010406 -288.076407)
			(xy 380.018349 -288.023703) (xy 380.034059 -287.972773) (xy 380.057185 -287.924752) (xy 380.087209 -287.880715)
			(xy 380.123461 -287.841644) (xy 380.165132 -287.808413) (xy 380.21129 -287.781764) (xy 380.260904 -287.762292)
			(xy 380.312866 -287.750432) (xy 380.366016 -287.746449) (xy 380.419166 -287.750432) (xy 380.471128 -287.762292)
			(xy 380.520742 -287.781764) (xy 380.5669 -287.808413) (xy 380.608571 -287.841644) (xy 380.644823 -287.880715)
			(xy 380.674847 -287.924752) (xy 380.697973 -287.972773) (xy 380.713683 -288.023703) (xy 380.721626 -288.076407)
			(xy 380.722124 -288.103056) (xy 380.721751 -288.126302) (xy 380.721305 -288.129705) (xy 381.890006 -288.129705)
			(xy 381.890006 -288.076407) (xy 381.897949 -288.023703) (xy 381.913659 -287.972773) (xy 381.936785 -287.924752)
			(xy 381.966809 -287.880715) (xy 382.003061 -287.841644) (xy 382.044732 -287.808413) (xy 382.09089 -287.781764)
			(xy 382.140504 -287.762292) (xy 382.192466 -287.750432) (xy 382.245616 -287.746449) (xy 382.298766 -287.750432)
			(xy 382.350728 -287.762292) (xy 382.400342 -287.781764) (xy 382.4465 -287.808413) (xy 382.488171 -287.841644)
			(xy 382.524423 -287.880715) (xy 382.554447 -287.924752) (xy 382.577573 -287.972773) (xy 382.593283 -288.023703)
			(xy 382.601226 -288.076407) (xy 382.601724 -288.103056) (xy 382.601226 -288.129705) (xy 382.593283 -288.182409)
			(xy 382.577573 -288.233339) (xy 382.554447 -288.28136) (xy 382.524423 -288.325397) (xy 382.488171 -288.364468)
			(xy 382.4465 -288.397699) (xy 382.400342 -288.424348) (xy 382.350728 -288.44382) (xy 382.298766 -288.45568)
			(xy 382.245616 -288.459664) (xy 382.192466 -288.45568) (xy 382.140504 -288.44382) (xy 382.09089 -288.424348)
			(xy 382.044732 -288.397699) (xy 382.003061 -288.364468) (xy 381.966809 -288.325397) (xy 381.936785 -288.28136)
			(xy 381.913659 -288.233339) (xy 381.897949 -288.182409) (xy 381.890006 -288.129705) (xy 380.721305 -288.129705)
			(xy 380.715712 -288.172399) (xy 380.703731 -288.217319) (xy 380.6952 -288.238946) (xy 380.685802 -288.261806)
			(xy 380.858268 -288.560764) (xy 380.882906 -288.564066) (xy 380.907443 -288.567762) (xy 380.955245 -288.58107)
			(xy 381.000736 -288.600888) (xy 381.043033 -288.626833) (xy 381.081316 -288.658401) (xy 381.114843 -288.694981)
			(xy 381.142964 -288.735863) (xy 381.154432 -288.757868) (xy 381.4572 -288.757868) (xy 381.469382 -288.734558)
			(xy 381.499567 -288.691486) (xy 381.535758 -288.653323) (xy 381.577169 -288.620898) (xy 381.622899 -288.594917)
			(xy 381.671953 -288.575944) (xy 381.723264 -288.564393) (xy 381.775716 -288.560514) (xy 381.828168 -288.564393)
			(xy 381.879479 -288.575944) (xy 381.928533 -288.594917) (xy 381.974263 -288.620898) (xy 382.015674 -288.653323)
			(xy 382.051865 -288.691486) (xy 382.08205 -288.734558) (xy 382.094232 -288.757868) (xy 382.397 -288.757868)
			(xy 382.41008 -288.732903) (xy 382.442907 -288.687094) (xy 382.48254 -288.647027) (xy 382.52799 -288.613703)
			(xy 382.578122 -288.587954) (xy 382.631683 -288.570424) (xy 382.687337 -288.561549) (xy 382.715516 -288.561018)
			(xy 382.741113 -288.561442) (xy 382.791782 -288.568739) (xy 382.840883 -288.583222) (xy 382.887401 -288.604594)
			(xy 382.930376 -288.632411) (xy 382.949958 -288.648902) (xy 382.985518 -288.680398) (xy 383.072386 -288.59353)
			(xy 383.082048 -288.583229) (xy 383.095796 -288.558571) (xy 383.102275 -288.531092) (xy 383.100989 -288.50289)
			(xy 383.092038 -288.476115) (xy 383.076104 -288.452809) (xy 383.054403 -288.434752) (xy 383.041652 -288.428684)
			(xy 383.018303 -288.417898) (xy 382.974716 -288.390596) (xy 382.935513 -288.357306) (xy 382.901509 -288.318719)
			(xy 382.873414 -288.275639) (xy 382.851811 -288.228965) (xy 382.837152 -288.179666) (xy 382.829741 -288.128772)
			(xy 382.829308 -288.103056) (xy 382.82986 -288.075076) (xy 382.838621 -288.019805) (xy 382.855919 -287.966585)
			(xy 382.88133 -287.916726) (xy 382.914227 -287.871455) (xy 382.953801 -287.831888) (xy 382.999077 -287.798999)
			(xy 383.04894 -287.773596) (xy 383.102163 -287.756307) (xy 383.157436 -287.747556) (xy 383.185416 -287.746948)
			(xy 383.211131 -287.747402) (xy 383.262025 -287.754808) (xy 383.311322 -287.769463) (xy 383.357997 -287.791063)
			(xy 383.401075 -287.819156) (xy 383.439661 -287.853159) (xy 383.47295 -287.892361) (xy 383.500249 -287.935948)
			(xy 383.511044 -287.959292) (xy 383.517168 -287.972016) (xy 383.535211 -287.993724) (xy 383.558505 -288.009666)
			(xy 383.585273 -288.018625) (xy 383.613471 -288.019916) (xy 383.640945 -288.013441) (xy 383.665599 -287.999695)
			(xy 383.67589 -287.990026) (xy 384.258058 -287.407858) (xy 384.250692 -287.379664) (xy 384.245216 -287.357396)
			(xy 384.239356 -287.311915) (xy 384.239008 -287.288986) (xy 384.23953 -287.261002) (xy 384.248287 -287.205723)
			(xy 384.265585 -287.152494) (xy 384.290996 -287.102627) (xy 384.323895 -287.057349) (xy 384.363472 -287.017775)
			(xy 384.408753 -286.98488) (xy 384.458622 -286.959473) (xy 384.511852 -286.94218) (xy 384.567132 -286.933427)
			(xy 384.595116 -286.932878) (xy 384.618045 -286.933218) (xy 384.663527 -286.93908) (xy 384.685794 -286.944562)
			(xy 384.713988 -286.951928) (xy 384.804158 -286.861758) (xy 384.814865 -286.850231) (xy 384.829304 -286.822298)
			(xy 384.834587 -286.791301) (xy 384.830215 -286.760162) (xy 384.816601 -286.731819) (xy 384.80619 -286.720026)
			(xy 384.787979 -286.700069) (xy 384.757182 -286.655681) (xy 384.733445 -286.607149) (xy 384.717312 -286.555589)
			(xy 384.709155 -286.502183) (xy 384.708654 -286.47517) (xy 384.709205 -286.447187) (xy 384.717964 -286.391912)
			(xy 384.73526 -286.338686) (xy 384.760669 -286.288821) (xy 384.793565 -286.243545) (xy 384.833139 -286.203971)
			(xy 384.878414 -286.171074) (xy 384.928279 -286.145663) (xy 384.981504 -286.128366) (xy 385.036779 -286.119606)
			(xy 385.064762 -286.119062) (xy 385.091776 -286.11956) (xy 385.145184 -286.127715) (xy 385.196748 -286.143843)
			(xy 385.245285 -286.167575) (xy 385.289679 -286.198366) (xy 385.309618 -286.216598) (xy 385.321439 -286.226974)
			(xy 385.349765 -286.240608) (xy 385.380894 -286.244988) (xy 385.411882 -286.2397) (xy 385.439797 -286.225243)
			(xy 385.45135 -286.214566) (xy 385.490212 -286.175704) (xy 385.500652 -286.164538) (xy 385.514914 -286.137515)
			(xy 385.520561 -286.107485) (xy 385.51709 -286.077128) (xy 385.50481 -286.049148) (xy 385.484817 -286.026042)
			(xy 385.458892 -286.009868) (xy 385.444238 -286.005524) (xy 385.419205 -285.99846) (xy 385.371356 -285.978069)
			(xy 385.326982 -285.950934) (xy 385.287028 -285.917633) (xy 385.252343 -285.878873) (xy 385.223666 -285.83548)
			(xy 385.201606 -285.788377) (xy 385.186634 -285.738566) (xy 385.179067 -285.687106) (xy 385.178554 -285.6611)
			(xy 385.179103 -285.633116) (xy 385.187858 -285.577836) (xy 385.205152 -285.524607) (xy 385.230559 -285.474738)
			(xy 385.263455 -285.429457) (xy 385.303028 -285.389879) (xy 385.348305 -285.356979) (xy 385.398172 -285.331566)
			(xy 385.451399 -285.314267) (xy 385.506678 -285.305506) (xy 385.534662 -285.304992) (xy 385.562277 -285.305517)
			(xy 385.616844 -285.314051) (xy 385.66944 -285.330905) (xy 385.718804 -285.355675) (xy 385.763753 -285.387768)
			(xy 385.803211 -285.426413) (xy 385.836231 -285.470686) (xy 385.862021 -285.519525) (xy 385.879965 -285.571759)
			(xy 385.889631 -285.626137) (xy 385.89077 -285.653734) (xy 385.891024 -285.674054) (xy 385.94157 -285.724346)
			(xy 386.001768 -285.664148) (xy 386.001768 -285.206186) (xy 385.957572 -285.200344) (xy 385.930897 -285.196289)
			(xy 385.879102 -285.18118) (xy 385.830179 -285.158431) (xy 385.785247 -285.128564) (xy 385.745333 -285.092261)
			(xy 385.711352 -285.050353) (xy 385.68408 -285.0038) (xy 385.664142 -284.953665) (xy 385.651994 -284.901097)
			(xy 385.647914 -284.847298) (xy 385.651994 -284.793499) (xy 385.664143 -284.740931) (xy 385.684082 -284.690797)
			(xy 385.711354 -284.644243) (xy 385.745336 -284.602336) (xy 385.78525 -284.566034) (xy 385.830183 -284.536167)
			(xy 385.879106 -284.513419) (xy 385.930901 -284.49831) (xy 385.957572 -284.494224) (xy 386.001768 -284.488382)
			(xy 386.001768 -283.578808) (xy 385.957572 -283.572966) (xy 385.930906 -283.568898) (xy 385.879132 -283.553767)
			(xy 385.83023 -283.531003) (xy 385.78532 -283.501126) (xy 385.745428 -283.46482) (xy 385.711466 -283.422914)
			(xy 385.68421 -283.376367) (xy 385.664284 -283.326242) (xy 385.652143 -283.273686) (xy 385.648065 -283.219901)
			(xy 385.652143 -283.166115) (xy 385.664284 -283.113559) (xy 385.68421 -283.063434) (xy 385.711465 -283.016887)
			(xy 385.745427 -282.974981) (xy 385.785319 -282.938675) (xy 385.830229 -282.908798) (xy 385.87913 -282.886034)
			(xy 385.930904 -282.870903) (xy 385.957572 -282.866846) (xy 386.001768 -282.861004) (xy 386.001768 -281.950922)
			(xy 385.957572 -281.94508) (xy 385.932225 -281.94126) (xy 385.882906 -281.927288) (xy 385.8361 -281.906389)
			(xy 385.792775 -281.878995) (xy 385.753825 -281.845671) (xy 385.720056 -281.807107) (xy 385.692166 -281.764099)
			(xy 385.670731 -281.717536) (xy 385.656193 -281.668381) (xy 385.648855 -281.61765) (xy 385.648454 -281.59202)
			(xy 385.648708 -281.577542) (xy 385.649724 -281.555444) (xy 385.593844 -281.499564) (xy 385.583944 -281.490259)
			(xy 385.560363 -281.476785) (xy 385.534062 -281.470012) (xy 385.506906 -281.470419) (xy 385.480819 -281.477978)
			(xy 385.457653 -281.492153) (xy 385.439048 -281.511939) (xy 385.426324 -281.535933) (xy 385.420382 -281.562435)
			(xy 385.420616 -281.576018) (xy 385.42087 -281.59202) (xy 385.420363 -281.619096) (xy 385.41216 -281.672624)
			(xy 385.395946 -281.724293) (xy 385.372096 -281.77291) (xy 385.341159 -281.817356) (xy 385.303848 -281.856604)
			(xy 385.261025 -281.88975) (xy 385.213676 -281.91603) (xy 385.162894 -281.934837) (xy 385.109849 -281.945737)
			(xy 385.055766 -281.94848) (xy 385.001891 -281.943001) (xy 384.949467 -281.929428) (xy 384.899703 -281.908073)
			(xy 384.853746 -281.879429) (xy 384.812656 -281.844156) (xy 384.777382 -281.803069) (xy 384.748735 -281.757113)
			(xy 384.727378 -281.70735) (xy 384.713802 -281.654926) (xy 384.708321 -281.601052) (xy 384.711061 -281.546969)
			(xy 384.721958 -281.493924) (xy 384.740763 -281.443141) (xy 384.76704 -281.395791) (xy 384.800184 -281.352965)
			(xy 384.83943 -281.315653) (xy 384.883874 -281.284713) (xy 384.932491 -281.26086) (xy 384.984158 -281.244644)
			(xy 385.037686 -281.236438) (xy 385.064762 -281.235912) (xy 385.080764 -281.236166) (xy 385.094324 -281.236332)
			(xy 385.120763 -281.230343) (xy 385.144692 -281.217603) (xy 385.164422 -281.199012) (xy 385.178561 -281.175882)
			(xy 385.18611 -281.149846) (xy 385.186537 -281.12274) (xy 385.179812 -281.096479) (xy 385.166409 -281.072915)
			(xy 385.157218 -281.062938) (xy 385.050284 -280.956004) (xy 385.039227 -280.945712) (xy 385.012575 -280.93153)
			(xy 384.982939 -280.925768) (xy 384.952915 -280.928931) (xy 384.92513 -280.940743) (xy 384.902019 -280.960168)
			(xy 384.893312 -280.972514) (xy 384.879146 -280.993467) (xy 384.845835 -281.031527) (xy 384.807474 -281.06449)
			(xy 384.764835 -281.091693) (xy 384.718774 -281.112587) (xy 384.670221 -281.126753) (xy 384.620151 -281.133905)
			(xy 384.594862 -281.134312) (xy 384.566881 -281.13376) (xy 384.511608 -281.125) (xy 384.458386 -281.107703)
			(xy 384.408524 -281.082293) (xy 384.363252 -281.049396) (xy 384.323682 -281.009822) (xy 384.29079 -280.964547)
			(xy 384.265384 -280.914683) (xy 384.248092 -280.861459) (xy 384.239337 -280.806185) (xy 384.238754 -280.778204)
			(xy 384.239196 -280.752916) (xy 384.246349 -280.702848) (xy 384.260511 -280.654295) (xy 384.281397 -280.608233)
			(xy 384.308588 -280.565588) (xy 384.341537 -280.527218) (xy 384.379582 -280.493893) (xy 384.400552 -280.479754)
			(xy 384.412886 -280.471058) (xy 384.43224 -280.447924) (xy 384.444002 -280.42015) (xy 384.447149 -280.390153)
			(xy 384.441407 -280.360542) (xy 384.427275 -280.333895) (xy 384.417062 -280.322782) (xy 384.342894 -280.248614)
			(xy 384.308858 -280.269188) (xy 384.287949 -280.281299) (xy 384.24356 -280.300391) (xy 384.197001 -280.313316)
			(xy 384.149122 -280.319835) (xy 384.124962 -280.320242) (xy 384.09698 -280.31969) (xy 384.041705 -280.310931)
			(xy 383.988481 -280.293633) (xy 383.938618 -280.268224) (xy 383.893342 -280.235327) (xy 383.85377 -280.195754)
			(xy 383.820874 -280.150479) (xy 383.795465 -280.100615) (xy 383.778168 -280.047391) (xy 383.769409 -279.992116)
			(xy 383.768854 -279.964134) (xy 383.769406 -279.935046) (xy 383.778818 -279.877638) (xy 383.797444 -279.822525)
			(xy 383.82479 -279.771178) (xy 383.842006 -279.747726) (xy 383.596134 -279.501854) (xy 383.581402 -279.498806)
			(xy 383.556346 -279.493047) (xy 383.508099 -279.47529) (xy 383.462906 -279.450781) (xy 383.421706 -279.420031)
			(xy 383.385354 -279.383676) (xy 383.354606 -279.342474) (xy 383.330101 -279.297279) (xy 383.312347 -279.249031)
			(xy 383.306574 -279.223978) (xy 383.303526 -279.209246) (xy 383.239772 -279.145492) (xy 383.229498 -279.13591)
			(xy 383.204943 -279.122282) (xy 383.177606 -279.115852) (xy 383.149551 -279.117107) (xy 383.122897 -279.125951)
			(xy 383.099656 -279.141716) (xy 383.081585 -279.163212) (xy 383.070047 -279.188816) (xy 383.06756 -279.202642)
			(xy 383.062895 -279.230438) (xy 383.045944 -279.284187) (xy 383.020738 -279.334594) (xy 382.987904 -279.380401)
			(xy 382.948263 -279.420462) (xy 382.902806 -279.453777) (xy 382.852667 -279.479514) (xy 382.7991 -279.497031)
			(xy 382.743441 -279.505889) (xy 382.715262 -279.506426) (xy 382.68728 -279.505874) (xy 382.632007 -279.497115)
			(xy 382.578784 -279.479817) (xy 382.528921 -279.454407) (xy 382.483647 -279.421511) (xy 382.444076 -279.381937)
			(xy 382.411182 -279.336662) (xy 382.385775 -279.286798) (xy 382.368481 -279.233574) (xy 382.359724 -279.1783)
			(xy 382.359154 -279.150318) (xy 382.359695 -279.122143) (xy 382.368579 -279.066497) (xy 382.386112 -279.012944)
			(xy 382.411858 -278.962819) (xy 382.445173 -278.917372) (xy 382.485228 -278.877736) (xy 382.531023 -278.844901)
			(xy 382.581417 -278.819684) (xy 382.635151 -278.802715) (xy 382.662938 -278.79802) (xy 382.67678 -278.795547)
			(xy 382.702431 -278.784055) (xy 382.723972 -278.765999) (xy 382.739767 -278.74275) (xy 382.748617 -278.716072)
			(xy 382.74985 -278.687991) (xy 382.743372 -278.66064) (xy 382.729675 -278.636096) (xy 382.720088 -278.625808)
			(xy 382.66116 -278.56688) (xy 382.651068 -278.557309) (xy 382.626888 -278.543581) (xy 382.599899 -278.536895)
			(xy 382.572107 -278.537748) (xy 382.545579 -278.546075) (xy 382.522286 -278.561258) (xy 382.512824 -278.571452)
			(xy 382.49585 -278.590128) (xy 382.45754 -278.622979) (xy 382.414973 -278.650088) (xy 382.369004 -278.670913)
			(xy 382.320554 -278.685036) (xy 382.270595 -278.692174) (xy 382.245362 -278.69261) (xy 382.217381 -278.692058)
			(xy 382.162108 -278.683298) (xy 382.108886 -278.666001) (xy 382.059025 -278.640591) (xy 382.013752 -278.607694)
			(xy 381.974183 -278.56812) (xy 381.941291 -278.522844) (xy 381.915886 -278.472981) (xy 381.898593 -278.419757)
			(xy 381.889839 -278.364483) (xy 381.889254 -278.336502) (xy 381.889694 -278.311269) (xy 381.896826 -278.261309)
			(xy 381.910947 -278.212859) (xy 381.931773 -278.16689) (xy 381.958886 -278.124326) (xy 381.991743 -278.086021)
			(xy 382.010412 -278.06904) (xy 382.020516 -278.059506) (xy 382.035635 -278.036216) (xy 382.04393 -278.009716)
			(xy 382.044791 -277.981962) (xy 382.038153 -277.955) (xy 382.024506 -277.930817) (xy 382.014984 -277.920704)
			(xy 381.936244 -277.841964) (xy 381.905256 -277.854156) (xy 381.874027 -277.865556) (xy 381.808699 -277.877829)
			(xy 381.775462 -277.87854) (xy 381.74748 -277.877988) (xy 381.692205 -277.869229) (xy 381.638981 -277.851931)
			(xy 381.589118 -277.826522) (xy 381.543843 -277.793625) (xy 381.504271 -277.754052) (xy 381.471375 -277.708777)
			(xy 381.445967 -277.658913) (xy 381.42867 -277.605689) (xy 381.419911 -277.550414) (xy 381.419354 -277.522432)
			(xy 381.420071 -277.489196) (xy 381.432343 -277.423868) (xy 381.443738 -277.392638) (xy 381.45593 -277.36165)
			(xy 381.067564 -276.973284) (xy 381.066548 -276.972522) (xy 381.04191 -276.947884) (xy 381.041148 -276.946868)
			(xy 380.872746 -276.778466) (xy 380.861894 -276.768321) (xy 380.835755 -276.754234) (xy 380.806667 -276.748263)
			(xy 380.777092 -276.750915) (xy 380.749531 -276.761964) (xy 380.726315 -276.780476) (xy 380.709407 -276.804886)
			(xy 380.704344 -276.818852) (xy 380.695165 -276.845277) (xy 380.669745 -276.895105) (xy 380.636848 -276.940346)
			(xy 380.597283 -276.979888) (xy 380.552022 -277.012758) (xy 380.502178 -277.038147) (xy 380.448978 -277.055432)
			(xy 380.393731 -277.064187) (xy 380.365762 -277.064724) (xy 380.33778 -277.064172) (xy 380.282507 -277.055413)
			(xy 380.229284 -277.038115) (xy 380.179422 -277.012705) (xy 380.134148 -276.979809) (xy 380.094577 -276.940235)
			(xy 380.061683 -276.894959) (xy 380.036277 -276.845096) (xy 380.018982 -276.791872) (xy 380.010226 -276.736598)
			(xy 380.009654 -276.708616) (xy 380.010201 -276.680647) (xy 380.018946 -276.625396) (xy 380.036225 -276.572193)
			(xy 380.06161 -276.522346) (xy 380.094479 -276.477083) (xy 380.134022 -276.437516) (xy 380.179266 -276.404621)
			(xy 380.229098 -276.379205) (xy 380.255526 -276.370034) (xy 380.269466 -276.364938) (xy 380.293826 -276.348004)
			(xy 380.3123 -276.324789) (xy 380.323332 -276.297249) (xy 380.325993 -276.2677) (xy 380.320059 -276.238632)
			(xy 380.306031 -276.212491) (xy 380.295912 -276.201632) (xy 380.265178 -276.170898) (xy 380.254031 -276.160538)
			(xy 380.227153 -276.1463) (xy 380.197276 -276.140606) (xy 380.167046 -276.14396) (xy 380.139142 -276.156064)
			(xy 380.127256 -276.165564) (xy 380.10781 -276.181588) (xy 380.065259 -276.208575) (xy 380.019331 -276.229299)
			(xy 379.970942 -276.243347) (xy 379.921056 -276.25044) (xy 379.895862 -276.250908) (xy 379.867881 -276.250356)
			(xy 379.812608 -276.241596) (xy 379.759386 -276.224299) (xy 379.709525 -276.198888) (xy 379.664253 -276.165992)
			(xy 379.624684 -276.126418) (xy 379.591792 -276.081142) (xy 379.566387 -276.031279) (xy 379.549095 -275.978055)
			(xy 379.540341 -275.922781) (xy 379.539754 -275.8948) (xy 379.54019 -275.869605) (xy 379.547288 -275.819718)
			(xy 379.561344 -275.771328) (xy 379.582076 -275.725401) (xy 379.609072 -275.682852) (xy 379.625098 -275.663406)
			(xy 379.634552 -275.651487) (xy 379.646648 -275.62359) (xy 379.650009 -275.59337) (xy 379.644338 -275.563498)
			(xy 379.630136 -275.536612) (xy 379.619764 -275.525484) (xy 379.519688 -275.425408) (xy 379.493272 -275.430488)
			(xy 379.47667 -275.433479) (xy 379.443084 -275.436662) (xy 379.426216 -275.436838) (xy 379.398231 -275.43629)
			(xy 379.34295 -275.427537) (xy 379.289719 -275.410245) (xy 379.239849 -275.384838) (xy 379.194566 -275.351943)
			(xy 379.154987 -275.312369) (xy 379.122086 -275.267091) (xy 379.096673 -275.217223) (xy 379.079373 -275.163994)
			(xy 379.070613 -275.108715) (xy 379.070108 -275.08073) (xy 379.070305 -275.063863) (xy 379.073482 -275.030278)
			(xy 379.076458 -275.013674) (xy 379.081538 -274.987258) (xy 378.496322 -274.402042) (xy 378.486301 -274.392647)
			(xy 378.46242 -274.379094) (xy 378.435792 -274.372391) (xy 378.408341 -274.373025) (xy 378.38205 -274.380947)
			(xy 378.358819 -274.395587) (xy 378.340328 -274.415886) (xy 378.333762 -274.42795) (xy 378.320629 -274.452716)
			(xy 378.28777 -274.498131) (xy 378.248196 -274.537832) (xy 378.202886 -274.570835) (xy 378.15296 -274.596324)
			(xy 378.099655 -274.613667) (xy 378.04429 -274.622437) (xy 378.016262 -274.623022) (xy 377.98828 -274.62247)
			(xy 377.933007 -274.613711) (xy 377.879784 -274.596413) (xy 377.829922 -274.571003) (xy 377.784649 -274.538106)
			(xy 377.745078 -274.498533) (xy 377.712185 -274.453257) (xy 377.686778 -274.403394) (xy 377.669484 -274.35017)
			(xy 377.660728 -274.294896) (xy 377.660154 -274.266914) (xy 377.660852 -274.235915) (xy 377.671626 -274.174857)
			(xy 377.692784 -274.116579) (xy 377.707652 -274.089368) (xy 377.71483 -274.075912) (xy 377.721603 -274.046189)
			(xy 377.719307 -274.01579) (xy 377.708146 -273.987422) (xy 377.689113 -273.963609) (xy 377.663902 -273.946469)
			(xy 377.634758 -273.93753) (xy 377.619514 -273.936968) (xy 377.47321 -273.936968) (xy 377.457986 -273.937546)
			(xy 377.428892 -273.946534) (xy 377.403733 -273.963686) (xy 377.384736 -273.987484) (xy 377.373585 -274.015819)
			(xy 377.371267 -274.04618) (xy 377.377988 -274.075879) (xy 377.385072 -274.089368) (xy 377.399968 -274.116565)
			(xy 377.421139 -274.174844) (xy 377.431877 -274.235911) (xy 377.43257 -274.266914) (xy 377.432072 -274.293563)
			(xy 377.424129 -274.346267) (xy 377.408419 -274.397197) (xy 377.385293 -274.445218) (xy 377.355269 -274.489255)
			(xy 377.319017 -274.528326) (xy 377.277346 -274.561557) (xy 377.231188 -274.588206) (xy 377.181574 -274.607678)
			(xy 377.129612 -274.619538) (xy 377.076462 -274.623522) (xy 377.023312 -274.619538) (xy 376.97135 -274.607678)
			(xy 376.921736 -274.588206) (xy 376.875578 -274.561557) (xy 376.833907 -274.528326) (xy 376.797655 -274.489255)
			(xy 376.767631 -274.445218) (xy 376.744505 -274.397197) (xy 376.728795 -274.346267) (xy 376.720852 -274.293563)
			(xy 376.720354 -274.266914) (xy 376.721052 -274.235915) (xy 376.731826 -274.174857) (xy 376.752984 -274.116579)
			(xy 376.767852 -274.089368) (xy 376.77503 -274.075912) (xy 376.781803 -274.046189) (xy 376.779507 -274.01579)
			(xy 376.768346 -273.987422) (xy 376.749313 -273.963609) (xy 376.724102 -273.946469) (xy 376.694958 -273.93753)
			(xy 376.679714 -273.936968) (xy 376.53341 -273.936968) (xy 376.518186 -273.937546) (xy 376.489092 -273.946534)
			(xy 376.463933 -273.963686) (xy 376.444936 -273.987484) (xy 376.433785 -274.015819) (xy 376.431467 -274.04618)
			(xy 376.438188 -274.075879) (xy 376.445272 -274.089368) (xy 376.460168 -274.116565) (xy 376.481339 -274.174844)
			(xy 376.492077 -274.235911) (xy 376.49277 -274.266914) (xy 376.492272 -274.293563) (xy 376.484329 -274.346267)
			(xy 376.468619 -274.397197) (xy 376.445493 -274.445218) (xy 376.415469 -274.489255) (xy 376.379217 -274.528326)
			(xy 376.337546 -274.561557) (xy 376.291388 -274.588206) (xy 376.241774 -274.607678) (xy 376.189812 -274.619538)
			(xy 376.136662 -274.623522) (xy 376.083512 -274.619538) (xy 376.03155 -274.607678) (xy 375.981936 -274.588206)
			(xy 375.935778 -274.561557) (xy 375.894107 -274.528326) (xy 375.857855 -274.489255) (xy 375.827831 -274.445218)
			(xy 375.804705 -274.397197) (xy 375.788995 -274.346267) (xy 375.781052 -274.293563) (xy 375.780554 -274.266914)
			(xy 375.781252 -274.235915) (xy 375.792026 -274.174857) (xy 375.813184 -274.116579) (xy 375.828052 -274.089368)
			(xy 375.83523 -274.075912) (xy 375.842003 -274.046189) (xy 375.839707 -274.01579) (xy 375.828546 -273.987422)
			(xy 375.809513 -273.963609) (xy 375.784302 -273.946469) (xy 375.755158 -273.93753) (xy 375.739914 -273.936968)
			(xy 375.59361 -273.936968) (xy 375.578386 -273.937546) (xy 375.549292 -273.946534) (xy 375.524133 -273.963686)
			(xy 375.505136 -273.987484) (xy 375.493985 -274.015819) (xy 375.491667 -274.04618) (xy 375.498388 -274.075879)
			(xy 375.505472 -274.089368) (xy 375.520368 -274.116565) (xy 375.541539 -274.174844) (xy 375.552277 -274.235911)
			(xy 375.55297 -274.266914) (xy 375.552472 -274.293563) (xy 375.544529 -274.346267) (xy 375.528819 -274.397197)
			(xy 375.505693 -274.445218) (xy 375.475669 -274.489255) (xy 375.439417 -274.528326) (xy 375.397746 -274.561557)
			(xy 375.351588 -274.588206) (xy 375.301974 -274.607678) (xy 375.250012 -274.619538) (xy 375.196862 -274.623522)
			(xy 375.143712 -274.619538) (xy 375.09175 -274.607678) (xy 375.042136 -274.588206) (xy 374.995978 -274.561557)
			(xy 374.954307 -274.528326) (xy 374.918055 -274.489255) (xy 374.888031 -274.445218) (xy 374.864905 -274.397197)
			(xy 374.849195 -274.346267) (xy 374.841252 -274.293563) (xy 374.840754 -274.266914) (xy 374.841452 -274.235915)
			(xy 374.852226 -274.174857) (xy 374.873384 -274.116579) (xy 374.888252 -274.089368) (xy 374.89543 -274.075912)
			(xy 374.902203 -274.046189) (xy 374.899907 -274.01579) (xy 374.888746 -273.987422) (xy 374.869713 -273.963609)
			(xy 374.844502 -273.946469) (xy 374.815358 -273.93753) (xy 374.800114 -273.936968) (xy 374.654064 -273.936968)
			(xy 374.638833 -273.937539) (xy 374.609725 -273.946518) (xy 374.584551 -273.963669) (xy 374.565543 -273.987472)
			(xy 374.554386 -274.015817) (xy 374.552068 -274.04619) (xy 374.558796 -274.075899) (xy 374.565926 -274.089368)
			(xy 374.580824 -274.116565) (xy 374.601997 -274.174843) (xy 374.612737 -274.235911) (xy 374.613424 -274.266914)
			(xy 374.612926 -274.293563) (xy 374.604983 -274.346267) (xy 374.589273 -274.397197) (xy 374.566147 -274.445218)
			(xy 374.536123 -274.489255) (xy 374.499871 -274.528326) (xy 374.4582 -274.561557) (xy 374.412042 -274.588206)
			(xy 374.362428 -274.607678) (xy 374.310466 -274.619538) (xy 374.257316 -274.623522) (xy 374.204166 -274.619538)
			(xy 374.152204 -274.607678) (xy 374.10259 -274.588206) (xy 374.056432 -274.561557) (xy 374.014761 -274.528326)
			(xy 373.978509 -274.489255) (xy 373.948485 -274.445218) (xy 373.925359 -274.397197) (xy 373.909649 -274.346267)
			(xy 373.901706 -274.293563) (xy 373.901208 -274.266914) (xy 373.901905 -274.235914) (xy 373.912679 -274.174856)
			(xy 373.933834 -274.116576) (xy 373.948706 -274.089368) (xy 373.955881 -274.075909) (xy 373.962651 -274.046183)
			(xy 373.960353 -274.015782) (xy 373.949193 -273.98741) (xy 373.930163 -273.963591) (xy 373.904956 -273.946443)
			(xy 373.875812 -273.937491) (xy 373.860568 -273.936968) (xy 373.71401 -273.936968) (xy 373.698786 -273.937546)
			(xy 373.669692 -273.946534) (xy 373.644533 -273.963686) (xy 373.625536 -273.987484) (xy 373.614385 -274.015819)
			(xy 373.612067 -274.04618) (xy 373.618788 -274.075879) (xy 373.625872 -274.089368) (xy 373.640768 -274.116565)
			(xy 373.661939 -274.174844) (xy 373.672677 -274.235911) (xy 373.67337 -274.266914) (xy 373.672872 -274.293563)
			(xy 373.664929 -274.346267) (xy 373.649219 -274.397197) (xy 373.626093 -274.445218) (xy 373.596069 -274.489255)
			(xy 373.559817 -274.528326) (xy 373.518146 -274.561557) (xy 373.471988 -274.588206) (xy 373.422374 -274.607678)
			(xy 373.370412 -274.619538) (xy 373.317262 -274.623522) (xy 373.264112 -274.619538) (xy 373.21215 -274.607678)
			(xy 373.162536 -274.588206) (xy 373.116378 -274.561557) (xy 373.074707 -274.528326) (xy 373.038455 -274.489255)
			(xy 373.008431 -274.445218) (xy 372.985305 -274.397197) (xy 372.969595 -274.346267) (xy 372.961652 -274.293563)
			(xy 372.961154 -274.266914) (xy 372.961852 -274.235915) (xy 372.972626 -274.174857) (xy 372.993784 -274.116579)
			(xy 373.008652 -274.089368) (xy 373.01583 -274.075912) (xy 373.022603 -274.046189) (xy 373.020307 -274.01579)
			(xy 373.009146 -273.987422) (xy 372.990113 -273.963609) (xy 372.964902 -273.946469) (xy 372.935758 -273.93753)
			(xy 372.920514 -273.936968) (xy 372.77421 -273.936968) (xy 372.758986 -273.937546) (xy 372.729892 -273.946534)
			(xy 372.704733 -273.963686) (xy 372.685736 -273.987484) (xy 372.674585 -274.015819) (xy 372.672267 -274.04618)
			(xy 372.678988 -274.075879) (xy 372.686072 -274.089368) (xy 372.700968 -274.116565) (xy 372.722139 -274.174844)
			(xy 372.732877 -274.235911) (xy 372.73357 -274.266914) (xy 372.733072 -274.293563) (xy 372.725129 -274.346267)
			(xy 372.709419 -274.397197) (xy 372.686293 -274.445218) (xy 372.656269 -274.489255) (xy 372.620017 -274.528326)
			(xy 372.578346 -274.561557) (xy 372.532188 -274.588206) (xy 372.482574 -274.607678) (xy 372.430612 -274.619538)
			(xy 372.377462 -274.623522) (xy 372.324312 -274.619538) (xy 372.27235 -274.607678) (xy 372.222736 -274.588206)
			(xy 372.176578 -274.561557) (xy 372.134907 -274.528326) (xy 372.098655 -274.489255) (xy 372.068631 -274.445218)
			(xy 372.045505 -274.397197) (xy 372.029795 -274.346267) (xy 372.021852 -274.293563) (xy 372.021354 -274.266914)
			(xy 372.022052 -274.235915) (xy 372.032826 -274.174857) (xy 372.053984 -274.116579) (xy 372.068852 -274.089368)
			(xy 372.07603 -274.075912) (xy 372.082803 -274.046189) (xy 372.080507 -274.01579) (xy 372.069346 -273.987422)
			(xy 372.050313 -273.963609) (xy 372.025102 -273.946469) (xy 371.995958 -273.93753) (xy 371.980714 -273.936968)
			(xy 371.83441 -273.936968) (xy 371.819186 -273.937546) (xy 371.790092 -273.946534) (xy 371.764933 -273.963686)
			(xy 371.745936 -273.987484) (xy 371.734785 -274.015819) (xy 371.732467 -274.04618) (xy 371.739188 -274.075879)
			(xy 371.746272 -274.089368) (xy 371.761168 -274.116565) (xy 371.782339 -274.174844) (xy 371.793077 -274.235911)
			(xy 371.79377 -274.266914) (xy 371.793272 -274.293563) (xy 371.785329 -274.346267) (xy 371.769619 -274.397197)
			(xy 371.746493 -274.445218) (xy 371.716469 -274.489255) (xy 371.680217 -274.528326) (xy 371.638546 -274.561557)
			(xy 371.592388 -274.588206) (xy 371.542774 -274.607678) (xy 371.490812 -274.619538) (xy 371.437662 -274.623522)
			(xy 371.384512 -274.619538) (xy 371.33255 -274.607678) (xy 371.282936 -274.588206) (xy 371.236778 -274.561557)
			(xy 371.195107 -274.528326) (xy 371.158855 -274.489255) (xy 371.128831 -274.445218) (xy 371.105705 -274.397197)
			(xy 371.089995 -274.346267) (xy 371.082052 -274.293563) (xy 371.081554 -274.266914) (xy 371.082252 -274.235915)
			(xy 371.093026 -274.174857) (xy 371.114184 -274.116579) (xy 371.129052 -274.089368) (xy 371.13623 -274.075912)
			(xy 371.143003 -274.046189) (xy 371.140707 -274.01579) (xy 371.129546 -273.987422) (xy 371.110513 -273.963609)
			(xy 371.085302 -273.946469) (xy 371.056158 -273.93753) (xy 371.040914 -273.936968) (xy 370.89461 -273.936968)
			(xy 370.879386 -273.937546) (xy 370.850292 -273.946534) (xy 370.825133 -273.963686) (xy 370.806136 -273.987484)
			(xy 370.794985 -274.015819) (xy 370.792667 -274.04618) (xy 370.799388 -274.075879) (xy 370.806472 -274.089368)
			(xy 370.821368 -274.116565) (xy 370.842539 -274.174844) (xy 370.853277 -274.235911) (xy 370.85397 -274.266914)
			(xy 370.853472 -274.293563) (xy 370.845529 -274.346267) (xy 370.829819 -274.397197) (xy 370.806693 -274.445218)
			(xy 370.776669 -274.489255) (xy 370.740417 -274.528326) (xy 370.698746 -274.561557) (xy 370.652588 -274.588206)
			(xy 370.602974 -274.607678) (xy 370.551012 -274.619538) (xy 370.497862 -274.623522) (xy 370.444712 -274.619538)
			(xy 370.39275 -274.607678) (xy 370.343136 -274.588206) (xy 370.296978 -274.561557) (xy 370.255307 -274.528326)
			(xy 370.219055 -274.489255) (xy 370.189031 -274.445218) (xy 370.165905 -274.397197) (xy 370.150195 -274.346267)
			(xy 370.142252 -274.293563) (xy 370.141754 -274.266914) (xy 370.142452 -274.235915) (xy 370.153226 -274.174857)
			(xy 370.174384 -274.116579) (xy 370.189252 -274.089368) (xy 370.19643 -274.075912) (xy 370.203203 -274.046189)
			(xy 370.200907 -274.01579) (xy 370.189746 -273.987422) (xy 370.170713 -273.963609) (xy 370.145502 -273.946469)
			(xy 370.116358 -273.93753) (xy 370.101114 -273.936968) (xy 369.955064 -273.936968) (xy 369.939833 -273.937539)
			(xy 369.910725 -273.946518) (xy 369.885551 -273.963669) (xy 369.866543 -273.987472) (xy 369.855386 -274.015817)
			(xy 369.853068 -274.04619) (xy 369.859796 -274.075899) (xy 369.866926 -274.089368) (xy 369.881824 -274.116565)
			(xy 369.902997 -274.174843) (xy 369.913737 -274.235911) (xy 369.914424 -274.266914) (xy 369.913926 -274.293563)
			(xy 369.905983 -274.346267) (xy 369.890273 -274.397197) (xy 369.867147 -274.445218) (xy 369.837123 -274.489255)
			(xy 369.800871 -274.528326) (xy 369.7592 -274.561557) (xy 369.713042 -274.588206) (xy 369.663428 -274.607678)
			(xy 369.611466 -274.619538) (xy 369.558316 -274.623522) (xy 369.505166 -274.619538) (xy 369.453204 -274.607678)
			(xy 369.40359 -274.588206) (xy 369.357432 -274.561557) (xy 369.315761 -274.528326) (xy 369.279509 -274.489255)
			(xy 369.249485 -274.445218) (xy 369.226359 -274.397197) (xy 369.210649 -274.346267) (xy 369.202706 -274.293563)
			(xy 369.202208 -274.266914) (xy 369.202905 -274.235914) (xy 369.213679 -274.174856) (xy 369.234834 -274.116576)
			(xy 369.249706 -274.089368) (xy 369.256881 -274.075909) (xy 369.263651 -274.046183) (xy 369.261353 -274.015782)
			(xy 369.250193 -273.98741) (xy 369.231163 -273.963591) (xy 369.205956 -273.946443) (xy 369.176812 -273.937491)
			(xy 369.161568 -273.936968) (xy 369.01501 -273.936968) (xy 368.999786 -273.937546) (xy 368.970692 -273.946534)
			(xy 368.945533 -273.963686) (xy 368.926536 -273.987484) (xy 368.915385 -274.015819) (xy 368.913067 -274.04618)
			(xy 368.919788 -274.075879) (xy 368.926872 -274.089368) (xy 368.941768 -274.116565) (xy 368.962939 -274.174844)
			(xy 368.973677 -274.235911) (xy 368.97437 -274.266914) (xy 368.973872 -274.293563) (xy 368.965929 -274.346267)
			(xy 368.950219 -274.397197) (xy 368.927093 -274.445218) (xy 368.897069 -274.489255) (xy 368.860817 -274.528326)
			(xy 368.819146 -274.561557) (xy 368.772988 -274.588206) (xy 368.723374 -274.607678) (xy 368.671412 -274.619538)
			(xy 368.618262 -274.623522) (xy 368.565112 -274.619538) (xy 368.51315 -274.607678) (xy 368.463536 -274.588206)
			(xy 368.417378 -274.561557) (xy 368.375707 -274.528326) (xy 368.339455 -274.489255) (xy 368.309431 -274.445218)
			(xy 368.286305 -274.397197) (xy 368.270595 -274.346267) (xy 368.262652 -274.293563) (xy 368.262154 -274.266914)
			(xy 368.262852 -274.235915) (xy 368.273626 -274.174857) (xy 368.294784 -274.116579) (xy 368.309652 -274.089368)
			(xy 368.31683 -274.075912) (xy 368.323603 -274.046189) (xy 368.321307 -274.01579) (xy 368.310146 -273.987422)
			(xy 368.291113 -273.963609) (xy 368.265902 -273.946469) (xy 368.236758 -273.93753) (xy 368.221514 -273.936968)
			(xy 368.07521 -273.936968) (xy 368.059986 -273.937546) (xy 368.030892 -273.946534) (xy 368.005733 -273.963686)
			(xy 367.986736 -273.987484) (xy 367.975585 -274.015819) (xy 367.973267 -274.04618) (xy 367.979988 -274.075879)
			(xy 367.987072 -274.089368) (xy 368.001968 -274.116565) (xy 368.023139 -274.174844) (xy 368.033877 -274.235911)
			(xy 368.03457 -274.266914) (xy 368.034072 -274.293563) (xy 368.026129 -274.346267) (xy 368.010419 -274.397197)
			(xy 367.987293 -274.445218) (xy 367.957269 -274.489255) (xy 367.921017 -274.528326) (xy 367.879346 -274.561557)
			(xy 367.833188 -274.588206) (xy 367.783574 -274.607678) (xy 367.731612 -274.619538) (xy 367.678462 -274.623522)
			(xy 367.625312 -274.619538) (xy 367.57335 -274.607678) (xy 367.523736 -274.588206) (xy 367.477578 -274.561557)
			(xy 367.435907 -274.528326) (xy 367.399655 -274.489255) (xy 367.369631 -274.445218) (xy 367.346505 -274.397197)
			(xy 367.330795 -274.346267) (xy 367.322852 -274.293563) (xy 367.322354 -274.266914) (xy 367.323052 -274.235915)
			(xy 367.333826 -274.174857) (xy 367.354984 -274.116579) (xy 367.369852 -274.089368) (xy 367.37703 -274.075912)
			(xy 367.383803 -274.046189) (xy 367.381507 -274.01579) (xy 367.370346 -273.987422) (xy 367.351313 -273.963609)
			(xy 367.326102 -273.946469) (xy 367.296958 -273.93753) (xy 367.281714 -273.936968) (xy 367.13541 -273.936968)
			(xy 367.120186 -273.937546) (xy 367.091092 -273.946534) (xy 367.065933 -273.963686) (xy 367.046936 -273.987484)
			(xy 367.035785 -274.015819) (xy 367.033467 -274.04618) (xy 367.040188 -274.075879) (xy 367.047272 -274.089368)
			(xy 367.062168 -274.116565) (xy 367.083339 -274.174844) (xy 367.094077 -274.235911) (xy 367.09477 -274.266914)
			(xy 367.094272 -274.293563) (xy 367.086329 -274.346267) (xy 367.070619 -274.397197) (xy 367.047493 -274.445218)
			(xy 367.017469 -274.489255) (xy 366.981217 -274.528326) (xy 366.939546 -274.561557) (xy 366.893388 -274.588206)
			(xy 366.843774 -274.607678) (xy 366.791812 -274.619538) (xy 366.738662 -274.623522) (xy 366.685512 -274.619538)
			(xy 366.63355 -274.607678) (xy 366.583936 -274.588206) (xy 366.537778 -274.561557) (xy 366.496107 -274.528326)
			(xy 366.459855 -274.489255) (xy 366.429831 -274.445218) (xy 366.406705 -274.397197) (xy 366.390995 -274.346267)
			(xy 366.383052 -274.293563) (xy 366.382554 -274.266914) (xy 366.383252 -274.235915) (xy 366.394026 -274.174857)
			(xy 366.415184 -274.116579) (xy 366.430052 -274.089368) (xy 366.43723 -274.075912) (xy 366.444003 -274.046189)
			(xy 366.441707 -274.01579) (xy 366.430546 -273.987422) (xy 366.411513 -273.963609) (xy 366.386302 -273.946469)
			(xy 366.357158 -273.93753) (xy 366.341914 -273.936968) (xy 366.195864 -273.936968) (xy 366.180633 -273.937539)
			(xy 366.151525 -273.946518) (xy 366.126351 -273.963669) (xy 366.107343 -273.987472) (xy 366.096186 -274.015817)
			(xy 366.093868 -274.04619) (xy 366.100596 -274.075899) (xy 366.107726 -274.089368) (xy 366.122624 -274.116565)
			(xy 366.143797 -274.174843) (xy 366.154537 -274.235911) (xy 366.155224 -274.266914) (xy 366.154726 -274.293563)
			(xy 366.146783 -274.346267) (xy 366.131073 -274.397197) (xy 366.107947 -274.445218) (xy 366.077923 -274.489255)
			(xy 366.041671 -274.528326) (xy 366 -274.561557) (xy 365.953842 -274.588206) (xy 365.904228 -274.607678)
			(xy 365.852266 -274.619538) (xy 365.799116 -274.623522) (xy 365.745966 -274.619538) (xy 365.694004 -274.607678)
			(xy 365.64439 -274.588206) (xy 365.598232 -274.561557) (xy 365.556561 -274.528326) (xy 365.520309 -274.489255)
			(xy 365.490285 -274.445218) (xy 365.467159 -274.397197) (xy 365.451449 -274.346267) (xy 365.443506 -274.293563)
			(xy 365.443008 -274.266914) (xy 365.443705 -274.235914) (xy 365.454479 -274.174856) (xy 365.475634 -274.116576)
			(xy 365.490506 -274.089368) (xy 365.497681 -274.075909) (xy 365.504451 -274.046183) (xy 365.502153 -274.015782)
			(xy 365.490993 -273.98741) (xy 365.471963 -273.963591) (xy 365.446756 -273.946443) (xy 365.417612 -273.937491)
			(xy 365.402368 -273.936968) (xy 365.256064 -273.936968) (xy 365.240833 -273.937539) (xy 365.211725 -273.946518)
			(xy 365.186551 -273.963669) (xy 365.167543 -273.987472) (xy 365.156386 -274.015817) (xy 365.154068 -274.04619)
			(xy 365.160796 -274.075899) (xy 365.167926 -274.089368) (xy 365.182824 -274.116565) (xy 365.203997 -274.174843)
			(xy 365.214737 -274.235911) (xy 365.215424 -274.266914) (xy 365.214926 -274.293563) (xy 365.206983 -274.346267)
			(xy 365.191273 -274.397197) (xy 365.168147 -274.445218) (xy 365.138123 -274.489255) (xy 365.101871 -274.528326)
			(xy 365.0602 -274.561557) (xy 365.014042 -274.588206) (xy 364.964428 -274.607678) (xy 364.912466 -274.619538)
			(xy 364.859316 -274.623522) (xy 364.806166 -274.619538) (xy 364.754204 -274.607678) (xy 364.70459 -274.588206)
			(xy 364.658432 -274.561557) (xy 364.616761 -274.528326) (xy 364.580509 -274.489255) (xy 364.550485 -274.445218)
			(xy 364.527359 -274.397197) (xy 364.511649 -274.346267) (xy 364.503706 -274.293563) (xy 364.503208 -274.266914)
			(xy 364.503905 -274.235914) (xy 364.514679 -274.174856) (xy 364.535834 -274.116576) (xy 364.550706 -274.089368)
			(xy 364.557881 -274.075909) (xy 364.564651 -274.046183) (xy 364.562353 -274.015782) (xy 364.551193 -273.98741)
			(xy 364.532163 -273.963591) (xy 364.506956 -273.946443) (xy 364.477812 -273.937491) (xy 364.462568 -273.936968)
			(xy 364.316264 -273.936968) (xy 364.301033 -273.937539) (xy 364.271925 -273.946518) (xy 364.246751 -273.963669)
			(xy 364.227743 -273.987472) (xy 364.216586 -274.015817) (xy 364.214268 -274.04619) (xy 364.220996 -274.075899)
			(xy 364.228126 -274.089368) (xy 364.243024 -274.116565) (xy 364.264197 -274.174843) (xy 364.274937 -274.235911)
			(xy 364.275624 -274.266914) (xy 364.275126 -274.293563) (xy 364.267183 -274.346267) (xy 364.251473 -274.397197)
			(xy 364.228347 -274.445218) (xy 364.198323 -274.489255) (xy 364.162071 -274.528326) (xy 364.1204 -274.561557)
			(xy 364.074242 -274.588206) (xy 364.024628 -274.607678) (xy 363.972666 -274.619538) (xy 363.919516 -274.623522)
			(xy 363.866366 -274.619538) (xy 363.814404 -274.607678) (xy 363.76479 -274.588206) (xy 363.718632 -274.561557)
			(xy 363.676961 -274.528326) (xy 363.640709 -274.489255) (xy 363.610685 -274.445218) (xy 363.587559 -274.397197)
			(xy 363.571849 -274.346267) (xy 363.563906 -274.293563) (xy 363.563408 -274.266914) (xy 363.564105 -274.235914)
			(xy 363.574879 -274.174856) (xy 363.596034 -274.116576) (xy 363.610906 -274.089368) (xy 363.618081 -274.075909)
			(xy 363.624851 -274.046183) (xy 363.622553 -274.015782) (xy 363.611393 -273.98741) (xy 363.592363 -273.963591)
			(xy 363.567156 -273.946443) (xy 363.538012 -273.937491) (xy 363.522768 -273.936968) (xy 363.37621 -273.936968)
			(xy 363.360986 -273.937546) (xy 363.331892 -273.946534) (xy 363.306733 -273.963686) (xy 363.287736 -273.987484)
			(xy 363.276585 -274.015819) (xy 363.274267 -274.04618) (xy 363.280988 -274.075879) (xy 363.288072 -274.089368)
			(xy 363.302968 -274.116565) (xy 363.324139 -274.174844) (xy 363.334877 -274.235911) (xy 363.33557 -274.266914)
			(xy 363.335048 -274.294898) (xy 363.326291 -274.350175) (xy 363.308993 -274.403402) (xy 363.283582 -274.453268)
			(xy 363.250682 -274.498544) (xy 363.211104 -274.538116) (xy 363.165823 -274.571009) (xy 363.115954 -274.596413)
			(xy 363.062725 -274.613703) (xy 363.007446 -274.622452) (xy 362.979462 -274.623022) (xy 362.953489 -274.622555)
			(xy 362.902094 -274.615015) (xy 362.85234 -274.600086) (xy 362.805283 -274.578085) (xy 362.761924 -274.54948)
			(xy 362.723181 -274.514877) (xy 362.689879 -274.475011) (xy 362.675932 -274.453096) (xy 362.667468 -274.44031)
			(xy 362.644411 -274.420115) (xy 362.616406 -274.407658) (xy 362.585968 -274.404056) (xy 362.555829 -274.409632)
			(xy 362.528695 -274.423886) (xy 362.517436 -274.4343) (xy 362.318808 -274.632928) (xy 362.318808 -274.74926)
			(xy 362.378498 -274.74926) (xy 362.387134 -274.746212) (xy 362.416662 -274.736116) (xy 362.478108 -274.72526)
			(xy 362.509308 -274.724622) (xy 362.535955 -274.725121) (xy 362.588653 -274.733065) (xy 362.639578 -274.748774)
			(xy 362.687593 -274.771898) (xy 362.731626 -274.80192) (xy 362.770692 -274.838169) (xy 362.803919 -274.879836)
			(xy 362.830566 -274.925989) (xy 362.850036 -274.975599) (xy 362.861894 -275.027556) (xy 362.865877 -275.0807)
			(xy 362.863877 -275.107379) (xy 363.093498 -275.107379) (xy 363.093498 -275.054081) (xy 363.101441 -275.001377)
			(xy 363.117151 -274.950447) (xy 363.140277 -274.902426) (xy 363.170301 -274.858389) (xy 363.206553 -274.819318)
			(xy 363.248224 -274.786087) (xy 363.294382 -274.759438) (xy 363.343996 -274.739966) (xy 363.395958 -274.728106)
			(xy 363.449108 -274.724123) (xy 363.502258 -274.728106) (xy 363.55422 -274.739966) (xy 363.603834 -274.759438)
			(xy 363.649992 -274.786087) (xy 363.691663 -274.819318) (xy 363.727915 -274.858389) (xy 363.757939 -274.902426)
			(xy 363.781065 -274.950447) (xy 363.796775 -275.001377) (xy 363.804718 -275.054081) (xy 363.805216 -275.08073)
			(xy 363.804718 -275.107379) (xy 364.033552 -275.107379) (xy 364.033552 -275.054081) (xy 364.041495 -275.001377)
			(xy 364.057205 -274.950447) (xy 364.080331 -274.902426) (xy 364.110355 -274.858389) (xy 364.146607 -274.819318)
			(xy 364.188278 -274.786087) (xy 364.234436 -274.759438) (xy 364.28405 -274.739966) (xy 364.336012 -274.728106)
			(xy 364.389162 -274.724123) (xy 364.442312 -274.728106) (xy 364.494274 -274.739966) (xy 364.543888 -274.759438)
			(xy 364.590046 -274.786087) (xy 364.631717 -274.819318) (xy 364.667969 -274.858389) (xy 364.697993 -274.902426)
			(xy 364.721119 -274.950447) (xy 364.736829 -275.001377) (xy 364.744772 -275.054081) (xy 364.74527 -275.08073)
			(xy 364.744772 -275.107379) (xy 367.793006 -275.107379) (xy 367.793006 -275.054081) (xy 367.800949 -275.001377)
			(xy 367.816659 -274.950447) (xy 367.839785 -274.902426) (xy 367.869809 -274.858389) (xy 367.906061 -274.819318)
			(xy 367.947732 -274.786087) (xy 367.99389 -274.759438) (xy 368.043504 -274.739966) (xy 368.095466 -274.728106)
			(xy 368.148616 -274.724123) (xy 368.201766 -274.728106) (xy 368.253728 -274.739966) (xy 368.303342 -274.759438)
			(xy 368.3495 -274.786087) (xy 368.391171 -274.819318) (xy 368.427423 -274.858389) (xy 368.457447 -274.902426)
			(xy 368.480573 -274.950447) (xy 368.496283 -275.001377) (xy 368.504226 -275.054081) (xy 368.504724 -275.08073)
			(xy 368.504231 -275.107125) (xy 368.732552 -275.107125) (xy 368.732552 -275.053827) (xy 368.740495 -275.001123)
			(xy 368.756205 -274.950193) (xy 368.779331 -274.902172) (xy 368.809355 -274.858135) (xy 368.845607 -274.819064)
			(xy 368.887278 -274.785833) (xy 368.933436 -274.759184) (xy 368.98305 -274.739712) (xy 369.035012 -274.727852)
			(xy 369.088162 -274.723869) (xy 369.141312 -274.727852) (xy 369.193274 -274.739712) (xy 369.242888 -274.759184)
			(xy 369.289046 -274.785833) (xy 369.330717 -274.819064) (xy 369.366969 -274.858135) (xy 369.396993 -274.902172)
			(xy 369.420119 -274.950193) (xy 369.435829 -275.001123) (xy 369.443772 -275.053827) (xy 369.44427 -275.080476)
			(xy 369.443772 -275.107125) (xy 369.443734 -275.107379) (xy 369.672606 -275.107379) (xy 369.672606 -275.054081)
			(xy 369.680549 -275.001377) (xy 369.696259 -274.950447) (xy 369.719385 -274.902426) (xy 369.749409 -274.858389)
			(xy 369.785661 -274.819318) (xy 369.827332 -274.786087) (xy 369.87349 -274.759438) (xy 369.923104 -274.739966)
			(xy 369.975066 -274.728106) (xy 370.028216 -274.724123) (xy 370.081366 -274.728106) (xy 370.133328 -274.739966)
			(xy 370.182942 -274.759438) (xy 370.2291 -274.786087) (xy 370.270771 -274.819318) (xy 370.307023 -274.858389)
			(xy 370.337047 -274.902426) (xy 370.360173 -274.950447) (xy 370.375883 -275.001377) (xy 370.383826 -275.054081)
			(xy 370.384324 -275.08073) (xy 370.383826 -275.107379) (xy 370.612406 -275.107379) (xy 370.612406 -275.054081)
			(xy 370.620349 -275.001377) (xy 370.636059 -274.950447) (xy 370.659185 -274.902426) (xy 370.689209 -274.858389)
			(xy 370.725461 -274.819318) (xy 370.767132 -274.786087) (xy 370.81329 -274.759438) (xy 370.862904 -274.739966)
			(xy 370.914866 -274.728106) (xy 370.968016 -274.724123) (xy 371.021166 -274.728106) (xy 371.073128 -274.739966)
			(xy 371.122742 -274.759438) (xy 371.1689 -274.786087) (xy 371.210571 -274.819318) (xy 371.246823 -274.858389)
			(xy 371.276847 -274.902426) (xy 371.299973 -274.950447) (xy 371.315683 -275.001377) (xy 371.323626 -275.054081)
			(xy 371.324124 -275.08073) (xy 371.323626 -275.107379) (xy 371.552206 -275.107379) (xy 371.552206 -275.054081)
			(xy 371.560149 -275.001377) (xy 371.575859 -274.950447) (xy 371.598985 -274.902426) (xy 371.629009 -274.858389)
			(xy 371.665261 -274.819318) (xy 371.706932 -274.786087) (xy 371.75309 -274.759438) (xy 371.802704 -274.739966)
			(xy 371.854666 -274.728106) (xy 371.907816 -274.724123) (xy 371.960966 -274.728106) (xy 372.012928 -274.739966)
			(xy 372.062542 -274.759438) (xy 372.1087 -274.786087) (xy 372.150371 -274.819318) (xy 372.186623 -274.858389)
			(xy 372.216647 -274.902426) (xy 372.239773 -274.950447) (xy 372.255483 -275.001377) (xy 372.263426 -275.054081)
			(xy 372.263924 -275.08073) (xy 372.263426 -275.107379) (xy 372.492006 -275.107379) (xy 372.492006 -275.054081)
			(xy 372.499949 -275.001377) (xy 372.515659 -274.950447) (xy 372.538785 -274.902426) (xy 372.568809 -274.858389)
			(xy 372.605061 -274.819318) (xy 372.646732 -274.786087) (xy 372.69289 -274.759438) (xy 372.742504 -274.739966)
			(xy 372.794466 -274.728106) (xy 372.847616 -274.724123) (xy 372.900766 -274.728106) (xy 372.952728 -274.739966)
			(xy 373.002342 -274.759438) (xy 373.0485 -274.786087) (xy 373.090171 -274.819318) (xy 373.126423 -274.858389)
			(xy 373.156447 -274.902426) (xy 373.179573 -274.950447) (xy 373.195283 -275.001377) (xy 373.203226 -275.054081)
			(xy 373.203724 -275.08073) (xy 373.203226 -275.107379) (xy 373.431806 -275.107379) (xy 373.431806 -275.054081)
			(xy 373.439749 -275.001377) (xy 373.455459 -274.950447) (xy 373.478585 -274.902426) (xy 373.508609 -274.858389)
			(xy 373.544861 -274.819318) (xy 373.586532 -274.786087) (xy 373.63269 -274.759438) (xy 373.682304 -274.739966)
			(xy 373.734266 -274.728106) (xy 373.787416 -274.724123) (xy 373.840566 -274.728106) (xy 373.892528 -274.739966)
			(xy 373.942142 -274.759438) (xy 373.9883 -274.786087) (xy 374.029971 -274.819318) (xy 374.066223 -274.858389)
			(xy 374.096247 -274.902426) (xy 374.119373 -274.950447) (xy 374.135083 -275.001377) (xy 374.143026 -275.054081)
			(xy 374.143524 -275.08073) (xy 374.143026 -275.107379) (xy 374.371352 -275.107379) (xy 374.371352 -275.054081)
			(xy 374.379295 -275.001377) (xy 374.395005 -274.950447) (xy 374.418131 -274.902426) (xy 374.448155 -274.858389)
			(xy 374.484407 -274.819318) (xy 374.526078 -274.786087) (xy 374.572236 -274.759438) (xy 374.62185 -274.739966)
			(xy 374.673812 -274.728106) (xy 374.726962 -274.724123) (xy 374.780112 -274.728106) (xy 374.832074 -274.739966)
			(xy 374.881688 -274.759438) (xy 374.927846 -274.786087) (xy 374.969517 -274.819318) (xy 375.005769 -274.858389)
			(xy 375.035793 -274.902426) (xy 375.058919 -274.950447) (xy 375.074629 -275.001377) (xy 375.082572 -275.054081)
			(xy 375.08307 -275.08073) (xy 375.082572 -275.107379) (xy 375.311406 -275.107379) (xy 375.311406 -275.054081)
			(xy 375.319349 -275.001377) (xy 375.335059 -274.950447) (xy 375.358185 -274.902426) (xy 375.388209 -274.858389)
			(xy 375.424461 -274.819318) (xy 375.466132 -274.786087) (xy 375.51229 -274.759438) (xy 375.561904 -274.739966)
			(xy 375.613866 -274.728106) (xy 375.667016 -274.724123) (xy 375.720166 -274.728106) (xy 375.772128 -274.739966)
			(xy 375.821742 -274.759438) (xy 375.8679 -274.786087) (xy 375.909571 -274.819318) (xy 375.945823 -274.858389)
			(xy 375.975847 -274.902426) (xy 375.998973 -274.950447) (xy 376.014683 -275.001377) (xy 376.022626 -275.054081)
			(xy 376.023124 -275.08073) (xy 376.022626 -275.107379) (xy 376.251206 -275.107379) (xy 376.251206 -275.054081)
			(xy 376.259149 -275.001377) (xy 376.274859 -274.950447) (xy 376.297985 -274.902426) (xy 376.328009 -274.858389)
			(xy 376.364261 -274.819318) (xy 376.405932 -274.786087) (xy 376.45209 -274.759438) (xy 376.501704 -274.739966)
			(xy 376.553666 -274.728106) (xy 376.606816 -274.724123) (xy 376.659966 -274.728106) (xy 376.711928 -274.739966)
			(xy 376.761542 -274.759438) (xy 376.8077 -274.786087) (xy 376.849371 -274.819318) (xy 376.885623 -274.858389)
			(xy 376.915647 -274.902426) (xy 376.938773 -274.950447) (xy 376.954483 -275.001377) (xy 376.962426 -275.054081)
			(xy 376.962924 -275.08073) (xy 376.962426 -275.107379) (xy 377.191006 -275.107379) (xy 377.191006 -275.054081)
			(xy 377.198949 -275.001377) (xy 377.214659 -274.950447) (xy 377.237785 -274.902426) (xy 377.267809 -274.858389)
			(xy 377.304061 -274.819318) (xy 377.345732 -274.786087) (xy 377.39189 -274.759438) (xy 377.441504 -274.739966)
			(xy 377.493466 -274.728106) (xy 377.546616 -274.724123) (xy 377.599766 -274.728106) (xy 377.651728 -274.739966)
			(xy 377.701342 -274.759438) (xy 377.7475 -274.786087) (xy 377.789171 -274.819318) (xy 377.825423 -274.858389)
			(xy 377.855447 -274.902426) (xy 377.878573 -274.950447) (xy 377.894283 -275.001377) (xy 377.902226 -275.054081)
			(xy 377.902724 -275.08073) (xy 377.902226 -275.107379) (xy 378.130806 -275.107379) (xy 378.130806 -275.054081)
			(xy 378.138749 -275.001377) (xy 378.154459 -274.950447) (xy 378.177585 -274.902426) (xy 378.207609 -274.858389)
			(xy 378.243861 -274.819318) (xy 378.285532 -274.786087) (xy 378.33169 -274.759438) (xy 378.381304 -274.739966)
			(xy 378.433266 -274.728106) (xy 378.486416 -274.724123) (xy 378.539566 -274.728106) (xy 378.591528 -274.739966)
			(xy 378.641142 -274.759438) (xy 378.6873 -274.786087) (xy 378.728971 -274.819318) (xy 378.765223 -274.858389)
			(xy 378.795247 -274.902426) (xy 378.818373 -274.950447) (xy 378.834083 -275.001377) (xy 378.842026 -275.054081)
			(xy 378.842524 -275.08073) (xy 378.842026 -275.107379) (xy 378.834083 -275.160083) (xy 378.818373 -275.211013)
			(xy 378.795247 -275.259034) (xy 378.765223 -275.303071) (xy 378.728971 -275.342142) (xy 378.6873 -275.375373)
			(xy 378.641142 -275.402022) (xy 378.591528 -275.421494) (xy 378.539566 -275.433354) (xy 378.486416 -275.437338)
			(xy 378.433266 -275.433354) (xy 378.381304 -275.421494) (xy 378.33169 -275.402022) (xy 378.285532 -275.375373)
			(xy 378.243861 -275.342142) (xy 378.207609 -275.303071) (xy 378.177585 -275.259034) (xy 378.154459 -275.211013)
			(xy 378.138749 -275.160083) (xy 378.130806 -275.107379) (xy 377.902226 -275.107379) (xy 377.894283 -275.160083)
			(xy 377.878573 -275.211013) (xy 377.855447 -275.259034) (xy 377.825423 -275.303071) (xy 377.789171 -275.342142)
			(xy 377.7475 -275.375373) (xy 377.701342 -275.402022) (xy 377.651728 -275.421494) (xy 377.599766 -275.433354)
			(xy 377.546616 -275.437338) (xy 377.493466 -275.433354) (xy 377.441504 -275.421494) (xy 377.39189 -275.402022)
			(xy 377.345732 -275.375373) (xy 377.304061 -275.342142) (xy 377.267809 -275.303071) (xy 377.237785 -275.259034)
			(xy 377.214659 -275.211013) (xy 377.198949 -275.160083) (xy 377.191006 -275.107379) (xy 376.962426 -275.107379)
			(xy 376.954483 -275.160083) (xy 376.938773 -275.211013) (xy 376.915647 -275.259034) (xy 376.885623 -275.303071)
			(xy 376.849371 -275.342142) (xy 376.8077 -275.375373) (xy 376.761542 -275.402022) (xy 376.711928 -275.421494)
			(xy 376.659966 -275.433354) (xy 376.606816 -275.437338) (xy 376.553666 -275.433354) (xy 376.501704 -275.421494)
			(xy 376.45209 -275.402022) (xy 376.405932 -275.375373) (xy 376.364261 -275.342142) (xy 376.328009 -275.303071)
			(xy 376.297985 -275.259034) (xy 376.274859 -275.211013) (xy 376.259149 -275.160083) (xy 376.251206 -275.107379)
			(xy 376.022626 -275.107379) (xy 376.014683 -275.160083) (xy 375.998973 -275.211013) (xy 375.975847 -275.259034)
			(xy 375.945823 -275.303071) (xy 375.909571 -275.342142) (xy 375.8679 -275.375373) (xy 375.821742 -275.402022)
			(xy 375.772128 -275.421494) (xy 375.720166 -275.433354) (xy 375.667016 -275.437338) (xy 375.613866 -275.433354)
			(xy 375.561904 -275.421494) (xy 375.51229 -275.402022) (xy 375.466132 -275.375373) (xy 375.424461 -275.342142)
			(xy 375.388209 -275.303071) (xy 375.358185 -275.259034) (xy 375.335059 -275.211013) (xy 375.319349 -275.160083)
			(xy 375.311406 -275.107379) (xy 375.082572 -275.107379) (xy 375.074629 -275.160083) (xy 375.058919 -275.211013)
			(xy 375.035793 -275.259034) (xy 375.005769 -275.303071) (xy 374.969517 -275.342142) (xy 374.927846 -275.375373)
			(xy 374.881688 -275.402022) (xy 374.832074 -275.421494) (xy 374.780112 -275.433354) (xy 374.726962 -275.437338)
			(xy 374.673812 -275.433354) (xy 374.62185 -275.421494) (xy 374.572236 -275.402022) (xy 374.526078 -275.375373)
			(xy 374.484407 -275.342142) (xy 374.448155 -275.303071) (xy 374.418131 -275.259034) (xy 374.395005 -275.211013)
			(xy 374.379295 -275.160083) (xy 374.371352 -275.107379) (xy 374.143026 -275.107379) (xy 374.135083 -275.160083)
			(xy 374.119373 -275.211013) (xy 374.096247 -275.259034) (xy 374.066223 -275.303071) (xy 374.029971 -275.342142)
			(xy 373.9883 -275.375373) (xy 373.942142 -275.402022) (xy 373.892528 -275.421494) (xy 373.840566 -275.433354)
			(xy 373.787416 -275.437338) (xy 373.734266 -275.433354) (xy 373.682304 -275.421494) (xy 373.63269 -275.402022)
			(xy 373.586532 -275.375373) (xy 373.544861 -275.342142) (xy 373.508609 -275.303071) (xy 373.478585 -275.259034)
			(xy 373.455459 -275.211013) (xy 373.439749 -275.160083) (xy 373.431806 -275.107379) (xy 373.203226 -275.107379)
			(xy 373.195283 -275.160083) (xy 373.179573 -275.211013) (xy 373.156447 -275.259034) (xy 373.126423 -275.303071)
			(xy 373.090171 -275.342142) (xy 373.0485 -275.375373) (xy 373.002342 -275.402022) (xy 372.952728 -275.421494)
			(xy 372.900766 -275.433354) (xy 372.847616 -275.437338) (xy 372.794466 -275.433354) (xy 372.742504 -275.421494)
			(xy 372.69289 -275.402022) (xy 372.646732 -275.375373) (xy 372.605061 -275.342142) (xy 372.568809 -275.303071)
			(xy 372.538785 -275.259034) (xy 372.515659 -275.211013) (xy 372.499949 -275.160083) (xy 372.492006 -275.107379)
			(xy 372.263426 -275.107379) (xy 372.255483 -275.160083) (xy 372.239773 -275.211013) (xy 372.216647 -275.259034)
			(xy 372.186623 -275.303071) (xy 372.150371 -275.342142) (xy 372.1087 -275.375373) (xy 372.062542 -275.402022)
			(xy 372.012928 -275.421494) (xy 371.960966 -275.433354) (xy 371.907816 -275.437338) (xy 371.854666 -275.433354)
			(xy 371.802704 -275.421494) (xy 371.75309 -275.402022) (xy 371.706932 -275.375373) (xy 371.665261 -275.342142)
			(xy 371.629009 -275.303071) (xy 371.598985 -275.259034) (xy 371.575859 -275.211013) (xy 371.560149 -275.160083)
			(xy 371.552206 -275.107379) (xy 371.323626 -275.107379) (xy 371.315683 -275.160083) (xy 371.299973 -275.211013)
			(xy 371.276847 -275.259034) (xy 371.246823 -275.303071) (xy 371.210571 -275.342142) (xy 371.1689 -275.375373)
			(xy 371.122742 -275.402022) (xy 371.073128 -275.421494) (xy 371.021166 -275.433354) (xy 370.968016 -275.437338)
			(xy 370.914866 -275.433354) (xy 370.862904 -275.421494) (xy 370.81329 -275.402022) (xy 370.767132 -275.375373)
			(xy 370.725461 -275.342142) (xy 370.689209 -275.303071) (xy 370.659185 -275.259034) (xy 370.636059 -275.211013)
			(xy 370.620349 -275.160083) (xy 370.612406 -275.107379) (xy 370.383826 -275.107379) (xy 370.375883 -275.160083)
			(xy 370.360173 -275.211013) (xy 370.337047 -275.259034) (xy 370.307023 -275.303071) (xy 370.270771 -275.342142)
			(xy 370.2291 -275.375373) (xy 370.182942 -275.402022) (xy 370.133328 -275.421494) (xy 370.081366 -275.433354)
			(xy 370.028216 -275.437338) (xy 369.975066 -275.433354) (xy 369.923104 -275.421494) (xy 369.87349 -275.402022)
			(xy 369.827332 -275.375373) (xy 369.785661 -275.342142) (xy 369.749409 -275.303071) (xy 369.719385 -275.259034)
			(xy 369.696259 -275.211013) (xy 369.680549 -275.160083) (xy 369.672606 -275.107379) (xy 369.443734 -275.107379)
			(xy 369.435829 -275.159829) (xy 369.420119 -275.210759) (xy 369.396993 -275.25878) (xy 369.366969 -275.302817)
			(xy 369.330717 -275.341888) (xy 369.289046 -275.375119) (xy 369.242888 -275.401768) (xy 369.193274 -275.42124)
			(xy 369.141312 -275.4331) (xy 369.088162 -275.437084) (xy 369.035012 -275.4331) (xy 368.98305 -275.42124)
			(xy 368.933436 -275.401768) (xy 368.887278 -275.375119) (xy 368.845607 -275.341888) (xy 368.809355 -275.302817)
			(xy 368.779331 -275.25878) (xy 368.756205 -275.210759) (xy 368.740495 -275.159829) (xy 368.732552 -275.107125)
			(xy 368.504231 -275.107125) (xy 368.504226 -275.107379) (xy 368.496283 -275.160083) (xy 368.480573 -275.211013)
			(xy 368.457447 -275.259034) (xy 368.427423 -275.303071) (xy 368.391171 -275.342142) (xy 368.3495 -275.375373)
			(xy 368.303342 -275.402022) (xy 368.253728 -275.421494) (xy 368.201766 -275.433354) (xy 368.148616 -275.437338)
			(xy 368.095466 -275.433354) (xy 368.043504 -275.421494) (xy 367.99389 -275.402022) (xy 367.947732 -275.375373)
			(xy 367.906061 -275.342142) (xy 367.869809 -275.303071) (xy 367.839785 -275.259034) (xy 367.816659 -275.211013)
			(xy 367.800949 -275.160083) (xy 367.793006 -275.107379) (xy 364.744772 -275.107379) (xy 364.736829 -275.160083)
			(xy 364.721119 -275.211013) (xy 364.697993 -275.259034) (xy 364.667969 -275.303071) (xy 364.631717 -275.342142)
			(xy 364.590046 -275.375373) (xy 364.543888 -275.402022) (xy 364.494274 -275.421494) (xy 364.442312 -275.433354)
			(xy 364.389162 -275.437338) (xy 364.336012 -275.433354) (xy 364.28405 -275.421494) (xy 364.234436 -275.402022)
			(xy 364.188278 -275.375373) (xy 364.146607 -275.342142) (xy 364.110355 -275.303071) (xy 364.080331 -275.259034)
			(xy 364.057205 -275.211013) (xy 364.041495 -275.160083) (xy 364.033552 -275.107379) (xy 363.804718 -275.107379)
			(xy 363.796775 -275.160083) (xy 363.781065 -275.211013) (xy 363.757939 -275.259034) (xy 363.727915 -275.303071)
			(xy 363.691663 -275.342142) (xy 363.649992 -275.375373) (xy 363.603834 -275.402022) (xy 363.55422 -275.421494)
			(xy 363.502258 -275.433354) (xy 363.449108 -275.437338) (xy 363.395958 -275.433354) (xy 363.343996 -275.421494)
			(xy 363.294382 -275.402022) (xy 363.248224 -275.375373) (xy 363.206553 -275.342142) (xy 363.170301 -275.303071)
			(xy 363.140277 -275.259034) (xy 363.117151 -275.211013) (xy 363.101441 -275.160083) (xy 363.093498 -275.107379)
			(xy 362.863877 -275.107379) (xy 362.861894 -275.133844) (xy 362.850036 -275.185801) (xy 362.830566 -275.235411)
			(xy 362.803919 -275.281564) (xy 362.770692 -275.323231) (xy 362.731626 -275.35948) (xy 362.687593 -275.389502)
			(xy 362.639578 -275.412626) (xy 362.588653 -275.428335) (xy 362.535955 -275.436279) (xy 362.509308 -275.436838)
			(xy 362.491921 -275.436601) (xy 362.457316 -275.433161) (xy 362.44022 -275.42998) (xy 362.425394 -275.427577)
			(xy 362.395521 -275.430529) (xy 362.367791 -275.442028) (xy 362.344597 -275.461086) (xy 362.327937 -275.486058)
			(xy 362.319248 -275.514792) (xy 362.318808 -275.529802) (xy 362.318808 -275.673312) (xy 362.336912 -275.697111)
			(xy 362.365738 -275.749495) (xy 362.385423 -275.805953) (xy 362.395414 -275.864904) (xy 362.396024 -275.8948)
			(xy 362.395518 -275.921263) (xy 362.39549 -275.921449) (xy 363.563652 -275.921449) (xy 363.563652 -275.868151)
			(xy 363.571595 -275.815447) (xy 363.587305 -275.764517) (xy 363.610431 -275.716496) (xy 363.640455 -275.672459)
			(xy 363.676707 -275.633388) (xy 363.718378 -275.600157) (xy 363.764536 -275.573508) (xy 363.81415 -275.554036)
			(xy 363.866112 -275.542176) (xy 363.919262 -275.538193) (xy 363.972412 -275.542176) (xy 364.024374 -275.554036)
			(xy 364.073988 -275.573508) (xy 364.120146 -275.600157) (xy 364.161817 -275.633388) (xy 364.198069 -275.672459)
			(xy 364.228093 -275.716496) (xy 364.251219 -275.764517) (xy 364.266929 -275.815447) (xy 364.274872 -275.868151)
			(xy 364.27537 -275.8948) (xy 364.274877 -275.921195) (xy 364.503706 -275.921195) (xy 364.503706 -275.867897)
			(xy 364.511649 -275.815193) (xy 364.527359 -275.764263) (xy 364.550485 -275.716242) (xy 364.580509 -275.672205)
			(xy 364.616761 -275.633134) (xy 364.658432 -275.599903) (xy 364.70459 -275.573254) (xy 364.754204 -275.553782)
			(xy 364.806166 -275.541922) (xy 364.859316 -275.537939) (xy 364.912466 -275.541922) (xy 364.964428 -275.553782)
			(xy 365.014042 -275.573254) (xy 365.0602 -275.599903) (xy 365.101871 -275.633134) (xy 365.138123 -275.672205)
			(xy 365.168147 -275.716242) (xy 365.191273 -275.764263) (xy 365.206983 -275.815193) (xy 365.214926 -275.867897)
			(xy 365.215424 -275.894546) (xy 365.214926 -275.921195) (xy 365.214888 -275.921449) (xy 365.443252 -275.921449)
			(xy 365.443252 -275.868151) (xy 365.451195 -275.815447) (xy 365.466905 -275.764517) (xy 365.490031 -275.716496)
			(xy 365.520055 -275.672459) (xy 365.556307 -275.633388) (xy 365.597978 -275.600157) (xy 365.644136 -275.573508)
			(xy 365.69375 -275.554036) (xy 365.745712 -275.542176) (xy 365.798862 -275.538193) (xy 365.852012 -275.542176)
			(xy 365.903974 -275.554036) (xy 365.953588 -275.573508) (xy 365.999746 -275.600157) (xy 366.041417 -275.633388)
			(xy 366.077669 -275.672459) (xy 366.107693 -275.716496) (xy 366.130819 -275.764517) (xy 366.146529 -275.815447)
			(xy 366.154472 -275.868151) (xy 366.15497 -275.8948) (xy 366.154472 -275.921449) (xy 366.383306 -275.921449)
			(xy 366.383306 -275.868151) (xy 366.391249 -275.815447) (xy 366.406959 -275.764517) (xy 366.430085 -275.716496)
			(xy 366.460109 -275.672459) (xy 366.496361 -275.633388) (xy 366.538032 -275.600157) (xy 366.58419 -275.573508)
			(xy 366.633804 -275.554036) (xy 366.685766 -275.542176) (xy 366.738916 -275.538193) (xy 366.792066 -275.542176)
			(xy 366.844028 -275.554036) (xy 366.893642 -275.573508) (xy 366.9398 -275.600157) (xy 366.981471 -275.633388)
			(xy 367.017723 -275.672459) (xy 367.047747 -275.716496) (xy 367.070873 -275.764517) (xy 367.086583 -275.815447)
			(xy 367.094526 -275.868151) (xy 367.095024 -275.8948) (xy 367.094531 -275.921195) (xy 367.323106 -275.921195)
			(xy 367.323106 -275.867897) (xy 367.331049 -275.815193) (xy 367.346759 -275.764263) (xy 367.369885 -275.716242)
			(xy 367.399909 -275.672205) (xy 367.436161 -275.633134) (xy 367.477832 -275.599903) (xy 367.52399 -275.573254)
			(xy 367.573604 -275.553782) (xy 367.625566 -275.541922) (xy 367.678716 -275.537939) (xy 367.731866 -275.541922)
			(xy 367.783828 -275.553782) (xy 367.833442 -275.573254) (xy 367.8796 -275.599903) (xy 367.921271 -275.633134)
			(xy 367.957523 -275.672205) (xy 367.987547 -275.716242) (xy 368.010673 -275.764263) (xy 368.026383 -275.815193)
			(xy 368.034326 -275.867897) (xy 368.034824 -275.894546) (xy 368.034326 -275.921195) (xy 368.262906 -275.921195)
			(xy 368.262906 -275.867897) (xy 368.270849 -275.815193) (xy 368.286559 -275.764263) (xy 368.309685 -275.716242)
			(xy 368.339709 -275.672205) (xy 368.375961 -275.633134) (xy 368.417632 -275.599903) (xy 368.46379 -275.573254)
			(xy 368.513404 -275.553782) (xy 368.565366 -275.541922) (xy 368.618516 -275.537939) (xy 368.671666 -275.541922)
			(xy 368.723628 -275.553782) (xy 368.773242 -275.573254) (xy 368.8194 -275.599903) (xy 368.861071 -275.633134)
			(xy 368.897323 -275.672205) (xy 368.927347 -275.716242) (xy 368.950473 -275.764263) (xy 368.966183 -275.815193)
			(xy 368.974126 -275.867897) (xy 368.974624 -275.894546) (xy 368.974126 -275.921195) (xy 369.202706 -275.921195)
			(xy 369.202706 -275.867897) (xy 369.210649 -275.815193) (xy 369.226359 -275.764263) (xy 369.249485 -275.716242)
			(xy 369.279509 -275.672205) (xy 369.315761 -275.633134) (xy 369.357432 -275.599903) (xy 369.40359 -275.573254)
			(xy 369.453204 -275.553782) (xy 369.505166 -275.541922) (xy 369.558316 -275.537939) (xy 369.611466 -275.541922)
			(xy 369.663428 -275.553782) (xy 369.713042 -275.573254) (xy 369.7592 -275.599903) (xy 369.800871 -275.633134)
			(xy 369.837123 -275.672205) (xy 369.867147 -275.716242) (xy 369.890273 -275.764263) (xy 369.905983 -275.815193)
			(xy 369.913926 -275.867897) (xy 369.914424 -275.894546) (xy 369.913926 -275.921195) (xy 369.913888 -275.921449)
			(xy 370.142506 -275.921449) (xy 370.142506 -275.868151) (xy 370.150449 -275.815447) (xy 370.166159 -275.764517)
			(xy 370.189285 -275.716496) (xy 370.219309 -275.672459) (xy 370.255561 -275.633388) (xy 370.297232 -275.600157)
			(xy 370.34339 -275.573508) (xy 370.393004 -275.554036) (xy 370.444966 -275.542176) (xy 370.498116 -275.538193)
			(xy 370.551266 -275.542176) (xy 370.603228 -275.554036) (xy 370.652842 -275.573508) (xy 370.699 -275.600157)
			(xy 370.740671 -275.633388) (xy 370.776923 -275.672459) (xy 370.806947 -275.716496) (xy 370.830073 -275.764517)
			(xy 370.845783 -275.815447) (xy 370.853726 -275.868151) (xy 370.854224 -275.8948) (xy 370.853726 -275.921449)
			(xy 371.082052 -275.921449) (xy 371.082052 -275.868151) (xy 371.089995 -275.815447) (xy 371.105705 -275.764517)
			(xy 371.128831 -275.716496) (xy 371.158855 -275.672459) (xy 371.195107 -275.633388) (xy 371.236778 -275.600157)
			(xy 371.282936 -275.573508) (xy 371.33255 -275.554036) (xy 371.384512 -275.542176) (xy 371.437662 -275.538193)
			(xy 371.490812 -275.542176) (xy 371.542774 -275.554036) (xy 371.592388 -275.573508) (xy 371.638546 -275.600157)
			(xy 371.680217 -275.633388) (xy 371.716469 -275.672459) (xy 371.746493 -275.716496) (xy 371.769619 -275.764517)
			(xy 371.785329 -275.815447) (xy 371.793272 -275.868151) (xy 371.79377 -275.8948) (xy 371.793272 -275.921449)
			(xy 372.021852 -275.921449) (xy 372.021852 -275.868151) (xy 372.029795 -275.815447) (xy 372.045505 -275.764517)
			(xy 372.068631 -275.716496) (xy 372.098655 -275.672459) (xy 372.134907 -275.633388) (xy 372.176578 -275.600157)
			(xy 372.222736 -275.573508) (xy 372.27235 -275.554036) (xy 372.324312 -275.542176) (xy 372.377462 -275.538193)
			(xy 372.430612 -275.542176) (xy 372.482574 -275.554036) (xy 372.532188 -275.573508) (xy 372.578346 -275.600157)
			(xy 372.620017 -275.633388) (xy 372.656269 -275.672459) (xy 372.686293 -275.716496) (xy 372.709419 -275.764517)
			(xy 372.725129 -275.815447) (xy 372.733072 -275.868151) (xy 372.73357 -275.8948) (xy 372.733072 -275.921449)
			(xy 372.961652 -275.921449) (xy 372.961652 -275.868151) (xy 372.969595 -275.815447) (xy 372.985305 -275.764517)
			(xy 373.008431 -275.716496) (xy 373.038455 -275.672459) (xy 373.074707 -275.633388) (xy 373.116378 -275.600157)
			(xy 373.162536 -275.573508) (xy 373.21215 -275.554036) (xy 373.264112 -275.542176) (xy 373.317262 -275.538193)
			(xy 373.370412 -275.542176) (xy 373.422374 -275.554036) (xy 373.471988 -275.573508) (xy 373.518146 -275.600157)
			(xy 373.559817 -275.633388) (xy 373.596069 -275.672459) (xy 373.626093 -275.716496) (xy 373.649219 -275.764517)
			(xy 373.664929 -275.815447) (xy 373.672872 -275.868151) (xy 373.67337 -275.8948) (xy 373.672872 -275.921449)
			(xy 373.901452 -275.921449) (xy 373.901452 -275.868151) (xy 373.909395 -275.815447) (xy 373.925105 -275.764517)
			(xy 373.948231 -275.716496) (xy 373.978255 -275.672459) (xy 374.014507 -275.633388) (xy 374.056178 -275.600157)
			(xy 374.102336 -275.573508) (xy 374.15195 -275.554036) (xy 374.203912 -275.542176) (xy 374.257062 -275.538193)
			(xy 374.310212 -275.542176) (xy 374.362174 -275.554036) (xy 374.411788 -275.573508) (xy 374.457946 -275.600157)
			(xy 374.499617 -275.633388) (xy 374.535869 -275.672459) (xy 374.565893 -275.716496) (xy 374.589019 -275.764517)
			(xy 374.604729 -275.815447) (xy 374.612672 -275.868151) (xy 374.61317 -275.8948) (xy 374.612672 -275.921449)
			(xy 374.841252 -275.921449) (xy 374.841252 -275.868151) (xy 374.849195 -275.815447) (xy 374.864905 -275.764517)
			(xy 374.888031 -275.716496) (xy 374.918055 -275.672459) (xy 374.954307 -275.633388) (xy 374.995978 -275.600157)
			(xy 375.042136 -275.573508) (xy 375.09175 -275.554036) (xy 375.143712 -275.542176) (xy 375.196862 -275.538193)
			(xy 375.250012 -275.542176) (xy 375.301974 -275.554036) (xy 375.351588 -275.573508) (xy 375.397746 -275.600157)
			(xy 375.439417 -275.633388) (xy 375.475669 -275.672459) (xy 375.505693 -275.716496) (xy 375.528819 -275.764517)
			(xy 375.544529 -275.815447) (xy 375.552472 -275.868151) (xy 375.55297 -275.8948) (xy 375.552472 -275.921449)
			(xy 375.781052 -275.921449) (xy 375.781052 -275.868151) (xy 375.788995 -275.815447) (xy 375.804705 -275.764517)
			(xy 375.827831 -275.716496) (xy 375.857855 -275.672459) (xy 375.894107 -275.633388) (xy 375.935778 -275.600157)
			(xy 375.981936 -275.573508) (xy 376.03155 -275.554036) (xy 376.083512 -275.542176) (xy 376.136662 -275.538193)
			(xy 376.189812 -275.542176) (xy 376.241774 -275.554036) (xy 376.291388 -275.573508) (xy 376.337546 -275.600157)
			(xy 376.379217 -275.633388) (xy 376.415469 -275.672459) (xy 376.445493 -275.716496) (xy 376.468619 -275.764517)
			(xy 376.484329 -275.815447) (xy 376.492272 -275.868151) (xy 376.49277 -275.8948) (xy 376.492272 -275.921449)
			(xy 376.721106 -275.921449) (xy 376.721106 -275.868151) (xy 376.729049 -275.815447) (xy 376.744759 -275.764517)
			(xy 376.767885 -275.716496) (xy 376.797909 -275.672459) (xy 376.834161 -275.633388) (xy 376.875832 -275.600157)
			(xy 376.92199 -275.573508) (xy 376.971604 -275.554036) (xy 377.023566 -275.542176) (xy 377.076716 -275.538193)
			(xy 377.129866 -275.542176) (xy 377.181828 -275.554036) (xy 377.231442 -275.573508) (xy 377.2776 -275.600157)
			(xy 377.319271 -275.633388) (xy 377.355523 -275.672459) (xy 377.385547 -275.716496) (xy 377.408673 -275.764517)
			(xy 377.424383 -275.815447) (xy 377.432326 -275.868151) (xy 377.432824 -275.8948) (xy 377.432326 -275.921449)
			(xy 377.660652 -275.921449) (xy 377.660652 -275.868151) (xy 377.668595 -275.815447) (xy 377.684305 -275.764517)
			(xy 377.707431 -275.716496) (xy 377.737455 -275.672459) (xy 377.773707 -275.633388) (xy 377.815378 -275.600157)
			(xy 377.861536 -275.573508) (xy 377.91115 -275.554036) (xy 377.963112 -275.542176) (xy 378.016262 -275.538193)
			(xy 378.069412 -275.542176) (xy 378.121374 -275.554036) (xy 378.170988 -275.573508) (xy 378.217146 -275.600157)
			(xy 378.258817 -275.633388) (xy 378.295069 -275.672459) (xy 378.325093 -275.716496) (xy 378.348219 -275.764517)
			(xy 378.363929 -275.815447) (xy 378.371872 -275.868151) (xy 378.37237 -275.8948) (xy 378.371872 -275.921449)
			(xy 378.600452 -275.921449) (xy 378.600452 -275.868151) (xy 378.608395 -275.815447) (xy 378.624105 -275.764517)
			(xy 378.647231 -275.716496) (xy 378.677255 -275.672459) (xy 378.713507 -275.633388) (xy 378.755178 -275.600157)
			(xy 378.801336 -275.573508) (xy 378.85095 -275.554036) (xy 378.902912 -275.542176) (xy 378.956062 -275.538193)
			(xy 379.009212 -275.542176) (xy 379.061174 -275.554036) (xy 379.110788 -275.573508) (xy 379.156946 -275.600157)
			(xy 379.198617 -275.633388) (xy 379.234869 -275.672459) (xy 379.264893 -275.716496) (xy 379.288019 -275.764517)
			(xy 379.303729 -275.815447) (xy 379.311672 -275.868151) (xy 379.31217 -275.8948) (xy 379.311672 -275.921449)
			(xy 379.303729 -275.974153) (xy 379.288019 -276.025083) (xy 379.264893 -276.073104) (xy 379.234869 -276.117141)
			(xy 379.198617 -276.156212) (xy 379.156946 -276.189443) (xy 379.110788 -276.216092) (xy 379.061174 -276.235564)
			(xy 379.009212 -276.247424) (xy 378.956062 -276.251408) (xy 378.902912 -276.247424) (xy 378.85095 -276.235564)
			(xy 378.801336 -276.216092) (xy 378.755178 -276.189443) (xy 378.713507 -276.156212) (xy 378.677255 -276.117141)
			(xy 378.647231 -276.073104) (xy 378.624105 -276.025083) (xy 378.608395 -275.974153) (xy 378.600452 -275.921449)
			(xy 378.371872 -275.921449) (xy 378.363929 -275.974153) (xy 378.348219 -276.025083) (xy 378.325093 -276.073104)
			(xy 378.295069 -276.117141) (xy 378.258817 -276.156212) (xy 378.217146 -276.189443) (xy 378.170988 -276.216092)
			(xy 378.121374 -276.235564) (xy 378.069412 -276.247424) (xy 378.016262 -276.251408) (xy 377.963112 -276.247424)
			(xy 377.91115 -276.235564) (xy 377.861536 -276.216092) (xy 377.815378 -276.189443) (xy 377.773707 -276.156212)
			(xy 377.737455 -276.117141) (xy 377.707431 -276.073104) (xy 377.684305 -276.025083) (xy 377.668595 -275.974153)
			(xy 377.660652 -275.921449) (xy 377.432326 -275.921449) (xy 377.424383 -275.974153) (xy 377.408673 -276.025083)
			(xy 377.385547 -276.073104) (xy 377.355523 -276.117141) (xy 377.319271 -276.156212) (xy 377.2776 -276.189443)
			(xy 377.231442 -276.216092) (xy 377.181828 -276.235564) (xy 377.129866 -276.247424) (xy 377.076716 -276.251408)
			(xy 377.023566 -276.247424) (xy 376.971604 -276.235564) (xy 376.92199 -276.216092) (xy 376.875832 -276.189443)
			(xy 376.834161 -276.156212) (xy 376.797909 -276.117141) (xy 376.767885 -276.073104) (xy 376.744759 -276.025083)
			(xy 376.729049 -275.974153) (xy 376.721106 -275.921449) (xy 376.492272 -275.921449) (xy 376.484329 -275.974153)
			(xy 376.468619 -276.025083) (xy 376.445493 -276.073104) (xy 376.415469 -276.117141) (xy 376.379217 -276.156212)
			(xy 376.337546 -276.189443) (xy 376.291388 -276.216092) (xy 376.241774 -276.235564) (xy 376.189812 -276.247424)
			(xy 376.136662 -276.251408) (xy 376.083512 -276.247424) (xy 376.03155 -276.235564) (xy 375.981936 -276.216092)
			(xy 375.935778 -276.189443) (xy 375.894107 -276.156212) (xy 375.857855 -276.117141) (xy 375.827831 -276.073104)
			(xy 375.804705 -276.025083) (xy 375.788995 -275.974153) (xy 375.781052 -275.921449) (xy 375.552472 -275.921449)
			(xy 375.544529 -275.974153) (xy 375.528819 -276.025083) (xy 375.505693 -276.073104) (xy 375.475669 -276.117141)
			(xy 375.439417 -276.156212) (xy 375.397746 -276.189443) (xy 375.351588 -276.216092) (xy 375.301974 -276.235564)
			(xy 375.250012 -276.247424) (xy 375.196862 -276.251408) (xy 375.143712 -276.247424) (xy 375.09175 -276.235564)
			(xy 375.042136 -276.216092) (xy 374.995978 -276.189443) (xy 374.954307 -276.156212) (xy 374.918055 -276.117141)
			(xy 374.888031 -276.073104) (xy 374.864905 -276.025083) (xy 374.849195 -275.974153) (xy 374.841252 -275.921449)
			(xy 374.612672 -275.921449) (xy 374.604729 -275.974153) (xy 374.589019 -276.025083) (xy 374.565893 -276.073104)
			(xy 374.535869 -276.117141) (xy 374.499617 -276.156212) (xy 374.457946 -276.189443) (xy 374.411788 -276.216092)
			(xy 374.362174 -276.235564) (xy 374.310212 -276.247424) (xy 374.257062 -276.251408) (xy 374.203912 -276.247424)
			(xy 374.15195 -276.235564) (xy 374.102336 -276.216092) (xy 374.056178 -276.189443) (xy 374.014507 -276.156212)
			(xy 373.978255 -276.117141) (xy 373.948231 -276.073104) (xy 373.925105 -276.025083) (xy 373.909395 -275.974153)
			(xy 373.901452 -275.921449) (xy 373.672872 -275.921449) (xy 373.664929 -275.974153) (xy 373.649219 -276.025083)
			(xy 373.626093 -276.073104) (xy 373.596069 -276.117141) (xy 373.559817 -276.156212) (xy 373.518146 -276.189443)
			(xy 373.471988 -276.216092) (xy 373.422374 -276.235564) (xy 373.370412 -276.247424) (xy 373.317262 -276.251408)
			(xy 373.264112 -276.247424) (xy 373.21215 -276.235564) (xy 373.162536 -276.216092) (xy 373.116378 -276.189443)
			(xy 373.074707 -276.156212) (xy 373.038455 -276.117141) (xy 373.008431 -276.073104) (xy 372.985305 -276.025083)
			(xy 372.969595 -275.974153) (xy 372.961652 -275.921449) (xy 372.733072 -275.921449) (xy 372.725129 -275.974153)
			(xy 372.709419 -276.025083) (xy 372.686293 -276.073104) (xy 372.656269 -276.117141) (xy 372.620017 -276.156212)
			(xy 372.578346 -276.189443) (xy 372.532188 -276.216092) (xy 372.482574 -276.235564) (xy 372.430612 -276.247424)
			(xy 372.377462 -276.251408) (xy 372.324312 -276.247424) (xy 372.27235 -276.235564) (xy 372.222736 -276.216092)
			(xy 372.176578 -276.189443) (xy 372.134907 -276.156212) (xy 372.098655 -276.117141) (xy 372.068631 -276.073104)
			(xy 372.045505 -276.025083) (xy 372.029795 -275.974153) (xy 372.021852 -275.921449) (xy 371.793272 -275.921449)
			(xy 371.785329 -275.974153) (xy 371.769619 -276.025083) (xy 371.746493 -276.073104) (xy 371.716469 -276.117141)
			(xy 371.680217 -276.156212) (xy 371.638546 -276.189443) (xy 371.592388 -276.216092) (xy 371.542774 -276.235564)
			(xy 371.490812 -276.247424) (xy 371.437662 -276.251408) (xy 371.384512 -276.247424) (xy 371.33255 -276.235564)
			(xy 371.282936 -276.216092) (xy 371.236778 -276.189443) (xy 371.195107 -276.156212) (xy 371.158855 -276.117141)
			(xy 371.128831 -276.073104) (xy 371.105705 -276.025083) (xy 371.089995 -275.974153) (xy 371.082052 -275.921449)
			(xy 370.853726 -275.921449) (xy 370.845783 -275.974153) (xy 370.830073 -276.025083) (xy 370.806947 -276.073104)
			(xy 370.776923 -276.117141) (xy 370.740671 -276.156212) (xy 370.699 -276.189443) (xy 370.652842 -276.216092)
			(xy 370.603228 -276.235564) (xy 370.551266 -276.247424) (xy 370.498116 -276.251408) (xy 370.444966 -276.247424)
			(xy 370.393004 -276.235564) (xy 370.34339 -276.216092) (xy 370.297232 -276.189443) (xy 370.255561 -276.156212)
			(xy 370.219309 -276.117141) (xy 370.189285 -276.073104) (xy 370.166159 -276.025083) (xy 370.150449 -275.974153)
			(xy 370.142506 -275.921449) (xy 369.913888 -275.921449) (xy 369.905983 -275.973899) (xy 369.890273 -276.024829)
			(xy 369.867147 -276.07285) (xy 369.837123 -276.116887) (xy 369.800871 -276.155958) (xy 369.7592 -276.189189)
			(xy 369.713042 -276.215838) (xy 369.663428 -276.23531) (xy 369.611466 -276.24717) (xy 369.558316 -276.251154)
			(xy 369.505166 -276.24717) (xy 369.453204 -276.23531) (xy 369.40359 -276.215838) (xy 369.357432 -276.189189)
			(xy 369.315761 -276.155958) (xy 369.279509 -276.116887) (xy 369.249485 -276.07285) (xy 369.226359 -276.024829)
			(xy 369.210649 -275.973899) (xy 369.202706 -275.921195) (xy 368.974126 -275.921195) (xy 368.966183 -275.973899)
			(xy 368.950473 -276.024829) (xy 368.927347 -276.07285) (xy 368.897323 -276.116887) (xy 368.861071 -276.155958)
			(xy 368.8194 -276.189189) (xy 368.773242 -276.215838) (xy 368.723628 -276.23531) (xy 368.671666 -276.24717)
			(xy 368.618516 -276.251154) (xy 368.565366 -276.24717) (xy 368.513404 -276.23531) (xy 368.46379 -276.215838)
			(xy 368.417632 -276.189189) (xy 368.375961 -276.155958) (xy 368.339709 -276.116887) (xy 368.309685 -276.07285)
			(xy 368.286559 -276.024829) (xy 368.270849 -275.973899) (xy 368.262906 -275.921195) (xy 368.034326 -275.921195)
			(xy 368.026383 -275.973899) (xy 368.010673 -276.024829) (xy 367.987547 -276.07285) (xy 367.957523 -276.116887)
			(xy 367.921271 -276.155958) (xy 367.8796 -276.189189) (xy 367.833442 -276.215838) (xy 367.783828 -276.23531)
			(xy 367.731866 -276.24717) (xy 367.678716 -276.251154) (xy 367.625566 -276.24717) (xy 367.573604 -276.23531)
			(xy 367.52399 -276.215838) (xy 367.477832 -276.189189) (xy 367.436161 -276.155958) (xy 367.399909 -276.116887)
			(xy 367.369885 -276.07285) (xy 367.346759 -276.024829) (xy 367.331049 -275.973899) (xy 367.323106 -275.921195)
			(xy 367.094531 -275.921195) (xy 367.094526 -275.921449) (xy 367.086583 -275.974153) (xy 367.070873 -276.025083)
			(xy 367.047747 -276.073104) (xy 367.017723 -276.117141) (xy 366.981471 -276.156212) (xy 366.9398 -276.189443)
			(xy 366.893642 -276.216092) (xy 366.844028 -276.235564) (xy 366.792066 -276.247424) (xy 366.738916 -276.251408)
			(xy 366.685766 -276.247424) (xy 366.633804 -276.235564) (xy 366.58419 -276.216092) (xy 366.538032 -276.189443)
			(xy 366.496361 -276.156212) (xy 366.460109 -276.117141) (xy 366.430085 -276.073104) (xy 366.406959 -276.025083)
			(xy 366.391249 -275.974153) (xy 366.383306 -275.921449) (xy 366.154472 -275.921449) (xy 366.146529 -275.974153)
			(xy 366.130819 -276.025083) (xy 366.107693 -276.073104) (xy 366.077669 -276.117141) (xy 366.041417 -276.156212)
			(xy 365.999746 -276.189443) (xy 365.953588 -276.216092) (xy 365.903974 -276.235564) (xy 365.852012 -276.247424)
			(xy 365.798862 -276.251408) (xy 365.745712 -276.247424) (xy 365.69375 -276.235564) (xy 365.644136 -276.216092)
			(xy 365.597978 -276.189443) (xy 365.556307 -276.156212) (xy 365.520055 -276.117141) (xy 365.490031 -276.073104)
			(xy 365.466905 -276.025083) (xy 365.451195 -275.974153) (xy 365.443252 -275.921449) (xy 365.214888 -275.921449)
			(xy 365.206983 -275.973899) (xy 365.191273 -276.024829) (xy 365.168147 -276.07285) (xy 365.138123 -276.116887)
			(xy 365.101871 -276.155958) (xy 365.0602 -276.189189) (xy 365.014042 -276.215838) (xy 364.964428 -276.23531)
			(xy 364.912466 -276.24717) (xy 364.859316 -276.251154) (xy 364.806166 -276.24717) (xy 364.754204 -276.23531)
			(xy 364.70459 -276.215838) (xy 364.658432 -276.189189) (xy 364.616761 -276.155958) (xy 364.580509 -276.116887)
			(xy 364.550485 -276.07285) (xy 364.527359 -276.024829) (xy 364.511649 -275.973899) (xy 364.503706 -275.921195)
			(xy 364.274877 -275.921195) (xy 364.274872 -275.921449) (xy 364.266929 -275.974153) (xy 364.251219 -276.025083)
			(xy 364.228093 -276.073104) (xy 364.198069 -276.117141) (xy 364.161817 -276.156212) (xy 364.120146 -276.189443)
			(xy 364.073988 -276.216092) (xy 364.024374 -276.235564) (xy 363.972412 -276.247424) (xy 363.919262 -276.251408)
			(xy 363.866112 -276.247424) (xy 363.81415 -276.235564) (xy 363.764536 -276.216092) (xy 363.718378 -276.189443)
			(xy 363.676707 -276.156212) (xy 363.640455 -276.117141) (xy 363.610431 -276.073104) (xy 363.587305 -276.025083)
			(xy 363.571595 -275.974153) (xy 363.563652 -275.921449) (xy 362.39549 -275.921449) (xy 362.38764 -275.973601)
			(xy 362.372103 -276.024197) (xy 362.349249 -276.071936) (xy 362.319581 -276.115767) (xy 362.302044 -276.135592)
			(xy 362.518452 -276.352) (xy 362.537248 -276.353524) (xy 362.565169 -276.356208) (xy 362.619722 -276.369244)
			(xy 362.671557 -276.390669) (xy 362.719393 -276.419955) (xy 362.762048 -276.456377) (xy 362.798466 -276.499035)
			(xy 362.827747 -276.546874) (xy 362.849167 -276.598711) (xy 362.862197 -276.653265) (xy 362.864908 -276.681184)
			(xy 362.866432 -276.69998) (xy 362.920534 -276.754082) (xy 362.931216 -276.764097) (xy 362.956923 -276.778089)
			(xy 362.985544 -276.784218) (xy 363.014727 -276.781978) (xy 363.042077 -276.771555) (xy 363.065348 -276.753804)
			(xy 363.082631 -276.730182) (xy 363.092505 -276.702629) (xy 363.093762 -276.688042) (xy 363.095793 -276.661144)
			(xy 363.106951 -276.608371) (xy 363.125943 -276.557885) (xy 363.152333 -276.510842) (xy 363.185517 -276.468318)
			(xy 363.224737 -276.431287) (xy 363.269094 -276.400596) (xy 363.317574 -276.376948) (xy 363.369066 -276.360883)
			(xy 363.422392 -276.35277) (xy 363.449362 -276.352254) (xy 363.477348 -276.3528) (xy 363.532632 -276.36155)
			(xy 363.585867 -276.378841) (xy 363.635741 -276.404246) (xy 363.681027 -276.437141) (xy 363.720609 -276.476715)
			(xy 363.753514 -276.521994) (xy 363.77893 -276.571863) (xy 363.796232 -276.625094) (xy 363.804994 -276.680376)
			(xy 363.80547 -276.708362) (xy 363.804975 -276.735011) (xy 364.033552 -276.735011) (xy 364.033552 -276.681713)
			(xy 364.041495 -276.629009) (xy 364.057205 -276.578079) (xy 364.080331 -276.530058) (xy 364.110355 -276.486021)
			(xy 364.146607 -276.44695) (xy 364.188278 -276.413719) (xy 364.234436 -276.38707) (xy 364.28405 -276.367598)
			(xy 364.336012 -276.355738) (xy 364.389162 -276.351755) (xy 364.442312 -276.355738) (xy 364.494274 -276.367598)
			(xy 364.543888 -276.38707) (xy 364.590046 -276.413719) (xy 364.631717 -276.44695) (xy 364.667969 -276.486021)
			(xy 364.697993 -276.530058) (xy 364.721119 -276.578079) (xy 364.736829 -276.629009) (xy 364.744772 -276.681713)
			(xy 364.74527 -276.708362) (xy 364.744772 -276.735011) (xy 364.973352 -276.735011) (xy 364.973352 -276.681713)
			(xy 364.981295 -276.629009) (xy 364.997005 -276.578079) (xy 365.020131 -276.530058) (xy 365.050155 -276.486021)
			(xy 365.086407 -276.44695) (xy 365.128078 -276.413719) (xy 365.174236 -276.38707) (xy 365.22385 -276.367598)
			(xy 365.275812 -276.355738) (xy 365.328962 -276.351755) (xy 365.382112 -276.355738) (xy 365.434074 -276.367598)
			(xy 365.483688 -276.38707) (xy 365.529846 -276.413719) (xy 365.571517 -276.44695) (xy 365.607769 -276.486021)
			(xy 365.637793 -276.530058) (xy 365.660919 -276.578079) (xy 365.676629 -276.629009) (xy 365.684572 -276.681713)
			(xy 365.68507 -276.708362) (xy 365.684572 -276.735011) (xy 365.913152 -276.735011) (xy 365.913152 -276.681713)
			(xy 365.921095 -276.629009) (xy 365.936805 -276.578079) (xy 365.959931 -276.530058) (xy 365.989955 -276.486021)
			(xy 366.026207 -276.44695) (xy 366.067878 -276.413719) (xy 366.114036 -276.38707) (xy 366.16365 -276.367598)
			(xy 366.215612 -276.355738) (xy 366.268762 -276.351755) (xy 366.321912 -276.355738) (xy 366.373874 -276.367598)
			(xy 366.423488 -276.38707) (xy 366.469646 -276.413719) (xy 366.511317 -276.44695) (xy 366.547569 -276.486021)
			(xy 366.577593 -276.530058) (xy 366.600719 -276.578079) (xy 366.616429 -276.629009) (xy 366.624372 -276.681713)
			(xy 366.62487 -276.708362) (xy 366.624372 -276.735011) (xy 366.624334 -276.735265) (xy 366.852952 -276.735265)
			(xy 366.852952 -276.681967) (xy 366.860895 -276.629263) (xy 366.876605 -276.578333) (xy 366.899731 -276.530312)
			(xy 366.929755 -276.486275) (xy 366.966007 -276.447204) (xy 367.007678 -276.413973) (xy 367.053836 -276.387324)
			(xy 367.10345 -276.367852) (xy 367.155412 -276.355992) (xy 367.208562 -276.352009) (xy 367.261712 -276.355992)
			(xy 367.313674 -276.367852) (xy 367.363288 -276.387324) (xy 367.409446 -276.413973) (xy 367.451117 -276.447204)
			(xy 367.487369 -276.486275) (xy 367.517393 -276.530312) (xy 367.540519 -276.578333) (xy 367.556229 -276.629263)
			(xy 367.564172 -276.681967) (xy 367.56467 -276.708616) (xy 367.564177 -276.735011) (xy 367.792752 -276.735011)
			(xy 367.792752 -276.681713) (xy 367.800695 -276.629009) (xy 367.816405 -276.578079) (xy 367.839531 -276.530058)
			(xy 367.869555 -276.486021) (xy 367.905807 -276.44695) (xy 367.947478 -276.413719) (xy 367.993636 -276.38707)
			(xy 368.04325 -276.367598) (xy 368.095212 -276.355738) (xy 368.148362 -276.351755) (xy 368.201512 -276.355738)
			(xy 368.253474 -276.367598) (xy 368.303088 -276.38707) (xy 368.349246 -276.413719) (xy 368.390917 -276.44695)
			(xy 368.427169 -276.486021) (xy 368.457193 -276.530058) (xy 368.480319 -276.578079) (xy 368.496029 -276.629009)
			(xy 368.503972 -276.681713) (xy 368.50447 -276.708362) (xy 368.503972 -276.735011) (xy 368.503934 -276.735265)
			(xy 368.732806 -276.735265) (xy 368.732806 -276.681967) (xy 368.740749 -276.629263) (xy 368.756459 -276.578333)
			(xy 368.779585 -276.530312) (xy 368.809609 -276.486275) (xy 368.845861 -276.447204) (xy 368.887532 -276.413973)
			(xy 368.93369 -276.387324) (xy 368.983304 -276.367852) (xy 369.035266 -276.355992) (xy 369.088416 -276.352009)
			(xy 369.141566 -276.355992) (xy 369.193528 -276.367852) (xy 369.243142 -276.387324) (xy 369.2893 -276.413973)
			(xy 369.330971 -276.447204) (xy 369.367223 -276.486275) (xy 369.397247 -276.530312) (xy 369.420373 -276.578333)
			(xy 369.436083 -276.629263) (xy 369.444026 -276.681967) (xy 369.444524 -276.708616) (xy 369.444026 -276.735265)
			(xy 370.612406 -276.735265) (xy 370.612406 -276.681967) (xy 370.620349 -276.629263) (xy 370.636059 -276.578333)
			(xy 370.659185 -276.530312) (xy 370.689209 -276.486275) (xy 370.725461 -276.447204) (xy 370.767132 -276.413973)
			(xy 370.81329 -276.387324) (xy 370.862904 -276.367852) (xy 370.914866 -276.355992) (xy 370.968016 -276.352009)
			(xy 371.021166 -276.355992) (xy 371.073128 -276.367852) (xy 371.122742 -276.387324) (xy 371.1689 -276.413973)
			(xy 371.210571 -276.447204) (xy 371.246823 -276.486275) (xy 371.276847 -276.530312) (xy 371.299973 -276.578333)
			(xy 371.315683 -276.629263) (xy 371.323626 -276.681967) (xy 371.324124 -276.708616) (xy 371.323626 -276.735265)
			(xy 371.552206 -276.735265) (xy 371.552206 -276.681967) (xy 371.560149 -276.629263) (xy 371.575859 -276.578333)
			(xy 371.598985 -276.530312) (xy 371.629009 -276.486275) (xy 371.665261 -276.447204) (xy 371.706932 -276.413973)
			(xy 371.75309 -276.387324) (xy 371.802704 -276.367852) (xy 371.854666 -276.355992) (xy 371.907816 -276.352009)
			(xy 371.960966 -276.355992) (xy 372.012928 -276.367852) (xy 372.062542 -276.387324) (xy 372.1087 -276.413973)
			(xy 372.150371 -276.447204) (xy 372.186623 -276.486275) (xy 372.216647 -276.530312) (xy 372.239773 -276.578333)
			(xy 372.255483 -276.629263) (xy 372.263426 -276.681967) (xy 372.263924 -276.708616) (xy 372.263426 -276.735265)
			(xy 372.492006 -276.735265) (xy 372.492006 -276.681967) (xy 372.499949 -276.629263) (xy 372.515659 -276.578333)
			(xy 372.538785 -276.530312) (xy 372.568809 -276.486275) (xy 372.605061 -276.447204) (xy 372.646732 -276.413973)
			(xy 372.69289 -276.387324) (xy 372.742504 -276.367852) (xy 372.794466 -276.355992) (xy 372.847616 -276.352009)
			(xy 372.900766 -276.355992) (xy 372.952728 -276.367852) (xy 373.002342 -276.387324) (xy 373.0485 -276.413973)
			(xy 373.090171 -276.447204) (xy 373.126423 -276.486275) (xy 373.156447 -276.530312) (xy 373.179573 -276.578333)
			(xy 373.195283 -276.629263) (xy 373.203226 -276.681967) (xy 373.203724 -276.708616) (xy 373.203226 -276.735265)
			(xy 373.431552 -276.735265) (xy 373.431552 -276.681967) (xy 373.439495 -276.629263) (xy 373.455205 -276.578333)
			(xy 373.478331 -276.530312) (xy 373.508355 -276.486275) (xy 373.544607 -276.447204) (xy 373.586278 -276.413973)
			(xy 373.632436 -276.387324) (xy 373.68205 -276.367852) (xy 373.734012 -276.355992) (xy 373.787162 -276.352009)
			(xy 373.840312 -276.355992) (xy 373.892274 -276.367852) (xy 373.941888 -276.387324) (xy 373.988046 -276.413973)
			(xy 374.029717 -276.447204) (xy 374.065969 -276.486275) (xy 374.095993 -276.530312) (xy 374.119119 -276.578333)
			(xy 374.134829 -276.629263) (xy 374.142772 -276.681967) (xy 374.14327 -276.708616) (xy 374.142772 -276.735265)
			(xy 374.371606 -276.735265) (xy 374.371606 -276.681967) (xy 374.379549 -276.629263) (xy 374.395259 -276.578333)
			(xy 374.418385 -276.530312) (xy 374.448409 -276.486275) (xy 374.484661 -276.447204) (xy 374.526332 -276.413973)
			(xy 374.57249 -276.387324) (xy 374.622104 -276.367852) (xy 374.674066 -276.355992) (xy 374.727216 -276.352009)
			(xy 374.780366 -276.355992) (xy 374.832328 -276.367852) (xy 374.881942 -276.387324) (xy 374.9281 -276.413973)
			(xy 374.969771 -276.447204) (xy 375.006023 -276.486275) (xy 375.036047 -276.530312) (xy 375.059173 -276.578333)
			(xy 375.074883 -276.629263) (xy 375.082826 -276.681967) (xy 375.083324 -276.708616) (xy 375.082826 -276.735265)
			(xy 375.311406 -276.735265) (xy 375.311406 -276.681967) (xy 375.319349 -276.629263) (xy 375.335059 -276.578333)
			(xy 375.358185 -276.530312) (xy 375.388209 -276.486275) (xy 375.424461 -276.447204) (xy 375.466132 -276.413973)
			(xy 375.51229 -276.387324) (xy 375.561904 -276.367852) (xy 375.613866 -276.355992) (xy 375.667016 -276.352009)
			(xy 375.720166 -276.355992) (xy 375.772128 -276.367852) (xy 375.821742 -276.387324) (xy 375.8679 -276.413973)
			(xy 375.909571 -276.447204) (xy 375.945823 -276.486275) (xy 375.975847 -276.530312) (xy 375.998973 -276.578333)
			(xy 376.014683 -276.629263) (xy 376.022626 -276.681967) (xy 376.023124 -276.708616) (xy 376.022626 -276.735265)
			(xy 376.251206 -276.735265) (xy 376.251206 -276.681967) (xy 376.259149 -276.629263) (xy 376.274859 -276.578333)
			(xy 376.297985 -276.530312) (xy 376.328009 -276.486275) (xy 376.364261 -276.447204) (xy 376.405932 -276.413973)
			(xy 376.45209 -276.387324) (xy 376.501704 -276.367852) (xy 376.553666 -276.355992) (xy 376.606816 -276.352009)
			(xy 376.659966 -276.355992) (xy 376.711928 -276.367852) (xy 376.761542 -276.387324) (xy 376.8077 -276.413973)
			(xy 376.849371 -276.447204) (xy 376.885623 -276.486275) (xy 376.915647 -276.530312) (xy 376.938773 -276.578333)
			(xy 376.954483 -276.629263) (xy 376.962426 -276.681967) (xy 376.962924 -276.708616) (xy 376.962426 -276.735265)
			(xy 377.191006 -276.735265) (xy 377.191006 -276.681967) (xy 377.198949 -276.629263) (xy 377.214659 -276.578333)
			(xy 377.237785 -276.530312) (xy 377.267809 -276.486275) (xy 377.304061 -276.447204) (xy 377.345732 -276.413973)
			(xy 377.39189 -276.387324) (xy 377.441504 -276.367852) (xy 377.493466 -276.355992) (xy 377.546616 -276.352009)
			(xy 377.599766 -276.355992) (xy 377.651728 -276.367852) (xy 377.701342 -276.387324) (xy 377.7475 -276.413973)
			(xy 377.789171 -276.447204) (xy 377.825423 -276.486275) (xy 377.855447 -276.530312) (xy 377.878573 -276.578333)
			(xy 377.894283 -276.629263) (xy 377.902226 -276.681967) (xy 377.902724 -276.708616) (xy 377.902226 -276.735265)
			(xy 378.130806 -276.735265) (xy 378.130806 -276.681967) (xy 378.138749 -276.629263) (xy 378.154459 -276.578333)
			(xy 378.177585 -276.530312) (xy 378.207609 -276.486275) (xy 378.243861 -276.447204) (xy 378.285532 -276.413973)
			(xy 378.33169 -276.387324) (xy 378.381304 -276.367852) (xy 378.433266 -276.355992) (xy 378.486416 -276.352009)
			(xy 378.539566 -276.355992) (xy 378.591528 -276.367852) (xy 378.641142 -276.387324) (xy 378.6873 -276.413973)
			(xy 378.728971 -276.447204) (xy 378.765223 -276.486275) (xy 378.795247 -276.530312) (xy 378.818373 -276.578333)
			(xy 378.834083 -276.629263) (xy 378.842026 -276.681967) (xy 378.842524 -276.708616) (xy 378.842026 -276.735265)
			(xy 379.070606 -276.735265) (xy 379.070606 -276.681967) (xy 379.078549 -276.629263) (xy 379.094259 -276.578333)
			(xy 379.117385 -276.530312) (xy 379.147409 -276.486275) (xy 379.183661 -276.447204) (xy 379.225332 -276.413973)
			(xy 379.27149 -276.387324) (xy 379.321104 -276.367852) (xy 379.373066 -276.355992) (xy 379.426216 -276.352009)
			(xy 379.479366 -276.355992) (xy 379.531328 -276.367852) (xy 379.580942 -276.387324) (xy 379.6271 -276.413973)
			(xy 379.668771 -276.447204) (xy 379.705023 -276.486275) (xy 379.735047 -276.530312) (xy 379.758173 -276.578333)
			(xy 379.773883 -276.629263) (xy 379.781826 -276.681967) (xy 379.782324 -276.708616) (xy 379.781826 -276.735265)
			(xy 379.773883 -276.787969) (xy 379.758173 -276.838899) (xy 379.735047 -276.88692) (xy 379.705023 -276.930957)
			(xy 379.668771 -276.970028) (xy 379.6271 -277.003259) (xy 379.580942 -277.029908) (xy 379.531328 -277.04938)
			(xy 379.479366 -277.06124) (xy 379.426216 -277.065224) (xy 379.373066 -277.06124) (xy 379.321104 -277.04938)
			(xy 379.27149 -277.029908) (xy 379.225332 -277.003259) (xy 379.183661 -276.970028) (xy 379.147409 -276.930957)
			(xy 379.117385 -276.88692) (xy 379.094259 -276.838899) (xy 379.078549 -276.787969) (xy 379.070606 -276.735265)
			(xy 378.842026 -276.735265) (xy 378.834083 -276.787969) (xy 378.818373 -276.838899) (xy 378.795247 -276.88692)
			(xy 378.765223 -276.930957) (xy 378.728971 -276.970028) (xy 378.6873 -277.003259) (xy 378.641142 -277.029908)
			(xy 378.591528 -277.04938) (xy 378.539566 -277.06124) (xy 378.486416 -277.065224) (xy 378.433266 -277.06124)
			(xy 378.381304 -277.04938) (xy 378.33169 -277.029908) (xy 378.285532 -277.003259) (xy 378.243861 -276.970028)
			(xy 378.207609 -276.930957) (xy 378.177585 -276.88692) (xy 378.154459 -276.838899) (xy 378.138749 -276.787969)
			(xy 378.130806 -276.735265) (xy 377.902226 -276.735265) (xy 377.894283 -276.787969) (xy 377.878573 -276.838899)
			(xy 377.855447 -276.88692) (xy 377.825423 -276.930957) (xy 377.789171 -276.970028) (xy 377.7475 -277.003259)
			(xy 377.701342 -277.029908) (xy 377.651728 -277.04938) (xy 377.599766 -277.06124) (xy 377.546616 -277.065224)
			(xy 377.493466 -277.06124) (xy 377.441504 -277.04938) (xy 377.39189 -277.029908) (xy 377.345732 -277.003259)
			(xy 377.304061 -276.970028) (xy 377.267809 -276.930957) (xy 377.237785 -276.88692) (xy 377.214659 -276.838899)
			(xy 377.198949 -276.787969) (xy 377.191006 -276.735265) (xy 376.962426 -276.735265) (xy 376.954483 -276.787969)
			(xy 376.938773 -276.838899) (xy 376.915647 -276.88692) (xy 376.885623 -276.930957) (xy 376.849371 -276.970028)
			(xy 376.8077 -277.003259) (xy 376.761542 -277.029908) (xy 376.711928 -277.04938) (xy 376.659966 -277.06124)
			(xy 376.606816 -277.065224) (xy 376.553666 -277.06124) (xy 376.501704 -277.04938) (xy 376.45209 -277.029908)
			(xy 376.405932 -277.003259) (xy 376.364261 -276.970028) (xy 376.328009 -276.930957) (xy 376.297985 -276.88692)
			(xy 376.274859 -276.838899) (xy 376.259149 -276.787969) (xy 376.251206 -276.735265) (xy 376.022626 -276.735265)
			(xy 376.014683 -276.787969) (xy 375.998973 -276.838899) (xy 375.975847 -276.88692) (xy 375.945823 -276.930957)
			(xy 375.909571 -276.970028) (xy 375.8679 -277.003259) (xy 375.821742 -277.029908) (xy 375.772128 -277.04938)
			(xy 375.720166 -277.06124) (xy 375.667016 -277.065224) (xy 375.613866 -277.06124) (xy 375.561904 -277.04938)
			(xy 375.51229 -277.029908) (xy 375.466132 -277.003259) (xy 375.424461 -276.970028) (xy 375.388209 -276.930957)
			(xy 375.358185 -276.88692) (xy 375.335059 -276.838899) (xy 375.319349 -276.787969) (xy 375.311406 -276.735265)
			(xy 375.082826 -276.735265) (xy 375.074883 -276.787969) (xy 375.059173 -276.838899) (xy 375.036047 -276.88692)
			(xy 375.006023 -276.930957) (xy 374.969771 -276.970028) (xy 374.9281 -277.003259) (xy 374.881942 -277.029908)
			(xy 374.832328 -277.04938) (xy 374.780366 -277.06124) (xy 374.727216 -277.065224) (xy 374.674066 -277.06124)
			(xy 374.622104 -277.04938) (xy 374.57249 -277.029908) (xy 374.526332 -277.003259) (xy 374.484661 -276.970028)
			(xy 374.448409 -276.930957) (xy 374.418385 -276.88692) (xy 374.395259 -276.838899) (xy 374.379549 -276.787969)
			(xy 374.371606 -276.735265) (xy 374.142772 -276.735265) (xy 374.134829 -276.787969) (xy 374.119119 -276.838899)
			(xy 374.095993 -276.88692) (xy 374.065969 -276.930957) (xy 374.029717 -276.970028) (xy 373.988046 -277.003259)
			(xy 373.941888 -277.029908) (xy 373.892274 -277.04938) (xy 373.840312 -277.06124) (xy 373.787162 -277.065224)
			(xy 373.734012 -277.06124) (xy 373.68205 -277.04938) (xy 373.632436 -277.029908) (xy 373.586278 -277.003259)
			(xy 373.544607 -276.970028) (xy 373.508355 -276.930957) (xy 373.478331 -276.88692) (xy 373.455205 -276.838899)
			(xy 373.439495 -276.787969) (xy 373.431552 -276.735265) (xy 373.203226 -276.735265) (xy 373.195283 -276.787969)
			(xy 373.179573 -276.838899) (xy 373.156447 -276.88692) (xy 373.126423 -276.930957) (xy 373.090171 -276.970028)
			(xy 373.0485 -277.003259) (xy 373.002342 -277.029908) (xy 372.952728 -277.04938) (xy 372.900766 -277.06124)
			(xy 372.847616 -277.065224) (xy 372.794466 -277.06124) (xy 372.742504 -277.04938) (xy 372.69289 -277.029908)
			(xy 372.646732 -277.003259) (xy 372.605061 -276.970028) (xy 372.568809 -276.930957) (xy 372.538785 -276.88692)
			(xy 372.515659 -276.838899) (xy 372.499949 -276.787969) (xy 372.492006 -276.735265) (xy 372.263426 -276.735265)
			(xy 372.255483 -276.787969) (xy 372.239773 -276.838899) (xy 372.216647 -276.88692) (xy 372.186623 -276.930957)
			(xy 372.150371 -276.970028) (xy 372.1087 -277.003259) (xy 372.062542 -277.029908) (xy 372.012928 -277.04938)
			(xy 371.960966 -277.06124) (xy 371.907816 -277.065224) (xy 371.854666 -277.06124) (xy 371.802704 -277.04938)
			(xy 371.75309 -277.029908) (xy 371.706932 -277.003259) (xy 371.665261 -276.970028) (xy 371.629009 -276.930957)
			(xy 371.598985 -276.88692) (xy 371.575859 -276.838899) (xy 371.560149 -276.787969) (xy 371.552206 -276.735265)
			(xy 371.323626 -276.735265) (xy 371.315683 -276.787969) (xy 371.299973 -276.838899) (xy 371.276847 -276.88692)
			(xy 371.246823 -276.930957) (xy 371.210571 -276.970028) (xy 371.1689 -277.003259) (xy 371.122742 -277.029908)
			(xy 371.073128 -277.04938) (xy 371.021166 -277.06124) (xy 370.968016 -277.065224) (xy 370.914866 -277.06124)
			(xy 370.862904 -277.04938) (xy 370.81329 -277.029908) (xy 370.767132 -277.003259) (xy 370.725461 -276.970028)
			(xy 370.689209 -276.930957) (xy 370.659185 -276.88692) (xy 370.636059 -276.838899) (xy 370.620349 -276.787969)
			(xy 370.612406 -276.735265) (xy 369.444026 -276.735265) (xy 369.436083 -276.787969) (xy 369.420373 -276.838899)
			(xy 369.397247 -276.88692) (xy 369.367223 -276.930957) (xy 369.330971 -276.970028) (xy 369.2893 -277.003259)
			(xy 369.243142 -277.029908) (xy 369.193528 -277.04938) (xy 369.141566 -277.06124) (xy 369.088416 -277.065224)
			(xy 369.035266 -277.06124) (xy 368.983304 -277.04938) (xy 368.93369 -277.029908) (xy 368.887532 -277.003259)
			(xy 368.845861 -276.970028) (xy 368.809609 -276.930957) (xy 368.779585 -276.88692) (xy 368.756459 -276.838899)
			(xy 368.740749 -276.787969) (xy 368.732806 -276.735265) (xy 368.503934 -276.735265) (xy 368.496029 -276.787715)
			(xy 368.480319 -276.838645) (xy 368.457193 -276.886666) (xy 368.427169 -276.930703) (xy 368.390917 -276.969774)
			(xy 368.349246 -277.003005) (xy 368.303088 -277.029654) (xy 368.253474 -277.049126) (xy 368.201512 -277.060986)
			(xy 368.148362 -277.06497) (xy 368.095212 -277.060986) (xy 368.04325 -277.049126) (xy 367.993636 -277.029654)
			(xy 367.947478 -277.003005) (xy 367.905807 -276.969774) (xy 367.869555 -276.930703) (xy 367.839531 -276.886666)
			(xy 367.816405 -276.838645) (xy 367.800695 -276.787715) (xy 367.792752 -276.735011) (xy 367.564177 -276.735011)
			(xy 367.564172 -276.735265) (xy 367.556229 -276.787969) (xy 367.540519 -276.838899) (xy 367.517393 -276.88692)
			(xy 367.487369 -276.930957) (xy 367.451117 -276.970028) (xy 367.409446 -277.003259) (xy 367.363288 -277.029908)
			(xy 367.313674 -277.04938) (xy 367.261712 -277.06124) (xy 367.208562 -277.065224) (xy 367.155412 -277.06124)
			(xy 367.10345 -277.04938) (xy 367.053836 -277.029908) (xy 367.007678 -277.003259) (xy 366.966007 -276.970028)
			(xy 366.929755 -276.930957) (xy 366.899731 -276.88692) (xy 366.876605 -276.838899) (xy 366.860895 -276.787969)
			(xy 366.852952 -276.735265) (xy 366.624334 -276.735265) (xy 366.616429 -276.787715) (xy 366.600719 -276.838645)
			(xy 366.577593 -276.886666) (xy 366.547569 -276.930703) (xy 366.511317 -276.969774) (xy 366.469646 -277.003005)
			(xy 366.423488 -277.029654) (xy 366.373874 -277.049126) (xy 366.321912 -277.060986) (xy 366.268762 -277.06497)
			(xy 366.215612 -277.060986) (xy 366.16365 -277.049126) (xy 366.114036 -277.029654) (xy 366.067878 -277.003005)
			(xy 366.026207 -276.969774) (xy 365.989955 -276.930703) (xy 365.959931 -276.886666) (xy 365.936805 -276.838645)
			(xy 365.921095 -276.787715) (xy 365.913152 -276.735011) (xy 365.684572 -276.735011) (xy 365.676629 -276.787715)
			(xy 365.660919 -276.838645) (xy 365.637793 -276.886666) (xy 365.607769 -276.930703) (xy 365.571517 -276.969774)
			(xy 365.529846 -277.003005) (xy 365.483688 -277.029654) (xy 365.434074 -277.049126) (xy 365.382112 -277.060986)
			(xy 365.328962 -277.06497) (xy 365.275812 -277.060986) (xy 365.22385 -277.049126) (xy 365.174236 -277.029654)
			(xy 365.128078 -277.003005) (xy 365.086407 -276.969774) (xy 365.050155 -276.930703) (xy 365.020131 -276.886666)
			(xy 364.997005 -276.838645) (xy 364.981295 -276.787715) (xy 364.973352 -276.735011) (xy 364.744772 -276.735011)
			(xy 364.736829 -276.787715) (xy 364.721119 -276.838645) (xy 364.697993 -276.886666) (xy 364.667969 -276.930703)
			(xy 364.631717 -276.969774) (xy 364.590046 -277.003005) (xy 364.543888 -277.029654) (xy 364.494274 -277.049126)
			(xy 364.442312 -277.060986) (xy 364.389162 -277.06497) (xy 364.336012 -277.060986) (xy 364.28405 -277.049126)
			(xy 364.234436 -277.029654) (xy 364.188278 -277.003005) (xy 364.146607 -276.969774) (xy 364.110355 -276.930703)
			(xy 364.080331 -276.886666) (xy 364.057205 -276.838645) (xy 364.041495 -276.787715) (xy 364.033552 -276.735011)
			(xy 363.804975 -276.735011) (xy 363.804969 -276.735329) (xy 363.79683 -276.788647) (xy 363.780747 -276.840128)
			(xy 363.757088 -276.888597) (xy 363.726394 -276.932946) (xy 363.689365 -276.972161) (xy 363.646848 -277.005347)
			(xy 363.599815 -277.031746) (xy 363.54934 -277.050753) (xy 363.496577 -277.061934) (xy 363.469682 -277.063962)
			(xy 363.455117 -277.06529) (xy 363.427607 -277.075187) (xy 363.404026 -277.092469) (xy 363.386304 -277.115722)
			(xy 363.375892 -277.143041) (xy 363.373641 -277.17219) (xy 363.379737 -277.200783) (xy 363.39368 -277.22648)
			(xy 363.403642 -277.23719) (xy 363.483398 -277.316946) (xy 363.493982 -277.326829) (xy 363.519359 -277.340747)
			(xy 363.547626 -277.346973) (xy 363.576502 -277.345004) (xy 363.603662 -277.335) (xy 363.626917 -277.317767)
			(xy 363.636052 -277.306532) (xy 363.653031 -277.285113) (xy 363.692403 -277.247208) (xy 363.737101 -277.215756)
			(xy 363.786075 -277.191496) (xy 363.838178 -277.174995) (xy 363.892189 -277.16664) (xy 363.919516 -277.16607)
			(xy 363.947499 -277.16662) (xy 364.002775 -277.175377) (xy 364.056002 -277.192673) (xy 364.105867 -277.218081)
			(xy 364.151145 -277.250977) (xy 364.190719 -277.290551) (xy 364.223616 -277.335828) (xy 364.249025 -277.385693)
			(xy 364.266322 -277.438919) (xy 364.275079 -277.494195) (xy 364.275624 -277.522178) (xy 364.275135 -277.549081)
			(xy 364.503452 -277.549081) (xy 364.503452 -277.495783) (xy 364.511395 -277.443079) (xy 364.527105 -277.392149)
			(xy 364.550231 -277.344128) (xy 364.580255 -277.300091) (xy 364.616507 -277.26102) (xy 364.658178 -277.227789)
			(xy 364.704336 -277.20114) (xy 364.75395 -277.181668) (xy 364.805912 -277.169808) (xy 364.859062 -277.165825)
			(xy 364.912212 -277.169808) (xy 364.964174 -277.181668) (xy 365.013788 -277.20114) (xy 365.059946 -277.227789)
			(xy 365.101617 -277.26102) (xy 365.137869 -277.300091) (xy 365.167893 -277.344128) (xy 365.191019 -277.392149)
			(xy 365.206729 -277.443079) (xy 365.214672 -277.495783) (xy 365.21517 -277.522432) (xy 365.214677 -277.548827)
			(xy 365.443506 -277.548827) (xy 365.443506 -277.495529) (xy 365.451449 -277.442825) (xy 365.467159 -277.391895)
			(xy 365.490285 -277.343874) (xy 365.520309 -277.299837) (xy 365.556561 -277.260766) (xy 365.598232 -277.227535)
			(xy 365.64439 -277.200886) (xy 365.694004 -277.181414) (xy 365.745966 -277.169554) (xy 365.799116 -277.165571)
			(xy 365.852266 -277.169554) (xy 365.904228 -277.181414) (xy 365.953842 -277.200886) (xy 366 -277.227535)
			(xy 366.041671 -277.260766) (xy 366.077923 -277.299837) (xy 366.107947 -277.343874) (xy 366.131073 -277.391895)
			(xy 366.146783 -277.442825) (xy 366.154726 -277.495529) (xy 366.155224 -277.522178) (xy 366.154726 -277.548827)
			(xy 366.154688 -277.549081) (xy 366.383306 -277.549081) (xy 366.383306 -277.495783) (xy 366.391249 -277.443079)
			(xy 366.406959 -277.392149) (xy 366.430085 -277.344128) (xy 366.460109 -277.300091) (xy 366.496361 -277.26102)
			(xy 366.538032 -277.227789) (xy 366.58419 -277.20114) (xy 366.633804 -277.181668) (xy 366.685766 -277.169808)
			(xy 366.738916 -277.165825) (xy 366.792066 -277.169808) (xy 366.844028 -277.181668) (xy 366.893642 -277.20114)
			(xy 366.9398 -277.227789) (xy 366.981471 -277.26102) (xy 367.017723 -277.300091) (xy 367.047747 -277.344128)
			(xy 367.070873 -277.392149) (xy 367.086583 -277.443079) (xy 367.094526 -277.495783) (xy 367.095024 -277.522432)
			(xy 367.094531 -277.548827) (xy 367.323106 -277.548827) (xy 367.323106 -277.495529) (xy 367.331049 -277.442825)
			(xy 367.346759 -277.391895) (xy 367.369885 -277.343874) (xy 367.399909 -277.299837) (xy 367.436161 -277.260766)
			(xy 367.477832 -277.227535) (xy 367.52399 -277.200886) (xy 367.573604 -277.181414) (xy 367.625566 -277.169554)
			(xy 367.678716 -277.165571) (xy 367.731866 -277.169554) (xy 367.783828 -277.181414) (xy 367.833442 -277.200886)
			(xy 367.8796 -277.227535) (xy 367.921271 -277.260766) (xy 367.957523 -277.299837) (xy 367.987547 -277.343874)
			(xy 368.010673 -277.391895) (xy 368.026383 -277.442825) (xy 368.034326 -277.495529) (xy 368.034824 -277.522178)
			(xy 368.034326 -277.548827) (xy 368.262906 -277.548827) (xy 368.262906 -277.495529) (xy 368.270849 -277.442825)
			(xy 368.286559 -277.391895) (xy 368.309685 -277.343874) (xy 368.339709 -277.299837) (xy 368.375961 -277.260766)
			(xy 368.417632 -277.227535) (xy 368.46379 -277.200886) (xy 368.513404 -277.181414) (xy 368.565366 -277.169554)
			(xy 368.618516 -277.165571) (xy 368.671666 -277.169554) (xy 368.723628 -277.181414) (xy 368.773242 -277.200886)
			(xy 368.8194 -277.227535) (xy 368.861071 -277.260766) (xy 368.897323 -277.299837) (xy 368.927347 -277.343874)
			(xy 368.950473 -277.391895) (xy 368.966183 -277.442825) (xy 368.974126 -277.495529) (xy 368.974624 -277.522178)
			(xy 368.974126 -277.548827) (xy 369.202706 -277.548827) (xy 369.202706 -277.495529) (xy 369.210649 -277.442825)
			(xy 369.226359 -277.391895) (xy 369.249485 -277.343874) (xy 369.279509 -277.299837) (xy 369.315761 -277.260766)
			(xy 369.357432 -277.227535) (xy 369.40359 -277.200886) (xy 369.453204 -277.181414) (xy 369.505166 -277.169554)
			(xy 369.558316 -277.165571) (xy 369.611466 -277.169554) (xy 369.663428 -277.181414) (xy 369.713042 -277.200886)
			(xy 369.7592 -277.227535) (xy 369.800871 -277.260766) (xy 369.837123 -277.299837) (xy 369.867147 -277.343874)
			(xy 369.890273 -277.391895) (xy 369.905983 -277.442825) (xy 369.913926 -277.495529) (xy 369.914424 -277.522178)
			(xy 369.913926 -277.548827) (xy 370.142506 -277.548827) (xy 370.142506 -277.495529) (xy 370.150449 -277.442825)
			(xy 370.166159 -277.391895) (xy 370.189285 -277.343874) (xy 370.219309 -277.299837) (xy 370.255561 -277.260766)
			(xy 370.297232 -277.227535) (xy 370.34339 -277.200886) (xy 370.393004 -277.181414) (xy 370.444966 -277.169554)
			(xy 370.498116 -277.165571) (xy 370.551266 -277.169554) (xy 370.603228 -277.181414) (xy 370.652842 -277.200886)
			(xy 370.699 -277.227535) (xy 370.740671 -277.260766) (xy 370.776923 -277.299837) (xy 370.806947 -277.343874)
			(xy 370.830073 -277.391895) (xy 370.845783 -277.442825) (xy 370.853726 -277.495529) (xy 370.854224 -277.522178)
			(xy 370.853726 -277.548827) (xy 370.853688 -277.549081) (xy 371.082052 -277.549081) (xy 371.082052 -277.495783)
			(xy 371.089995 -277.443079) (xy 371.105705 -277.392149) (xy 371.128831 -277.344128) (xy 371.158855 -277.300091)
			(xy 371.195107 -277.26102) (xy 371.236778 -277.227789) (xy 371.282936 -277.20114) (xy 371.33255 -277.181668)
			(xy 371.384512 -277.169808) (xy 371.437662 -277.165825) (xy 371.490812 -277.169808) (xy 371.542774 -277.181668)
			(xy 371.592388 -277.20114) (xy 371.638546 -277.227789) (xy 371.680217 -277.26102) (xy 371.716469 -277.300091)
			(xy 371.746493 -277.344128) (xy 371.769619 -277.392149) (xy 371.785329 -277.443079) (xy 371.793272 -277.495783)
			(xy 371.79377 -277.522432) (xy 371.793272 -277.549081) (xy 372.021852 -277.549081) (xy 372.021852 -277.495783)
			(xy 372.029795 -277.443079) (xy 372.045505 -277.392149) (xy 372.068631 -277.344128) (xy 372.098655 -277.300091)
			(xy 372.134907 -277.26102) (xy 372.176578 -277.227789) (xy 372.222736 -277.20114) (xy 372.27235 -277.181668)
			(xy 372.324312 -277.169808) (xy 372.377462 -277.165825) (xy 372.430612 -277.169808) (xy 372.482574 -277.181668)
			(xy 372.532188 -277.20114) (xy 372.578346 -277.227789) (xy 372.620017 -277.26102) (xy 372.656269 -277.300091)
			(xy 372.686293 -277.344128) (xy 372.709419 -277.392149) (xy 372.725129 -277.443079) (xy 372.733072 -277.495783)
			(xy 372.73357 -277.522432) (xy 372.733072 -277.549081) (xy 372.961906 -277.549081) (xy 372.961906 -277.495783)
			(xy 372.969849 -277.443079) (xy 372.985559 -277.392149) (xy 373.008685 -277.344128) (xy 373.038709 -277.300091)
			(xy 373.074961 -277.26102) (xy 373.116632 -277.227789) (xy 373.16279 -277.20114) (xy 373.212404 -277.181668)
			(xy 373.264366 -277.169808) (xy 373.317516 -277.165825) (xy 373.370666 -277.169808) (xy 373.422628 -277.181668)
			(xy 373.472242 -277.20114) (xy 373.5184 -277.227789) (xy 373.560071 -277.26102) (xy 373.596323 -277.300091)
			(xy 373.626347 -277.344128) (xy 373.649473 -277.392149) (xy 373.665183 -277.443079) (xy 373.673126 -277.495783)
			(xy 373.673624 -277.522432) (xy 373.673126 -277.549081) (xy 373.901452 -277.549081) (xy 373.901452 -277.495783)
			(xy 373.909395 -277.443079) (xy 373.925105 -277.392149) (xy 373.948231 -277.344128) (xy 373.978255 -277.300091)
			(xy 374.014507 -277.26102) (xy 374.056178 -277.227789) (xy 374.102336 -277.20114) (xy 374.15195 -277.181668)
			(xy 374.203912 -277.169808) (xy 374.257062 -277.165825) (xy 374.310212 -277.169808) (xy 374.362174 -277.181668)
			(xy 374.411788 -277.20114) (xy 374.457946 -277.227789) (xy 374.499617 -277.26102) (xy 374.535869 -277.300091)
			(xy 374.565893 -277.344128) (xy 374.589019 -277.392149) (xy 374.604729 -277.443079) (xy 374.612672 -277.495783)
			(xy 374.61317 -277.522432) (xy 374.612672 -277.549081) (xy 374.841252 -277.549081) (xy 374.841252 -277.495783)
			(xy 374.849195 -277.443079) (xy 374.864905 -277.392149) (xy 374.888031 -277.344128) (xy 374.918055 -277.300091)
			(xy 374.954307 -277.26102) (xy 374.995978 -277.227789) (xy 375.042136 -277.20114) (xy 375.09175 -277.181668)
			(xy 375.143712 -277.169808) (xy 375.196862 -277.165825) (xy 375.250012 -277.169808) (xy 375.301974 -277.181668)
			(xy 375.351588 -277.20114) (xy 375.397746 -277.227789) (xy 375.439417 -277.26102) (xy 375.475669 -277.300091)
			(xy 375.505693 -277.344128) (xy 375.528819 -277.392149) (xy 375.544529 -277.443079) (xy 375.552472 -277.495783)
			(xy 375.55297 -277.522432) (xy 375.552472 -277.549081) (xy 375.781052 -277.549081) (xy 375.781052 -277.495783)
			(xy 375.788995 -277.443079) (xy 375.804705 -277.392149) (xy 375.827831 -277.344128) (xy 375.857855 -277.300091)
			(xy 375.894107 -277.26102) (xy 375.935778 -277.227789) (xy 375.981936 -277.20114) (xy 376.03155 -277.181668)
			(xy 376.083512 -277.169808) (xy 376.136662 -277.165825) (xy 376.189812 -277.169808) (xy 376.241774 -277.181668)
			(xy 376.291388 -277.20114) (xy 376.337546 -277.227789) (xy 376.379217 -277.26102) (xy 376.415469 -277.300091)
			(xy 376.445493 -277.344128) (xy 376.468619 -277.392149) (xy 376.484329 -277.443079) (xy 376.492272 -277.495783)
			(xy 376.49277 -277.522432) (xy 376.492272 -277.549081) (xy 376.720852 -277.549081) (xy 376.720852 -277.495783)
			(xy 376.728795 -277.443079) (xy 376.744505 -277.392149) (xy 376.767631 -277.344128) (xy 376.797655 -277.300091)
			(xy 376.833907 -277.26102) (xy 376.875578 -277.227789) (xy 376.921736 -277.20114) (xy 376.97135 -277.181668)
			(xy 377.023312 -277.169808) (xy 377.076462 -277.165825) (xy 377.129612 -277.169808) (xy 377.181574 -277.181668)
			(xy 377.231188 -277.20114) (xy 377.277346 -277.227789) (xy 377.319017 -277.26102) (xy 377.355269 -277.300091)
			(xy 377.385293 -277.344128) (xy 377.408419 -277.392149) (xy 377.424129 -277.443079) (xy 377.432072 -277.495783)
			(xy 377.43257 -277.522432) (xy 377.432072 -277.549081) (xy 377.660906 -277.549081) (xy 377.660906 -277.495783)
			(xy 377.668849 -277.443079) (xy 377.684559 -277.392149) (xy 377.707685 -277.344128) (xy 377.737709 -277.300091)
			(xy 377.773961 -277.26102) (xy 377.815632 -277.227789) (xy 377.86179 -277.20114) (xy 377.911404 -277.181668)
			(xy 377.963366 -277.169808) (xy 378.016516 -277.165825) (xy 378.069666 -277.169808) (xy 378.121628 -277.181668)
			(xy 378.171242 -277.20114) (xy 378.2174 -277.227789) (xy 378.259071 -277.26102) (xy 378.295323 -277.300091)
			(xy 378.325347 -277.344128) (xy 378.348473 -277.392149) (xy 378.364183 -277.443079) (xy 378.372126 -277.495783)
			(xy 378.372624 -277.522432) (xy 378.372126 -277.549081) (xy 378.600706 -277.549081) (xy 378.600706 -277.495783)
			(xy 378.608649 -277.443079) (xy 378.624359 -277.392149) (xy 378.647485 -277.344128) (xy 378.677509 -277.300091)
			(xy 378.713761 -277.26102) (xy 378.755432 -277.227789) (xy 378.80159 -277.20114) (xy 378.851204 -277.181668)
			(xy 378.903166 -277.169808) (xy 378.956316 -277.165825) (xy 379.009466 -277.169808) (xy 379.061428 -277.181668)
			(xy 379.111042 -277.20114) (xy 379.1572 -277.227789) (xy 379.198871 -277.26102) (xy 379.235123 -277.300091)
			(xy 379.265147 -277.344128) (xy 379.288273 -277.392149) (xy 379.303983 -277.443079) (xy 379.311926 -277.495783)
			(xy 379.312424 -277.522432) (xy 379.311926 -277.549081) (xy 379.540252 -277.549081) (xy 379.540252 -277.495783)
			(xy 379.548195 -277.443079) (xy 379.563905 -277.392149) (xy 379.587031 -277.344128) (xy 379.617055 -277.300091)
			(xy 379.653307 -277.26102) (xy 379.694978 -277.227789) (xy 379.741136 -277.20114) (xy 379.79075 -277.181668)
			(xy 379.842712 -277.169808) (xy 379.895862 -277.165825) (xy 379.949012 -277.169808) (xy 380.000974 -277.181668)
			(xy 380.050588 -277.20114) (xy 380.096746 -277.227789) (xy 380.138417 -277.26102) (xy 380.174669 -277.300091)
			(xy 380.204693 -277.344128) (xy 380.227819 -277.392149) (xy 380.243529 -277.443079) (xy 380.251472 -277.495783)
			(xy 380.25197 -277.522432) (xy 380.251472 -277.549081) (xy 380.480052 -277.549081) (xy 380.480052 -277.495783)
			(xy 380.487995 -277.443079) (xy 380.503705 -277.392149) (xy 380.526831 -277.344128) (xy 380.556855 -277.300091)
			(xy 380.593107 -277.26102) (xy 380.634778 -277.227789) (xy 380.680936 -277.20114) (xy 380.73055 -277.181668)
			(xy 380.782512 -277.169808) (xy 380.835662 -277.165825) (xy 380.888812 -277.169808) (xy 380.940774 -277.181668)
			(xy 380.990388 -277.20114) (xy 381.036546 -277.227789) (xy 381.078217 -277.26102) (xy 381.114469 -277.300091)
			(xy 381.144493 -277.344128) (xy 381.167619 -277.392149) (xy 381.183329 -277.443079) (xy 381.191272 -277.495783)
			(xy 381.19177 -277.522432) (xy 381.191272 -277.549081) (xy 381.183329 -277.601785) (xy 381.167619 -277.652715)
			(xy 381.144493 -277.700736) (xy 381.114469 -277.744773) (xy 381.078217 -277.783844) (xy 381.036546 -277.817075)
			(xy 380.990388 -277.843724) (xy 380.940774 -277.863196) (xy 380.888812 -277.875056) (xy 380.835662 -277.87904)
			(xy 380.782512 -277.875056) (xy 380.73055 -277.863196) (xy 380.680936 -277.843724) (xy 380.634778 -277.817075)
			(xy 380.593107 -277.783844) (xy 380.556855 -277.744773) (xy 380.526831 -277.700736) (xy 380.503705 -277.652715)
			(xy 380.487995 -277.601785) (xy 380.480052 -277.549081) (xy 380.251472 -277.549081) (xy 380.243529 -277.601785)
			(xy 380.227819 -277.652715) (xy 380.204693 -277.700736) (xy 380.174669 -277.744773) (xy 380.138417 -277.783844)
			(xy 380.096746 -277.817075) (xy 380.050588 -277.843724) (xy 380.000974 -277.863196) (xy 379.949012 -277.875056)
			(xy 379.895862 -277.87904) (xy 379.842712 -277.875056) (xy 379.79075 -277.863196) (xy 379.741136 -277.843724)
			(xy 379.694978 -277.817075) (xy 379.653307 -277.783844) (xy 379.617055 -277.744773) (xy 379.587031 -277.700736)
			(xy 379.563905 -277.652715) (xy 379.548195 -277.601785) (xy 379.540252 -277.549081) (xy 379.311926 -277.549081)
			(xy 379.303983 -277.601785) (xy 379.288273 -277.652715) (xy 379.265147 -277.700736) (xy 379.235123 -277.744773)
			(xy 379.198871 -277.783844) (xy 379.1572 -277.817075) (xy 379.111042 -277.843724) (xy 379.061428 -277.863196)
			(xy 379.009466 -277.875056) (xy 378.956316 -277.87904) (xy 378.903166 -277.875056) (xy 378.851204 -277.863196)
			(xy 378.80159 -277.843724) (xy 378.755432 -277.817075) (xy 378.713761 -277.783844) (xy 378.677509 -277.744773)
			(xy 378.647485 -277.700736) (xy 378.624359 -277.652715) (xy 378.608649 -277.601785) (xy 378.600706 -277.549081)
			(xy 378.372126 -277.549081) (xy 378.364183 -277.601785) (xy 378.348473 -277.652715) (xy 378.325347 -277.700736)
			(xy 378.295323 -277.744773) (xy 378.259071 -277.783844) (xy 378.2174 -277.817075) (xy 378.171242 -277.843724)
			(xy 378.121628 -277.863196) (xy 378.069666 -277.875056) (xy 378.016516 -277.87904) (xy 377.963366 -277.875056)
			(xy 377.911404 -277.863196) (xy 377.86179 -277.843724) (xy 377.815632 -277.817075) (xy 377.773961 -277.783844)
			(xy 377.737709 -277.744773) (xy 377.707685 -277.700736) (xy 377.684559 -277.652715) (xy 377.668849 -277.601785)
			(xy 377.660906 -277.549081) (xy 377.432072 -277.549081) (xy 377.424129 -277.601785) (xy 377.408419 -277.652715)
			(xy 377.385293 -277.700736) (xy 377.355269 -277.744773) (xy 377.319017 -277.783844) (xy 377.277346 -277.817075)
			(xy 377.231188 -277.843724) (xy 377.181574 -277.863196) (xy 377.129612 -277.875056) (xy 377.076462 -277.87904)
			(xy 377.023312 -277.875056) (xy 376.97135 -277.863196) (xy 376.921736 -277.843724) (xy 376.875578 -277.817075)
			(xy 376.833907 -277.783844) (xy 376.797655 -277.744773) (xy 376.767631 -277.700736) (xy 376.744505 -277.652715)
			(xy 376.728795 -277.601785) (xy 376.720852 -277.549081) (xy 376.492272 -277.549081) (xy 376.484329 -277.601785)
			(xy 376.468619 -277.652715) (xy 376.445493 -277.700736) (xy 376.415469 -277.744773) (xy 376.379217 -277.783844)
			(xy 376.337546 -277.817075) (xy 376.291388 -277.843724) (xy 376.241774 -277.863196) (xy 376.189812 -277.875056)
			(xy 376.136662 -277.87904) (xy 376.083512 -277.875056) (xy 376.03155 -277.863196) (xy 375.981936 -277.843724)
			(xy 375.935778 -277.817075) (xy 375.894107 -277.783844) (xy 375.857855 -277.744773) (xy 375.827831 -277.700736)
			(xy 375.804705 -277.652715) (xy 375.788995 -277.601785) (xy 375.781052 -277.549081) (xy 375.552472 -277.549081)
			(xy 375.544529 -277.601785) (xy 375.528819 -277.652715) (xy 375.505693 -277.700736) (xy 375.475669 -277.744773)
			(xy 375.439417 -277.783844) (xy 375.397746 -277.817075) (xy 375.351588 -277.843724) (xy 375.301974 -277.863196)
			(xy 375.250012 -277.875056) (xy 375.196862 -277.87904) (xy 375.143712 -277.875056) (xy 375.09175 -277.863196)
			(xy 375.042136 -277.843724) (xy 374.995978 -277.817075) (xy 374.954307 -277.783844) (xy 374.918055 -277.744773)
			(xy 374.888031 -277.700736) (xy 374.864905 -277.652715) (xy 374.849195 -277.601785) (xy 374.841252 -277.549081)
			(xy 374.612672 -277.549081) (xy 374.604729 -277.601785) (xy 374.589019 -277.652715) (xy 374.565893 -277.700736)
			(xy 374.535869 -277.744773) (xy 374.499617 -277.783844) (xy 374.457946 -277.817075) (xy 374.411788 -277.843724)
			(xy 374.362174 -277.863196) (xy 374.310212 -277.875056) (xy 374.257062 -277.87904) (xy 374.203912 -277.875056)
			(xy 374.15195 -277.863196) (xy 374.102336 -277.843724) (xy 374.056178 -277.817075) (xy 374.014507 -277.783844)
			(xy 373.978255 -277.744773) (xy 373.948231 -277.700736) (xy 373.925105 -277.652715) (xy 373.909395 -277.601785)
			(xy 373.901452 -277.549081) (xy 373.673126 -277.549081) (xy 373.665183 -277.601785) (xy 373.649473 -277.652715)
			(xy 373.626347 -277.700736) (xy 373.596323 -277.744773) (xy 373.560071 -277.783844) (xy 373.5184 -277.817075)
			(xy 373.472242 -277.843724) (xy 373.422628 -277.863196) (xy 373.370666 -277.875056) (xy 373.317516 -277.87904)
			(xy 373.264366 -277.875056) (xy 373.212404 -277.863196) (xy 373.16279 -277.843724) (xy 373.116632 -277.817075)
			(xy 373.074961 -277.783844) (xy 373.038709 -277.744773) (xy 373.008685 -277.700736) (xy 372.985559 -277.652715)
			(xy 372.969849 -277.601785) (xy 372.961906 -277.549081) (xy 372.733072 -277.549081) (xy 372.725129 -277.601785)
			(xy 372.709419 -277.652715) (xy 372.686293 -277.700736) (xy 372.656269 -277.744773) (xy 372.620017 -277.783844)
			(xy 372.578346 -277.817075) (xy 372.532188 -277.843724) (xy 372.482574 -277.863196) (xy 372.430612 -277.875056)
			(xy 372.377462 -277.87904) (xy 372.324312 -277.875056) (xy 372.27235 -277.863196) (xy 372.222736 -277.843724)
			(xy 372.176578 -277.817075) (xy 372.134907 -277.783844) (xy 372.098655 -277.744773) (xy 372.068631 -277.700736)
			(xy 372.045505 -277.652715) (xy 372.029795 -277.601785) (xy 372.021852 -277.549081) (xy 371.793272 -277.549081)
			(xy 371.785329 -277.601785) (xy 371.769619 -277.652715) (xy 371.746493 -277.700736) (xy 371.716469 -277.744773)
			(xy 371.680217 -277.783844) (xy 371.638546 -277.817075) (xy 371.592388 -277.843724) (xy 371.542774 -277.863196)
			(xy 371.490812 -277.875056) (xy 371.437662 -277.87904) (xy 371.384512 -277.875056) (xy 371.33255 -277.863196)
			(xy 371.282936 -277.843724) (xy 371.236778 -277.817075) (xy 371.195107 -277.783844) (xy 371.158855 -277.744773)
			(xy 371.128831 -277.700736) (xy 371.105705 -277.652715) (xy 371.089995 -277.601785) (xy 371.082052 -277.549081)
			(xy 370.853688 -277.549081) (xy 370.845783 -277.601531) (xy 370.830073 -277.652461) (xy 370.806947 -277.700482)
			(xy 370.776923 -277.744519) (xy 370.740671 -277.78359) (xy 370.699 -277.816821) (xy 370.652842 -277.84347)
			(xy 370.603228 -277.862942) (xy 370.551266 -277.874802) (xy 370.498116 -277.878786) (xy 370.444966 -277.874802)
			(xy 370.393004 -277.862942) (xy 370.34339 -277.84347) (xy 370.297232 -277.816821) (xy 370.255561 -277.78359)
			(xy 370.219309 -277.744519) (xy 370.189285 -277.700482) (xy 370.166159 -277.652461) (xy 370.150449 -277.601531)
			(xy 370.142506 -277.548827) (xy 369.913926 -277.548827) (xy 369.905983 -277.601531) (xy 369.890273 -277.652461)
			(xy 369.867147 -277.700482) (xy 369.837123 -277.744519) (xy 369.800871 -277.78359) (xy 369.7592 -277.816821)
			(xy 369.713042 -277.84347) (xy 369.663428 -277.862942) (xy 369.611466 -277.874802) (xy 369.558316 -277.878786)
			(xy 369.505166 -277.874802) (xy 369.453204 -277.862942) (xy 369.40359 -277.84347) (xy 369.357432 -277.816821)
			(xy 369.315761 -277.78359) (xy 369.279509 -277.744519) (xy 369.249485 -277.700482) (xy 369.226359 -277.652461)
			(xy 369.210649 -277.601531) (xy 369.202706 -277.548827) (xy 368.974126 -277.548827) (xy 368.966183 -277.601531)
			(xy 368.950473 -277.652461) (xy 368.927347 -277.700482) (xy 368.897323 -277.744519) (xy 368.861071 -277.78359)
			(xy 368.8194 -277.816821) (xy 368.773242 -277.84347) (xy 368.723628 -277.862942) (xy 368.671666 -277.874802)
			(xy 368.618516 -277.878786) (xy 368.565366 -277.874802) (xy 368.513404 -277.862942) (xy 368.46379 -277.84347)
			(xy 368.417632 -277.816821) (xy 368.375961 -277.78359) (xy 368.339709 -277.744519) (xy 368.309685 -277.700482)
			(xy 368.286559 -277.652461) (xy 368.270849 -277.601531) (xy 368.262906 -277.548827) (xy 368.034326 -277.548827)
			(xy 368.026383 -277.601531) (xy 368.010673 -277.652461) (xy 367.987547 -277.700482) (xy 367.957523 -277.744519)
			(xy 367.921271 -277.78359) (xy 367.8796 -277.816821) (xy 367.833442 -277.84347) (xy 367.783828 -277.862942)
			(xy 367.731866 -277.874802) (xy 367.678716 -277.878786) (xy 367.625566 -277.874802) (xy 367.573604 -277.862942)
			(xy 367.52399 -277.84347) (xy 367.477832 -277.816821) (xy 367.436161 -277.78359) (xy 367.399909 -277.744519)
			(xy 367.369885 -277.700482) (xy 367.346759 -277.652461) (xy 367.331049 -277.601531) (xy 367.323106 -277.548827)
			(xy 367.094531 -277.548827) (xy 367.094526 -277.549081) (xy 367.086583 -277.601785) (xy 367.070873 -277.652715)
			(xy 367.047747 -277.700736) (xy 367.017723 -277.744773) (xy 366.981471 -277.783844) (xy 366.9398 -277.817075)
			(xy 366.893642 -277.843724) (xy 366.844028 -277.863196) (xy 366.792066 -277.875056) (xy 366.738916 -277.87904)
			(xy 366.685766 -277.875056) (xy 366.633804 -277.863196) (xy 366.58419 -277.843724) (xy 366.538032 -277.817075)
			(xy 366.496361 -277.783844) (xy 366.460109 -277.744773) (xy 366.430085 -277.700736) (xy 366.406959 -277.652715)
			(xy 366.391249 -277.601785) (xy 366.383306 -277.549081) (xy 366.154688 -277.549081) (xy 366.146783 -277.601531)
			(xy 366.131073 -277.652461) (xy 366.107947 -277.700482) (xy 366.077923 -277.744519) (xy 366.041671 -277.78359)
			(xy 366 -277.816821) (xy 365.953842 -277.84347) (xy 365.904228 -277.862942) (xy 365.852266 -277.874802)
			(xy 365.799116 -277.878786) (xy 365.745966 -277.874802) (xy 365.694004 -277.862942) (xy 365.64439 -277.84347)
			(xy 365.598232 -277.816821) (xy 365.556561 -277.78359) (xy 365.520309 -277.744519) (xy 365.490285 -277.700482)
			(xy 365.467159 -277.652461) (xy 365.451449 -277.601531) (xy 365.443506 -277.548827) (xy 365.214677 -277.548827)
			(xy 365.214672 -277.549081) (xy 365.206729 -277.601785) (xy 365.191019 -277.652715) (xy 365.167893 -277.700736)
			(xy 365.137869 -277.744773) (xy 365.101617 -277.783844) (xy 365.059946 -277.817075) (xy 365.013788 -277.843724)
			(xy 364.964174 -277.863196) (xy 364.912212 -277.875056) (xy 364.859062 -277.87904) (xy 364.805912 -277.875056)
			(xy 364.75395 -277.863196) (xy 364.704336 -277.843724) (xy 364.658178 -277.817075) (xy 364.616507 -277.783844)
			(xy 364.580255 -277.744773) (xy 364.550231 -277.700736) (xy 364.527105 -277.652715) (xy 364.511395 -277.601785)
			(xy 364.503452 -277.549081) (xy 364.275135 -277.549081) (xy 364.275127 -277.549509) (xy 364.266778 -277.60353)
			(xy 364.250272 -277.655641) (xy 364.225997 -277.704618) (xy 364.194523 -277.74931) (xy 364.15659 -277.788668)
			(xy 364.135162 -277.805642) (xy 364.123981 -277.814812) (xy 364.106835 -277.83808) (xy 364.096884 -277.865215)
			(xy 364.094923 -277.894052) (xy 364.10111 -277.922285) (xy 364.11495 -277.947659) (xy 364.124748 -277.958296)
			(xy 364.19917 -278.032718) (xy 364.231936 -278.016716) (xy 364.256525 -278.005184) (xy 364.308329 -277.988881)
			(xy 364.362008 -277.980639) (xy 364.389162 -277.98014) (xy 364.417148 -277.980658) (xy 364.472431 -277.989409)
			(xy 364.525665 -278.006702) (xy 364.575537 -278.032111) (xy 364.620819 -278.06501) (xy 364.660396 -278.104589)
			(xy 364.693294 -278.149872) (xy 364.718702 -278.199745) (xy 364.735993 -278.252978) (xy 364.744743 -278.308262)
			(xy 364.74527 -278.336248) (xy 364.744766 -278.362897) (xy 364.973352 -278.362897) (xy 364.973352 -278.309599)
			(xy 364.981295 -278.256895) (xy 364.997005 -278.205965) (xy 365.020131 -278.157944) (xy 365.050155 -278.113907)
			(xy 365.086407 -278.074836) (xy 365.128078 -278.041605) (xy 365.174236 -278.014956) (xy 365.22385 -277.995484)
			(xy 365.275812 -277.983624) (xy 365.328962 -277.979641) (xy 365.382112 -277.983624) (xy 365.434074 -277.995484)
			(xy 365.483688 -278.014956) (xy 365.529846 -278.041605) (xy 365.571517 -278.074836) (xy 365.607769 -278.113907)
			(xy 365.637793 -278.157944) (xy 365.660919 -278.205965) (xy 365.676629 -278.256895) (xy 365.684572 -278.309599)
			(xy 365.68507 -278.336248) (xy 365.684572 -278.362897) (xy 365.913152 -278.362897) (xy 365.913152 -278.309599)
			(xy 365.921095 -278.256895) (xy 365.936805 -278.205965) (xy 365.959931 -278.157944) (xy 365.989955 -278.113907)
			(xy 366.026207 -278.074836) (xy 366.067878 -278.041605) (xy 366.114036 -278.014956) (xy 366.16365 -277.995484)
			(xy 366.215612 -277.983624) (xy 366.268762 -277.979641) (xy 366.321912 -277.983624) (xy 366.373874 -277.995484)
			(xy 366.423488 -278.014956) (xy 366.469646 -278.041605) (xy 366.511317 -278.074836) (xy 366.547569 -278.113907)
			(xy 366.577593 -278.157944) (xy 366.600719 -278.205965) (xy 366.616429 -278.256895) (xy 366.624372 -278.309599)
			(xy 366.62487 -278.336248) (xy 366.624372 -278.362897) (xy 366.624334 -278.363151) (xy 366.853206 -278.363151)
			(xy 366.853206 -278.309853) (xy 366.861149 -278.257149) (xy 366.876859 -278.206219) (xy 366.899985 -278.158198)
			(xy 366.930009 -278.114161) (xy 366.966261 -278.07509) (xy 367.007932 -278.041859) (xy 367.05409 -278.01521)
			(xy 367.103704 -277.995738) (xy 367.155666 -277.983878) (xy 367.208816 -277.979895) (xy 367.261966 -277.983878)
			(xy 367.313928 -277.995738) (xy 367.363542 -278.01521) (xy 367.4097 -278.041859) (xy 367.451371 -278.07509)
			(xy 367.487623 -278.114161) (xy 367.517647 -278.158198) (xy 367.540773 -278.206219) (xy 367.556483 -278.257149)
			(xy 367.564426 -278.309853) (xy 367.564924 -278.336502) (xy 367.564431 -278.362897) (xy 368.732552 -278.362897)
			(xy 368.732552 -278.309599) (xy 368.740495 -278.256895) (xy 368.756205 -278.205965) (xy 368.779331 -278.157944)
			(xy 368.809355 -278.113907) (xy 368.845607 -278.074836) (xy 368.887278 -278.041605) (xy 368.933436 -278.014956)
			(xy 368.98305 -277.995484) (xy 369.035012 -277.983624) (xy 369.088162 -277.979641) (xy 369.141312 -277.983624)
			(xy 369.193274 -277.995484) (xy 369.242888 -278.014956) (xy 369.289046 -278.041605) (xy 369.330717 -278.074836)
			(xy 369.366969 -278.113907) (xy 369.396993 -278.157944) (xy 369.420119 -278.205965) (xy 369.435829 -278.256895)
			(xy 369.443772 -278.309599) (xy 369.44427 -278.336248) (xy 369.443772 -278.362897) (xy 369.443734 -278.363151)
			(xy 369.672352 -278.363151) (xy 369.672352 -278.309853) (xy 369.680295 -278.257149) (xy 369.696005 -278.206219)
			(xy 369.719131 -278.158198) (xy 369.749155 -278.114161) (xy 369.785407 -278.07509) (xy 369.827078 -278.041859)
			(xy 369.873236 -278.01521) (xy 369.92285 -277.995738) (xy 369.974812 -277.983878) (xy 370.027962 -277.979895)
			(xy 370.081112 -277.983878) (xy 370.133074 -277.995738) (xy 370.182688 -278.01521) (xy 370.228846 -278.041859)
			(xy 370.270517 -278.07509) (xy 370.306769 -278.114161) (xy 370.336793 -278.158198) (xy 370.359919 -278.206219)
			(xy 370.375629 -278.257149) (xy 370.383572 -278.309853) (xy 370.38407 -278.336502) (xy 370.383572 -278.363151)
			(xy 370.612406 -278.363151) (xy 370.612406 -278.309853) (xy 370.620349 -278.257149) (xy 370.636059 -278.206219)
			(xy 370.659185 -278.158198) (xy 370.689209 -278.114161) (xy 370.725461 -278.07509) (xy 370.767132 -278.041859)
			(xy 370.81329 -278.01521) (xy 370.862904 -277.995738) (xy 370.914866 -277.983878) (xy 370.968016 -277.979895)
			(xy 371.021166 -277.983878) (xy 371.073128 -277.995738) (xy 371.122742 -278.01521) (xy 371.1689 -278.041859)
			(xy 371.210571 -278.07509) (xy 371.246823 -278.114161) (xy 371.276847 -278.158198) (xy 371.299973 -278.206219)
			(xy 371.315683 -278.257149) (xy 371.323626 -278.309853) (xy 371.324124 -278.336502) (xy 371.323626 -278.363151)
			(xy 372.492006 -278.363151) (xy 372.492006 -278.309853) (xy 372.499949 -278.257149) (xy 372.515659 -278.206219)
			(xy 372.538785 -278.158198) (xy 372.568809 -278.114161) (xy 372.605061 -278.07509) (xy 372.646732 -278.041859)
			(xy 372.69289 -278.01521) (xy 372.742504 -277.995738) (xy 372.794466 -277.983878) (xy 372.847616 -277.979895)
			(xy 372.900766 -277.983878) (xy 372.952728 -277.995738) (xy 373.002342 -278.01521) (xy 373.0485 -278.041859)
			(xy 373.090171 -278.07509) (xy 373.126423 -278.114161) (xy 373.156447 -278.158198) (xy 373.179573 -278.206219)
			(xy 373.195283 -278.257149) (xy 373.203226 -278.309853) (xy 373.203724 -278.336502) (xy 373.203226 -278.363151)
			(xy 373.431806 -278.363151) (xy 373.431806 -278.309853) (xy 373.439749 -278.257149) (xy 373.455459 -278.206219)
			(xy 373.478585 -278.158198) (xy 373.508609 -278.114161) (xy 373.544861 -278.07509) (xy 373.586532 -278.041859)
			(xy 373.63269 -278.01521) (xy 373.682304 -277.995738) (xy 373.734266 -277.983878) (xy 373.787416 -277.979895)
			(xy 373.840566 -277.983878) (xy 373.892528 -277.995738) (xy 373.942142 -278.01521) (xy 373.9883 -278.041859)
			(xy 374.029971 -278.07509) (xy 374.066223 -278.114161) (xy 374.096247 -278.158198) (xy 374.119373 -278.206219)
			(xy 374.135083 -278.257149) (xy 374.143026 -278.309853) (xy 374.143524 -278.336502) (xy 374.143026 -278.363151)
			(xy 374.371606 -278.363151) (xy 374.371606 -278.309853) (xy 374.379549 -278.257149) (xy 374.395259 -278.206219)
			(xy 374.418385 -278.158198) (xy 374.448409 -278.114161) (xy 374.484661 -278.07509) (xy 374.526332 -278.041859)
			(xy 374.57249 -278.01521) (xy 374.622104 -277.995738) (xy 374.674066 -277.983878) (xy 374.727216 -277.979895)
			(xy 374.780366 -277.983878) (xy 374.832328 -277.995738) (xy 374.881942 -278.01521) (xy 374.9281 -278.041859)
			(xy 374.969771 -278.07509) (xy 375.006023 -278.114161) (xy 375.036047 -278.158198) (xy 375.059173 -278.206219)
			(xy 375.074883 -278.257149) (xy 375.082826 -278.309853) (xy 375.083324 -278.336502) (xy 375.082826 -278.363151)
			(xy 375.311406 -278.363151) (xy 375.311406 -278.309853) (xy 375.319349 -278.257149) (xy 375.335059 -278.206219)
			(xy 375.358185 -278.158198) (xy 375.388209 -278.114161) (xy 375.424461 -278.07509) (xy 375.466132 -278.041859)
			(xy 375.51229 -278.01521) (xy 375.561904 -277.995738) (xy 375.613866 -277.983878) (xy 375.667016 -277.979895)
			(xy 375.720166 -277.983878) (xy 375.772128 -277.995738) (xy 375.821742 -278.01521) (xy 375.8679 -278.041859)
			(xy 375.909571 -278.07509) (xy 375.945823 -278.114161) (xy 375.975847 -278.158198) (xy 375.998973 -278.206219)
			(xy 376.014683 -278.257149) (xy 376.022626 -278.309853) (xy 376.023124 -278.336502) (xy 376.022626 -278.363151)
			(xy 376.250952 -278.363151) (xy 376.250952 -278.309853) (xy 376.258895 -278.257149) (xy 376.274605 -278.206219)
			(xy 376.297731 -278.158198) (xy 376.327755 -278.114161) (xy 376.364007 -278.07509) (xy 376.405678 -278.041859)
			(xy 376.451836 -278.01521) (xy 376.50145 -277.995738) (xy 376.553412 -277.983878) (xy 376.606562 -277.979895)
			(xy 376.659712 -277.983878) (xy 376.711674 -277.995738) (xy 376.761288 -278.01521) (xy 376.807446 -278.041859)
			(xy 376.849117 -278.07509) (xy 376.885369 -278.114161) (xy 376.915393 -278.158198) (xy 376.938519 -278.206219)
			(xy 376.954229 -278.257149) (xy 376.962172 -278.309853) (xy 376.96267 -278.336502) (xy 376.962172 -278.363151)
			(xy 377.191006 -278.363151) (xy 377.191006 -278.309853) (xy 377.198949 -278.257149) (xy 377.214659 -278.206219)
			(xy 377.237785 -278.158198) (xy 377.267809 -278.114161) (xy 377.304061 -278.07509) (xy 377.345732 -278.041859)
			(xy 377.39189 -278.01521) (xy 377.441504 -277.995738) (xy 377.493466 -277.983878) (xy 377.546616 -277.979895)
			(xy 377.599766 -277.983878) (xy 377.651728 -277.995738) (xy 377.701342 -278.01521) (xy 377.7475 -278.041859)
			(xy 377.789171 -278.07509) (xy 377.825423 -278.114161) (xy 377.855447 -278.158198) (xy 377.878573 -278.206219)
			(xy 377.894283 -278.257149) (xy 377.902226 -278.309853) (xy 377.902724 -278.336502) (xy 377.902226 -278.363151)
			(xy 378.130552 -278.363151) (xy 378.130552 -278.309853) (xy 378.138495 -278.257149) (xy 378.154205 -278.206219)
			(xy 378.177331 -278.158198) (xy 378.207355 -278.114161) (xy 378.243607 -278.07509) (xy 378.285278 -278.041859)
			(xy 378.331436 -278.01521) (xy 378.38105 -277.995738) (xy 378.433012 -277.983878) (xy 378.486162 -277.979895)
			(xy 378.539312 -277.983878) (xy 378.591274 -277.995738) (xy 378.640888 -278.01521) (xy 378.687046 -278.041859)
			(xy 378.728717 -278.07509) (xy 378.764969 -278.114161) (xy 378.794993 -278.158198) (xy 378.818119 -278.206219)
			(xy 378.833829 -278.257149) (xy 378.841772 -278.309853) (xy 378.84227 -278.336502) (xy 378.841772 -278.363151)
			(xy 379.070606 -278.363151) (xy 379.070606 -278.309853) (xy 379.078549 -278.257149) (xy 379.094259 -278.206219)
			(xy 379.117385 -278.158198) (xy 379.147409 -278.114161) (xy 379.183661 -278.07509) (xy 379.225332 -278.041859)
			(xy 379.27149 -278.01521) (xy 379.321104 -277.995738) (xy 379.373066 -277.983878) (xy 379.426216 -277.979895)
			(xy 379.479366 -277.983878) (xy 379.531328 -277.995738) (xy 379.580942 -278.01521) (xy 379.6271 -278.041859)
			(xy 379.668771 -278.07509) (xy 379.705023 -278.114161) (xy 379.735047 -278.158198) (xy 379.758173 -278.206219)
			(xy 379.773883 -278.257149) (xy 379.781826 -278.309853) (xy 379.782324 -278.336502) (xy 379.781826 -278.363151)
			(xy 380.010406 -278.363151) (xy 380.010406 -278.309853) (xy 380.018349 -278.257149) (xy 380.034059 -278.206219)
			(xy 380.057185 -278.158198) (xy 380.087209 -278.114161) (xy 380.123461 -278.07509) (xy 380.165132 -278.041859)
			(xy 380.21129 -278.01521) (xy 380.260904 -277.995738) (xy 380.312866 -277.983878) (xy 380.366016 -277.979895)
			(xy 380.419166 -277.983878) (xy 380.471128 -277.995738) (xy 380.520742 -278.01521) (xy 380.5669 -278.041859)
			(xy 380.608571 -278.07509) (xy 380.644823 -278.114161) (xy 380.674847 -278.158198) (xy 380.697973 -278.206219)
			(xy 380.713683 -278.257149) (xy 380.721626 -278.309853) (xy 380.722124 -278.336502) (xy 380.721626 -278.363151)
			(xy 380.950206 -278.363151) (xy 380.950206 -278.309853) (xy 380.958149 -278.257149) (xy 380.973859 -278.206219)
			(xy 380.996985 -278.158198) (xy 381.027009 -278.114161) (xy 381.063261 -278.07509) (xy 381.104932 -278.041859)
			(xy 381.15109 -278.01521) (xy 381.200704 -277.995738) (xy 381.252666 -277.983878) (xy 381.305816 -277.979895)
			(xy 381.358966 -277.983878) (xy 381.410928 -277.995738) (xy 381.460542 -278.01521) (xy 381.5067 -278.041859)
			(xy 381.548371 -278.07509) (xy 381.584623 -278.114161) (xy 381.614647 -278.158198) (xy 381.637773 -278.206219)
			(xy 381.653483 -278.257149) (xy 381.661426 -278.309853) (xy 381.661924 -278.336502) (xy 381.661426 -278.363151)
			(xy 381.653483 -278.415855) (xy 381.637773 -278.466785) (xy 381.614647 -278.514806) (xy 381.584623 -278.558843)
			(xy 381.548371 -278.597914) (xy 381.5067 -278.631145) (xy 381.460542 -278.657794) (xy 381.410928 -278.677266)
			(xy 381.358966 -278.689126) (xy 381.305816 -278.69311) (xy 381.252666 -278.689126) (xy 381.200704 -278.677266)
			(xy 381.15109 -278.657794) (xy 381.104932 -278.631145) (xy 381.063261 -278.597914) (xy 381.027009 -278.558843)
			(xy 380.996985 -278.514806) (xy 380.973859 -278.466785) (xy 380.958149 -278.415855) (xy 380.950206 -278.363151)
			(xy 380.721626 -278.363151) (xy 380.713683 -278.415855) (xy 380.697973 -278.466785) (xy 380.674847 -278.514806)
			(xy 380.644823 -278.558843) (xy 380.608571 -278.597914) (xy 380.5669 -278.631145) (xy 380.520742 -278.657794)
			(xy 380.471128 -278.677266) (xy 380.419166 -278.689126) (xy 380.366016 -278.69311) (xy 380.312866 -278.689126)
			(xy 380.260904 -278.677266) (xy 380.21129 -278.657794) (xy 380.165132 -278.631145) (xy 380.123461 -278.597914)
			(xy 380.087209 -278.558843) (xy 380.057185 -278.514806) (xy 380.034059 -278.466785) (xy 380.018349 -278.415855)
			(xy 380.010406 -278.363151) (xy 379.781826 -278.363151) (xy 379.773883 -278.415855) (xy 379.758173 -278.466785)
			(xy 379.735047 -278.514806) (xy 379.705023 -278.558843) (xy 379.668771 -278.597914) (xy 379.6271 -278.631145)
			(xy 379.580942 -278.657794) (xy 379.531328 -278.677266) (xy 379.479366 -278.689126) (xy 379.426216 -278.69311)
			(xy 379.373066 -278.689126) (xy 379.321104 -278.677266) (xy 379.27149 -278.657794) (xy 379.225332 -278.631145)
			(xy 379.183661 -278.597914) (xy 379.147409 -278.558843) (xy 379.117385 -278.514806) (xy 379.094259 -278.466785)
			(xy 379.078549 -278.415855) (xy 379.070606 -278.363151) (xy 378.841772 -278.363151) (xy 378.833829 -278.415855)
			(xy 378.818119 -278.466785) (xy 378.794993 -278.514806) (xy 378.764969 -278.558843) (xy 378.728717 -278.597914)
			(xy 378.687046 -278.631145) (xy 378.640888 -278.657794) (xy 378.591274 -278.677266) (xy 378.539312 -278.689126)
			(xy 378.486162 -278.69311) (xy 378.433012 -278.689126) (xy 378.38105 -278.677266) (xy 378.331436 -278.657794)
			(xy 378.285278 -278.631145) (xy 378.243607 -278.597914) (xy 378.207355 -278.558843) (xy 378.177331 -278.514806)
			(xy 378.154205 -278.466785) (xy 378.138495 -278.415855) (xy 378.130552 -278.363151) (xy 377.902226 -278.363151)
			(xy 377.894283 -278.415855) (xy 377.878573 -278.466785) (xy 377.855447 -278.514806) (xy 377.825423 -278.558843)
			(xy 377.789171 -278.597914) (xy 377.7475 -278.631145) (xy 377.701342 -278.657794) (xy 377.651728 -278.677266)
			(xy 377.599766 -278.689126) (xy 377.546616 -278.69311) (xy 377.493466 -278.689126) (xy 377.441504 -278.677266)
			(xy 377.39189 -278.657794) (xy 377.345732 -278.631145) (xy 377.304061 -278.597914) (xy 377.267809 -278.558843)
			(xy 377.237785 -278.514806) (xy 377.214659 -278.466785) (xy 377.198949 -278.415855) (xy 377.191006 -278.363151)
			(xy 376.962172 -278.363151) (xy 376.954229 -278.415855) (xy 376.938519 -278.466785) (xy 376.915393 -278.514806)
			(xy 376.885369 -278.558843) (xy 376.849117 -278.597914) (xy 376.807446 -278.631145) (xy 376.761288 -278.657794)
			(xy 376.711674 -278.677266) (xy 376.659712 -278.689126) (xy 376.606562 -278.69311) (xy 376.553412 -278.689126)
			(xy 376.50145 -278.677266) (xy 376.451836 -278.657794) (xy 376.405678 -278.631145) (xy 376.364007 -278.597914)
			(xy 376.327755 -278.558843) (xy 376.297731 -278.514806) (xy 376.274605 -278.466785) (xy 376.258895 -278.415855)
			(xy 376.250952 -278.363151) (xy 376.022626 -278.363151) (xy 376.014683 -278.415855) (xy 375.998973 -278.466785)
			(xy 375.975847 -278.514806) (xy 375.945823 -278.558843) (xy 375.909571 -278.597914) (xy 375.8679 -278.631145)
			(xy 375.821742 -278.657794) (xy 375.772128 -278.677266) (xy 375.720166 -278.689126) (xy 375.667016 -278.69311)
			(xy 375.613866 -278.689126) (xy 375.561904 -278.677266) (xy 375.51229 -278.657794) (xy 375.466132 -278.631145)
			(xy 375.424461 -278.597914) (xy 375.388209 -278.558843) (xy 375.358185 -278.514806) (xy 375.335059 -278.466785)
			(xy 375.319349 -278.415855) (xy 375.311406 -278.363151) (xy 375.082826 -278.363151) (xy 375.074883 -278.415855)
			(xy 375.059173 -278.466785) (xy 375.036047 -278.514806) (xy 375.006023 -278.558843) (xy 374.969771 -278.597914)
			(xy 374.9281 -278.631145) (xy 374.881942 -278.657794) (xy 374.832328 -278.677266) (xy 374.780366 -278.689126)
			(xy 374.727216 -278.69311) (xy 374.674066 -278.689126) (xy 374.622104 -278.677266) (xy 374.57249 -278.657794)
			(xy 374.526332 -278.631145) (xy 374.484661 -278.597914) (xy 374.448409 -278.558843) (xy 374.418385 -278.514806)
			(xy 374.395259 -278.466785) (xy 374.379549 -278.415855) (xy 374.371606 -278.363151) (xy 374.143026 -278.363151)
			(xy 374.135083 -278.415855) (xy 374.119373 -278.466785) (xy 374.096247 -278.514806) (xy 374.066223 -278.558843)
			(xy 374.029971 -278.597914) (xy 373.9883 -278.631145) (xy 373.942142 -278.657794) (xy 373.892528 -278.677266)
			(xy 373.840566 -278.689126) (xy 373.787416 -278.69311) (xy 373.734266 -278.689126) (xy 373.682304 -278.677266)
			(xy 373.63269 -278.657794) (xy 373.586532 -278.631145) (xy 373.544861 -278.597914) (xy 373.508609 -278.558843)
			(xy 373.478585 -278.514806) (xy 373.455459 -278.466785) (xy 373.439749 -278.415855) (xy 373.431806 -278.363151)
			(xy 373.203226 -278.363151) (xy 373.195283 -278.415855) (xy 373.179573 -278.466785) (xy 373.156447 -278.514806)
			(xy 373.126423 -278.558843) (xy 373.090171 -278.597914) (xy 373.0485 -278.631145) (xy 373.002342 -278.657794)
			(xy 372.952728 -278.677266) (xy 372.900766 -278.689126) (xy 372.847616 -278.69311) (xy 372.794466 -278.689126)
			(xy 372.742504 -278.677266) (xy 372.69289 -278.657794) (xy 372.646732 -278.631145) (xy 372.605061 -278.597914)
			(xy 372.568809 -278.558843) (xy 372.538785 -278.514806) (xy 372.515659 -278.466785) (xy 372.499949 -278.415855)
			(xy 372.492006 -278.363151) (xy 371.323626 -278.363151) (xy 371.315683 -278.415855) (xy 371.299973 -278.466785)
			(xy 371.276847 -278.514806) (xy 371.246823 -278.558843) (xy 371.210571 -278.597914) (xy 371.1689 -278.631145)
			(xy 371.122742 -278.657794) (xy 371.073128 -278.677266) (xy 371.021166 -278.689126) (xy 370.968016 -278.69311)
			(xy 370.914866 -278.689126) (xy 370.862904 -278.677266) (xy 370.81329 -278.657794) (xy 370.767132 -278.631145)
			(xy 370.725461 -278.597914) (xy 370.689209 -278.558843) (xy 370.659185 -278.514806) (xy 370.636059 -278.466785)
			(xy 370.620349 -278.415855) (xy 370.612406 -278.363151) (xy 370.383572 -278.363151) (xy 370.375629 -278.415855)
			(xy 370.359919 -278.466785) (xy 370.336793 -278.514806) (xy 370.306769 -278.558843) (xy 370.270517 -278.597914)
			(xy 370.228846 -278.631145) (xy 370.182688 -278.657794) (xy 370.133074 -278.677266) (xy 370.081112 -278.689126)
			(xy 370.027962 -278.69311) (xy 369.974812 -278.689126) (xy 369.92285 -278.677266) (xy 369.873236 -278.657794)
			(xy 369.827078 -278.631145) (xy 369.785407 -278.597914) (xy 369.749155 -278.558843) (xy 369.719131 -278.514806)
			(xy 369.696005 -278.466785) (xy 369.680295 -278.415855) (xy 369.672352 -278.363151) (xy 369.443734 -278.363151)
			(xy 369.435829 -278.415601) (xy 369.420119 -278.466531) (xy 369.396993 -278.514552) (xy 369.366969 -278.558589)
			(xy 369.330717 -278.59766) (xy 369.289046 -278.630891) (xy 369.242888 -278.65754) (xy 369.193274 -278.677012)
			(xy 369.141312 -278.688872) (xy 369.088162 -278.692856) (xy 369.035012 -278.688872) (xy 368.98305 -278.677012)
			(xy 368.933436 -278.65754) (xy 368.887278 -278.630891) (xy 368.845607 -278.59766) (xy 368.809355 -278.558589)
			(xy 368.779331 -278.514552) (xy 368.756205 -278.466531) (xy 368.740495 -278.415601) (xy 368.732552 -278.362897)
			(xy 367.564431 -278.362897) (xy 367.564426 -278.363151) (xy 367.556483 -278.415855) (xy 367.540773 -278.466785)
			(xy 367.517647 -278.514806) (xy 367.487623 -278.558843) (xy 367.451371 -278.597914) (xy 367.4097 -278.631145)
			(xy 367.363542 -278.657794) (xy 367.313928 -278.677266) (xy 367.261966 -278.689126) (xy 367.208816 -278.69311)
			(xy 367.155666 -278.689126) (xy 367.103704 -278.677266) (xy 367.05409 -278.657794) (xy 367.007932 -278.631145)
			(xy 366.966261 -278.597914) (xy 366.930009 -278.558843) (xy 366.899985 -278.514806) (xy 366.876859 -278.466785)
			(xy 366.861149 -278.415855) (xy 366.853206 -278.363151) (xy 366.624334 -278.363151) (xy 366.616429 -278.415601)
			(xy 366.600719 -278.466531) (xy 366.577593 -278.514552) (xy 366.547569 -278.558589) (xy 366.511317 -278.59766)
			(xy 366.469646 -278.630891) (xy 366.423488 -278.65754) (xy 366.373874 -278.677012) (xy 366.321912 -278.688872)
			(xy 366.268762 -278.692856) (xy 366.215612 -278.688872) (xy 366.16365 -278.677012) (xy 366.114036 -278.65754)
			(xy 366.067878 -278.630891) (xy 366.026207 -278.59766) (xy 365.989955 -278.558589) (xy 365.959931 -278.514552)
			(xy 365.936805 -278.466531) (xy 365.921095 -278.415601) (xy 365.913152 -278.362897) (xy 365.684572 -278.362897)
			(xy 365.676629 -278.415601) (xy 365.660919 -278.466531) (xy 365.637793 -278.514552) (xy 365.607769 -278.558589)
			(xy 365.571517 -278.59766) (xy 365.529846 -278.630891) (xy 365.483688 -278.65754) (xy 365.434074 -278.677012)
			(xy 365.382112 -278.688872) (xy 365.328962 -278.692856) (xy 365.275812 -278.688872) (xy 365.22385 -278.677012)
			(xy 365.174236 -278.65754) (xy 365.128078 -278.630891) (xy 365.086407 -278.59766) (xy 365.050155 -278.558589)
			(xy 365.020131 -278.514552) (xy 364.997005 -278.466531) (xy 364.981295 -278.415601) (xy 364.973352 -278.362897)
			(xy 364.744766 -278.362897) (xy 364.744756 -278.363401) (xy 364.736507 -278.417076) (xy 364.720208 -278.468878)
			(xy 364.708694 -278.493474) (xy 364.692692 -278.52624) (xy 364.950248 -278.783796) (xy 364.950248 -278.803862)
			(xy 364.983268 -278.816308) (xy 365.008456 -278.8262) (xy 365.055748 -278.852499) (xy 365.098517 -278.88565)
			(xy 365.135777 -278.924891) (xy 365.16667 -278.969318) (xy 365.190486 -279.017908) (xy 365.206674 -279.069542)
			(xy 365.214864 -279.123031) (xy 365.214866 -279.176967) (xy 365.443506 -279.176967) (xy 365.443506 -279.123669)
			(xy 365.451449 -279.070965) (xy 365.467159 -279.020035) (xy 365.490285 -278.972014) (xy 365.520309 -278.927977)
			(xy 365.556561 -278.888906) (xy 365.598232 -278.855675) (xy 365.64439 -278.829026) (xy 365.694004 -278.809554)
			(xy 365.745966 -278.797694) (xy 365.799116 -278.793711) (xy 365.852266 -278.797694) (xy 365.904228 -278.809554)
			(xy 365.953842 -278.829026) (xy 366 -278.855675) (xy 366.041671 -278.888906) (xy 366.077923 -278.927977)
			(xy 366.107947 -278.972014) (xy 366.131073 -279.020035) (xy 366.146783 -279.070965) (xy 366.154726 -279.123669)
			(xy 366.155224 -279.150318) (xy 366.154726 -279.176967) (xy 367.322852 -279.176967) (xy 367.322852 -279.123669)
			(xy 367.330795 -279.070965) (xy 367.346505 -279.020035) (xy 367.369631 -278.972014) (xy 367.399655 -278.927977)
			(xy 367.435907 -278.888906) (xy 367.477578 -278.855675) (xy 367.523736 -278.829026) (xy 367.57335 -278.809554)
			(xy 367.625312 -278.797694) (xy 367.678462 -278.793711) (xy 367.731612 -278.797694) (xy 367.783574 -278.809554)
			(xy 367.833188 -278.829026) (xy 367.879346 -278.855675) (xy 367.921017 -278.888906) (xy 367.957269 -278.927977)
			(xy 367.987293 -278.972014) (xy 368.010419 -279.020035) (xy 368.026129 -279.070965) (xy 368.034072 -279.123669)
			(xy 368.03457 -279.150318) (xy 368.034072 -279.176967) (xy 368.262906 -279.176967) (xy 368.262906 -279.123669)
			(xy 368.270849 -279.070965) (xy 368.286559 -279.020035) (xy 368.309685 -278.972014) (xy 368.339709 -278.927977)
			(xy 368.375961 -278.888906) (xy 368.417632 -278.855675) (xy 368.46379 -278.829026) (xy 368.513404 -278.809554)
			(xy 368.565366 -278.797694) (xy 368.618516 -278.793711) (xy 368.671666 -278.797694) (xy 368.723628 -278.809554)
			(xy 368.773242 -278.829026) (xy 368.8194 -278.855675) (xy 368.861071 -278.888906) (xy 368.897323 -278.927977)
			(xy 368.927347 -278.972014) (xy 368.950473 -279.020035) (xy 368.966183 -279.070965) (xy 368.974126 -279.123669)
			(xy 368.974624 -279.150318) (xy 368.974126 -279.176967) (xy 369.202452 -279.176967) (xy 369.202452 -279.123669)
			(xy 369.210395 -279.070965) (xy 369.226105 -279.020035) (xy 369.249231 -278.972014) (xy 369.279255 -278.927977)
			(xy 369.315507 -278.888906) (xy 369.357178 -278.855675) (xy 369.403336 -278.829026) (xy 369.45295 -278.809554)
			(xy 369.504912 -278.797694) (xy 369.558062 -278.793711) (xy 369.611212 -278.797694) (xy 369.663174 -278.809554)
			(xy 369.712788 -278.829026) (xy 369.758946 -278.855675) (xy 369.800617 -278.888906) (xy 369.836869 -278.927977)
			(xy 369.866893 -278.972014) (xy 369.890019 -279.020035) (xy 369.905729 -279.070965) (xy 369.913672 -279.123669)
			(xy 369.91417 -279.150318) (xy 369.913672 -279.176967) (xy 370.142252 -279.176967) (xy 370.142252 -279.123669)
			(xy 370.150195 -279.070965) (xy 370.165905 -279.020035) (xy 370.189031 -278.972014) (xy 370.219055 -278.927977)
			(xy 370.255307 -278.888906) (xy 370.296978 -278.855675) (xy 370.343136 -278.829026) (xy 370.39275 -278.809554)
			(xy 370.444712 -278.797694) (xy 370.497862 -278.793711) (xy 370.551012 -278.797694) (xy 370.602974 -278.809554)
			(xy 370.652588 -278.829026) (xy 370.698746 -278.855675) (xy 370.740417 -278.888906) (xy 370.776669 -278.927977)
			(xy 370.806693 -278.972014) (xy 370.829819 -279.020035) (xy 370.845529 -279.070965) (xy 370.853472 -279.123669)
			(xy 370.85397 -279.150318) (xy 370.853472 -279.176967) (xy 371.082306 -279.176967) (xy 371.082306 -279.123669)
			(xy 371.090249 -279.070965) (xy 371.105959 -279.020035) (xy 371.129085 -278.972014) (xy 371.159109 -278.927977)
			(xy 371.195361 -278.888906) (xy 371.237032 -278.855675) (xy 371.28319 -278.829026) (xy 371.332804 -278.809554)
			(xy 371.384766 -278.797694) (xy 371.437916 -278.793711) (xy 371.491066 -278.797694) (xy 371.543028 -278.809554)
			(xy 371.592642 -278.829026) (xy 371.6388 -278.855675) (xy 371.680471 -278.888906) (xy 371.716723 -278.927977)
			(xy 371.746747 -278.972014) (xy 371.769873 -279.020035) (xy 371.785583 -279.070965) (xy 371.793526 -279.123669)
			(xy 371.794024 -279.150318) (xy 371.793526 -279.176967) (xy 372.021852 -279.176967) (xy 372.021852 -279.123669)
			(xy 372.029795 -279.070965) (xy 372.045505 -279.020035) (xy 372.068631 -278.972014) (xy 372.098655 -278.927977)
			(xy 372.134907 -278.888906) (xy 372.176578 -278.855675) (xy 372.222736 -278.829026) (xy 372.27235 -278.809554)
			(xy 372.324312 -278.797694) (xy 372.377462 -278.793711) (xy 372.430612 -278.797694) (xy 372.482574 -278.809554)
			(xy 372.532188 -278.829026) (xy 372.578346 -278.855675) (xy 372.620017 -278.888906) (xy 372.656269 -278.927977)
			(xy 372.686293 -278.972014) (xy 372.709419 -279.020035) (xy 372.725129 -279.070965) (xy 372.733072 -279.123669)
			(xy 372.73357 -279.150318) (xy 372.733072 -279.176967) (xy 372.961652 -279.176967) (xy 372.961652 -279.123669)
			(xy 372.969595 -279.070965) (xy 372.985305 -279.020035) (xy 373.008431 -278.972014) (xy 373.038455 -278.927977)
			(xy 373.074707 -278.888906) (xy 373.116378 -278.855675) (xy 373.162536 -278.829026) (xy 373.21215 -278.809554)
			(xy 373.264112 -278.797694) (xy 373.317262 -278.793711) (xy 373.370412 -278.797694) (xy 373.422374 -278.809554)
			(xy 373.471988 -278.829026) (xy 373.518146 -278.855675) (xy 373.559817 -278.888906) (xy 373.596069 -278.927977)
			(xy 373.626093 -278.972014) (xy 373.649219 -279.020035) (xy 373.664929 -279.070965) (xy 373.672872 -279.123669)
			(xy 373.67337 -279.150318) (xy 373.672872 -279.176967) (xy 373.901452 -279.176967) (xy 373.901452 -279.123669)
			(xy 373.909395 -279.070965) (xy 373.925105 -279.020035) (xy 373.948231 -278.972014) (xy 373.978255 -278.927977)
			(xy 374.014507 -278.888906) (xy 374.056178 -278.855675) (xy 374.102336 -278.829026) (xy 374.15195 -278.809554)
			(xy 374.203912 -278.797694) (xy 374.257062 -278.793711) (xy 374.310212 -278.797694) (xy 374.362174 -278.809554)
			(xy 374.411788 -278.829026) (xy 374.457946 -278.855675) (xy 374.499617 -278.888906) (xy 374.535869 -278.927977)
			(xy 374.565893 -278.972014) (xy 374.589019 -279.020035) (xy 374.604729 -279.070965) (xy 374.612672 -279.123669)
			(xy 374.61317 -279.150318) (xy 374.612672 -279.176967) (xy 374.841252 -279.176967) (xy 374.841252 -279.123669)
			(xy 374.849195 -279.070965) (xy 374.864905 -279.020035) (xy 374.888031 -278.972014) (xy 374.918055 -278.927977)
			(xy 374.954307 -278.888906) (xy 374.995978 -278.855675) (xy 375.042136 -278.829026) (xy 375.09175 -278.809554)
			(xy 375.143712 -278.797694) (xy 375.196862 -278.793711) (xy 375.250012 -278.797694) (xy 375.301974 -278.809554)
			(xy 375.351588 -278.829026) (xy 375.397746 -278.855675) (xy 375.439417 -278.888906) (xy 375.475669 -278.927977)
			(xy 375.505693 -278.972014) (xy 375.528819 -279.020035) (xy 375.544529 -279.070965) (xy 375.552472 -279.123669)
			(xy 375.55297 -279.150318) (xy 375.552472 -279.176967) (xy 375.781052 -279.176967) (xy 375.781052 -279.123669)
			(xy 375.788995 -279.070965) (xy 375.804705 -279.020035) (xy 375.827831 -278.972014) (xy 375.857855 -278.927977)
			(xy 375.894107 -278.888906) (xy 375.935778 -278.855675) (xy 375.981936 -278.829026) (xy 376.03155 -278.809554)
			(xy 376.083512 -278.797694) (xy 376.136662 -278.793711) (xy 376.189812 -278.797694) (xy 376.241774 -278.809554)
			(xy 376.291388 -278.829026) (xy 376.337546 -278.855675) (xy 376.379217 -278.888906) (xy 376.415469 -278.927977)
			(xy 376.445493 -278.972014) (xy 376.468619 -279.020035) (xy 376.484329 -279.070965) (xy 376.492272 -279.123669)
			(xy 376.49277 -279.150318) (xy 376.492272 -279.176967) (xy 376.720852 -279.176967) (xy 376.720852 -279.123669)
			(xy 376.728795 -279.070965) (xy 376.744505 -279.020035) (xy 376.767631 -278.972014) (xy 376.797655 -278.927977)
			(xy 376.833907 -278.888906) (xy 376.875578 -278.855675) (xy 376.921736 -278.829026) (xy 376.97135 -278.809554)
			(xy 377.023312 -278.797694) (xy 377.076462 -278.793711) (xy 377.129612 -278.797694) (xy 377.181574 -278.809554)
			(xy 377.231188 -278.829026) (xy 377.277346 -278.855675) (xy 377.319017 -278.888906) (xy 377.355269 -278.927977)
			(xy 377.385293 -278.972014) (xy 377.408419 -279.020035) (xy 377.424129 -279.070965) (xy 377.432072 -279.123669)
			(xy 377.43257 -279.150318) (xy 377.432072 -279.176967) (xy 377.660906 -279.176967) (xy 377.660906 -279.123669)
			(xy 377.668849 -279.070965) (xy 377.684559 -279.020035) (xy 377.707685 -278.972014) (xy 377.737709 -278.927977)
			(xy 377.773961 -278.888906) (xy 377.815632 -278.855675) (xy 377.86179 -278.829026) (xy 377.911404 -278.809554)
			(xy 377.963366 -278.797694) (xy 378.016516 -278.793711) (xy 378.069666 -278.797694) (xy 378.121628 -278.809554)
			(xy 378.171242 -278.829026) (xy 378.2174 -278.855675) (xy 378.259071 -278.888906) (xy 378.295323 -278.927977)
			(xy 378.325347 -278.972014) (xy 378.348473 -279.020035) (xy 378.364183 -279.070965) (xy 378.372126 -279.123669)
			(xy 378.372624 -279.150318) (xy 378.372126 -279.176967) (xy 378.600452 -279.176967) (xy 378.600452 -279.123669)
			(xy 378.608395 -279.070965) (xy 378.624105 -279.020035) (xy 378.647231 -278.972014) (xy 378.677255 -278.927977)
			(xy 378.713507 -278.888906) (xy 378.755178 -278.855675) (xy 378.801336 -278.829026) (xy 378.85095 -278.809554)
			(xy 378.902912 -278.797694) (xy 378.956062 -278.793711) (xy 379.009212 -278.797694) (xy 379.061174 -278.809554)
			(xy 379.110788 -278.829026) (xy 379.156946 -278.855675) (xy 379.198617 -278.888906) (xy 379.234869 -278.927977)
			(xy 379.264893 -278.972014) (xy 379.288019 -279.020035) (xy 379.303729 -279.070965) (xy 379.311672 -279.123669)
			(xy 379.31217 -279.150318) (xy 379.311672 -279.176967) (xy 379.540506 -279.176967) (xy 379.540506 -279.123669)
			(xy 379.548449 -279.070965) (xy 379.564159 -279.020035) (xy 379.587285 -278.972014) (xy 379.617309 -278.927977)
			(xy 379.653561 -278.888906) (xy 379.695232 -278.855675) (xy 379.74139 -278.829026) (xy 379.791004 -278.809554)
			(xy 379.842966 -278.797694) (xy 379.896116 -278.793711) (xy 379.949266 -278.797694) (xy 380.001228 -278.809554)
			(xy 380.050842 -278.829026) (xy 380.097 -278.855675) (xy 380.138671 -278.888906) (xy 380.174923 -278.927977)
			(xy 380.204947 -278.972014) (xy 380.228073 -279.020035) (xy 380.243783 -279.070965) (xy 380.251726 -279.123669)
			(xy 380.252224 -279.150318) (xy 380.251726 -279.176967) (xy 381.419852 -279.176967) (xy 381.419852 -279.123669)
			(xy 381.427795 -279.070965) (xy 381.443505 -279.020035) (xy 381.466631 -278.972014) (xy 381.496655 -278.927977)
			(xy 381.532907 -278.888906) (xy 381.574578 -278.855675) (xy 381.620736 -278.829026) (xy 381.67035 -278.809554)
			(xy 381.722312 -278.797694) (xy 381.775462 -278.793711) (xy 381.828612 -278.797694) (xy 381.880574 -278.809554)
			(xy 381.930188 -278.829026) (xy 381.976346 -278.855675) (xy 382.018017 -278.888906) (xy 382.054269 -278.927977)
			(xy 382.084293 -278.972014) (xy 382.107419 -279.020035) (xy 382.123129 -279.070965) (xy 382.131072 -279.123669)
			(xy 382.13157 -279.150318) (xy 382.131072 -279.176967) (xy 382.123129 -279.229671) (xy 382.107419 -279.280601)
			(xy 382.084293 -279.328622) (xy 382.054269 -279.372659) (xy 382.018017 -279.41173) (xy 381.976346 -279.444961)
			(xy 381.930188 -279.47161) (xy 381.880574 -279.491082) (xy 381.828612 -279.502942) (xy 381.775462 -279.506926)
			(xy 381.722312 -279.502942) (xy 381.67035 -279.491082) (xy 381.620736 -279.47161) (xy 381.574578 -279.444961)
			(xy 381.532907 -279.41173) (xy 381.496655 -279.372659) (xy 381.466631 -279.328622) (xy 381.443505 -279.280601)
			(xy 381.427795 -279.229671) (xy 381.419852 -279.176967) (xy 380.251726 -279.176967) (xy 380.243783 -279.229671)
			(xy 380.228073 -279.280601) (xy 380.204947 -279.328622) (xy 380.174923 -279.372659) (xy 380.138671 -279.41173)
			(xy 380.097 -279.444961) (xy 380.050842 -279.47161) (xy 380.001228 -279.491082) (xy 379.949266 -279.502942)
			(xy 379.896116 -279.506926) (xy 379.842966 -279.502942) (xy 379.791004 -279.491082) (xy 379.74139 -279.47161)
			(xy 379.695232 -279.444961) (xy 379.653561 -279.41173) (xy 379.617309 -279.372659) (xy 379.587285 -279.328622)
			(xy 379.564159 -279.280601) (xy 379.548449 -279.229671) (xy 379.540506 -279.176967) (xy 379.311672 -279.176967)
			(xy 379.303729 -279.229671) (xy 379.288019 -279.280601) (xy 379.264893 -279.328622) (xy 379.234869 -279.372659)
			(xy 379.198617 -279.41173) (xy 379.156946 -279.444961) (xy 379.110788 -279.47161) (xy 379.061174 -279.491082)
			(xy 379.009212 -279.502942) (xy 378.956062 -279.506926) (xy 378.902912 -279.502942) (xy 378.85095 -279.491082)
			(xy 378.801336 -279.47161) (xy 378.755178 -279.444961) (xy 378.713507 -279.41173) (xy 378.677255 -279.372659)
			(xy 378.647231 -279.328622) (xy 378.624105 -279.280601) (xy 378.608395 -279.229671) (xy 378.600452 -279.176967)
			(xy 378.372126 -279.176967) (xy 378.364183 -279.229671) (xy 378.348473 -279.280601) (xy 378.325347 -279.328622)
			(xy 378.295323 -279.372659) (xy 378.259071 -279.41173) (xy 378.2174 -279.444961) (xy 378.171242 -279.47161)
			(xy 378.121628 -279.491082) (xy 378.069666 -279.502942) (xy 378.016516 -279.506926) (xy 377.963366 -279.502942)
			(xy 377.911404 -279.491082) (xy 377.86179 -279.47161) (xy 377.815632 -279.444961) (xy 377.773961 -279.41173)
			(xy 377.737709 -279.372659) (xy 377.707685 -279.328622) (xy 377.684559 -279.280601) (xy 377.668849 -279.229671)
			(xy 377.660906 -279.176967) (xy 377.432072 -279.176967) (xy 377.424129 -279.229671) (xy 377.408419 -279.280601)
			(xy 377.385293 -279.328622) (xy 377.355269 -279.372659) (xy 377.319017 -279.41173) (xy 377.277346 -279.444961)
			(xy 377.231188 -279.47161) (xy 377.181574 -279.491082) (xy 377.129612 -279.502942) (xy 377.076462 -279.506926)
			(xy 377.023312 -279.502942) (xy 376.97135 -279.491082) (xy 376.921736 -279.47161) (xy 376.875578 -279.444961)
			(xy 376.833907 -279.41173) (xy 376.797655 -279.372659) (xy 376.767631 -279.328622) (xy 376.744505 -279.280601)
			(xy 376.728795 -279.229671) (xy 376.720852 -279.176967) (xy 376.492272 -279.176967) (xy 376.484329 -279.229671)
			(xy 376.468619 -279.280601) (xy 376.445493 -279.328622) (xy 376.415469 -279.372659) (xy 376.379217 -279.41173)
			(xy 376.337546 -279.444961) (xy 376.291388 -279.47161) (xy 376.241774 -279.491082) (xy 376.189812 -279.502942)
			(xy 376.136662 -279.506926) (xy 376.083512 -279.502942) (xy 376.03155 -279.491082) (xy 375.981936 -279.47161)
			(xy 375.935778 -279.444961) (xy 375.894107 -279.41173) (xy 375.857855 -279.372659) (xy 375.827831 -279.328622)
			(xy 375.804705 -279.280601) (xy 375.788995 -279.229671) (xy 375.781052 -279.176967) (xy 375.552472 -279.176967)
			(xy 375.544529 -279.229671) (xy 375.528819 -279.280601) (xy 375.505693 -279.328622) (xy 375.475669 -279.372659)
			(xy 375.439417 -279.41173) (xy 375.397746 -279.444961) (xy 375.351588 -279.47161) (xy 375.301974 -279.491082)
			(xy 375.250012 -279.502942) (xy 375.196862 -279.506926) (xy 375.143712 -279.502942) (xy 375.09175 -279.491082)
			(xy 375.042136 -279.47161) (xy 374.995978 -279.444961) (xy 374.954307 -279.41173) (xy 374.918055 -279.372659)
			(xy 374.888031 -279.328622) (xy 374.864905 -279.280601) (xy 374.849195 -279.229671) (xy 374.841252 -279.176967)
			(xy 374.612672 -279.176967) (xy 374.604729 -279.229671) (xy 374.589019 -279.280601) (xy 374.565893 -279.328622)
			(xy 374.535869 -279.372659) (xy 374.499617 -279.41173) (xy 374.457946 -279.444961) (xy 374.411788 -279.47161)
			(xy 374.362174 -279.491082) (xy 374.310212 -279.502942) (xy 374.257062 -279.506926) (xy 374.203912 -279.502942)
			(xy 374.15195 -279.491082) (xy 374.102336 -279.47161) (xy 374.056178 -279.444961) (xy 374.014507 -279.41173)
			(xy 373.978255 -279.372659) (xy 373.948231 -279.328622) (xy 373.925105 -279.280601) (xy 373.909395 -279.229671)
			(xy 373.901452 -279.176967) (xy 373.672872 -279.176967) (xy 373.664929 -279.229671) (xy 373.649219 -279.280601)
			(xy 373.626093 -279.328622) (xy 373.596069 -279.372659) (xy 373.559817 -279.41173) (xy 373.518146 -279.444961)
			(xy 373.471988 -279.47161) (xy 373.422374 -279.491082) (xy 373.370412 -279.502942) (xy 373.317262 -279.506926)
			(xy 373.264112 -279.502942) (xy 373.21215 -279.491082) (xy 373.162536 -279.47161) (xy 373.116378 -279.444961)
			(xy 373.074707 -279.41173) (xy 373.038455 -279.372659) (xy 373.008431 -279.328622) (xy 372.985305 -279.280601)
			(xy 372.969595 -279.229671) (xy 372.961652 -279.176967) (xy 372.733072 -279.176967) (xy 372.725129 -279.229671)
			(xy 372.709419 -279.280601) (xy 372.686293 -279.328622) (xy 372.656269 -279.372659) (xy 372.620017 -279.41173)
			(xy 372.578346 -279.444961) (xy 372.532188 -279.47161) (xy 372.482574 -279.491082) (xy 372.430612 -279.502942)
			(xy 372.377462 -279.506926) (xy 372.324312 -279.502942) (xy 372.27235 -279.491082) (xy 372.222736 -279.47161)
			(xy 372.176578 -279.444961) (xy 372.134907 -279.41173) (xy 372.098655 -279.372659) (xy 372.068631 -279.328622)
			(xy 372.045505 -279.280601) (xy 372.029795 -279.229671) (xy 372.021852 -279.176967) (xy 371.793526 -279.176967)
			(xy 371.785583 -279.229671) (xy 371.769873 -279.280601) (xy 371.746747 -279.328622) (xy 371.716723 -279.372659)
			(xy 371.680471 -279.41173) (xy 371.6388 -279.444961) (xy 371.592642 -279.47161) (xy 371.543028 -279.491082)
			(xy 371.491066 -279.502942) (xy 371.437916 -279.506926) (xy 371.384766 -279.502942) (xy 371.332804 -279.491082)
			(xy 371.28319 -279.47161) (xy 371.237032 -279.444961) (xy 371.195361 -279.41173) (xy 371.159109 -279.372659)
			(xy 371.129085 -279.328622) (xy 371.105959 -279.280601) (xy 371.090249 -279.229671) (xy 371.082306 -279.176967)
			(xy 370.853472 -279.176967) (xy 370.845529 -279.229671) (xy 370.829819 -279.280601) (xy 370.806693 -279.328622)
			(xy 370.776669 -279.372659) (xy 370.740417 -279.41173) (xy 370.698746 -279.444961) (xy 370.652588 -279.47161)
			(xy 370.602974 -279.491082) (xy 370.551012 -279.502942) (xy 370.497862 -279.506926) (xy 370.444712 -279.502942)
			(xy 370.39275 -279.491082) (xy 370.343136 -279.47161) (xy 370.296978 -279.444961) (xy 370.255307 -279.41173)
			(xy 370.219055 -279.372659) (xy 370.189031 -279.328622) (xy 370.165905 -279.280601) (xy 370.150195 -279.229671)
			(xy 370.142252 -279.176967) (xy 369.913672 -279.176967) (xy 369.905729 -279.229671) (xy 369.890019 -279.280601)
			(xy 369.866893 -279.328622) (xy 369.836869 -279.372659) (xy 369.800617 -279.41173) (xy 369.758946 -279.444961)
			(xy 369.712788 -279.47161) (xy 369.663174 -279.491082) (xy 369.611212 -279.502942) (xy 369.558062 -279.506926)
			(xy 369.504912 -279.502942) (xy 369.45295 -279.491082) (xy 369.403336 -279.47161) (xy 369.357178 -279.444961)
			(xy 369.315507 -279.41173) (xy 369.279255 -279.372659) (xy 369.249231 -279.328622) (xy 369.226105 -279.280601)
			(xy 369.210395 -279.229671) (xy 369.202452 -279.176967) (xy 368.974126 -279.176967) (xy 368.966183 -279.229671)
			(xy 368.950473 -279.280601) (xy 368.927347 -279.328622) (xy 368.897323 -279.372659) (xy 368.861071 -279.41173)
			(xy 368.8194 -279.444961) (xy 368.773242 -279.47161) (xy 368.723628 -279.491082) (xy 368.671666 -279.502942)
			(xy 368.618516 -279.506926) (xy 368.565366 -279.502942) (xy 368.513404 -279.491082) (xy 368.46379 -279.47161)
			(xy 368.417632 -279.444961) (xy 368.375961 -279.41173) (xy 368.339709 -279.372659) (xy 368.309685 -279.328622)
			(xy 368.286559 -279.280601) (xy 368.270849 -279.229671) (xy 368.262906 -279.176967) (xy 368.034072 -279.176967)
			(xy 368.026129 -279.229671) (xy 368.010419 -279.280601) (xy 367.987293 -279.328622) (xy 367.957269 -279.372659)
			(xy 367.921017 -279.41173) (xy 367.879346 -279.444961) (xy 367.833188 -279.47161) (xy 367.783574 -279.491082)
			(xy 367.731612 -279.502942) (xy 367.678462 -279.506926) (xy 367.625312 -279.502942) (xy 367.57335 -279.491082)
			(xy 367.523736 -279.47161) (xy 367.477578 -279.444961) (xy 367.435907 -279.41173) (xy 367.399655 -279.372659)
			(xy 367.369631 -279.328622) (xy 367.346505 -279.280601) (xy 367.330795 -279.229671) (xy 367.322852 -279.176967)
			(xy 366.154726 -279.176967) (xy 366.146783 -279.229671) (xy 366.131073 -279.280601) (xy 366.107947 -279.328622)
			(xy 366.077923 -279.372659) (xy 366.041671 -279.41173) (xy 366 -279.444961) (xy 365.953842 -279.47161)
			(xy 365.904228 -279.491082) (xy 365.852266 -279.502942) (xy 365.799116 -279.506926) (xy 365.745966 -279.502942)
			(xy 365.694004 -279.491082) (xy 365.64439 -279.47161) (xy 365.598232 -279.444961) (xy 365.556561 -279.41173)
			(xy 365.520309 -279.372659) (xy 365.490285 -279.328622) (xy 365.467159 -279.280601) (xy 365.451449 -279.229671)
			(xy 365.443506 -279.176967) (xy 365.214866 -279.176967) (xy 365.214866 -279.177144) (xy 365.20668 -279.230633)
			(xy 365.190495 -279.282269) (xy 365.166683 -279.33086) (xy 365.135793 -279.37529) (xy 365.098536 -279.414533)
			(xy 365.055769 -279.447688) (xy 365.008479 -279.473989) (xy 364.983268 -279.48382) (xy 364.950248 -279.496266)
			(xy 364.950248 -279.990783) (xy 365.913152 -279.990783) (xy 365.913152 -279.937485) (xy 365.921095 -279.884781)
			(xy 365.936805 -279.833851) (xy 365.959931 -279.78583) (xy 365.989955 -279.741793) (xy 366.026207 -279.702722)
			(xy 366.067878 -279.669491) (xy 366.114036 -279.642842) (xy 366.16365 -279.62337) (xy 366.215612 -279.61151)
			(xy 366.268762 -279.607527) (xy 366.321912 -279.61151) (xy 366.373874 -279.62337) (xy 366.423488 -279.642842)
			(xy 366.469646 -279.669491) (xy 366.511317 -279.702722) (xy 366.547569 -279.741793) (xy 366.577593 -279.78583)
			(xy 366.600719 -279.833851) (xy 366.616429 -279.884781) (xy 366.624372 -279.937485) (xy 366.62487 -279.964134)
			(xy 366.624372 -279.990783) (xy 366.853206 -279.990783) (xy 366.853206 -279.937485) (xy 366.861149 -279.884781)
			(xy 366.876859 -279.833851) (xy 366.899985 -279.78583) (xy 366.930009 -279.741793) (xy 366.966261 -279.702722)
			(xy 367.007932 -279.669491) (xy 367.05409 -279.642842) (xy 367.103704 -279.62337) (xy 367.155666 -279.61151)
			(xy 367.208816 -279.607527) (xy 367.261966 -279.61151) (xy 367.313928 -279.62337) (xy 367.363542 -279.642842)
			(xy 367.4097 -279.669491) (xy 367.451371 -279.702722) (xy 367.487623 -279.741793) (xy 367.517647 -279.78583)
			(xy 367.540773 -279.833851) (xy 367.556483 -279.884781) (xy 367.564426 -279.937485) (xy 367.564924 -279.964134)
			(xy 367.564426 -279.990783) (xy 367.793006 -279.990783) (xy 367.793006 -279.937485) (xy 367.800949 -279.884781)
			(xy 367.816659 -279.833851) (xy 367.839785 -279.78583) (xy 367.869809 -279.741793) (xy 367.906061 -279.702722)
			(xy 367.947732 -279.669491) (xy 367.99389 -279.642842) (xy 368.043504 -279.62337) (xy 368.095466 -279.61151)
			(xy 368.148616 -279.607527) (xy 368.201766 -279.61151) (xy 368.253728 -279.62337) (xy 368.303342 -279.642842)
			(xy 368.3495 -279.669491) (xy 368.391171 -279.702722) (xy 368.427423 -279.741793) (xy 368.457447 -279.78583)
			(xy 368.480573 -279.833851) (xy 368.496283 -279.884781) (xy 368.504226 -279.937485) (xy 368.504724 -279.964134)
			(xy 368.504226 -279.990783) (xy 368.732806 -279.990783) (xy 368.732806 -279.937485) (xy 368.740749 -279.884781)
			(xy 368.756459 -279.833851) (xy 368.779585 -279.78583) (xy 368.809609 -279.741793) (xy 368.845861 -279.702722)
			(xy 368.887532 -279.669491) (xy 368.93369 -279.642842) (xy 368.983304 -279.62337) (xy 369.035266 -279.61151)
			(xy 369.088416 -279.607527) (xy 369.141566 -279.61151) (xy 369.193528 -279.62337) (xy 369.243142 -279.642842)
			(xy 369.2893 -279.669491) (xy 369.330971 -279.702722) (xy 369.367223 -279.741793) (xy 369.397247 -279.78583)
			(xy 369.420373 -279.833851) (xy 369.436083 -279.884781) (xy 369.444026 -279.937485) (xy 369.444524 -279.964134)
			(xy 369.444026 -279.990783) (xy 370.612406 -279.990783) (xy 370.612406 -279.937485) (xy 370.620349 -279.884781)
			(xy 370.636059 -279.833851) (xy 370.659185 -279.78583) (xy 370.689209 -279.741793) (xy 370.725461 -279.702722)
			(xy 370.767132 -279.669491) (xy 370.81329 -279.642842) (xy 370.862904 -279.62337) (xy 370.914866 -279.61151)
			(xy 370.968016 -279.607527) (xy 371.021166 -279.61151) (xy 371.073128 -279.62337) (xy 371.122742 -279.642842)
			(xy 371.1689 -279.669491) (xy 371.210571 -279.702722) (xy 371.246823 -279.741793) (xy 371.276847 -279.78583)
			(xy 371.299973 -279.833851) (xy 371.315683 -279.884781) (xy 371.323626 -279.937485) (xy 371.324124 -279.964134)
			(xy 371.323626 -279.990783) (xy 371.551952 -279.990783) (xy 371.551952 -279.937485) (xy 371.559895 -279.884781)
			(xy 371.575605 -279.833851) (xy 371.598731 -279.78583) (xy 371.628755 -279.741793) (xy 371.665007 -279.702722)
			(xy 371.706678 -279.669491) (xy 371.752836 -279.642842) (xy 371.80245 -279.62337) (xy 371.854412 -279.61151)
			(xy 371.907562 -279.607527) (xy 371.960712 -279.61151) (xy 372.012674 -279.62337) (xy 372.062288 -279.642842)
			(xy 372.108446 -279.669491) (xy 372.150117 -279.702722) (xy 372.186369 -279.741793) (xy 372.216393 -279.78583)
			(xy 372.239519 -279.833851) (xy 372.255229 -279.884781) (xy 372.263172 -279.937485) (xy 372.26367 -279.964134)
			(xy 372.263172 -279.990783) (xy 372.492006 -279.990783) (xy 372.492006 -279.937485) (xy 372.499949 -279.884781)
			(xy 372.515659 -279.833851) (xy 372.538785 -279.78583) (xy 372.568809 -279.741793) (xy 372.605061 -279.702722)
			(xy 372.646732 -279.669491) (xy 372.69289 -279.642842) (xy 372.742504 -279.62337) (xy 372.794466 -279.61151)
			(xy 372.847616 -279.607527) (xy 372.900766 -279.61151) (xy 372.952728 -279.62337) (xy 373.002342 -279.642842)
			(xy 373.0485 -279.669491) (xy 373.090171 -279.702722) (xy 373.126423 -279.741793) (xy 373.156447 -279.78583)
			(xy 373.179573 -279.833851) (xy 373.195283 -279.884781) (xy 373.203226 -279.937485) (xy 373.203724 -279.964134)
			(xy 373.203226 -279.990783) (xy 373.431806 -279.990783) (xy 373.431806 -279.937485) (xy 373.439749 -279.884781)
			(xy 373.455459 -279.833851) (xy 373.478585 -279.78583) (xy 373.508609 -279.741793) (xy 373.544861 -279.702722)
			(xy 373.586532 -279.669491) (xy 373.63269 -279.642842) (xy 373.682304 -279.62337) (xy 373.734266 -279.61151)
			(xy 373.787416 -279.607527) (xy 373.840566 -279.61151) (xy 373.892528 -279.62337) (xy 373.942142 -279.642842)
			(xy 373.9883 -279.669491) (xy 374.029971 -279.702722) (xy 374.066223 -279.741793) (xy 374.096247 -279.78583)
			(xy 374.119373 -279.833851) (xy 374.135083 -279.884781) (xy 374.143026 -279.937485) (xy 374.143524 -279.964134)
			(xy 374.143026 -279.990783) (xy 374.371352 -279.990783) (xy 374.371352 -279.937485) (xy 374.379295 -279.884781)
			(xy 374.395005 -279.833851) (xy 374.418131 -279.78583) (xy 374.448155 -279.741793) (xy 374.484407 -279.702722)
			(xy 374.526078 -279.669491) (xy 374.572236 -279.642842) (xy 374.62185 -279.62337) (xy 374.673812 -279.61151)
			(xy 374.726962 -279.607527) (xy 374.780112 -279.61151) (xy 374.832074 -279.62337) (xy 374.881688 -279.642842)
			(xy 374.927846 -279.669491) (xy 374.969517 -279.702722) (xy 375.005769 -279.741793) (xy 375.035793 -279.78583)
			(xy 375.058919 -279.833851) (xy 375.074629 -279.884781) (xy 375.082572 -279.937485) (xy 375.08307 -279.964134)
			(xy 375.082572 -279.990783) (xy 375.311406 -279.990783) (xy 375.311406 -279.937485) (xy 375.319349 -279.884781)
			(xy 375.335059 -279.833851) (xy 375.358185 -279.78583) (xy 375.388209 -279.741793) (xy 375.424461 -279.702722)
			(xy 375.466132 -279.669491) (xy 375.51229 -279.642842) (xy 375.561904 -279.62337) (xy 375.613866 -279.61151)
			(xy 375.667016 -279.607527) (xy 375.720166 -279.61151) (xy 375.772128 -279.62337) (xy 375.821742 -279.642842)
			(xy 375.8679 -279.669491) (xy 375.909571 -279.702722) (xy 375.945823 -279.741793) (xy 375.975847 -279.78583)
			(xy 375.998973 -279.833851) (xy 376.014683 -279.884781) (xy 376.022626 -279.937485) (xy 376.023124 -279.964134)
			(xy 376.022631 -279.990529) (xy 376.250952 -279.990529) (xy 376.250952 -279.937231) (xy 376.258895 -279.884527)
			(xy 376.274605 -279.833597) (xy 376.297731 -279.785576) (xy 376.327755 -279.741539) (xy 376.364007 -279.702468)
			(xy 376.405678 -279.669237) (xy 376.451836 -279.642588) (xy 376.50145 -279.623116) (xy 376.553412 -279.611256)
			(xy 376.606562 -279.607273) (xy 376.659712 -279.611256) (xy 376.711674 -279.623116) (xy 376.761288 -279.642588)
			(xy 376.807446 -279.669237) (xy 376.849117 -279.702468) (xy 376.885369 -279.741539) (xy 376.915393 -279.785576)
			(xy 376.938519 -279.833597) (xy 376.954229 -279.884527) (xy 376.962172 -279.937231) (xy 376.96267 -279.96388)
			(xy 376.962172 -279.990529) (xy 376.962134 -279.990783) (xy 378.130806 -279.990783) (xy 378.130806 -279.937485)
			(xy 378.138749 -279.884781) (xy 378.154459 -279.833851) (xy 378.177585 -279.78583) (xy 378.207609 -279.741793)
			(xy 378.243861 -279.702722) (xy 378.285532 -279.669491) (xy 378.33169 -279.642842) (xy 378.381304 -279.62337)
			(xy 378.433266 -279.61151) (xy 378.486416 -279.607527) (xy 378.539566 -279.61151) (xy 378.591528 -279.62337)
			(xy 378.641142 -279.642842) (xy 378.6873 -279.669491) (xy 378.728971 -279.702722) (xy 378.765223 -279.741793)
			(xy 378.795247 -279.78583) (xy 378.818373 -279.833851) (xy 378.834083 -279.884781) (xy 378.842026 -279.937485)
			(xy 378.842524 -279.964134) (xy 378.842026 -279.990783) (xy 379.070606 -279.990783) (xy 379.070606 -279.937485)
			(xy 379.078549 -279.884781) (xy 379.094259 -279.833851) (xy 379.117385 -279.78583) (xy 379.147409 -279.741793)
			(xy 379.183661 -279.702722) (xy 379.225332 -279.669491) (xy 379.27149 -279.642842) (xy 379.321104 -279.62337)
			(xy 379.373066 -279.61151) (xy 379.426216 -279.607527) (xy 379.479366 -279.61151) (xy 379.531328 -279.62337)
			(xy 379.580942 -279.642842) (xy 379.6271 -279.669491) (xy 379.668771 -279.702722) (xy 379.705023 -279.741793)
			(xy 379.735047 -279.78583) (xy 379.758173 -279.833851) (xy 379.773883 -279.884781) (xy 379.781826 -279.937485)
			(xy 379.782324 -279.964134) (xy 379.781826 -279.990783) (xy 380.010152 -279.990783) (xy 380.010152 -279.937485)
			(xy 380.018095 -279.884781) (xy 380.033805 -279.833851) (xy 380.056931 -279.78583) (xy 380.086955 -279.741793)
			(xy 380.123207 -279.702722) (xy 380.164878 -279.669491) (xy 380.211036 -279.642842) (xy 380.26065 -279.62337)
			(xy 380.312612 -279.61151) (xy 380.365762 -279.607527) (xy 380.418912 -279.61151) (xy 380.470874 -279.62337)
			(xy 380.520488 -279.642842) (xy 380.566646 -279.669491) (xy 380.608317 -279.702722) (xy 380.644569 -279.741793)
			(xy 380.674593 -279.78583) (xy 380.697719 -279.833851) (xy 380.713429 -279.884781) (xy 380.721372 -279.937485)
			(xy 380.72187 -279.964134) (xy 380.721372 -279.990783) (xy 382.829298 -279.990783) (xy 382.829298 -279.937485)
			(xy 382.837241 -279.884781) (xy 382.852951 -279.833851) (xy 382.876077 -279.78583) (xy 382.906101 -279.741793)
			(xy 382.942353 -279.702722) (xy 382.984024 -279.669491) (xy 383.030182 -279.642842) (xy 383.079796 -279.62337)
			(xy 383.131758 -279.61151) (xy 383.184908 -279.607527) (xy 383.238058 -279.61151) (xy 383.29002 -279.62337)
			(xy 383.339634 -279.642842) (xy 383.385792 -279.669491) (xy 383.427463 -279.702722) (xy 383.463715 -279.741793)
			(xy 383.493739 -279.78583) (xy 383.516865 -279.833851) (xy 383.532575 -279.884781) (xy 383.540518 -279.937485)
			(xy 383.541016 -279.964134) (xy 383.540518 -279.990783) (xy 383.532575 -280.043487) (xy 383.516865 -280.094417)
			(xy 383.493739 -280.142438) (xy 383.463715 -280.186475) (xy 383.427463 -280.225546) (xy 383.385792 -280.258777)
			(xy 383.339634 -280.285426) (xy 383.29002 -280.304898) (xy 383.238058 -280.316758) (xy 383.184908 -280.320742)
			(xy 383.131758 -280.316758) (xy 383.079796 -280.304898) (xy 383.030182 -280.285426) (xy 382.984024 -280.258777)
			(xy 382.942353 -280.225546) (xy 382.906101 -280.186475) (xy 382.876077 -280.142438) (xy 382.852951 -280.094417)
			(xy 382.837241 -280.043487) (xy 382.829298 -279.990783) (xy 380.721372 -279.990783) (xy 380.713429 -280.043487)
			(xy 380.697719 -280.094417) (xy 380.674593 -280.142438) (xy 380.644569 -280.186475) (xy 380.608317 -280.225546)
			(xy 380.566646 -280.258777) (xy 380.520488 -280.285426) (xy 380.470874 -280.304898) (xy 380.418912 -280.316758)
			(xy 380.365762 -280.320742) (xy 380.312612 -280.316758) (xy 380.26065 -280.304898) (xy 380.211036 -280.285426)
			(xy 380.164878 -280.258777) (xy 380.123207 -280.225546) (xy 380.086955 -280.186475) (xy 380.056931 -280.142438)
			(xy 380.033805 -280.094417) (xy 380.018095 -280.043487) (xy 380.010152 -279.990783) (xy 379.781826 -279.990783)
			(xy 379.773883 -280.043487) (xy 379.758173 -280.094417) (xy 379.735047 -280.142438) (xy 379.705023 -280.186475)
			(xy 379.668771 -280.225546) (xy 379.6271 -280.258777) (xy 379.580942 -280.285426) (xy 379.531328 -280.304898)
			(xy 379.479366 -280.316758) (xy 379.426216 -280.320742) (xy 379.373066 -280.316758) (xy 379.321104 -280.304898)
			(xy 379.27149 -280.285426) (xy 379.225332 -280.258777) (xy 379.183661 -280.225546) (xy 379.147409 -280.186475)
			(xy 379.117385 -280.142438) (xy 379.094259 -280.094417) (xy 379.078549 -280.043487) (xy 379.070606 -279.990783)
			(xy 378.842026 -279.990783) (xy 378.834083 -280.043487) (xy 378.818373 -280.094417) (xy 378.795247 -280.142438)
			(xy 378.765223 -280.186475) (xy 378.728971 -280.225546) (xy 378.6873 -280.258777) (xy 378.641142 -280.285426)
			(xy 378.591528 -280.304898) (xy 378.539566 -280.316758) (xy 378.486416 -280.320742) (xy 378.433266 -280.316758)
			(xy 378.381304 -280.304898) (xy 378.33169 -280.285426) (xy 378.285532 -280.258777) (xy 378.243861 -280.225546)
			(xy 378.207609 -280.186475) (xy 378.177585 -280.142438) (xy 378.154459 -280.094417) (xy 378.138749 -280.043487)
			(xy 378.130806 -279.990783) (xy 376.962134 -279.990783) (xy 376.954229 -280.043233) (xy 376.938519 -280.094163)
			(xy 376.915393 -280.142184) (xy 376.885369 -280.186221) (xy 376.849117 -280.225292) (xy 376.807446 -280.258523)
			(xy 376.761288 -280.285172) (xy 376.711674 -280.304644) (xy 376.659712 -280.316504) (xy 376.606562 -280.320488)
			(xy 376.553412 -280.316504) (xy 376.50145 -280.304644) (xy 376.451836 -280.285172) (xy 376.405678 -280.258523)
			(xy 376.364007 -280.225292) (xy 376.327755 -280.186221) (xy 376.297731 -280.142184) (xy 376.274605 -280.094163)
			(xy 376.258895 -280.043233) (xy 376.250952 -279.990529) (xy 376.022631 -279.990529) (xy 376.022626 -279.990783)
			(xy 376.014683 -280.043487) (xy 375.998973 -280.094417) (xy 375.975847 -280.142438) (xy 375.945823 -280.186475)
			(xy 375.909571 -280.225546) (xy 375.8679 -280.258777) (xy 375.821742 -280.285426) (xy 375.772128 -280.304898)
			(xy 375.720166 -280.316758) (xy 375.667016 -280.320742) (xy 375.613866 -280.316758) (xy 375.561904 -280.304898)
			(xy 375.51229 -280.285426) (xy 375.466132 -280.258777) (xy 375.424461 -280.225546) (xy 375.388209 -280.186475)
			(xy 375.358185 -280.142438) (xy 375.335059 -280.094417) (xy 375.319349 -280.043487) (xy 375.311406 -279.990783)
			(xy 375.082572 -279.990783) (xy 375.074629 -280.043487) (xy 375.058919 -280.094417) (xy 375.035793 -280.142438)
			(xy 375.005769 -280.186475) (xy 374.969517 -280.225546) (xy 374.927846 -280.258777) (xy 374.881688 -280.285426)
			(xy 374.832074 -280.304898) (xy 374.780112 -280.316758) (xy 374.726962 -280.320742) (xy 374.673812 -280.316758)
			(xy 374.62185 -280.304898) (xy 374.572236 -280.285426) (xy 374.526078 -280.258777) (xy 374.484407 -280.225546)
			(xy 374.448155 -280.186475) (xy 374.418131 -280.142438) (xy 374.395005 -280.094417) (xy 374.379295 -280.043487)
			(xy 374.371352 -279.990783) (xy 374.143026 -279.990783) (xy 374.135083 -280.043487) (xy 374.119373 -280.094417)
			(xy 374.096247 -280.142438) (xy 374.066223 -280.186475) (xy 374.029971 -280.225546) (xy 373.9883 -280.258777)
			(xy 373.942142 -280.285426) (xy 373.892528 -280.304898) (xy 373.840566 -280.316758) (xy 373.787416 -280.320742)
			(xy 373.734266 -280.316758) (xy 373.682304 -280.304898) (xy 373.63269 -280.285426) (xy 373.586532 -280.258777)
			(xy 373.544861 -280.225546) (xy 373.508609 -280.186475) (xy 373.478585 -280.142438) (xy 373.455459 -280.094417)
			(xy 373.439749 -280.043487) (xy 373.431806 -279.990783) (xy 373.203226 -279.990783) (xy 373.195283 -280.043487)
			(xy 373.179573 -280.094417) (xy 373.156447 -280.142438) (xy 373.126423 -280.186475) (xy 373.090171 -280.225546)
			(xy 373.0485 -280.258777) (xy 373.002342 -280.285426) (xy 372.952728 -280.304898) (xy 372.900766 -280.316758)
			(xy 372.847616 -280.320742) (xy 372.794466 -280.316758) (xy 372.742504 -280.304898) (xy 372.69289 -280.285426)
			(xy 372.646732 -280.258777) (xy 372.605061 -280.225546) (xy 372.568809 -280.186475) (xy 372.538785 -280.142438)
			(xy 372.515659 -280.094417) (xy 372.499949 -280.043487) (xy 372.492006 -279.990783) (xy 372.263172 -279.990783)
			(xy 372.255229 -280.043487) (xy 372.239519 -280.094417) (xy 372.216393 -280.142438) (xy 372.186369 -280.186475)
			(xy 372.150117 -280.225546) (xy 372.108446 -280.258777) (xy 372.062288 -280.285426) (xy 372.012674 -280.304898)
			(xy 371.960712 -280.316758) (xy 371.907562 -280.320742) (xy 371.854412 -280.316758) (xy 371.80245 -280.304898)
			(xy 371.752836 -280.285426) (xy 371.706678 -280.258777) (xy 371.665007 -280.225546) (xy 371.628755 -280.186475)
			(xy 371.598731 -280.142438) (xy 371.575605 -280.094417) (xy 371.559895 -280.043487) (xy 371.551952 -279.990783)
			(xy 371.323626 -279.990783) (xy 371.315683 -280.043487) (xy 371.299973 -280.094417) (xy 371.276847 -280.142438)
			(xy 371.246823 -280.186475) (xy 371.210571 -280.225546) (xy 371.1689 -280.258777) (xy 371.122742 -280.285426)
			(xy 371.073128 -280.304898) (xy 371.021166 -280.316758) (xy 370.968016 -280.320742) (xy 370.914866 -280.316758)
			(xy 370.862904 -280.304898) (xy 370.81329 -280.285426) (xy 370.767132 -280.258777) (xy 370.725461 -280.225546)
			(xy 370.689209 -280.186475) (xy 370.659185 -280.142438) (xy 370.636059 -280.094417) (xy 370.620349 -280.043487)
			(xy 370.612406 -279.990783) (xy 369.444026 -279.990783) (xy 369.436083 -280.043487) (xy 369.420373 -280.094417)
			(xy 369.397247 -280.142438) (xy 369.367223 -280.186475) (xy 369.330971 -280.225546) (xy 369.2893 -280.258777)
			(xy 369.243142 -280.285426) (xy 369.193528 -280.304898) (xy 369.141566 -280.316758) (xy 369.088416 -280.320742)
			(xy 369.035266 -280.316758) (xy 368.983304 -280.304898) (xy 368.93369 -280.285426) (xy 368.887532 -280.258777)
			(xy 368.845861 -280.225546) (xy 368.809609 -280.186475) (xy 368.779585 -280.142438) (xy 368.756459 -280.094417)
			(xy 368.740749 -280.043487) (xy 368.732806 -279.990783) (xy 368.504226 -279.990783) (xy 368.496283 -280.043487)
			(xy 368.480573 -280.094417) (xy 368.457447 -280.142438) (xy 368.427423 -280.186475) (xy 368.391171 -280.225546)
			(xy 368.3495 -280.258777) (xy 368.303342 -280.285426) (xy 368.253728 -280.304898) (xy 368.201766 -280.316758)
			(xy 368.148616 -280.320742) (xy 368.095466 -280.316758) (xy 368.043504 -280.304898) (xy 367.99389 -280.285426)
			(xy 367.947732 -280.258777) (xy 367.906061 -280.225546) (xy 367.869809 -280.186475) (xy 367.839785 -280.142438)
			(xy 367.816659 -280.094417) (xy 367.800949 -280.043487) (xy 367.793006 -279.990783) (xy 367.564426 -279.990783)
			(xy 367.556483 -280.043487) (xy 367.540773 -280.094417) (xy 367.517647 -280.142438) (xy 367.487623 -280.186475)
			(xy 367.451371 -280.225546) (xy 367.4097 -280.258777) (xy 367.363542 -280.285426) (xy 367.313928 -280.304898)
			(xy 367.261966 -280.316758) (xy 367.208816 -280.320742) (xy 367.155666 -280.316758) (xy 367.103704 -280.304898)
			(xy 367.05409 -280.285426) (xy 367.007932 -280.258777) (xy 366.966261 -280.225546) (xy 366.930009 -280.186475)
			(xy 366.899985 -280.142438) (xy 366.876859 -280.094417) (xy 366.861149 -280.043487) (xy 366.853206 -279.990783)
			(xy 366.624372 -279.990783) (xy 366.616429 -280.043487) (xy 366.600719 -280.094417) (xy 366.577593 -280.142438)
			(xy 366.547569 -280.186475) (xy 366.511317 -280.225546) (xy 366.469646 -280.258777) (xy 366.423488 -280.285426)
			(xy 366.373874 -280.304898) (xy 366.321912 -280.316758) (xy 366.268762 -280.320742) (xy 366.215612 -280.316758)
			(xy 366.16365 -280.304898) (xy 366.114036 -280.285426) (xy 366.067878 -280.258777) (xy 366.026207 -280.225546)
			(xy 365.989955 -280.186475) (xy 365.959931 -280.142438) (xy 365.936805 -280.094417) (xy 365.921095 -280.043487)
			(xy 365.913152 -279.990783) (xy 364.950248 -279.990783) (xy 364.950248 -280.432002) (xy 364.983268 -280.444448)
			(xy 365.008455 -280.454342) (xy 365.055747 -280.480642) (xy 365.098518 -280.513792) (xy 365.135783 -280.553028)
			(xy 365.166686 -280.59745) (xy 365.190515 -280.646033) (xy 365.206722 -280.697662) (xy 365.214936 -280.751148)
			(xy 365.215424 -280.778204) (xy 365.214912 -280.804853) (xy 365.443506 -280.804853) (xy 365.443506 -280.751555)
			(xy 365.451449 -280.698851) (xy 365.467159 -280.647921) (xy 365.490285 -280.5999) (xy 365.520309 -280.555863)
			(xy 365.556561 -280.516792) (xy 365.598232 -280.483561) (xy 365.64439 -280.456912) (xy 365.694004 -280.43744)
			(xy 365.745966 -280.42558) (xy 365.799116 -280.421597) (xy 365.852266 -280.42558) (xy 365.904228 -280.43744)
			(xy 365.953842 -280.456912) (xy 366 -280.483561) (xy 366.041671 -280.516792) (xy 366.077923 -280.555863)
			(xy 366.107947 -280.5999) (xy 366.131073 -280.647921) (xy 366.146783 -280.698851) (xy 366.154726 -280.751555)
			(xy 366.155224 -280.778204) (xy 366.154726 -280.804853) (xy 366.383052 -280.804853) (xy 366.383052 -280.751555)
			(xy 366.390995 -280.698851) (xy 366.406705 -280.647921) (xy 366.429831 -280.5999) (xy 366.459855 -280.555863)
			(xy 366.496107 -280.516792) (xy 366.537778 -280.483561) (xy 366.583936 -280.456912) (xy 366.63355 -280.43744)
			(xy 366.685512 -280.42558) (xy 366.738662 -280.421597) (xy 366.791812 -280.42558) (xy 366.843774 -280.43744)
			(xy 366.893388 -280.456912) (xy 366.939546 -280.483561) (xy 366.981217 -280.516792) (xy 367.017469 -280.555863)
			(xy 367.047493 -280.5999) (xy 367.070619 -280.647921) (xy 367.086329 -280.698851) (xy 367.094272 -280.751555)
			(xy 367.09477 -280.778204) (xy 367.094272 -280.804853) (xy 367.322852 -280.804853) (xy 367.322852 -280.751555)
			(xy 367.330795 -280.698851) (xy 367.346505 -280.647921) (xy 367.369631 -280.5999) (xy 367.399655 -280.555863)
			(xy 367.435907 -280.516792) (xy 367.477578 -280.483561) (xy 367.523736 -280.456912) (xy 367.57335 -280.43744)
			(xy 367.625312 -280.42558) (xy 367.678462 -280.421597) (xy 367.731612 -280.42558) (xy 367.783574 -280.43744)
			(xy 367.833188 -280.456912) (xy 367.879346 -280.483561) (xy 367.921017 -280.516792) (xy 367.957269 -280.555863)
			(xy 367.987293 -280.5999) (xy 368.010419 -280.647921) (xy 368.026129 -280.698851) (xy 368.034072 -280.751555)
			(xy 368.03457 -280.778204) (xy 368.034072 -280.804853) (xy 368.262652 -280.804853) (xy 368.262652 -280.751555)
			(xy 368.270595 -280.698851) (xy 368.286305 -280.647921) (xy 368.309431 -280.5999) (xy 368.339455 -280.555863)
			(xy 368.375707 -280.516792) (xy 368.417378 -280.483561) (xy 368.463536 -280.456912) (xy 368.51315 -280.43744)
			(xy 368.565112 -280.42558) (xy 368.618262 -280.421597) (xy 368.671412 -280.42558) (xy 368.723374 -280.43744)
			(xy 368.772988 -280.456912) (xy 368.819146 -280.483561) (xy 368.860817 -280.516792) (xy 368.897069 -280.555863)
			(xy 368.927093 -280.5999) (xy 368.950219 -280.647921) (xy 368.965929 -280.698851) (xy 368.973872 -280.751555)
			(xy 368.97437 -280.778204) (xy 368.973872 -280.804853) (xy 369.202452 -280.804853) (xy 369.202452 -280.751555)
			(xy 369.210395 -280.698851) (xy 369.226105 -280.647921) (xy 369.249231 -280.5999) (xy 369.279255 -280.555863)
			(xy 369.315507 -280.516792) (xy 369.357178 -280.483561) (xy 369.403336 -280.456912) (xy 369.45295 -280.43744)
			(xy 369.504912 -280.42558) (xy 369.558062 -280.421597) (xy 369.611212 -280.42558) (xy 369.663174 -280.43744)
			(xy 369.712788 -280.456912) (xy 369.758946 -280.483561) (xy 369.800617 -280.516792) (xy 369.836869 -280.555863)
			(xy 369.866893 -280.5999) (xy 369.890019 -280.647921) (xy 369.905729 -280.698851) (xy 369.913672 -280.751555)
			(xy 369.91417 -280.778204) (xy 369.913672 -280.804853) (xy 370.142252 -280.804853) (xy 370.142252 -280.751555)
			(xy 370.150195 -280.698851) (xy 370.165905 -280.647921) (xy 370.189031 -280.5999) (xy 370.219055 -280.555863)
			(xy 370.255307 -280.516792) (xy 370.296978 -280.483561) (xy 370.343136 -280.456912) (xy 370.39275 -280.43744)
			(xy 370.444712 -280.42558) (xy 370.497862 -280.421597) (xy 370.551012 -280.42558) (xy 370.602974 -280.43744)
			(xy 370.652588 -280.456912) (xy 370.698746 -280.483561) (xy 370.740417 -280.516792) (xy 370.776669 -280.555863)
			(xy 370.806693 -280.5999) (xy 370.829819 -280.647921) (xy 370.845529 -280.698851) (xy 370.853472 -280.751555)
			(xy 370.85397 -280.778204) (xy 370.853472 -280.804853) (xy 371.082052 -280.804853) (xy 371.082052 -280.751555)
			(xy 371.089995 -280.698851) (xy 371.105705 -280.647921) (xy 371.128831 -280.5999) (xy 371.158855 -280.555863)
			(xy 371.195107 -280.516792) (xy 371.236778 -280.483561) (xy 371.282936 -280.456912) (xy 371.33255 -280.43744)
			(xy 371.384512 -280.42558) (xy 371.437662 -280.421597) (xy 371.490812 -280.42558) (xy 371.542774 -280.43744)
			(xy 371.592388 -280.456912) (xy 371.638546 -280.483561) (xy 371.680217 -280.516792) (xy 371.716469 -280.555863)
			(xy 371.746493 -280.5999) (xy 371.769619 -280.647921) (xy 371.785329 -280.698851) (xy 371.793272 -280.751555)
			(xy 371.79377 -280.778204) (xy 371.793272 -280.804853) (xy 372.021852 -280.804853) (xy 372.021852 -280.751555)
			(xy 372.029795 -280.698851) (xy 372.045505 -280.647921) (xy 372.068631 -280.5999) (xy 372.098655 -280.555863)
			(xy 372.134907 -280.516792) (xy 372.176578 -280.483561) (xy 372.222736 -280.456912) (xy 372.27235 -280.43744)
			(xy 372.324312 -280.42558) (xy 372.377462 -280.421597) (xy 372.430612 -280.42558) (xy 372.482574 -280.43744)
			(xy 372.532188 -280.456912) (xy 372.578346 -280.483561) (xy 372.620017 -280.516792) (xy 372.656269 -280.555863)
			(xy 372.686293 -280.5999) (xy 372.709419 -280.647921) (xy 372.725129 -280.698851) (xy 372.733072 -280.751555)
			(xy 372.73357 -280.778204) (xy 372.733072 -280.804853) (xy 372.961652 -280.804853) (xy 372.961652 -280.751555)
			(xy 372.969595 -280.698851) (xy 372.985305 -280.647921) (xy 373.008431 -280.5999) (xy 373.038455 -280.555863)
			(xy 373.074707 -280.516792) (xy 373.116378 -280.483561) (xy 373.162536 -280.456912) (xy 373.21215 -280.43744)
			(xy 373.264112 -280.42558) (xy 373.317262 -280.421597) (xy 373.370412 -280.42558) (xy 373.422374 -280.43744)
			(xy 373.471988 -280.456912) (xy 373.518146 -280.483561) (xy 373.559817 -280.516792) (xy 373.596069 -280.555863)
			(xy 373.626093 -280.5999) (xy 373.649219 -280.647921) (xy 373.664929 -280.698851) (xy 373.672872 -280.751555)
			(xy 373.67337 -280.778204) (xy 373.672872 -280.804853) (xy 373.901706 -280.804853) (xy 373.901706 -280.751555)
			(xy 373.909649 -280.698851) (xy 373.925359 -280.647921) (xy 373.948485 -280.5999) (xy 373.978509 -280.555863)
			(xy 374.014761 -280.516792) (xy 374.056432 -280.483561) (xy 374.10259 -280.456912) (xy 374.152204 -280.43744)
			(xy 374.204166 -280.42558) (xy 374.257316 -280.421597) (xy 374.310466 -280.42558) (xy 374.362428 -280.43744)
			(xy 374.412042 -280.456912) (xy 374.4582 -280.483561) (xy 374.499871 -280.516792) (xy 374.536123 -280.555863)
			(xy 374.566147 -280.5999) (xy 374.589273 -280.647921) (xy 374.604983 -280.698851) (xy 374.612926 -280.751555)
			(xy 374.613424 -280.778204) (xy 374.612926 -280.804853) (xy 374.841506 -280.804853) (xy 374.841506 -280.751555)
			(xy 374.849449 -280.698851) (xy 374.865159 -280.647921) (xy 374.888285 -280.5999) (xy 374.918309 -280.555863)
			(xy 374.954561 -280.516792) (xy 374.996232 -280.483561) (xy 375.04239 -280.456912) (xy 375.092004 -280.43744)
			(xy 375.143966 -280.42558) (xy 375.197116 -280.421597) (xy 375.250266 -280.42558) (xy 375.302228 -280.43744)
			(xy 375.351842 -280.456912) (xy 375.398 -280.483561) (xy 375.439671 -280.516792) (xy 375.475923 -280.555863)
			(xy 375.505947 -280.5999) (xy 375.529073 -280.647921) (xy 375.544783 -280.698851) (xy 375.552726 -280.751555)
			(xy 375.553224 -280.778204) (xy 375.552726 -280.804853) (xy 375.781306 -280.804853) (xy 375.781306 -280.751555)
			(xy 375.789249 -280.698851) (xy 375.804959 -280.647921) (xy 375.828085 -280.5999) (xy 375.858109 -280.555863)
			(xy 375.894361 -280.516792) (xy 375.936032 -280.483561) (xy 375.98219 -280.456912) (xy 376.031804 -280.43744)
			(xy 376.083766 -280.42558) (xy 376.136916 -280.421597) (xy 376.190066 -280.42558) (xy 376.242028 -280.43744)
			(xy 376.291642 -280.456912) (xy 376.3378 -280.483561) (xy 376.379471 -280.516792) (xy 376.415723 -280.555863)
			(xy 376.445747 -280.5999) (xy 376.468873 -280.647921) (xy 376.484583 -280.698851) (xy 376.492526 -280.751555)
			(xy 376.493024 -280.778204) (xy 376.492526 -280.804853) (xy 376.721106 -280.804853) (xy 376.721106 -280.751555)
			(xy 376.729049 -280.698851) (xy 376.744759 -280.647921) (xy 376.767885 -280.5999) (xy 376.797909 -280.555863)
			(xy 376.834161 -280.516792) (xy 376.875832 -280.483561) (xy 376.92199 -280.456912) (xy 376.971604 -280.43744)
			(xy 377.023566 -280.42558) (xy 377.076716 -280.421597) (xy 377.129866 -280.42558) (xy 377.181828 -280.43744)
			(xy 377.231442 -280.456912) (xy 377.2776 -280.483561) (xy 377.319271 -280.516792) (xy 377.355523 -280.555863)
			(xy 377.385547 -280.5999) (xy 377.408673 -280.647921) (xy 377.424383 -280.698851) (xy 377.432326 -280.751555)
			(xy 377.432824 -280.778204) (xy 377.432326 -280.804853) (xy 377.660906 -280.804853) (xy 377.660906 -280.751555)
			(xy 377.668849 -280.698851) (xy 377.684559 -280.647921) (xy 377.707685 -280.5999) (xy 377.737709 -280.555863)
			(xy 377.773961 -280.516792) (xy 377.815632 -280.483561) (xy 377.86179 -280.456912) (xy 377.911404 -280.43744)
			(xy 377.963366 -280.42558) (xy 378.016516 -280.421597) (xy 378.069666 -280.42558) (xy 378.121628 -280.43744)
			(xy 378.171242 -280.456912) (xy 378.2174 -280.483561) (xy 378.259071 -280.516792) (xy 378.295323 -280.555863)
			(xy 378.325347 -280.5999) (xy 378.348473 -280.647921) (xy 378.364183 -280.698851) (xy 378.372126 -280.751555)
			(xy 378.372624 -280.778204) (xy 378.372126 -280.804853) (xy 378.600452 -280.804853) (xy 378.600452 -280.751555)
			(xy 378.608395 -280.698851) (xy 378.624105 -280.647921) (xy 378.647231 -280.5999) (xy 378.677255 -280.555863)
			(xy 378.713507 -280.516792) (xy 378.755178 -280.483561) (xy 378.801336 -280.456912) (xy 378.85095 -280.43744)
			(xy 378.902912 -280.42558) (xy 378.956062 -280.421597) (xy 379.009212 -280.42558) (xy 379.061174 -280.43744)
			(xy 379.110788 -280.456912) (xy 379.156946 -280.483561) (xy 379.198617 -280.516792) (xy 379.234869 -280.555863)
			(xy 379.264893 -280.5999) (xy 379.288019 -280.647921) (xy 379.303729 -280.698851) (xy 379.311672 -280.751555)
			(xy 379.31217 -280.778204) (xy 379.311672 -280.804853) (xy 379.540252 -280.804853) (xy 379.540252 -280.751555)
			(xy 379.548195 -280.698851) (xy 379.563905 -280.647921) (xy 379.587031 -280.5999) (xy 379.617055 -280.555863)
			(xy 379.653307 -280.516792) (xy 379.694978 -280.483561) (xy 379.741136 -280.456912) (xy 379.79075 -280.43744)
			(xy 379.842712 -280.42558) (xy 379.895862 -280.421597) (xy 379.949012 -280.42558) (xy 380.000974 -280.43744)
			(xy 380.050588 -280.456912) (xy 380.096746 -280.483561) (xy 380.138417 -280.516792) (xy 380.174669 -280.555863)
			(xy 380.204693 -280.5999) (xy 380.227819 -280.647921) (xy 380.243529 -280.698851) (xy 380.251472 -280.751555)
			(xy 380.25197 -280.778204) (xy 380.251472 -280.804853) (xy 380.480052 -280.804853) (xy 380.480052 -280.751555)
			(xy 380.487995 -280.698851) (xy 380.503705 -280.647921) (xy 380.526831 -280.5999) (xy 380.556855 -280.555863)
			(xy 380.593107 -280.516792) (xy 380.634778 -280.483561) (xy 380.680936 -280.456912) (xy 380.73055 -280.43744)
			(xy 380.782512 -280.42558) (xy 380.835662 -280.421597) (xy 380.888812 -280.42558) (xy 380.940774 -280.43744)
			(xy 380.990388 -280.456912) (xy 381.036546 -280.483561) (xy 381.078217 -280.516792) (xy 381.114469 -280.555863)
			(xy 381.144493 -280.5999) (xy 381.167619 -280.647921) (xy 381.183329 -280.698851) (xy 381.191272 -280.751555)
			(xy 381.19177 -280.778204) (xy 381.191272 -280.804853) (xy 381.419852 -280.804853) (xy 381.419852 -280.751555)
			(xy 381.427795 -280.698851) (xy 381.443505 -280.647921) (xy 381.466631 -280.5999) (xy 381.496655 -280.555863)
			(xy 381.532907 -280.516792) (xy 381.574578 -280.483561) (xy 381.620736 -280.456912) (xy 381.67035 -280.43744)
			(xy 381.722312 -280.42558) (xy 381.775462 -280.421597) (xy 381.828612 -280.42558) (xy 381.880574 -280.43744)
			(xy 381.930188 -280.456912) (xy 381.976346 -280.483561) (xy 382.018017 -280.516792) (xy 382.054269 -280.555863)
			(xy 382.084293 -280.5999) (xy 382.107419 -280.647921) (xy 382.123129 -280.698851) (xy 382.131072 -280.751555)
			(xy 382.13157 -280.778204) (xy 382.131072 -280.804853) (xy 383.299452 -280.804853) (xy 383.299452 -280.751555)
			(xy 383.307395 -280.698851) (xy 383.323105 -280.647921) (xy 383.346231 -280.5999) (xy 383.376255 -280.555863)
			(xy 383.412507 -280.516792) (xy 383.454178 -280.483561) (xy 383.500336 -280.456912) (xy 383.54995 -280.43744)
			(xy 383.601912 -280.42558) (xy 383.655062 -280.421597) (xy 383.708212 -280.42558) (xy 383.760174 -280.43744)
			(xy 383.809788 -280.456912) (xy 383.855946 -280.483561) (xy 383.897617 -280.516792) (xy 383.933869 -280.555863)
			(xy 383.963893 -280.5999) (xy 383.987019 -280.647921) (xy 384.002729 -280.698851) (xy 384.010672 -280.751555)
			(xy 384.01117 -280.778204) (xy 384.010672 -280.804853) (xy 384.002729 -280.857557) (xy 383.987019 -280.908487)
			(xy 383.963893 -280.956508) (xy 383.933869 -281.000545) (xy 383.897617 -281.039616) (xy 383.855946 -281.072847)
			(xy 383.809788 -281.099496) (xy 383.760174 -281.118968) (xy 383.708212 -281.130828) (xy 383.655062 -281.134812)
			(xy 383.601912 -281.130828) (xy 383.54995 -281.118968) (xy 383.500336 -281.099496) (xy 383.454178 -281.072847)
			(xy 383.412507 -281.039616) (xy 383.376255 -281.000545) (xy 383.346231 -280.956508) (xy 383.323105 -280.908487)
			(xy 383.307395 -280.857557) (xy 383.299452 -280.804853) (xy 382.131072 -280.804853) (xy 382.123129 -280.857557)
			(xy 382.107419 -280.908487) (xy 382.084293 -280.956508) (xy 382.054269 -281.000545) (xy 382.018017 -281.039616)
			(xy 381.976346 -281.072847) (xy 381.930188 -281.099496) (xy 381.880574 -281.118968) (xy 381.828612 -281.130828)
			(xy 381.775462 -281.134812) (xy 381.722312 -281.130828) (xy 381.67035 -281.118968) (xy 381.620736 -281.099496)
			(xy 381.574578 -281.072847) (xy 381.532907 -281.039616) (xy 381.496655 -281.000545) (xy 381.466631 -280.956508)
			(xy 381.443505 -280.908487) (xy 381.427795 -280.857557) (xy 381.419852 -280.804853) (xy 381.191272 -280.804853)
			(xy 381.183329 -280.857557) (xy 381.167619 -280.908487) (xy 381.144493 -280.956508) (xy 381.114469 -281.000545)
			(xy 381.078217 -281.039616) (xy 381.036546 -281.072847) (xy 380.990388 -281.099496) (xy 380.940774 -281.118968)
			(xy 380.888812 -281.130828) (xy 380.835662 -281.134812) (xy 380.782512 -281.130828) (xy 380.73055 -281.118968)
			(xy 380.680936 -281.099496) (xy 380.634778 -281.072847) (xy 380.593107 -281.039616) (xy 380.556855 -281.000545)
			(xy 380.526831 -280.956508) (xy 380.503705 -280.908487) (xy 380.487995 -280.857557) (xy 380.480052 -280.804853)
			(xy 380.251472 -280.804853) (xy 380.243529 -280.857557) (xy 380.227819 -280.908487) (xy 380.204693 -280.956508)
			(xy 380.174669 -281.000545) (xy 380.138417 -281.039616) (xy 380.096746 -281.072847) (xy 380.050588 -281.099496)
			(xy 380.000974 -281.118968) (xy 379.949012 -281.130828) (xy 379.895862 -281.134812) (xy 379.842712 -281.130828)
			(xy 379.79075 -281.118968) (xy 379.741136 -281.099496) (xy 379.694978 -281.072847) (xy 379.653307 -281.039616)
			(xy 379.617055 -281.000545) (xy 379.587031 -280.956508) (xy 379.563905 -280.908487) (xy 379.548195 -280.857557)
			(xy 379.540252 -280.804853) (xy 379.311672 -280.804853) (xy 379.303729 -280.857557) (xy 379.288019 -280.908487)
			(xy 379.264893 -280.956508) (xy 379.234869 -281.000545) (xy 379.198617 -281.039616) (xy 379.156946 -281.072847)
			(xy 379.110788 -281.099496) (xy 379.061174 -281.118968) (xy 379.009212 -281.130828) (xy 378.956062 -281.134812)
			(xy 378.902912 -281.130828) (xy 378.85095 -281.118968) (xy 378.801336 -281.099496) (xy 378.755178 -281.072847)
			(xy 378.713507 -281.039616) (xy 378.677255 -281.000545) (xy 378.647231 -280.956508) (xy 378.624105 -280.908487)
			(xy 378.608395 -280.857557) (xy 378.600452 -280.804853) (xy 378.372126 -280.804853) (xy 378.364183 -280.857557)
			(xy 378.348473 -280.908487) (xy 378.325347 -280.956508) (xy 378.295323 -281.000545) (xy 378.259071 -281.039616)
			(xy 378.2174 -281.072847) (xy 378.171242 -281.099496) (xy 378.121628 -281.118968) (xy 378.069666 -281.130828)
			(xy 378.016516 -281.134812) (xy 377.963366 -281.130828) (xy 377.911404 -281.118968) (xy 377.86179 -281.099496)
			(xy 377.815632 -281.072847) (xy 377.773961 -281.039616) (xy 377.737709 -281.000545) (xy 377.707685 -280.956508)
			(xy 377.684559 -280.908487) (xy 377.668849 -280.857557) (xy 377.660906 -280.804853) (xy 377.432326 -280.804853)
			(xy 377.424383 -280.857557) (xy 377.408673 -280.908487) (xy 377.385547 -280.956508) (xy 377.355523 -281.000545)
			(xy 377.319271 -281.039616) (xy 377.2776 -281.072847) (xy 377.231442 -281.099496) (xy 377.181828 -281.118968)
			(xy 377.129866 -281.130828) (xy 377.076716 -281.134812) (xy 377.023566 -281.130828) (xy 376.971604 -281.118968)
			(xy 376.92199 -281.099496) (xy 376.875832 -281.072847) (xy 376.834161 -281.039616) (xy 376.797909 -281.000545)
			(xy 376.767885 -280.956508) (xy 376.744759 -280.908487) (xy 376.729049 -280.857557) (xy 376.721106 -280.804853)
			(xy 376.492526 -280.804853) (xy 376.484583 -280.857557) (xy 376.468873 -280.908487) (xy 376.445747 -280.956508)
			(xy 376.415723 -281.000545) (xy 376.379471 -281.039616) (xy 376.3378 -281.072847) (xy 376.291642 -281.099496)
			(xy 376.242028 -281.118968) (xy 376.190066 -281.130828) (xy 376.136916 -281.134812) (xy 376.083766 -281.130828)
			(xy 376.031804 -281.118968) (xy 375.98219 -281.099496) (xy 375.936032 -281.072847) (xy 375.894361 -281.039616)
			(xy 375.858109 -281.000545) (xy 375.828085 -280.956508) (xy 375.804959 -280.908487) (xy 375.789249 -280.857557)
			(xy 375.781306 -280.804853) (xy 375.552726 -280.804853) (xy 375.544783 -280.857557) (xy 375.529073 -280.908487)
			(xy 375.505947 -280.956508) (xy 375.475923 -281.000545) (xy 375.439671 -281.039616) (xy 375.398 -281.072847)
			(xy 375.351842 -281.099496) (xy 375.302228 -281.118968) (xy 375.250266 -281.130828) (xy 375.197116 -281.134812)
			(xy 375.143966 -281.130828) (xy 375.092004 -281.118968) (xy 375.04239 -281.099496) (xy 374.996232 -281.072847)
			(xy 374.954561 -281.039616) (xy 374.918309 -281.000545) (xy 374.888285 -280.956508) (xy 374.865159 -280.908487)
			(xy 374.849449 -280.857557) (xy 374.841506 -280.804853) (xy 374.612926 -280.804853) (xy 374.604983 -280.857557)
			(xy 374.589273 -280.908487) (xy 374.566147 -280.956508) (xy 374.536123 -281.000545) (xy 374.499871 -281.039616)
			(xy 374.4582 -281.072847) (xy 374.412042 -281.099496) (xy 374.362428 -281.118968) (xy 374.310466 -281.130828)
			(xy 374.257316 -281.134812) (xy 374.204166 -281.130828) (xy 374.152204 -281.118968) (xy 374.10259 -281.099496)
			(xy 374.056432 -281.072847) (xy 374.014761 -281.039616) (xy 373.978509 -281.000545) (xy 373.948485 -280.956508)
			(xy 373.925359 -280.908487) (xy 373.909649 -280.857557) (xy 373.901706 -280.804853) (xy 373.672872 -280.804853)
			(xy 373.664929 -280.857557) (xy 373.649219 -280.908487) (xy 373.626093 -280.956508) (xy 373.596069 -281.000545)
			(xy 373.559817 -281.039616) (xy 373.518146 -281.072847) (xy 373.471988 -281.099496) (xy 373.422374 -281.118968)
			(xy 373.370412 -281.130828) (xy 373.317262 -281.134812) (xy 373.264112 -281.130828) (xy 373.21215 -281.118968)
			(xy 373.162536 -281.099496) (xy 373.116378 -281.072847) (xy 373.074707 -281.039616) (xy 373.038455 -281.000545)
			(xy 373.008431 -280.956508) (xy 372.985305 -280.908487) (xy 372.969595 -280.857557) (xy 372.961652 -280.804853)
			(xy 372.733072 -280.804853) (xy 372.725129 -280.857557) (xy 372.709419 -280.908487) (xy 372.686293 -280.956508)
			(xy 372.656269 -281.000545) (xy 372.620017 -281.039616) (xy 372.578346 -281.072847) (xy 372.532188 -281.099496)
			(xy 372.482574 -281.118968) (xy 372.430612 -281.130828) (xy 372.377462 -281.134812) (xy 372.324312 -281.130828)
			(xy 372.27235 -281.118968) (xy 372.222736 -281.099496) (xy 372.176578 -281.072847) (xy 372.134907 -281.039616)
			(xy 372.098655 -281.000545) (xy 372.068631 -280.956508) (xy 372.045505 -280.908487) (xy 372.029795 -280.857557)
			(xy 372.021852 -280.804853) (xy 371.793272 -280.804853) (xy 371.785329 -280.857557) (xy 371.769619 -280.908487)
			(xy 371.746493 -280.956508) (xy 371.716469 -281.000545) (xy 371.680217 -281.039616) (xy 371.638546 -281.072847)
			(xy 371.592388 -281.099496) (xy 371.542774 -281.118968) (xy 371.490812 -281.130828) (xy 371.437662 -281.134812)
			(xy 371.384512 -281.130828) (xy 371.33255 -281.118968) (xy 371.282936 -281.099496) (xy 371.236778 -281.072847)
			(xy 371.195107 -281.039616) (xy 371.158855 -281.000545) (xy 371.128831 -280.956508) (xy 371.105705 -280.908487)
			(xy 371.089995 -280.857557) (xy 371.082052 -280.804853) (xy 370.853472 -280.804853) (xy 370.845529 -280.857557)
			(xy 370.829819 -280.908487) (xy 370.806693 -280.956508) (xy 370.776669 -281.000545) (xy 370.740417 -281.039616)
			(xy 370.698746 -281.072847) (xy 370.652588 -281.099496) (xy 370.602974 -281.118968) (xy 370.551012 -281.130828)
			(xy 370.497862 -281.134812) (xy 370.444712 -281.130828) (xy 370.39275 -281.118968) (xy 370.343136 -281.099496)
			(xy 370.296978 -281.072847) (xy 370.255307 -281.039616) (xy 370.219055 -281.000545) (xy 370.189031 -280.956508)
			(xy 370.165905 -280.908487) (xy 370.150195 -280.857557) (xy 370.142252 -280.804853) (xy 369.913672 -280.804853)
			(xy 369.905729 -280.857557) (xy 369.890019 -280.908487) (xy 369.866893 -280.956508) (xy 369.836869 -281.000545)
			(xy 369.800617 -281.039616) (xy 369.758946 -281.072847) (xy 369.712788 -281.099496) (xy 369.663174 -281.118968)
			(xy 369.611212 -281.130828) (xy 369.558062 -281.134812) (xy 369.504912 -281.130828) (xy 369.45295 -281.118968)
			(xy 369.403336 -281.099496) (xy 369.357178 -281.072847) (xy 369.315507 -281.039616) (xy 369.279255 -281.000545)
			(xy 369.249231 -280.956508) (xy 369.226105 -280.908487) (xy 369.210395 -280.857557) (xy 369.202452 -280.804853)
			(xy 368.973872 -280.804853) (xy 368.965929 -280.857557) (xy 368.950219 -280.908487) (xy 368.927093 -280.956508)
			(xy 368.897069 -281.000545) (xy 368.860817 -281.039616) (xy 368.819146 -281.072847) (xy 368.772988 -281.099496)
			(xy 368.723374 -281.118968) (xy 368.671412 -281.130828) (xy 368.618262 -281.134812) (xy 368.565112 -281.130828)
			(xy 368.51315 -281.118968) (xy 368.463536 -281.099496) (xy 368.417378 -281.072847) (xy 368.375707 -281.039616)
			(xy 368.339455 -281.000545) (xy 368.309431 -280.956508) (xy 368.286305 -280.908487) (xy 368.270595 -280.857557)
			(xy 368.262652 -280.804853) (xy 368.034072 -280.804853) (xy 368.026129 -280.857557) (xy 368.010419 -280.908487)
			(xy 367.987293 -280.956508) (xy 367.957269 -281.000545) (xy 367.921017 -281.039616) (xy 367.879346 -281.072847)
			(xy 367.833188 -281.099496) (xy 367.783574 -281.118968) (xy 367.731612 -281.130828) (xy 367.678462 -281.134812)
			(xy 367.625312 -281.130828) (xy 367.57335 -281.118968) (xy 367.523736 -281.099496) (xy 367.477578 -281.072847)
			(xy 367.435907 -281.039616) (xy 367.399655 -281.000545) (xy 367.369631 -280.956508) (xy 367.346505 -280.908487)
			(xy 367.330795 -280.857557) (xy 367.322852 -280.804853) (xy 367.094272 -280.804853) (xy 367.086329 -280.857557)
			(xy 367.070619 -280.908487) (xy 367.047493 -280.956508) (xy 367.017469 -281.000545) (xy 366.981217 -281.039616)
			(xy 366.939546 -281.072847) (xy 366.893388 -281.099496) (xy 366.843774 -281.118968) (xy 366.791812 -281.130828)
			(xy 366.738662 -281.134812) (xy 366.685512 -281.130828) (xy 366.63355 -281.118968) (xy 366.583936 -281.099496)
			(xy 366.537778 -281.072847) (xy 366.496107 -281.039616) (xy 366.459855 -281.000545) (xy 366.429831 -280.956508)
			(xy 366.406705 -280.908487) (xy 366.390995 -280.857557) (xy 366.383052 -280.804853) (xy 366.154726 -280.804853)
			(xy 366.146783 -280.857557) (xy 366.131073 -280.908487) (xy 366.107947 -280.956508) (xy 366.077923 -281.000545)
			(xy 366.041671 -281.039616) (xy 366 -281.072847) (xy 365.953842 -281.099496) (xy 365.904228 -281.118968)
			(xy 365.852266 -281.130828) (xy 365.799116 -281.134812) (xy 365.745966 -281.130828) (xy 365.694004 -281.118968)
			(xy 365.64439 -281.099496) (xy 365.598232 -281.072847) (xy 365.556561 -281.039616) (xy 365.520309 -281.000545)
			(xy 365.490285 -280.956508) (xy 365.467159 -280.908487) (xy 365.451449 -280.857557) (xy 365.443506 -280.804853)
			(xy 365.214912 -280.804853) (xy 365.21488 -280.806496) (xy 365.205937 -280.862368) (xy 365.188276 -280.916125)
			(xy 365.162341 -280.966415) (xy 365.128784 -281.011975) (xy 365.108998 -281.032204) (xy 365.099743 -281.041883)
			(xy 365.086201 -281.064976) (xy 365.079118 -281.090793) (xy 365.07898 -281.117563) (xy 365.085797 -281.143452)
			(xy 365.099101 -281.166683) (xy 365.108236 -281.176476) (xy 365.193326 -281.261566) (xy 365.222536 -281.252168)
			(xy 365.248545 -281.244553) (xy 365.302119 -281.236388) (xy 365.329216 -281.235912) (xy 365.3572 -281.236434)
			(xy 365.412478 -281.245192) (xy 365.465706 -281.262489) (xy 365.515573 -281.2879) (xy 365.56085 -281.3208)
			(xy 365.600424 -281.360377) (xy 365.633318 -281.405658) (xy 365.658725 -281.455527) (xy 365.676017 -281.508757)
			(xy 365.684769 -281.564036) (xy 365.685324 -281.59202) (xy 365.684842 -281.618669) (xy 365.913152 -281.618669)
			(xy 365.913152 -281.565371) (xy 365.921095 -281.512667) (xy 365.936805 -281.461737) (xy 365.959931 -281.413716)
			(xy 365.989955 -281.369679) (xy 366.026207 -281.330608) (xy 366.067878 -281.297377) (xy 366.114036 -281.270728)
			(xy 366.16365 -281.251256) (xy 366.215612 -281.239396) (xy 366.268762 -281.235413) (xy 366.321912 -281.239396)
			(xy 366.373874 -281.251256) (xy 366.423488 -281.270728) (xy 366.469646 -281.297377) (xy 366.511317 -281.330608)
			(xy 366.547569 -281.369679) (xy 366.577593 -281.413716) (xy 366.600719 -281.461737) (xy 366.616429 -281.512667)
			(xy 366.624372 -281.565371) (xy 366.62487 -281.59202) (xy 366.624372 -281.618669) (xy 366.853206 -281.618669)
			(xy 366.853206 -281.565371) (xy 366.861149 -281.512667) (xy 366.876859 -281.461737) (xy 366.899985 -281.413716)
			(xy 366.930009 -281.369679) (xy 366.966261 -281.330608) (xy 367.007932 -281.297377) (xy 367.05409 -281.270728)
			(xy 367.103704 -281.251256) (xy 367.155666 -281.239396) (xy 367.208816 -281.235413) (xy 367.261966 -281.239396)
			(xy 367.313928 -281.251256) (xy 367.363542 -281.270728) (xy 367.4097 -281.297377) (xy 367.451371 -281.330608)
			(xy 367.487623 -281.369679) (xy 367.517647 -281.413716) (xy 367.540773 -281.461737) (xy 367.556483 -281.512667)
			(xy 367.564426 -281.565371) (xy 367.564924 -281.59202) (xy 367.564426 -281.618669) (xy 367.793006 -281.618669)
			(xy 367.793006 -281.565371) (xy 367.800949 -281.512667) (xy 367.816659 -281.461737) (xy 367.839785 -281.413716)
			(xy 367.869809 -281.369679) (xy 367.906061 -281.330608) (xy 367.947732 -281.297377) (xy 367.99389 -281.270728)
			(xy 368.043504 -281.251256) (xy 368.095466 -281.239396) (xy 368.148616 -281.235413) (xy 368.201766 -281.239396)
			(xy 368.253728 -281.251256) (xy 368.303342 -281.270728) (xy 368.3495 -281.297377) (xy 368.391171 -281.330608)
			(xy 368.427423 -281.369679) (xy 368.457447 -281.413716) (xy 368.480573 -281.461737) (xy 368.496283 -281.512667)
			(xy 368.504226 -281.565371) (xy 368.504724 -281.59202) (xy 368.504226 -281.618669) (xy 368.732806 -281.618669)
			(xy 368.732806 -281.565371) (xy 368.740749 -281.512667) (xy 368.756459 -281.461737) (xy 368.779585 -281.413716)
			(xy 368.809609 -281.369679) (xy 368.845861 -281.330608) (xy 368.887532 -281.297377) (xy 368.93369 -281.270728)
			(xy 368.983304 -281.251256) (xy 369.035266 -281.239396) (xy 369.088416 -281.235413) (xy 369.141566 -281.239396)
			(xy 369.193528 -281.251256) (xy 369.243142 -281.270728) (xy 369.2893 -281.297377) (xy 369.330971 -281.330608)
			(xy 369.367223 -281.369679) (xy 369.397247 -281.413716) (xy 369.420373 -281.461737) (xy 369.436083 -281.512667)
			(xy 369.444026 -281.565371) (xy 369.444524 -281.59202) (xy 369.444026 -281.618669) (xy 369.672606 -281.618669)
			(xy 369.672606 -281.565371) (xy 369.680549 -281.512667) (xy 369.696259 -281.461737) (xy 369.719385 -281.413716)
			(xy 369.749409 -281.369679) (xy 369.785661 -281.330608) (xy 369.827332 -281.297377) (xy 369.87349 -281.270728)
			(xy 369.923104 -281.251256) (xy 369.975066 -281.239396) (xy 370.028216 -281.235413) (xy 370.081366 -281.239396)
			(xy 370.133328 -281.251256) (xy 370.182942 -281.270728) (xy 370.2291 -281.297377) (xy 370.270771 -281.330608)
			(xy 370.307023 -281.369679) (xy 370.337047 -281.413716) (xy 370.360173 -281.461737) (xy 370.375883 -281.512667)
			(xy 370.383826 -281.565371) (xy 370.384324 -281.59202) (xy 370.383826 -281.618669) (xy 370.612406 -281.618669)
			(xy 370.612406 -281.565371) (xy 370.620349 -281.512667) (xy 370.636059 -281.461737) (xy 370.659185 -281.413716)
			(xy 370.689209 -281.369679) (xy 370.725461 -281.330608) (xy 370.767132 -281.297377) (xy 370.81329 -281.270728)
			(xy 370.862904 -281.251256) (xy 370.914866 -281.239396) (xy 370.968016 -281.235413) (xy 371.021166 -281.239396)
			(xy 371.073128 -281.251256) (xy 371.122742 -281.270728) (xy 371.1689 -281.297377) (xy 371.210571 -281.330608)
			(xy 371.246823 -281.369679) (xy 371.276847 -281.413716) (xy 371.299973 -281.461737) (xy 371.315683 -281.512667)
			(xy 371.323626 -281.565371) (xy 371.324124 -281.59202) (xy 371.323626 -281.618669) (xy 371.552206 -281.618669)
			(xy 371.552206 -281.565371) (xy 371.560149 -281.512667) (xy 371.575859 -281.461737) (xy 371.598985 -281.413716)
			(xy 371.629009 -281.369679) (xy 371.665261 -281.330608) (xy 371.706932 -281.297377) (xy 371.75309 -281.270728)
			(xy 371.802704 -281.251256) (xy 371.854666 -281.239396) (xy 371.907816 -281.235413) (xy 371.960966 -281.239396)
			(xy 372.012928 -281.251256) (xy 372.062542 -281.270728) (xy 372.1087 -281.297377) (xy 372.150371 -281.330608)
			(xy 372.186623 -281.369679) (xy 372.216647 -281.413716) (xy 372.239773 -281.461737) (xy 372.255483 -281.512667)
			(xy 372.263426 -281.565371) (xy 372.263924 -281.59202) (xy 372.263426 -281.618669) (xy 372.492006 -281.618669)
			(xy 372.492006 -281.565371) (xy 372.499949 -281.512667) (xy 372.515659 -281.461737) (xy 372.538785 -281.413716)
			(xy 372.568809 -281.369679) (xy 372.605061 -281.330608) (xy 372.646732 -281.297377) (xy 372.69289 -281.270728)
			(xy 372.742504 -281.251256) (xy 372.794466 -281.239396) (xy 372.847616 -281.235413) (xy 372.900766 -281.239396)
			(xy 372.952728 -281.251256) (xy 373.002342 -281.270728) (xy 373.0485 -281.297377) (xy 373.090171 -281.330608)
			(xy 373.126423 -281.369679) (xy 373.156447 -281.413716) (xy 373.179573 -281.461737) (xy 373.195283 -281.512667)
			(xy 373.203226 -281.565371) (xy 373.203724 -281.59202) (xy 373.203226 -281.618669) (xy 373.431806 -281.618669)
			(xy 373.431806 -281.565371) (xy 373.439749 -281.512667) (xy 373.455459 -281.461737) (xy 373.478585 -281.413716)
			(xy 373.508609 -281.369679) (xy 373.544861 -281.330608) (xy 373.586532 -281.297377) (xy 373.63269 -281.270728)
			(xy 373.682304 -281.251256) (xy 373.734266 -281.239396) (xy 373.787416 -281.235413) (xy 373.840566 -281.239396)
			(xy 373.892528 -281.251256) (xy 373.942142 -281.270728) (xy 373.9883 -281.297377) (xy 374.029971 -281.330608)
			(xy 374.066223 -281.369679) (xy 374.096247 -281.413716) (xy 374.119373 -281.461737) (xy 374.135083 -281.512667)
			(xy 374.143026 -281.565371) (xy 374.143524 -281.59202) (xy 374.143026 -281.618669) (xy 374.371352 -281.618669)
			(xy 374.371352 -281.565371) (xy 374.379295 -281.512667) (xy 374.395005 -281.461737) (xy 374.418131 -281.413716)
			(xy 374.448155 -281.369679) (xy 374.484407 -281.330608) (xy 374.526078 -281.297377) (xy 374.572236 -281.270728)
			(xy 374.62185 -281.251256) (xy 374.673812 -281.239396) (xy 374.726962 -281.235413) (xy 374.780112 -281.239396)
			(xy 374.832074 -281.251256) (xy 374.881688 -281.270728) (xy 374.927846 -281.297377) (xy 374.969517 -281.330608)
			(xy 375.005769 -281.369679) (xy 375.035793 -281.413716) (xy 375.058919 -281.461737) (xy 375.074629 -281.512667)
			(xy 375.082572 -281.565371) (xy 375.08307 -281.59202) (xy 375.082577 -281.618415) (xy 375.311152 -281.618415)
			(xy 375.311152 -281.565117) (xy 375.319095 -281.512413) (xy 375.334805 -281.461483) (xy 375.357931 -281.413462)
			(xy 375.387955 -281.369425) (xy 375.424207 -281.330354) (xy 375.465878 -281.297123) (xy 375.512036 -281.270474)
			(xy 375.56165 -281.251002) (xy 375.613612 -281.239142) (xy 375.666762 -281.235159) (xy 375.719912 -281.239142)
			(xy 375.771874 -281.251002) (xy 375.821488 -281.270474) (xy 375.867646 -281.297123) (xy 375.909317 -281.330354)
			(xy 375.945569 -281.369425) (xy 375.975593 -281.413462) (xy 375.998719 -281.461483) (xy 376.014429 -281.512413)
			(xy 376.022372 -281.565117) (xy 376.02287 -281.591766) (xy 376.022372 -281.618415) (xy 376.022334 -281.618669)
			(xy 376.251206 -281.618669) (xy 376.251206 -281.565371) (xy 376.259149 -281.512667) (xy 376.274859 -281.461737)
			(xy 376.297985 -281.413716) (xy 376.328009 -281.369679) (xy 376.364261 -281.330608) (xy 376.405932 -281.297377)
			(xy 376.45209 -281.270728) (xy 376.501704 -281.251256) (xy 376.553666 -281.239396) (xy 376.606816 -281.235413)
			(xy 376.659966 -281.239396) (xy 376.711928 -281.251256) (xy 376.761542 -281.270728) (xy 376.8077 -281.297377)
			(xy 376.849371 -281.330608) (xy 376.885623 -281.369679) (xy 376.915647 -281.413716) (xy 376.938773 -281.461737)
			(xy 376.954483 -281.512667) (xy 376.962426 -281.565371) (xy 376.962924 -281.59202) (xy 376.962426 -281.618669)
			(xy 377.190752 -281.618669) (xy 377.190752 -281.565371) (xy 377.198695 -281.512667) (xy 377.214405 -281.461737)
			(xy 377.237531 -281.413716) (xy 377.267555 -281.369679) (xy 377.303807 -281.330608) (xy 377.345478 -281.297377)
			(xy 377.391636 -281.270728) (xy 377.44125 -281.251256) (xy 377.493212 -281.239396) (xy 377.546362 -281.235413)
			(xy 377.599512 -281.239396) (xy 377.651474 -281.251256) (xy 377.701088 -281.270728) (xy 377.747246 -281.297377)
			(xy 377.788917 -281.330608) (xy 377.825169 -281.369679) (xy 377.855193 -281.413716) (xy 377.878319 -281.461737)
			(xy 377.894029 -281.512667) (xy 377.901972 -281.565371) (xy 377.90247 -281.59202) (xy 377.901972 -281.618669)
			(xy 378.130806 -281.618669) (xy 378.130806 -281.565371) (xy 378.138749 -281.512667) (xy 378.154459 -281.461737)
			(xy 378.177585 -281.413716) (xy 378.207609 -281.369679) (xy 378.243861 -281.330608) (xy 378.285532 -281.297377)
			(xy 378.33169 -281.270728) (xy 378.381304 -281.251256) (xy 378.433266 -281.239396) (xy 378.486416 -281.235413)
			(xy 378.539566 -281.239396) (xy 378.591528 -281.251256) (xy 378.641142 -281.270728) (xy 378.6873 -281.297377)
			(xy 378.728971 -281.330608) (xy 378.765223 -281.369679) (xy 378.795247 -281.413716) (xy 378.818373 -281.461737)
			(xy 378.834083 -281.512667) (xy 378.842026 -281.565371) (xy 378.842524 -281.59202) (xy 378.842026 -281.618669)
			(xy 379.070606 -281.618669) (xy 379.070606 -281.565371) (xy 379.078549 -281.512667) (xy 379.094259 -281.461737)
			(xy 379.117385 -281.413716) (xy 379.147409 -281.369679) (xy 379.183661 -281.330608) (xy 379.225332 -281.297377)
			(xy 379.27149 -281.270728) (xy 379.321104 -281.251256) (xy 379.373066 -281.239396) (xy 379.426216 -281.235413)
			(xy 379.479366 -281.239396) (xy 379.531328 -281.251256) (xy 379.580942 -281.270728) (xy 379.6271 -281.297377)
			(xy 379.668771 -281.330608) (xy 379.705023 -281.369679) (xy 379.735047 -281.413716) (xy 379.758173 -281.461737)
			(xy 379.773883 -281.512667) (xy 379.781826 -281.565371) (xy 379.782324 -281.59202) (xy 379.781826 -281.618669)
			(xy 380.010406 -281.618669) (xy 380.010406 -281.565371) (xy 380.018349 -281.512667) (xy 380.034059 -281.461737)
			(xy 380.057185 -281.413716) (xy 380.087209 -281.369679) (xy 380.123461 -281.330608) (xy 380.165132 -281.297377)
			(xy 380.21129 -281.270728) (xy 380.260904 -281.251256) (xy 380.312866 -281.239396) (xy 380.366016 -281.235413)
			(xy 380.419166 -281.239396) (xy 380.471128 -281.251256) (xy 380.520742 -281.270728) (xy 380.5669 -281.297377)
			(xy 380.608571 -281.330608) (xy 380.644823 -281.369679) (xy 380.674847 -281.413716) (xy 380.697973 -281.461737)
			(xy 380.713683 -281.512667) (xy 380.721626 -281.565371) (xy 380.722124 -281.59202) (xy 380.721626 -281.618669)
			(xy 380.950206 -281.618669) (xy 380.950206 -281.565371) (xy 380.958149 -281.512667) (xy 380.973859 -281.461737)
			(xy 380.996985 -281.413716) (xy 381.027009 -281.369679) (xy 381.063261 -281.330608) (xy 381.104932 -281.297377)
			(xy 381.15109 -281.270728) (xy 381.200704 -281.251256) (xy 381.252666 -281.239396) (xy 381.305816 -281.235413)
			(xy 381.358966 -281.239396) (xy 381.410928 -281.251256) (xy 381.460542 -281.270728) (xy 381.5067 -281.297377)
			(xy 381.548371 -281.330608) (xy 381.584623 -281.369679) (xy 381.614647 -281.413716) (xy 381.637773 -281.461737)
			(xy 381.653483 -281.512667) (xy 381.661426 -281.565371) (xy 381.661924 -281.59202) (xy 381.661426 -281.618669)
			(xy 381.890006 -281.618669) (xy 381.890006 -281.565371) (xy 381.897949 -281.512667) (xy 381.913659 -281.461737)
			(xy 381.936785 -281.413716) (xy 381.966809 -281.369679) (xy 382.003061 -281.330608) (xy 382.044732 -281.297377)
			(xy 382.09089 -281.270728) (xy 382.140504 -281.251256) (xy 382.192466 -281.239396) (xy 382.245616 -281.235413)
			(xy 382.298766 -281.239396) (xy 382.350728 -281.251256) (xy 382.400342 -281.270728) (xy 382.4465 -281.297377)
			(xy 382.488171 -281.330608) (xy 382.524423 -281.369679) (xy 382.554447 -281.413716) (xy 382.577573 -281.461737)
			(xy 382.593283 -281.512667) (xy 382.601226 -281.565371) (xy 382.601724 -281.59202) (xy 382.601226 -281.618669)
			(xy 382.829552 -281.618669) (xy 382.829552 -281.565371) (xy 382.837495 -281.512667) (xy 382.853205 -281.461737)
			(xy 382.876331 -281.413716) (xy 382.906355 -281.369679) (xy 382.942607 -281.330608) (xy 382.984278 -281.297377)
			(xy 383.030436 -281.270728) (xy 383.08005 -281.251256) (xy 383.132012 -281.239396) (xy 383.185162 -281.235413)
			(xy 383.238312 -281.239396) (xy 383.290274 -281.251256) (xy 383.339888 -281.270728) (xy 383.386046 -281.297377)
			(xy 383.427717 -281.330608) (xy 383.463969 -281.369679) (xy 383.493993 -281.413716) (xy 383.517119 -281.461737)
			(xy 383.532829 -281.512667) (xy 383.540772 -281.565371) (xy 383.54127 -281.59202) (xy 383.540772 -281.618669)
			(xy 383.769352 -281.618669) (xy 383.769352 -281.565371) (xy 383.777295 -281.512667) (xy 383.793005 -281.461737)
			(xy 383.816131 -281.413716) (xy 383.846155 -281.369679) (xy 383.882407 -281.330608) (xy 383.924078 -281.297377)
			(xy 383.970236 -281.270728) (xy 384.01985 -281.251256) (xy 384.071812 -281.239396) (xy 384.124962 -281.235413)
			(xy 384.178112 -281.239396) (xy 384.230074 -281.251256) (xy 384.279688 -281.270728) (xy 384.325846 -281.297377)
			(xy 384.367517 -281.330608) (xy 384.403769 -281.369679) (xy 384.433793 -281.413716) (xy 384.456919 -281.461737)
			(xy 384.472629 -281.512667) (xy 384.480572 -281.565371) (xy 384.48107 -281.59202) (xy 384.480572 -281.618669)
			(xy 384.472629 -281.671373) (xy 384.456919 -281.722303) (xy 384.433793 -281.770324) (xy 384.403769 -281.814361)
			(xy 384.367517 -281.853432) (xy 384.325846 -281.886663) (xy 384.279688 -281.913312) (xy 384.230074 -281.932784)
			(xy 384.178112 -281.944644) (xy 384.124962 -281.948628) (xy 384.071812 -281.944644) (xy 384.01985 -281.932784)
			(xy 383.970236 -281.913312) (xy 383.924078 -281.886663) (xy 383.882407 -281.853432) (xy 383.846155 -281.814361)
			(xy 383.816131 -281.770324) (xy 383.793005 -281.722303) (xy 383.777295 -281.671373) (xy 383.769352 -281.618669)
			(xy 383.540772 -281.618669) (xy 383.532829 -281.671373) (xy 383.517119 -281.722303) (xy 383.493993 -281.770324)
			(xy 383.463969 -281.814361) (xy 383.427717 -281.853432) (xy 383.386046 -281.886663) (xy 383.339888 -281.913312)
			(xy 383.290274 -281.932784) (xy 383.238312 -281.944644) (xy 383.185162 -281.948628) (xy 383.132012 -281.944644)
			(xy 383.08005 -281.932784) (xy 383.030436 -281.913312) (xy 382.984278 -281.886663) (xy 382.942607 -281.853432)
			(xy 382.906355 -281.814361) (xy 382.876331 -281.770324) (xy 382.853205 -281.722303) (xy 382.837495 -281.671373)
			(xy 382.829552 -281.618669) (xy 382.601226 -281.618669) (xy 382.593283 -281.671373) (xy 382.577573 -281.722303)
			(xy 382.554447 -281.770324) (xy 382.524423 -281.814361) (xy 382.488171 -281.853432) (xy 382.4465 -281.886663)
			(xy 382.400342 -281.913312) (xy 382.350728 -281.932784) (xy 382.298766 -281.944644) (xy 382.245616 -281.948628)
			(xy 382.192466 -281.944644) (xy 382.140504 -281.932784) (xy 382.09089 -281.913312) (xy 382.044732 -281.886663)
			(xy 382.003061 -281.853432) (xy 381.966809 -281.814361) (xy 381.936785 -281.770324) (xy 381.913659 -281.722303)
			(xy 381.897949 -281.671373) (xy 381.890006 -281.618669) (xy 381.661426 -281.618669) (xy 381.653483 -281.671373)
			(xy 381.637773 -281.722303) (xy 381.614647 -281.770324) (xy 381.584623 -281.814361) (xy 381.548371 -281.853432)
			(xy 381.5067 -281.886663) (xy 381.460542 -281.913312) (xy 381.410928 -281.932784) (xy 381.358966 -281.944644)
			(xy 381.305816 -281.948628) (xy 381.252666 -281.944644) (xy 381.200704 -281.932784) (xy 381.15109 -281.913312)
			(xy 381.104932 -281.886663) (xy 381.063261 -281.853432) (xy 381.027009 -281.814361) (xy 380.996985 -281.770324)
			(xy 380.973859 -281.722303) (xy 380.958149 -281.671373) (xy 380.950206 -281.618669) (xy 380.721626 -281.618669)
			(xy 380.713683 -281.671373) (xy 380.697973 -281.722303) (xy 380.674847 -281.770324) (xy 380.644823 -281.814361)
			(xy 380.608571 -281.853432) (xy 380.5669 -281.886663) (xy 380.520742 -281.913312) (xy 380.471128 -281.932784)
			(xy 380.419166 -281.944644) (xy 380.366016 -281.948628) (xy 380.312866 -281.944644) (xy 380.260904 -281.932784)
			(xy 380.21129 -281.913312) (xy 380.165132 -281.886663) (xy 380.123461 -281.853432) (xy 380.087209 -281.814361)
			(xy 380.057185 -281.770324) (xy 380.034059 -281.722303) (xy 380.018349 -281.671373) (xy 380.010406 -281.618669)
			(xy 379.781826 -281.618669) (xy 379.773883 -281.671373) (xy 379.758173 -281.722303) (xy 379.735047 -281.770324)
			(xy 379.705023 -281.814361) (xy 379.668771 -281.853432) (xy 379.6271 -281.886663) (xy 379.580942 -281.913312)
			(xy 379.531328 -281.932784) (xy 379.479366 -281.944644) (xy 379.426216 -281.948628) (xy 379.373066 -281.944644)
			(xy 379.321104 -281.932784) (xy 379.27149 -281.913312) (xy 379.225332 -281.886663) (xy 379.183661 -281.853432)
			(xy 379.147409 -281.814361) (xy 379.117385 -281.770324) (xy 379.094259 -281.722303) (xy 379.078549 -281.671373)
			(xy 379.070606 -281.618669) (xy 378.842026 -281.618669) (xy 378.834083 -281.671373) (xy 378.818373 -281.722303)
			(xy 378.795247 -281.770324) (xy 378.765223 -281.814361) (xy 378.728971 -281.853432) (xy 378.6873 -281.886663)
			(xy 378.641142 -281.913312) (xy 378.591528 -281.932784) (xy 378.539566 -281.944644) (xy 378.486416 -281.948628)
			(xy 378.433266 -281.944644) (xy 378.381304 -281.932784) (xy 378.33169 -281.913312) (xy 378.285532 -281.886663)
			(xy 378.243861 -281.853432) (xy 378.207609 -281.814361) (xy 378.177585 -281.770324) (xy 378.154459 -281.722303)
			(xy 378.138749 -281.671373) (xy 378.130806 -281.618669) (xy 377.901972 -281.618669) (xy 377.894029 -281.671373)
			(xy 377.878319 -281.722303) (xy 377.855193 -281.770324) (xy 377.825169 -281.814361) (xy 377.788917 -281.853432)
			(xy 377.747246 -281.886663) (xy 377.701088 -281.913312) (xy 377.651474 -281.932784) (xy 377.599512 -281.944644)
			(xy 377.546362 -281.948628) (xy 377.493212 -281.944644) (xy 377.44125 -281.932784) (xy 377.391636 -281.913312)
			(xy 377.345478 -281.886663) (xy 377.303807 -281.853432) (xy 377.267555 -281.814361) (xy 377.237531 -281.770324)
			(xy 377.214405 -281.722303) (xy 377.198695 -281.671373) (xy 377.190752 -281.618669) (xy 376.962426 -281.618669)
			(xy 376.954483 -281.671373) (xy 376.938773 -281.722303) (xy 376.915647 -281.770324) (xy 376.885623 -281.814361)
			(xy 376.849371 -281.853432) (xy 376.8077 -281.886663) (xy 376.761542 -281.913312) (xy 376.711928 -281.932784)
			(xy 376.659966 -281.944644) (xy 376.606816 -281.948628) (xy 376.553666 -281.944644) (xy 376.501704 -281.932784)
			(xy 376.45209 -281.913312) (xy 376.405932 -281.886663) (xy 376.364261 -281.853432) (xy 376.328009 -281.814361)
			(xy 376.297985 -281.770324) (xy 376.274859 -281.722303) (xy 376.259149 -281.671373) (xy 376.251206 -281.618669)
			(xy 376.022334 -281.618669) (xy 376.014429 -281.671119) (xy 375.998719 -281.722049) (xy 375.975593 -281.77007)
			(xy 375.945569 -281.814107) (xy 375.909317 -281.853178) (xy 375.867646 -281.886409) (xy 375.821488 -281.913058)
			(xy 375.771874 -281.93253) (xy 375.719912 -281.94439) (xy 375.666762 -281.948374) (xy 375.613612 -281.94439)
			(xy 375.56165 -281.93253) (xy 375.512036 -281.913058) (xy 375.465878 -281.886409) (xy 375.424207 -281.853178)
			(xy 375.387955 -281.814107) (xy 375.357931 -281.77007) (xy 375.334805 -281.722049) (xy 375.319095 -281.671119)
			(xy 375.311152 -281.618415) (xy 375.082577 -281.618415) (xy 375.082572 -281.618669) (xy 375.074629 -281.671373)
			(xy 375.058919 -281.722303) (xy 375.035793 -281.770324) (xy 375.005769 -281.814361) (xy 374.969517 -281.853432)
			(xy 374.927846 -281.886663) (xy 374.881688 -281.913312) (xy 374.832074 -281.932784) (xy 374.780112 -281.944644)
			(xy 374.726962 -281.948628) (xy 374.673812 -281.944644) (xy 374.62185 -281.932784) (xy 374.572236 -281.913312)
			(xy 374.526078 -281.886663) (xy 374.484407 -281.853432) (xy 374.448155 -281.814361) (xy 374.418131 -281.770324)
			(xy 374.395005 -281.722303) (xy 374.379295 -281.671373) (xy 374.371352 -281.618669) (xy 374.143026 -281.618669)
			(xy 374.135083 -281.671373) (xy 374.119373 -281.722303) (xy 374.096247 -281.770324) (xy 374.066223 -281.814361)
			(xy 374.029971 -281.853432) (xy 373.9883 -281.886663) (xy 373.942142 -281.913312) (xy 373.892528 -281.932784)
			(xy 373.840566 -281.944644) (xy 373.787416 -281.948628) (xy 373.734266 -281.944644) (xy 373.682304 -281.932784)
			(xy 373.63269 -281.913312) (xy 373.586532 -281.886663) (xy 373.544861 -281.853432) (xy 373.508609 -281.814361)
			(xy 373.478585 -281.770324) (xy 373.455459 -281.722303) (xy 373.439749 -281.671373) (xy 373.431806 -281.618669)
			(xy 373.203226 -281.618669) (xy 373.195283 -281.671373) (xy 373.179573 -281.722303) (xy 373.156447 -281.770324)
			(xy 373.126423 -281.814361) (xy 373.090171 -281.853432) (xy 373.0485 -281.886663) (xy 373.002342 -281.913312)
			(xy 372.952728 -281.932784) (xy 372.900766 -281.944644) (xy 372.847616 -281.948628) (xy 372.794466 -281.944644)
			(xy 372.742504 -281.932784) (xy 372.69289 -281.913312) (xy 372.646732 -281.886663) (xy 372.605061 -281.853432)
			(xy 372.568809 -281.814361) (xy 372.538785 -281.770324) (xy 372.515659 -281.722303) (xy 372.499949 -281.671373)
			(xy 372.492006 -281.618669) (xy 372.263426 -281.618669) (xy 372.255483 -281.671373) (xy 372.239773 -281.722303)
			(xy 372.216647 -281.770324) (xy 372.186623 -281.814361) (xy 372.150371 -281.853432) (xy 372.1087 -281.886663)
			(xy 372.062542 -281.913312) (xy 372.012928 -281.932784) (xy 371.960966 -281.944644) (xy 371.907816 -281.948628)
			(xy 371.854666 -281.944644) (xy 371.802704 -281.932784) (xy 371.75309 -281.913312) (xy 371.706932 -281.886663)
			(xy 371.665261 -281.853432) (xy 371.629009 -281.814361) (xy 371.598985 -281.770324) (xy 371.575859 -281.722303)
			(xy 371.560149 -281.671373) (xy 371.552206 -281.618669) (xy 371.323626 -281.618669) (xy 371.315683 -281.671373)
			(xy 371.299973 -281.722303) (xy 371.276847 -281.770324) (xy 371.246823 -281.814361) (xy 371.210571 -281.853432)
			(xy 371.1689 -281.886663) (xy 371.122742 -281.913312) (xy 371.073128 -281.932784) (xy 371.021166 -281.944644)
			(xy 370.968016 -281.948628) (xy 370.914866 -281.944644) (xy 370.862904 -281.932784) (xy 370.81329 -281.913312)
			(xy 370.767132 -281.886663) (xy 370.725461 -281.853432) (xy 370.689209 -281.814361) (xy 370.659185 -281.770324)
			(xy 370.636059 -281.722303) (xy 370.620349 -281.671373) (xy 370.612406 -281.618669) (xy 370.383826 -281.618669)
			(xy 370.375883 -281.671373) (xy 370.360173 -281.722303) (xy 370.337047 -281.770324) (xy 370.307023 -281.814361)
			(xy 370.270771 -281.853432) (xy 370.2291 -281.886663) (xy 370.182942 -281.913312) (xy 370.133328 -281.932784)
			(xy 370.081366 -281.944644) (xy 370.028216 -281.948628) (xy 369.975066 -281.944644) (xy 369.923104 -281.932784)
			(xy 369.87349 -281.913312) (xy 369.827332 -281.886663) (xy 369.785661 -281.853432) (xy 369.749409 -281.814361)
			(xy 369.719385 -281.770324) (xy 369.696259 -281.722303) (xy 369.680549 -281.671373) (xy 369.672606 -281.618669)
			(xy 369.444026 -281.618669) (xy 369.436083 -281.671373) (xy 369.420373 -281.722303) (xy 369.397247 -281.770324)
			(xy 369.367223 -281.814361) (xy 369.330971 -281.853432) (xy 369.2893 -281.886663) (xy 369.243142 -281.913312)
			(xy 369.193528 -281.932784) (xy 369.141566 -281.944644) (xy 369.088416 -281.948628) (xy 369.035266 -281.944644)
			(xy 368.983304 -281.932784) (xy 368.93369 -281.913312) (xy 368.887532 -281.886663) (xy 368.845861 -281.853432)
			(xy 368.809609 -281.814361) (xy 368.779585 -281.770324) (xy 368.756459 -281.722303) (xy 368.740749 -281.671373)
			(xy 368.732806 -281.618669) (xy 368.504226 -281.618669) (xy 368.496283 -281.671373) (xy 368.480573 -281.722303)
			(xy 368.457447 -281.770324) (xy 368.427423 -281.814361) (xy 368.391171 -281.853432) (xy 368.3495 -281.886663)
			(xy 368.303342 -281.913312) (xy 368.253728 -281.932784) (xy 368.201766 -281.944644) (xy 368.148616 -281.948628)
			(xy 368.095466 -281.944644) (xy 368.043504 -281.932784) (xy 367.99389 -281.913312) (xy 367.947732 -281.886663)
			(xy 367.906061 -281.853432) (xy 367.869809 -281.814361) (xy 367.839785 -281.770324) (xy 367.816659 -281.722303)
			(xy 367.800949 -281.671373) (xy 367.793006 -281.618669) (xy 367.564426 -281.618669) (xy 367.556483 -281.671373)
			(xy 367.540773 -281.722303) (xy 367.517647 -281.770324) (xy 367.487623 -281.814361) (xy 367.451371 -281.853432)
			(xy 367.4097 -281.886663) (xy 367.363542 -281.913312) (xy 367.313928 -281.932784) (xy 367.261966 -281.944644)
			(xy 367.208816 -281.948628) (xy 367.155666 -281.944644) (xy 367.103704 -281.932784) (xy 367.05409 -281.913312)
			(xy 367.007932 -281.886663) (xy 366.966261 -281.853432) (xy 366.930009 -281.814361) (xy 366.899985 -281.770324)
			(xy 366.876859 -281.722303) (xy 366.861149 -281.671373) (xy 366.853206 -281.618669) (xy 366.624372 -281.618669)
			(xy 366.616429 -281.671373) (xy 366.600719 -281.722303) (xy 366.577593 -281.770324) (xy 366.547569 -281.814361)
			(xy 366.511317 -281.853432) (xy 366.469646 -281.886663) (xy 366.423488 -281.913312) (xy 366.373874 -281.932784)
			(xy 366.321912 -281.944644) (xy 366.268762 -281.948628) (xy 366.215612 -281.944644) (xy 366.16365 -281.932784)
			(xy 366.114036 -281.913312) (xy 366.067878 -281.886663) (xy 366.026207 -281.853432) (xy 365.989955 -281.814361)
			(xy 365.959931 -281.770324) (xy 365.936805 -281.722303) (xy 365.921095 -281.671373) (xy 365.913152 -281.618669)
			(xy 365.684842 -281.618669) (xy 365.684834 -281.619116) (xy 365.676669 -281.672688) (xy 365.669068 -281.6987)
			(xy 365.65967 -281.72791) (xy 366.241076 -282.309316) (xy 366.251596 -282.319149) (xy 366.276807 -282.333036)
			(xy 366.304891 -282.33934) (xy 366.333619 -282.33756) (xy 366.36071 -282.327837) (xy 366.384014 -282.310944)
			(xy 366.401682 -282.288221) (xy 366.407446 -282.275026) (xy 366.417675 -282.250462) (xy 366.444359 -282.204428)
			(xy 366.477596 -282.162877) (xy 366.516644 -282.126733) (xy 366.560636 -282.096801) (xy 366.608591 -282.073748)
			(xy 366.659442 -282.058086) (xy 366.712058 -282.050164) (xy 366.738662 -282.049728) (xy 366.766648 -282.050246)
			(xy 366.821932 -282.058997) (xy 366.875166 -282.07629) (xy 366.925039 -282.101699) (xy 366.970323 -282.134597)
			(xy 367.009901 -282.174176) (xy 367.0428 -282.219459) (xy 367.068209 -282.269332) (xy 367.085503 -282.322566)
			(xy 367.094254 -282.37785) (xy 367.09477 -282.405836) (xy 367.094273 -282.432437) (xy 367.094266 -282.432485)
			(xy 367.322852 -282.432485) (xy 367.322852 -282.379187) (xy 367.330795 -282.326483) (xy 367.346505 -282.275553)
			(xy 367.369631 -282.227532) (xy 367.399655 -282.183495) (xy 367.435907 -282.144424) (xy 367.477578 -282.111193)
			(xy 367.523736 -282.084544) (xy 367.57335 -282.065072) (xy 367.625312 -282.053212) (xy 367.678462 -282.049229)
			(xy 367.731612 -282.053212) (xy 367.783574 -282.065072) (xy 367.833188 -282.084544) (xy 367.879346 -282.111193)
			(xy 367.921017 -282.144424) (xy 367.957269 -282.183495) (xy 367.987293 -282.227532) (xy 368.010419 -282.275553)
			(xy 368.026129 -282.326483) (xy 368.034072 -282.379187) (xy 368.03457 -282.405836) (xy 368.034072 -282.432485)
			(xy 368.262652 -282.432485) (xy 368.262652 -282.379187) (xy 368.270595 -282.326483) (xy 368.286305 -282.275553)
			(xy 368.309431 -282.227532) (xy 368.339455 -282.183495) (xy 368.375707 -282.144424) (xy 368.417378 -282.111193)
			(xy 368.463536 -282.084544) (xy 368.51315 -282.065072) (xy 368.565112 -282.053212) (xy 368.618262 -282.049229)
			(xy 368.671412 -282.053212) (xy 368.723374 -282.065072) (xy 368.772988 -282.084544) (xy 368.819146 -282.111193)
			(xy 368.860817 -282.144424) (xy 368.897069 -282.183495) (xy 368.927093 -282.227532) (xy 368.950219 -282.275553)
			(xy 368.965929 -282.326483) (xy 368.973872 -282.379187) (xy 368.97437 -282.405836) (xy 368.973872 -282.432485)
			(xy 369.202452 -282.432485) (xy 369.202452 -282.379187) (xy 369.210395 -282.326483) (xy 369.226105 -282.275553)
			(xy 369.249231 -282.227532) (xy 369.279255 -282.183495) (xy 369.315507 -282.144424) (xy 369.357178 -282.111193)
			(xy 369.403336 -282.084544) (xy 369.45295 -282.065072) (xy 369.504912 -282.053212) (xy 369.558062 -282.049229)
			(xy 369.611212 -282.053212) (xy 369.663174 -282.065072) (xy 369.712788 -282.084544) (xy 369.758946 -282.111193)
			(xy 369.800617 -282.144424) (xy 369.836869 -282.183495) (xy 369.866893 -282.227532) (xy 369.890019 -282.275553)
			(xy 369.905729 -282.326483) (xy 369.913672 -282.379187) (xy 369.91417 -282.405836) (xy 369.913672 -282.432485)
			(xy 370.142252 -282.432485) (xy 370.142252 -282.379187) (xy 370.150195 -282.326483) (xy 370.165905 -282.275553)
			(xy 370.189031 -282.227532) (xy 370.219055 -282.183495) (xy 370.255307 -282.144424) (xy 370.296978 -282.111193)
			(xy 370.343136 -282.084544) (xy 370.39275 -282.065072) (xy 370.444712 -282.053212) (xy 370.497862 -282.049229)
			(xy 370.551012 -282.053212) (xy 370.602974 -282.065072) (xy 370.652588 -282.084544) (xy 370.698746 -282.111193)
			(xy 370.740417 -282.144424) (xy 370.776669 -282.183495) (xy 370.806693 -282.227532) (xy 370.829819 -282.275553)
			(xy 370.845529 -282.326483) (xy 370.853472 -282.379187) (xy 370.85397 -282.405836) (xy 370.853472 -282.432485)
			(xy 371.082052 -282.432485) (xy 371.082052 -282.379187) (xy 371.089995 -282.326483) (xy 371.105705 -282.275553)
			(xy 371.128831 -282.227532) (xy 371.158855 -282.183495) (xy 371.195107 -282.144424) (xy 371.236778 -282.111193)
			(xy 371.282936 -282.084544) (xy 371.33255 -282.065072) (xy 371.384512 -282.053212) (xy 371.437662 -282.049229)
			(xy 371.490812 -282.053212) (xy 371.542774 -282.065072) (xy 371.592388 -282.084544) (xy 371.638546 -282.111193)
			(xy 371.680217 -282.144424) (xy 371.716469 -282.183495) (xy 371.746493 -282.227532) (xy 371.769619 -282.275553)
			(xy 371.785329 -282.326483) (xy 371.793272 -282.379187) (xy 371.79377 -282.405836) (xy 371.793272 -282.432485)
			(xy 372.021852 -282.432485) (xy 372.021852 -282.379187) (xy 372.029795 -282.326483) (xy 372.045505 -282.275553)
			(xy 372.068631 -282.227532) (xy 372.098655 -282.183495) (xy 372.134907 -282.144424) (xy 372.176578 -282.111193)
			(xy 372.222736 -282.084544) (xy 372.27235 -282.065072) (xy 372.324312 -282.053212) (xy 372.377462 -282.049229)
			(xy 372.430612 -282.053212) (xy 372.482574 -282.065072) (xy 372.532188 -282.084544) (xy 372.578346 -282.111193)
			(xy 372.620017 -282.144424) (xy 372.656269 -282.183495) (xy 372.686293 -282.227532) (xy 372.709419 -282.275553)
			(xy 372.725129 -282.326483) (xy 372.733072 -282.379187) (xy 372.73357 -282.405836) (xy 372.733072 -282.432485)
			(xy 372.961652 -282.432485) (xy 372.961652 -282.379187) (xy 372.969595 -282.326483) (xy 372.985305 -282.275553)
			(xy 373.008431 -282.227532) (xy 373.038455 -282.183495) (xy 373.074707 -282.144424) (xy 373.116378 -282.111193)
			(xy 373.162536 -282.084544) (xy 373.21215 -282.065072) (xy 373.264112 -282.053212) (xy 373.317262 -282.049229)
			(xy 373.370412 -282.053212) (xy 373.422374 -282.065072) (xy 373.471988 -282.084544) (xy 373.518146 -282.111193)
			(xy 373.559817 -282.144424) (xy 373.596069 -282.183495) (xy 373.626093 -282.227532) (xy 373.649219 -282.275553)
			(xy 373.664929 -282.326483) (xy 373.672872 -282.379187) (xy 373.67337 -282.405836) (xy 373.672872 -282.432485)
			(xy 373.901706 -282.432485) (xy 373.901706 -282.379187) (xy 373.909649 -282.326483) (xy 373.925359 -282.275553)
			(xy 373.948485 -282.227532) (xy 373.978509 -282.183495) (xy 374.014761 -282.144424) (xy 374.056432 -282.111193)
			(xy 374.10259 -282.084544) (xy 374.152204 -282.065072) (xy 374.204166 -282.053212) (xy 374.257316 -282.049229)
			(xy 374.310466 -282.053212) (xy 374.362428 -282.065072) (xy 374.412042 -282.084544) (xy 374.4582 -282.111193)
			(xy 374.499871 -282.144424) (xy 374.536123 -282.183495) (xy 374.566147 -282.227532) (xy 374.589273 -282.275553)
			(xy 374.604983 -282.326483) (xy 374.612926 -282.379187) (xy 374.613424 -282.405836) (xy 374.612931 -282.432231)
			(xy 374.841506 -282.432231) (xy 374.841506 -282.378933) (xy 374.849449 -282.326229) (xy 374.865159 -282.275299)
			(xy 374.888285 -282.227278) (xy 374.918309 -282.183241) (xy 374.954561 -282.14417) (xy 374.996232 -282.110939)
			(xy 375.04239 -282.08429) (xy 375.092004 -282.064818) (xy 375.143966 -282.052958) (xy 375.197116 -282.048975)
			(xy 375.250266 -282.052958) (xy 375.302228 -282.064818) (xy 375.351842 -282.08429) (xy 375.398 -282.110939)
			(xy 375.439671 -282.14417) (xy 375.475923 -282.183241) (xy 375.505947 -282.227278) (xy 375.529073 -282.275299)
			(xy 375.544783 -282.326229) (xy 375.552726 -282.378933) (xy 375.553224 -282.405582) (xy 375.552726 -282.432231)
			(xy 375.781306 -282.432231) (xy 375.781306 -282.378933) (xy 375.789249 -282.326229) (xy 375.804959 -282.275299)
			(xy 375.828085 -282.227278) (xy 375.858109 -282.183241) (xy 375.894361 -282.14417) (xy 375.936032 -282.110939)
			(xy 375.98219 -282.08429) (xy 376.031804 -282.064818) (xy 376.083766 -282.052958) (xy 376.136916 -282.048975)
			(xy 376.190066 -282.052958) (xy 376.242028 -282.064818) (xy 376.291642 -282.08429) (xy 376.3378 -282.110939)
			(xy 376.379471 -282.14417) (xy 376.415723 -282.183241) (xy 376.445747 -282.227278) (xy 376.468873 -282.275299)
			(xy 376.484583 -282.326229) (xy 376.492526 -282.378933) (xy 376.493024 -282.405582) (xy 376.492526 -282.432231)
			(xy 376.721106 -282.432231) (xy 376.721106 -282.378933) (xy 376.729049 -282.326229) (xy 376.744759 -282.275299)
			(xy 376.767885 -282.227278) (xy 376.797909 -282.183241) (xy 376.834161 -282.14417) (xy 376.875832 -282.110939)
			(xy 376.92199 -282.08429) (xy 376.971604 -282.064818) (xy 377.023566 -282.052958) (xy 377.076716 -282.048975)
			(xy 377.129866 -282.052958) (xy 377.181828 -282.064818) (xy 377.231442 -282.08429) (xy 377.2776 -282.110939)
			(xy 377.319271 -282.14417) (xy 377.355523 -282.183241) (xy 377.385547 -282.227278) (xy 377.408673 -282.275299)
			(xy 377.424383 -282.326229) (xy 377.432326 -282.378933) (xy 377.432824 -282.405582) (xy 377.432326 -282.432231)
			(xy 377.660906 -282.432231) (xy 377.660906 -282.378933) (xy 377.668849 -282.326229) (xy 377.684559 -282.275299)
			(xy 377.707685 -282.227278) (xy 377.737709 -282.183241) (xy 377.773961 -282.14417) (xy 377.815632 -282.110939)
			(xy 377.86179 -282.08429) (xy 377.911404 -282.064818) (xy 377.963366 -282.052958) (xy 378.016516 -282.048975)
			(xy 378.069666 -282.052958) (xy 378.121628 -282.064818) (xy 378.171242 -282.08429) (xy 378.2174 -282.110939)
			(xy 378.259071 -282.14417) (xy 378.295323 -282.183241) (xy 378.325347 -282.227278) (xy 378.348473 -282.275299)
			(xy 378.364183 -282.326229) (xy 378.372126 -282.378933) (xy 378.372624 -282.405582) (xy 378.372126 -282.432231)
			(xy 378.372088 -282.432485) (xy 378.600452 -282.432485) (xy 378.600452 -282.379187) (xy 378.608395 -282.326483)
			(xy 378.624105 -282.275553) (xy 378.647231 -282.227532) (xy 378.677255 -282.183495) (xy 378.713507 -282.144424)
			(xy 378.755178 -282.111193) (xy 378.801336 -282.084544) (xy 378.85095 -282.065072) (xy 378.902912 -282.053212)
			(xy 378.956062 -282.049229) (xy 379.009212 -282.053212) (xy 379.061174 -282.065072) (xy 379.110788 -282.084544)
			(xy 379.156946 -282.111193) (xy 379.198617 -282.144424) (xy 379.234869 -282.183495) (xy 379.264893 -282.227532)
			(xy 379.288019 -282.275553) (xy 379.303729 -282.326483) (xy 379.311672 -282.379187) (xy 379.31217 -282.405836)
			(xy 379.311672 -282.432485) (xy 379.540252 -282.432485) (xy 379.540252 -282.379187) (xy 379.548195 -282.326483)
			(xy 379.563905 -282.275553) (xy 379.587031 -282.227532) (xy 379.617055 -282.183495) (xy 379.653307 -282.144424)
			(xy 379.694978 -282.111193) (xy 379.741136 -282.084544) (xy 379.79075 -282.065072) (xy 379.842712 -282.053212)
			(xy 379.895862 -282.049229) (xy 379.949012 -282.053212) (xy 380.000974 -282.065072) (xy 380.050588 -282.084544)
			(xy 380.096746 -282.111193) (xy 380.138417 -282.144424) (xy 380.174669 -282.183495) (xy 380.204693 -282.227532)
			(xy 380.227819 -282.275553) (xy 380.243529 -282.326483) (xy 380.251472 -282.379187) (xy 380.25197 -282.405836)
			(xy 380.251472 -282.432485) (xy 380.480052 -282.432485) (xy 380.480052 -282.379187) (xy 380.487995 -282.326483)
			(xy 380.503705 -282.275553) (xy 380.526831 -282.227532) (xy 380.556855 -282.183495) (xy 380.593107 -282.144424)
			(xy 380.634778 -282.111193) (xy 380.680936 -282.084544) (xy 380.73055 -282.065072) (xy 380.782512 -282.053212)
			(xy 380.835662 -282.049229) (xy 380.888812 -282.053212) (xy 380.940774 -282.065072) (xy 380.990388 -282.084544)
			(xy 381.036546 -282.111193) (xy 381.078217 -282.144424) (xy 381.114469 -282.183495) (xy 381.144493 -282.227532)
			(xy 381.167619 -282.275553) (xy 381.183329 -282.326483) (xy 381.191272 -282.379187) (xy 381.19177 -282.405836)
			(xy 381.191272 -282.432485) (xy 381.419852 -282.432485) (xy 381.419852 -282.379187) (xy 381.427795 -282.326483)
			(xy 381.443505 -282.275553) (xy 381.466631 -282.227532) (xy 381.496655 -282.183495) (xy 381.532907 -282.144424)
			(xy 381.574578 -282.111193) (xy 381.620736 -282.084544) (xy 381.67035 -282.065072) (xy 381.722312 -282.053212)
			(xy 381.775462 -282.049229) (xy 381.828612 -282.053212) (xy 381.880574 -282.065072) (xy 381.930188 -282.084544)
			(xy 381.976346 -282.111193) (xy 382.018017 -282.144424) (xy 382.054269 -282.183495) (xy 382.084293 -282.227532)
			(xy 382.107419 -282.275553) (xy 382.123129 -282.326483) (xy 382.131072 -282.379187) (xy 382.13157 -282.405836)
			(xy 382.131072 -282.432485) (xy 382.359906 -282.432485) (xy 382.359906 -282.379187) (xy 382.367849 -282.326483)
			(xy 382.383559 -282.275553) (xy 382.406685 -282.227532) (xy 382.436709 -282.183495) (xy 382.472961 -282.144424)
			(xy 382.514632 -282.111193) (xy 382.56079 -282.084544) (xy 382.610404 -282.065072) (xy 382.662366 -282.053212)
			(xy 382.715516 -282.049229) (xy 382.768666 -282.053212) (xy 382.820628 -282.065072) (xy 382.870242 -282.084544)
			(xy 382.9164 -282.111193) (xy 382.958071 -282.144424) (xy 382.994323 -282.183495) (xy 383.024347 -282.227532)
			(xy 383.047473 -282.275553) (xy 383.063183 -282.326483) (xy 383.071126 -282.379187) (xy 383.071624 -282.405836)
			(xy 383.071126 -282.432485) (xy 383.299452 -282.432485) (xy 383.299452 -282.379187) (xy 383.307395 -282.326483)
			(xy 383.323105 -282.275553) (xy 383.346231 -282.227532) (xy 383.376255 -282.183495) (xy 383.412507 -282.144424)
			(xy 383.454178 -282.111193) (xy 383.500336 -282.084544) (xy 383.54995 -282.065072) (xy 383.601912 -282.053212)
			(xy 383.655062 -282.049229) (xy 383.708212 -282.053212) (xy 383.760174 -282.065072) (xy 383.809788 -282.084544)
			(xy 383.855946 -282.111193) (xy 383.897617 -282.144424) (xy 383.933869 -282.183495) (xy 383.963893 -282.227532)
			(xy 383.987019 -282.275553) (xy 384.002729 -282.326483) (xy 384.010672 -282.379187) (xy 384.01117 -282.405836)
			(xy 384.010672 -282.432485) (xy 384.239252 -282.432485) (xy 384.239252 -282.379187) (xy 384.247195 -282.326483)
			(xy 384.262905 -282.275553) (xy 384.286031 -282.227532) (xy 384.316055 -282.183495) (xy 384.352307 -282.144424)
			(xy 384.393978 -282.111193) (xy 384.440136 -282.084544) (xy 384.48975 -282.065072) (xy 384.541712 -282.053212)
			(xy 384.594862 -282.049229) (xy 384.648012 -282.053212) (xy 384.699974 -282.065072) (xy 384.749588 -282.084544)
			(xy 384.795746 -282.111193) (xy 384.837417 -282.144424) (xy 384.873669 -282.183495) (xy 384.903693 -282.227532)
			(xy 384.926819 -282.275553) (xy 384.942529 -282.326483) (xy 384.950472 -282.379187) (xy 384.95097 -282.405836)
			(xy 384.950472 -282.432485) (xy 385.179052 -282.432485) (xy 385.179052 -282.379187) (xy 385.186995 -282.326483)
			(xy 385.202705 -282.275553) (xy 385.225831 -282.227532) (xy 385.255855 -282.183495) (xy 385.292107 -282.144424)
			(xy 385.333778 -282.111193) (xy 385.379936 -282.084544) (xy 385.42955 -282.065072) (xy 385.481512 -282.053212)
			(xy 385.534662 -282.049229) (xy 385.587812 -282.053212) (xy 385.639774 -282.065072) (xy 385.689388 -282.084544)
			(xy 385.735546 -282.111193) (xy 385.777217 -282.144424) (xy 385.813469 -282.183495) (xy 385.843493 -282.227532)
			(xy 385.866619 -282.275553) (xy 385.882329 -282.326483) (xy 385.890272 -282.379187) (xy 385.89077 -282.405836)
			(xy 385.890272 -282.432485) (xy 385.882329 -282.485189) (xy 385.866619 -282.536119) (xy 385.843493 -282.58414)
			(xy 385.813469 -282.628177) (xy 385.777217 -282.667248) (xy 385.735546 -282.700479) (xy 385.689388 -282.727128)
			(xy 385.639774 -282.7466) (xy 385.587812 -282.75846) (xy 385.534662 -282.762444) (xy 385.481512 -282.75846)
			(xy 385.42955 -282.7466) (xy 385.379936 -282.727128) (xy 385.333778 -282.700479) (xy 385.292107 -282.667248)
			(xy 385.255855 -282.628177) (xy 385.225831 -282.58414) (xy 385.202705 -282.536119) (xy 385.186995 -282.485189)
			(xy 385.179052 -282.432485) (xy 384.950472 -282.432485) (xy 384.942529 -282.485189) (xy 384.926819 -282.536119)
			(xy 384.903693 -282.58414) (xy 384.873669 -282.628177) (xy 384.837417 -282.667248) (xy 384.795746 -282.700479)
			(xy 384.749588 -282.727128) (xy 384.699974 -282.7466) (xy 384.648012 -282.75846) (xy 384.594862 -282.762444)
			(xy 384.541712 -282.75846) (xy 384.48975 -282.7466) (xy 384.440136 -282.727128) (xy 384.393978 -282.700479)
			(xy 384.352307 -282.667248) (xy 384.316055 -282.628177) (xy 384.286031 -282.58414) (xy 384.262905 -282.536119)
			(xy 384.247195 -282.485189) (xy 384.239252 -282.432485) (xy 384.010672 -282.432485) (xy 384.002729 -282.485189)
			(xy 383.987019 -282.536119) (xy 383.963893 -282.58414) (xy 383.933869 -282.628177) (xy 383.897617 -282.667248)
			(xy 383.855946 -282.700479) (xy 383.809788 -282.727128) (xy 383.760174 -282.7466) (xy 383.708212 -282.75846)
			(xy 383.655062 -282.762444) (xy 383.601912 -282.75846) (xy 383.54995 -282.7466) (xy 383.500336 -282.727128)
			(xy 383.454178 -282.700479) (xy 383.412507 -282.667248) (xy 383.376255 -282.628177) (xy 383.346231 -282.58414)
			(xy 383.323105 -282.536119) (xy 383.307395 -282.485189) (xy 383.299452 -282.432485) (xy 383.071126 -282.432485)
			(xy 383.063183 -282.485189) (xy 383.047473 -282.536119) (xy 383.024347 -282.58414) (xy 382.994323 -282.628177)
			(xy 382.958071 -282.667248) (xy 382.9164 -282.700479) (xy 382.870242 -282.727128) (xy 382.820628 -282.7466)
			(xy 382.768666 -282.75846) (xy 382.715516 -282.762444) (xy 382.662366 -282.75846) (xy 382.610404 -282.7466)
			(xy 382.56079 -282.727128) (xy 382.514632 -282.700479) (xy 382.472961 -282.667248) (xy 382.436709 -282.628177)
			(xy 382.406685 -282.58414) (xy 382.383559 -282.536119) (xy 382.367849 -282.485189) (xy 382.359906 -282.432485)
			(xy 382.131072 -282.432485) (xy 382.123129 -282.485189) (xy 382.107419 -282.536119) (xy 382.084293 -282.58414)
			(xy 382.054269 -282.628177) (xy 382.018017 -282.667248) (xy 381.976346 -282.700479) (xy 381.930188 -282.727128)
			(xy 381.880574 -282.7466) (xy 381.828612 -282.75846) (xy 381.775462 -282.762444) (xy 381.722312 -282.75846)
			(xy 381.67035 -282.7466) (xy 381.620736 -282.727128) (xy 381.574578 -282.700479) (xy 381.532907 -282.667248)
			(xy 381.496655 -282.628177) (xy 381.466631 -282.58414) (xy 381.443505 -282.536119) (xy 381.427795 -282.485189)
			(xy 381.419852 -282.432485) (xy 381.191272 -282.432485) (xy 381.183329 -282.485189) (xy 381.167619 -282.536119)
			(xy 381.144493 -282.58414) (xy 381.114469 -282.628177) (xy 381.078217 -282.667248) (xy 381.036546 -282.700479)
			(xy 380.990388 -282.727128) (xy 380.940774 -282.7466) (xy 380.888812 -282.75846) (xy 380.835662 -282.762444)
			(xy 380.782512 -282.75846) (xy 380.73055 -282.7466) (xy 380.680936 -282.727128) (xy 380.634778 -282.700479)
			(xy 380.593107 -282.667248) (xy 380.556855 -282.628177) (xy 380.526831 -282.58414) (xy 380.503705 -282.536119)
			(xy 380.487995 -282.485189) (xy 380.480052 -282.432485) (xy 380.251472 -282.432485) (xy 380.243529 -282.485189)
			(xy 380.227819 -282.536119) (xy 380.204693 -282.58414) (xy 380.174669 -282.628177) (xy 380.138417 -282.667248)
			(xy 380.096746 -282.700479) (xy 380.050588 -282.727128) (xy 380.000974 -282.7466) (xy 379.949012 -282.75846)
			(xy 379.895862 -282.762444) (xy 379.842712 -282.75846) (xy 379.79075 -282.7466) (xy 379.741136 -282.727128)
			(xy 379.694978 -282.700479) (xy 379.653307 -282.667248) (xy 379.617055 -282.628177) (xy 379.587031 -282.58414)
			(xy 379.563905 -282.536119) (xy 379.548195 -282.485189) (xy 379.540252 -282.432485) (xy 379.311672 -282.432485)
			(xy 379.303729 -282.485189) (xy 379.288019 -282.536119) (xy 379.264893 -282.58414) (xy 379.234869 -282.628177)
			(xy 379.198617 -282.667248) (xy 379.156946 -282.700479) (xy 379.110788 -282.727128) (xy 379.061174 -282.7466)
			(xy 379.009212 -282.75846) (xy 378.956062 -282.762444) (xy 378.902912 -282.75846) (xy 378.85095 -282.7466)
			(xy 378.801336 -282.727128) (xy 378.755178 -282.700479) (xy 378.713507 -282.667248) (xy 378.677255 -282.628177)
			(xy 378.647231 -282.58414) (xy 378.624105 -282.536119) (xy 378.608395 -282.485189) (xy 378.600452 -282.432485)
			(xy 378.372088 -282.432485) (xy 378.364183 -282.484935) (xy 378.348473 -282.535865) (xy 378.325347 -282.583886)
			(xy 378.295323 -282.627923) (xy 378.259071 -282.666994) (xy 378.2174 -282.700225) (xy 378.171242 -282.726874)
			(xy 378.121628 -282.746346) (xy 378.069666 -282.758206) (xy 378.016516 -282.76219) (xy 377.963366 -282.758206)
			(xy 377.911404 -282.746346) (xy 377.86179 -282.726874) (xy 377.815632 -282.700225) (xy 377.773961 -282.666994)
			(xy 377.737709 -282.627923) (xy 377.707685 -282.583886) (xy 377.684559 -282.535865) (xy 377.668849 -282.484935)
			(xy 377.660906 -282.432231) (xy 377.432326 -282.432231) (xy 377.424383 -282.484935) (xy 377.408673 -282.535865)
			(xy 377.385547 -282.583886) (xy 377.355523 -282.627923) (xy 377.319271 -282.666994) (xy 377.2776 -282.700225)
			(xy 377.231442 -282.726874) (xy 377.181828 -282.746346) (xy 377.129866 -282.758206) (xy 377.076716 -282.76219)
			(xy 377.023566 -282.758206) (xy 376.971604 -282.746346) (xy 376.92199 -282.726874) (xy 376.875832 -282.700225)
			(xy 376.834161 -282.666994) (xy 376.797909 -282.627923) (xy 376.767885 -282.583886) (xy 376.744759 -282.535865)
			(xy 376.729049 -282.484935) (xy 376.721106 -282.432231) (xy 376.492526 -282.432231) (xy 376.484583 -282.484935)
			(xy 376.468873 -282.535865) (xy 376.445747 -282.583886) (xy 376.415723 -282.627923) (xy 376.379471 -282.666994)
			(xy 376.3378 -282.700225) (xy 376.291642 -282.726874) (xy 376.242028 -282.746346) (xy 376.190066 -282.758206)
			(xy 376.136916 -282.76219) (xy 376.083766 -282.758206) (xy 376.031804 -282.746346) (xy 375.98219 -282.726874)
			(xy 375.936032 -282.700225) (xy 375.894361 -282.666994) (xy 375.858109 -282.627923) (xy 375.828085 -282.583886)
			(xy 375.804959 -282.535865) (xy 375.789249 -282.484935) (xy 375.781306 -282.432231) (xy 375.552726 -282.432231)
			(xy 375.544783 -282.484935) (xy 375.529073 -282.535865) (xy 375.505947 -282.583886) (xy 375.475923 -282.627923)
			(xy 375.439671 -282.666994) (xy 375.398 -282.700225) (xy 375.351842 -282.726874) (xy 375.302228 -282.746346)
			(xy 375.250266 -282.758206) (xy 375.197116 -282.76219) (xy 375.143966 -282.758206) (xy 375.092004 -282.746346)
			(xy 375.04239 -282.726874) (xy 374.996232 -282.700225) (xy 374.954561 -282.666994) (xy 374.918309 -282.627923)
			(xy 374.888285 -282.583886) (xy 374.865159 -282.535865) (xy 374.849449 -282.484935) (xy 374.841506 -282.432231)
			(xy 374.612931 -282.432231) (xy 374.612926 -282.432485) (xy 374.604983 -282.485189) (xy 374.589273 -282.536119)
			(xy 374.566147 -282.58414) (xy 374.536123 -282.628177) (xy 374.499871 -282.667248) (xy 374.4582 -282.700479)
			(xy 374.412042 -282.727128) (xy 374.362428 -282.7466) (xy 374.310466 -282.75846) (xy 374.257316 -282.762444)
			(xy 374.204166 -282.75846) (xy 374.152204 -282.7466) (xy 374.10259 -282.727128) (xy 374.056432 -282.700479)
			(xy 374.014761 -282.667248) (xy 373.978509 -282.628177) (xy 373.948485 -282.58414) (xy 373.925359 -282.536119)
			(xy 373.909649 -282.485189) (xy 373.901706 -282.432485) (xy 373.672872 -282.432485) (xy 373.664929 -282.485189)
			(xy 373.649219 -282.536119) (xy 373.626093 -282.58414) (xy 373.596069 -282.628177) (xy 373.559817 -282.667248)
			(xy 373.518146 -282.700479) (xy 373.471988 -282.727128) (xy 373.422374 -282.7466) (xy 373.370412 -282.75846)
			(xy 373.317262 -282.762444) (xy 373.264112 -282.75846) (xy 373.21215 -282.7466) (xy 373.162536 -282.727128)
			(xy 373.116378 -282.700479) (xy 373.074707 -282.667248) (xy 373.038455 -282.628177) (xy 373.008431 -282.58414)
			(xy 372.985305 -282.536119) (xy 372.969595 -282.485189) (xy 372.961652 -282.432485) (xy 372.733072 -282.432485)
			(xy 372.725129 -282.485189) (xy 372.709419 -282.536119) (xy 372.686293 -282.58414) (xy 372.656269 -282.628177)
			(xy 372.620017 -282.667248) (xy 372.578346 -282.700479) (xy 372.532188 -282.727128) (xy 372.482574 -282.7466)
			(xy 372.430612 -282.75846) (xy 372.377462 -282.762444) (xy 372.324312 -282.75846) (xy 372.27235 -282.7466)
			(xy 372.222736 -282.727128) (xy 372.176578 -282.700479) (xy 372.134907 -282.667248) (xy 372.098655 -282.628177)
			(xy 372.068631 -282.58414) (xy 372.045505 -282.536119) (xy 372.029795 -282.485189) (xy 372.021852 -282.432485)
			(xy 371.793272 -282.432485) (xy 371.785329 -282.485189) (xy 371.769619 -282.536119) (xy 371.746493 -282.58414)
			(xy 371.716469 -282.628177) (xy 371.680217 -282.667248) (xy 371.638546 -282.700479) (xy 371.592388 -282.727128)
			(xy 371.542774 -282.7466) (xy 371.490812 -282.75846) (xy 371.437662 -282.762444) (xy 371.384512 -282.75846)
			(xy 371.33255 -282.7466) (xy 371.282936 -282.727128) (xy 371.236778 -282.700479) (xy 371.195107 -282.667248)
			(xy 371.158855 -282.628177) (xy 371.128831 -282.58414) (xy 371.105705 -282.536119) (xy 371.089995 -282.485189)
			(xy 371.082052 -282.432485) (xy 370.853472 -282.432485) (xy 370.845529 -282.485189) (xy 370.829819 -282.536119)
			(xy 370.806693 -282.58414) (xy 370.776669 -282.628177) (xy 370.740417 -282.667248) (xy 370.698746 -282.700479)
			(xy 370.652588 -282.727128) (xy 370.602974 -282.7466) (xy 370.551012 -282.75846) (xy 370.497862 -282.762444)
			(xy 370.444712 -282.75846) (xy 370.39275 -282.7466) (xy 370.343136 -282.727128) (xy 370.296978 -282.700479)
			(xy 370.255307 -282.667248) (xy 370.219055 -282.628177) (xy 370.189031 -282.58414) (xy 370.165905 -282.536119)
			(xy 370.150195 -282.485189) (xy 370.142252 -282.432485) (xy 369.913672 -282.432485) (xy 369.905729 -282.485189)
			(xy 369.890019 -282.536119) (xy 369.866893 -282.58414) (xy 369.836869 -282.628177) (xy 369.800617 -282.667248)
			(xy 369.758946 -282.700479) (xy 369.712788 -282.727128) (xy 369.663174 -282.7466) (xy 369.611212 -282.75846)
			(xy 369.558062 -282.762444) (xy 369.504912 -282.75846) (xy 369.45295 -282.7466) (xy 369.403336 -282.727128)
			(xy 369.357178 -282.700479) (xy 369.315507 -282.667248) (xy 369.279255 -282.628177) (xy 369.249231 -282.58414)
			(xy 369.226105 -282.536119) (xy 369.210395 -282.485189) (xy 369.202452 -282.432485) (xy 368.973872 -282.432485)
			(xy 368.965929 -282.485189) (xy 368.950219 -282.536119) (xy 368.927093 -282.58414) (xy 368.897069 -282.628177)
			(xy 368.860817 -282.667248) (xy 368.819146 -282.700479) (xy 368.772988 -282.727128) (xy 368.723374 -282.7466)
			(xy 368.671412 -282.75846) (xy 368.618262 -282.762444) (xy 368.565112 -282.75846) (xy 368.51315 -282.7466)
			(xy 368.463536 -282.727128) (xy 368.417378 -282.700479) (xy 368.375707 -282.667248) (xy 368.339455 -282.628177)
			(xy 368.309431 -282.58414) (xy 368.286305 -282.536119) (xy 368.270595 -282.485189) (xy 368.262652 -282.432485)
			(xy 368.034072 -282.432485) (xy 368.026129 -282.485189) (xy 368.010419 -282.536119) (xy 367.987293 -282.58414)
			(xy 367.957269 -282.628177) (xy 367.921017 -282.667248) (xy 367.879346 -282.700479) (xy 367.833188 -282.727128)
			(xy 367.783574 -282.7466) (xy 367.731612 -282.75846) (xy 367.678462 -282.762444) (xy 367.625312 -282.75846)
			(xy 367.57335 -282.7466) (xy 367.523736 -282.727128) (xy 367.477578 -282.700479) (xy 367.435907 -282.667248)
			(xy 367.399655 -282.628177) (xy 367.369631 -282.58414) (xy 367.346505 -282.536119) (xy 367.330795 -282.485189)
			(xy 367.322852 -282.432485) (xy 367.094266 -282.432485) (xy 367.086354 -282.485048) (xy 367.070697 -282.535894)
			(xy 367.047651 -282.583847) (xy 367.017728 -282.627837) (xy 366.981595 -282.666887) (xy 366.940055 -282.700128)
			(xy 366.894032 -282.72682) (xy 366.869472 -282.737052) (xy 366.856262 -282.742802) (xy 366.8335 -282.760441)
			(xy 366.816577 -282.783741) (xy 366.806845 -282.810843) (xy 366.805081 -282.839586) (xy 366.811423 -282.867675)
			(xy 366.825368 -282.892871) (xy 366.835182 -282.903422) (xy 366.927384 -282.995624) (xy 366.963452 -282.961588)
			(xy 366.98342 -282.943338) (xy 367.027844 -282.91247) (xy 367.076423 -282.888674) (xy 367.128043 -282.872497)
			(xy 367.181515 -282.864312) (xy 367.208562 -282.863798) (xy 367.236549 -282.864316) (xy 367.291835 -282.873067)
			(xy 367.345071 -282.890359) (xy 367.394946 -282.915768) (xy 367.440232 -282.948666) (xy 367.479813 -282.988244)
			(xy 367.512716 -283.033527) (xy 367.538128 -283.083399) (xy 367.555426 -283.136634) (xy 367.564182 -283.191919)
			(xy 367.56467 -283.219906) (xy 367.564173 -283.246555) (xy 367.793006 -283.246555) (xy 367.793006 -283.193257)
			(xy 367.800949 -283.140553) (xy 367.816659 -283.089623) (xy 367.839785 -283.041602) (xy 367.869809 -282.997565)
			(xy 367.906061 -282.958494) (xy 367.947732 -282.925263) (xy 367.99389 -282.898614) (xy 368.043504 -282.879142)
			(xy 368.095466 -282.867282) (xy 368.148616 -282.863299) (xy 368.201766 -282.867282) (xy 368.253728 -282.879142)
			(xy 368.303342 -282.898614) (xy 368.3495 -282.925263) (xy 368.391171 -282.958494) (xy 368.427423 -282.997565)
			(xy 368.457447 -283.041602) (xy 368.480573 -283.089623) (xy 368.496283 -283.140553) (xy 368.504226 -283.193257)
			(xy 368.504724 -283.219906) (xy 368.504226 -283.246555) (xy 368.732552 -283.246555) (xy 368.732552 -283.193257)
			(xy 368.740495 -283.140553) (xy 368.756205 -283.089623) (xy 368.779331 -283.041602) (xy 368.809355 -282.997565)
			(xy 368.845607 -282.958494) (xy 368.887278 -282.925263) (xy 368.933436 -282.898614) (xy 368.98305 -282.879142)
			(xy 369.035012 -282.867282) (xy 369.088162 -282.863299) (xy 369.141312 -282.867282) (xy 369.193274 -282.879142)
			(xy 369.242888 -282.898614) (xy 369.289046 -282.925263) (xy 369.330717 -282.958494) (xy 369.366969 -282.997565)
			(xy 369.396993 -283.041602) (xy 369.420119 -283.089623) (xy 369.435829 -283.140553) (xy 369.443772 -283.193257)
			(xy 369.44427 -283.219906) (xy 369.443772 -283.246555) (xy 369.672352 -283.246555) (xy 369.672352 -283.193257)
			(xy 369.680295 -283.140553) (xy 369.696005 -283.089623) (xy 369.719131 -283.041602) (xy 369.749155 -282.997565)
			(xy 369.785407 -282.958494) (xy 369.827078 -282.925263) (xy 369.873236 -282.898614) (xy 369.92285 -282.879142)
			(xy 369.974812 -282.867282) (xy 370.027962 -282.863299) (xy 370.081112 -282.867282) (xy 370.133074 -282.879142)
			(xy 370.182688 -282.898614) (xy 370.228846 -282.925263) (xy 370.270517 -282.958494) (xy 370.306769 -282.997565)
			(xy 370.336793 -283.041602) (xy 370.359919 -283.089623) (xy 370.375629 -283.140553) (xy 370.383572 -283.193257)
			(xy 370.38407 -283.219906) (xy 370.383572 -283.246555) (xy 370.612406 -283.246555) (xy 370.612406 -283.193257)
			(xy 370.620349 -283.140553) (xy 370.636059 -283.089623) (xy 370.659185 -283.041602) (xy 370.689209 -282.997565)
			(xy 370.725461 -282.958494) (xy 370.767132 -282.925263) (xy 370.81329 -282.898614) (xy 370.862904 -282.879142)
			(xy 370.914866 -282.867282) (xy 370.968016 -282.863299) (xy 371.021166 -282.867282) (xy 371.073128 -282.879142)
			(xy 371.122742 -282.898614) (xy 371.1689 -282.925263) (xy 371.210571 -282.958494) (xy 371.246823 -282.997565)
			(xy 371.276847 -283.041602) (xy 371.299973 -283.089623) (xy 371.315683 -283.140553) (xy 371.323626 -283.193257)
			(xy 371.324124 -283.219906) (xy 371.323626 -283.246555) (xy 372.492006 -283.246555) (xy 372.492006 -283.193257)
			(xy 372.499949 -283.140553) (xy 372.515659 -283.089623) (xy 372.538785 -283.041602) (xy 372.568809 -282.997565)
			(xy 372.605061 -282.958494) (xy 372.646732 -282.925263) (xy 372.69289 -282.898614) (xy 372.742504 -282.879142)
			(xy 372.794466 -282.867282) (xy 372.847616 -282.863299) (xy 372.900766 -282.867282) (xy 372.952728 -282.879142)
			(xy 373.002342 -282.898614) (xy 373.0485 -282.925263) (xy 373.090171 -282.958494) (xy 373.126423 -282.997565)
			(xy 373.156447 -283.041602) (xy 373.179573 -283.089623) (xy 373.195283 -283.140553) (xy 373.203226 -283.193257)
			(xy 373.203724 -283.219906) (xy 373.203226 -283.246555) (xy 373.431806 -283.246555) (xy 373.431806 -283.193257)
			(xy 373.439749 -283.140553) (xy 373.455459 -283.089623) (xy 373.478585 -283.041602) (xy 373.508609 -282.997565)
			(xy 373.544861 -282.958494) (xy 373.586532 -282.925263) (xy 373.63269 -282.898614) (xy 373.682304 -282.879142)
			(xy 373.734266 -282.867282) (xy 373.787416 -282.863299) (xy 373.840566 -282.867282) (xy 373.892528 -282.879142)
			(xy 373.942142 -282.898614) (xy 373.9883 -282.925263) (xy 374.029971 -282.958494) (xy 374.066223 -282.997565)
			(xy 374.096247 -283.041602) (xy 374.119373 -283.089623) (xy 374.135083 -283.140553) (xy 374.143026 -283.193257)
			(xy 374.143524 -283.219906) (xy 374.143026 -283.246555) (xy 374.371352 -283.246555) (xy 374.371352 -283.193257)
			(xy 374.379295 -283.140553) (xy 374.395005 -283.089623) (xy 374.418131 -283.041602) (xy 374.448155 -282.997565)
			(xy 374.484407 -282.958494) (xy 374.526078 -282.925263) (xy 374.572236 -282.898614) (xy 374.62185 -282.879142)
			(xy 374.673812 -282.867282) (xy 374.726962 -282.863299) (xy 374.780112 -282.867282) (xy 374.832074 -282.879142)
			(xy 374.881688 -282.898614) (xy 374.927846 -282.925263) (xy 374.969517 -282.958494) (xy 375.005769 -282.997565)
			(xy 375.035793 -283.041602) (xy 375.058919 -283.089623) (xy 375.074629 -283.140553) (xy 375.082572 -283.193257)
			(xy 375.08307 -283.219906) (xy 375.082577 -283.246301) (xy 376.250952 -283.246301) (xy 376.250952 -283.193003)
			(xy 376.258895 -283.140299) (xy 376.274605 -283.089369) (xy 376.297731 -283.041348) (xy 376.327755 -282.997311)
			(xy 376.364007 -282.95824) (xy 376.405678 -282.925009) (xy 376.451836 -282.89836) (xy 376.50145 -282.878888)
			(xy 376.553412 -282.867028) (xy 376.606562 -282.863045) (xy 376.659712 -282.867028) (xy 376.711674 -282.878888)
			(xy 376.761288 -282.89836) (xy 376.807446 -282.925009) (xy 376.849117 -282.95824) (xy 376.885369 -282.997311)
			(xy 376.915393 -283.041348) (xy 376.938519 -283.089369) (xy 376.954229 -283.140299) (xy 376.962172 -283.193003)
			(xy 376.96267 -283.219652) (xy 376.962172 -283.246301) (xy 376.962134 -283.246555) (xy 377.190752 -283.246555)
			(xy 377.190752 -283.193257) (xy 377.198695 -283.140553) (xy 377.214405 -283.089623) (xy 377.237531 -283.041602)
			(xy 377.267555 -282.997565) (xy 377.303807 -282.958494) (xy 377.345478 -282.925263) (xy 377.391636 -282.898614)
			(xy 377.44125 -282.879142) (xy 377.493212 -282.867282) (xy 377.546362 -282.863299) (xy 377.599512 -282.867282)
			(xy 377.651474 -282.879142) (xy 377.701088 -282.898614) (xy 377.747246 -282.925263) (xy 377.788917 -282.958494)
			(xy 377.825169 -282.997565) (xy 377.855193 -283.041602) (xy 377.878319 -283.089623) (xy 377.894029 -283.140553)
			(xy 377.901972 -283.193257) (xy 377.90247 -283.219906) (xy 377.901972 -283.246555) (xy 378.130552 -283.246555)
			(xy 378.130552 -283.193257) (xy 378.138495 -283.140553) (xy 378.154205 -283.089623) (xy 378.177331 -283.041602)
			(xy 378.207355 -282.997565) (xy 378.243607 -282.958494) (xy 378.285278 -282.925263) (xy 378.331436 -282.898614)
			(xy 378.38105 -282.879142) (xy 378.433012 -282.867282) (xy 378.486162 -282.863299) (xy 378.539312 -282.867282)
			(xy 378.591274 -282.879142) (xy 378.640888 -282.898614) (xy 378.687046 -282.925263) (xy 378.728717 -282.958494)
			(xy 378.764969 -282.997565) (xy 378.794993 -283.041602) (xy 378.818119 -283.089623) (xy 378.833829 -283.140553)
			(xy 378.841772 -283.193257) (xy 378.84227 -283.219906) (xy 378.841772 -283.246555) (xy 379.070606 -283.246555)
			(xy 379.070606 -283.193257) (xy 379.078549 -283.140553) (xy 379.094259 -283.089623) (xy 379.117385 -283.041602)
			(xy 379.147409 -282.997565) (xy 379.183661 -282.958494) (xy 379.225332 -282.925263) (xy 379.27149 -282.898614)
			(xy 379.321104 -282.879142) (xy 379.373066 -282.867282) (xy 379.426216 -282.863299) (xy 379.479366 -282.867282)
			(xy 379.531328 -282.879142) (xy 379.580942 -282.898614) (xy 379.6271 -282.925263) (xy 379.668771 -282.958494)
			(xy 379.705023 -282.997565) (xy 379.735047 -283.041602) (xy 379.758173 -283.089623) (xy 379.773883 -283.140553)
			(xy 379.781826 -283.193257) (xy 379.782324 -283.219906) (xy 379.781826 -283.246555) (xy 380.010152 -283.246555)
			(xy 380.010152 -283.193257) (xy 380.018095 -283.140553) (xy 380.033805 -283.089623) (xy 380.056931 -283.041602)
			(xy 380.086955 -282.997565) (xy 380.123207 -282.958494) (xy 380.164878 -282.925263) (xy 380.211036 -282.898614)
			(xy 380.26065 -282.879142) (xy 380.312612 -282.867282) (xy 380.365762 -282.863299) (xy 380.418912 -282.867282)
			(xy 380.470874 -282.879142) (xy 380.520488 -282.898614) (xy 380.566646 -282.925263) (xy 380.608317 -282.958494)
			(xy 380.644569 -282.997565) (xy 380.674593 -283.041602) (xy 380.697719 -283.089623) (xy 380.713429 -283.140553)
			(xy 380.721372 -283.193257) (xy 380.72187 -283.219906) (xy 380.721372 -283.246555) (xy 380.950206 -283.246555)
			(xy 380.950206 -283.193257) (xy 380.958149 -283.140553) (xy 380.973859 -283.089623) (xy 380.996985 -283.041602)
			(xy 381.027009 -282.997565) (xy 381.063261 -282.958494) (xy 381.104932 -282.925263) (xy 381.15109 -282.898614)
			(xy 381.200704 -282.879142) (xy 381.252666 -282.867282) (xy 381.305816 -282.863299) (xy 381.358966 -282.867282)
			(xy 381.410928 -282.879142) (xy 381.460542 -282.898614) (xy 381.5067 -282.925263) (xy 381.548371 -282.958494)
			(xy 381.584623 -282.997565) (xy 381.614647 -283.041602) (xy 381.637773 -283.089623) (xy 381.653483 -283.140553)
			(xy 381.661426 -283.193257) (xy 381.661924 -283.219906) (xy 381.661426 -283.246555) (xy 381.890006 -283.246555)
			(xy 381.890006 -283.193257) (xy 381.897949 -283.140553) (xy 381.913659 -283.089623) (xy 381.936785 -283.041602)
			(xy 381.966809 -282.997565) (xy 382.003061 -282.958494) (xy 382.044732 -282.925263) (xy 382.09089 -282.898614)
			(xy 382.140504 -282.879142) (xy 382.192466 -282.867282) (xy 382.245616 -282.863299) (xy 382.298766 -282.867282)
			(xy 382.350728 -282.879142) (xy 382.400342 -282.898614) (xy 382.4465 -282.925263) (xy 382.488171 -282.958494)
			(xy 382.524423 -282.997565) (xy 382.554447 -283.041602) (xy 382.577573 -283.089623) (xy 382.593283 -283.140553)
			(xy 382.601226 -283.193257) (xy 382.601724 -283.219906) (xy 382.601226 -283.246555) (xy 382.829552 -283.246555)
			(xy 382.829552 -283.193257) (xy 382.837495 -283.140553) (xy 382.853205 -283.089623) (xy 382.876331 -283.041602)
			(xy 382.906355 -282.997565) (xy 382.942607 -282.958494) (xy 382.984278 -282.925263) (xy 383.030436 -282.898614)
			(xy 383.08005 -282.879142) (xy 383.132012 -282.867282) (xy 383.185162 -282.863299) (xy 383.238312 -282.867282)
			(xy 383.290274 -282.879142) (xy 383.339888 -282.898614) (xy 383.386046 -282.925263) (xy 383.427717 -282.958494)
			(xy 383.463969 -282.997565) (xy 383.493993 -283.041602) (xy 383.517119 -283.089623) (xy 383.532829 -283.140553)
			(xy 383.540772 -283.193257) (xy 383.54127 -283.219906) (xy 383.540772 -283.246555) (xy 383.769352 -283.246555)
			(xy 383.769352 -283.193257) (xy 383.777295 -283.140553) (xy 383.793005 -283.089623) (xy 383.816131 -283.041602)
			(xy 383.846155 -282.997565) (xy 383.882407 -282.958494) (xy 383.924078 -282.925263) (xy 383.970236 -282.898614)
			(xy 384.01985 -282.879142) (xy 384.071812 -282.867282) (xy 384.124962 -282.863299) (xy 384.178112 -282.867282)
			(xy 384.230074 -282.879142) (xy 384.279688 -282.898614) (xy 384.325846 -282.925263) (xy 384.367517 -282.958494)
			(xy 384.403769 -282.997565) (xy 384.433793 -283.041602) (xy 384.456919 -283.089623) (xy 384.472629 -283.140553)
			(xy 384.480572 -283.193257) (xy 384.48107 -283.219906) (xy 384.480572 -283.246555) (xy 384.709406 -283.246555)
			(xy 384.709406 -283.193257) (xy 384.717349 -283.140553) (xy 384.733059 -283.089623) (xy 384.756185 -283.041602)
			(xy 384.786209 -282.997565) (xy 384.822461 -282.958494) (xy 384.864132 -282.925263) (xy 384.91029 -282.898614)
			(xy 384.959904 -282.879142) (xy 385.011866 -282.867282) (xy 385.065016 -282.863299) (xy 385.118166 -282.867282)
			(xy 385.170128 -282.879142) (xy 385.219742 -282.898614) (xy 385.2659 -282.925263) (xy 385.307571 -282.958494)
			(xy 385.343823 -282.997565) (xy 385.373847 -283.041602) (xy 385.396973 -283.089623) (xy 385.412683 -283.140553)
			(xy 385.420626 -283.193257) (xy 385.421124 -283.219906) (xy 385.420626 -283.246555) (xy 385.412683 -283.299259)
			(xy 385.396973 -283.350189) (xy 385.373847 -283.39821) (xy 385.343823 -283.442247) (xy 385.307571 -283.481318)
			(xy 385.2659 -283.514549) (xy 385.219742 -283.541198) (xy 385.170128 -283.56067) (xy 385.118166 -283.57253)
			(xy 385.065016 -283.576514) (xy 385.011866 -283.57253) (xy 384.959904 -283.56067) (xy 384.91029 -283.541198)
			(xy 384.864132 -283.514549) (xy 384.822461 -283.481318) (xy 384.786209 -283.442247) (xy 384.756185 -283.39821)
			(xy 384.733059 -283.350189) (xy 384.717349 -283.299259) (xy 384.709406 -283.246555) (xy 384.480572 -283.246555)
			(xy 384.472629 -283.299259) (xy 384.456919 -283.350189) (xy 384.433793 -283.39821) (xy 384.403769 -283.442247)
			(xy 384.367517 -283.481318) (xy 384.325846 -283.514549) (xy 384.279688 -283.541198) (xy 384.230074 -283.56067)
			(xy 384.178112 -283.57253) (xy 384.124962 -283.576514) (xy 384.071812 -283.57253) (xy 384.01985 -283.56067)
			(xy 383.970236 -283.541198) (xy 383.924078 -283.514549) (xy 383.882407 -283.481318) (xy 383.846155 -283.442247)
			(xy 383.816131 -283.39821) (xy 383.793005 -283.350189) (xy 383.777295 -283.299259) (xy 383.769352 -283.246555)
			(xy 383.540772 -283.246555) (xy 383.532829 -283.299259) (xy 383.517119 -283.350189) (xy 383.493993 -283.39821)
			(xy 383.463969 -283.442247) (xy 383.427717 -283.481318) (xy 383.386046 -283.514549) (xy 383.339888 -283.541198)
			(xy 383.290274 -283.56067) (xy 383.238312 -283.57253) (xy 383.185162 -283.576514) (xy 383.132012 -283.57253)
			(xy 383.08005 -283.56067) (xy 383.030436 -283.541198) (xy 382.984278 -283.514549) (xy 382.942607 -283.481318)
			(xy 382.906355 -283.442247) (xy 382.876331 -283.39821) (xy 382.853205 -283.350189) (xy 382.837495 -283.299259)
			(xy 382.829552 -283.246555) (xy 382.601226 -283.246555) (xy 382.593283 -283.299259) (xy 382.577573 -283.350189)
			(xy 382.554447 -283.39821) (xy 382.524423 -283.442247) (xy 382.488171 -283.481318) (xy 382.4465 -283.514549)
			(xy 382.400342 -283.541198) (xy 382.350728 -283.56067) (xy 382.298766 -283.57253) (xy 382.245616 -283.576514)
			(xy 382.192466 -283.57253) (xy 382.140504 -283.56067) (xy 382.09089 -283.541198) (xy 382.044732 -283.514549)
			(xy 382.003061 -283.481318) (xy 381.966809 -283.442247) (xy 381.936785 -283.39821) (xy 381.913659 -283.350189)
			(xy 381.897949 -283.299259) (xy 381.890006 -283.246555) (xy 381.661426 -283.246555) (xy 381.653483 -283.299259)
			(xy 381.637773 -283.350189) (xy 381.614647 -283.39821) (xy 381.584623 -283.442247) (xy 381.548371 -283.481318)
			(xy 381.5067 -283.514549) (xy 381.460542 -283.541198) (xy 381.410928 -283.56067) (xy 381.358966 -283.57253)
			(xy 381.305816 -283.576514) (xy 381.252666 -283.57253) (xy 381.200704 -283.56067) (xy 381.15109 -283.541198)
			(xy 381.104932 -283.514549) (xy 381.063261 -283.481318) (xy 381.027009 -283.442247) (xy 380.996985 -283.39821)
			(xy 380.973859 -283.350189) (xy 380.958149 -283.299259) (xy 380.950206 -283.246555) (xy 380.721372 -283.246555)
			(xy 380.713429 -283.299259) (xy 380.697719 -283.350189) (xy 380.674593 -283.39821) (xy 380.644569 -283.442247)
			(xy 380.608317 -283.481318) (xy 380.566646 -283.514549) (xy 380.520488 -283.541198) (xy 380.470874 -283.56067)
			(xy 380.418912 -283.57253) (xy 380.365762 -283.576514) (xy 380.312612 -283.57253) (xy 380.26065 -283.56067)
			(xy 380.211036 -283.541198) (xy 380.164878 -283.514549) (xy 380.123207 -283.481318) (xy 380.086955 -283.442247)
			(xy 380.056931 -283.39821) (xy 380.033805 -283.350189) (xy 380.018095 -283.299259) (xy 380.010152 -283.246555)
			(xy 379.781826 -283.246555) (xy 379.773883 -283.299259) (xy 379.758173 -283.350189) (xy 379.735047 -283.39821)
			(xy 379.705023 -283.442247) (xy 379.668771 -283.481318) (xy 379.6271 -283.514549) (xy 379.580942 -283.541198)
			(xy 379.531328 -283.56067) (xy 379.479366 -283.57253) (xy 379.426216 -283.576514) (xy 379.373066 -283.57253)
			(xy 379.321104 -283.56067) (xy 379.27149 -283.541198) (xy 379.225332 -283.514549) (xy 379.183661 -283.481318)
			(xy 379.147409 -283.442247) (xy 379.117385 -283.39821) (xy 379.094259 -283.350189) (xy 379.078549 -283.299259)
			(xy 379.070606 -283.246555) (xy 378.841772 -283.246555) (xy 378.833829 -283.299259) (xy 378.818119 -283.350189)
			(xy 378.794993 -283.39821) (xy 378.764969 -283.442247) (xy 378.728717 -283.481318) (xy 378.687046 -283.514549)
			(xy 378.640888 -283.541198) (xy 378.591274 -283.56067) (xy 378.539312 -283.57253) (xy 378.486162 -283.576514)
			(xy 378.433012 -283.57253) (xy 378.38105 -283.56067) (xy 378.331436 -283.541198) (xy 378.285278 -283.514549)
			(xy 378.243607 -283.481318) (xy 378.207355 -283.442247) (xy 378.177331 -283.39821) (xy 378.154205 -283.350189)
			(xy 378.138495 -283.299259) (xy 378.130552 -283.246555) (xy 377.901972 -283.246555) (xy 377.894029 -283.299259)
			(xy 377.878319 -283.350189) (xy 377.855193 -283.39821) (xy 377.825169 -283.442247) (xy 377.788917 -283.481318)
			(xy 377.747246 -283.514549) (xy 377.701088 -283.541198) (xy 377.651474 -283.56067) (xy 377.599512 -283.57253)
			(xy 377.546362 -283.576514) (xy 377.493212 -283.57253) (xy 377.44125 -283.56067) (xy 377.391636 -283.541198)
			(xy 377.345478 -283.514549) (xy 377.303807 -283.481318) (xy 377.267555 -283.442247) (xy 377.237531 -283.39821)
			(xy 377.214405 -283.350189) (xy 377.198695 -283.299259) (xy 377.190752 -283.246555) (xy 376.962134 -283.246555)
			(xy 376.954229 -283.299005) (xy 376.938519 -283.349935) (xy 376.915393 -283.397956) (xy 376.885369 -283.441993)
			(xy 376.849117 -283.481064) (xy 376.807446 -283.514295) (xy 376.761288 -283.540944) (xy 376.711674 -283.560416)
			(xy 376.659712 -283.572276) (xy 376.606562 -283.57626) (xy 376.553412 -283.572276) (xy 376.50145 -283.560416)
			(xy 376.451836 -283.540944) (xy 376.405678 -283.514295) (xy 376.364007 -283.481064) (xy 376.327755 -283.441993)
			(xy 376.297731 -283.397956) (xy 376.274605 -283.349935) (xy 376.258895 -283.299005) (xy 376.250952 -283.246301)
			(xy 375.082577 -283.246301) (xy 375.082572 -283.246555) (xy 375.074629 -283.299259) (xy 375.058919 -283.350189)
			(xy 375.035793 -283.39821) (xy 375.005769 -283.442247) (xy 374.969517 -283.481318) (xy 374.927846 -283.514549)
			(xy 374.881688 -283.541198) (xy 374.832074 -283.56067) (xy 374.780112 -283.57253) (xy 374.726962 -283.576514)
			(xy 374.673812 -283.57253) (xy 374.62185 -283.56067) (xy 374.572236 -283.541198) (xy 374.526078 -283.514549)
			(xy 374.484407 -283.481318) (xy 374.448155 -283.442247) (xy 374.418131 -283.39821) (xy 374.395005 -283.350189)
			(xy 374.379295 -283.299259) (xy 374.371352 -283.246555) (xy 374.143026 -283.246555) (xy 374.135083 -283.299259)
			(xy 374.119373 -283.350189) (xy 374.096247 -283.39821) (xy 374.066223 -283.442247) (xy 374.029971 -283.481318)
			(xy 373.9883 -283.514549) (xy 373.942142 -283.541198) (xy 373.892528 -283.56067) (xy 373.840566 -283.57253)
			(xy 373.787416 -283.576514) (xy 373.734266 -283.57253) (xy 373.682304 -283.56067) (xy 373.63269 -283.541198)
			(xy 373.586532 -283.514549) (xy 373.544861 -283.481318) (xy 373.508609 -283.442247) (xy 373.478585 -283.39821)
			(xy 373.455459 -283.350189) (xy 373.439749 -283.299259) (xy 373.431806 -283.246555) (xy 373.203226 -283.246555)
			(xy 373.195283 -283.299259) (xy 373.179573 -283.350189) (xy 373.156447 -283.39821) (xy 373.126423 -283.442247)
			(xy 373.090171 -283.481318) (xy 373.0485 -283.514549) (xy 373.002342 -283.541198) (xy 372.952728 -283.56067)
			(xy 372.900766 -283.57253) (xy 372.847616 -283.576514) (xy 372.794466 -283.57253) (xy 372.742504 -283.56067)
			(xy 372.69289 -283.541198) (xy 372.646732 -283.514549) (xy 372.605061 -283.481318) (xy 372.568809 -283.442247)
			(xy 372.538785 -283.39821) (xy 372.515659 -283.350189) (xy 372.499949 -283.299259) (xy 372.492006 -283.246555)
			(xy 371.323626 -283.246555) (xy 371.315683 -283.299259) (xy 371.299973 -283.350189) (xy 371.276847 -283.39821)
			(xy 371.246823 -283.442247) (xy 371.210571 -283.481318) (xy 371.1689 -283.514549) (xy 371.122742 -283.541198)
			(xy 371.073128 -283.56067) (xy 371.021166 -283.57253) (xy 370.968016 -283.576514) (xy 370.914866 -283.57253)
			(xy 370.862904 -283.56067) (xy 370.81329 -283.541198) (xy 370.767132 -283.514549) (xy 370.725461 -283.481318)
			(xy 370.689209 -283.442247) (xy 370.659185 -283.39821) (xy 370.636059 -283.350189) (xy 370.620349 -283.299259)
			(xy 370.612406 -283.246555) (xy 370.383572 -283.246555) (xy 370.375629 -283.299259) (xy 370.359919 -283.350189)
			(xy 370.336793 -283.39821) (xy 370.306769 -283.442247) (xy 370.270517 -283.481318) (xy 370.228846 -283.514549)
			(xy 370.182688 -283.541198) (xy 370.133074 -283.56067) (xy 370.081112 -283.57253) (xy 370.027962 -283.576514)
			(xy 369.974812 -283.57253) (xy 369.92285 -283.56067) (xy 369.873236 -283.541198) (xy 369.827078 -283.514549)
			(xy 369.785407 -283.481318) (xy 369.749155 -283.442247) (xy 369.719131 -283.39821) (xy 369.696005 -283.350189)
			(xy 369.680295 -283.299259) (xy 369.672352 -283.246555) (xy 369.443772 -283.246555) (xy 369.435829 -283.299259)
			(xy 369.420119 -283.350189) (xy 369.396993 -283.39821) (xy 369.366969 -283.442247) (xy 369.330717 -283.481318)
			(xy 369.289046 -283.514549) (xy 369.242888 -283.541198) (xy 369.193274 -283.56067) (xy 369.141312 -283.57253)
			(xy 369.088162 -283.576514) (xy 369.035012 -283.57253) (xy 368.98305 -283.56067) (xy 368.933436 -283.541198)
			(xy 368.887278 -283.514549) (xy 368.845607 -283.481318) (xy 368.809355 -283.442247) (xy 368.779331 -283.39821)
			(xy 368.756205 -283.350189) (xy 368.740495 -283.299259) (xy 368.732552 -283.246555) (xy 368.504226 -283.246555)
			(xy 368.496283 -283.299259) (xy 368.480573 -283.350189) (xy 368.457447 -283.39821) (xy 368.427423 -283.442247)
			(xy 368.391171 -283.481318) (xy 368.3495 -283.514549) (xy 368.303342 -283.541198) (xy 368.253728 -283.56067)
			(xy 368.201766 -283.57253) (xy 368.148616 -283.576514) (xy 368.095466 -283.57253) (xy 368.043504 -283.56067)
			(xy 367.99389 -283.541198) (xy 367.947732 -283.514549) (xy 367.906061 -283.481318) (xy 367.869809 -283.442247)
			(xy 367.839785 -283.39821) (xy 367.816659 -283.350189) (xy 367.800949 -283.299259) (xy 367.793006 -283.246555)
			(xy 367.564173 -283.246555) (xy 367.564166 -283.246954) (xy 367.555983 -283.300427) (xy 367.539804 -283.352047)
			(xy 367.516004 -283.400626) (xy 367.48513 -283.445046) (xy 367.46688 -283.465016) (xy 367.432844 -283.501084)
			(xy 367.614454 -283.682694) (xy 367.638584 -283.6799) (xy 367.648519 -283.678833) (xy 367.66847 -283.677687)
			(xy 367.678462 -283.677614) (xy 367.706449 -283.678132) (xy 367.761734 -283.686883) (xy 367.814969 -283.704176)
			(xy 367.864842 -283.729584) (xy 367.910127 -283.762483) (xy 367.949707 -283.802061) (xy 367.982607 -283.847344)
			(xy 368.008018 -283.897217) (xy 368.025313 -283.950451) (xy 368.034067 -284.005735) (xy 368.03457 -284.033722)
			(xy 368.034091 -284.060371) (xy 368.262652 -284.060371) (xy 368.262652 -284.007073) (xy 368.270595 -283.954369)
			(xy 368.286305 -283.903439) (xy 368.309431 -283.855418) (xy 368.339455 -283.811381) (xy 368.375707 -283.77231)
			(xy 368.417378 -283.739079) (xy 368.463536 -283.71243) (xy 368.51315 -283.692958) (xy 368.565112 -283.681098)
			(xy 368.618262 -283.677115) (xy 368.671412 -283.681098) (xy 368.723374 -283.692958) (xy 368.772988 -283.71243)
			(xy 368.819146 -283.739079) (xy 368.860817 -283.77231) (xy 368.897069 -283.811381) (xy 368.927093 -283.855418)
			(xy 368.950219 -283.903439) (xy 368.965929 -283.954369) (xy 368.973872 -284.007073) (xy 368.97437 -284.033722)
			(xy 368.973872 -284.060371) (xy 369.202452 -284.060371) (xy 369.202452 -284.007073) (xy 369.210395 -283.954369)
			(xy 369.226105 -283.903439) (xy 369.249231 -283.855418) (xy 369.279255 -283.811381) (xy 369.315507 -283.77231)
			(xy 369.357178 -283.739079) (xy 369.403336 -283.71243) (xy 369.45295 -283.692958) (xy 369.504912 -283.681098)
			(xy 369.558062 -283.677115) (xy 369.611212 -283.681098) (xy 369.663174 -283.692958) (xy 369.712788 -283.71243)
			(xy 369.758946 -283.739079) (xy 369.800617 -283.77231) (xy 369.836869 -283.811381) (xy 369.866893 -283.855418)
			(xy 369.890019 -283.903439) (xy 369.905729 -283.954369) (xy 369.913672 -284.007073) (xy 369.91417 -284.033722)
			(xy 369.913672 -284.060371) (xy 370.142252 -284.060371) (xy 370.142252 -284.007073) (xy 370.150195 -283.954369)
			(xy 370.165905 -283.903439) (xy 370.189031 -283.855418) (xy 370.219055 -283.811381) (xy 370.255307 -283.77231)
			(xy 370.296978 -283.739079) (xy 370.343136 -283.71243) (xy 370.39275 -283.692958) (xy 370.444712 -283.681098)
			(xy 370.497862 -283.677115) (xy 370.551012 -283.681098) (xy 370.602974 -283.692958) (xy 370.652588 -283.71243)
			(xy 370.698746 -283.739079) (xy 370.740417 -283.77231) (xy 370.776669 -283.811381) (xy 370.806693 -283.855418)
			(xy 370.829819 -283.903439) (xy 370.845529 -283.954369) (xy 370.853472 -284.007073) (xy 370.85397 -284.033722)
			(xy 370.853472 -284.060371) (xy 371.082052 -284.060371) (xy 371.082052 -284.007073) (xy 371.089995 -283.954369)
			(xy 371.105705 -283.903439) (xy 371.128831 -283.855418) (xy 371.158855 -283.811381) (xy 371.195107 -283.77231)
			(xy 371.236778 -283.739079) (xy 371.282936 -283.71243) (xy 371.33255 -283.692958) (xy 371.384512 -283.681098)
			(xy 371.437662 -283.677115) (xy 371.490812 -283.681098) (xy 371.542774 -283.692958) (xy 371.592388 -283.71243)
			(xy 371.638546 -283.739079) (xy 371.680217 -283.77231) (xy 371.716469 -283.811381) (xy 371.746493 -283.855418)
			(xy 371.769619 -283.903439) (xy 371.785329 -283.954369) (xy 371.793272 -284.007073) (xy 371.79377 -284.033722)
			(xy 371.793272 -284.060371) (xy 372.021852 -284.060371) (xy 372.021852 -284.007073) (xy 372.029795 -283.954369)
			(xy 372.045505 -283.903439) (xy 372.068631 -283.855418) (xy 372.098655 -283.811381) (xy 372.134907 -283.77231)
			(xy 372.176578 -283.739079) (xy 372.222736 -283.71243) (xy 372.27235 -283.692958) (xy 372.324312 -283.681098)
			(xy 372.377462 -283.677115) (xy 372.430612 -283.681098) (xy 372.482574 -283.692958) (xy 372.532188 -283.71243)
			(xy 372.578346 -283.739079) (xy 372.620017 -283.77231) (xy 372.656269 -283.811381) (xy 372.686293 -283.855418)
			(xy 372.709419 -283.903439) (xy 372.725129 -283.954369) (xy 372.733072 -284.007073) (xy 372.73357 -284.033722)
			(xy 372.733072 -284.060371) (xy 372.961906 -284.060371) (xy 372.961906 -284.007073) (xy 372.969849 -283.954369)
			(xy 372.985559 -283.903439) (xy 373.008685 -283.855418) (xy 373.038709 -283.811381) (xy 373.074961 -283.77231)
			(xy 373.116632 -283.739079) (xy 373.16279 -283.71243) (xy 373.212404 -283.692958) (xy 373.264366 -283.681098)
			(xy 373.317516 -283.677115) (xy 373.370666 -283.681098) (xy 373.422628 -283.692958) (xy 373.472242 -283.71243)
			(xy 373.5184 -283.739079) (xy 373.560071 -283.77231) (xy 373.596323 -283.811381) (xy 373.626347 -283.855418)
			(xy 373.649473 -283.903439) (xy 373.665183 -283.954369) (xy 373.673126 -284.007073) (xy 373.673624 -284.033722)
			(xy 373.673126 -284.060371) (xy 373.901452 -284.060371) (xy 373.901452 -284.007073) (xy 373.909395 -283.954369)
			(xy 373.925105 -283.903439) (xy 373.948231 -283.855418) (xy 373.978255 -283.811381) (xy 374.014507 -283.77231)
			(xy 374.056178 -283.739079) (xy 374.102336 -283.71243) (xy 374.15195 -283.692958) (xy 374.203912 -283.681098)
			(xy 374.257062 -283.677115) (xy 374.310212 -283.681098) (xy 374.362174 -283.692958) (xy 374.411788 -283.71243)
			(xy 374.457946 -283.739079) (xy 374.499617 -283.77231) (xy 374.535869 -283.811381) (xy 374.565893 -283.855418)
			(xy 374.589019 -283.903439) (xy 374.604729 -283.954369) (xy 374.612672 -284.007073) (xy 374.61317 -284.033722)
			(xy 374.612672 -284.060371) (xy 374.841252 -284.060371) (xy 374.841252 -284.007073) (xy 374.849195 -283.954369)
			(xy 374.864905 -283.903439) (xy 374.888031 -283.855418) (xy 374.918055 -283.811381) (xy 374.954307 -283.77231)
			(xy 374.995978 -283.739079) (xy 375.042136 -283.71243) (xy 375.09175 -283.692958) (xy 375.143712 -283.681098)
			(xy 375.196862 -283.677115) (xy 375.250012 -283.681098) (xy 375.301974 -283.692958) (xy 375.351588 -283.71243)
			(xy 375.397746 -283.739079) (xy 375.439417 -283.77231) (xy 375.475669 -283.811381) (xy 375.505693 -283.855418)
			(xy 375.528819 -283.903439) (xy 375.544529 -283.954369) (xy 375.552472 -284.007073) (xy 375.55297 -284.033722)
			(xy 375.552472 -284.060371) (xy 375.781052 -284.060371) (xy 375.781052 -284.007073) (xy 375.788995 -283.954369)
			(xy 375.804705 -283.903439) (xy 375.827831 -283.855418) (xy 375.857855 -283.811381) (xy 375.894107 -283.77231)
			(xy 375.935778 -283.739079) (xy 375.981936 -283.71243) (xy 376.03155 -283.692958) (xy 376.083512 -283.681098)
			(xy 376.136662 -283.677115) (xy 376.189812 -283.681098) (xy 376.241774 -283.692958) (xy 376.291388 -283.71243)
			(xy 376.337546 -283.739079) (xy 376.379217 -283.77231) (xy 376.415469 -283.811381) (xy 376.445493 -283.855418)
			(xy 376.468619 -283.903439) (xy 376.484329 -283.954369) (xy 376.492272 -284.007073) (xy 376.49277 -284.033722)
			(xy 376.492272 -284.060371) (xy 376.720852 -284.060371) (xy 376.720852 -284.007073) (xy 376.728795 -283.954369)
			(xy 376.744505 -283.903439) (xy 376.767631 -283.855418) (xy 376.797655 -283.811381) (xy 376.833907 -283.77231)
			(xy 376.875578 -283.739079) (xy 376.921736 -283.71243) (xy 376.97135 -283.692958) (xy 377.023312 -283.681098)
			(xy 377.076462 -283.677115) (xy 377.129612 -283.681098) (xy 377.181574 -283.692958) (xy 377.231188 -283.71243)
			(xy 377.277346 -283.739079) (xy 377.319017 -283.77231) (xy 377.355269 -283.811381) (xy 377.385293 -283.855418)
			(xy 377.408419 -283.903439) (xy 377.424129 -283.954369) (xy 377.432072 -284.007073) (xy 377.43257 -284.033722)
			(xy 377.432072 -284.060371) (xy 377.660652 -284.060371) (xy 377.660652 -284.007073) (xy 377.668595 -283.954369)
			(xy 377.684305 -283.903439) (xy 377.707431 -283.855418) (xy 377.737455 -283.811381) (xy 377.773707 -283.77231)
			(xy 377.815378 -283.739079) (xy 377.861536 -283.71243) (xy 377.91115 -283.692958) (xy 377.963112 -283.681098)
			(xy 378.016262 -283.677115) (xy 378.069412 -283.681098) (xy 378.121374 -283.692958) (xy 378.170988 -283.71243)
			(xy 378.217146 -283.739079) (xy 378.258817 -283.77231) (xy 378.295069 -283.811381) (xy 378.325093 -283.855418)
			(xy 378.348219 -283.903439) (xy 378.363929 -283.954369) (xy 378.371872 -284.007073) (xy 378.37237 -284.033722)
			(xy 378.371872 -284.060371) (xy 378.600452 -284.060371) (xy 378.600452 -284.007073) (xy 378.608395 -283.954369)
			(xy 378.624105 -283.903439) (xy 378.647231 -283.855418) (xy 378.677255 -283.811381) (xy 378.713507 -283.77231)
			(xy 378.755178 -283.739079) (xy 378.801336 -283.71243) (xy 378.85095 -283.692958) (xy 378.902912 -283.681098)
			(xy 378.956062 -283.677115) (xy 379.009212 -283.681098) (xy 379.061174 -283.692958) (xy 379.110788 -283.71243)
			(xy 379.156946 -283.739079) (xy 379.198617 -283.77231) (xy 379.234869 -283.811381) (xy 379.264893 -283.855418)
			(xy 379.288019 -283.903439) (xy 379.303729 -283.954369) (xy 379.311672 -284.007073) (xy 379.31217 -284.033722)
			(xy 379.311672 -284.060371) (xy 379.540252 -284.060371) (xy 379.540252 -284.007073) (xy 379.548195 -283.954369)
			(xy 379.563905 -283.903439) (xy 379.587031 -283.855418) (xy 379.617055 -283.811381) (xy 379.653307 -283.77231)
			(xy 379.694978 -283.739079) (xy 379.741136 -283.71243) (xy 379.79075 -283.692958) (xy 379.842712 -283.681098)
			(xy 379.895862 -283.677115) (xy 379.949012 -283.681098) (xy 380.000974 -283.692958) (xy 380.050588 -283.71243)
			(xy 380.096746 -283.739079) (xy 380.138417 -283.77231) (xy 380.174669 -283.811381) (xy 380.204693 -283.855418)
			(xy 380.227819 -283.903439) (xy 380.243529 -283.954369) (xy 380.251472 -284.007073) (xy 380.25197 -284.033722)
			(xy 380.251472 -284.060371) (xy 380.480052 -284.060371) (xy 380.480052 -284.007073) (xy 380.487995 -283.954369)
			(xy 380.503705 -283.903439) (xy 380.526831 -283.855418) (xy 380.556855 -283.811381) (xy 380.593107 -283.77231)
			(xy 380.634778 -283.739079) (xy 380.680936 -283.71243) (xy 380.73055 -283.692958) (xy 380.782512 -283.681098)
			(xy 380.835662 -283.677115) (xy 380.888812 -283.681098) (xy 380.940774 -283.692958) (xy 380.990388 -283.71243)
			(xy 381.036546 -283.739079) (xy 381.078217 -283.77231) (xy 381.114469 -283.811381) (xy 381.144493 -283.855418)
			(xy 381.167619 -283.903439) (xy 381.183329 -283.954369) (xy 381.191272 -284.007073) (xy 381.19177 -284.033722)
			(xy 381.191272 -284.060371) (xy 382.359652 -284.060371) (xy 382.359652 -284.007073) (xy 382.367595 -283.954369)
			(xy 382.383305 -283.903439) (xy 382.406431 -283.855418) (xy 382.436455 -283.811381) (xy 382.472707 -283.77231)
			(xy 382.514378 -283.739079) (xy 382.560536 -283.71243) (xy 382.61015 -283.692958) (xy 382.662112 -283.681098)
			(xy 382.715262 -283.677115) (xy 382.768412 -283.681098) (xy 382.820374 -283.692958) (xy 382.869988 -283.71243)
			(xy 382.916146 -283.739079) (xy 382.957817 -283.77231) (xy 382.994069 -283.811381) (xy 383.024093 -283.855418)
			(xy 383.047219 -283.903439) (xy 383.062929 -283.954369) (xy 383.070872 -284.007073) (xy 383.07137 -284.033722)
			(xy 383.070872 -284.060371) (xy 383.062929 -284.113075) (xy 383.047219 -284.164005) (xy 383.024093 -284.212026)
			(xy 382.994069 -284.256063) (xy 382.957817 -284.295134) (xy 382.916146 -284.328365) (xy 382.869988 -284.355014)
			(xy 382.820374 -284.374486) (xy 382.768412 -284.386346) (xy 382.715262 -284.39033) (xy 382.662112 -284.386346)
			(xy 382.61015 -284.374486) (xy 382.560536 -284.355014) (xy 382.514378 -284.328365) (xy 382.472707 -284.295134)
			(xy 382.436455 -284.256063) (xy 382.406431 -284.212026) (xy 382.383305 -284.164005) (xy 382.367595 -284.113075)
			(xy 382.359652 -284.060371) (xy 381.191272 -284.060371) (xy 381.183329 -284.113075) (xy 381.167619 -284.164005)
			(xy 381.144493 -284.212026) (xy 381.114469 -284.256063) (xy 381.078217 -284.295134) (xy 381.036546 -284.328365)
			(xy 380.990388 -284.355014) (xy 380.940774 -284.374486) (xy 380.888812 -284.386346) (xy 380.835662 -284.39033)
			(xy 380.782512 -284.386346) (xy 380.73055 -284.374486) (xy 380.680936 -284.355014) (xy 380.634778 -284.328365)
			(xy 380.593107 -284.295134) (xy 380.556855 -284.256063) (xy 380.526831 -284.212026) (xy 380.503705 -284.164005)
			(xy 380.487995 -284.113075) (xy 380.480052 -284.060371) (xy 380.251472 -284.060371) (xy 380.243529 -284.113075)
			(xy 380.227819 -284.164005) (xy 380.204693 -284.212026) (xy 380.174669 -284.256063) (xy 380.138417 -284.295134)
			(xy 380.096746 -284.328365) (xy 380.050588 -284.355014) (xy 380.000974 -284.374486) (xy 379.949012 -284.386346)
			(xy 379.895862 -284.39033) (xy 379.842712 -284.386346) (xy 379.79075 -284.374486) (xy 379.741136 -284.355014)
			(xy 379.694978 -284.328365) (xy 379.653307 -284.295134) (xy 379.617055 -284.256063) (xy 379.587031 -284.212026)
			(xy 379.563905 -284.164005) (xy 379.548195 -284.113075) (xy 379.540252 -284.060371) (xy 379.311672 -284.060371)
			(xy 379.303729 -284.113075) (xy 379.288019 -284.164005) (xy 379.264893 -284.212026) (xy 379.234869 -284.256063)
			(xy 379.198617 -284.295134) (xy 379.156946 -284.328365) (xy 379.110788 -284.355014) (xy 379.061174 -284.374486)
			(xy 379.009212 -284.386346) (xy 378.956062 -284.39033) (xy 378.902912 -284.386346) (xy 378.85095 -284.374486)
			(xy 378.801336 -284.355014) (xy 378.755178 -284.328365) (xy 378.713507 -284.295134) (xy 378.677255 -284.256063)
			(xy 378.647231 -284.212026) (xy 378.624105 -284.164005) (xy 378.608395 -284.113075) (xy 378.600452 -284.060371)
			(xy 378.371872 -284.060371) (xy 378.363929 -284.113075) (xy 378.348219 -284.164005) (xy 378.325093 -284.212026)
			(xy 378.295069 -284.256063) (xy 378.258817 -284.295134) (xy 378.217146 -284.328365) (xy 378.170988 -284.355014)
			(xy 378.121374 -284.374486) (xy 378.069412 -284.386346) (xy 378.016262 -284.39033) (xy 377.963112 -284.386346)
			(xy 377.91115 -284.374486) (xy 377.861536 -284.355014) (xy 377.815378 -284.328365) (xy 377.773707 -284.295134)
			(xy 377.737455 -284.256063) (xy 377.707431 -284.212026) (xy 377.684305 -284.164005) (xy 377.668595 -284.113075)
			(xy 377.660652 -284.060371) (xy 377.432072 -284.060371) (xy 377.424129 -284.113075) (xy 377.408419 -284.164005)
			(xy 377.385293 -284.212026) (xy 377.355269 -284.256063) (xy 377.319017 -284.295134) (xy 377.277346 -284.328365)
			(xy 377.231188 -284.355014) (xy 377.181574 -284.374486) (xy 377.129612 -284.386346) (xy 377.076462 -284.39033)
			(xy 377.023312 -284.386346) (xy 376.97135 -284.374486) (xy 376.921736 -284.355014) (xy 376.875578 -284.328365)
			(xy 376.833907 -284.295134) (xy 376.797655 -284.256063) (xy 376.767631 -284.212026) (xy 376.744505 -284.164005)
			(xy 376.728795 -284.113075) (xy 376.720852 -284.060371) (xy 376.492272 -284.060371) (xy 376.484329 -284.113075)
			(xy 376.468619 -284.164005) (xy 376.445493 -284.212026) (xy 376.415469 -284.256063) (xy 376.379217 -284.295134)
			(xy 376.337546 -284.328365) (xy 376.291388 -284.355014) (xy 376.241774 -284.374486) (xy 376.189812 -284.386346)
			(xy 376.136662 -284.39033) (xy 376.083512 -284.386346) (xy 376.03155 -284.374486) (xy 375.981936 -284.355014)
			(xy 375.935778 -284.328365) (xy 375.894107 -284.295134) (xy 375.857855 -284.256063) (xy 375.827831 -284.212026)
			(xy 375.804705 -284.164005) (xy 375.788995 -284.113075) (xy 375.781052 -284.060371) (xy 375.552472 -284.060371)
			(xy 375.544529 -284.113075) (xy 375.528819 -284.164005) (xy 375.505693 -284.212026) (xy 375.475669 -284.256063)
			(xy 375.439417 -284.295134) (xy 375.397746 -284.328365) (xy 375.351588 -284.355014) (xy 375.301974 -284.374486)
			(xy 375.250012 -284.386346) (xy 375.196862 -284.39033) (xy 375.143712 -284.386346) (xy 375.09175 -284.374486)
			(xy 375.042136 -284.355014) (xy 374.995978 -284.328365) (xy 374.954307 -284.295134) (xy 374.918055 -284.256063)
			(xy 374.888031 -284.212026) (xy 374.864905 -284.164005) (xy 374.849195 -284.113075) (xy 374.841252 -284.060371)
			(xy 374.612672 -284.060371) (xy 374.604729 -284.113075) (xy 374.589019 -284.164005) (xy 374.565893 -284.212026)
			(xy 374.535869 -284.256063) (xy 374.499617 -284.295134) (xy 374.457946 -284.328365) (xy 374.411788 -284.355014)
			(xy 374.362174 -284.374486) (xy 374.310212 -284.386346) (xy 374.257062 -284.39033) (xy 374.203912 -284.386346)
			(xy 374.15195 -284.374486) (xy 374.102336 -284.355014) (xy 374.056178 -284.328365) (xy 374.014507 -284.295134)
			(xy 373.978255 -284.256063) (xy 373.948231 -284.212026) (xy 373.925105 -284.164005) (xy 373.909395 -284.113075)
			(xy 373.901452 -284.060371) (xy 373.673126 -284.060371) (xy 373.665183 -284.113075) (xy 373.649473 -284.164005)
			(xy 373.626347 -284.212026) (xy 373.596323 -284.256063) (xy 373.560071 -284.295134) (xy 373.5184 -284.328365)
			(xy 373.472242 -284.355014) (xy 373.422628 -284.374486) (xy 373.370666 -284.386346) (xy 373.317516 -284.39033)
			(xy 373.264366 -284.386346) (xy 373.212404 -284.374486) (xy 373.16279 -284.355014) (xy 373.116632 -284.328365)
			(xy 373.074961 -284.295134) (xy 373.038709 -284.256063) (xy 373.008685 -284.212026) (xy 372.985559 -284.164005)
			(xy 372.969849 -284.113075) (xy 372.961906 -284.060371) (xy 372.733072 -284.060371) (xy 372.725129 -284.113075)
			(xy 372.709419 -284.164005) (xy 372.686293 -284.212026) (xy 372.656269 -284.256063) (xy 372.620017 -284.295134)
			(xy 372.578346 -284.328365) (xy 372.532188 -284.355014) (xy 372.482574 -284.374486) (xy 372.430612 -284.386346)
			(xy 372.377462 -284.39033) (xy 372.324312 -284.386346) (xy 372.27235 -284.374486) (xy 372.222736 -284.355014)
			(xy 372.176578 -284.328365) (xy 372.134907 -284.295134) (xy 372.098655 -284.256063) (xy 372.068631 -284.212026)
			(xy 372.045505 -284.164005) (xy 372.029795 -284.113075) (xy 372.021852 -284.060371) (xy 371.793272 -284.060371)
			(xy 371.785329 -284.113075) (xy 371.769619 -284.164005) (xy 371.746493 -284.212026) (xy 371.716469 -284.256063)
			(xy 371.680217 -284.295134) (xy 371.638546 -284.328365) (xy 371.592388 -284.355014) (xy 371.542774 -284.374486)
			(xy 371.490812 -284.386346) (xy 371.437662 -284.39033) (xy 371.384512 -284.386346) (xy 371.33255 -284.374486)
			(xy 371.282936 -284.355014) (xy 371.236778 -284.328365) (xy 371.195107 -284.295134) (xy 371.158855 -284.256063)
			(xy 371.128831 -284.212026) (xy 371.105705 -284.164005) (xy 371.089995 -284.113075) (xy 371.082052 -284.060371)
			(xy 370.853472 -284.060371) (xy 370.845529 -284.113075) (xy 370.829819 -284.164005) (xy 370.806693 -284.212026)
			(xy 370.776669 -284.256063) (xy 370.740417 -284.295134) (xy 370.698746 -284.328365) (xy 370.652588 -284.355014)
			(xy 370.602974 -284.374486) (xy 370.551012 -284.386346) (xy 370.497862 -284.39033) (xy 370.444712 -284.386346)
			(xy 370.39275 -284.374486) (xy 370.343136 -284.355014) (xy 370.296978 -284.328365) (xy 370.255307 -284.295134)
			(xy 370.219055 -284.256063) (xy 370.189031 -284.212026) (xy 370.165905 -284.164005) (xy 370.150195 -284.113075)
			(xy 370.142252 -284.060371) (xy 369.913672 -284.060371) (xy 369.905729 -284.113075) (xy 369.890019 -284.164005)
			(xy 369.866893 -284.212026) (xy 369.836869 -284.256063) (xy 369.800617 -284.295134) (xy 369.758946 -284.328365)
			(xy 369.712788 -284.355014) (xy 369.663174 -284.374486) (xy 369.611212 -284.386346) (xy 369.558062 -284.39033)
			(xy 369.504912 -284.386346) (xy 369.45295 -284.374486) (xy 369.403336 -284.355014) (xy 369.357178 -284.328365)
			(xy 369.315507 -284.295134) (xy 369.279255 -284.256063) (xy 369.249231 -284.212026) (xy 369.226105 -284.164005)
			(xy 369.210395 -284.113075) (xy 369.202452 -284.060371) (xy 368.973872 -284.060371) (xy 368.965929 -284.113075)
			(xy 368.950219 -284.164005) (xy 368.927093 -284.212026) (xy 368.897069 -284.256063) (xy 368.860817 -284.295134)
			(xy 368.819146 -284.328365) (xy 368.772988 -284.355014) (xy 368.723374 -284.374486) (xy 368.671412 -284.386346)
			(xy 368.618262 -284.39033) (xy 368.565112 -284.386346) (xy 368.51315 -284.374486) (xy 368.463536 -284.355014)
			(xy 368.417378 -284.328365) (xy 368.375707 -284.295134) (xy 368.339455 -284.256063) (xy 368.309431 -284.212026)
			(xy 368.286305 -284.164005) (xy 368.270595 -284.113075) (xy 368.262652 -284.060371) (xy 368.034091 -284.060371)
			(xy 368.034089 -284.06046) (xy 368.026089 -284.113333) (xy 368.010272 -284.164416) (xy 367.986995 -284.212559)
			(xy 367.95678 -284.256679) (xy 367.920306 -284.295786) (xy 367.878396 -284.328998) (xy 367.831989 -284.35557)
			(xy 367.80724 -284.3657) (xy 367.774728 -284.3784) (xy 367.774728 -284.847538) (xy 368.732308 -284.847538)
			(xy 368.732806 -284.820889) (xy 368.740749 -284.768185) (xy 368.756459 -284.717255) (xy 368.779585 -284.669234)
			(xy 368.809609 -284.625197) (xy 368.845861 -284.586126) (xy 368.887532 -284.552895) (xy 368.93369 -284.526246)
			(xy 368.983304 -284.506774) (xy 369.035266 -284.494914) (xy 369.088416 -284.490931) (xy 369.141566 -284.494914)
			(xy 369.193528 -284.506774) (xy 369.243142 -284.526246) (xy 369.2893 -284.552895) (xy 369.330971 -284.586126)
			(xy 369.367223 -284.625197) (xy 369.397247 -284.669234) (xy 369.420373 -284.717255) (xy 369.436083 -284.768185)
			(xy 369.444026 -284.820889) (xy 369.444524 -284.847538) (xy 370.611908 -284.847538) (xy 370.612406 -284.820889)
			(xy 370.620349 -284.768185) (xy 370.636059 -284.717255) (xy 370.659185 -284.669234) (xy 370.689209 -284.625197)
			(xy 370.725461 -284.586126) (xy 370.767132 -284.552895) (xy 370.81329 -284.526246) (xy 370.862904 -284.506774)
			(xy 370.914866 -284.494914) (xy 370.968016 -284.490931) (xy 371.021166 -284.494914) (xy 371.073128 -284.506774)
			(xy 371.122742 -284.526246) (xy 371.1689 -284.552895) (xy 371.210571 -284.586126) (xy 371.246823 -284.625197)
			(xy 371.276847 -284.669234) (xy 371.299973 -284.717255) (xy 371.315683 -284.768185) (xy 371.323626 -284.820889)
			(xy 371.324124 -284.847538) (xy 372.491508 -284.847538) (xy 372.492006 -284.820889) (xy 372.499949 -284.768185)
			(xy 372.515659 -284.717255) (xy 372.538785 -284.669234) (xy 372.568809 -284.625197) (xy 372.605061 -284.586126)
			(xy 372.646732 -284.552895) (xy 372.69289 -284.526246) (xy 372.742504 -284.506774) (xy 372.794466 -284.494914)
			(xy 372.847616 -284.490931) (xy 372.900766 -284.494914) (xy 372.952728 -284.506774) (xy 373.002342 -284.526246)
			(xy 373.0485 -284.552895) (xy 373.090171 -284.586126) (xy 373.126423 -284.625197) (xy 373.156447 -284.669234)
			(xy 373.179573 -284.717255) (xy 373.195283 -284.768185) (xy 373.203226 -284.820889) (xy 373.203724 -284.847538)
			(xy 373.203334 -284.870782) (xy 373.202888 -284.874187) (xy 373.431806 -284.874187) (xy 373.431806 -284.820889)
			(xy 373.439749 -284.768185) (xy 373.455459 -284.717255) (xy 373.478585 -284.669234) (xy 373.508609 -284.625197)
			(xy 373.544861 -284.586126) (xy 373.586532 -284.552895) (xy 373.63269 -284.526246) (xy 373.682304 -284.506774)
			(xy 373.734266 -284.494914) (xy 373.787416 -284.490931) (xy 373.840566 -284.494914) (xy 373.892528 -284.506774)
			(xy 373.942142 -284.526246) (xy 373.9883 -284.552895) (xy 374.029971 -284.586126) (xy 374.066223 -284.625197)
			(xy 374.096247 -284.669234) (xy 374.119373 -284.717255) (xy 374.135083 -284.768185) (xy 374.143026 -284.820889)
			(xy 374.143524 -284.847538) (xy 374.371108 -284.847538) (xy 374.371606 -284.820889) (xy 374.379549 -284.768185)
			(xy 374.395259 -284.717255) (xy 374.418385 -284.669234) (xy 374.448409 -284.625197) (xy 374.484661 -284.586126)
			(xy 374.526332 -284.552895) (xy 374.57249 -284.526246) (xy 374.622104 -284.506774) (xy 374.674066 -284.494914)
			(xy 374.727216 -284.490931) (xy 374.780366 -284.494914) (xy 374.832328 -284.506774) (xy 374.881942 -284.526246)
			(xy 374.9281 -284.552895) (xy 374.969771 -284.586126) (xy 375.006023 -284.625197) (xy 375.036047 -284.669234)
			(xy 375.059173 -284.717255) (xy 375.074883 -284.768185) (xy 375.082826 -284.820889) (xy 375.083324 -284.847538)
			(xy 376.250708 -284.847538) (xy 376.251206 -284.820889) (xy 376.259149 -284.768185) (xy 376.274859 -284.717255)
			(xy 376.297985 -284.669234) (xy 376.328009 -284.625197) (xy 376.364261 -284.586126) (xy 376.405932 -284.552895)
			(xy 376.45209 -284.526246) (xy 376.501704 -284.506774) (xy 376.553666 -284.494914) (xy 376.606816 -284.490931)
			(xy 376.659966 -284.494914) (xy 376.711928 -284.506774) (xy 376.761542 -284.526246) (xy 376.8077 -284.552895)
			(xy 376.849371 -284.586126) (xy 376.885623 -284.625197) (xy 376.915647 -284.669234) (xy 376.938773 -284.717255)
			(xy 376.954483 -284.768185) (xy 376.962426 -284.820889) (xy 376.962924 -284.847538) (xy 378.130308 -284.847538)
			(xy 378.130806 -284.820889) (xy 378.138749 -284.768185) (xy 378.154459 -284.717255) (xy 378.177585 -284.669234)
			(xy 378.207609 -284.625197) (xy 378.243861 -284.586126) (xy 378.285532 -284.552895) (xy 378.33169 -284.526246)
			(xy 378.381304 -284.506774) (xy 378.433266 -284.494914) (xy 378.486416 -284.490931) (xy 378.539566 -284.494914)
			(xy 378.591528 -284.506774) (xy 378.641142 -284.526246) (xy 378.6873 -284.552895) (xy 378.728971 -284.586126)
			(xy 378.765223 -284.625197) (xy 378.795247 -284.669234) (xy 378.818373 -284.717255) (xy 378.834083 -284.768185)
			(xy 378.842026 -284.820889) (xy 378.842524 -284.847538) (xy 380.009908 -284.847538) (xy 380.010406 -284.820889)
			(xy 380.018349 -284.768185) (xy 380.034059 -284.717255) (xy 380.057185 -284.669234) (xy 380.087209 -284.625197)
			(xy 380.123461 -284.586126) (xy 380.165132 -284.552895) (xy 380.21129 -284.526246) (xy 380.260904 -284.506774)
			(xy 380.312866 -284.494914) (xy 380.366016 -284.490931) (xy 380.419166 -284.494914) (xy 380.471128 -284.506774)
			(xy 380.520742 -284.526246) (xy 380.5669 -284.552895) (xy 380.608571 -284.586126) (xy 380.644823 -284.625197)
			(xy 380.674847 -284.669234) (xy 380.697973 -284.717255) (xy 380.713683 -284.768185) (xy 380.721626 -284.820889)
			(xy 380.722124 -284.847538) (xy 380.721734 -284.870782) (xy 380.721288 -284.874187) (xy 381.890006 -284.874187)
			(xy 381.890006 -284.820889) (xy 381.897949 -284.768185) (xy 381.913659 -284.717255) (xy 381.936785 -284.669234)
			(xy 381.966809 -284.625197) (xy 382.003061 -284.586126) (xy 382.044732 -284.552895) (xy 382.09089 -284.526246)
			(xy 382.140504 -284.506774) (xy 382.192466 -284.494914) (xy 382.245616 -284.490931) (xy 382.298766 -284.494914)
			(xy 382.350728 -284.506774) (xy 382.400342 -284.526246) (xy 382.4465 -284.552895) (xy 382.488171 -284.586126)
			(xy 382.524423 -284.625197) (xy 382.554447 -284.669234) (xy 382.577573 -284.717255) (xy 382.593283 -284.768185)
			(xy 382.601226 -284.820889) (xy 382.601724 -284.847538) (xy 382.601231 -284.873933) (xy 382.829552 -284.873933)
			(xy 382.829552 -284.820635) (xy 382.837495 -284.767931) (xy 382.853205 -284.717001) (xy 382.876331 -284.66898)
			(xy 382.906355 -284.624943) (xy 382.942607 -284.585872) (xy 382.984278 -284.552641) (xy 383.030436 -284.525992)
			(xy 383.08005 -284.50652) (xy 383.132012 -284.49466) (xy 383.185162 -284.490677) (xy 383.238312 -284.49466)
			(xy 383.290274 -284.50652) (xy 383.339888 -284.525992) (xy 383.386046 -284.552641) (xy 383.427717 -284.585872)
			(xy 383.463969 -284.624943) (xy 383.493993 -284.66898) (xy 383.517119 -284.717001) (xy 383.532829 -284.767931)
			(xy 383.540772 -284.820635) (xy 383.54127 -284.847284) (xy 383.540772 -284.873933) (xy 383.769352 -284.873933)
			(xy 383.769352 -284.820635) (xy 383.777295 -284.767931) (xy 383.793005 -284.717001) (xy 383.816131 -284.66898)
			(xy 383.846155 -284.624943) (xy 383.882407 -284.585872) (xy 383.924078 -284.552641) (xy 383.970236 -284.525992)
			(xy 384.01985 -284.50652) (xy 384.071812 -284.49466) (xy 384.124962 -284.490677) (xy 384.178112 -284.49466)
			(xy 384.230074 -284.50652) (xy 384.279688 -284.525992) (xy 384.325846 -284.552641) (xy 384.367517 -284.585872)
			(xy 384.403769 -284.624943) (xy 384.433793 -284.66898) (xy 384.456919 -284.717001) (xy 384.472629 -284.767931)
			(xy 384.480572 -284.820635) (xy 384.48107 -284.847284) (xy 384.480572 -284.873933) (xy 384.709152 -284.873933)
			(xy 384.709152 -284.820635) (xy 384.717095 -284.767931) (xy 384.732805 -284.717001) (xy 384.755931 -284.66898)
			(xy 384.785955 -284.624943) (xy 384.822207 -284.585872) (xy 384.863878 -284.552641) (xy 384.910036 -284.525992)
			(xy 384.95965 -284.50652) (xy 385.011612 -284.49466) (xy 385.064762 -284.490677) (xy 385.117912 -284.49466)
			(xy 385.169874 -284.50652) (xy 385.219488 -284.525992) (xy 385.265646 -284.552641) (xy 385.307317 -284.585872)
			(xy 385.343569 -284.624943) (xy 385.373593 -284.66898) (xy 385.396719 -284.717001) (xy 385.412429 -284.767931)
			(xy 385.420372 -284.820635) (xy 385.42087 -284.847284) (xy 385.420372 -284.873933) (xy 385.412429 -284.926637)
			(xy 385.396719 -284.977567) (xy 385.373593 -285.025588) (xy 385.343569 -285.069625) (xy 385.307317 -285.108696)
			(xy 385.265646 -285.141927) (xy 385.219488 -285.168576) (xy 385.169874 -285.188048) (xy 385.117912 -285.199908)
			(xy 385.064762 -285.203892) (xy 385.011612 -285.199908) (xy 384.95965 -285.188048) (xy 384.910036 -285.168576)
			(xy 384.863878 -285.141927) (xy 384.822207 -285.108696) (xy 384.785955 -285.069625) (xy 384.755931 -285.025588)
			(xy 384.732805 -284.977567) (xy 384.717095 -284.926637) (xy 384.709152 -284.873933) (xy 384.480572 -284.873933)
			(xy 384.472629 -284.926637) (xy 384.456919 -284.977567) (xy 384.433793 -285.025588) (xy 384.403769 -285.069625)
			(xy 384.367517 -285.108696) (xy 384.325846 -285.141927) (xy 384.279688 -285.168576) (xy 384.230074 -285.188048)
			(xy 384.178112 -285.199908) (xy 384.124962 -285.203892) (xy 384.071812 -285.199908) (xy 384.01985 -285.188048)
			(xy 383.970236 -285.168576) (xy 383.924078 -285.141927) (xy 383.882407 -285.108696) (xy 383.846155 -285.069625)
			(xy 383.816131 -285.025588) (xy 383.793005 -284.977567) (xy 383.777295 -284.926637) (xy 383.769352 -284.873933)
			(xy 383.540772 -284.873933) (xy 383.532829 -284.926637) (xy 383.517119 -284.977567) (xy 383.493993 -285.025588)
			(xy 383.463969 -285.069625) (xy 383.427717 -285.108696) (xy 383.386046 -285.141927) (xy 383.339888 -285.168576)
			(xy 383.290274 -285.188048) (xy 383.238312 -285.199908) (xy 383.185162 -285.203892) (xy 383.132012 -285.199908)
			(xy 383.08005 -285.188048) (xy 383.030436 -285.168576) (xy 382.984278 -285.141927) (xy 382.942607 -285.108696)
			(xy 382.906355 -285.069625) (xy 382.876331 -285.025588) (xy 382.853205 -284.977567) (xy 382.837495 -284.926637)
			(xy 382.829552 -284.873933) (xy 382.601231 -284.873933) (xy 382.601226 -284.874187) (xy 382.593283 -284.926891)
			(xy 382.577573 -284.977821) (xy 382.554447 -285.025842) (xy 382.524423 -285.069879) (xy 382.488171 -285.10895)
			(xy 382.4465 -285.142181) (xy 382.400342 -285.16883) (xy 382.350728 -285.188302) (xy 382.298766 -285.200162)
			(xy 382.245616 -285.204146) (xy 382.192466 -285.200162) (xy 382.140504 -285.188302) (xy 382.09089 -285.16883)
			(xy 382.044732 -285.142181) (xy 382.003061 -285.10895) (xy 381.966809 -285.069879) (xy 381.936785 -285.025842)
			(xy 381.913659 -284.977821) (xy 381.897949 -284.926891) (xy 381.890006 -284.874187) (xy 380.721288 -284.874187)
			(xy 380.715696 -284.916877) (xy 380.703714 -284.961796) (xy 380.6952 -284.983428) (xy 380.685548 -285.006542)
			(xy 380.858014 -285.304992) (xy 380.882652 -285.308294) (xy 380.907998 -285.312098) (xy 380.957304 -285.326091)
			(xy 381.004095 -285.347006) (xy 381.047407 -285.37441) (xy 381.086345 -285.407737) (xy 381.120105 -285.4463)
			(xy 381.147991 -285.489303) (xy 381.169427 -285.535858) (xy 381.183971 -285.585004) (xy 381.191322 -285.635728)
			(xy 381.19177 -285.661354) (xy 381.191272 -285.688003) (xy 381.183329 -285.740707) (xy 381.167619 -285.791637)
			(xy 381.144493 -285.839658) (xy 381.114469 -285.883695) (xy 381.078217 -285.922766) (xy 381.036546 -285.955997)
			(xy 380.990388 -285.982646) (xy 380.940774 -286.002118) (xy 380.888812 -286.013978) (xy 380.835662 -286.017962)
			(xy 380.782512 -286.013978) (xy 380.73055 -286.002118) (xy 380.680936 -285.982646) (xy 380.634778 -285.955997)
			(xy 380.593107 -285.922766) (xy 380.556855 -285.883695) (xy 380.526831 -285.839658) (xy 380.503705 -285.791637)
			(xy 380.487995 -285.740707) (xy 380.480052 -285.688003) (xy 380.479554 -285.661354) (xy 380.479943 -285.63811)
			(xy 380.485982 -285.592015) (xy 380.497964 -285.547096) (xy 380.506478 -285.525464) (xy 380.51613 -285.50235)
			(xy 380.343664 -285.2039) (xy 380.319026 -285.200598) (xy 380.293688 -285.196741) (xy 380.244383 -285.182757)
			(xy 380.19759 -285.161852) (xy 380.154277 -285.134455) (xy 380.115337 -285.101134) (xy 380.081575 -285.062577)
			(xy 380.053688 -285.019578) (xy 380.032251 -284.973027) (xy 380.017707 -284.923883) (xy 380.010356 -284.873163)
			(xy 380.009908 -284.847538) (xy 378.842524 -284.847538) (xy 378.842134 -284.870782) (xy 378.836096 -284.916877)
			(xy 378.824114 -284.961796) (xy 378.8156 -284.983428) (xy 378.805948 -285.006542) (xy 378.978414 -285.304992)
			(xy 379.003052 -285.308294) (xy 379.028398 -285.312098) (xy 379.077704 -285.326091) (xy 379.124495 -285.347006)
			(xy 379.167807 -285.37441) (xy 379.206745 -285.407737) (xy 379.240505 -285.4463) (xy 379.268391 -285.489303)
			(xy 379.289827 -285.535858) (xy 379.304371 -285.585004) (xy 379.311722 -285.635728) (xy 379.31217 -285.661354)
			(xy 379.311672 -285.688003) (xy 379.303729 -285.740707) (xy 379.288019 -285.791637) (xy 379.264893 -285.839658)
			(xy 379.234869 -285.883695) (xy 379.198617 -285.922766) (xy 379.156946 -285.955997) (xy 379.110788 -285.982646)
			(xy 379.061174 -286.002118) (xy 379.009212 -286.013978) (xy 378.956062 -286.017962) (xy 378.902912 -286.013978)
			(xy 378.85095 -286.002118) (xy 378.801336 -285.982646) (xy 378.755178 -285.955997) (xy 378.713507 -285.922766)
			(xy 378.677255 -285.883695) (xy 378.647231 -285.839658) (xy 378.624105 -285.791637) (xy 378.608395 -285.740707)
			(xy 378.600452 -285.688003) (xy 378.599954 -285.661354) (xy 378.600343 -285.63811) (xy 378.606382 -285.592015)
			(xy 378.618364 -285.547096) (xy 378.626878 -285.525464) (xy 378.63653 -285.50235) (xy 378.464064 -285.2039)
			(xy 378.439426 -285.200598) (xy 378.414088 -285.196741) (xy 378.364783 -285.182757) (xy 378.31799 -285.161852)
			(xy 378.274677 -285.134455) (xy 378.235737 -285.101134) (xy 378.201975 -285.062577) (xy 378.174088 -285.019578)
			(xy 378.152651 -284.973027) (xy 378.138107 -284.923883) (xy 378.130756 -284.873163) (xy 378.130308 -284.847538)
			(xy 376.962924 -284.847538) (xy 376.962534 -284.870782) (xy 376.956496 -284.916877) (xy 376.944514 -284.961796)
			(xy 376.936 -284.983428) (xy 376.926348 -285.006542) (xy 377.098814 -285.304992) (xy 377.123452 -285.308294)
			(xy 377.148798 -285.312098) (xy 377.198104 -285.326091) (xy 377.244895 -285.347006) (xy 377.288207 -285.37441)
			(xy 377.327145 -285.407737) (xy 377.360905 -285.4463) (xy 377.388791 -285.489303) (xy 377.410227 -285.535858)
			(xy 377.424771 -285.585004) (xy 377.432122 -285.635728) (xy 377.43257 -285.661354) (xy 377.432072 -285.688003)
			(xy 377.424129 -285.740707) (xy 377.408419 -285.791637) (xy 377.385293 -285.839658) (xy 377.355269 -285.883695)
			(xy 377.319017 -285.922766) (xy 377.277346 -285.955997) (xy 377.231188 -285.982646) (xy 377.181574 -286.002118)
			(xy 377.129612 -286.013978) (xy 377.076462 -286.017962) (xy 377.023312 -286.013978) (xy 376.97135 -286.002118)
			(xy 376.921736 -285.982646) (xy 376.875578 -285.955997) (xy 376.833907 -285.922766) (xy 376.797655 -285.883695)
			(xy 376.767631 -285.839658) (xy 376.744505 -285.791637) (xy 376.728795 -285.740707) (xy 376.720852 -285.688003)
			(xy 376.720354 -285.661354) (xy 376.720743 -285.63811) (xy 376.726782 -285.592015) (xy 376.738764 -285.547096)
			(xy 376.747278 -285.525464) (xy 376.75693 -285.50235) (xy 376.584464 -285.2039) (xy 376.559826 -285.200598)
			(xy 376.534488 -285.196741) (xy 376.485183 -285.182757) (xy 376.43839 -285.161852) (xy 376.395077 -285.134455)
			(xy 376.356137 -285.101134) (xy 376.322375 -285.062577) (xy 376.294488 -285.019578) (xy 376.273051 -284.973027)
			(xy 376.258507 -284.923883) (xy 376.251156 -284.873163) (xy 376.250708 -284.847538) (xy 375.083324 -284.847538)
			(xy 375.082934 -284.870782) (xy 375.076896 -284.916877) (xy 375.064914 -284.961796) (xy 375.0564 -284.983428)
			(xy 375.046748 -285.006542) (xy 375.219214 -285.304992) (xy 375.243852 -285.308294) (xy 375.269198 -285.312098)
			(xy 375.318504 -285.326091) (xy 375.365295 -285.347006) (xy 375.408607 -285.37441) (xy 375.447545 -285.407737)
			(xy 375.481305 -285.4463) (xy 375.509191 -285.489303) (xy 375.530627 -285.535858) (xy 375.545171 -285.585004)
			(xy 375.552522 -285.635728) (xy 375.55297 -285.661354) (xy 375.552472 -285.688003) (xy 375.544529 -285.740707)
			(xy 375.528819 -285.791637) (xy 375.505693 -285.839658) (xy 375.475669 -285.883695) (xy 375.439417 -285.922766)
			(xy 375.397746 -285.955997) (xy 375.351588 -285.982646) (xy 375.301974 -286.002118) (xy 375.250012 -286.013978)
			(xy 375.196862 -286.017962) (xy 375.143712 -286.013978) (xy 375.09175 -286.002118) (xy 375.042136 -285.982646)
			(xy 374.995978 -285.955997) (xy 374.954307 -285.922766) (xy 374.918055 -285.883695) (xy 374.888031 -285.839658)
			(xy 374.864905 -285.791637) (xy 374.849195 -285.740707) (xy 374.841252 -285.688003) (xy 374.840754 -285.661354)
			(xy 374.841143 -285.63811) (xy 374.847182 -285.592015) (xy 374.859164 -285.547096) (xy 374.867678 -285.525464)
			(xy 374.87733 -285.50235) (xy 374.704864 -285.2039) (xy 374.680226 -285.200598) (xy 374.654888 -285.196741)
			(xy 374.605583 -285.182757) (xy 374.55879 -285.161852) (xy 374.515477 -285.134455) (xy 374.476537 -285.101134)
			(xy 374.442775 -285.062577) (xy 374.414888 -285.019578) (xy 374.393451 -284.973027) (xy 374.378907 -284.923883)
			(xy 374.371556 -284.873163) (xy 374.371108 -284.847538) (xy 374.143524 -284.847538) (xy 374.143026 -284.874187)
			(xy 374.135083 -284.926891) (xy 374.119373 -284.977821) (xy 374.096247 -285.025842) (xy 374.066223 -285.069879)
			(xy 374.029971 -285.10895) (xy 373.9883 -285.142181) (xy 373.942142 -285.16883) (xy 373.892528 -285.188302)
			(xy 373.840566 -285.200162) (xy 373.787416 -285.204146) (xy 373.734266 -285.200162) (xy 373.682304 -285.188302)
			(xy 373.63269 -285.16883) (xy 373.586532 -285.142181) (xy 373.544861 -285.10895) (xy 373.508609 -285.069879)
			(xy 373.478585 -285.025842) (xy 373.455459 -284.977821) (xy 373.439749 -284.926891) (xy 373.431806 -284.874187)
			(xy 373.202888 -284.874187) (xy 373.197296 -284.916877) (xy 373.185314 -284.961796) (xy 373.1768 -284.983428)
			(xy 373.167148 -285.006542) (xy 373.339614 -285.304992) (xy 373.364252 -285.308294) (xy 373.389598 -285.312098)
			(xy 373.438904 -285.326091) (xy 373.485695 -285.347006) (xy 373.529007 -285.37441) (xy 373.567945 -285.407737)
			(xy 373.601705 -285.4463) (xy 373.629591 -285.489303) (xy 373.651027 -285.535858) (xy 373.665571 -285.585004)
			(xy 373.672922 -285.635728) (xy 373.67337 -285.661354) (xy 373.672872 -285.688003) (xy 373.664929 -285.740707)
			(xy 373.649219 -285.791637) (xy 373.626093 -285.839658) (xy 373.596069 -285.883695) (xy 373.559817 -285.922766)
			(xy 373.518146 -285.955997) (xy 373.471988 -285.982646) (xy 373.422374 -286.002118) (xy 373.370412 -286.013978)
			(xy 373.317262 -286.017962) (xy 373.264112 -286.013978) (xy 373.21215 -286.002118) (xy 373.162536 -285.982646)
			(xy 373.116378 -285.955997) (xy 373.074707 -285.922766) (xy 373.038455 -285.883695) (xy 373.008431 -285.839658)
			(xy 372.985305 -285.791637) (xy 372.969595 -285.740707) (xy 372.961652 -285.688003) (xy 372.961154 -285.661354)
			(xy 372.961543 -285.63811) (xy 372.967582 -285.592015) (xy 372.979564 -285.547096) (xy 372.988078 -285.525464)
			(xy 372.99773 -285.50235) (xy 372.825264 -285.2039) (xy 372.800626 -285.200598) (xy 372.775288 -285.196741)
			(xy 372.725983 -285.182757) (xy 372.67919 -285.161852) (xy 372.635877 -285.134455) (xy 372.596937 -285.101134)
			(xy 372.563175 -285.062577) (xy 372.535288 -285.019578) (xy 372.513851 -284.973027) (xy 372.499307 -284.923883)
			(xy 372.491956 -284.873163) (xy 372.491508 -284.847538) (xy 371.324124 -284.847538) (xy 371.323734 -284.870782)
			(xy 371.317696 -284.916877) (xy 371.305714 -284.961796) (xy 371.2972 -284.983428) (xy 371.287548 -285.006542)
			(xy 371.460014 -285.304992) (xy 371.484652 -285.308294) (xy 371.509998 -285.312098) (xy 371.559304 -285.326091)
			(xy 371.606095 -285.347006) (xy 371.649407 -285.37441) (xy 371.688345 -285.407737) (xy 371.722105 -285.4463)
			(xy 371.749991 -285.489303) (xy 371.771427 -285.535858) (xy 371.785971 -285.585004) (xy 371.793322 -285.635728)
			(xy 371.79377 -285.661354) (xy 371.793272 -285.688003) (xy 371.785329 -285.740707) (xy 371.769619 -285.791637)
			(xy 371.746493 -285.839658) (xy 371.716469 -285.883695) (xy 371.680217 -285.922766) (xy 371.638546 -285.955997)
			(xy 371.592388 -285.982646) (xy 371.542774 -286.002118) (xy 371.490812 -286.013978) (xy 371.437662 -286.017962)
			(xy 371.384512 -286.013978) (xy 371.33255 -286.002118) (xy 371.282936 -285.982646) (xy 371.236778 -285.955997)
			(xy 371.195107 -285.922766) (xy 371.158855 -285.883695) (xy 371.128831 -285.839658) (xy 371.105705 -285.791637)
			(xy 371.089995 -285.740707) (xy 371.082052 -285.688003) (xy 371.081554 -285.661354) (xy 371.081943 -285.63811)
			(xy 371.087982 -285.592015) (xy 371.099964 -285.547096) (xy 371.108478 -285.525464) (xy 371.11813 -285.50235)
			(xy 370.945664 -285.2039) (xy 370.921026 -285.200598) (xy 370.895688 -285.196741) (xy 370.846383 -285.182757)
			(xy 370.79959 -285.161852) (xy 370.756277 -285.134455) (xy 370.717337 -285.101134) (xy 370.683575 -285.062577)
			(xy 370.655688 -285.019578) (xy 370.634251 -284.973027) (xy 370.619707 -284.923883) (xy 370.612356 -284.873163)
			(xy 370.611908 -284.847538) (xy 369.444524 -284.847538) (xy 369.444134 -284.870782) (xy 369.438096 -284.916877)
			(xy 369.426114 -284.961796) (xy 369.4176 -284.983428) (xy 369.407948 -285.006542) (xy 369.580414 -285.304992)
			(xy 369.605052 -285.308294) (xy 369.630398 -285.312098) (xy 369.679704 -285.326091) (xy 369.726495 -285.347006)
			(xy 369.769807 -285.37441) (xy 369.808745 -285.407737) (xy 369.842505 -285.4463) (xy 369.870391 -285.489303)
			(xy 369.891827 -285.535858) (xy 369.906371 -285.585004) (xy 369.913722 -285.635728) (xy 369.91417 -285.661354)
			(xy 369.913672 -285.688003) (xy 369.905729 -285.740707) (xy 369.890019 -285.791637) (xy 369.866893 -285.839658)
			(xy 369.836869 -285.883695) (xy 369.800617 -285.922766) (xy 369.758946 -285.955997) (xy 369.712788 -285.982646)
			(xy 369.663174 -286.002118) (xy 369.611212 -286.013978) (xy 369.558062 -286.017962) (xy 369.504912 -286.013978)
			(xy 369.45295 -286.002118) (xy 369.403336 -285.982646) (xy 369.357178 -285.955997) (xy 369.315507 -285.922766)
			(xy 369.279255 -285.883695) (xy 369.249231 -285.839658) (xy 369.226105 -285.791637) (xy 369.210395 -285.740707)
			(xy 369.202452 -285.688003) (xy 369.201954 -285.661354) (xy 369.202343 -285.63811) (xy 369.208382 -285.592015)
			(xy 369.220364 -285.547096) (xy 369.228878 -285.525464) (xy 369.23853 -285.50235) (xy 369.066064 -285.2039)
			(xy 369.041426 -285.200598) (xy 369.016088 -285.196741) (xy 368.966783 -285.182757) (xy 368.91999 -285.161852)
			(xy 368.876677 -285.134455) (xy 368.837737 -285.101134) (xy 368.803975 -285.062577) (xy 368.776088 -285.019578)
			(xy 368.754651 -284.973027) (xy 368.740107 -284.923883) (xy 368.732756 -284.873163) (xy 368.732308 -284.847538)
			(xy 367.774728 -284.847538) (xy 367.774728 -285.316676) (xy 367.80724 -285.329376) (xy 367.831999 -285.339491)
			(xy 367.878413 -285.366066) (xy 367.92033 -285.399282) (xy 367.956809 -285.438394) (xy 367.987028 -285.482521)
			(xy 368.010309 -285.530671) (xy 368.026128 -285.581761) (xy 368.034128 -285.634642) (xy 368.034131 -285.688125)
			(xy 368.026135 -285.741007) (xy 368.010321 -285.792098) (xy 367.987045 -285.84025) (xy 367.95683 -285.88438)
			(xy 367.920354 -285.923495) (xy 367.87844 -285.956716) (xy 367.832029 -285.983295) (xy 367.80724 -285.993332)
			(xy 367.774728 -286.006032) (xy 367.774728 -286.107632) (xy 367.775169 -286.121681) (xy 367.782818 -286.148717)
			(xy 367.797553 -286.172641) (xy 367.818256 -286.191636) (xy 367.843357 -286.204261) (xy 367.870951 -286.209558)
			(xy 367.898942 -286.207126) (xy 367.925208 -286.197148) (xy 367.93678 -286.189166) (xy 367.961247 -286.17183)
			(xy 368.014731 -286.144727) (xy 368.071991 -286.126938) (xy 368.101626 -286.122364) (xy 368.126264 -286.119062)
			(xy 368.29873 -285.820358) (xy 368.289078 -285.797244) (xy 368.280564 -285.775612) (xy 368.268581 -285.730694)
			(xy 368.262541 -285.684599) (xy 368.262154 -285.661354) (xy 368.262652 -285.634705) (xy 368.270595 -285.582001)
			(xy 368.286305 -285.531071) (xy 368.309431 -285.48305) (xy 368.339455 -285.439013) (xy 368.375707 -285.399942)
			(xy 368.417378 -285.366711) (xy 368.463536 -285.340062) (xy 368.51315 -285.32059) (xy 368.565112 -285.30873)
			(xy 368.618262 -285.304747) (xy 368.671412 -285.30873) (xy 368.723374 -285.32059) (xy 368.772988 -285.340062)
			(xy 368.819146 -285.366711) (xy 368.860817 -285.399942) (xy 368.897069 -285.439013) (xy 368.927093 -285.48305)
			(xy 368.950219 -285.531071) (xy 368.965929 -285.582001) (xy 368.973872 -285.634705) (xy 368.97437 -285.661354)
			(xy 368.973921 -285.68698) (xy 368.966569 -285.737702) (xy 368.952025 -285.786848) (xy 368.930588 -285.833402)
			(xy 368.902702 -285.876404) (xy 368.868942 -285.914966) (xy 368.830004 -285.948292) (xy 368.786693 -285.975695)
			(xy 368.739902 -285.996609) (xy 368.690597 -286.010603) (xy 368.665252 -286.014414) (xy 368.640614 -286.017716)
			(xy 368.468148 -286.31642) (xy 368.4778 -286.339534) (xy 368.486316 -286.361166) (xy 368.498303 -286.406084)
			(xy 368.504346 -286.452179) (xy 368.504724 -286.475424) (xy 368.504226 -286.502073) (xy 368.732552 -286.502073)
			(xy 368.732552 -286.448775) (xy 368.740495 -286.396071) (xy 368.756205 -286.345141) (xy 368.779331 -286.29712)
			(xy 368.809355 -286.253083) (xy 368.845607 -286.214012) (xy 368.887278 -286.180781) (xy 368.933436 -286.154132)
			(xy 368.98305 -286.13466) (xy 369.035012 -286.1228) (xy 369.088162 -286.118817) (xy 369.141312 -286.1228)
			(xy 369.193274 -286.13466) (xy 369.242888 -286.154132) (xy 369.289046 -286.180781) (xy 369.330717 -286.214012)
			(xy 369.366969 -286.253083) (xy 369.396993 -286.29712) (xy 369.420119 -286.345141) (xy 369.435829 -286.396071)
			(xy 369.443772 -286.448775) (xy 369.44427 -286.475424) (xy 369.672108 -286.475424) (xy 369.672589 -286.449797)
			(xy 369.67992 -286.399071) (xy 369.69445 -286.34992) (xy 369.715876 -286.30336) (xy 369.743757 -286.260354)
			(xy 369.777517 -286.221789) (xy 369.816458 -286.188464) (xy 369.859774 -286.161067) (xy 369.906571 -286.140164)
			(xy 369.955882 -286.126187) (xy 369.981226 -286.122364) (xy 370.005864 -286.119062) (xy 370.17833 -285.820358)
			(xy 370.168678 -285.797244) (xy 370.160146 -285.775618) (xy 370.148165 -285.730697) (xy 370.142126 -285.6846)
			(xy 370.141754 -285.661354) (xy 370.142252 -285.634705) (xy 370.150195 -285.582001) (xy 370.165905 -285.531071)
			(xy 370.189031 -285.48305) (xy 370.219055 -285.439013) (xy 370.255307 -285.399942) (xy 370.296978 -285.366711)
			(xy 370.343136 -285.340062) (xy 370.39275 -285.32059) (xy 370.444712 -285.30873) (xy 370.497862 -285.304747)
			(xy 370.551012 -285.30873) (xy 370.602974 -285.32059) (xy 370.652588 -285.340062) (xy 370.698746 -285.366711)
			(xy 370.740417 -285.399942) (xy 370.776669 -285.439013) (xy 370.806693 -285.48305) (xy 370.829819 -285.531071)
			(xy 370.845529 -285.582001) (xy 370.853472 -285.634705) (xy 370.85397 -285.661354) (xy 370.853488 -285.686981)
			(xy 370.846159 -285.737708) (xy 370.831631 -285.786861) (xy 370.810206 -285.833421) (xy 370.782325 -285.876429)
			(xy 370.748565 -285.914993) (xy 370.709624 -285.948319) (xy 370.666307 -285.975715) (xy 370.619508 -285.996617)
			(xy 370.570196 -286.010592) (xy 370.544852 -286.014414) (xy 370.520214 -286.017716) (xy 370.347748 -286.31642)
			(xy 370.3574 -286.339534) (xy 370.365925 -286.361163) (xy 370.377908 -286.406082) (xy 370.38395 -286.452179)
			(xy 370.384324 -286.475424) (xy 370.383826 -286.502073) (xy 370.612152 -286.502073) (xy 370.612152 -286.448775)
			(xy 370.620095 -286.396071) (xy 370.635805 -286.345141) (xy 370.658931 -286.29712) (xy 370.688955 -286.253083)
			(xy 370.725207 -286.214012) (xy 370.766878 -286.180781) (xy 370.813036 -286.154132) (xy 370.86265 -286.13466)
			(xy 370.914612 -286.1228) (xy 370.967762 -286.118817) (xy 371.020912 -286.1228) (xy 371.072874 -286.13466)
			(xy 371.122488 -286.154132) (xy 371.168646 -286.180781) (xy 371.210317 -286.214012) (xy 371.246569 -286.253083)
			(xy 371.276593 -286.29712) (xy 371.299719 -286.345141) (xy 371.315429 -286.396071) (xy 371.323372 -286.448775)
			(xy 371.32387 -286.475424) (xy 371.551708 -286.475424) (xy 371.552189 -286.449797) (xy 371.55952 -286.399071)
			(xy 371.57405 -286.34992) (xy 371.595476 -286.30336) (xy 371.623357 -286.260354) (xy 371.657117 -286.221789)
			(xy 371.696058 -286.188464) (xy 371.739374 -286.161067) (xy 371.786171 -286.140164) (xy 371.835482 -286.126187)
			(xy 371.860826 -286.122364) (xy 371.885464 -286.119062) (xy 372.05793 -285.820358) (xy 372.048278 -285.797244)
			(xy 372.039746 -285.775618) (xy 372.027765 -285.730697) (xy 372.021726 -285.6846) (xy 372.021354 -285.661354)
			(xy 372.021852 -285.634705) (xy 372.029795 -285.582001) (xy 372.045505 -285.531071) (xy 372.068631 -285.48305)
			(xy 372.098655 -285.439013) (xy 372.134907 -285.399942) (xy 372.176578 -285.366711) (xy 372.222736 -285.340062)
			(xy 372.27235 -285.32059) (xy 372.324312 -285.30873) (xy 372.377462 -285.304747) (xy 372.430612 -285.30873)
			(xy 372.482574 -285.32059) (xy 372.532188 -285.340062) (xy 372.578346 -285.366711) (xy 372.620017 -285.399942)
			(xy 372.656269 -285.439013) (xy 372.686293 -285.48305) (xy 372.709419 -285.531071) (xy 372.725129 -285.582001)
			(xy 372.733072 -285.634705) (xy 372.73357 -285.661354) (xy 372.733088 -285.686981) (xy 372.725759 -285.737708)
			(xy 372.711231 -285.786861) (xy 372.689806 -285.833421) (xy 372.661925 -285.876429) (xy 372.628165 -285.914993)
			(xy 372.589224 -285.948319) (xy 372.545907 -285.975715) (xy 372.499108 -285.996617) (xy 372.449796 -286.010592)
			(xy 372.424452 -286.014414) (xy 372.399814 -286.017716) (xy 372.227348 -286.31642) (xy 372.237 -286.339534)
			(xy 372.245525 -286.361163) (xy 372.257508 -286.406082) (xy 372.26355 -286.452179) (xy 372.263924 -286.475424)
			(xy 372.263426 -286.502073) (xy 372.491752 -286.502073) (xy 372.491752 -286.448775) (xy 372.499695 -286.396071)
			(xy 372.515405 -286.345141) (xy 372.538531 -286.29712) (xy 372.568555 -286.253083) (xy 372.604807 -286.214012)
			(xy 372.646478 -286.180781) (xy 372.692636 -286.154132) (xy 372.74225 -286.13466) (xy 372.794212 -286.1228)
			(xy 372.847362 -286.118817) (xy 372.900512 -286.1228) (xy 372.952474 -286.13466) (xy 373.002088 -286.154132)
			(xy 373.048246 -286.180781) (xy 373.089917 -286.214012) (xy 373.126169 -286.253083) (xy 373.156193 -286.29712)
			(xy 373.179319 -286.345141) (xy 373.195029 -286.396071) (xy 373.202972 -286.448775) (xy 373.20347 -286.475424)
			(xy 373.431308 -286.475424) (xy 373.431789 -286.449797) (xy 373.43912 -286.399071) (xy 373.45365 -286.34992)
			(xy 373.475076 -286.30336) (xy 373.502957 -286.260354) (xy 373.536717 -286.221789) (xy 373.575658 -286.188464)
			(xy 373.618974 -286.161067) (xy 373.665771 -286.140164) (xy 373.715082 -286.126187) (xy 373.740426 -286.122364)
			(xy 373.765064 -286.119062) (xy 373.93753 -285.820358) (xy 373.927878 -285.797244) (xy 373.919346 -285.775618)
			(xy 373.907365 -285.730697) (xy 373.901326 -285.6846) (xy 373.900954 -285.661354) (xy 373.901452 -285.634705)
			(xy 373.909395 -285.582001) (xy 373.925105 -285.531071) (xy 373.948231 -285.48305) (xy 373.978255 -285.439013)
			(xy 374.014507 -285.399942) (xy 374.056178 -285.366711) (xy 374.102336 -285.340062) (xy 374.15195 -285.32059)
			(xy 374.203912 -285.30873) (xy 374.257062 -285.304747) (xy 374.310212 -285.30873) (xy 374.362174 -285.32059)
			(xy 374.411788 -285.340062) (xy 374.457946 -285.366711) (xy 374.499617 -285.399942) (xy 374.535869 -285.439013)
			(xy 374.565893 -285.48305) (xy 374.589019 -285.531071) (xy 374.604729 -285.582001) (xy 374.612672 -285.634705)
			(xy 374.61317 -285.661354) (xy 374.612688 -285.686981) (xy 374.605359 -285.737708) (xy 374.590831 -285.786861)
			(xy 374.569406 -285.833421) (xy 374.541525 -285.876429) (xy 374.507765 -285.914993) (xy 374.468824 -285.948319)
			(xy 374.425507 -285.975715) (xy 374.378708 -285.996617) (xy 374.329396 -286.010592) (xy 374.304052 -286.014414)
			(xy 374.279414 -286.017716) (xy 374.106948 -286.31642) (xy 374.1166 -286.339534) (xy 374.125125 -286.361163)
			(xy 374.137108 -286.406082) (xy 374.14315 -286.452179) (xy 374.143524 -286.475424) (xy 374.143026 -286.502073)
			(xy 374.371352 -286.502073) (xy 374.371352 -286.448775) (xy 374.379295 -286.396071) (xy 374.395005 -286.345141)
			(xy 374.418131 -286.29712) (xy 374.448155 -286.253083) (xy 374.484407 -286.214012) (xy 374.526078 -286.180781)
			(xy 374.572236 -286.154132) (xy 374.62185 -286.13466) (xy 374.673812 -286.1228) (xy 374.726962 -286.118817)
			(xy 374.780112 -286.1228) (xy 374.832074 -286.13466) (xy 374.881688 -286.154132) (xy 374.927846 -286.180781)
			(xy 374.969517 -286.214012) (xy 375.005769 -286.253083) (xy 375.035793 -286.29712) (xy 375.058919 -286.345141)
			(xy 375.074629 -286.396071) (xy 375.082572 -286.448775) (xy 375.08307 -286.475424) (xy 375.310908 -286.475424)
			(xy 375.311389 -286.449797) (xy 375.31872 -286.399071) (xy 375.33325 -286.34992) (xy 375.354676 -286.30336)
			(xy 375.382557 -286.260354) (xy 375.416317 -286.221789) (xy 375.455258 -286.188464) (xy 375.498574 -286.161067)
			(xy 375.545371 -286.140164) (xy 375.594682 -286.126187) (xy 375.620026 -286.122364) (xy 375.644664 -286.119062)
			(xy 375.81713 -285.820358) (xy 375.807478 -285.797244) (xy 375.798946 -285.775618) (xy 375.786965 -285.730697)
			(xy 375.780926 -285.6846) (xy 375.780554 -285.661354) (xy 375.781052 -285.634705) (xy 375.788995 -285.582001)
			(xy 375.804705 -285.531071) (xy 375.827831 -285.48305) (xy 375.857855 -285.439013) (xy 375.894107 -285.399942)
			(xy 375.935778 -285.366711) (xy 375.981936 -285.340062) (xy 376.03155 -285.32059) (xy 376.083512 -285.30873)
			(xy 376.136662 -285.304747) (xy 376.189812 -285.30873) (xy 376.241774 -285.32059) (xy 376.291388 -285.340062)
			(xy 376.337546 -285.366711) (xy 376.379217 -285.399942) (xy 376.415469 -285.439013) (xy 376.445493 -285.48305)
			(xy 376.468619 -285.531071) (xy 376.484329 -285.582001) (xy 376.492272 -285.634705) (xy 376.49277 -285.661354)
			(xy 376.492288 -285.686981) (xy 376.484959 -285.737708) (xy 376.470431 -285.786861) (xy 376.449006 -285.833421)
			(xy 376.421125 -285.876429) (xy 376.387365 -285.914993) (xy 376.348424 -285.948319) (xy 376.305107 -285.975715)
			(xy 376.258308 -285.996617) (xy 376.208996 -286.010592) (xy 376.183652 -286.014414) (xy 376.159014 -286.017716)
			(xy 375.986548 -286.31642) (xy 375.9962 -286.339534) (xy 376.004725 -286.361163) (xy 376.016708 -286.406082)
			(xy 376.02275 -286.452179) (xy 376.023124 -286.475424) (xy 376.022626 -286.502073) (xy 376.250952 -286.502073)
			(xy 376.250952 -286.448775) (xy 376.258895 -286.396071) (xy 376.274605 -286.345141) (xy 376.297731 -286.29712)
			(xy 376.327755 -286.253083) (xy 376.364007 -286.214012) (xy 376.405678 -286.180781) (xy 376.451836 -286.154132)
			(xy 376.50145 -286.13466) (xy 376.553412 -286.1228) (xy 376.606562 -286.118817) (xy 376.659712 -286.1228)
			(xy 376.711674 -286.13466) (xy 376.761288 -286.154132) (xy 376.807446 -286.180781) (xy 376.849117 -286.214012)
			(xy 376.885369 -286.253083) (xy 376.915393 -286.29712) (xy 376.938519 -286.345141) (xy 376.954229 -286.396071)
			(xy 376.962172 -286.448775) (xy 376.96267 -286.475424) (xy 377.190508 -286.475424) (xy 377.190989 -286.449797)
			(xy 377.19832 -286.399071) (xy 377.21285 -286.34992) (xy 377.234276 -286.30336) (xy 377.262157 -286.260354)
			(xy 377.295917 -286.221789) (xy 377.334858 -286.188464) (xy 377.378174 -286.161067) (xy 377.424971 -286.140164)
			(xy 377.474282 -286.126187) (xy 377.499626 -286.122364) (xy 377.524264 -286.119062) (xy 377.69673 -285.820358)
			(xy 377.687078 -285.797244) (xy 377.678546 -285.775618) (xy 377.666565 -285.730697) (xy 377.660526 -285.6846)
			(xy 377.660154 -285.661354) (xy 377.660652 -285.634705) (xy 377.668595 -285.582001) (xy 377.684305 -285.531071)
			(xy 377.707431 -285.48305) (xy 377.737455 -285.439013) (xy 377.773707 -285.399942) (xy 377.815378 -285.366711)
			(xy 377.861536 -285.340062) (xy 377.91115 -285.32059) (xy 377.963112 -285.30873) (xy 378.016262 -285.304747)
			(xy 378.069412 -285.30873) (xy 378.121374 -285.32059) (xy 378.170988 -285.340062) (xy 378.217146 -285.366711)
			(xy 378.258817 -285.399942) (xy 378.295069 -285.439013) (xy 378.325093 -285.48305) (xy 378.348219 -285.531071)
			(xy 378.363929 -285.582001) (xy 378.371872 -285.634705) (xy 378.37237 -285.661354) (xy 378.371888 -285.686981)
			(xy 378.364559 -285.737708) (xy 378.350031 -285.786861) (xy 378.328606 -285.833421) (xy 378.300725 -285.876429)
			(xy 378.266965 -285.914993) (xy 378.228024 -285.948319) (xy 378.184707 -285.975715) (xy 378.137908 -285.996617)
			(xy 378.088596 -286.010592) (xy 378.063252 -286.014414) (xy 378.038614 -286.017716) (xy 377.866148 -286.31642)
			(xy 377.8758 -286.339534) (xy 377.884325 -286.361163) (xy 377.896308 -286.406082) (xy 377.90235 -286.452179)
			(xy 377.902724 -286.475424) (xy 377.902226 -286.502073) (xy 378.130552 -286.502073) (xy 378.130552 -286.448775)
			(xy 378.138495 -286.396071) (xy 378.154205 -286.345141) (xy 378.177331 -286.29712) (xy 378.207355 -286.253083)
			(xy 378.243607 -286.214012) (xy 378.285278 -286.180781) (xy 378.331436 -286.154132) (xy 378.38105 -286.13466)
			(xy 378.433012 -286.1228) (xy 378.486162 -286.118817) (xy 378.539312 -286.1228) (xy 378.591274 -286.13466)
			(xy 378.640888 -286.154132) (xy 378.687046 -286.180781) (xy 378.728717 -286.214012) (xy 378.764969 -286.253083)
			(xy 378.794993 -286.29712) (xy 378.818119 -286.345141) (xy 378.833829 -286.396071) (xy 378.841772 -286.448775)
			(xy 378.84227 -286.475424) (xy 379.070108 -286.475424) (xy 379.070589 -286.449797) (xy 379.07792 -286.399071)
			(xy 379.09245 -286.34992) (xy 379.113876 -286.30336) (xy 379.141757 -286.260354) (xy 379.175517 -286.221789)
			(xy 379.214458 -286.188464) (xy 379.257774 -286.161067) (xy 379.304571 -286.140164) (xy 379.353882 -286.126187)
			(xy 379.379226 -286.122364) (xy 379.403864 -286.119062) (xy 379.57633 -285.820358) (xy 379.566678 -285.797244)
			(xy 379.558146 -285.775618) (xy 379.546165 -285.730697) (xy 379.540126 -285.6846) (xy 379.539754 -285.661354)
			(xy 379.540252 -285.634705) (xy 379.548195 -285.582001) (xy 379.563905 -285.531071) (xy 379.587031 -285.48305)
			(xy 379.617055 -285.439013) (xy 379.653307 -285.399942) (xy 379.694978 -285.366711) (xy 379.741136 -285.340062)
			(xy 379.79075 -285.32059) (xy 379.842712 -285.30873) (xy 379.895862 -285.304747) (xy 379.949012 -285.30873)
			(xy 380.000974 -285.32059) (xy 380.050588 -285.340062) (xy 380.096746 -285.366711) (xy 380.138417 -285.399942)
			(xy 380.174669 -285.439013) (xy 380.204693 -285.48305) (xy 380.227819 -285.531071) (xy 380.243529 -285.582001)
			(xy 380.251472 -285.634705) (xy 380.25197 -285.661354) (xy 380.251488 -285.686981) (xy 380.244159 -285.737708)
			(xy 380.229631 -285.786861) (xy 380.208206 -285.833421) (xy 380.180325 -285.876429) (xy 380.146565 -285.914993)
			(xy 380.107624 -285.948319) (xy 380.064307 -285.975715) (xy 380.017508 -285.996617) (xy 379.968196 -286.010592)
			(xy 379.942852 -286.014414) (xy 379.918214 -286.017716) (xy 379.745748 -286.31642) (xy 379.7554 -286.339534)
			(xy 379.763925 -286.361163) (xy 379.775908 -286.406082) (xy 379.78195 -286.452179) (xy 379.782324 -286.475424)
			(xy 379.781826 -286.502073) (xy 380.010152 -286.502073) (xy 380.010152 -286.448775) (xy 380.018095 -286.396071)
			(xy 380.033805 -286.345141) (xy 380.056931 -286.29712) (xy 380.086955 -286.253083) (xy 380.123207 -286.214012)
			(xy 380.164878 -286.180781) (xy 380.211036 -286.154132) (xy 380.26065 -286.13466) (xy 380.312612 -286.1228)
			(xy 380.365762 -286.118817) (xy 380.418912 -286.1228) (xy 380.470874 -286.13466) (xy 380.520488 -286.154132)
			(xy 380.566646 -286.180781) (xy 380.608317 -286.214012) (xy 380.644569 -286.253083) (xy 380.674593 -286.29712)
			(xy 380.697719 -286.345141) (xy 380.713429 -286.396071) (xy 380.721372 -286.448775) (xy 380.72187 -286.475424)
			(xy 380.949708 -286.475424) (xy 380.950189 -286.449797) (xy 380.95752 -286.399071) (xy 380.97205 -286.34992)
			(xy 380.993476 -286.30336) (xy 381.021357 -286.260354) (xy 381.055117 -286.221789) (xy 381.094058 -286.188464)
			(xy 381.137374 -286.161067) (xy 381.184171 -286.140164) (xy 381.233482 -286.126187) (xy 381.258826 -286.122364)
			(xy 381.283464 -286.119062) (xy 381.45593 -285.820358) (xy 381.446278 -285.797244) (xy 381.437746 -285.775618)
			(xy 381.425765 -285.730697) (xy 381.419726 -285.6846) (xy 381.419354 -285.661354) (xy 381.419852 -285.634705)
			(xy 381.427795 -285.582001) (xy 381.443505 -285.531071) (xy 381.466631 -285.48305) (xy 381.496655 -285.439013)
			(xy 381.532907 -285.399942) (xy 381.574578 -285.366711) (xy 381.620736 -285.340062) (xy 381.67035 -285.32059)
			(xy 381.722312 -285.30873) (xy 381.775462 -285.304747) (xy 381.828612 -285.30873) (xy 381.880574 -285.32059)
			(xy 381.930188 -285.340062) (xy 381.976346 -285.366711) (xy 382.018017 -285.399942) (xy 382.054269 -285.439013)
			(xy 382.084293 -285.48305) (xy 382.107419 -285.531071) (xy 382.123129 -285.582001) (xy 382.131072 -285.634705)
			(xy 382.13157 -285.661354) (xy 382.131088 -285.686981) (xy 382.13094 -285.688003) (xy 382.359652 -285.688003)
			(xy 382.359652 -285.634705) (xy 382.367595 -285.582001) (xy 382.383305 -285.531071) (xy 382.406431 -285.48305)
			(xy 382.436455 -285.439013) (xy 382.472707 -285.399942) (xy 382.514378 -285.366711) (xy 382.560536 -285.340062)
			(xy 382.61015 -285.32059) (xy 382.662112 -285.30873) (xy 382.715262 -285.304747) (xy 382.768412 -285.30873)
			(xy 382.820374 -285.32059) (xy 382.869988 -285.340062) (xy 382.916146 -285.366711) (xy 382.957817 -285.399942)
			(xy 382.994069 -285.439013) (xy 383.024093 -285.48305) (xy 383.047219 -285.531071) (xy 383.062929 -285.582001)
			(xy 383.070872 -285.634705) (xy 383.07137 -285.661354) (xy 383.070877 -285.687749) (xy 383.299452 -285.687749)
			(xy 383.299452 -285.634451) (xy 383.307395 -285.581747) (xy 383.323105 -285.530817) (xy 383.346231 -285.482796)
			(xy 383.376255 -285.438759) (xy 383.412507 -285.399688) (xy 383.454178 -285.366457) (xy 383.500336 -285.339808)
			(xy 383.54995 -285.320336) (xy 383.601912 -285.308476) (xy 383.655062 -285.304493) (xy 383.708212 -285.308476)
			(xy 383.760174 -285.320336) (xy 383.809788 -285.339808) (xy 383.855946 -285.366457) (xy 383.897617 -285.399688)
			(xy 383.933869 -285.438759) (xy 383.963893 -285.482796) (xy 383.987019 -285.530817) (xy 384.002729 -285.581747)
			(xy 384.010672 -285.634451) (xy 384.01117 -285.6611) (xy 384.010672 -285.687749) (xy 384.010634 -285.688003)
			(xy 384.239252 -285.688003) (xy 384.239252 -285.634705) (xy 384.247195 -285.582001) (xy 384.262905 -285.531071)
			(xy 384.286031 -285.48305) (xy 384.316055 -285.439013) (xy 384.352307 -285.399942) (xy 384.393978 -285.366711)
			(xy 384.440136 -285.340062) (xy 384.48975 -285.32059) (xy 384.541712 -285.30873) (xy 384.594862 -285.304747)
			(xy 384.648012 -285.30873) (xy 384.699974 -285.32059) (xy 384.749588 -285.340062) (xy 384.795746 -285.366711)
			(xy 384.837417 -285.399942) (xy 384.873669 -285.439013) (xy 384.903693 -285.48305) (xy 384.926819 -285.531071)
			(xy 384.942529 -285.582001) (xy 384.950472 -285.634705) (xy 384.95097 -285.661354) (xy 384.950472 -285.688003)
			(xy 384.942529 -285.740707) (xy 384.926819 -285.791637) (xy 384.903693 -285.839658) (xy 384.873669 -285.883695)
			(xy 384.837417 -285.922766) (xy 384.795746 -285.955997) (xy 384.749588 -285.982646) (xy 384.699974 -286.002118)
			(xy 384.648012 -286.013978) (xy 384.594862 -286.017962) (xy 384.541712 -286.013978) (xy 384.48975 -286.002118)
			(xy 384.440136 -285.982646) (xy 384.393978 -285.955997) (xy 384.352307 -285.922766) (xy 384.316055 -285.883695)
			(xy 384.286031 -285.839658) (xy 384.262905 -285.791637) (xy 384.247195 -285.740707) (xy 384.239252 -285.688003)
			(xy 384.010634 -285.688003) (xy 384.002729 -285.740453) (xy 383.987019 -285.791383) (xy 383.963893 -285.839404)
			(xy 383.933869 -285.883441) (xy 383.897617 -285.922512) (xy 383.855946 -285.955743) (xy 383.809788 -285.982392)
			(xy 383.760174 -286.001864) (xy 383.708212 -286.013724) (xy 383.655062 -286.017708) (xy 383.601912 -286.013724)
			(xy 383.54995 -286.001864) (xy 383.500336 -285.982392) (xy 383.454178 -285.955743) (xy 383.412507 -285.922512)
			(xy 383.376255 -285.883441) (xy 383.346231 -285.839404) (xy 383.323105 -285.791383) (xy 383.307395 -285.740453)
			(xy 383.299452 -285.687749) (xy 383.070877 -285.687749) (xy 383.070872 -285.688003) (xy 383.062929 -285.740707)
			(xy 383.047219 -285.791637) (xy 383.024093 -285.839658) (xy 382.994069 -285.883695) (xy 382.957817 -285.922766)
			(xy 382.916146 -285.955997) (xy 382.869988 -285.982646) (xy 382.820374 -286.002118) (xy 382.768412 -286.013978)
			(xy 382.715262 -286.017962) (xy 382.662112 -286.013978) (xy 382.61015 -286.002118) (xy 382.560536 -285.982646)
			(xy 382.514378 -285.955997) (xy 382.472707 -285.922766) (xy 382.436455 -285.883695) (xy 382.406431 -285.839658)
			(xy 382.383305 -285.791637) (xy 382.367595 -285.740707) (xy 382.359652 -285.688003) (xy 382.13094 -285.688003)
			(xy 382.123759 -285.737708) (xy 382.109231 -285.786861) (xy 382.087806 -285.833421) (xy 382.059925 -285.876429)
			(xy 382.026165 -285.914993) (xy 381.987224 -285.948319) (xy 381.943907 -285.975715) (xy 381.897108 -285.996617)
			(xy 381.847796 -286.010592) (xy 381.822452 -286.014414) (xy 381.797814 -286.017716) (xy 381.625348 -286.31642)
			(xy 381.635 -286.339534) (xy 381.643525 -286.361163) (xy 381.655508 -286.406082) (xy 381.66155 -286.452179)
			(xy 381.661924 -286.475424) (xy 381.661426 -286.502073) (xy 381.890006 -286.502073) (xy 381.890006 -286.448775)
			(xy 381.897949 -286.396071) (xy 381.913659 -286.345141) (xy 381.936785 -286.29712) (xy 381.966809 -286.253083)
			(xy 382.003061 -286.214012) (xy 382.044732 -286.180781) (xy 382.09089 -286.154132) (xy 382.140504 -286.13466)
			(xy 382.192466 -286.1228) (xy 382.245616 -286.118817) (xy 382.298766 -286.1228) (xy 382.350728 -286.13466)
			(xy 382.400342 -286.154132) (xy 382.4465 -286.180781) (xy 382.488171 -286.214012) (xy 382.524423 -286.253083)
			(xy 382.554447 -286.29712) (xy 382.577573 -286.345141) (xy 382.593283 -286.396071) (xy 382.601226 -286.448775)
			(xy 382.601724 -286.475424) (xy 382.601231 -286.501819) (xy 382.829552 -286.501819) (xy 382.829552 -286.448521)
			(xy 382.837495 -286.395817) (xy 382.853205 -286.344887) (xy 382.876331 -286.296866) (xy 382.906355 -286.252829)
			(xy 382.942607 -286.213758) (xy 382.984278 -286.180527) (xy 383.030436 -286.153878) (xy 383.08005 -286.134406)
			(xy 383.132012 -286.122546) (xy 383.185162 -286.118563) (xy 383.238312 -286.122546) (xy 383.290274 -286.134406)
			(xy 383.339888 -286.153878) (xy 383.386046 -286.180527) (xy 383.427717 -286.213758) (xy 383.463969 -286.252829)
			(xy 383.493993 -286.296866) (xy 383.517119 -286.344887) (xy 383.532829 -286.395817) (xy 383.540772 -286.448521)
			(xy 383.54127 -286.47517) (xy 383.540772 -286.501819) (xy 383.769352 -286.501819) (xy 383.769352 -286.448521)
			(xy 383.777295 -286.395817) (xy 383.793005 -286.344887) (xy 383.816131 -286.296866) (xy 383.846155 -286.252829)
			(xy 383.882407 -286.213758) (xy 383.924078 -286.180527) (xy 383.970236 -286.153878) (xy 384.01985 -286.134406)
			(xy 384.071812 -286.122546) (xy 384.124962 -286.118563) (xy 384.178112 -286.122546) (xy 384.230074 -286.134406)
			(xy 384.279688 -286.153878) (xy 384.325846 -286.180527) (xy 384.367517 -286.213758) (xy 384.403769 -286.252829)
			(xy 384.433793 -286.296866) (xy 384.456919 -286.344887) (xy 384.472629 -286.395817) (xy 384.480572 -286.448521)
			(xy 384.48107 -286.47517) (xy 384.480572 -286.501819) (xy 384.472629 -286.554523) (xy 384.456919 -286.605453)
			(xy 384.433793 -286.653474) (xy 384.403769 -286.697511) (xy 384.367517 -286.736582) (xy 384.325846 -286.769813)
			(xy 384.279688 -286.796462) (xy 384.230074 -286.815934) (xy 384.178112 -286.827794) (xy 384.124962 -286.831778)
			(xy 384.071812 -286.827794) (xy 384.01985 -286.815934) (xy 383.970236 -286.796462) (xy 383.924078 -286.769813)
			(xy 383.882407 -286.736582) (xy 383.846155 -286.697511) (xy 383.816131 -286.653474) (xy 383.793005 -286.605453)
			(xy 383.777295 -286.554523) (xy 383.769352 -286.501819) (xy 383.540772 -286.501819) (xy 383.532829 -286.554523)
			(xy 383.517119 -286.605453) (xy 383.493993 -286.653474) (xy 383.463969 -286.697511) (xy 383.427717 -286.736582)
			(xy 383.386046 -286.769813) (xy 383.339888 -286.796462) (xy 383.290274 -286.815934) (xy 383.238312 -286.827794)
			(xy 383.185162 -286.831778) (xy 383.132012 -286.827794) (xy 383.08005 -286.815934) (xy 383.030436 -286.796462)
			(xy 382.984278 -286.769813) (xy 382.942607 -286.736582) (xy 382.906355 -286.697511) (xy 382.876331 -286.653474)
			(xy 382.853205 -286.605453) (xy 382.837495 -286.554523) (xy 382.829552 -286.501819) (xy 382.601231 -286.501819)
			(xy 382.601226 -286.502073) (xy 382.593283 -286.554777) (xy 382.577573 -286.605707) (xy 382.554447 -286.653728)
			(xy 382.524423 -286.697765) (xy 382.488171 -286.736836) (xy 382.4465 -286.770067) (xy 382.400342 -286.796716)
			(xy 382.350728 -286.816188) (xy 382.298766 -286.828048) (xy 382.245616 -286.832032) (xy 382.192466 -286.828048)
			(xy 382.140504 -286.816188) (xy 382.09089 -286.796716) (xy 382.044732 -286.770067) (xy 382.003061 -286.736836)
			(xy 381.966809 -286.697765) (xy 381.936785 -286.653728) (xy 381.913659 -286.605707) (xy 381.897949 -286.554777)
			(xy 381.890006 -286.502073) (xy 381.661426 -286.502073) (xy 381.653483 -286.554777) (xy 381.637773 -286.605707)
			(xy 381.614647 -286.653728) (xy 381.584623 -286.697765) (xy 381.548371 -286.736836) (xy 381.5067 -286.770067)
			(xy 381.460542 -286.796716) (xy 381.410928 -286.816188) (xy 381.358966 -286.828048) (xy 381.305816 -286.832032)
			(xy 381.252666 -286.828048) (xy 381.200704 -286.816188) (xy 381.15109 -286.796716) (xy 381.104932 -286.770067)
			(xy 381.063261 -286.736836) (xy 381.027009 -286.697765) (xy 380.996985 -286.653728) (xy 380.973859 -286.605707)
			(xy 380.958149 -286.554777) (xy 380.950206 -286.502073) (xy 380.949708 -286.475424) (xy 380.72187 -286.475424)
			(xy 380.721372 -286.502073) (xy 380.713429 -286.554777) (xy 380.697719 -286.605707) (xy 380.674593 -286.653728)
			(xy 380.644569 -286.697765) (xy 380.608317 -286.736836) (xy 380.566646 -286.770067) (xy 380.520488 -286.796716)
			(xy 380.470874 -286.816188) (xy 380.418912 -286.828048) (xy 380.365762 -286.832032) (xy 380.312612 -286.828048)
			(xy 380.26065 -286.816188) (xy 380.211036 -286.796716) (xy 380.164878 -286.770067) (xy 380.123207 -286.736836)
			(xy 380.086955 -286.697765) (xy 380.056931 -286.653728) (xy 380.033805 -286.605707) (xy 380.018095 -286.554777)
			(xy 380.010152 -286.502073) (xy 379.781826 -286.502073) (xy 379.773883 -286.554777) (xy 379.758173 -286.605707)
			(xy 379.735047 -286.653728) (xy 379.705023 -286.697765) (xy 379.668771 -286.736836) (xy 379.6271 -286.770067)
			(xy 379.580942 -286.796716) (xy 379.531328 -286.816188) (xy 379.479366 -286.828048) (xy 379.426216 -286.832032)
			(xy 379.373066 -286.828048) (xy 379.321104 -286.816188) (xy 379.27149 -286.796716) (xy 379.225332 -286.770067)
			(xy 379.183661 -286.736836) (xy 379.147409 -286.697765) (xy 379.117385 -286.653728) (xy 379.094259 -286.605707)
			(xy 379.078549 -286.554777) (xy 379.070606 -286.502073) (xy 379.070108 -286.475424) (xy 378.84227 -286.475424)
			(xy 378.841772 -286.502073) (xy 378.833829 -286.554777) (xy 378.818119 -286.605707) (xy 378.794993 -286.653728)
			(xy 378.764969 -286.697765) (xy 378.728717 -286.736836) (xy 378.687046 -286.770067) (xy 378.640888 -286.796716)
			(xy 378.591274 -286.816188) (xy 378.539312 -286.828048) (xy 378.486162 -286.832032) (xy 378.433012 -286.828048)
			(xy 378.38105 -286.816188) (xy 378.331436 -286.796716) (xy 378.285278 -286.770067) (xy 378.243607 -286.736836)
			(xy 378.207355 -286.697765) (xy 378.177331 -286.653728) (xy 378.154205 -286.605707) (xy 378.138495 -286.554777)
			(xy 378.130552 -286.502073) (xy 377.902226 -286.502073) (xy 377.894283 -286.554777) (xy 377.878573 -286.605707)
			(xy 377.855447 -286.653728) (xy 377.825423 -286.697765) (xy 377.789171 -286.736836) (xy 377.7475 -286.770067)
			(xy 377.701342 -286.796716) (xy 377.651728 -286.816188) (xy 377.599766 -286.828048) (xy 377.546616 -286.832032)
			(xy 377.493466 -286.828048) (xy 377.441504 -286.816188) (xy 377.39189 -286.796716) (xy 377.345732 -286.770067)
			(xy 377.304061 -286.736836) (xy 377.267809 -286.697765) (xy 377.237785 -286.653728) (xy 377.214659 -286.605707)
			(xy 377.198949 -286.554777) (xy 377.191006 -286.502073) (xy 377.190508 -286.475424) (xy 376.96267 -286.475424)
			(xy 376.962172 -286.502073) (xy 376.954229 -286.554777) (xy 376.938519 -286.605707) (xy 376.915393 -286.653728)
			(xy 376.885369 -286.697765) (xy 376.849117 -286.736836) (xy 376.807446 -286.770067) (xy 376.761288 -286.796716)
			(xy 376.711674 -286.816188) (xy 376.659712 -286.828048) (xy 376.606562 -286.832032) (xy 376.553412 -286.828048)
			(xy 376.50145 -286.816188) (xy 376.451836 -286.796716) (xy 376.405678 -286.770067) (xy 376.364007 -286.736836)
			(xy 376.327755 -286.697765) (xy 376.297731 -286.653728) (xy 376.274605 -286.605707) (xy 376.258895 -286.554777)
			(xy 376.250952 -286.502073) (xy 376.022626 -286.502073) (xy 376.014683 -286.554777) (xy 375.998973 -286.605707)
			(xy 375.975847 -286.653728) (xy 375.945823 -286.697765) (xy 375.909571 -286.736836) (xy 375.8679 -286.770067)
			(xy 375.821742 -286.796716) (xy 375.772128 -286.816188) (xy 375.720166 -286.828048) (xy 375.667016 -286.832032)
			(xy 375.613866 -286.828048) (xy 375.561904 -286.816188) (xy 375.51229 -286.796716) (xy 375.466132 -286.770067)
			(xy 375.424461 -286.736836) (xy 375.388209 -286.697765) (xy 375.358185 -286.653728) (xy 375.335059 -286.605707)
			(xy 375.319349 -286.554777) (xy 375.311406 -286.502073) (xy 375.310908 -286.475424) (xy 375.08307 -286.475424)
			(xy 375.082572 -286.502073) (xy 375.074629 -286.554777) (xy 375.058919 -286.605707) (xy 375.035793 -286.653728)
			(xy 375.005769 -286.697765) (xy 374.969517 -286.736836) (xy 374.927846 -286.770067) (xy 374.881688 -286.796716)
			(xy 374.832074 -286.816188) (xy 374.780112 -286.828048) (xy 374.726962 -286.832032) (xy 374.673812 -286.828048)
			(xy 374.62185 -286.816188) (xy 374.572236 -286.796716) (xy 374.526078 -286.770067) (xy 374.484407 -286.736836)
			(xy 374.448155 -286.697765) (xy 374.418131 -286.653728) (xy 374.395005 -286.605707) (xy 374.379295 -286.554777)
			(xy 374.371352 -286.502073) (xy 374.143026 -286.502073) (xy 374.135083 -286.554777) (xy 374.119373 -286.605707)
			(xy 374.096247 -286.653728) (xy 374.066223 -286.697765) (xy 374.029971 -286.736836) (xy 373.9883 -286.770067)
			(xy 373.942142 -286.796716) (xy 373.892528 -286.816188) (xy 373.840566 -286.828048) (xy 373.787416 -286.832032)
			(xy 373.734266 -286.828048) (xy 373.682304 -286.816188) (xy 373.63269 -286.796716) (xy 373.586532 -286.770067)
			(xy 373.544861 -286.736836) (xy 373.508609 -286.697765) (xy 373.478585 -286.653728) (xy 373.455459 -286.605707)
			(xy 373.439749 -286.554777) (xy 373.431806 -286.502073) (xy 373.431308 -286.475424) (xy 373.20347 -286.475424)
			(xy 373.202972 -286.502073) (xy 373.195029 -286.554777) (xy 373.179319 -286.605707) (xy 373.156193 -286.653728)
			(xy 373.126169 -286.697765) (xy 373.089917 -286.736836) (xy 373.048246 -286.770067) (xy 373.002088 -286.796716)
			(xy 372.952474 -286.816188) (xy 372.900512 -286.828048) (xy 372.847362 -286.832032) (xy 372.794212 -286.828048)
			(xy 372.74225 -286.816188) (xy 372.692636 -286.796716) (xy 372.646478 -286.770067) (xy 372.604807 -286.736836)
			(xy 372.568555 -286.697765) (xy 372.538531 -286.653728) (xy 372.515405 -286.605707) (xy 372.499695 -286.554777)
			(xy 372.491752 -286.502073) (xy 372.263426 -286.502073) (xy 372.255483 -286.554777) (xy 372.239773 -286.605707)
			(xy 372.216647 -286.653728) (xy 372.186623 -286.697765) (xy 372.150371 -286.736836) (xy 372.1087 -286.770067)
			(xy 372.062542 -286.796716) (xy 372.012928 -286.816188) (xy 371.960966 -286.828048) (xy 371.907816 -286.832032)
			(xy 371.854666 -286.828048) (xy 371.802704 -286.816188) (xy 371.75309 -286.796716) (xy 371.706932 -286.770067)
			(xy 371.665261 -286.736836) (xy 371.629009 -286.697765) (xy 371.598985 -286.653728) (xy 371.575859 -286.605707)
			(xy 371.560149 -286.554777) (xy 371.552206 -286.502073) (xy 371.551708 -286.475424) (xy 371.32387 -286.475424)
			(xy 371.323372 -286.502073) (xy 371.315429 -286.554777) (xy 371.299719 -286.605707) (xy 371.276593 -286.653728)
			(xy 371.246569 -286.697765) (xy 371.210317 -286.736836) (xy 371.168646 -286.770067) (xy 371.122488 -286.796716)
			(xy 371.072874 -286.816188) (xy 371.020912 -286.828048) (xy 370.967762 -286.832032) (xy 370.914612 -286.828048)
			(xy 370.86265 -286.816188) (xy 370.813036 -286.796716) (xy 370.766878 -286.770067) (xy 370.725207 -286.736836)
			(xy 370.688955 -286.697765) (xy 370.658931 -286.653728) (xy 370.635805 -286.605707) (xy 370.620095 -286.554777)
			(xy 370.612152 -286.502073) (xy 370.383826 -286.502073) (xy 370.375883 -286.554777) (xy 370.360173 -286.605707)
			(xy 370.337047 -286.653728) (xy 370.307023 -286.697765) (xy 370.270771 -286.736836) (xy 370.2291 -286.770067)
			(xy 370.182942 -286.796716) (xy 370.133328 -286.816188) (xy 370.081366 -286.828048) (xy 370.028216 -286.832032)
			(xy 369.975066 -286.828048) (xy 369.923104 -286.816188) (xy 369.87349 -286.796716) (xy 369.827332 -286.770067)
			(xy 369.785661 -286.736836) (xy 369.749409 -286.697765) (xy 369.719385 -286.653728) (xy 369.696259 -286.605707)
			(xy 369.680549 -286.554777) (xy 369.672606 -286.502073) (xy 369.672108 -286.475424) (xy 369.44427 -286.475424)
			(xy 369.443772 -286.502073) (xy 369.435829 -286.554777) (xy 369.420119 -286.605707) (xy 369.396993 -286.653728)
			(xy 369.366969 -286.697765) (xy 369.330717 -286.736836) (xy 369.289046 -286.770067) (xy 369.242888 -286.796716)
			(xy 369.193274 -286.816188) (xy 369.141312 -286.828048) (xy 369.088162 -286.832032) (xy 369.035012 -286.828048)
			(xy 368.98305 -286.816188) (xy 368.933436 -286.796716) (xy 368.887278 -286.770067) (xy 368.845607 -286.736836)
			(xy 368.809355 -286.697765) (xy 368.779331 -286.653728) (xy 368.756205 -286.605707) (xy 368.740495 -286.554777)
			(xy 368.732552 -286.502073) (xy 368.504226 -286.502073) (xy 368.504199 -286.503544) (xy 368.495369 -286.559085)
			(xy 368.477917 -286.612547) (xy 368.452277 -286.662601) (xy 368.419086 -286.708002) (xy 368.379171 -286.747619)
			(xy 368.333523 -286.780469) (xy 368.283279 -286.805734) (xy 368.229687 -286.822785) (xy 368.201956 -286.827468)
			(xy 368.188103 -286.829973) (xy 368.162446 -286.841536) (xy 368.140923 -286.859666) (xy 368.125171 -286.882986)
			(xy 368.116387 -286.909722) (xy 368.11524 -286.937841) (xy 368.121817 -286.965203) (xy 368.135618 -286.989728)
			(xy 368.145314 -286.999934) (xy 368.20348 -287.0581) (xy 368.213583 -287.067571) (xy 368.23768 -287.08119)
			(xy 368.264553 -287.087822) (xy 368.29222 -287.086975) (xy 368.318638 -287.078714) (xy 368.341858 -287.063647)
			(xy 368.351308 -287.053528) (xy 368.368288 -287.034955) (xy 368.406575 -287.002301) (xy 368.449078 -286.975362)
			(xy 368.494951 -286.954676) (xy 368.54328 -286.940655) (xy 368.593101 -286.933579) (xy 368.618262 -286.933132)
			(xy 368.646248 -286.93365) (xy 368.701532 -286.942401) (xy 368.754766 -286.959694) (xy 368.804638 -286.985103)
			(xy 368.849921 -287.018002) (xy 368.8895 -287.05758) (xy 368.922398 -287.102863) (xy 368.947807 -287.152736)
			(xy 368.965099 -287.20597) (xy 368.97385 -287.261254) (xy 368.97437 -287.28924) (xy 368.973934 -287.3144)
			(xy 368.973722 -287.315889) (xy 369.202452 -287.315889) (xy 369.202452 -287.262591) (xy 369.210395 -287.209887)
			(xy 369.226105 -287.158957) (xy 369.249231 -287.110936) (xy 369.279255 -287.066899) (xy 369.315507 -287.027828)
			(xy 369.357178 -286.994597) (xy 369.403336 -286.967948) (xy 369.45295 -286.948476) (xy 369.504912 -286.936616)
			(xy 369.558062 -286.932633) (xy 369.611212 -286.936616) (xy 369.663174 -286.948476) (xy 369.712788 -286.967948)
			(xy 369.758946 -286.994597) (xy 369.800617 -287.027828) (xy 369.836869 -287.066899) (xy 369.866893 -287.110936)
			(xy 369.890019 -287.158957) (xy 369.905729 -287.209887) (xy 369.913672 -287.262591) (xy 369.91417 -287.28924)
			(xy 369.913672 -287.315889) (xy 370.142252 -287.315889) (xy 370.142252 -287.262591) (xy 370.150195 -287.209887)
			(xy 370.165905 -287.158957) (xy 370.189031 -287.110936) (xy 370.219055 -287.066899) (xy 370.255307 -287.027828)
			(xy 370.296978 -286.994597) (xy 370.343136 -286.967948) (xy 370.39275 -286.948476) (xy 370.444712 -286.936616)
			(xy 370.497862 -286.932633) (xy 370.551012 -286.936616) (xy 370.602974 -286.948476) (xy 370.652588 -286.967948)
			(xy 370.698746 -286.994597) (xy 370.740417 -287.027828) (xy 370.776669 -287.066899) (xy 370.806693 -287.110936)
			(xy 370.829819 -287.158957) (xy 370.845529 -287.209887) (xy 370.853472 -287.262591) (xy 370.85397 -287.28924)
			(xy 370.853472 -287.315889) (xy 371.082052 -287.315889) (xy 371.082052 -287.262591) (xy 371.089995 -287.209887)
			(xy 371.105705 -287.158957) (xy 371.128831 -287.110936) (xy 371.158855 -287.066899) (xy 371.195107 -287.027828)
			(xy 371.236778 -286.994597) (xy 371.282936 -286.967948) (xy 371.33255 -286.948476) (xy 371.384512 -286.936616)
			(xy 371.437662 -286.932633) (xy 371.490812 -286.936616) (xy 371.542774 -286.948476) (xy 371.592388 -286.967948)
			(xy 371.638546 -286.994597) (xy 371.680217 -287.027828) (xy 371.716469 -287.066899) (xy 371.746493 -287.110936)
			(xy 371.769619 -287.158957) (xy 371.785329 -287.209887) (xy 371.793272 -287.262591) (xy 371.79377 -287.28924)
			(xy 371.793272 -287.315889) (xy 372.021852 -287.315889) (xy 372.021852 -287.262591) (xy 372.029795 -287.209887)
			(xy 372.045505 -287.158957) (xy 372.068631 -287.110936) (xy 372.098655 -287.066899) (xy 372.134907 -287.027828)
			(xy 372.176578 -286.994597) (xy 372.222736 -286.967948) (xy 372.27235 -286.948476) (xy 372.324312 -286.936616)
			(xy 372.377462 -286.932633) (xy 372.430612 -286.936616) (xy 372.482574 -286.948476) (xy 372.532188 -286.967948)
			(xy 372.578346 -286.994597) (xy 372.620017 -287.027828) (xy 372.656269 -287.066899) (xy 372.686293 -287.110936)
			(xy 372.709419 -287.158957) (xy 372.725129 -287.209887) (xy 372.733072 -287.262591) (xy 372.73357 -287.28924)
			(xy 372.733072 -287.315889) (xy 372.961652 -287.315889) (xy 372.961652 -287.262591) (xy 372.969595 -287.209887)
			(xy 372.985305 -287.158957) (xy 373.008431 -287.110936) (xy 373.038455 -287.066899) (xy 373.074707 -287.027828)
			(xy 373.116378 -286.994597) (xy 373.162536 -286.967948) (xy 373.21215 -286.948476) (xy 373.264112 -286.936616)
			(xy 373.317262 -286.932633) (xy 373.370412 -286.936616) (xy 373.422374 -286.948476) (xy 373.471988 -286.967948)
			(xy 373.518146 -286.994597) (xy 373.559817 -287.027828) (xy 373.596069 -287.066899) (xy 373.626093 -287.110936)
			(xy 373.649219 -287.158957) (xy 373.664929 -287.209887) (xy 373.672872 -287.262591) (xy 373.67337 -287.28924)
			(xy 373.672872 -287.315889) (xy 373.901452 -287.315889) (xy 373.901452 -287.262591) (xy 373.909395 -287.209887)
			(xy 373.925105 -287.158957) (xy 373.948231 -287.110936) (xy 373.978255 -287.066899) (xy 374.014507 -287.027828)
			(xy 374.056178 -286.994597) (xy 374.102336 -286.967948) (xy 374.15195 -286.948476) (xy 374.203912 -286.936616)
			(xy 374.257062 -286.932633) (xy 374.310212 -286.936616) (xy 374.362174 -286.948476) (xy 374.411788 -286.967948)
			(xy 374.457946 -286.994597) (xy 374.499617 -287.027828) (xy 374.535869 -287.066899) (xy 374.565893 -287.110936)
			(xy 374.589019 -287.158957) (xy 374.604729 -287.209887) (xy 374.612672 -287.262591) (xy 374.61317 -287.28924)
			(xy 374.612672 -287.315889) (xy 374.841252 -287.315889) (xy 374.841252 -287.262591) (xy 374.849195 -287.209887)
			(xy 374.864905 -287.158957) (xy 374.888031 -287.110936) (xy 374.918055 -287.066899) (xy 374.954307 -287.027828)
			(xy 374.995978 -286.994597) (xy 375.042136 -286.967948) (xy 375.09175 -286.948476) (xy 375.143712 -286.936616)
			(xy 375.196862 -286.932633) (xy 375.250012 -286.936616) (xy 375.301974 -286.948476) (xy 375.351588 -286.967948)
			(xy 375.397746 -286.994597) (xy 375.439417 -287.027828) (xy 375.475669 -287.066899) (xy 375.505693 -287.110936)
			(xy 375.528819 -287.158957) (xy 375.544529 -287.209887) (xy 375.552472 -287.262591) (xy 375.55297 -287.28924)
			(xy 375.552472 -287.315889) (xy 375.781052 -287.315889) (xy 375.781052 -287.262591) (xy 375.788995 -287.209887)
			(xy 375.804705 -287.158957) (xy 375.827831 -287.110936) (xy 375.857855 -287.066899) (xy 375.894107 -287.027828)
			(xy 375.935778 -286.994597) (xy 375.981936 -286.967948) (xy 376.03155 -286.948476) (xy 376.083512 -286.936616)
			(xy 376.136662 -286.932633) (xy 376.189812 -286.936616) (xy 376.241774 -286.948476) (xy 376.291388 -286.967948)
			(xy 376.337546 -286.994597) (xy 376.379217 -287.027828) (xy 376.415469 -287.066899) (xy 376.445493 -287.110936)
			(xy 376.468619 -287.158957) (xy 376.484329 -287.209887) (xy 376.492272 -287.262591) (xy 376.49277 -287.28924)
			(xy 376.492272 -287.315889) (xy 376.720852 -287.315889) (xy 376.720852 -287.262591) (xy 376.728795 -287.209887)
			(xy 376.744505 -287.158957) (xy 376.767631 -287.110936) (xy 376.797655 -287.066899) (xy 376.833907 -287.027828)
			(xy 376.875578 -286.994597) (xy 376.921736 -286.967948) (xy 376.97135 -286.948476) (xy 377.023312 -286.936616)
			(xy 377.076462 -286.932633) (xy 377.129612 -286.936616) (xy 377.181574 -286.948476) (xy 377.231188 -286.967948)
			(xy 377.277346 -286.994597) (xy 377.319017 -287.027828) (xy 377.355269 -287.066899) (xy 377.385293 -287.110936)
			(xy 377.408419 -287.158957) (xy 377.424129 -287.209887) (xy 377.432072 -287.262591) (xy 377.43257 -287.28924)
			(xy 377.432072 -287.315889) (xy 377.660652 -287.315889) (xy 377.660652 -287.262591) (xy 377.668595 -287.209887)
			(xy 377.684305 -287.158957) (xy 377.707431 -287.110936) (xy 377.737455 -287.066899) (xy 377.773707 -287.027828)
			(xy 377.815378 -286.994597) (xy 377.861536 -286.967948) (xy 377.91115 -286.948476) (xy 377.963112 -286.936616)
			(xy 378.016262 -286.932633) (xy 378.069412 -286.936616) (xy 378.121374 -286.948476) (xy 378.170988 -286.967948)
			(xy 378.217146 -286.994597) (xy 378.258817 -287.027828) (xy 378.295069 -287.066899) (xy 378.325093 -287.110936)
			(xy 378.348219 -287.158957) (xy 378.363929 -287.209887) (xy 378.371872 -287.262591) (xy 378.37237 -287.28924)
			(xy 378.371872 -287.315889) (xy 378.600452 -287.315889) (xy 378.600452 -287.262591) (xy 378.608395 -287.209887)
			(xy 378.624105 -287.158957) (xy 378.647231 -287.110936) (xy 378.677255 -287.066899) (xy 378.713507 -287.027828)
			(xy 378.755178 -286.994597) (xy 378.801336 -286.967948) (xy 378.85095 -286.948476) (xy 378.902912 -286.936616)
			(xy 378.956062 -286.932633) (xy 379.009212 -286.936616) (xy 379.061174 -286.948476) (xy 379.110788 -286.967948)
			(xy 379.156946 -286.994597) (xy 379.198617 -287.027828) (xy 379.234869 -287.066899) (xy 379.264893 -287.110936)
			(xy 379.288019 -287.158957) (xy 379.303729 -287.209887) (xy 379.311672 -287.262591) (xy 379.31217 -287.28924)
			(xy 379.311672 -287.315889) (xy 379.540252 -287.315889) (xy 379.540252 -287.262591) (xy 379.548195 -287.209887)
			(xy 379.563905 -287.158957) (xy 379.587031 -287.110936) (xy 379.617055 -287.066899) (xy 379.653307 -287.027828)
			(xy 379.694978 -286.994597) (xy 379.741136 -286.967948) (xy 379.79075 -286.948476) (xy 379.842712 -286.936616)
			(xy 379.895862 -286.932633) (xy 379.949012 -286.936616) (xy 380.000974 -286.948476) (xy 380.050588 -286.967948)
			(xy 380.096746 -286.994597) (xy 380.138417 -287.027828) (xy 380.174669 -287.066899) (xy 380.204693 -287.110936)
			(xy 380.227819 -287.158957) (xy 380.243529 -287.209887) (xy 380.251472 -287.262591) (xy 380.25197 -287.28924)
			(xy 380.251472 -287.315889) (xy 380.480052 -287.315889) (xy 380.480052 -287.262591) (xy 380.487995 -287.209887)
			(xy 380.503705 -287.158957) (xy 380.526831 -287.110936) (xy 380.556855 -287.066899) (xy 380.593107 -287.027828)
			(xy 380.634778 -286.994597) (xy 380.680936 -286.967948) (xy 380.73055 -286.948476) (xy 380.782512 -286.936616)
			(xy 380.835662 -286.932633) (xy 380.888812 -286.936616) (xy 380.940774 -286.948476) (xy 380.990388 -286.967948)
			(xy 381.036546 -286.994597) (xy 381.078217 -287.027828) (xy 381.114469 -287.066899) (xy 381.144493 -287.110936)
			(xy 381.167619 -287.158957) (xy 381.183329 -287.209887) (xy 381.191272 -287.262591) (xy 381.19177 -287.28924)
			(xy 381.191272 -287.315889) (xy 381.419852 -287.315889) (xy 381.419852 -287.262591) (xy 381.427795 -287.209887)
			(xy 381.443505 -287.158957) (xy 381.466631 -287.110936) (xy 381.496655 -287.066899) (xy 381.532907 -287.027828)
			(xy 381.574578 -286.994597) (xy 381.620736 -286.967948) (xy 381.67035 -286.948476) (xy 381.722312 -286.936616)
			(xy 381.775462 -286.932633) (xy 381.828612 -286.936616) (xy 381.880574 -286.948476) (xy 381.930188 -286.967948)
			(xy 381.976346 -286.994597) (xy 382.018017 -287.027828) (xy 382.054269 -287.066899) (xy 382.084293 -287.110936)
			(xy 382.107419 -287.158957) (xy 382.123129 -287.209887) (xy 382.131072 -287.262591) (xy 382.13157 -287.28924)
			(xy 382.131072 -287.315889) (xy 382.359652 -287.315889) (xy 382.359652 -287.262591) (xy 382.367595 -287.209887)
			(xy 382.383305 -287.158957) (xy 382.406431 -287.110936) (xy 382.436455 -287.066899) (xy 382.472707 -287.027828)
			(xy 382.514378 -286.994597) (xy 382.560536 -286.967948) (xy 382.61015 -286.948476) (xy 382.662112 -286.936616)
			(xy 382.715262 -286.932633) (xy 382.768412 -286.936616) (xy 382.820374 -286.948476) (xy 382.869988 -286.967948)
			(xy 382.916146 -286.994597) (xy 382.957817 -287.027828) (xy 382.994069 -287.066899) (xy 383.024093 -287.110936)
			(xy 383.047219 -287.158957) (xy 383.062929 -287.209887) (xy 383.070872 -287.262591) (xy 383.07137 -287.28924)
			(xy 383.070872 -287.315889) (xy 383.299452 -287.315889) (xy 383.299452 -287.262591) (xy 383.307395 -287.209887)
			(xy 383.323105 -287.158957) (xy 383.346231 -287.110936) (xy 383.376255 -287.066899) (xy 383.412507 -287.027828)
			(xy 383.454178 -286.994597) (xy 383.500336 -286.967948) (xy 383.54995 -286.948476) (xy 383.601912 -286.936616)
			(xy 383.655062 -286.932633) (xy 383.708212 -286.936616) (xy 383.760174 -286.948476) (xy 383.809788 -286.967948)
			(xy 383.855946 -286.994597) (xy 383.897617 -287.027828) (xy 383.933869 -287.066899) (xy 383.963893 -287.110936)
			(xy 383.987019 -287.158957) (xy 384.002729 -287.209887) (xy 384.010672 -287.262591) (xy 384.01117 -287.28924)
			(xy 384.010672 -287.315889) (xy 384.002729 -287.368593) (xy 383.987019 -287.419523) (xy 383.963893 -287.467544)
			(xy 383.933869 -287.511581) (xy 383.897617 -287.550652) (xy 383.855946 -287.583883) (xy 383.809788 -287.610532)
			(xy 383.760174 -287.630004) (xy 383.708212 -287.641864) (xy 383.655062 -287.645848) (xy 383.601912 -287.641864)
			(xy 383.54995 -287.630004) (xy 383.500336 -287.610532) (xy 383.454178 -287.583883) (xy 383.412507 -287.550652)
			(xy 383.376255 -287.511581) (xy 383.346231 -287.467544) (xy 383.323105 -287.419523) (xy 383.307395 -287.368593)
			(xy 383.299452 -287.315889) (xy 383.070872 -287.315889) (xy 383.062929 -287.368593) (xy 383.047219 -287.419523)
			(xy 383.024093 -287.467544) (xy 382.994069 -287.511581) (xy 382.957817 -287.550652) (xy 382.916146 -287.583883)
			(xy 382.869988 -287.610532) (xy 382.820374 -287.630004) (xy 382.768412 -287.641864) (xy 382.715262 -287.645848)
			(xy 382.662112 -287.641864) (xy 382.61015 -287.630004) (xy 382.560536 -287.610532) (xy 382.514378 -287.583883)
			(xy 382.472707 -287.550652) (xy 382.436455 -287.511581) (xy 382.406431 -287.467544) (xy 382.383305 -287.419523)
			(xy 382.367595 -287.368593) (xy 382.359652 -287.315889) (xy 382.131072 -287.315889) (xy 382.123129 -287.368593)
			(xy 382.107419 -287.419523) (xy 382.084293 -287.467544) (xy 382.054269 -287.511581) (xy 382.018017 -287.550652)
			(xy 381.976346 -287.583883) (xy 381.930188 -287.610532) (xy 381.880574 -287.630004) (xy 381.828612 -287.641864)
			(xy 381.775462 -287.645848) (xy 381.722312 -287.641864) (xy 381.67035 -287.630004) (xy 381.620736 -287.610532)
			(xy 381.574578 -287.583883) (xy 381.532907 -287.550652) (xy 381.496655 -287.511581) (xy 381.466631 -287.467544)
			(xy 381.443505 -287.419523) (xy 381.427795 -287.368593) (xy 381.419852 -287.315889) (xy 381.191272 -287.315889)
			(xy 381.183329 -287.368593) (xy 381.167619 -287.419523) (xy 381.144493 -287.467544) (xy 381.114469 -287.511581)
			(xy 381.078217 -287.550652) (xy 381.036546 -287.583883) (xy 380.990388 -287.610532) (xy 380.940774 -287.630004)
			(xy 380.888812 -287.641864) (xy 380.835662 -287.645848) (xy 380.782512 -287.641864) (xy 380.73055 -287.630004)
			(xy 380.680936 -287.610532) (xy 380.634778 -287.583883) (xy 380.593107 -287.550652) (xy 380.556855 -287.511581)
			(xy 380.526831 -287.467544) (xy 380.503705 -287.419523) (xy 380.487995 -287.368593) (xy 380.480052 -287.315889)
			(xy 380.251472 -287.315889) (xy 380.243529 -287.368593) (xy 380.227819 -287.419523) (xy 380.204693 -287.467544)
			(xy 380.174669 -287.511581) (xy 380.138417 -287.550652) (xy 380.096746 -287.583883) (xy 380.050588 -287.610532)
			(xy 380.000974 -287.630004) (xy 379.949012 -287.641864) (xy 379.895862 -287.645848) (xy 379.842712 -287.641864)
			(xy 379.79075 -287.630004) (xy 379.741136 -287.610532) (xy 379.694978 -287.583883) (xy 379.653307 -287.550652)
			(xy 379.617055 -287.511581) (xy 379.587031 -287.467544) (xy 379.563905 -287.419523) (xy 379.548195 -287.368593)
			(xy 379.540252 -287.315889) (xy 379.311672 -287.315889) (xy 379.303729 -287.368593) (xy 379.288019 -287.419523)
			(xy 379.264893 -287.467544) (xy 379.234869 -287.511581) (xy 379.198617 -287.550652) (xy 379.156946 -287.583883)
			(xy 379.110788 -287.610532) (xy 379.061174 -287.630004) (xy 379.009212 -287.641864) (xy 378.956062 -287.645848)
			(xy 378.902912 -287.641864) (xy 378.85095 -287.630004) (xy 378.801336 -287.610532) (xy 378.755178 -287.583883)
			(xy 378.713507 -287.550652) (xy 378.677255 -287.511581) (xy 378.647231 -287.467544) (xy 378.624105 -287.419523)
			(xy 378.608395 -287.368593) (xy 378.600452 -287.315889) (xy 378.371872 -287.315889) (xy 378.363929 -287.368593)
			(xy 378.348219 -287.419523) (xy 378.325093 -287.467544) (xy 378.295069 -287.511581) (xy 378.258817 -287.550652)
			(xy 378.217146 -287.583883) (xy 378.170988 -287.610532) (xy 378.121374 -287.630004) (xy 378.069412 -287.641864)
			(xy 378.016262 -287.645848) (xy 377.963112 -287.641864) (xy 377.91115 -287.630004) (xy 377.861536 -287.610532)
			(xy 377.815378 -287.583883) (xy 377.773707 -287.550652) (xy 377.737455 -287.511581) (xy 377.707431 -287.467544)
			(xy 377.684305 -287.419523) (xy 377.668595 -287.368593) (xy 377.660652 -287.315889) (xy 377.432072 -287.315889)
			(xy 377.424129 -287.368593) (xy 377.408419 -287.419523) (xy 377.385293 -287.467544) (xy 377.355269 -287.511581)
			(xy 377.319017 -287.550652) (xy 377.277346 -287.583883) (xy 377.231188 -287.610532) (xy 377.181574 -287.630004)
			(xy 377.129612 -287.641864) (xy 377.076462 -287.645848) (xy 377.023312 -287.641864) (xy 376.97135 -287.630004)
			(xy 376.921736 -287.610532) (xy 376.875578 -287.583883) (xy 376.833907 -287.550652) (xy 376.797655 -287.511581)
			(xy 376.767631 -287.467544) (xy 376.744505 -287.419523) (xy 376.728795 -287.368593) (xy 376.720852 -287.315889)
			(xy 376.492272 -287.315889) (xy 376.484329 -287.368593) (xy 376.468619 -287.419523) (xy 376.445493 -287.467544)
			(xy 376.415469 -287.511581) (xy 376.379217 -287.550652) (xy 376.337546 -287.583883) (xy 376.291388 -287.610532)
			(xy 376.241774 -287.630004) (xy 376.189812 -287.641864) (xy 376.136662 -287.645848) (xy 376.083512 -287.641864)
			(xy 376.03155 -287.630004) (xy 375.981936 -287.610532) (xy 375.935778 -287.583883) (xy 375.894107 -287.550652)
			(xy 375.857855 -287.511581) (xy 375.827831 -287.467544) (xy 375.804705 -287.419523) (xy 375.788995 -287.368593)
			(xy 375.781052 -287.315889) (xy 375.552472 -287.315889) (xy 375.544529 -287.368593) (xy 375.528819 -287.419523)
			(xy 375.505693 -287.467544) (xy 375.475669 -287.511581) (xy 375.439417 -287.550652) (xy 375.397746 -287.583883)
			(xy 375.351588 -287.610532) (xy 375.301974 -287.630004) (xy 375.250012 -287.641864) (xy 375.196862 -287.645848)
			(xy 375.143712 -287.641864) (xy 375.09175 -287.630004) (xy 375.042136 -287.610532) (xy 374.995978 -287.583883)
			(xy 374.954307 -287.550652) (xy 374.918055 -287.511581) (xy 374.888031 -287.467544) (xy 374.864905 -287.419523)
			(xy 374.849195 -287.368593) (xy 374.841252 -287.315889) (xy 374.612672 -287.315889) (xy 374.604729 -287.368593)
			(xy 374.589019 -287.419523) (xy 374.565893 -287.467544) (xy 374.535869 -287.511581) (xy 374.499617 -287.550652)
			(xy 374.457946 -287.583883) (xy 374.411788 -287.610532) (xy 374.362174 -287.630004) (xy 374.310212 -287.641864)
			(xy 374.257062 -287.645848) (xy 374.203912 -287.641864) (xy 374.15195 -287.630004) (xy 374.102336 -287.610532)
			(xy 374.056178 -287.583883) (xy 374.014507 -287.550652) (xy 373.978255 -287.511581) (xy 373.948231 -287.467544)
			(xy 373.925105 -287.419523) (xy 373.909395 -287.368593) (xy 373.901452 -287.315889) (xy 373.672872 -287.315889)
			(xy 373.664929 -287.368593) (xy 373.649219 -287.419523) (xy 373.626093 -287.467544) (xy 373.596069 -287.511581)
			(xy 373.559817 -287.550652) (xy 373.518146 -287.583883) (xy 373.471988 -287.610532) (xy 373.422374 -287.630004)
			(xy 373.370412 -287.641864) (xy 373.317262 -287.645848) (xy 373.264112 -287.641864) (xy 373.21215 -287.630004)
			(xy 373.162536 -287.610532) (xy 373.116378 -287.583883) (xy 373.074707 -287.550652) (xy 373.038455 -287.511581)
			(xy 373.008431 -287.467544) (xy 372.985305 -287.419523) (xy 372.969595 -287.368593) (xy 372.961652 -287.315889)
			(xy 372.733072 -287.315889) (xy 372.725129 -287.368593) (xy 372.709419 -287.419523) (xy 372.686293 -287.467544)
			(xy 372.656269 -287.511581) (xy 372.620017 -287.550652) (xy 372.578346 -287.583883) (xy 372.532188 -287.610532)
			(xy 372.482574 -287.630004) (xy 372.430612 -287.641864) (xy 372.377462 -287.645848) (xy 372.324312 -287.641864)
			(xy 372.27235 -287.630004) (xy 372.222736 -287.610532) (xy 372.176578 -287.583883) (xy 372.134907 -287.550652)
			(xy 372.098655 -287.511581) (xy 372.068631 -287.467544) (xy 372.045505 -287.419523) (xy 372.029795 -287.368593)
			(xy 372.021852 -287.315889) (xy 371.793272 -287.315889) (xy 371.785329 -287.368593) (xy 371.769619 -287.419523)
			(xy 371.746493 -287.467544) (xy 371.716469 -287.511581) (xy 371.680217 -287.550652) (xy 371.638546 -287.583883)
			(xy 371.592388 -287.610532) (xy 371.542774 -287.630004) (xy 371.490812 -287.641864) (xy 371.437662 -287.645848)
			(xy 371.384512 -287.641864) (xy 371.33255 -287.630004) (xy 371.282936 -287.610532) (xy 371.236778 -287.583883)
			(xy 371.195107 -287.550652) (xy 371.158855 -287.511581) (xy 371.128831 -287.467544) (xy 371.105705 -287.419523)
			(xy 371.089995 -287.368593) (xy 371.082052 -287.315889) (xy 370.853472 -287.315889) (xy 370.845529 -287.368593)
			(xy 370.829819 -287.419523) (xy 370.806693 -287.467544) (xy 370.776669 -287.511581) (xy 370.740417 -287.550652)
			(xy 370.698746 -287.583883) (xy 370.652588 -287.610532) (xy 370.602974 -287.630004) (xy 370.551012 -287.641864)
			(xy 370.497862 -287.645848) (xy 370.444712 -287.641864) (xy 370.39275 -287.630004) (xy 370.343136 -287.610532)
			(xy 370.296978 -287.583883) (xy 370.255307 -287.550652) (xy 370.219055 -287.511581) (xy 370.189031 -287.467544)
			(xy 370.165905 -287.419523) (xy 370.150195 -287.368593) (xy 370.142252 -287.315889) (xy 369.913672 -287.315889)
			(xy 369.905729 -287.368593) (xy 369.890019 -287.419523) (xy 369.866893 -287.467544) (xy 369.836869 -287.511581)
			(xy 369.800617 -287.550652) (xy 369.758946 -287.583883) (xy 369.712788 -287.610532) (xy 369.663174 -287.630004)
			(xy 369.611212 -287.641864) (xy 369.558062 -287.645848) (xy 369.504912 -287.641864) (xy 369.45295 -287.630004)
			(xy 369.403336 -287.610532) (xy 369.357178 -287.583883) (xy 369.315507 -287.550652) (xy 369.279255 -287.511581)
			(xy 369.249231 -287.467544) (xy 369.226105 -287.419523) (xy 369.210395 -287.368593) (xy 369.202452 -287.315889)
			(xy 368.973722 -287.315889) (xy 368.966846 -287.364218) (xy 368.952816 -287.412542) (xy 368.932125 -287.458411)
			(xy 368.905184 -287.500911) (xy 368.872529 -287.539196) (xy 368.853974 -287.556194) (xy 368.843947 -287.565718)
			(xy 368.828955 -287.588942) (xy 368.820728 -287.615332) (xy 368.819868 -287.642961) (xy 368.826437 -287.669812)
			(xy 368.839957 -287.693923) (xy 368.849402 -287.704022) (xy 368.928396 -287.783016) (xy 368.959384 -287.771078)
			(xy 368.990443 -287.759806) (xy 369.055383 -287.747662) (xy 369.088416 -287.746948) (xy 369.1164 -287.747498)
			(xy 369.171677 -287.756255) (xy 369.224905 -287.77355) (xy 369.274772 -287.798959) (xy 369.320051 -287.831854)
			(xy 369.359628 -287.871427) (xy 369.392527 -287.916704) (xy 369.417939 -287.966569) (xy 369.435239 -288.019795)
			(xy 369.444 -288.075073) (xy 369.444524 -288.103056) (xy 369.443829 -288.136091) (xy 369.431687 -288.201035)
			(xy 369.420394 -288.232088) (xy 369.408456 -288.263076) (xy 369.903248 -288.757868)
		)
		(stroke
			(width 0)
			(type solid)
		)
		(fill yes)
		(layer "In13.Cu")
		(net "PVCCFA_EHV_FIVRA_CPU0")
	)
	(gr_poly
		(pts
			(xy 383.46888 -370.34343) (xy 388.376668 -357.392986) (xy 388.376668 -350.891348) (xy 390.68756 -348.580456)
			(xy 391.28573 -344.913458) (xy 391.28573 -335.614772) (xy 391.165588 -335.118456) (xy 388.515352 -332.46822)
			(xy 382.559052 -332.46822) (xy 379.719586 -329.628754) (xy 375.044716 -329.628754) (xy 371.72011 -326.304148)
			(xy 343.25306 -326.304148) (xy 339.999066 -329.558142) (xy 334.388968 -329.558142) (xy 332.80096 -331.14615)
			(xy 332.80096 -332.219554) (xy 331.583792 -333.436722) (xy 320.98742 -333.436722) (xy 319.247774 -335.176368)
			(xy 340.981284 -335.176368) (xy 340.981711 -335.148996) (xy 340.989535 -335.094815) (xy 341.005032 -335.04231)
			(xy 341.027883 -334.992564) (xy 341.057618 -334.9466) (xy 341.075264 -334.92567) (xy 341.084535 -334.914367)
			(xy 341.096713 -334.887801) (xy 341.100881 -334.858876) (xy 341.096699 -334.829952) (xy 341.084508 -334.803392)
			(xy 341.075264 -334.792066) (xy 341.057637 -334.771124) (xy 341.027924 -334.725154) (xy 341.005087 -334.675409)
			(xy 340.989593 -334.62291) (xy 340.98176 -334.568736) (xy 340.981284 -334.541368) (xy 340.98177 -334.514117)
			(xy 340.989526 -334.460169) (xy 341.004881 -334.407874) (xy 341.027523 -334.358297) (xy 341.056989 -334.312447)
			(xy 341.09268 -334.271256) (xy 341.133871 -334.235565) (xy 341.179721 -334.206099) (xy 341.229298 -334.183457)
			(xy 341.281593 -334.168102) (xy 341.335541 -334.160346) (xy 341.390043 -334.160346) (xy 341.443991 -334.168102)
			(xy 341.496286 -334.183457) (xy 341.545863 -334.206099) (xy 341.591713 -334.235565) (xy 341.632904 -334.271256)
			(xy 341.668595 -334.312447) (xy 341.698061 -334.358297) (xy 341.720703 -334.407874) (xy 341.736058 -334.460169)
			(xy 341.743814 -334.514117) (xy 341.7443 -334.541368) (xy 341.743815 -334.568738) (xy 341.736002 -334.622916)
			(xy 341.720517 -334.675419) (xy 341.69768 -334.725166) (xy 341.667959 -334.771134) (xy 341.65032 -334.792066)
			(xy 341.641113 -334.803416) (xy 341.628929 -334.829965) (xy 341.62475 -334.858876) (xy 341.628916 -334.887788)
			(xy 341.641086 -334.914343) (xy 341.65032 -334.92567) (xy 341.667962 -334.9466) (xy 341.697672 -334.992574)
			(xy 341.720508 -335.042322) (xy 341.735998 -335.094823) (xy 341.743826 -335.148999) (xy 341.7443 -335.176368)
			(xy 341.743814 -335.203619) (xy 341.736058 -335.257567) (xy 341.720703 -335.309862) (xy 341.698061 -335.359439)
			(xy 341.668595 -335.405289) (xy 341.632904 -335.44648) (xy 341.591713 -335.482171) (xy 341.545863 -335.511637)
			(xy 341.496286 -335.534279) (xy 341.443991 -335.549634) (xy 341.390043 -335.55739) (xy 341.335541 -335.55739)
			(xy 341.281593 -335.549634) (xy 341.229298 -335.534279) (xy 341.179721 -335.511637) (xy 341.133871 -335.482171)
			(xy 341.09268 -335.44648) (xy 341.056989 -335.405289) (xy 341.027523 -335.359439) (xy 341.004881 -335.309862)
			(xy 340.989526 -335.257567) (xy 340.98177 -335.203619) (xy 340.981284 -335.176368) (xy 319.247774 -335.176368)
			(xy 318.668642 -335.7555) (xy 345.217421 -335.7555) (xy 345.22159 -335.699879) (xy 345.234002 -335.6455)
			(xy 345.254381 -335.593578) (xy 345.28227 -335.545274) (xy 345.317048 -335.501666) (xy 345.357937 -335.463729)
			(xy 345.404023 -335.432311) (xy 345.454278 -335.408112) (xy 345.507578 -335.391674) (xy 345.562733 -335.383363)
			(xy 345.590622 -335.38287) (xy 345.590876 -335.38287) (xy 345.618412 -335.383381) (xy 345.672883 -335.391499)
			(xy 345.725561 -335.40756) (xy 345.750642 -335.418938) (xy 345.763019 -335.424383) (xy 345.789613 -335.429217)
			(xy 345.816543 -335.426897) (xy 345.841919 -335.417588) (xy 345.86396 -335.401941) (xy 345.881119 -335.381056)
			(xy 345.88704 -335.3689) (xy 345.898378 -335.344653) (xy 345.927062 -335.299459) (xy 345.96192 -335.258838)
			(xy 346.002233 -335.223624) (xy 346.047173 -335.194544) (xy 346.095812 -335.172197) (xy 346.14715 -335.157042)
			(xy 346.200128 -335.149393) (xy 346.226892 -335.148936) (xy 346.253364 -335.149401) (xy 346.305773 -335.156901)
			(xy 346.356596 -335.171737) (xy 346.404809 -335.193611) (xy 346.449445 -335.222083) (xy 346.489606 -335.256582)
			(xy 346.524485 -335.296413) (xy 346.55338 -335.340776) (xy 346.564966 -335.364582) (xy 346.571667 -335.377804)
			(xy 346.5913 -335.399992) (xy 346.616473 -335.415614) (xy 346.64507 -335.423359) (xy 346.674687 -335.422574)
			(xy 346.688918 -335.41843) (xy 346.717263 -335.409661) (xy 346.775839 -335.400225) (xy 346.805504 -335.399634)
			(xy 346.833361 -335.40015) (xy 346.888456 -335.40844) (xy 346.915232 -335.416144) (xy 346.929563 -335.419986)
			(xy 346.959217 -335.420195) (xy 346.987682 -335.411879) (xy 347.01256 -335.395739) (xy 347.031755 -335.373135)
			(xy 347.038168 -335.359756) (xy 347.049483 -335.335288) (xy 347.078037 -335.289568) (xy 347.112884 -335.248442)
			(xy 347.153294 -335.212767) (xy 347.198425 -335.18329) (xy 347.247333 -335.160625) (xy 347.298997 -335.145247)
			(xy 347.352338 -335.137476) (xy 347.37929 -335.136998) (xy 347.407178 -335.13746) (xy 347.462333 -335.145772)
			(xy 347.515632 -335.162211) (xy 347.54503 -335.176368) (xy 349.141796 -335.176368) (xy 349.142244 -335.148997)
			(xy 349.150067 -335.094817) (xy 349.16556 -335.042314) (xy 349.188405 -334.992568) (xy 349.218133 -334.946601)
			(xy 349.235776 -334.92567) (xy 349.245046 -334.914367) (xy 349.257222 -334.887801) (xy 349.26139 -334.858876)
			(xy 349.257208 -334.829953) (xy 349.245019 -334.803393) (xy 349.235776 -334.792066) (xy 349.218151 -334.771123)
			(xy 349.188438 -334.725153) (xy 349.165599 -334.675408) (xy 349.150105 -334.62291) (xy 349.142273 -334.568736)
			(xy 349.141796 -334.541368) (xy 349.142282 -334.514117) (xy 349.150038 -334.460169) (xy 349.165393 -334.407874)
			(xy 349.188035 -334.358297) (xy 349.217501 -334.312447) (xy 349.253192 -334.271256) (xy 349.294383 -334.235565)
			(xy 349.340233 -334.206099) (xy 349.38981 -334.183457) (xy 349.442105 -334.168102) (xy 349.496053 -334.160346)
			(xy 349.550555 -334.160346) (xy 349.604503 -334.168102) (xy 349.656798 -334.183457) (xy 349.706375 -334.206099)
			(xy 349.752225 -334.235565) (xy 349.793416 -334.271256) (xy 349.829107 -334.312447) (xy 349.858573 -334.358297)
			(xy 349.881215 -334.407874) (xy 349.89657 -334.460169) (xy 349.904326 -334.514117) (xy 349.904812 -334.541368)
			(xy 349.904324 -334.568737) (xy 349.896511 -334.622915) (xy 349.881027 -334.675418) (xy 349.85819 -334.725165)
			(xy 349.828471 -334.771133) (xy 349.810832 -334.792066) (xy 349.801624 -334.803415) (xy 349.789439 -334.829965)
			(xy 349.785259 -334.858876) (xy 349.789425 -334.887789) (xy 349.801598 -334.914344) (xy 349.810832 -334.92567)
			(xy 349.828475 -334.946598) (xy 349.858186 -334.992573) (xy 349.88102 -335.042321) (xy 349.89651 -335.094823)
			(xy 349.904338 -335.148999) (xy 349.904812 -335.176368) (xy 357.302308 -335.176368) (xy 357.302753 -335.148997)
			(xy 357.310576 -335.094817) (xy 357.32607 -335.042314) (xy 357.348916 -334.992567) (xy 357.378645 -334.946601)
			(xy 357.396288 -334.92567) (xy 357.405557 -334.914366) (xy 357.417732 -334.8878) (xy 357.421899 -334.858876)
			(xy 357.417718 -334.829953) (xy 357.40553 -334.803393) (xy 357.396288 -334.792066) (xy 357.378665 -334.771121)
			(xy 357.348951 -334.725152) (xy 357.326112 -334.675408) (xy 357.310617 -334.62291) (xy 357.302785 -334.568736)
			(xy 357.302308 -334.541368) (xy 357.302794 -334.514117) (xy 357.31055 -334.460169) (xy 357.325905 -334.407874)
			(xy 357.348547 -334.358297) (xy 357.378013 -334.312447) (xy 357.413704 -334.271256) (xy 357.454895 -334.235565)
			(xy 357.500745 -334.206099) (xy 357.550322 -334.183457) (xy 357.602617 -334.168102) (xy 357.656565 -334.160346)
			(xy 357.711067 -334.160346) (xy 357.765015 -334.168102) (xy 357.81731 -334.183457) (xy 357.866887 -334.206099)
			(xy 357.912737 -334.235565) (xy 357.953928 -334.271256) (xy 357.989619 -334.312447) (xy 358.019085 -334.358297)
			(xy 358.041727 -334.407874) (xy 358.057082 -334.460169) (xy 358.064838 -334.514117) (xy 358.065324 -334.541368)
			(xy 358.064858 -334.568738) (xy 358.057043 -334.622918) (xy 358.041555 -334.675422) (xy 358.018713 -334.725169)
			(xy 357.988986 -334.771135) (xy 357.971344 -334.792066) (xy 357.962142 -334.803418) (xy 357.949968 -334.829968)
			(xy 357.945792 -334.858876) (xy 357.949954 -334.887786) (xy 357.962116 -334.914341) (xy 357.971344 -334.92567)
			(xy 357.98899 -334.946597) (xy 358.018699 -334.992572) (xy 358.041533 -335.042321) (xy 358.057023 -335.094822)
			(xy 358.064851 -335.148999) (xy 358.065324 -335.176368) (xy 365.46282 -335.176368) (xy 365.463262 -335.148997)
			(xy 365.471085 -335.094817) (xy 365.48658 -335.042313) (xy 365.509427 -334.992567) (xy 365.539156 -334.946601)
			(xy 365.5568 -334.92567) (xy 365.566068 -334.914366) (xy 365.578241 -334.8878) (xy 365.582408 -334.858876)
			(xy 365.578228 -334.829954) (xy 365.566041 -334.803393) (xy 365.5568 -334.792066) (xy 365.539178 -334.77112)
			(xy 365.509464 -334.725151) (xy 365.486625 -334.675407) (xy 365.471129 -334.622909) (xy 365.463297 -334.568736)
			(xy 365.46282 -334.541368) (xy 365.463306 -334.514117) (xy 365.471062 -334.460169) (xy 365.486417 -334.407874)
			(xy 365.509059 -334.358297) (xy 365.538525 -334.312447) (xy 365.574216 -334.271256) (xy 365.615407 -334.235565)
			(xy 365.661257 -334.206099) (xy 365.710834 -334.183457) (xy 365.763129 -334.168102) (xy 365.817077 -334.160346)
			(xy 365.871579 -334.160346) (xy 365.925527 -334.168102) (xy 365.977822 -334.183457) (xy 366.027399 -334.206099)
			(xy 366.073249 -334.235565) (xy 366.11444 -334.271256) (xy 366.150131 -334.312447) (xy 366.179597 -334.358297)
			(xy 366.202239 -334.407874) (xy 366.217594 -334.460169) (xy 366.22535 -334.514117) (xy 366.225836 -334.541368)
			(xy 366.225367 -334.568738) (xy 366.217552 -334.622918) (xy 366.202065 -334.675422) (xy 366.179223 -334.725169)
			(xy 366.149498 -334.771135) (xy 366.131856 -334.792066) (xy 366.122653 -334.803418) (xy 366.110478 -334.829967)
			(xy 366.106301 -334.858876) (xy 366.110464 -334.887786) (xy 366.122627 -334.914341) (xy 366.131856 -334.92567)
			(xy 366.149488 -334.946608) (xy 366.179202 -334.992579) (xy 366.20204 -335.042324) (xy 366.217533 -335.094824)
			(xy 366.225362 -335.148999) (xy 366.225836 -335.176368) (xy 366.22535 -335.203619) (xy 366.217594 -335.257567)
			(xy 366.202239 -335.309862) (xy 366.179597 -335.359439) (xy 366.150131 -335.405289) (xy 366.11444 -335.44648)
			(xy 366.073249 -335.482171) (xy 366.027399 -335.511637) (xy 365.977822 -335.534279) (xy 365.925527 -335.549634)
			(xy 365.871579 -335.55739) (xy 365.817077 -335.55739) (xy 365.763129 -335.549634) (xy 365.710834 -335.534279)
			(xy 365.661257 -335.511637) (xy 365.615407 -335.482171) (xy 365.574216 -335.44648) (xy 365.538525 -335.405289)
			(xy 365.509059 -335.359439) (xy 365.486417 -335.309862) (xy 365.471062 -335.257567) (xy 365.463306 -335.203619)
			(xy 365.46282 -335.176368) (xy 358.065324 -335.176368) (xy 358.064838 -335.203619) (xy 358.057082 -335.257567)
			(xy 358.041727 -335.309862) (xy 358.019085 -335.359439) (xy 357.989619 -335.405289) (xy 357.953928 -335.44648)
			(xy 357.912737 -335.482171) (xy 357.866887 -335.511637) (xy 357.81731 -335.534279) (xy 357.765015 -335.549634)
			(xy 357.711067 -335.55739) (xy 357.656565 -335.55739) (xy 357.602617 -335.549634) (xy 357.550322 -335.534279)
			(xy 357.500745 -335.511637) (xy 357.454895 -335.482171) (xy 357.413704 -335.44648) (xy 357.378013 -335.405289)
			(xy 357.348547 -335.359439) (xy 357.325905 -335.309862) (xy 357.31055 -335.257567) (xy 357.302794 -335.203619)
			(xy 357.302308 -335.176368) (xy 349.904812 -335.176368) (xy 349.904326 -335.203619) (xy 349.89657 -335.257567)
			(xy 349.881215 -335.309862) (xy 349.858573 -335.359439) (xy 349.829107 -335.405289) (xy 349.793416 -335.44648)
			(xy 349.752225 -335.482171) (xy 349.706375 -335.511637) (xy 349.656798 -335.534279) (xy 349.604503 -335.549634)
			(xy 349.550555 -335.55739) (xy 349.496053 -335.55739) (xy 349.442105 -335.549634) (xy 349.38981 -335.534279)
			(xy 349.340233 -335.511637) (xy 349.294383 -335.482171) (xy 349.253192 -335.44648) (xy 349.217501 -335.405289)
			(xy 349.188035 -335.359439) (xy 349.165393 -335.309862) (xy 349.150038 -335.257567) (xy 349.142282 -335.203619)
			(xy 349.141796 -335.176368) (xy 347.54503 -335.176368) (xy 347.565885 -335.186411) (xy 347.611971 -335.217831)
			(xy 347.652859 -335.255768) (xy 347.687636 -335.299376) (xy 347.715525 -335.34768) (xy 347.735902 -335.399601)
			(xy 347.748314 -335.453979) (xy 347.752483 -335.5096) (xy 347.748314 -335.565221) (xy 347.735902 -335.619599)
			(xy 347.715525 -335.67152) (xy 347.687636 -335.719824) (xy 347.652859 -335.763432) (xy 347.611971 -335.801369)
			(xy 347.565885 -335.832789) (xy 347.515632 -335.856989) (xy 347.462333 -335.873428) (xy 347.407178 -335.88174)
			(xy 347.37929 -335.882234) (xy 347.351433 -335.88172) (xy 347.296338 -335.873428) (xy 347.269562 -335.865724)
			(xy 347.255229 -335.861894) (xy 347.225578 -335.861687) (xy 347.197116 -335.870002) (xy 347.172239 -335.886138)
			(xy 347.153041 -335.908736) (xy 347.146626 -335.922112) (xy 347.135349 -335.946598) (xy 347.106786 -335.992315)
			(xy 347.071933 -336.033439) (xy 347.031516 -336.069111) (xy 346.986381 -336.098585) (xy 346.937469 -336.121247)
			(xy 346.885801 -336.136624) (xy 346.832457 -336.144393) (xy 346.805504 -336.14487) (xy 346.779032 -336.144405)
			(xy 346.726623 -336.136904) (xy 346.675801 -336.122068) (xy 346.627587 -336.100194) (xy 346.582951 -336.071722)
			(xy 346.54279 -336.037224) (xy 346.507912 -335.997393) (xy 346.479016 -335.95303) (xy 346.46743 -335.929224)
			(xy 346.46073 -335.916001) (xy 346.441097 -335.893812) (xy 346.415924 -335.878189) (xy 346.387326 -335.870445)
			(xy 346.357709 -335.871231) (xy 346.343478 -335.875376) (xy 346.315133 -335.884146) (xy 346.256557 -335.893581)
			(xy 346.226892 -335.894172) (xy 346.226638 -335.894172) (xy 346.199102 -335.893661) (xy 346.144631 -335.885544)
			(xy 346.091952 -335.869482) (xy 346.066872 -335.858104) (xy 346.054496 -335.852654) (xy 346.027901 -335.847814)
			(xy 346.000968 -335.850131) (xy 345.97559 -335.859442) (xy 345.953548 -335.875092) (xy 345.936392 -335.895983)
			(xy 345.930474 -335.908142) (xy 345.919098 -335.93237) (xy 345.890422 -335.977566) (xy 345.855571 -336.01819)
			(xy 345.815263 -336.053406) (xy 345.770329 -336.082489) (xy 345.721693 -336.104839) (xy 345.67036 -336.119996)
			(xy 345.617385 -336.127648) (xy 345.590622 -336.128106) (xy 345.562733 -336.127637) (xy 345.507578 -336.119326)
			(xy 345.454278 -336.102888) (xy 345.404023 -336.078689) (xy 345.357937 -336.047271) (xy 345.317048 -336.009334)
			(xy 345.28227 -335.965726) (xy 345.254381 -335.917422) (xy 345.234002 -335.8655) (xy 345.22159 -335.811121)
			(xy 345.217421 -335.7555) (xy 318.668642 -335.7555) (xy 318.34074 -336.083402) (xy 318.34074 -336.63128)
			(xy 341.85682 -336.63128) (xy 341.860891 -336.575658) (xy 341.873017 -336.521221) (xy 341.89294 -336.46913)
			(xy 341.920236 -336.420495) (xy 341.954322 -336.376352) (xy 341.994471 -336.337643) (xy 342.039829 -336.305192)
			(xy 342.089429 -336.279691) (xy 342.142213 -336.261684) (xy 342.197056 -336.251554) (xy 342.25279 -336.249517)
			(xy 342.308227 -336.255617) (xy 342.362184 -336.269723) (xy 342.413513 -336.291535) (xy 342.461119 -336.320589)
			(xy 342.503987 -336.356264) (xy 342.541204 -336.397801) (xy 342.571977 -336.444314) (xy 342.595649 -336.494811)
			(xy 342.611717 -336.548218) (xy 342.619837 -336.603394) (xy 342.620346 -336.63128) (xy 342.619837 -336.659166)
			(xy 342.611717 -336.714342) (xy 342.595649 -336.767749) (xy 342.571977 -336.818246) (xy 342.541204 -336.864759)
			(xy 342.503987 -336.906296) (xy 342.461119 -336.941971) (xy 342.413513 -336.971025) (xy 342.362184 -336.992837)
			(xy 342.308227 -337.006943) (xy 342.25279 -337.013043) (xy 342.197056 -337.011006) (xy 342.142213 -337.000876)
			(xy 342.089429 -336.982869) (xy 342.039829 -336.957368) (xy 341.994471 -336.924917) (xy 341.954322 -336.886208)
			(xy 341.920236 -336.842065) (xy 341.89294 -336.79343) (xy 341.873017 -336.741339) (xy 341.860891 -336.686902)
			(xy 341.85682 -336.63128) (xy 318.34074 -336.63128) (xy 318.34074 -337.352894) (xy 341.12911 -337.352894)
			(xy 341.133181 -337.297272) (xy 341.145307 -337.242835) (xy 341.16523 -337.190744) (xy 341.192526 -337.142109)
			(xy 341.226612 -337.097966) (xy 341.266761 -337.059257) (xy 341.312119 -337.026806) (xy 341.361719 -337.001305)
			(xy 341.414503 -336.983298) (xy 341.469346 -336.973168) (xy 341.52508 -336.971131) (xy 341.580517 -336.977231)
			(xy 341.634474 -336.991337) (xy 341.685803 -337.013149) (xy 341.733409 -337.042203) (xy 341.776277 -337.077878)
			(xy 341.813494 -337.119415) (xy 341.844267 -337.165928) (xy 341.867939 -337.216425) (xy 341.884007 -337.269832)
			(xy 341.892127 -337.325008) (xy 341.892636 -337.352894) (xy 341.892127 -337.38078) (xy 341.884007 -337.435956)
			(xy 341.867939 -337.489363) (xy 341.844267 -337.53986) (xy 341.813494 -337.586373) (xy 341.776277 -337.62791)
			(xy 341.733409 -337.663585) (xy 341.685803 -337.692639) (xy 341.634474 -337.714451) (xy 341.580517 -337.728557)
			(xy 341.52508 -337.734657) (xy 341.469346 -337.73262) (xy 341.414503 -337.72249) (xy 341.361719 -337.704483)
			(xy 341.312119 -337.678982) (xy 341.266761 -337.646531) (xy 341.226612 -337.607822) (xy 341.192526 -337.563679)
			(xy 341.16523 -337.515044) (xy 341.145307 -337.462953) (xy 341.133181 -337.408516) (xy 341.12911 -337.352894)
			(xy 318.34074 -337.352894) (xy 318.34074 -338.586572) (xy 332.820772 -338.586572) (xy 332.821204 -338.5592)
			(xy 332.829027 -338.505019) (xy 332.844523 -338.452515) (xy 332.867373 -338.402769) (xy 332.897106 -338.356804)
			(xy 332.914752 -338.335874) (xy 332.924012 -338.324565) (xy 332.93618 -338.298) (xy 332.940345 -338.269079)
			(xy 332.936168 -338.240159) (xy 332.923989 -338.213599) (xy 332.914752 -338.20227) (xy 332.89714 -338.181316)
			(xy 332.867423 -338.13535) (xy 332.844581 -338.085608) (xy 332.829083 -338.033112) (xy 332.821249 -337.97894)
			(xy 332.820772 -337.951572) (xy 332.821258 -337.924321) (xy 332.829014 -337.870373) (xy 332.844369 -337.818078)
			(xy 332.867011 -337.768501) (xy 332.896477 -337.722651) (xy 332.932168 -337.68146) (xy 332.973359 -337.645769)
			(xy 333.019209 -337.616303) (xy 333.068786 -337.593661) (xy 333.121081 -337.578306) (xy 333.175029 -337.57055)
			(xy 333.229531 -337.57055) (xy 333.283479 -337.578306) (xy 333.335774 -337.593661) (xy 333.385351 -337.616303)
			(xy 333.431201 -337.645769) (xy 333.472392 -337.68146) (xy 333.508083 -337.722651) (xy 333.537549 -337.768501)
			(xy 333.560191 -337.818078) (xy 333.575546 -337.870373) (xy 333.583302 -337.924321) (xy 333.583788 -337.951572)
			(xy 333.583308 -337.978942) (xy 333.575494 -338.03312) (xy 333.560009 -338.085623) (xy 333.53717 -338.135371)
			(xy 333.507448 -338.181338) (xy 333.489808 -338.20227) (xy 333.480597 -338.213617) (xy 333.469256 -338.238338)
			(xy 342.578944 -338.238338) (xy 342.579509 -338.20865) (xy 342.588703 -338.149991) (xy 342.606875 -338.093464)
			(xy 342.633587 -338.040436) (xy 342.668192 -337.992187) (xy 342.709855 -337.949883) (xy 342.733376 -337.93176)
			(xy 342.74396 -337.923305) (xy 342.760672 -337.902001) (xy 342.771195 -337.877053) (xy 342.77479 -337.850216)
			(xy 342.771204 -337.823377) (xy 342.760688 -337.798426) (xy 342.743982 -337.777116) (xy 342.733376 -337.768692)
			(xy 342.709857 -337.750567) (xy 342.668198 -337.70826) (xy 342.633595 -337.660011) (xy 342.606884 -337.606984)
			(xy 342.588709 -337.550459) (xy 342.57951 -337.491801) (xy 342.578944 -337.462114) (xy 342.57943 -337.434863)
			(xy 342.587186 -337.380915) (xy 342.602541 -337.32862) (xy 342.625183 -337.279043) (xy 342.654649 -337.233193)
			(xy 342.69034 -337.192002) (xy 342.731531 -337.156311) (xy 342.777381 -337.126845) (xy 342.826958 -337.104203)
			(xy 342.879253 -337.088848) (xy 342.933201 -337.081092) (xy 342.987703 -337.081092) (xy 343.041651 -337.088848)
			(xy 343.093946 -337.104203) (xy 343.143523 -337.126845) (xy 343.189373 -337.156311) (xy 343.230564 -337.192002)
			(xy 343.266255 -337.233193) (xy 343.295721 -337.279043) (xy 343.318363 -337.32862) (xy 343.333718 -337.380915)
			(xy 343.341474 -337.434863) (xy 343.34196 -337.462114) (xy 343.341431 -337.491803) (xy 343.332229 -337.550464)
			(xy 343.31405 -337.606991) (xy 343.287332 -337.660019) (xy 343.275257 -337.676851) (xy 343.595444 -337.676851)
			(xy 343.595444 -337.622349) (xy 343.6032 -337.5684) (xy 343.618554 -337.516105) (xy 343.641193 -337.466526)
			(xy 343.670658 -337.420674) (xy 343.706347 -337.379481) (xy 343.747536 -337.343787) (xy 343.793384 -337.314316)
			(xy 343.84296 -337.291671) (xy 343.895253 -337.27631) (xy 343.949201 -337.268547) (xy 343.976452 -337.268058)
			(xy 343.976706 -337.268058) (xy 344.00191 -337.268452) (xy 344.051878 -337.275093) (xy 344.100533 -337.288271)
			(xy 344.147022 -337.307756) (xy 344.168984 -337.320128) (xy 344.181966 -337.327134) (xy 344.210596 -337.334177)
			(xy 344.240045 -337.33274) (xy 344.267854 -337.322944) (xy 344.291702 -337.305606) (xy 344.309598 -337.282175)
			(xy 344.315288 -337.268566) (xy 344.325959 -337.241779) (xy 344.354252 -337.191538) (xy 344.389785 -337.146129)
			(xy 344.431751 -337.106587) (xy 344.479192 -337.073815) (xy 344.531026 -337.048559) (xy 344.586072 -337.031395)
			(xy 344.643074 -337.022715) (xy 344.671904 -337.022186) (xy 344.699155 -337.022674) (xy 344.753102 -337.030431)
			(xy 344.805397 -337.045786) (xy 344.854974 -337.068427) (xy 344.900824 -337.097894) (xy 344.942014 -337.133585)
			(xy 344.977705 -337.174775) (xy 345.007172 -337.220625) (xy 345.016538 -337.241134) (xy 347.15958 -337.241134)
			(xy 347.160076 -337.213561) (xy 347.168023 -337.158989) (xy 347.183743 -337.10613) (xy 347.206907 -337.056085)
			(xy 347.237034 -337.009894) (xy 347.273496 -336.968521) (xy 347.2942 -336.950304) (xy 347.305063 -336.940371)
			(xy 347.321136 -336.91573) (xy 347.329523 -336.887532) (xy 347.32953 -336.858112) (xy 347.321155 -336.82991)
			(xy 347.305092 -336.805263) (xy 347.2942 -336.795364) (xy 347.273468 -336.777175) (xy 347.237 -336.735802)
			(xy 347.20687 -336.689607) (xy 347.183708 -336.639555) (xy 347.167996 -336.586688) (xy 347.160062 -336.53211)
			(xy 347.15958 -336.504534) (xy 347.160087 -336.477283) (xy 347.167839 -336.423334) (xy 347.18319 -336.371037)
			(xy 347.205828 -336.321458) (xy 347.235291 -336.275606) (xy 347.27098 -336.234413) (xy 347.312169 -336.198719)
			(xy 347.358018 -336.16925) (xy 347.407594 -336.146606) (xy 347.459889 -336.131249) (xy 347.513837 -336.12349)
			(xy 347.541088 -336.123026) (xy 347.541596 -336.123026) (xy 347.575378 -336.12455) (xy 347.588737 -336.125329)
			(xy 347.615099 -336.120819) (xy 347.639377 -336.109598) (xy 347.659895 -336.092442) (xy 347.675237 -336.070533)
			(xy 347.684343 -336.045386) (xy 347.685868 -336.032094) (xy 347.688871 -336.003927) (xy 347.702039 -335.948837)
			(xy 347.723211 -335.896301) (xy 347.751922 -335.847475) (xy 347.78754 -335.803434) (xy 347.829282 -335.765146)
			(xy 347.876228 -335.733455) (xy 347.927346 -335.709058) (xy 347.981511 -335.692491) (xy 348.037531 -335.684119)
			(xy 348.065852 -335.683606) (xy 348.083871 -335.683823) (xy 348.119746 -335.68726) (xy 348.13748 -335.690464)
			(xy 348.152691 -335.692778) (xy 348.183241 -335.689255) (xy 348.211358 -335.6768) (xy 348.234494 -335.65654)
			(xy 348.250551 -335.630313) (xy 348.254828 -335.615534) (xy 348.262201 -335.588483) (xy 348.283834 -335.536756)
			(xy 348.312802 -335.48875) (xy 348.348481 -335.445499) (xy 348.390103 -335.407933) (xy 348.436774 -335.37686)
			(xy 348.487488 -335.352948) (xy 348.541154 -335.336713) (xy 348.596618 -335.328504) (xy 348.624652 -335.328006)
			(xy 348.651904 -335.3285) (xy 348.705855 -335.336251) (xy 348.758153 -335.351601) (xy 348.807734 -335.374239)
			(xy 348.853588 -335.403704) (xy 348.894782 -335.439394) (xy 348.930476 -335.480585) (xy 348.959944 -335.526436)
			(xy 348.982587 -335.576015) (xy 348.983463 -335.579) (xy 353.390417 -335.579) (xy 353.394585 -335.523382)
			(xy 353.406996 -335.469006) (xy 353.427372 -335.417087) (xy 353.455258 -335.368785) (xy 353.490031 -335.325178)
			(xy 353.530916 -335.287241) (xy 353.576997 -335.255821) (xy 353.627247 -335.23162) (xy 353.680542 -335.215178)
			(xy 353.735693 -335.206862) (xy 353.76358 -335.20634) (xy 353.790913 -335.206792) (xy 353.844993 -335.214765)
			(xy 353.897328 -335.230556) (xy 353.946793 -335.253827) (xy 353.992325 -335.284078) (xy 354.032946 -335.320659)
			(xy 354.067785 -335.362784) (xy 354.08235 -335.385918) (xy 354.090244 -335.398163) (xy 354.111724 -335.417832)
			(xy 354.137885 -335.430633) (xy 354.166597 -335.435523) (xy 354.195521 -335.432104) (xy 354.209096 -335.426812)
			(xy 354.23231 -335.417332) (xy 354.280641 -335.403977) (xy 354.330329 -335.397245) (xy 354.3554 -335.39684)
			(xy 354.380469 -335.397275) (xy 354.430152 -335.40402) (xy 354.478486 -335.417348) (xy 354.501704 -335.426812)
			(xy 354.515304 -335.431992) (xy 354.544193 -335.435371) (xy 354.572863 -335.430475) (xy 354.598994 -335.417702)
			(xy 354.620468 -335.398086) (xy 354.62845 -335.385918) (xy 354.643019 -335.362787) (xy 354.677862 -335.320666)
			(xy 354.718485 -335.284087) (xy 354.764016 -335.253836) (xy 354.813478 -335.23056) (xy 354.865809 -335.21476)
			(xy 354.919888 -335.206774) (xy 354.974552 -335.206774) (xy 355.028631 -335.21476) (xy 355.080962 -335.23056)
			(xy 355.130424 -335.253836) (xy 355.175955 -335.284087) (xy 355.216578 -335.320666) (xy 355.251421 -335.362787)
			(xy 355.26599 -335.385918) (xy 355.273941 -335.398122) (xy 355.295405 -335.417791) (xy 355.321551 -335.430597)
			(xy 355.350249 -335.435498) (xy 355.379163 -335.432094) (xy 355.392736 -335.426812) (xy 355.415945 -335.41732)
			(xy 355.464278 -335.403969) (xy 355.513968 -335.397243) (xy 355.53904 -335.39684) (xy 355.56588 -335.397387)
			(xy 355.619004 -335.405082) (xy 355.670475 -335.420321) (xy 355.719225 -335.442789) (xy 355.764247 -335.472021)
			(xy 355.804608 -335.507411) (xy 355.839472 -335.548227) (xy 355.868118 -335.593623) (xy 355.889952 -335.642661)
			(xy 355.897688 -335.668366) (xy 355.902375 -335.682854) (xy 355.91889 -335.708414) (xy 355.9422 -335.727978)
			(xy 355.970239 -335.739808) (xy 356.000517 -335.742857) (xy 356.030351 -335.736853) (xy 356.043992 -335.730088)
			(xy 356.072132 -335.715442) (xy 356.132086 -335.694719) (xy 356.194647 -335.684226) (xy 356.226364 -335.683606)
			(xy 356.244384 -335.683822) (xy 356.280258 -335.687259) (xy 356.297992 -335.690464) (xy 356.313202 -335.69279)
			(xy 356.343753 -335.689265) (xy 356.371871 -335.676806) (xy 356.395007 -335.656544) (xy 356.411064 -335.630314)
			(xy 356.41534 -335.615534) (xy 356.422702 -335.588479) (xy 356.444336 -335.536752) (xy 356.473305 -335.488746)
			(xy 356.508985 -335.445495) (xy 356.550609 -335.407928) (xy 356.597281 -335.376856) (xy 356.647996 -335.352945)
			(xy 356.701664 -335.336711) (xy 356.757129 -335.328503) (xy 356.785164 -335.328006) (xy 356.812417 -335.328489)
			(xy 356.866368 -335.336241) (xy 356.918666 -335.351593) (xy 356.968247 -335.374233) (xy 357.014101 -335.403698)
			(xy 357.055294 -335.43939) (xy 357.090988 -335.480582) (xy 357.120457 -335.526434) (xy 357.143099 -335.576013)
			(xy 357.143976 -335.579) (xy 361.550917 -335.579) (xy 361.555086 -335.523381) (xy 361.567497 -335.469004)
			(xy 361.587873 -335.417084) (xy 361.61576 -335.368781) (xy 361.650535 -335.325174) (xy 361.691421 -335.287237)
			(xy 361.737504 -335.255817) (xy 361.787755 -335.231616) (xy 361.841052 -335.215175) (xy 361.896204 -335.206862)
			(xy 361.924092 -335.20634) (xy 361.951425 -335.206783) (xy 362.005506 -335.214757) (xy 362.057841 -335.23055)
			(xy 362.107306 -335.253822) (xy 362.152838 -335.284075) (xy 362.193459 -335.320657) (xy 362.228297 -335.362784)
			(xy 362.242862 -335.385918) (xy 362.250744 -335.398171) (xy 362.272228 -335.417841) (xy 362.298392 -335.43064)
			(xy 362.327106 -335.435528) (xy 362.356032 -335.432105) (xy 362.369608 -335.426812) (xy 362.39282 -335.417328)
			(xy 362.441152 -335.403975) (xy 362.490841 -335.397244) (xy 362.515912 -335.39684) (xy 362.540981 -335.397271)
			(xy 362.590664 -335.404017) (xy 362.638998 -335.417347) (xy 362.662216 -335.426812) (xy 362.675812 -335.432005)
			(xy 362.704703 -335.435381) (xy 362.733375 -335.430482) (xy 362.759506 -335.417706) (xy 362.78098 -335.398087)
			(xy 362.788962 -335.385918) (xy 362.803531 -335.362787) (xy 362.838374 -335.320666) (xy 362.878997 -335.284087)
			(xy 362.924528 -335.253836) (xy 362.97399 -335.23056) (xy 363.026321 -335.21476) (xy 363.0804 -335.206774)
			(xy 363.135064 -335.206774) (xy 363.189143 -335.21476) (xy 363.241474 -335.23056) (xy 363.290936 -335.253836)
			(xy 363.336467 -335.284087) (xy 363.37709 -335.320666) (xy 363.411933 -335.362787) (xy 363.426502 -335.385918)
			(xy 363.434441 -335.39813) (xy 363.455909 -335.417799) (xy 363.482058 -335.430604) (xy 363.510759 -335.435503)
			(xy 363.539675 -335.432096) (xy 363.553248 -335.426812) (xy 363.576455 -335.417316) (xy 363.624789 -335.403967)
			(xy 363.67448 -335.397242) (xy 363.699552 -335.39684) (xy 363.726392 -335.397376) (xy 363.779517 -335.405073)
			(xy 363.830988 -335.420314) (xy 363.879739 -335.442783) (xy 363.92476 -335.472016) (xy 363.965121 -335.507407)
			(xy 363.999985 -335.548224) (xy 364.02863 -335.593622) (xy 364.050464 -335.642661) (xy 364.0582 -335.668366)
			(xy 364.062871 -335.68286) (xy 364.079389 -335.708422) (xy 364.102703 -335.727986) (xy 364.130744 -335.739816)
			(xy 364.161026 -335.742862) (xy 364.190862 -335.736855) (xy 364.204504 -335.730088) (xy 364.232659 -335.715474)
			(xy 364.292606 -335.69474) (xy 364.35516 -335.684233) (xy 364.386876 -335.683606) (xy 364.404896 -335.68382)
			(xy 364.44077 -335.687259) (xy 364.458504 -335.690464) (xy 364.473713 -335.692802) (xy 364.504265 -335.689273)
			(xy 364.532384 -335.676812) (xy 364.555519 -335.656547) (xy 364.571576 -335.630315) (xy 364.575852 -335.615534)
			(xy 364.583203 -335.588476) (xy 364.604838 -335.536748) (xy 364.633808 -335.488742) (xy 364.66949 -335.44549)
			(xy 364.711115 -335.407924) (xy 364.757788 -335.376851) (xy 364.808505 -335.352942) (xy 364.862174 -335.336709)
			(xy 364.917641 -335.328502) (xy 364.945676 -335.328006) (xy 364.972929 -335.328478) (xy 365.02688 -335.336232)
			(xy 365.079179 -335.351585) (xy 365.12876 -335.374226) (xy 365.174614 -335.403693) (xy 365.215807 -335.439386)
			(xy 365.251501 -335.480578) (xy 365.280969 -335.526431) (xy 365.303611 -335.576012) (xy 365.304488 -335.579)
			(xy 369.711391 -335.579) (xy 369.71556 -335.523376) (xy 369.727972 -335.468994) (xy 369.748351 -335.41707)
			(xy 369.776242 -335.368763) (xy 369.81102 -335.325152) (xy 369.85191 -335.287212) (xy 369.897998 -335.255791)
			(xy 369.948254 -335.231589) (xy 370.001557 -335.215148) (xy 370.056714 -335.206835) (xy 370.084604 -335.20634)
			(xy 370.111937 -335.206773) (xy 370.166019 -335.214749) (xy 370.218354 -335.230543) (xy 370.267819 -335.253818)
			(xy 370.313351 -335.284071) (xy 370.353972 -335.320655) (xy 370.38881 -335.362783) (xy 370.403374 -335.385918)
			(xy 370.41134 -335.398111) (xy 370.4328 -335.41778) (xy 370.458942 -335.430588) (xy 370.487637 -335.435491)
			(xy 370.516548 -335.432092) (xy 370.53012 -335.426812) (xy 370.553331 -335.417325) (xy 370.601663 -335.403973)
			(xy 370.651352 -335.397244) (xy 370.676424 -335.39684) (xy 370.701493 -335.397267) (xy 370.751176 -335.404015)
			(xy 370.799511 -335.417346) (xy 370.822728 -335.426812) (xy 370.836319 -335.432017) (xy 370.865212 -335.435391)
			(xy 370.893886 -335.430489) (xy 370.920018 -335.41771) (xy 370.941493 -335.398088) (xy 370.949474 -335.385918)
			(xy 370.964043 -335.362787) (xy 370.998886 -335.320666) (xy 371.039509 -335.284087) (xy 371.08504 -335.253836)
			(xy 371.134502 -335.23056) (xy 371.186833 -335.21476) (xy 371.240912 -335.206774) (xy 371.295576 -335.206774)
			(xy 371.349655 -335.21476) (xy 371.401986 -335.23056) (xy 371.451448 -335.253836) (xy 371.496979 -335.284087)
			(xy 371.537602 -335.320666) (xy 371.572445 -335.362787) (xy 371.587014 -335.385918) (xy 371.594942 -335.398139)
			(xy 371.616413 -335.417808) (xy 371.642565 -335.430612) (xy 371.671268 -335.435508) (xy 371.700186 -335.432098)
			(xy 371.71376 -335.426812) (xy 371.736966 -335.417312) (xy 371.785301 -335.403965) (xy 371.834992 -335.397241)
			(xy 371.860064 -335.39684) (xy 371.887949 -335.397417) (xy 371.943098 -335.405724) (xy 371.996392 -335.422159)
			(xy 372.046641 -335.446353) (xy 372.092723 -335.477767) (xy 372.133608 -335.515699) (xy 372.168382 -335.5593)
			(xy 372.196269 -335.607598) (xy 372.216645 -335.659513) (xy 372.229056 -335.713885) (xy 372.233224 -335.7695)
			(xy 372.229056 -335.825115) (xy 372.216645 -335.879487) (xy 372.196269 -335.931402) (xy 372.168382 -335.9797)
			(xy 372.133608 -336.023301) (xy 372.092723 -336.061233) (xy 372.046641 -336.092647) (xy 371.996392 -336.116841)
			(xy 371.943098 -336.133276) (xy 371.887949 -336.141583) (xy 371.860064 -336.142076) (xy 371.832733 -336.141582)
			(xy 371.778654 -336.133616) (xy 371.726321 -336.117831) (xy 371.676857 -336.094567) (xy 371.631324 -336.064323)
			(xy 371.590701 -336.027748) (xy 371.55586 -335.985629) (xy 371.541294 -335.962498) (xy 371.533355 -335.950285)
			(xy 371.511888 -335.930614) (xy 371.485739 -335.917808) (xy 371.457037 -335.91291) (xy 371.428121 -335.916318)
			(xy 371.414548 -335.921604) (xy 371.391341 -335.931102) (xy 371.343007 -335.94445) (xy 371.293316 -335.951174)
			(xy 371.268244 -335.951576) (xy 371.243174 -335.951158) (xy 371.193491 -335.944406) (xy 371.145157 -335.931071)
			(xy 371.12194 -335.921604) (xy 371.108362 -335.916358) (xy 371.079462 -335.912991) (xy 371.050783 -335.917901)
			(xy 371.024648 -335.93069) (xy 371.003174 -335.950323) (xy 370.995194 -335.962498) (xy 370.980625 -335.985629)
			(xy 370.945782 -336.02775) (xy 370.905159 -336.064329) (xy 370.859628 -336.09458) (xy 370.810166 -336.117856)
			(xy 370.757835 -336.133656) (xy 370.703756 -336.141642) (xy 370.649092 -336.141642) (xy 370.595013 -336.133656)
			(xy 370.542682 -336.117856) (xy 370.49322 -336.09458) (xy 370.447689 -336.064329) (xy 370.407066 -336.02775)
			(xy 370.372223 -335.985629) (xy 370.357654 -335.962498) (xy 370.349753 -335.950258) (xy 370.328276 -335.930587)
			(xy 370.302116 -335.917784) (xy 370.273406 -335.912893) (xy 370.244483 -335.916312) (xy 370.230908 -335.921604)
			(xy 370.207694 -335.931084) (xy 370.159363 -335.944438) (xy 370.109675 -335.95117) (xy 370.084604 -335.951576)
			(xy 370.056714 -335.951165) (xy 370.001557 -335.942852) (xy 369.948254 -335.926411) (xy 369.897998 -335.902209)
			(xy 369.85191 -335.870788) (xy 369.81102 -335.832848) (xy 369.776242 -335.789237) (xy 369.748351 -335.74093)
			(xy 369.727972 -335.689006) (xy 369.71556 -335.634624) (xy 369.711391 -335.579) (xy 365.304488 -335.579)
			(xy 365.318966 -335.62831) (xy 365.326722 -335.682261) (xy 365.327184 -335.709514) (xy 365.326665 -335.737087)
			(xy 365.318724 -335.791657) (xy 365.30301 -335.844517) (xy 365.27985 -335.894563) (xy 365.249727 -335.940754)
			(xy 365.213267 -335.982127) (xy 365.192564 -336.000344) (xy 365.181647 -336.010225) (xy 365.165566 -336.034878)
			(xy 365.157178 -336.063092) (xy 365.157181 -336.092526) (xy 365.165573 -336.120739) (xy 365.181659 -336.145388)
			(xy 365.192564 -336.155284) (xy 365.213285 -336.173484) (xy 365.249752 -336.214856) (xy 365.279881 -336.261047)
			(xy 365.303045 -336.311096) (xy 365.318761 -336.363959) (xy 365.326701 -336.418534) (xy 365.326699 -336.473684)
			(xy 365.318757 -336.528258) (xy 365.303039 -336.581121) (xy 365.279872 -336.631168) (xy 365.249741 -336.677359)
			(xy 365.213272 -336.718729) (xy 365.192564 -336.736944) (xy 365.181647 -336.746825) (xy 365.165566 -336.771478)
			(xy 365.157178 -336.799692) (xy 365.157181 -336.829126) (xy 365.165573 -336.857339) (xy 365.181659 -336.881988)
			(xy 365.192564 -336.891884) (xy 365.213263 -336.910108) (xy 365.249736 -336.951473) (xy 365.279871 -336.99766)
			(xy 365.303039 -337.047706) (xy 365.318757 -337.100566) (xy 365.326698 -337.15514) (xy 365.327184 -337.182714)
			(xy 365.326758 -337.209968) (xy 365.318999 -337.263922) (xy 365.312332 -337.286625) (xy 365.717275 -337.286625)
			(xy 365.717279 -337.232123) (xy 365.725039 -337.178175) (xy 365.740398 -337.125881) (xy 365.763043 -337.076305)
			(xy 365.792513 -337.030457) (xy 365.828207 -336.989269) (xy 365.8694 -336.95358) (xy 365.915253 -336.924117)
			(xy 365.964832 -336.901479) (xy 366.017128 -336.886128) (xy 366.071077 -336.878375) (xy 366.098328 -336.877914)
			(xy 366.113057 -336.878063) (xy 366.142427 -336.880351) (xy 366.157002 -336.882486) (xy 366.171557 -336.88423)
			(xy 366.200601 -336.880377) (xy 366.227353 -336.86843) (xy 366.249607 -336.849374) (xy 366.265529 -336.82478)
			(xy 366.273806 -336.796675) (xy 366.273755 -336.767376) (xy 366.270032 -336.7532) (xy 366.262676 -336.726691)
			(xy 366.254769 -336.672249) (xy 366.254284 -336.644742) (xy 366.25471 -336.617485) (xy 366.262462 -336.563526)
			(xy 366.277815 -336.511219) (xy 366.300456 -336.46163) (xy 366.329924 -336.415768) (xy 366.365619 -336.374566)
			(xy 366.406814 -336.338864) (xy 366.452671 -336.309388) (xy 366.502256 -336.286739) (xy 366.55456 -336.271377)
			(xy 366.608518 -336.263615) (xy 366.663031 -336.263611) (xy 366.71699 -336.271366) (xy 366.769296 -336.286721)
			(xy 366.818885 -336.309364) (xy 366.864745 -336.338834) (xy 366.905946 -336.37453) (xy 366.941646 -336.415727)
			(xy 366.97112 -336.461586) (xy 366.993767 -336.511172) (xy 367.009127 -336.563476) (xy 367.016886 -336.617435)
			(xy 367.016888 -336.671948) (xy 367.009131 -336.725907) (xy 366.993773 -336.778212) (xy 366.971128 -336.827799)
			(xy 366.941656 -336.873659) (xy 366.905958 -336.914857) (xy 366.864759 -336.950556) (xy 366.8189 -336.980028)
			(xy 366.769313 -337.002673) (xy 366.717007 -337.01803) (xy 366.663049 -337.025788) (xy 366.635792 -337.02625)
			(xy 366.621063 -337.026099) (xy 366.591693 -337.023813) (xy 366.577118 -337.021678) (xy 366.562577 -337.019774)
			(xy 366.533512 -337.023648) (xy 366.506747 -337.03562) (xy 366.484486 -337.054704) (xy 366.468564 -337.079326)
			(xy 366.460293 -337.107457) (xy 366.460356 -337.136778) (xy 366.464088 -337.150964) (xy 366.471458 -337.17747)
			(xy 366.479357 -337.231915) (xy 366.479836 -337.259422) (xy 366.479321 -337.286673) (xy 366.471561 -337.340621)
			(xy 366.456203 -337.392915) (xy 366.433559 -337.442491) (xy 366.40409 -337.48834) (xy 366.368396 -337.529528)
			(xy 366.327203 -337.565217) (xy 366.281351 -337.594681) (xy 366.231772 -337.617319) (xy 366.179476 -337.632671)
			(xy 366.125527 -337.640424) (xy 366.071025 -337.640421) (xy 366.017077 -337.632661) (xy 365.964783 -337.617302)
			(xy 365.915207 -337.594658) (xy 365.869358 -337.565189) (xy 365.82817 -337.529494) (xy 365.792481 -337.488301)
			(xy 365.763018 -337.442449) (xy 365.74038 -337.39287) (xy 365.725028 -337.340574) (xy 365.717275 -337.286625)
			(xy 365.312332 -337.286625) (xy 365.30364 -337.316222) (xy 365.280994 -337.365804) (xy 365.251522 -337.411658)
			(xy 365.215824 -337.452851) (xy 365.174628 -337.488545) (xy 365.12877 -337.518012) (xy 365.079186 -337.540653)
			(xy 365.026885 -337.556007) (xy 364.97293 -337.563761) (xy 364.945676 -337.564222) (xy 364.917821 -337.563704)
			(xy 364.862706 -337.555578) (xy 364.809356 -337.53953) (xy 364.758904 -337.515902) (xy 364.71242 -337.485194)
			(xy 364.670891 -337.448059) (xy 364.635198 -337.405284) (xy 364.606098 -337.357777) (xy 364.584209 -337.306547)
			(xy 364.576614 -337.279742) (xy 364.572272 -337.26565) (xy 364.556899 -337.240508) (xy 364.534998 -337.22079)
			(xy 364.508385 -337.208132) (xy 364.479268 -337.203584) (xy 364.4646 -337.205066) (xy 364.451647 -337.206728)
			(xy 364.425589 -337.208508) (xy 364.41253 -337.208622) (xy 364.412276 -337.208622) (xy 364.398127 -337.208531)
			(xy 364.369904 -337.206495) (xy 364.355888 -337.204558) (xy 364.342533 -337.203057) (xy 364.315853 -337.206144)
			(xy 364.290907 -337.216099) (xy 364.26943 -337.232227) (xy 364.252916 -337.253409) (xy 364.242512 -337.278171)
			(xy 364.240318 -337.291426) (xy 364.236214 -337.318577) (xy 364.221244 -337.371407) (xy 364.198855 -337.421545)
			(xy 364.169509 -337.467956) (xy 364.133814 -337.509681) (xy 364.092506 -337.545858) (xy 364.046438 -337.57574)
			(xy 363.996563 -337.598709) (xy 363.94391 -337.614291) (xy 363.889567 -337.622164) (xy 363.862112 -337.622642)
			(xy 363.834863 -337.622111) (xy 363.780918 -337.614357) (xy 363.728627 -337.599005) (xy 363.679052 -337.576368)
			(xy 363.633203 -337.546906) (xy 363.592014 -337.511219) (xy 363.556322 -337.470034) (xy 363.526855 -337.424189)
			(xy 363.504211 -337.374617) (xy 363.488853 -337.322327) (xy 363.481093 -337.268383) (xy 363.480604 -337.241134)
			(xy 363.481092 -337.21356) (xy 363.48904 -337.158988) (xy 363.50476 -337.106129) (xy 363.527926 -337.056083)
			(xy 363.558055 -337.009893) (xy 363.594519 -336.96852) (xy 363.615224 -336.950304) (xy 363.626084 -336.940369)
			(xy 363.642154 -336.915728) (xy 363.650539 -336.887531) (xy 363.650546 -336.858113) (xy 363.642173 -336.829912)
			(xy 363.626114 -336.805264) (xy 363.615224 -336.795364) (xy 363.594497 -336.77717) (xy 363.558027 -336.735798)
			(xy 363.527896 -336.689605) (xy 363.504733 -336.639553) (xy 363.48902 -336.586688) (xy 363.481086 -336.53211)
			(xy 363.480604 -336.504534) (xy 363.481038 -336.478032) (xy 363.488387 -336.42554) (xy 363.502936 -336.374572)
			(xy 363.524404 -336.32611) (xy 363.552377 -336.281088) (xy 363.568996 -336.26044) (xy 363.578467 -336.248313)
			(xy 363.590263 -336.219907) (xy 363.593087 -336.189278) (xy 363.586685 -336.159193) (xy 363.571635 -336.132369)
			(xy 363.549295 -336.111226) (xy 363.535722 -336.103976) (xy 363.512025 -336.091888) (xy 363.468045 -336.061961)
			(xy 363.428765 -336.026086) (xy 363.394984 -335.984992) (xy 363.380782 -335.962498) (xy 363.372854 -335.950277)
			(xy 363.351384 -335.930606) (xy 363.325232 -335.917801) (xy 363.296528 -335.912905) (xy 363.26761 -335.916317)
			(xy 363.254036 -335.921604) (xy 363.230819 -335.931075) (xy 363.18249 -335.944433) (xy 363.132803 -335.951169)
			(xy 363.107732 -335.951576) (xy 363.082662 -335.951162) (xy 363.032979 -335.944408) (xy 362.984645 -335.931072)
			(xy 362.961428 -335.921604) (xy 362.947855 -335.916345) (xy 362.918952 -335.912981) (xy 362.890271 -335.917894)
			(xy 362.864136 -335.930686) (xy 362.842662 -335.950321) (xy 362.834682 -335.962498) (xy 362.820113 -335.985629)
			(xy 362.78527 -336.02775) (xy 362.744647 -336.064329) (xy 362.699116 -336.09458) (xy 362.649654 -336.117856)
			(xy 362.597323 -336.133656) (xy 362.543244 -336.141642) (xy 362.48858 -336.141642) (xy 362.434501 -336.133656)
			(xy 362.38217 -336.117856) (xy 362.332708 -336.09458) (xy 362.287177 -336.064329) (xy 362.246554 -336.02775)
			(xy 362.211711 -335.985629) (xy 362.197142 -335.962498) (xy 362.189252 -335.95025) (xy 362.167772 -335.930579)
			(xy 362.141609 -335.917777) (xy 362.112896 -335.912888) (xy 362.083971 -335.916311) (xy 362.070396 -335.921604)
			(xy 362.047184 -335.931087) (xy 361.998852 -335.944441) (xy 361.949163 -335.951171) (xy 361.924092 -335.951576)
			(xy 361.896204 -335.951138) (xy 361.841052 -335.942825) (xy 361.787755 -335.926384) (xy 361.737504 -335.902183)
			(xy 361.691421 -335.870763) (xy 361.650535 -335.832826) (xy 361.61576 -335.789219) (xy 361.587873 -335.740916)
			(xy 361.567497 -335.688996) (xy 361.555086 -335.634619) (xy 361.550917 -335.579) (xy 357.143976 -335.579)
			(xy 357.158454 -335.628311) (xy 357.16621 -335.682261) (xy 357.166672 -335.709514) (xy 357.166157 -335.737087)
			(xy 357.158216 -335.791658) (xy 357.142501 -335.844517) (xy 357.119341 -335.894564) (xy 357.089216 -335.940755)
			(xy 357.052756 -335.982127) (xy 357.032052 -336.000344) (xy 357.021136 -336.010226) (xy 357.005057 -336.034879)
			(xy 356.99667 -336.063092) (xy 356.996673 -336.092526) (xy 357.005064 -336.120738) (xy 357.021148 -336.145388)
			(xy 357.032052 -336.155284) (xy 357.052774 -336.173483) (xy 357.089241 -336.214855) (xy 357.119372 -336.261047)
			(xy 357.142536 -336.311096) (xy 357.158253 -336.363959) (xy 357.166193 -336.418534) (xy 357.166192 -336.473684)
			(xy 357.158249 -336.528259) (xy 357.14253 -336.581121) (xy 357.119363 -336.631169) (xy 357.08923 -336.67736)
			(xy 357.052761 -336.718729) (xy 357.032052 -336.736944) (xy 357.021136 -336.746826) (xy 357.005057 -336.771479)
			(xy 356.99667 -336.799692) (xy 356.996673 -336.829126) (xy 357.005064 -336.857338) (xy 357.021148 -336.881988)
			(xy 357.032052 -336.891884) (xy 357.052749 -336.910111) (xy 357.089222 -336.951475) (xy 357.119358 -336.997661)
			(xy 357.142526 -337.047706) (xy 357.158245 -337.100567) (xy 357.166186 -337.15514) (xy 357.166672 -337.182714)
			(xy 357.166258 -337.209969) (xy 357.160641 -337.249022) (xy 357.497106 -337.249022) (xy 357.49711 -337.194524)
			(xy 357.50487 -337.140581) (xy 357.520227 -337.088292) (xy 357.54287 -337.03872) (xy 357.572337 -336.992875)
			(xy 357.608029 -336.951691) (xy 357.649218 -336.916005) (xy 357.695067 -336.886545) (xy 357.744642 -336.863909)
			(xy 357.796933 -336.848559) (xy 357.850877 -336.840806) (xy 357.878126 -336.840322) (xy 357.903517 -336.840764)
			(xy 357.953848 -336.847513) (xy 357.978456 -336.853784) (xy 357.993101 -336.857224) (xy 358.023156 -336.856294)
			(xy 358.051639 -336.846659) (xy 358.076088 -336.829153) (xy 358.094384 -336.805291) (xy 358.104946 -336.777137)
			(xy 358.106859 -336.747129) (xy 358.103932 -336.732372) (xy 358.099173 -336.710842) (xy 358.094083 -336.667043)
			(xy 358.093772 -336.644996) (xy 358.093772 -336.644742) (xy 358.09421 -336.617485) (xy 358.101962 -336.563526)
			(xy 358.117315 -336.511219) (xy 358.139957 -336.461629) (xy 358.169425 -336.415767) (xy 358.20512 -336.374565)
			(xy 358.246316 -336.338863) (xy 358.292173 -336.309387) (xy 358.341759 -336.286738) (xy 358.394064 -336.271376)
			(xy 358.448022 -336.263615) (xy 358.502536 -336.263611) (xy 358.556495 -336.271367) (xy 358.608801 -336.286723)
			(xy 358.658389 -336.309366) (xy 358.70425 -336.338837) (xy 358.74545 -336.374535) (xy 358.78115 -336.415732)
			(xy 358.810623 -336.461592) (xy 358.83327 -336.511179) (xy 358.848628 -336.563484) (xy 358.856387 -336.617443)
			(xy 358.856387 -336.671956) (xy 358.848629 -336.725915) (xy 358.83327 -336.77822) (xy 358.810624 -336.827807)
			(xy 358.781151 -336.873667) (xy 358.745451 -336.914864) (xy 358.704251 -336.950562) (xy 358.65839 -336.980033)
			(xy 358.608802 -337.002677) (xy 358.556496 -337.018033) (xy 358.502537 -337.025788) (xy 358.47528 -337.02625)
			(xy 358.449889 -337.025807) (xy 358.399558 -337.019059) (xy 358.37495 -337.012788) (xy 358.360298 -337.009388)
			(xy 358.330251 -337.010317) (xy 358.301774 -337.019948) (xy 358.27733 -337.037447) (xy 358.259034 -337.061301)
			(xy 358.24847 -337.089446) (xy 358.246551 -337.119446) (xy 358.249474 -337.1342) (xy 358.254228 -337.155731)
			(xy 358.259321 -337.199529) (xy 358.259634 -337.221576) (xy 358.259634 -337.22183) (xy 358.25909 -337.249079)
			(xy 358.25133 -337.303022) (xy 358.235972 -337.355311) (xy 358.213328 -337.404882) (xy 358.183861 -337.450727)
			(xy 358.148169 -337.491911) (xy 358.10698 -337.527596) (xy 358.061131 -337.557057) (xy 358.011556 -337.579692)
			(xy 357.959264 -337.595042) (xy 357.90532 -337.602794) (xy 357.850822 -337.60279) (xy 357.79688 -337.59503)
			(xy 357.74459 -337.579672) (xy 357.695019 -337.557029) (xy 357.649174 -337.527562) (xy 357.60799 -337.49187)
			(xy 357.572305 -337.450681) (xy 357.542844 -337.404832) (xy 357.520208 -337.355257) (xy 357.504858 -337.302966)
			(xy 357.497106 -337.249022) (xy 357.160641 -337.249022) (xy 357.158498 -337.263923) (xy 357.143139 -337.316225)
			(xy 357.120492 -337.365807) (xy 357.091019 -337.411662) (xy 357.05532 -337.452855) (xy 357.014122 -337.488549)
			(xy 356.968263 -337.518016) (xy 356.918678 -337.540656) (xy 356.866375 -337.556009) (xy 356.812419 -337.563762)
			(xy 356.785164 -337.564222) (xy 356.757309 -337.563715) (xy 356.702193 -337.555587) (xy 356.648843 -337.539538)
			(xy 356.598391 -337.515908) (xy 356.551907 -337.485199) (xy 356.510378 -337.448062) (xy 356.474685 -337.405286)
			(xy 356.445586 -337.357779) (xy 356.423697 -337.306547) (xy 356.416102 -337.279742) (xy 356.411772 -337.265645)
			(xy 356.396397 -337.240502) (xy 356.374492 -337.220784) (xy 356.347876 -337.208128) (xy 356.318757 -337.203582)
			(xy 356.304088 -337.205066) (xy 356.291135 -337.206729) (xy 356.265077 -337.208508) (xy 356.252018 -337.208622)
			(xy 356.251764 -337.208622) (xy 356.237615 -337.208532) (xy 356.209392 -337.206495) (xy 356.195376 -337.204558)
			(xy 356.182023 -337.203045) (xy 356.155341 -337.206135) (xy 356.130394 -337.216092) (xy 356.108917 -337.232223)
			(xy 356.092403 -337.253406) (xy 356.082 -337.27817) (xy 356.079806 -337.291426) (xy 356.075714 -337.318579)
			(xy 356.060743 -337.37141) (xy 356.038353 -337.421549) (xy 356.009006 -337.46796) (xy 355.973309 -337.509686)
			(xy 355.932 -337.545862) (xy 355.885931 -337.575744) (xy 355.836054 -337.598712) (xy 355.7834 -337.614293)
			(xy 355.729056 -337.622165) (xy 355.7016 -337.622642) (xy 355.67435 -337.622122) (xy 355.620406 -337.614367)
			(xy 355.568114 -337.599013) (xy 355.518539 -337.576375) (xy 355.47269 -337.546911) (xy 355.4315 -337.511224)
			(xy 355.395809 -337.470037) (xy 355.366342 -337.424191) (xy 355.343699 -337.374618) (xy 355.328341 -337.322328)
			(xy 355.32058 -337.268384) (xy 355.320092 -337.241134) (xy 355.320584 -337.21356) (xy 355.328531 -337.158989)
			(xy 355.344252 -337.10613) (xy 355.367417 -337.056084) (xy 355.397544 -337.009893) (xy 355.434007 -336.968521)
			(xy 355.454712 -336.950304) (xy 355.465574 -336.94037) (xy 355.481645 -336.915729) (xy 355.490031 -336.887531)
			(xy 355.490038 -336.858113) (xy 355.481664 -336.829911) (xy 355.465603 -336.805263) (xy 355.454712 -336.795364)
			(xy 355.433983 -336.777173) (xy 355.397513 -336.7358) (xy 355.367383 -336.689606) (xy 355.34422 -336.639554)
			(xy 355.328508 -336.586688) (xy 355.320574 -336.53211) (xy 355.320092 -336.504534) (xy 355.320528 -336.478032)
			(xy 355.327878 -336.425541) (xy 355.342426 -336.374573) (xy 355.363893 -336.326111) (xy 355.391865 -336.281089)
			(xy 355.408484 -336.26044) (xy 355.417925 -336.248295) (xy 355.429707 -336.219894) (xy 355.432526 -336.189276)
			(xy 355.42613 -336.159201) (xy 355.411094 -336.13238) (xy 355.388774 -336.111232) (xy 355.37521 -336.103976)
			(xy 355.351511 -336.091892) (xy 355.307531 -336.061963) (xy 355.268253 -336.026087) (xy 355.234472 -335.984992)
			(xy 355.22027 -335.962498) (xy 355.212354 -335.950269) (xy 355.19088 -335.930598) (xy 355.164725 -335.917794)
			(xy 355.136018 -335.9129) (xy 355.107098 -335.916315) (xy 355.093524 -335.921604) (xy 355.070308 -335.931079)
			(xy 355.021978 -335.944435) (xy 354.972291 -335.951169) (xy 354.94722 -335.951576) (xy 354.922151 -335.951133)
			(xy 354.872469 -335.944392) (xy 354.824134 -335.931066) (xy 354.800916 -335.921604) (xy 354.787324 -335.916389)
			(xy 354.758423 -335.913003) (xy 354.729739 -335.917897) (xy 354.703596 -335.930674) (xy 354.682112 -335.950299)
			(xy 354.67417 -335.962498) (xy 354.659601 -335.985629) (xy 354.624758 -336.02775) (xy 354.584135 -336.064329)
			(xy 354.538604 -336.09458) (xy 354.489142 -336.117856) (xy 354.436811 -336.133656) (xy 354.382732 -336.141642)
			(xy 354.328068 -336.141642) (xy 354.273989 -336.133656) (xy 354.221658 -336.117856) (xy 354.172196 -336.09458)
			(xy 354.126665 -336.064329) (xy 354.086042 -336.02775) (xy 354.051199 -335.985629) (xy 354.03663 -335.962498)
			(xy 354.028751 -335.950242) (xy 354.007268 -335.93057) (xy 353.981103 -335.91777) (xy 353.952387 -335.912884)
			(xy 353.92346 -335.916309) (xy 353.909884 -335.921604) (xy 353.886673 -335.931091) (xy 353.838341 -335.944443)
			(xy 353.788652 -335.951172) (xy 353.76358 -335.951576) (xy 353.735693 -335.951138) (xy 353.680542 -335.942822)
			(xy 353.627247 -335.92638) (xy 353.576997 -335.902179) (xy 353.530916 -335.870759) (xy 353.490031 -335.832822)
			(xy 353.455258 -335.789215) (xy 353.427372 -335.740913) (xy 353.406996 -335.688994) (xy 353.394585 -335.634618)
			(xy 353.390417 -335.579) (xy 348.983463 -335.579) (xy 348.997942 -335.628312) (xy 349.005698 -335.682262)
			(xy 349.00616 -335.709514) (xy 349.005649 -335.737087) (xy 348.997708 -335.791659) (xy 348.981993 -335.844518)
			(xy 348.958831 -335.894565) (xy 348.928706 -335.940755) (xy 348.892245 -335.982128) (xy 348.87154 -336.000344)
			(xy 348.860626 -336.010227) (xy 348.844548 -336.03488) (xy 348.836162 -336.063093) (xy 348.836165 -336.092525)
			(xy 348.844555 -336.120737) (xy 348.860638 -336.145387) (xy 348.87154 -336.155284) (xy 348.892262 -336.173483)
			(xy 348.928731 -336.214854) (xy 348.958862 -336.261046) (xy 348.982028 -336.311095) (xy 348.997745 -336.363958)
			(xy 349.005685 -336.418534) (xy 349.005684 -336.473684) (xy 348.997741 -336.52826) (xy 348.982021 -336.581122)
			(xy 348.958854 -336.63117) (xy 348.92872 -336.67736) (xy 348.892249 -336.71873) (xy 348.87154 -336.736944)
			(xy 348.860626 -336.746827) (xy 348.844548 -336.77148) (xy 348.836162 -336.799693) (xy 348.836165 -336.829125)
			(xy 348.844555 -336.857337) (xy 348.860638 -336.881987) (xy 348.87154 -336.891884) (xy 348.892255 -336.910091)
			(xy 348.928723 -336.951462) (xy 348.958854 -336.997653) (xy 348.982018 -337.047701) (xy 348.997735 -337.100564)
			(xy 349.005674 -337.155139) (xy 349.00616 -337.182714) (xy 349.005758 -337.209969) (xy 349.00376 -337.223862)
			(xy 349.430848 -337.223862) (xy 349.431342 -337.196612) (xy 349.439103 -337.142667) (xy 349.454461 -337.090375)
			(xy 349.477103 -337.0408) (xy 349.506569 -336.994952) (xy 349.542259 -336.953764) (xy 349.583447 -336.918073)
			(xy 349.629295 -336.888606) (xy 349.678869 -336.865963) (xy 349.731161 -336.850604) (xy 349.785106 -336.842843)
			(xy 349.812356 -336.842354) (xy 349.83547 -336.843116) (xy 349.848795 -336.843542) (xy 349.874897 -336.838144)
			(xy 349.898719 -336.826187) (xy 349.918644 -336.808483) (xy 349.933321 -336.786233) (xy 349.941752 -336.760947)
			(xy 349.943367 -336.734342) (xy 349.941134 -336.721196) (xy 349.937481 -336.702293) (xy 349.933539 -336.663993)
			(xy 349.93326 -336.644742) (xy 349.933794 -336.617492) (xy 349.941545 -336.563545) (xy 349.956894 -336.51125)
			(xy 349.979529 -336.461672) (xy 350.00899 -336.415821) (xy 350.044676 -336.374628) (xy 350.085861 -336.338934)
			(xy 350.131707 -336.309465) (xy 350.181281 -336.28682) (xy 350.233573 -336.27146) (xy 350.287518 -336.2637)
			(xy 350.314768 -336.263234) (xy 350.342022 -336.263685) (xy 350.395976 -336.271439) (xy 350.448276 -336.286793)
			(xy 350.497859 -336.309435) (xy 350.543714 -336.338903) (xy 350.584908 -336.374599) (xy 350.620603 -336.415794)
			(xy 350.65007 -336.46165) (xy 350.67271 -336.511233) (xy 350.688063 -336.563534) (xy 350.695816 -336.617488)
			(xy 350.696276 -336.644742) (xy 350.695861 -336.671996) (xy 350.688098 -336.725948) (xy 350.672736 -336.778246)
			(xy 350.650088 -336.827825) (xy 350.620614 -336.873677) (xy 350.584915 -336.914868) (xy 350.543718 -336.950558)
			(xy 350.49786 -336.980023) (xy 350.448276 -337.002662) (xy 350.395975 -337.018014) (xy 350.342022 -337.025766)
			(xy 350.314768 -337.02625) (xy 350.291654 -337.025488) (xy 350.278329 -337.025079) (xy 350.252227 -337.030472)
			(xy 350.228404 -337.042425) (xy 350.208478 -337.060126) (xy 350.193801 -337.082374) (xy 350.18537 -337.107659)
			(xy 350.183757 -337.134263) (xy 350.18599 -337.147408) (xy 350.189644 -337.166311) (xy 350.193585 -337.204611)
			(xy 350.193864 -337.223862) (xy 350.193409 -337.251116) (xy 350.185656 -337.305069) (xy 350.170303 -337.35737)
			(xy 350.147662 -337.406953) (xy 350.118193 -337.452809) (xy 350.082499 -337.494003) (xy 350.041304 -337.529697)
			(xy 349.995448 -337.559164) (xy 349.945865 -337.581805) (xy 349.893564 -337.597158) (xy 349.83961 -337.60491)
			(xy 349.812356 -337.60537) (xy 349.785102 -337.604963) (xy 349.731149 -337.5972) (xy 349.678851 -337.581837)
			(xy 349.629271 -337.559188) (xy 349.583419 -337.529713) (xy 349.542228 -337.494014) (xy 349.506537 -337.452815)
			(xy 349.477073 -337.406957) (xy 349.454434 -337.357372) (xy 349.439083 -337.30507) (xy 349.431331 -337.251116)
			(xy 349.430848 -337.223862) (xy 349.00376 -337.223862) (xy 348.997998 -337.263925) (xy 348.982638 -337.316227)
			(xy 348.95999 -337.365811) (xy 348.930516 -337.411666) (xy 348.894816 -337.45286) (xy 348.853616 -337.488553)
			(xy 348.807756 -337.51802) (xy 348.758169 -337.540659) (xy 348.705864 -337.556011) (xy 348.651907 -337.563762)
			(xy 348.624652 -337.564222) (xy 348.596796 -337.563726) (xy 348.54168 -337.555596) (xy 348.48833 -337.539545)
			(xy 348.437878 -337.515914) (xy 348.391394 -337.485204) (xy 348.349865 -337.448066) (xy 348.314173 -337.405289)
			(xy 348.285073 -337.35778) (xy 348.263185 -337.306548) (xy 348.25559 -337.279742) (xy 348.251272 -337.265641)
			(xy 348.235894 -337.240497) (xy 348.213987 -337.220779) (xy 348.187368 -337.208124) (xy 348.158246 -337.203581)
			(xy 348.143576 -337.205066) (xy 348.130623 -337.20673) (xy 348.104565 -337.208509) (xy 348.091506 -337.208622)
			(xy 348.091252 -337.208622) (xy 348.077103 -337.208522) (xy 348.04888 -337.206492) (xy 348.034864 -337.204558)
			(xy 348.021512 -337.203033) (xy 347.994829 -337.206126) (xy 347.969882 -337.216085) (xy 347.948405 -337.232218)
			(xy 347.931891 -337.253404) (xy 347.921488 -337.278169) (xy 347.919294 -337.291426) (xy 347.915213 -337.318581)
			(xy 347.900242 -337.371413) (xy 347.877851 -337.421553) (xy 347.848503 -337.467965) (xy 347.812805 -337.50969)
			(xy 347.771494 -337.545867) (xy 347.725423 -337.575748) (xy 347.675545 -337.598715) (xy 347.622889 -337.614295)
			(xy 347.568544 -337.622166) (xy 347.541088 -337.622642) (xy 347.513838 -337.622133) (xy 347.459893 -337.614376)
			(xy 347.407601 -337.599021) (xy 347.358026 -337.576381) (xy 347.312177 -337.546917) (xy 347.270988 -337.511228)
			(xy 347.235296 -337.470041) (xy 347.205829 -337.424194) (xy 347.183186 -337.37462) (xy 347.167828 -337.322329)
			(xy 347.160068 -337.268384) (xy 347.15958 -337.241134) (xy 345.016538 -337.241134) (xy 345.029813 -337.270201)
			(xy 345.045169 -337.322496) (xy 345.052926 -337.376443) (xy 345.053412 -337.403694) (xy 345.053412 -337.403948)
			(xy 345.05284 -337.433787) (xy 345.043522 -337.492733) (xy 345.03487 -337.521296) (xy 345.030926 -337.535227)
			(xy 345.030004 -337.564145) (xy 345.037252 -337.592155) (xy 345.052087 -337.616995) (xy 345.073309 -337.63666)
			(xy 345.099206 -337.649562) (xy 345.113356 -337.652614) (xy 345.139432 -337.657766) (xy 345.189936 -337.674341)
			(xy 345.237648 -337.697767) (xy 345.281646 -337.727591) (xy 345.321075 -337.763236) (xy 345.355174 -337.804011)
			(xy 345.38328 -337.849126) (xy 345.404849 -337.897706) (xy 345.419464 -337.94881) (xy 345.426841 -338.001449)
			(xy 345.4273 -338.028026) (xy 345.426814 -338.055277) (xy 345.419058 -338.109225) (xy 345.403703 -338.16152)
			(xy 345.381061 -338.211097) (xy 345.363554 -338.238338) (xy 350.739456 -338.238338) (xy 350.740016 -338.20865)
			(xy 350.749211 -338.14999) (xy 350.767383 -338.093463) (xy 350.794096 -338.040435) (xy 350.828702 -337.992186)
			(xy 350.870366 -337.949883) (xy 350.893888 -337.93176) (xy 350.904471 -337.923305) (xy 350.921181 -337.902)
			(xy 350.931703 -337.877052) (xy 350.935297 -337.850216) (xy 350.931711 -337.823378) (xy 350.921197 -337.798427)
			(xy 350.904493 -337.777117) (xy 350.893888 -337.768692) (xy 350.870371 -337.750564) (xy 350.828712 -337.708258)
			(xy 350.794108 -337.66001) (xy 350.767397 -337.606983) (xy 350.749222 -337.550459) (xy 350.740022 -337.491801)
			(xy 350.739456 -337.462114) (xy 350.739942 -337.434863) (xy 350.747698 -337.380915) (xy 350.763053 -337.32862)
			(xy 350.785695 -337.279043) (xy 350.815161 -337.233193) (xy 350.850852 -337.192002) (xy 350.892043 -337.156311)
			(xy 350.937893 -337.126845) (xy 350.98747 -337.104203) (xy 351.039765 -337.088848) (xy 351.093713 -337.081092)
			(xy 351.148215 -337.081092) (xy 351.202163 -337.088848) (xy 351.254458 -337.104203) (xy 351.304035 -337.126845)
			(xy 351.349885 -337.156311) (xy 351.391076 -337.192002) (xy 351.426767 -337.233193) (xy 351.456233 -337.279043)
			(xy 351.478875 -337.32862) (xy 351.49423 -337.380915) (xy 351.501986 -337.434863) (xy 351.502472 -337.462114)
			(xy 351.501938 -337.491803) (xy 351.492737 -337.550464) (xy 351.474558 -337.60699) (xy 351.447841 -337.660018)
			(xy 351.435765 -337.676852) (xy 351.755944 -337.676852) (xy 351.755944 -337.622348) (xy 351.7637 -337.568399)
			(xy 351.779055 -337.516102) (xy 351.801695 -337.466523) (xy 351.831161 -337.42067) (xy 351.866852 -337.379477)
			(xy 351.908041 -337.343782) (xy 351.953891 -337.314313) (xy 352.003468 -337.291667) (xy 352.055763 -337.276308)
			(xy 352.109712 -337.268546) (xy 352.136964 -337.268058) (xy 352.137218 -337.268058) (xy 352.162422 -337.268447)
			(xy 352.21239 -337.27509) (xy 352.261045 -337.288269) (xy 352.307534 -337.307755) (xy 352.329496 -337.320128)
			(xy 352.342471 -337.327148) (xy 352.371104 -337.334189) (xy 352.400555 -337.332749) (xy 352.428366 -337.322951)
			(xy 352.452214 -337.30561) (xy 352.47011 -337.282176) (xy 352.4758 -337.268566) (xy 352.486461 -337.241775)
			(xy 352.514755 -337.191533) (xy 352.55029 -337.146124) (xy 352.592257 -337.106583) (xy 352.639699 -337.073811)
			(xy 352.691535 -337.048556) (xy 352.746582 -337.031393) (xy 352.803586 -337.022714) (xy 352.832416 -337.022186)
			(xy 352.859667 -337.022663) (xy 352.913615 -337.030421) (xy 352.96591 -337.045778) (xy 353.015487 -337.068421)
			(xy 353.061337 -337.097888) (xy 353.102526 -337.133581) (xy 353.138218 -337.174771) (xy 353.167684 -337.220622)
			(xy 353.190325 -337.2702) (xy 353.205681 -337.322495) (xy 353.213438 -337.376443) (xy 353.213924 -337.403694)
			(xy 353.213924 -337.403948) (xy 353.213352 -337.433787) (xy 353.204034 -337.492733) (xy 353.195382 -337.521296)
			(xy 353.191429 -337.535225) (xy 353.190506 -337.564145) (xy 353.197755 -337.592157) (xy 353.212592 -337.616998)
			(xy 353.233817 -337.636663) (xy 353.259717 -337.649563) (xy 353.273868 -337.652614) (xy 353.299946 -337.657757)
			(xy 353.350449 -337.674333) (xy 353.398162 -337.697761) (xy 353.442159 -337.727587) (xy 353.481589 -337.763233)
			(xy 353.515687 -337.804008) (xy 353.543792 -337.849124) (xy 353.565362 -337.897704) (xy 353.579976 -337.94881)
			(xy 353.587353 -338.001449) (xy 353.587812 -338.028026) (xy 353.587326 -338.055277) (xy 353.57957 -338.109225)
			(xy 353.564215 -338.16152) (xy 353.541573 -338.211097) (xy 353.524066 -338.238338) (xy 358.899968 -338.238338)
			(xy 358.900524 -338.20865) (xy 358.909719 -338.149989) (xy 358.927892 -338.093462) (xy 358.954605 -338.040434)
			(xy 358.989212 -337.992186) (xy 359.030878 -337.949883) (xy 359.0544 -337.93176) (xy 359.064982 -337.923304)
			(xy 359.08169 -337.901999) (xy 359.092211 -337.877051) (xy 359.095804 -337.850216) (xy 359.092219 -337.823379)
			(xy 359.081706 -337.798428) (xy 359.065004 -337.777118) (xy 359.0544 -337.768692) (xy 359.030886 -337.750561)
			(xy 358.989225 -337.708256) (xy 358.954621 -337.660008) (xy 358.927909 -337.606982) (xy 358.909734 -337.550458)
			(xy 358.900534 -337.491801) (xy 358.899968 -337.462114) (xy 358.900454 -337.434863) (xy 358.90821 -337.380915)
			(xy 358.923565 -337.32862) (xy 358.946207 -337.279043) (xy 358.975673 -337.233193) (xy 359.011364 -337.192002)
			(xy 359.052555 -337.156311) (xy 359.098405 -337.126845) (xy 359.147982 -337.104203) (xy 359.200277 -337.088848)
			(xy 359.254225 -337.081092) (xy 359.308727 -337.081092) (xy 359.362675 -337.088848) (xy 359.41497 -337.104203)
			(xy 359.464547 -337.126845) (xy 359.510397 -337.156311) (xy 359.551588 -337.192002) (xy 359.587279 -337.233193)
			(xy 359.616745 -337.279043) (xy 359.639387 -337.32862) (xy 359.654742 -337.380915) (xy 359.662498 -337.434863)
			(xy 359.662984 -337.462114) (xy 359.662446 -337.491803) (xy 359.653244 -337.550463) (xy 359.635066 -337.606989)
			(xy 359.60835 -337.660017) (xy 359.596273 -337.676853) (xy 359.916444 -337.676853) (xy 359.916444 -337.622347)
			(xy 359.9242 -337.568397) (xy 359.939556 -337.516099) (xy 359.962197 -337.466519) (xy 359.991664 -337.420666)
			(xy 360.027356 -337.379473) (xy 360.068547 -337.343778) (xy 360.114398 -337.314309) (xy 360.163977 -337.291664)
			(xy 360.216274 -337.276305) (xy 360.270223 -337.268546) (xy 360.297476 -337.268058) (xy 360.29773 -337.268058)
			(xy 360.322934 -337.268442) (xy 360.372903 -337.275086) (xy 360.421557 -337.288267) (xy 360.468047 -337.307754)
			(xy 360.490008 -337.320128) (xy 360.502976 -337.327162) (xy 360.531612 -337.334201) (xy 360.561065 -337.332759)
			(xy 360.588877 -337.322957) (xy 360.612726 -337.305614) (xy 360.630622 -337.282177) (xy 360.636312 -337.268566)
			(xy 360.646963 -337.241771) (xy 360.675258 -337.191528) (xy 360.710794 -337.146119) (xy 360.752763 -337.106578)
			(xy 360.800207 -337.073806) (xy 360.852044 -337.048552) (xy 360.907092 -337.03139) (xy 360.964097 -337.022713)
			(xy 360.992928 -337.022186) (xy 361.02018 -337.022652) (xy 361.074128 -337.030412) (xy 361.126423 -337.04577)
			(xy 361.175999 -337.068414) (xy 361.221849 -337.097883) (xy 361.263039 -337.133576) (xy 361.29873 -337.174768)
			(xy 361.328196 -337.22062) (xy 361.350837 -337.270198) (xy 361.366193 -337.322494) (xy 361.37395 -337.376442)
			(xy 361.374436 -337.403694) (xy 361.374436 -337.403948) (xy 361.373863 -337.433787) (xy 361.364546 -337.492733)
			(xy 361.355894 -337.521296) (xy 361.351931 -337.535223) (xy 361.351008 -337.564145) (xy 361.358258 -337.592159)
			(xy 361.373097 -337.617001) (xy 361.394325 -337.636666) (xy 361.420227 -337.649564) (xy 361.43438 -337.652614)
			(xy 361.460445 -337.657823) (xy 361.510948 -337.674387) (xy 361.558661 -337.697804) (xy 361.60266 -337.727621)
			(xy 361.642092 -337.763259) (xy 361.676192 -337.804028) (xy 361.704301 -337.849138) (xy 361.725872 -337.897714)
			(xy 361.740488 -337.948815) (xy 361.747865 -338.001451) (xy 361.748324 -338.028026) (xy 361.747838 -338.055277)
			(xy 361.740082 -338.109225) (xy 361.724727 -338.16152) (xy 361.702085 -338.211097) (xy 361.684578 -338.238338)
			(xy 367.06048 -338.238338) (xy 367.061071 -338.208651) (xy 367.070263 -338.149994) (xy 367.088432 -338.09347)
			(xy 367.115138 -338.040442) (xy 367.149738 -337.992192) (xy 367.191394 -337.949885) (xy 367.214912 -337.93176)
			(xy 367.225493 -337.923304) (xy 367.242199 -337.901998) (xy 367.252719 -337.877051) (xy 367.256312 -337.850216)
			(xy 367.252727 -337.82338) (xy 367.242215 -337.798429) (xy 367.225516 -337.777118) (xy 367.214912 -337.768692)
			(xy 367.1914 -337.750558) (xy 367.149739 -337.708254) (xy 367.115135 -337.660007) (xy 367.088422 -337.606981)
			(xy 367.070246 -337.550458) (xy 367.061046 -337.491801) (xy 367.06048 -337.462114) (xy 367.060966 -337.434863)
			(xy 367.068722 -337.380915) (xy 367.084077 -337.32862) (xy 367.106719 -337.279043) (xy 367.136185 -337.233193)
			(xy 367.171876 -337.192002) (xy 367.213067 -337.156311) (xy 367.258917 -337.126845) (xy 367.308494 -337.104203)
			(xy 367.360789 -337.088848) (xy 367.414737 -337.081092) (xy 367.469239 -337.081092) (xy 367.523187 -337.088848)
			(xy 367.575482 -337.104203) (xy 367.625059 -337.126845) (xy 367.670909 -337.156311) (xy 367.7121 -337.192002)
			(xy 367.747791 -337.233193) (xy 367.777257 -337.279043) (xy 367.799899 -337.32862) (xy 367.815254 -337.380915)
			(xy 367.82301 -337.434863) (xy 367.823496 -337.462114) (xy 367.822953 -337.491802) (xy 367.813752 -337.550462)
			(xy 367.795574 -337.606988) (xy 367.768859 -337.660016) (xy 367.756782 -337.676853) (xy 368.076944 -337.676853)
			(xy 368.076944 -337.622347) (xy 368.084701 -337.568395) (xy 368.100057 -337.516097) (xy 368.122699 -337.466516)
			(xy 368.152167 -337.420662) (xy 368.18786 -337.379469) (xy 368.229053 -337.343774) (xy 368.274906 -337.314305)
			(xy 368.324486 -337.291661) (xy 368.376784 -337.276303) (xy 368.430735 -337.268545) (xy 368.457988 -337.268058)
			(xy 368.458242 -337.268058) (xy 368.483446 -337.268437) (xy 368.533415 -337.275082) (xy 368.58207 -337.288265)
			(xy 368.628559 -337.307753) (xy 368.65052 -337.320128) (xy 368.66348 -337.327177) (xy 368.692119 -337.334213)
			(xy 368.721575 -337.332769) (xy 368.749388 -337.322964) (xy 368.773238 -337.305619) (xy 368.791135 -337.282179)
			(xy 368.796824 -337.268566) (xy 368.807549 -337.241802) (xy 368.835835 -337.191563) (xy 368.871361 -337.146155)
			(xy 368.913319 -337.106613) (xy 368.960752 -337.073838) (xy 369.012578 -337.048578) (xy 369.067617 -337.031408)
			(xy 369.124613 -337.022719) (xy 369.15344 -337.022186) (xy 369.180692 -337.022641) (xy 369.23464 -337.030402)
			(xy 369.286935 -337.045762) (xy 369.336512 -337.068408) (xy 369.382362 -337.097878) (xy 369.423552 -337.133572)
			(xy 369.459243 -337.174765) (xy 369.488709 -337.220617) (xy 369.51135 -337.270196) (xy 369.526705 -337.322493)
			(xy 369.534462 -337.376442) (xy 369.534948 -337.403694) (xy 369.534948 -337.403948) (xy 369.534375 -337.433787)
			(xy 369.526646 -337.482688) (xy 371.647212 -337.482688) (xy 371.647734 -337.455115) (xy 371.655675 -337.400545)
			(xy 371.671388 -337.347686) (xy 371.694547 -337.29764) (xy 371.72467 -337.251449) (xy 371.761129 -337.210075)
			(xy 371.781832 -337.191858) (xy 371.792738 -337.18197) (xy 371.808804 -337.157315) (xy 371.817183 -337.129106)
			(xy 371.817181 -337.099679) (xy 371.808798 -337.071471) (xy 371.792728 -337.046819) (xy 371.781832 -337.036918)
			(xy 371.761133 -337.018694) (xy 371.72466 -336.977329) (xy 371.694526 -336.931142) (xy 371.671358 -336.881096)
			(xy 371.655639 -336.828235) (xy 371.647698 -336.773662) (xy 371.647212 -336.746088) (xy 371.647644 -336.718834)
			(xy 371.655403 -336.664881) (xy 371.670761 -336.612581) (xy 371.693407 -336.562999) (xy 371.722878 -336.517145)
			(xy 371.758575 -336.475952) (xy 371.799771 -336.440259) (xy 371.845628 -336.410791) (xy 371.895211 -336.38815)
			(xy 371.947512 -336.372796) (xy 372.001466 -336.365041) (xy 372.02872 -336.36458) (xy 372.029482 -336.36458)
			(xy 372.041453 -336.364696) (xy 372.065346 -336.366219) (xy 372.077234 -336.367628) (xy 372.090996 -336.368863)
			(xy 372.118323 -336.364892) (xy 372.143589 -336.353747) (xy 372.164947 -336.336242) (xy 372.180837 -336.313657)
			(xy 372.190098 -336.287642) (xy 372.191534 -336.273902) (xy 372.194089 -336.24537) (xy 372.206571 -336.189465)
			(xy 372.227274 -336.136055) (xy 372.255732 -336.086344) (xy 372.291306 -336.041447) (xy 372.333195 -336.002377)
			(xy 372.380457 -335.970012) (xy 372.432028 -335.945079) (xy 372.486747 -335.92814) (xy 372.543385 -335.919577)
			(xy 372.572026 -335.919064) (xy 372.590045 -335.919286) (xy 372.62592 -335.922719) (xy 372.643654 -335.925922)
			(xy 372.658866 -335.928241) (xy 372.689419 -335.924725) (xy 372.71754 -335.91227) (xy 372.740676 -335.892007)
			(xy 372.756729 -335.865774) (xy 372.761002 -335.850992) (xy 372.768437 -335.823959) (xy 372.790061 -335.772233)
			(xy 372.819019 -335.724227) (xy 372.854689 -335.680974) (xy 372.896304 -335.643406) (xy 372.942967 -335.61233)
			(xy 372.993675 -335.588415) (xy 373.047335 -335.572177) (xy 373.102794 -335.563964) (xy 373.130826 -335.563464)
			(xy 373.158077 -335.563954) (xy 373.212023 -335.571713) (xy 373.264316 -335.58707) (xy 373.313891 -335.609712)
			(xy 373.35974 -335.639178) (xy 373.400929 -335.674869) (xy 373.43662 -335.716058) (xy 373.466087 -335.761907)
			(xy 373.488729 -335.811482) (xy 373.504087 -335.863775) (xy 373.511846 -335.917721) (xy 373.512334 -335.944972)
			(xy 373.511872 -335.972547) (xy 373.503922 -336.027121) (xy 373.488198 -336.079982) (xy 373.465027 -336.130028)
			(xy 373.434893 -336.176218) (xy 373.398423 -336.217587) (xy 373.377714 -336.235802) (xy 373.366844 -336.245729)
			(xy 373.350769 -336.27037) (xy 373.342381 -336.298571) (xy 373.342376 -336.327993) (xy 373.350753 -336.356197)
			(xy 373.36682 -336.380844) (xy 373.377714 -336.390742) (xy 373.398391 -336.408989) (xy 373.434853 -336.450357)
			(xy 373.464979 -336.496543) (xy 373.488141 -336.546586) (xy 373.503857 -336.599442) (xy 373.511799 -336.65401)
			(xy 373.511802 -336.709154) (xy 373.503865 -336.763723) (xy 373.488154 -336.81658) (xy 373.464997 -336.866625)
			(xy 373.434875 -336.912815) (xy 373.398417 -336.954186) (xy 373.377714 -336.972402) (xy 373.366844 -336.982329)
			(xy 373.350769 -337.00697) (xy 373.342381 -337.035171) (xy 373.342376 -337.064593) (xy 373.350753 -337.092797)
			(xy 373.36682 -337.117444) (xy 373.377714 -337.127342) (xy 373.398403 -337.145577) (xy 373.434875 -337.186941)
			(xy 373.465009 -337.233126) (xy 373.488179 -337.283169) (xy 373.5039 -337.336028) (xy 373.511845 -337.390599)
			(xy 373.512334 -337.418172) (xy 373.511819 -337.445423) (xy 373.504066 -337.499371) (xy 373.488715 -337.551666)
			(xy 373.466078 -337.601244) (xy 373.436615 -337.647096) (xy 373.400927 -337.688289) (xy 373.35974 -337.723983)
			(xy 373.313892 -337.753452) (xy 373.264317 -337.776096) (xy 373.212024 -337.791455) (xy 373.158077 -337.799215)
			(xy 373.130826 -337.79968) (xy 373.102971 -337.799148) (xy 373.047855 -337.791028) (xy 372.994504 -337.774985)
			(xy 372.944051 -337.75136) (xy 372.897566 -337.720654) (xy 372.856036 -337.683519) (xy 372.820343 -337.640744)
			(xy 372.791244 -337.593237) (xy 372.769358 -337.542005) (xy 372.761764 -337.5152) (xy 372.757496 -337.501082)
			(xy 372.742104 -337.475937) (xy 372.720184 -337.456222) (xy 372.693554 -337.443572) (xy 372.664424 -337.439035)
			(xy 372.64975 -337.440524) (xy 372.636923 -337.442176) (xy 372.61112 -337.443953) (xy 372.598188 -337.44408)
			(xy 372.597426 -337.44408) (xy 372.579795 -337.443842) (xy 372.544687 -337.440537) (xy 372.527322 -337.437476)
			(xy 372.513546 -337.435268) (xy 372.485761 -337.437711) (xy 372.459678 -337.447592) (xy 372.437249 -337.464172)
			(xy 372.420152 -337.48621) (xy 372.409666 -337.512056) (xy 372.407688 -337.525868) (xy 372.404033 -337.553442)
			(xy 372.389802 -337.607212) (xy 372.36791 -337.658344) (xy 372.338821 -337.705752) (xy 372.303152 -337.748431)
			(xy 372.261661 -337.785475) (xy 372.215229 -337.816097) (xy 372.16484 -337.839648) (xy 372.111563 -337.855628)
			(xy 372.056531 -337.863698) (xy 372.02872 -337.864196) (xy 372.001467 -337.863726) (xy 371.947516 -337.855971)
			(xy 371.895217 -337.840617) (xy 371.845636 -337.817976) (xy 371.799783 -337.788509) (xy 371.758589 -337.752816)
			(xy 371.722896 -337.711624) (xy 371.693428 -337.665771) (xy 371.670785 -337.61619) (xy 371.65543 -337.563892)
			(xy 371.647675 -337.509941) (xy 371.647212 -337.482688) (xy 369.526646 -337.482688) (xy 369.525058 -337.492733)
			(xy 369.516406 -337.521296) (xy 369.512434 -337.535221) (xy 369.51151 -337.564145) (xy 369.518761 -337.59216)
			(xy 369.533602 -337.617004) (xy 369.554832 -337.636669) (xy 369.580738 -337.649566) (xy 369.594892 -337.652614)
			(xy 369.620959 -337.657814) (xy 369.671462 -337.67438) (xy 369.719175 -337.697798) (xy 369.763174 -337.727617)
			(xy 369.802605 -337.763256) (xy 369.836705 -337.804026) (xy 369.864813 -337.849136) (xy 369.886384 -337.897713)
			(xy 369.901 -337.948814) (xy 369.908377 -338.001451) (xy 369.908836 -338.028026) (xy 369.90835 -338.055277)
			(xy 369.900594 -338.109225) (xy 369.885239 -338.16152) (xy 369.862597 -338.211097) (xy 369.833131 -338.256947)
			(xy 369.79744 -338.298138) (xy 369.756249 -338.333829) (xy 369.710399 -338.363295) (xy 369.660822 -338.385937)
			(xy 369.608527 -338.401292) (xy 369.554579 -338.409048) (xy 369.500077 -338.409048) (xy 369.446129 -338.401292)
			(xy 369.393834 -338.385937) (xy 369.344257 -338.363295) (xy 369.298407 -338.333829) (xy 369.257216 -338.298138)
			(xy 369.221525 -338.256947) (xy 369.192059 -338.211097) (xy 369.169417 -338.16152) (xy 369.154062 -338.109225)
			(xy 369.146306 -338.055277) (xy 369.14582 -338.028026) (xy 369.14582 -338.027772) (xy 369.146395 -337.997933)
			(xy 369.15571 -337.938987) (xy 369.164362 -337.910424) (xy 369.168449 -337.896528) (xy 369.169356 -337.867586)
			(xy 369.162084 -337.839558) (xy 369.147221 -337.814708) (xy 369.125967 -337.795042) (xy 369.10004 -337.78215)
			(xy 369.085876 -337.779106) (xy 369.053035 -337.77253) (xy 368.990184 -337.749402) (xy 368.960908 -337.733132)
			(xy 368.947922 -337.726137) (xy 368.919294 -337.719101) (xy 368.889849 -337.720539) (xy 368.862044 -337.730333)
			(xy 368.838197 -337.747665) (xy 368.820298 -337.771089) (xy 368.814604 -337.784694) (xy 368.803918 -337.811475)
			(xy 368.77563 -337.861718) (xy 368.740099 -337.907128) (xy 368.698136 -337.946671) (xy 368.650697 -337.979445)
			(xy 368.598864 -338.004702) (xy 368.543819 -338.021866) (xy 368.486817 -338.030546) (xy 368.457988 -338.031074)
			(xy 368.430735 -338.030655) (xy 368.376784 -338.022897) (xy 368.324486 -338.007539) (xy 368.274906 -337.984895)
			(xy 368.229053 -337.955426) (xy 368.18786 -337.919731) (xy 368.152167 -337.878538) (xy 368.122699 -337.832684)
			(xy 368.100057 -337.783103) (xy 368.084701 -337.730805) (xy 368.076944 -337.676853) (xy 367.756782 -337.676853)
			(xy 367.734251 -337.708264) (xy 367.692586 -337.750569) (xy 367.669064 -337.768692) (xy 367.658433 -337.77709)
			(xy 367.641731 -337.79841) (xy 367.631218 -337.82337) (xy 367.627632 -337.850216) (xy 367.631226 -337.87706)
			(xy 367.641747 -337.902017) (xy 367.658456 -337.923332) (xy 367.669064 -337.93176) (xy 367.692595 -337.94987)
			(xy 367.734256 -337.992178) (xy 367.76886 -338.04043) (xy 367.795569 -338.09346) (xy 367.81374 -338.149989)
			(xy 367.822934 -338.208649) (xy 367.823496 -338.238338) (xy 367.82301 -338.265589) (xy 367.815254 -338.319537)
			(xy 367.799899 -338.371832) (xy 367.777257 -338.421409) (xy 367.747791 -338.467259) (xy 367.7121 -338.50845)
			(xy 367.670909 -338.544141) (xy 367.625059 -338.573607) (xy 367.582767 -338.592922) (xy 373.623332 -338.592922)
			(xy 373.623332 -338.592668) (xy 373.623867 -338.564654) (xy 373.632086 -338.509233) (xy 373.648313 -338.455606)
			(xy 373.672201 -338.404926) (xy 373.703237 -338.358279) (xy 373.72163 -338.337144) (xy 373.731299 -338.325722)
			(xy 373.74407 -338.298671) (xy 373.748448 -338.269079) (xy 373.744057 -338.239489) (xy 373.731275 -338.212444)
			(xy 373.72163 -338.201) (xy 373.703193 -338.179896) (xy 373.672127 -338.133257) (xy 373.648227 -338.082572)
			(xy 373.632007 -338.028932) (xy 373.623818 -337.973495) (xy 373.623332 -337.945476) (xy 373.623332 -337.945222)
			(xy 373.623818 -337.917971) (xy 373.631574 -337.864023) (xy 373.646929 -337.811728) (xy 373.669571 -337.762151)
			(xy 373.699037 -337.716301) (xy 373.734728 -337.67511) (xy 373.775919 -337.639419) (xy 373.821769 -337.609953)
			(xy 373.871346 -337.587311) (xy 373.923641 -337.571956) (xy 373.977589 -337.5642) (xy 374.032091 -337.5642)
			(xy 374.086039 -337.571956) (xy 374.138334 -337.587311) (xy 374.187911 -337.609953) (xy 374.233761 -337.639419)
			(xy 374.274952 -337.67511) (xy 374.310643 -337.716301) (xy 374.340109 -337.762151) (xy 374.362751 -337.811728)
			(xy 374.378106 -337.864023) (xy 374.385862 -337.917971) (xy 374.386348 -337.945222) (xy 374.386348 -337.945476)
			(xy 374.385845 -337.973491) (xy 374.377619 -338.028914) (xy 374.361384 -338.082541) (xy 374.337489 -338.133221)
			(xy 374.306447 -338.179866) (xy 374.28805 -338.201) (xy 374.27843 -338.212462) (xy 374.265642 -338.239497)
			(xy 374.261249 -338.269079) (xy 374.26563 -338.298663) (xy 374.278406 -338.325704) (xy 374.28805 -338.337144)
			(xy 374.306457 -338.358273) (xy 374.337528 -338.404905) (xy 374.361434 -338.455584) (xy 374.37766 -338.509218)
			(xy 374.385857 -338.56465) (xy 374.386348 -338.592668) (xy 374.386348 -338.592922) (xy 374.385862 -338.620173)
			(xy 374.378106 -338.674121) (xy 374.362751 -338.726416) (xy 374.340109 -338.775993) (xy 374.310643 -338.821843)
			(xy 374.274952 -338.863034) (xy 374.233761 -338.898725) (xy 374.187911 -338.928191) (xy 374.138334 -338.950833)
			(xy 374.086039 -338.966188) (xy 374.032091 -338.973944) (xy 373.977589 -338.973944) (xy 373.923641 -338.966188)
			(xy 373.871346 -338.950833) (xy 373.821769 -338.928191) (xy 373.775919 -338.898725) (xy 373.734728 -338.863034)
			(xy 373.699037 -338.821843) (xy 373.669571 -338.775993) (xy 373.646929 -338.726416) (xy 373.631574 -338.674121)
			(xy 373.623818 -338.620173) (xy 373.623332 -338.592922) (xy 367.582767 -338.592922) (xy 367.575482 -338.596249)
			(xy 367.523187 -338.611604) (xy 367.469239 -338.61936) (xy 367.414737 -338.61936) (xy 367.360789 -338.611604)
			(xy 367.308494 -338.596249) (xy 367.258917 -338.573607) (xy 367.213067 -338.544141) (xy 367.171876 -338.50845)
			(xy 367.136185 -338.467259) (xy 367.106719 -338.421409) (xy 367.084077 -338.371832) (xy 367.068722 -338.319537)
			(xy 367.060966 -338.265589) (xy 367.06048 -338.238338) (xy 361.684578 -338.238338) (xy 361.672619 -338.256947)
			(xy 361.636928 -338.298138) (xy 361.595737 -338.333829) (xy 361.549887 -338.363295) (xy 361.50031 -338.385937)
			(xy 361.448015 -338.401292) (xy 361.394067 -338.409048) (xy 361.339565 -338.409048) (xy 361.285617 -338.401292)
			(xy 361.233322 -338.385937) (xy 361.183745 -338.363295) (xy 361.137895 -338.333829) (xy 361.096704 -338.298138)
			(xy 361.061013 -338.256947) (xy 361.031547 -338.211097) (xy 361.008905 -338.16152) (xy 360.99355 -338.109225)
			(xy 360.985794 -338.055277) (xy 360.985308 -338.028026) (xy 360.985308 -338.027772) (xy 360.985883 -337.997933)
			(xy 360.995199 -337.938987) (xy 361.00385 -337.910424) (xy 361.007868 -337.896513) (xy 361.008772 -337.867586)
			(xy 361.001506 -337.839571) (xy 360.986658 -337.814728) (xy 360.965424 -337.795062) (xy 360.939518 -337.782159)
			(xy 360.925364 -337.779106) (xy 360.892528 -337.772509) (xy 360.829674 -337.749396) (xy 360.800396 -337.733132)
			(xy 360.787417 -337.726123) (xy 360.758786 -337.719088) (xy 360.729339 -337.720529) (xy 360.701532 -337.730326)
			(xy 360.677684 -337.74766) (xy 360.659785 -337.771087) (xy 360.654092 -337.784694) (xy 360.643416 -337.811479)
			(xy 360.615127 -337.861723) (xy 360.579595 -337.907133) (xy 360.53763 -337.946676) (xy 360.49019 -337.979449)
			(xy 360.438355 -338.004705) (xy 360.383309 -338.021868) (xy 360.326306 -338.030547) (xy 360.297476 -338.031074)
			(xy 360.270223 -338.030654) (xy 360.216274 -338.022895) (xy 360.163977 -338.007536) (xy 360.114398 -337.984891)
			(xy 360.068547 -337.955422) (xy 360.027356 -337.919727) (xy 359.991664 -337.878534) (xy 359.962197 -337.832681)
			(xy 359.939556 -337.783101) (xy 359.9242 -337.730803) (xy 359.916444 -337.676853) (xy 359.596273 -337.676853)
			(xy 359.57374 -337.708265) (xy 359.532074 -337.750569) (xy 359.508552 -337.768692) (xy 359.497922 -337.77709)
			(xy 359.481222 -337.798411) (xy 359.47071 -337.823371) (xy 359.467125 -337.850216) (xy 359.470718 -337.877059)
			(xy 359.481238 -337.902016) (xy 359.497945 -337.923332) (xy 359.508552 -337.93176) (xy 359.532102 -337.949846)
			(xy 359.573758 -337.992162) (xy 359.608356 -338.04042) (xy 359.635062 -338.093454) (xy 359.65323 -338.149985)
			(xy 359.662422 -338.208649) (xy 359.662984 -338.238338) (xy 359.662498 -338.265589) (xy 359.654742 -338.319537)
			(xy 359.639387 -338.371832) (xy 359.616745 -338.421409) (xy 359.587279 -338.467259) (xy 359.551588 -338.50845)
			(xy 359.510397 -338.544141) (xy 359.464547 -338.573607) (xy 359.41497 -338.596249) (xy 359.362675 -338.611604)
			(xy 359.308727 -338.61936) (xy 359.254225 -338.61936) (xy 359.200277 -338.611604) (xy 359.147982 -338.596249)
			(xy 359.098405 -338.573607) (xy 359.052555 -338.544141) (xy 359.011364 -338.50845) (xy 358.975673 -338.467259)
			(xy 358.946207 -338.421409) (xy 358.923565 -338.371832) (xy 358.90821 -338.319537) (xy 358.900454 -338.265589)
			(xy 358.899968 -338.238338) (xy 353.524066 -338.238338) (xy 353.512107 -338.256947) (xy 353.476416 -338.298138)
			(xy 353.435225 -338.333829) (xy 353.389375 -338.363295) (xy 353.339798 -338.385937) (xy 353.287503 -338.401292)
			(xy 353.233555 -338.409048) (xy 353.179053 -338.409048) (xy 353.125105 -338.401292) (xy 353.07281 -338.385937)
			(xy 353.023233 -338.363295) (xy 352.977383 -338.333829) (xy 352.936192 -338.298138) (xy 352.900501 -338.256947)
			(xy 352.871035 -338.211097) (xy 352.848393 -338.16152) (xy 352.833038 -338.109225) (xy 352.825282 -338.055277)
			(xy 352.824796 -338.028026) (xy 352.824796 -338.027772) (xy 352.825372 -337.997933) (xy 352.834687 -337.938987)
			(xy 352.843338 -337.910424) (xy 352.847365 -337.896515) (xy 352.848269 -337.867586) (xy 352.841003 -337.839569)
			(xy 352.826153 -337.814726) (xy 352.804916 -337.79506) (xy 352.779007 -337.782158) (xy 352.764852 -337.779106)
			(xy 352.732015 -337.772512) (xy 352.669162 -337.749397) (xy 352.639884 -337.733132) (xy 352.626912 -337.726109)
			(xy 352.598279 -337.719076) (xy 352.568829 -337.72052) (xy 352.541021 -337.730319) (xy 352.517172 -337.747656)
			(xy 352.499273 -337.771086) (xy 352.49358 -337.784694) (xy 352.482914 -337.811483) (xy 352.454624 -337.861727)
			(xy 352.41909 -337.907138) (xy 352.377124 -337.946681) (xy 352.329682 -337.979454) (xy 352.277846 -338.004709)
			(xy 352.222799 -338.021871) (xy 352.165794 -338.030548) (xy 352.136964 -338.031074) (xy 352.109712 -338.030654)
			(xy 352.055763 -338.022892) (xy 352.003468 -338.007533) (xy 351.953891 -337.984887) (xy 351.908041 -337.955418)
			(xy 351.866852 -337.919723) (xy 351.831161 -337.87853) (xy 351.801695 -337.832677) (xy 351.779055 -337.783098)
			(xy 351.7637 -337.730801) (xy 351.755944 -337.676852) (xy 351.435765 -337.676852) (xy 351.41323 -337.708266)
			(xy 351.371563 -337.750569) (xy 351.34804 -337.768692) (xy 351.337403 -337.777085) (xy 351.320688 -337.798403)
			(xy 351.310166 -337.823365) (xy 351.306577 -337.850216) (xy 351.310174 -337.877065) (xy 351.320704 -337.902024)
			(xy 351.337425 -337.923336) (xy 351.34804 -337.93176) (xy 351.371587 -337.94985) (xy 351.413244 -337.992164)
			(xy 351.447843 -338.040421) (xy 351.474549 -338.093455) (xy 351.492718 -338.149986) (xy 351.50191 -338.208649)
			(xy 351.502472 -338.238338) (xy 351.501986 -338.265589) (xy 351.49423 -338.319537) (xy 351.478875 -338.371832)
			(xy 351.456233 -338.421409) (xy 351.426767 -338.467259) (xy 351.391076 -338.50845) (xy 351.349885 -338.544141)
			(xy 351.304035 -338.573607) (xy 351.254458 -338.596249) (xy 351.202163 -338.611604) (xy 351.148215 -338.61936)
			(xy 351.093713 -338.61936) (xy 351.039765 -338.611604) (xy 350.98747 -338.596249) (xy 350.937893 -338.573607)
			(xy 350.892043 -338.544141) (xy 350.850852 -338.50845) (xy 350.815161 -338.467259) (xy 350.785695 -338.421409)
			(xy 350.763053 -338.371832) (xy 350.747698 -338.319537) (xy 350.739942 -338.265589) (xy 350.739456 -338.238338)
			(xy 345.363554 -338.238338) (xy 345.351595 -338.256947) (xy 345.315904 -338.298138) (xy 345.274713 -338.333829)
			(xy 345.228863 -338.363295) (xy 345.179286 -338.385937) (xy 345.126991 -338.401292) (xy 345.073043 -338.409048)
			(xy 345.018541 -338.409048) (xy 344.964593 -338.401292) (xy 344.912298 -338.385937) (xy 344.862721 -338.363295)
			(xy 344.816871 -338.333829) (xy 344.77568 -338.298138) (xy 344.739989 -338.256947) (xy 344.710523 -338.211097)
			(xy 344.687881 -338.16152) (xy 344.672526 -338.109225) (xy 344.66477 -338.055277) (xy 344.664284 -338.028026)
			(xy 344.664284 -338.027772) (xy 344.66486 -337.997933) (xy 344.674175 -337.938987) (xy 344.682826 -337.910424)
			(xy 344.686863 -337.896517) (xy 344.687767 -337.867586) (xy 344.6805 -337.839567) (xy 344.665647 -337.814723)
			(xy 344.644409 -337.795057) (xy 344.618497 -337.782157) (xy 344.60434 -337.779106) (xy 344.571503 -337.772515)
			(xy 344.508649 -337.749398) (xy 344.479372 -337.733132) (xy 344.466407 -337.726095) (xy 344.437771 -337.719064)
			(xy 344.40832 -337.72051) (xy 344.38051 -337.730312) (xy 344.35666 -337.747652) (xy 344.338761 -337.771085)
			(xy 344.333068 -337.784694) (xy 344.322329 -337.811452) (xy 344.294047 -337.861692) (xy 344.258523 -337.907102)
			(xy 344.216568 -337.946646) (xy 344.169137 -337.979422) (xy 344.117312 -338.004683) (xy 344.062274 -338.021853)
			(xy 344.005279 -338.030541) (xy 343.976452 -338.031074) (xy 343.949201 -338.030653) (xy 343.895253 -338.02289)
			(xy 343.84296 -338.007529) (xy 343.793384 -337.984884) (xy 343.747536 -337.955413) (xy 343.706347 -337.919719)
			(xy 343.670658 -337.878526) (xy 343.641193 -337.832674) (xy 343.618554 -337.783095) (xy 343.6032 -337.7308)
			(xy 343.595444 -337.676851) (xy 343.275257 -337.676851) (xy 343.25272 -337.708267) (xy 343.211052 -337.75057)
			(xy 343.187528 -337.768692) (xy 343.176892 -337.777086) (xy 343.160179 -337.798404) (xy 343.149658 -337.823366)
			(xy 343.14607 -337.850216) (xy 343.149666 -337.877064) (xy 343.160195 -337.902023) (xy 343.176914 -337.923336)
			(xy 343.187528 -337.93176) (xy 343.211073 -337.949853) (xy 343.25273 -337.992167) (xy 343.28733 -338.040423)
			(xy 343.314037 -338.093456) (xy 343.332205 -338.149986) (xy 343.341398 -338.208649) (xy 343.34196 -338.238338)
			(xy 343.341474 -338.265589) (xy 343.333718 -338.319537) (xy 343.318363 -338.371832) (xy 343.295721 -338.421409)
			(xy 343.266255 -338.467259) (xy 343.230564 -338.50845) (xy 343.189373 -338.544141) (xy 343.143523 -338.573607)
			(xy 343.093946 -338.596249) (xy 343.041651 -338.611604) (xy 342.987703 -338.61936) (xy 342.933201 -338.61936)
			(xy 342.879253 -338.611604) (xy 342.826958 -338.596249) (xy 342.777381 -338.573607) (xy 342.731531 -338.544141)
			(xy 342.69034 -338.50845) (xy 342.654649 -338.467259) (xy 342.625183 -338.421409) (xy 342.602541 -338.371832)
			(xy 342.587186 -338.319537) (xy 342.57943 -338.265589) (xy 342.578944 -338.238338) (xy 333.469256 -338.238338)
			(xy 333.468416 -338.240168) (xy 333.464238 -338.269079) (xy 333.468404 -338.297992) (xy 333.480574 -338.324547)
			(xy 333.489808 -338.335874) (xy 333.50745 -338.356804) (xy 333.537161 -338.402778) (xy 333.559996 -338.452526)
			(xy 333.575487 -338.505027) (xy 333.583314 -338.559203) (xy 333.583788 -338.586572) (xy 333.583302 -338.613823)
			(xy 333.575546 -338.667771) (xy 333.560191 -338.720066) (xy 333.537549 -338.769643) (xy 333.508083 -338.815493)
			(xy 333.472392 -338.856684) (xy 333.431201 -338.892375) (xy 333.385351 -338.921841) (xy 333.335774 -338.944483)
			(xy 333.283479 -338.959838) (xy 333.229531 -338.967594) (xy 333.175029 -338.967594) (xy 333.121081 -338.959838)
			(xy 333.068786 -338.944483) (xy 333.019209 -338.921841) (xy 332.973359 -338.892375) (xy 332.932168 -338.856684)
			(xy 332.896477 -338.815493) (xy 332.867011 -338.769643) (xy 332.844369 -338.720066) (xy 332.829014 -338.667771)
			(xy 332.821258 -338.613823) (xy 332.820772 -338.586572) (xy 318.34074 -338.586572) (xy 318.34074 -338.9892)
			(xy 337.069421 -338.9892) (xy 337.073589 -338.933585) (xy 337.085998 -338.879212) (xy 337.106372 -338.827295)
			(xy 337.134256 -338.778995) (xy 337.169027 -338.73539) (xy 337.209907 -338.697453) (xy 337.255985 -338.666033)
			(xy 337.306231 -338.64183) (xy 337.359523 -338.625386) (xy 337.41467 -338.617068) (xy 337.442556 -338.616544)
			(xy 337.469888 -338.617013) (xy 337.523968 -338.624982) (xy 337.576303 -338.64077) (xy 337.625767 -338.664039)
			(xy 337.6713 -338.694287) (xy 337.711922 -338.730866) (xy 337.746761 -338.772989) (xy 337.761326 -338.796122)
			(xy 337.769241 -338.808351) (xy 337.790716 -338.82802) (xy 337.816871 -338.840823) (xy 337.845578 -338.845717)
			(xy 337.874498 -338.842304) (xy 337.888072 -338.837016) (xy 337.911288 -338.827544) (xy 337.959618 -338.814186)
			(xy 338.009305 -338.807451) (xy 338.034376 -338.807044) (xy 338.059446 -338.807454) (xy 338.109129 -338.814209)
			(xy 338.157463 -338.827547) (xy 338.18068 -338.837016) (xy 338.194253 -338.842275) (xy 338.223156 -338.845636)
			(xy 338.251835 -338.840723) (xy 338.27797 -338.827931) (xy 338.299445 -338.808297) (xy 338.307426 -338.796122)
			(xy 338.321995 -338.772991) (xy 338.356838 -338.73087) (xy 338.397461 -338.694291) (xy 338.442992 -338.66404)
			(xy 338.492454 -338.640764) (xy 338.544785 -338.624964) (xy 338.598864 -338.616978) (xy 338.653528 -338.616978)
			(xy 338.707607 -338.624964) (xy 338.759938 -338.640764) (xy 338.8094 -338.66404) (xy 338.854931 -338.694291)
			(xy 338.895554 -338.73087) (xy 338.930397 -338.772991) (xy 338.944966 -338.796122) (xy 338.952843 -338.808379)
			(xy 338.974328 -338.828047) (xy 339.000494 -338.840846) (xy 339.029209 -338.845733) (xy 339.058136 -338.84231)
			(xy 339.071712 -338.837016) (xy 339.094924 -338.827531) (xy 339.143256 -338.814178) (xy 339.192945 -338.807448)
			(xy 339.218016 -338.807044) (xy 339.245655 -338.807541) (xy 339.300322 -338.815736) (xy 339.35318 -338.831914)
			(xy 339.40307 -338.85572) (xy 339.448896 -338.886633) (xy 339.489656 -338.923974) (xy 339.524454 -338.966925)
			(xy 339.552528 -339.014544) (xy 339.573262 -339.065786) (xy 339.58022 -339.09254) (xy 339.583825 -339.105648)
			(xy 339.596965 -339.129436) (xy 339.615914 -339.148918) (xy 339.639329 -339.162712) (xy 339.665554 -339.169842)
			(xy 339.69273 -339.169804) (xy 339.718934 -339.1626) (xy 339.730842 -339.15604) (xy 339.752965 -339.143433)
			(xy 339.799854 -339.123576) (xy 339.84897 -339.110142) (xy 339.899438 -339.103372) (xy 339.924898 -339.102954)
			(xy 339.925152 -339.102954) (xy 339.93201 -339.102954) (xy 339.947094 -339.102679) (xy 339.976082 -339.094373)
			(xy 340.001392 -339.07798) (xy 340.020827 -339.054924) (xy 340.032701 -339.027205) (xy 340.03488 -339.012276)
			(xy 340.038284 -338.984522) (xy 340.052283 -338.930385) (xy 340.07403 -338.878869) (xy 340.103059 -338.831077)
			(xy 340.13875 -338.788031) (xy 340.180338 -338.750652) (xy 340.226935 -338.71974) (xy 340.277543 -338.695956)
			(xy 340.331079 -338.67981) (xy 340.386397 -338.671646) (xy 340.414356 -338.671154) (xy 340.441606 -338.671696)
			(xy 340.495552 -338.679446) (xy 340.547846 -338.694795) (xy 340.597424 -338.717429) (xy 340.643275 -338.746889)
			(xy 340.684467 -338.782575) (xy 340.720162 -338.823759) (xy 340.749631 -338.869604) (xy 340.772277 -338.919177)
			(xy 340.787636 -338.971468) (xy 340.790187 -338.9892) (xy 377.871895 -338.9892) (xy 377.876064 -338.933575)
			(xy 377.888477 -338.879193) (xy 377.908856 -338.827269) (xy 377.936747 -338.778961) (xy 377.971527 -338.735351)
			(xy 378.012418 -338.697411) (xy 378.058507 -338.66599) (xy 378.108764 -338.641789) (xy 378.162068 -338.625349)
			(xy 378.217226 -338.617038) (xy 378.245116 -338.616544) (xy 378.27245 -338.616965) (xy 378.326532 -338.624943)
			(xy 378.378868 -338.64074) (xy 378.428332 -338.664016) (xy 378.473864 -338.694271) (xy 378.514485 -338.730857)
			(xy 378.549322 -338.772986) (xy 378.563886 -338.796122) (xy 378.571839 -338.808324) (xy 378.593304 -338.827993)
			(xy 378.619449 -338.840799) (xy 378.648146 -338.8457) (xy 378.677059 -338.842298) (xy 378.690632 -338.837016)
			(xy 378.713841 -338.827525) (xy 378.762174 -338.814174) (xy 378.811864 -338.807447) (xy 378.836936 -338.807044)
			(xy 378.862005 -338.807467) (xy 378.911688 -338.814217) (xy 378.960023 -338.82755) (xy 378.98324 -338.837016)
			(xy 378.996827 -338.842232) (xy 379.025723 -338.845603) (xy 379.054397 -338.840699) (xy 379.08053 -338.827917)
			(xy 379.102005 -338.808293) (xy 379.109986 -338.796122) (xy 379.124555 -338.772991) (xy 379.159398 -338.73087)
			(xy 379.200021 -338.694291) (xy 379.245552 -338.66404) (xy 379.295014 -338.640764) (xy 379.347345 -338.624964)
			(xy 379.401424 -338.616978) (xy 379.456088 -338.616978) (xy 379.510167 -338.624964) (xy 379.562498 -338.640764)
			(xy 379.61196 -338.66404) (xy 379.657491 -338.694291) (xy 379.698114 -338.73087) (xy 379.732957 -338.772991)
			(xy 379.747526 -338.796122) (xy 379.755441 -338.808351) (xy 379.776916 -338.82802) (xy 379.803071 -338.840823)
			(xy 379.831778 -338.845717) (xy 379.860698 -338.842304) (xy 379.874272 -338.837016) (xy 379.897488 -338.827544)
			(xy 379.945818 -338.814186) (xy 379.995505 -338.807451) (xy 380.020576 -338.807044) (xy 380.045517 -338.807416)
			(xy 380.094955 -338.814065) (xy 380.143064 -338.827247) (xy 380.188986 -338.846727) (xy 380.231899 -338.872158)
			(xy 380.251716 -338.887308) (xy 380.26328 -338.895793) (xy 380.289788 -338.906699) (xy 380.318285 -338.909788)
			(xy 380.346513 -338.904813) (xy 380.372238 -338.89217) (xy 380.393421 -338.872859) (xy 380.401322 -338.860892)
			(xy 380.416313 -338.837415) (xy 380.451977 -338.794632) (xy 380.493486 -338.757491) (xy 380.539956 -338.726784)
			(xy 380.590398 -338.703162) (xy 380.64374 -338.68713) (xy 380.698846 -338.679027) (xy 380.726696 -338.67852)
			(xy 380.754851 -338.678952) (xy 380.810552 -338.687216) (xy 380.864433 -338.703578) (xy 380.915323 -338.727684)
			(xy 380.962116 -338.75901) (xy 381.003795 -338.796875) (xy 381.039454 -338.840456) (xy 381.068319 -338.888806)
			(xy 381.089761 -338.940874) (xy 381.097028 -338.96808) (xy 381.101361 -338.983027) (xy 381.117615 -339.009543)
			(xy 381.141093 -339.029942) (xy 381.169619 -339.042335) (xy 381.200552 -339.045572) (xy 381.2159 -339.04301)
			(xy 381.234621 -339.039456) (xy 381.272538 -339.035641) (xy 381.291592 -339.03539) (xy 381.291846 -339.03539)
			(xy 381.319095 -339.035883) (xy 381.373037 -339.043645) (xy 381.425326 -339.059004) (xy 381.474898 -339.081647)
			(xy 381.520742 -339.111115) (xy 381.561926 -339.146806) (xy 381.597613 -339.187995) (xy 381.627075 -339.233843)
			(xy 381.649712 -339.283417) (xy 381.665065 -339.335708) (xy 381.67282 -339.389651) (xy 381.67282 -339.444149)
			(xy 381.665065 -339.498092) (xy 381.649712 -339.550383) (xy 381.627075 -339.599957) (xy 381.597613 -339.645805)
			(xy 381.561926 -339.686994) (xy 381.520742 -339.722685) (xy 381.474898 -339.752153) (xy 381.425326 -339.774796)
			(xy 381.373037 -339.790155) (xy 381.319095 -339.797917) (xy 381.291846 -339.798406) (xy 381.263693 -339.797916)
			(xy 381.207995 -339.789659) (xy 381.154117 -339.773304) (xy 381.103229 -339.749205) (xy 381.056436 -339.717886)
			(xy 381.014757 -339.680028) (xy 380.979096 -339.636454) (xy 380.950229 -339.588111) (xy 380.928783 -339.536049)
			(xy 380.921514 -339.508846) (xy 380.917228 -339.493882) (xy 380.900967 -339.467358) (xy 380.877478 -339.446956)
			(xy 380.848939 -339.434569) (xy 380.817994 -339.431344) (xy 380.802642 -339.433916) (xy 380.783858 -339.437482)
			(xy 380.745814 -339.4413) (xy 380.726696 -339.441536) (xy 380.726442 -339.441536) (xy 380.700302 -339.441074)
			(xy 380.648512 -339.433943) (xy 380.598183 -339.419797) (xy 380.550262 -339.3989) (xy 380.505649 -339.371646)
			(xy 380.485142 -339.35543) (xy 380.473724 -339.346722) (xy 380.44736 -339.335384) (xy 380.41888 -339.33185)
			(xy 380.390544 -339.3364) (xy 380.364601 -339.348673) (xy 380.343112 -339.367694) (xy 380.335028 -339.37956)
			(xy 380.3293 -339.388435) (xy 380.316971 -339.405588) (xy 380.31039 -339.41385) (xy 380.301159 -339.426158)
			(xy 380.289769 -339.454718) (xy 380.287381 -339.485373) (xy 380.29421 -339.515353) (xy 380.30964 -339.541948)
			(xy 380.332277 -339.562757) (xy 380.34595 -339.569806) (xy 380.369084 -339.581162) (xy 380.412323 -339.609201)
			(xy 380.451386 -339.642814) (xy 380.485561 -339.681387) (xy 380.514222 -339.724216) (xy 380.536847 -339.770519)
			(xy 380.54534 -339.79485) (xy 380.550438 -339.808602) (xy 380.567205 -339.832649) (xy 380.590102 -339.850956)
			(xy 380.61725 -339.862021) (xy 380.64642 -339.864934) (xy 380.66091 -339.862668) (xy 380.678646 -339.859483)
			(xy 380.71452 -339.856046) (xy 380.732538 -339.85581) (xy 380.7333 -339.85581) (xy 380.760554 -339.856255)
			(xy 380.814506 -339.864013) (xy 380.866805 -339.87937) (xy 380.916387 -339.902014) (xy 380.962241 -339.931483)
			(xy 381.003434 -339.967179) (xy 381.039128 -340.008374) (xy 381.068595 -340.054229) (xy 381.091237 -340.103811)
			(xy 381.106591 -340.156111) (xy 381.114346 -340.210064) (xy 381.114808 -340.237318) (xy 381.114554 -340.247732)
			(xy 381.114676 -340.262099) (xy 381.12194 -340.289884) (xy 381.136646 -340.31455) (xy 381.157635 -340.334151)
			(xy 381.183249 -340.347138) (xy 381.211465 -340.352486) (xy 381.225806 -340.351618) (xy 381.262382 -340.34984)
			(xy 381.289639 -340.350206) (xy 381.343599 -340.357962) (xy 381.395906 -340.373318) (xy 381.445494 -340.395962)
			(xy 381.491355 -340.425434) (xy 381.532555 -340.461132) (xy 381.568256 -340.50233) (xy 381.597729 -340.54819)
			(xy 381.620376 -340.597778) (xy 381.635735 -340.650084) (xy 381.643493 -340.704043) (xy 381.643493 -340.758557)
			(xy 381.635735 -340.812516) (xy 381.620376 -340.864822) (xy 381.597729 -340.91441) (xy 381.568256 -340.96027)
			(xy 381.532555 -341.001468) (xy 381.491355 -341.037166) (xy 381.445494 -341.066638) (xy 381.395906 -341.089282)
			(xy 381.343599 -341.104638) (xy 381.289639 -341.112394) (xy 381.262382 -341.112856) (xy 381.251371 -341.112781)
			(xy 381.229386 -341.111508) (xy 381.21844 -341.110316) (xy 381.203582 -341.109091) (xy 381.174247 -341.11434)
			(xy 381.14768 -341.12784) (xy 381.126144 -341.148439) (xy 381.111478 -341.17438) (xy 381.107696 -341.188802)
			(xy 381.100847 -341.216546) (xy 381.07999 -341.269747) (xy 381.051435 -341.319245) (xy 381.015821 -341.363933)
			(xy 380.973944 -341.402814) (xy 380.926739 -341.435018) (xy 380.875262 -341.459826) (xy 380.820661 -341.476683)
			(xy 380.764158 -341.485214) (xy 380.735586 -341.485728) (xy 380.706599 -341.485189) (xy 380.649292 -341.476416)
			(xy 380.593972 -341.459074) (xy 380.541912 -341.433561) (xy 380.494312 -341.400467) (xy 380.452267 -341.360551)
			(xy 380.416744 -341.314734) (xy 380.388562 -341.26407) (xy 380.36837 -341.209726) (xy 380.356632 -341.152952)
			(xy 380.354586 -341.124032) (xy 380.353411 -341.109958) (xy 380.34432 -341.083231) (xy 380.328247 -341.060024)
			(xy 380.306424 -341.042115) (xy 380.280526 -341.030879) (xy 380.252539 -341.027179) (xy 380.238508 -341.028782)
			(xy 380.224743 -341.030678) (xy 380.19703 -341.032711) (xy 380.183136 -341.032846) (xy 380.155887 -341.032288)
			(xy 380.101944 -341.024538) (xy 380.049653 -341.009189) (xy 380.000079 -340.986555) (xy 379.95423 -340.957096)
			(xy 379.91304 -340.921412) (xy 379.877348 -340.880229) (xy 379.847881 -340.834386) (xy 379.825237 -340.784816)
			(xy 379.809878 -340.732528) (xy 379.802117 -340.678587) (xy 379.801628 -340.651338) (xy 379.80211 -340.623764)
			(xy 379.810058 -340.569191) (xy 379.825779 -340.516331) (xy 379.848946 -340.466285) (xy 379.879076 -340.420095)
			(xy 379.915542 -340.378724) (xy 379.936248 -340.360508) (xy 379.947111 -340.350573) (xy 379.963193 -340.325935)
			(xy 379.971585 -340.297735) (xy 379.971592 -340.268314) (xy 379.963214 -340.24011) (xy 379.947144 -340.215464)
			(xy 379.936248 -340.205568) (xy 379.915528 -340.187366) (xy 379.879056 -340.145997) (xy 379.848924 -340.099805)
			(xy 379.825759 -340.049755) (xy 379.810046 -339.99689) (xy 379.80211 -339.942313) (xy 379.801628 -339.914738)
			(xy 379.802058 -339.888236) (xy 379.809408 -339.835744) (xy 379.823958 -339.784775) (xy 379.845426 -339.736313)
			(xy 379.8734 -339.691292) (xy 379.89002 -339.670644) (xy 379.899478 -339.658509) (xy 379.911271 -339.630105)
			(xy 379.914094 -339.59948) (xy 379.907695 -339.569399) (xy 379.892649 -339.542576) (xy 379.870316 -339.521432)
			(xy 379.856746 -339.51418) (xy 379.833054 -339.502083) (xy 379.789072 -339.472159) (xy 379.749792 -339.436287)
			(xy 379.716009 -339.395195) (xy 379.701806 -339.372702) (xy 379.693854 -339.360498) (xy 379.672391 -339.340827)
			(xy 379.646245 -339.328019) (xy 379.617547 -339.323119) (xy 379.588632 -339.326524) (xy 379.57506 -339.331808)
			(xy 379.551852 -339.341303) (xy 379.503518 -339.354652) (xy 379.453828 -339.361378) (xy 379.428756 -339.36178)
			(xy 379.403687 -339.361358) (xy 379.354004 -339.354608) (xy 379.305669 -339.341274) (xy 379.282452 -339.331808)
			(xy 379.26887 -339.326573) (xy 379.239972 -339.323203) (xy 379.211294 -339.32811) (xy 379.18516 -339.340897)
			(xy 379.163686 -339.360528) (xy 379.155706 -339.372702) (xy 379.141137 -339.395833) (xy 379.106294 -339.437954)
			(xy 379.065671 -339.474533) (xy 379.02014 -339.504784) (xy 378.970678 -339.52806) (xy 378.918347 -339.54386)
			(xy 378.864268 -339.551846) (xy 378.809604 -339.551846) (xy 378.755525 -339.54386) (xy 378.703194 -339.52806)
			(xy 378.653732 -339.504784) (xy 378.608201 -339.474533) (xy 378.567578 -339.437954) (xy 378.532735 -339.395833)
			(xy 378.518166 -339.372702) (xy 378.510252 -339.360471) (xy 378.488779 -339.340799) (xy 378.462623 -339.327995)
			(xy 378.433915 -339.323102) (xy 378.404994 -339.326518) (xy 378.39142 -339.331808) (xy 378.368205 -339.341284)
			(xy 378.319875 -339.35464) (xy 378.270187 -339.361374) (xy 378.245116 -339.36178) (xy 378.217226 -339.361362)
			(xy 378.162068 -339.353051) (xy 378.108764 -339.336611) (xy 378.058507 -339.31241) (xy 378.012418 -339.280989)
			(xy 377.971527 -339.243049) (xy 377.936747 -339.199439) (xy 377.908856 -339.151131) (xy 377.888477 -339.099207)
			(xy 377.876064 -339.044825) (xy 377.871895 -338.9892) (xy 340.790187 -338.9892) (xy 340.795398 -339.025412)
			(xy 340.795864 -339.052662) (xy 340.795316 -339.082032) (xy 340.786317 -339.14008) (xy 340.768526 -339.196061)
			(xy 340.742363 -339.248654) (xy 340.708447 -339.296614) (xy 340.66758 -339.338808) (xy 340.64448 -339.356954)
			(xy 340.633399 -339.366027) (xy 340.616251 -339.388944) (xy 340.606145 -339.415722) (xy 340.603874 -339.444253)
			(xy 340.609619 -339.472293) (xy 340.622926 -339.497633) (xy 340.642749 -339.518279) (xy 340.654894 -339.525864)
			(xy 340.679326 -339.540649) (xy 340.723967 -339.576255) (xy 340.762805 -339.618116) (xy 340.794972 -339.665295)
			(xy 340.819752 -339.716741) (xy 340.836589 -339.771304) (xy 340.845109 -339.827767) (xy 340.845648 -339.856318)
			(xy 340.845255 -339.882212) (xy 340.838252 -339.933526) (xy 340.824365 -339.983418) (xy 340.803849 -340.03097)
			(xy 340.777082 -340.075305) (xy 340.744557 -340.115607) (xy 340.726014 -340.133686) (xy 340.715911 -340.143825)
			(xy 340.701296 -340.168419) (xy 340.694088 -340.196105) (xy 340.694855 -340.224704) (xy 340.703535 -340.251965)
			(xy 340.719447 -340.275741) (xy 340.730078 -340.285324) (xy 340.750901 -340.30352) (xy 340.787573 -340.344907)
			(xy 340.817878 -340.39116) (xy 340.841179 -340.441307) (xy 340.856987 -340.494296) (xy 340.864971 -340.549014)
			(xy 340.86546 -340.576662) (xy 340.865009 -340.603916) (xy 340.861078 -340.631272) (xy 374.003316 -340.631272)
			(xy 374.003769 -340.603734) (xy 374.011666 -340.549227) (xy 374.027321 -340.496423) (xy 374.050409 -340.44642)
			(xy 374.080448 -340.400257) (xy 374.116816 -340.358896) (xy 374.158754 -340.323195) (xy 374.205391 -340.293897)
			(xy 374.255757 -340.271613) (xy 374.308805 -340.256804) (xy 374.336056 -340.252812) (xy 374.349853 -340.250659)
			(xy 374.375538 -340.239719) (xy 374.397306 -340.222238) (xy 374.413534 -340.199522) (xy 374.423013 -340.173262)
			(xy 374.425036 -340.145418) (xy 374.42267 -340.131654) (xy 374.419017 -340.112687) (xy 374.415068 -340.07426)
			(xy 374.414796 -340.054946) (xy 374.415298 -340.027694) (xy 374.423049 -339.973744) (xy 374.438399 -339.921447)
			(xy 374.461037 -339.871867) (xy 374.4905 -339.826013) (xy 374.52619 -339.78482) (xy 374.56738 -339.749126)
			(xy 374.61323 -339.719657) (xy 374.662808 -339.697014) (xy 374.715103 -339.681658) (xy 374.769052 -339.673901)
			(xy 374.796304 -339.673438) (xy 374.823559 -339.673852) (xy 374.877514 -339.68161) (xy 374.929816 -339.696969)
			(xy 374.979399 -339.719616) (xy 375.025254 -339.749088) (xy 375.066448 -339.784787) (xy 375.102142 -339.825986)
			(xy 375.131608 -339.871845) (xy 375.154248 -339.921431) (xy 375.1696 -339.973735) (xy 375.177352 -340.027691)
			(xy 375.177812 -340.054946) (xy 375.177351 -340.082484) (xy 375.169452 -340.136989) (xy 375.153796 -340.189791)
			(xy 375.130709 -340.239793) (xy 375.10067 -340.285954) (xy 375.064304 -340.327316) (xy 375.022367 -340.363016)
			(xy 374.975732 -340.392315) (xy 374.925368 -340.414601) (xy 374.872322 -340.429412) (xy 374.845072 -340.433406)
			(xy 374.831299 -340.435672) (xy 374.805626 -340.446595) (xy 374.783863 -340.464053) (xy 374.767632 -340.486746)
			(xy 374.758143 -340.512982) (xy 374.756103 -340.540807) (xy 374.758458 -340.554564) (xy 374.762114 -340.573531)
			(xy 374.766061 -340.611958) (xy 374.766332 -340.631272) (xy 374.765819 -340.658523) (xy 374.758066 -340.712471)
			(xy 374.742715 -340.764766) (xy 374.720077 -340.814345) (xy 374.690615 -340.860197) (xy 374.654926 -340.901389)
			(xy 374.613739 -340.937083) (xy 374.567891 -340.966552) (xy 374.518315 -340.989197) (xy 374.466022 -341.004555)
			(xy 374.412075 -341.012315) (xy 374.384824 -341.01278) (xy 374.35757 -341.012322) (xy 374.303618 -341.004568)
			(xy 374.251318 -340.989213) (xy 374.201736 -340.966572) (xy 374.155882 -340.937104) (xy 374.114688 -340.901409)
			(xy 374.078994 -340.860215) (xy 374.049526 -340.81436) (xy 374.026885 -340.764778) (xy 374.011531 -340.712478)
			(xy 374.003777 -340.658526) (xy 374.003316 -340.631272) (xy 340.861078 -340.631272) (xy 340.857256 -340.65787)
			(xy 340.841903 -340.710171) (xy 340.819261 -340.759754) (xy 340.789792 -340.80561) (xy 340.754097 -340.846804)
			(xy 340.712902 -340.882498) (xy 340.667045 -340.911966) (xy 340.617462 -340.934606) (xy 340.56516 -340.949958)
			(xy 340.511206 -340.95771) (xy 340.483952 -340.95817) (xy 340.454875 -340.957639) (xy 340.397395 -340.948821)
			(xy 340.341918 -340.93138) (xy 340.289732 -340.905722) (xy 340.242044 -340.872441) (xy 340.19996 -340.832307)
			(xy 340.164454 -340.786251) (xy 340.136351 -340.735339) (xy 340.125812 -340.708234) (xy 340.120356 -340.694656)
			(xy 340.102875 -340.671198) (xy 340.07946 -340.653661) (xy 340.052032 -340.643485) (xy 340.022844 -340.641505)
			(xy 340.008464 -340.644226) (xy 339.988029 -340.648495) (xy 339.946534 -340.653076) (xy 339.92566 -340.65337)
			(xy 339.925152 -340.65337) (xy 339.910936 -340.653208) (xy 339.882586 -340.65105) (xy 339.86851 -340.649052)
			(xy 339.853186 -340.647282) (xy 339.822729 -340.652112) (xy 339.795094 -340.665797) (xy 339.772792 -340.687094)
			(xy 339.757848 -340.714069) (xy 339.75421 -340.729062) (xy 339.747713 -340.757293) (xy 339.727473 -340.811567)
			(xy 339.699262 -340.862158) (xy 339.663727 -340.907903) (xy 339.621687 -340.947751) (xy 339.574106 -340.980787)
			(xy 339.522078 -341.006251) (xy 339.466799 -341.023558) (xy 339.409539 -341.03231) (xy 339.380576 -341.032846)
			(xy 339.353326 -341.032345) (xy 339.299381 -341.024586) (xy 339.247089 -341.00923) (xy 339.197514 -340.986588)
			(xy 339.151665 -340.957123) (xy 339.110476 -340.921434) (xy 339.074785 -340.880246) (xy 339.045318 -340.834399)
			(xy 339.022675 -340.784825) (xy 339.007317 -340.732533) (xy 338.999556 -340.678588) (xy 338.999068 -340.651338)
			(xy 338.999571 -340.623765) (xy 339.007517 -340.569194) (xy 339.023236 -340.516336) (xy 339.046399 -340.46629)
			(xy 339.076524 -340.420099) (xy 339.112984 -340.378726) (xy 339.133688 -340.360508) (xy 339.144548 -340.350571)
			(xy 339.160623 -340.325932) (xy 339.169012 -340.297734) (xy 339.169019 -340.268315) (xy 339.160644 -340.240113)
			(xy 339.14458 -340.215466) (xy 339.133688 -340.205568) (xy 339.112956 -340.18738) (xy 339.076488 -340.146006)
			(xy 339.046358 -340.099811) (xy 339.023196 -340.049759) (xy 339.007484 -339.996892) (xy 338.99955 -339.942314)
			(xy 338.999068 -339.914738) (xy 338.999512 -339.888237) (xy 339.006861 -339.835745) (xy 339.021408 -339.784778)
			(xy 339.042873 -339.736316) (xy 339.070842 -339.691293) (xy 339.08746 -339.670644) (xy 339.096904 -339.6585)
			(xy 339.10869 -339.630099) (xy 339.111512 -339.599479) (xy 339.105115 -339.569402) (xy 339.090076 -339.542581)
			(xy 339.067752 -339.521435) (xy 339.054186 -339.51418) (xy 339.0305 -339.502071) (xy 338.986517 -339.472151)
			(xy 338.947235 -339.436283) (xy 338.91345 -339.395194) (xy 338.899246 -339.372702) (xy 338.891351 -339.360457)
			(xy 338.869873 -339.340786) (xy 338.843711 -339.327983) (xy 338.814999 -339.323094) (xy 338.786075 -339.326515)
			(xy 338.7725 -339.331808) (xy 338.749287 -339.34129) (xy 338.700956 -339.354644) (xy 338.651267 -339.361375)
			(xy 338.626196 -339.36178) (xy 338.601127 -339.361345) (xy 338.551444 -339.3546) (xy 338.50311 -339.341272)
			(xy 338.479892 -339.331808) (xy 338.466296 -339.326615) (xy 338.437405 -339.323236) (xy 338.408732 -339.328134)
			(xy 338.3826 -339.340911) (xy 338.361126 -339.360532) (xy 338.353146 -339.372702) (xy 338.338577 -339.395833)
			(xy 338.303734 -339.437954) (xy 338.263111 -339.474533) (xy 338.21758 -339.504784) (xy 338.168118 -339.52806)
			(xy 338.115787 -339.54386) (xy 338.061708 -339.551846) (xy 338.007044 -339.551846) (xy 337.952965 -339.54386)
			(xy 337.900634 -339.52806) (xy 337.851172 -339.504784) (xy 337.805641 -339.474533) (xy 337.765018 -339.437954)
			(xy 337.730175 -339.395833) (xy 337.715606 -339.372702) (xy 337.707654 -339.360498) (xy 337.686191 -339.340827)
			(xy 337.660045 -339.328019) (xy 337.631347 -339.323119) (xy 337.602432 -339.326524) (xy 337.58886 -339.331808)
			(xy 337.565652 -339.341303) (xy 337.517318 -339.354652) (xy 337.467628 -339.361378) (xy 337.442556 -339.36178)
			(xy 337.41467 -339.361332) (xy 337.359523 -339.353014) (xy 337.306231 -339.33657) (xy 337.255985 -339.312367)
			(xy 337.209907 -339.280947) (xy 337.169027 -339.24301) (xy 337.134256 -339.199405) (xy 337.106372 -339.151105)
			(xy 337.085998 -339.099188) (xy 337.073589 -339.044815) (xy 337.069421 -338.9892) (xy 318.34074 -338.9892)
			(xy 318.34074 -340.054946) (xy 333.611726 -340.054946) (xy 333.615797 -339.999324) (xy 333.627923 -339.944887)
			(xy 333.647846 -339.892796) (xy 333.675142 -339.844161) (xy 333.709228 -339.800018) (xy 333.749377 -339.761309)
			(xy 333.794735 -339.728858) (xy 333.844335 -339.703357) (xy 333.897119 -339.68535) (xy 333.951962 -339.67522)
			(xy 334.007696 -339.673183) (xy 334.063133 -339.679283) (xy 334.11709 -339.693389) (xy 334.168419 -339.715201)
			(xy 334.216025 -339.744255) (xy 334.258893 -339.77993) (xy 334.29611 -339.821467) (xy 334.326883 -339.86798)
			(xy 334.350555 -339.918477) (xy 334.366623 -339.971884) (xy 334.374743 -340.02706) (xy 334.375252 -340.054946)
			(xy 334.374743 -340.082832) (xy 334.366623 -340.138008) (xy 334.350555 -340.191415) (xy 334.326883 -340.241912)
			(xy 334.29611 -340.288425) (xy 334.258893 -340.329962) (xy 334.216025 -340.365637) (xy 334.168419 -340.394691)
			(xy 334.11709 -340.416503) (xy 334.063133 -340.430609) (xy 334.007696 -340.436709) (xy 333.951962 -340.434672)
			(xy 333.897119 -340.424542) (xy 333.844335 -340.406535) (xy 333.794735 -340.381034) (xy 333.749377 -340.348583)
			(xy 333.709228 -340.309874) (xy 333.675142 -340.265731) (xy 333.647846 -340.217096) (xy 333.627923 -340.165005)
			(xy 333.615797 -340.110568) (xy 333.611726 -340.054946) (xy 318.34074 -340.054946) (xy 318.34074 -340.612222)
			(xy 318.443384 -341.013288) (xy 333.031082 -341.013288) (xy 333.035153 -340.957666) (xy 333.047279 -340.903229)
			(xy 333.067202 -340.851138) (xy 333.094498 -340.802503) (xy 333.128584 -340.75836) (xy 333.168733 -340.719651)
			(xy 333.214091 -340.6872) (xy 333.263691 -340.661699) (xy 333.316475 -340.643692) (xy 333.371318 -340.633562)
			(xy 333.427052 -340.631525) (xy 333.482489 -340.637625) (xy 333.536446 -340.651731) (xy 333.587775 -340.673543)
			(xy 333.635381 -340.702597) (xy 333.678249 -340.738272) (xy 333.715466 -340.779809) (xy 333.746239 -340.826322)
			(xy 333.769911 -340.876819) (xy 333.785979 -340.930226) (xy 333.794099 -340.985402) (xy 333.794608 -341.013288)
			(xy 333.794099 -341.041174) (xy 333.785979 -341.09635) (xy 333.769911 -341.149757) (xy 333.746239 -341.200254)
			(xy 333.715466 -341.246767) (xy 333.678249 -341.288304) (xy 333.635381 -341.323979) (xy 333.587775 -341.353033)
			(xy 333.536446 -341.374845) (xy 333.482489 -341.388951) (xy 333.427052 -341.395051) (xy 333.371318 -341.393014)
			(xy 333.316475 -341.382884) (xy 333.263691 -341.364877) (xy 333.214091 -341.339376) (xy 333.168733 -341.306925)
			(xy 333.128584 -341.268216) (xy 333.094498 -341.224073) (xy 333.067202 -341.175438) (xy 333.047279 -341.123347)
			(xy 333.035153 -341.06891) (xy 333.031082 -341.013288) (xy 318.443384 -341.013288) (xy 318.605963 -341.648542)
			(xy 334.418432 -341.648542) (xy 334.419005 -341.618854) (xy 334.428198 -341.560196) (xy 334.446369 -341.50367)
			(xy 334.473079 -341.450642) (xy 334.507682 -341.402392) (xy 334.549344 -341.360088) (xy 334.572864 -341.341964)
			(xy 334.583445 -341.333505) (xy 334.600159 -341.312203) (xy 334.610684 -341.287255) (xy 334.61428 -341.260418)
			(xy 334.610693 -341.23358) (xy 334.600177 -341.208628) (xy 334.583471 -341.18732) (xy 334.572864 -341.178896)
			(xy 334.549344 -341.160772) (xy 334.507686 -341.118465) (xy 334.473083 -341.070215) (xy 334.446373 -341.017188)
			(xy 334.428198 -340.960663) (xy 334.418998 -340.902005) (xy 334.418432 -340.872318) (xy 334.418918 -340.845067)
			(xy 334.426674 -340.791119) (xy 334.442029 -340.738824) (xy 334.464671 -340.689247) (xy 334.494137 -340.643397)
			(xy 334.529828 -340.602206) (xy 334.571019 -340.566515) (xy 334.616869 -340.537049) (xy 334.666446 -340.514407)
			(xy 334.718741 -340.499052) (xy 334.772689 -340.491296) (xy 334.827191 -340.491296) (xy 334.881139 -340.499052)
			(xy 334.933434 -340.514407) (xy 334.983011 -340.537049) (xy 335.028861 -340.566515) (xy 335.070052 -340.602206)
			(xy 335.105743 -340.643397) (xy 335.135209 -340.689247) (xy 335.157851 -340.738824) (xy 335.173206 -340.791119)
			(xy 335.180962 -340.845067) (xy 335.181448 -340.872318) (xy 335.180927 -340.902008) (xy 335.171724 -340.960669)
			(xy 335.153543 -341.017197) (xy 335.126824 -341.070225) (xy 335.114749 -341.087057) (xy 335.434825 -341.087057)
			(xy 335.434825 -341.032543) (xy 335.442584 -340.978584) (xy 335.457943 -340.926279) (xy 335.48059 -340.876692)
			(xy 335.510064 -340.830834) (xy 335.545765 -340.789637) (xy 335.586966 -340.75394) (xy 335.632828 -340.724471)
			(xy 335.682417 -340.701829) (xy 335.734724 -340.686475) (xy 335.788683 -340.678722) (xy 335.81594 -340.678262)
			(xy 335.816194 -340.678262) (xy 335.841398 -340.678661) (xy 335.891366 -340.6853) (xy 335.94002 -340.698477)
			(xy 335.98651 -340.71796) (xy 336.008472 -340.730332) (xy 336.021462 -340.737322) (xy 336.050089 -340.744366)
			(xy 336.079535 -340.742932) (xy 336.107342 -340.733139) (xy 336.131189 -340.715805) (xy 336.149085 -340.692377)
			(xy 336.154776 -340.67877) (xy 336.16546 -340.651988) (xy 336.19375 -340.601747) (xy 336.229282 -340.556338)
			(xy 336.271246 -340.516797) (xy 336.318685 -340.484024) (xy 336.370517 -340.458767) (xy 336.425562 -340.441602)
			(xy 336.482563 -340.432919) (xy 336.511392 -340.43239) (xy 336.538645 -340.432863) (xy 336.592595 -340.440619)
			(xy 336.644893 -340.455974) (xy 336.694473 -340.478615) (xy 336.740326 -340.508082) (xy 336.781518 -340.543775)
			(xy 336.817212 -340.584966) (xy 336.84668 -340.630819) (xy 336.869323 -340.680398) (xy 336.884679 -340.732695)
			(xy 336.892437 -340.786645) (xy 336.8929 -340.813898) (xy 336.8929 -340.814152) (xy 336.89233 -340.843991)
			(xy 336.883011 -340.902937) (xy 336.874358 -340.9315) (xy 336.870419 -340.945432) (xy 336.869498 -340.974349)
			(xy 336.876747 -341.002357) (xy 336.89158 -341.027197) (xy 336.9128 -341.046861) (xy 336.938695 -341.059765)
			(xy 336.952844 -341.062818) (xy 336.978919 -341.067975) (xy 337.029423 -341.084548) (xy 337.077136 -341.107974)
			(xy 337.121134 -341.137797) (xy 337.160564 -341.173442) (xy 337.194662 -341.214216) (xy 337.222769 -341.25933)
			(xy 337.244338 -341.30791) (xy 337.258953 -341.359015) (xy 337.26633 -341.411653) (xy 337.266788 -341.43823)
			(xy 337.266302 -341.465481) (xy 337.258546 -341.519429) (xy 337.243191 -341.571724) (xy 337.220549 -341.621301)
			(xy 337.203042 -341.648542) (xy 375.220992 -341.648542) (xy 375.221581 -341.618855) (xy 375.230773 -341.560198)
			(xy 375.248942 -341.503673) (xy 375.275649 -341.450645) (xy 375.310249 -341.402396) (xy 375.351906 -341.360089)
			(xy 375.375424 -341.341964) (xy 375.386 -341.333502) (xy 375.402704 -341.312197) (xy 375.413223 -341.287251)
			(xy 375.416816 -341.260418) (xy 375.413232 -341.233583) (xy 375.402723 -341.208634) (xy 375.386026 -341.187323)
			(xy 375.375424 -341.178896) (xy 375.351917 -341.160756) (xy 375.310255 -341.118454) (xy 375.275649 -341.070208)
			(xy 375.248936 -341.017184) (xy 375.230759 -340.960661) (xy 375.221558 -340.902005) (xy 375.220992 -340.872318)
			(xy 375.221478 -340.845067) (xy 375.229234 -340.791119) (xy 375.244589 -340.738824) (xy 375.267231 -340.689247)
			(xy 375.296697 -340.643397) (xy 375.332388 -340.602206) (xy 375.373579 -340.566515) (xy 375.419429 -340.537049)
			(xy 375.469006 -340.514407) (xy 375.521301 -340.499052) (xy 375.575249 -340.491296) (xy 375.629751 -340.491296)
			(xy 375.683699 -340.499052) (xy 375.735994 -340.514407) (xy 375.785571 -340.537049) (xy 375.831421 -340.566515)
			(xy 375.872612 -340.602206) (xy 375.908303 -340.643397) (xy 375.937769 -340.689247) (xy 375.960411 -340.738824)
			(xy 375.975766 -340.791119) (xy 375.983522 -340.845067) (xy 375.984008 -340.872318) (xy 375.983463 -340.902006)
			(xy 375.974262 -340.960666) (xy 375.956084 -341.017192) (xy 375.929369 -341.070219) (xy 375.917294 -341.087053)
			(xy 376.237448 -341.087053) (xy 376.237448 -341.032547) (xy 376.245205 -340.978595) (xy 376.260561 -340.926296)
			(xy 376.283204 -340.876715) (xy 376.312673 -340.830861) (xy 376.348367 -340.789667) (xy 376.389561 -340.753973)
			(xy 376.435415 -340.724504) (xy 376.484996 -340.701861) (xy 376.537295 -340.686505) (xy 376.591247 -340.678748)
			(xy 376.6185 -340.678262) (xy 376.618754 -340.678262) (xy 376.643957 -340.678679) (xy 376.693925 -340.685313)
			(xy 376.742579 -340.698484) (xy 376.78907 -340.717962) (xy 376.811032 -340.730332) (xy 376.823986 -340.737393)
			(xy 376.852628 -340.744427) (xy 376.882085 -340.74298) (xy 376.909899 -340.733173) (xy 376.93375 -340.715825)
			(xy 376.951646 -340.692384) (xy 376.957336 -340.67877) (xy 376.968053 -340.652003) (xy 376.996339 -340.601763)
			(xy 377.031867 -340.556355) (xy 377.073826 -340.516813) (xy 377.12126 -340.484038) (xy 377.173088 -340.458779)
			(xy 377.228127 -340.44161) (xy 377.285124 -340.432922) (xy 377.313952 -340.43239) (xy 377.341204 -340.4329)
			(xy 377.395153 -340.44065) (xy 377.44745 -340.456) (xy 377.497029 -340.478637) (xy 377.542883 -340.5081)
			(xy 377.584076 -340.543789) (xy 377.61977 -340.584977) (xy 377.649239 -340.630827) (xy 377.671882 -340.680403)
			(xy 377.687239 -340.732698) (xy 377.694996 -340.786646) (xy 377.69546 -340.813898) (xy 377.69546 -340.814152)
			(xy 377.694888 -340.843991) (xy 377.68557 -340.902937) (xy 377.676918 -340.9315) (xy 377.672932 -340.945422)
			(xy 377.672009 -340.974348) (xy 377.679262 -341.002366) (xy 377.694105 -341.027211) (xy 377.715339 -341.046875)
			(xy 377.741249 -341.059771) (xy 377.755404 -341.062818) (xy 377.781473 -341.068005) (xy 377.831977 -341.084573)
			(xy 377.87969 -341.107993) (xy 377.923689 -341.137813) (xy 377.96312 -341.173454) (xy 377.99722 -341.214225)
			(xy 378.025327 -341.259337) (xy 378.046897 -341.307914) (xy 378.061513 -341.359017) (xy 378.06889 -341.411654)
			(xy 378.069348 -341.43823) (xy 378.068862 -341.465481) (xy 378.061106 -341.519429) (xy 378.045751 -341.571724)
			(xy 378.023109 -341.621301) (xy 377.993643 -341.667151) (xy 377.957952 -341.708342) (xy 377.916761 -341.744033)
			(xy 377.870911 -341.773499) (xy 377.821334 -341.796141) (xy 377.769039 -341.811496) (xy 377.715091 -341.819252)
			(xy 377.660589 -341.819252) (xy 377.606641 -341.811496) (xy 377.554346 -341.796141) (xy 377.504769 -341.773499)
			(xy 377.458919 -341.744033) (xy 377.417728 -341.708342) (xy 377.382037 -341.667151) (xy 377.352571 -341.621301)
			(xy 377.329929 -341.571724) (xy 377.314574 -341.519429) (xy 377.306818 -341.465481) (xy 377.306332 -341.43823)
			(xy 377.306332 -341.437976) (xy 377.306911 -341.408137) (xy 377.316224 -341.349191) (xy 377.324874 -341.320628)
			(xy 377.328947 -341.306729) (xy 377.329854 -341.27779) (xy 377.322584 -341.249764) (xy 377.307724 -341.224915)
			(xy 377.286474 -341.205249) (xy 377.26055 -341.192355) (xy 377.246388 -341.18931) (xy 377.213548 -341.182731)
			(xy 377.150696 -341.159605) (xy 377.12142 -341.143336) (xy 377.108428 -341.136353) (xy 377.079802 -341.129314)
			(xy 377.050359 -341.13075) (xy 377.022554 -341.140542) (xy 376.998708 -341.157871) (xy 376.980809 -341.181294)
			(xy 376.975116 -341.194898) (xy 376.964422 -341.221675) (xy 376.936135 -341.271918) (xy 376.900605 -341.317328)
			(xy 376.858643 -341.356871) (xy 376.811205 -341.389645) (xy 376.759374 -341.414902) (xy 376.70433 -341.432068)
			(xy 376.647329 -341.440749) (xy 376.6185 -341.441278) (xy 376.591247 -341.440852) (xy 376.537295 -341.433095)
			(xy 376.484996 -341.417739) (xy 376.435415 -341.395096) (xy 376.389561 -341.365627) (xy 376.348367 -341.329933)
			(xy 376.312673 -341.288739) (xy 376.283204 -341.242885) (xy 376.260561 -341.193304) (xy 376.245205 -341.141005)
			(xy 376.237448 -341.087053) (xy 375.917294 -341.087053) (xy 375.894761 -341.118468) (xy 375.853097 -341.160772)
			(xy 375.829576 -341.178896) (xy 375.81894 -341.187288) (xy 375.802236 -341.208609) (xy 375.791721 -341.233571)
			(xy 375.788136 -341.260418) (xy 375.791731 -341.287264) (xy 375.802254 -341.312222) (xy 375.818966 -341.333537)
			(xy 375.829576 -341.341964) (xy 375.853064 -341.360127) (xy 375.894727 -341.402425) (xy 375.929335 -341.450666)
			(xy 375.956052 -341.503686) (xy 375.974232 -341.560204) (xy 375.983439 -341.618857) (xy 375.984008 -341.648542)
			(xy 375.983522 -341.675793) (xy 375.975766 -341.729741) (xy 375.960411 -341.782036) (xy 375.937769 -341.831613)
			(xy 375.908303 -341.877463) (xy 375.872612 -341.918654) (xy 375.831421 -341.954345) (xy 375.785571 -341.983811)
			(xy 375.735994 -342.006453) (xy 375.683699 -342.021808) (xy 375.629751 -342.029564) (xy 375.575249 -342.029564)
			(xy 375.521301 -342.021808) (xy 375.469006 -342.006453) (xy 375.419429 -341.983811) (xy 375.373579 -341.954345)
			(xy 375.332388 -341.918654) (xy 375.296697 -341.877463) (xy 375.267231 -341.831613) (xy 375.244589 -341.782036)
			(xy 375.229234 -341.729741) (xy 375.221478 -341.675793) (xy 375.220992 -341.648542) (xy 337.203042 -341.648542)
			(xy 337.191083 -341.667151) (xy 337.155392 -341.708342) (xy 337.114201 -341.744033) (xy 337.068351 -341.773499)
			(xy 337.018774 -341.796141) (xy 336.966479 -341.811496) (xy 336.912531 -341.819252) (xy 336.858029 -341.819252)
			(xy 336.804081 -341.811496) (xy 336.751786 -341.796141) (xy 336.702209 -341.773499) (xy 336.656359 -341.744033)
			(xy 336.615168 -341.708342) (xy 336.579477 -341.667151) (xy 336.550011 -341.621301) (xy 336.527369 -341.571724)
			(xy 336.512014 -341.519429) (xy 336.504258 -341.465481) (xy 336.503772 -341.43823) (xy 336.503772 -341.437976)
			(xy 336.50435 -341.408137) (xy 336.513664 -341.349191) (xy 336.522314 -341.320628) (xy 336.526356 -341.306722)
			(xy 336.527261 -341.277789) (xy 336.519994 -341.24977) (xy 336.505141 -341.224924) (xy 336.4839 -341.205258)
			(xy 336.457986 -341.19236) (xy 336.443828 -341.18931) (xy 336.41099 -341.182721) (xy 336.348137 -341.159602)
			(xy 336.31886 -341.143336) (xy 336.305903 -341.136282) (xy 336.277264 -341.129254) (xy 336.24781 -341.130702)
			(xy 336.219998 -341.140507) (xy 336.196148 -341.157851) (xy 336.178248 -341.181287) (xy 336.172556 -341.194898)
			(xy 336.161829 -341.221661) (xy 336.133545 -341.271902) (xy 336.09802 -341.317312) (xy 336.056063 -341.356855)
			(xy 336.00863 -341.38963) (xy 335.956803 -341.414891) (xy 335.901764 -341.43206) (xy 335.844767 -341.440746)
			(xy 335.81594 -341.441278) (xy 335.788683 -341.440878) (xy 335.734724 -341.433125) (xy 335.682417 -341.417771)
			(xy 335.632828 -341.395129) (xy 335.586966 -341.36566) (xy 335.545765 -341.329963) (xy 335.510064 -341.288766)
			(xy 335.48059 -341.242908) (xy 335.457943 -341.193321) (xy 335.442584 -341.141016) (xy 335.434825 -341.087057)
			(xy 335.114749 -341.087057) (xy 335.092211 -341.118472) (xy 335.05054 -341.160774) (xy 335.027016 -341.178896)
			(xy 335.016377 -341.187286) (xy 334.999666 -341.208606) (xy 334.989147 -341.233568) (xy 334.98556 -341.260418)
			(xy 334.989156 -341.287267) (xy 334.999684 -341.312225) (xy 335.016403 -341.333539) (xy 335.027016 -341.341964)
			(xy 335.050513 -341.360117) (xy 335.092173 -341.402418) (xy 335.126779 -341.450661) (xy 335.153494 -341.503683)
			(xy 335.171673 -341.560203) (xy 335.180879 -341.618856) (xy 335.181448 -341.648542) (xy 335.180962 -341.675793)
			(xy 335.173206 -341.729741) (xy 335.157851 -341.782036) (xy 335.135209 -341.831613) (xy 335.105743 -341.877463)
			(xy 335.070052 -341.918654) (xy 335.028861 -341.954345) (xy 334.983011 -341.983811) (xy 334.933434 -342.006453)
			(xy 334.881139 -342.021808) (xy 334.827191 -342.029564) (xy 334.772689 -342.029564) (xy 334.718741 -342.021808)
			(xy 334.666446 -342.006453) (xy 334.616869 -341.983811) (xy 334.571019 -341.954345) (xy 334.529828 -341.918654)
			(xy 334.494137 -341.877463) (xy 334.464671 -341.831613) (xy 334.442029 -341.782036) (xy 334.426674 -341.729741)
			(xy 334.418918 -341.675793) (xy 334.418432 -341.648542) (xy 318.605963 -341.648542) (xy 318.845184 -342.583262)
			(xy 319.01511 -342.870536) (xy 319.022218 -342.881855) (xy 319.041265 -342.900594) (xy 319.064529 -342.913738)
			(xy 319.090409 -342.920384) (xy 319.117126 -342.920076) (xy 319.142846 -342.912833) (xy 319.165799 -342.899155)
			(xy 319.175384 -342.88984) (xy 319.193404 -342.871935) (xy 319.233361 -342.840567) (xy 319.277128 -342.814779)
			(xy 319.32393 -342.795027) (xy 319.372939 -342.781662) (xy 319.423289 -342.774919) (xy 319.448688 -342.774524)
			(xy 319.475941 -342.774987) (xy 319.529891 -342.782742) (xy 319.582189 -342.798098) (xy 319.631768 -342.82074)
			(xy 319.67762 -342.850208) (xy 319.718812 -342.885902) (xy 319.754504 -342.927096) (xy 319.78397 -342.972949)
			(xy 319.806609 -343.02253) (xy 319.821962 -343.074828) (xy 319.829715 -343.128779) (xy 319.830196 -343.156032)
			(xy 319.829707 -343.183627) (xy 319.821753 -343.238242) (xy 319.806017 -343.291142) (xy 319.782826 -343.341224)
			(xy 319.752664 -343.387444) (xy 319.716159 -343.428838) (xy 319.674073 -343.464543) (xy 319.627284 -343.493814)
			(xy 319.576767 -343.516041) (xy 319.550288 -343.523824) (xy 319.537516 -343.52773) (xy 319.514475 -343.541219)
			(xy 319.495731 -343.560233) (xy 319.482574 -343.583466) (xy 319.475908 -343.609319) (xy 319.47619 -343.636017)
			(xy 319.483402 -343.661724) (xy 319.489836 -343.67343) (xy 319.947024 -344.446606) (xy 324.569328 -344.446606)
			(xy 324.569934 -344.416953) (xy 324.579123 -344.358362) (xy 324.597265 -344.301898) (xy 324.623923 -344.24892)
			(xy 324.658456 -344.200704) (xy 324.700032 -344.15841) (xy 324.723506 -344.140282) (xy 324.735339 -344.13073)
			(xy 324.753323 -344.106233) (xy 324.763305 -344.077529) (xy 324.764401 -344.047159) (xy 324.756515 -344.017811)
			(xy 324.748906 -344.004646) (xy 324.735111 -343.981796) (xy 324.713366 -343.933051) (xy 324.698629 -343.88175)
			(xy 324.691187 -343.828896) (xy 324.69074 -343.802208) (xy 324.691226 -343.774957) (xy 324.698982 -343.721009)
			(xy 324.714337 -343.668714) (xy 324.736979 -343.619137) (xy 324.766445 -343.573287) (xy 324.802136 -343.532096)
			(xy 324.843327 -343.496405) (xy 324.889177 -343.466939) (xy 324.938754 -343.444297) (xy 324.991049 -343.428942)
			(xy 325.044997 -343.421186) (xy 325.099499 -343.421186) (xy 325.153447 -343.428942) (xy 325.205742 -343.444297)
			(xy 325.255319 -343.466939) (xy 325.301169 -343.496405) (xy 325.34236 -343.532096) (xy 325.378051 -343.573287)
			(xy 325.407517 -343.619137) (xy 325.430159 -343.668714) (xy 325.445514 -343.721009) (xy 325.45327 -343.774957)
			(xy 325.453756 -343.802208) (xy 325.453167 -343.831862) (xy 325.443975 -343.890454) (xy 325.426565 -343.944632)
			(xy 344.389706 -343.944632) (xy 344.389706 -343.859936) (xy 344.397757 -343.775622) (xy 344.413786 -343.692456)
			(xy 344.437647 -343.611189) (xy 344.469126 -343.532559) (xy 344.507937 -343.457278) (xy 344.553727 -343.386026)
			(xy 344.606083 -343.31945) (xy 344.664531 -343.258152) (xy 344.728541 -343.202687) (xy 344.797533 -343.153558)
			(xy 344.870883 -343.111209) (xy 344.947926 -343.076025) (xy 345.027965 -343.048323) (xy 345.110274 -343.028355)
			(xy 345.194109 -343.016302) (xy 345.27871 -343.012272) (xy 345.363311 -343.016302) (xy 345.447146 -343.028355)
			(xy 345.529455 -343.048323) (xy 345.609494 -343.076025) (xy 345.686537 -343.111209) (xy 345.759887 -343.153558)
			(xy 345.828879 -343.202687) (xy 345.892889 -343.258152) (xy 345.951337 -343.31945) (xy 346.003693 -343.386026)
			(xy 346.049483 -343.457278) (xy 346.088294 -343.532559) (xy 346.119773 -343.611189) (xy 346.143634 -343.692456)
			(xy 346.159663 -343.775622) (xy 346.167714 -343.859936) (xy 346.168218 -343.902284) (xy 346.914219 -343.902284)
			(xy 346.918255 -343.818837) (xy 346.930327 -343.736169) (xy 346.95032 -343.655052) (xy 346.978049 -343.576243)
			(xy 347.013255 -343.500478) (xy 347.055609 -343.428465) (xy 347.104715 -343.360876) (xy 347.160116 -343.298342)
			(xy 347.221293 -343.241447) (xy 347.287676 -343.190721) (xy 347.358644 -343.14664) (xy 347.433536 -343.109614)
			(xy 347.511652 -343.079988) (xy 347.592262 -343.05804) (xy 347.674614 -343.043975) (xy 347.75794 -343.037923)
			(xy 347.84146 -343.039942) (xy 347.924396 -343.050012) (xy 348.005972 -343.06804) (xy 348.085428 -343.093857)
			(xy 348.162021 -343.127222) (xy 348.235037 -343.167823) (xy 348.303793 -343.215282) (xy 348.367647 -343.269155)
			(xy 348.426004 -343.32894) (xy 348.478319 -343.394077) (xy 348.524102 -343.46396) (xy 348.562927 -343.537935)
			(xy 348.594432 -343.615312) (xy 348.618321 -343.695369) (xy 348.634372 -343.777357) (xy 348.642435 -343.860512)
			(xy 348.64294 -343.902284) (xy 348.642435 -343.944056) (xy 348.642379 -343.944632) (xy 351.95027 -343.944632)
			(xy 351.95027 -343.859936) (xy 351.958321 -343.775622) (xy 351.97435 -343.692456) (xy 351.998211 -343.611189)
			(xy 352.02969 -343.532559) (xy 352.068501 -343.457278) (xy 352.114291 -343.386026) (xy 352.166647 -343.31945)
			(xy 352.225095 -343.258152) (xy 352.289105 -343.202687) (xy 352.358097 -343.153558) (xy 352.431447 -343.111209)
			(xy 352.50849 -343.076025) (xy 352.588529 -343.048323) (xy 352.670838 -343.028355) (xy 352.754673 -343.016302)
			(xy 352.839274 -343.012272) (xy 352.923875 -343.016302) (xy 353.00771 -343.028355) (xy 353.090019 -343.048323)
			(xy 353.170058 -343.076025) (xy 353.247101 -343.111209) (xy 353.320451 -343.153558) (xy 353.389443 -343.202687)
			(xy 353.453453 -343.258152) (xy 353.511901 -343.31945) (xy 353.564257 -343.386026) (xy 353.610047 -343.457278)
			(xy 353.648858 -343.532559) (xy 353.680337 -343.611189) (xy 353.704198 -343.692456) (xy 353.720227 -343.775622)
			(xy 353.728278 -343.859936) (xy 353.728782 -343.902284) (xy 354.474783 -343.902284) (xy 354.478819 -343.818837)
			(xy 354.490891 -343.736169) (xy 354.510884 -343.655052) (xy 354.538613 -343.576243) (xy 354.573819 -343.500478)
			(xy 354.616173 -343.428465) (xy 354.665279 -343.360876) (xy 354.72068 -343.298342) (xy 354.781857 -343.241447)
			(xy 354.84824 -343.190721) (xy 354.919208 -343.14664) (xy 354.9941 -343.109614) (xy 355.072216 -343.079988)
			(xy 355.152826 -343.05804) (xy 355.235178 -343.043975) (xy 355.318504 -343.037923) (xy 355.402024 -343.039942)
			(xy 355.48496 -343.050012) (xy 355.566536 -343.06804) (xy 355.645992 -343.093857) (xy 355.722585 -343.127222)
			(xy 355.795601 -343.167823) (xy 355.864357 -343.215282) (xy 355.928211 -343.269155) (xy 355.986568 -343.32894)
			(xy 356.038883 -343.394077) (xy 356.084666 -343.46396) (xy 356.123491 -343.537935) (xy 356.154996 -343.615312)
			(xy 356.178885 -343.695369) (xy 356.194936 -343.777357) (xy 356.202999 -343.860512) (xy 356.203504 -343.902284)
			(xy 356.202999 -343.944056) (xy 356.202943 -343.944632) (xy 359.655614 -343.944632) (xy 359.655614 -343.859936)
			(xy 359.663665 -343.775622) (xy 359.679694 -343.692456) (xy 359.703555 -343.611189) (xy 359.735034 -343.532559)
			(xy 359.773845 -343.457278) (xy 359.819635 -343.386026) (xy 359.871991 -343.31945) (xy 359.930439 -343.258152)
			(xy 359.994449 -343.202687) (xy 360.063441 -343.153558) (xy 360.136791 -343.111209) (xy 360.213834 -343.076025)
			(xy 360.293873 -343.048323) (xy 360.376182 -343.028355) (xy 360.460017 -343.016302) (xy 360.544618 -343.012272)
			(xy 360.629219 -343.016302) (xy 360.713054 -343.028355) (xy 360.795363 -343.048323) (xy 360.875402 -343.076025)
			(xy 360.952445 -343.111209) (xy 361.025795 -343.153558) (xy 361.094787 -343.202687) (xy 361.158797 -343.258152)
			(xy 361.217245 -343.31945) (xy 361.269601 -343.386026) (xy 361.315391 -343.457278) (xy 361.354202 -343.532559)
			(xy 361.385681 -343.611189) (xy 361.409542 -343.692456) (xy 361.425571 -343.775622) (xy 361.433622 -343.859936)
			(xy 361.434126 -343.902284) (xy 362.180127 -343.902284) (xy 362.184163 -343.818837) (xy 362.196235 -343.736169)
			(xy 362.216228 -343.655052) (xy 362.243957 -343.576243) (xy 362.279163 -343.500478) (xy 362.321517 -343.428465)
			(xy 362.370623 -343.360876) (xy 362.426024 -343.298342) (xy 362.487201 -343.241447) (xy 362.553584 -343.190721)
			(xy 362.624552 -343.14664) (xy 362.699444 -343.109614) (xy 362.77756 -343.079988) (xy 362.85817 -343.05804)
			(xy 362.940522 -343.043975) (xy 363.023848 -343.037923) (xy 363.107368 -343.039942) (xy 363.190304 -343.050012)
			(xy 363.27188 -343.06804) (xy 363.351336 -343.093857) (xy 363.427929 -343.127222) (xy 363.500945 -343.167823)
			(xy 363.569701 -343.215282) (xy 363.633555 -343.269155) (xy 363.691912 -343.32894) (xy 363.744227 -343.394077)
			(xy 363.79001 -343.46396) (xy 363.828835 -343.537935) (xy 363.86034 -343.615312) (xy 363.884229 -343.695369)
			(xy 363.90028 -343.777357) (xy 363.908343 -343.860512) (xy 363.908848 -343.902284) (xy 363.908343 -343.944056)
			(xy 363.908287 -343.944632) (xy 367.216178 -343.944632) (xy 367.216178 -343.859936) (xy 367.224229 -343.775622)
			(xy 367.240258 -343.692456) (xy 367.264119 -343.611189) (xy 367.295598 -343.532559) (xy 367.334409 -343.457278)
			(xy 367.380199 -343.386026) (xy 367.432555 -343.31945) (xy 367.491003 -343.258152) (xy 367.555013 -343.202687)
			(xy 367.624005 -343.153558) (xy 367.697355 -343.111209) (xy 367.774398 -343.076025) (xy 367.854437 -343.048323)
			(xy 367.936746 -343.028355) (xy 368.020581 -343.016302) (xy 368.105182 -343.012272) (xy 368.189783 -343.016302)
			(xy 368.273618 -343.028355) (xy 368.355927 -343.048323) (xy 368.435966 -343.076025) (xy 368.513009 -343.111209)
			(xy 368.586359 -343.153558) (xy 368.655351 -343.202687) (xy 368.719361 -343.258152) (xy 368.777809 -343.31945)
			(xy 368.830165 -343.386026) (xy 368.875955 -343.457278) (xy 368.914766 -343.532559) (xy 368.946245 -343.611189)
			(xy 368.970106 -343.692456) (xy 368.986135 -343.775622) (xy 368.994186 -343.859936) (xy 368.99469 -343.902284)
			(xy 369.740691 -343.902284) (xy 369.744727 -343.818837) (xy 369.756799 -343.736169) (xy 369.776792 -343.655052)
			(xy 369.804521 -343.576243) (xy 369.839727 -343.500478) (xy 369.882081 -343.428465) (xy 369.931187 -343.360876)
			(xy 369.986588 -343.298342) (xy 370.047765 -343.241447) (xy 370.114148 -343.190721) (xy 370.185116 -343.14664)
			(xy 370.260008 -343.109614) (xy 370.338124 -343.079988) (xy 370.418734 -343.05804) (xy 370.501086 -343.043975)
			(xy 370.584412 -343.037923) (xy 370.667932 -343.039942) (xy 370.750868 -343.050012) (xy 370.832444 -343.06804)
			(xy 370.9119 -343.093857) (xy 370.988493 -343.127222) (xy 371.061509 -343.167823) (xy 371.130265 -343.215282)
			(xy 371.194119 -343.269155) (xy 371.252476 -343.32894) (xy 371.304791 -343.394077) (xy 371.350574 -343.46396)
			(xy 371.389399 -343.537935) (xy 371.420904 -343.615312) (xy 371.444793 -343.695369) (xy 371.460844 -343.777357)
			(xy 371.468907 -343.860512) (xy 371.469412 -343.902284) (xy 371.468907 -343.944056) (xy 371.460844 -344.027211)
			(xy 371.444793 -344.109199) (xy 371.420904 -344.189256) (xy 371.389399 -344.266633) (xy 371.350574 -344.340608)
			(xy 371.326559 -344.377264) (xy 381.783844 -344.377264) (xy 381.784278 -344.349892) (xy 381.792102 -344.295712)
			(xy 381.807598 -344.243208) (xy 381.830447 -344.193461) (xy 381.860179 -344.147496) (xy 381.877824 -344.126566)
			(xy 381.887094 -344.115264) (xy 381.899264 -344.088697) (xy 381.903429 -344.059773) (xy 381.899248 -344.030851)
			(xy 381.887064 -344.00429) (xy 381.877824 -343.992962) (xy 381.860204 -343.972014) (xy 381.830489 -343.926046)
			(xy 381.807649 -343.876303) (xy 381.792153 -343.823805) (xy 381.78432 -343.769632) (xy 381.783844 -343.742264)
			(xy 381.78433 -343.715013) (xy 381.792086 -343.661065) (xy 381.807441 -343.60877) (xy 381.830083 -343.559193)
			(xy 381.859549 -343.513343) (xy 381.89524 -343.472152) (xy 381.936431 -343.436461) (xy 381.982281 -343.406995)
			(xy 382.031858 -343.384353) (xy 382.084153 -343.368998) (xy 382.138101 -343.361242) (xy 382.192603 -343.361242)
			(xy 382.246551 -343.368998) (xy 382.298846 -343.384353) (xy 382.348423 -343.406995) (xy 382.394273 -343.436461)
			(xy 382.435464 -343.472152) (xy 382.471155 -343.513343) (xy 382.500621 -343.559193) (xy 382.523263 -343.60877)
			(xy 382.538618 -343.661065) (xy 382.546374 -343.715013) (xy 382.54686 -343.742264) (xy 382.546383 -343.769634)
			(xy 382.538569 -343.823813) (xy 382.523083 -343.876316) (xy 382.500244 -343.926063) (xy 382.470521 -343.97203)
			(xy 382.45288 -343.992962) (xy 382.443679 -344.004316) (xy 382.4315 -344.030864) (xy 382.427322 -344.059773)
			(xy 382.431485 -344.088683) (xy 382.44365 -344.115238) (xy 382.45288 -344.126566) (xy 382.470514 -344.147503)
			(xy 382.500227 -344.193474) (xy 382.523064 -344.24322) (xy 382.538557 -344.29572) (xy 382.546386 -344.349895)
			(xy 382.54686 -344.377264) (xy 382.546374 -344.404515) (xy 382.538618 -344.458463) (xy 382.523263 -344.510758)
			(xy 382.500621 -344.560335) (xy 382.471155 -344.606185) (xy 382.435464 -344.647376) (xy 382.394273 -344.683067)
			(xy 382.348423 -344.712533) (xy 382.298846 -344.735175) (xy 382.246551 -344.75053) (xy 382.192603 -344.758286)
			(xy 382.138101 -344.758286) (xy 382.084153 -344.75053) (xy 382.031858 -344.735175) (xy 381.982281 -344.712533)
			(xy 381.936431 -344.683067) (xy 381.89524 -344.647376) (xy 381.859549 -344.606185) (xy 381.830083 -344.560335)
			(xy 381.807441 -344.510758) (xy 381.792086 -344.458463) (xy 381.78433 -344.404515) (xy 381.783844 -344.377264)
			(xy 371.326559 -344.377264) (xy 371.304791 -344.410491) (xy 371.252476 -344.475628) (xy 371.194119 -344.535413)
			(xy 371.130265 -344.589286) (xy 371.061509 -344.636745) (xy 370.988493 -344.677346) (xy 370.9119 -344.710711)
			(xy 370.832444 -344.736528) (xy 370.750868 -344.754556) (xy 370.667932 -344.764626) (xy 370.584412 -344.766645)
			(xy 370.501086 -344.760593) (xy 370.418734 -344.746528) (xy 370.338124 -344.72458) (xy 370.260008 -344.694954)
			(xy 370.185116 -344.657928) (xy 370.114148 -344.613847) (xy 370.047765 -344.563121) (xy 369.986588 -344.506226)
			(xy 369.931187 -344.443692) (xy 369.882081 -344.376103) (xy 369.839727 -344.30409) (xy 369.804521 -344.228325)
			(xy 369.776792 -344.149516) (xy 369.756799 -344.068399) (xy 369.744727 -343.985731) (xy 369.740691 -343.902284)
			(xy 368.99469 -343.902284) (xy 368.994186 -343.944632) (xy 368.986135 -344.028946) (xy 368.970106 -344.112112)
			(xy 368.946245 -344.193379) (xy 368.914766 -344.272009) (xy 368.875955 -344.34729) (xy 368.830165 -344.418542)
			(xy 368.777809 -344.485118) (xy 368.719361 -344.546416) (xy 368.655351 -344.601881) (xy 368.586359 -344.65101)
			(xy 368.513009 -344.693359) (xy 368.435966 -344.728543) (xy 368.355927 -344.756245) (xy 368.273618 -344.776213)
			(xy 368.247973 -344.7799) (xy 386.032387 -344.7799) (xy 386.036556 -344.724273) (xy 386.04897 -344.669889)
			(xy 386.069351 -344.617962) (xy 386.097243 -344.569653) (xy 386.132025 -344.526041) (xy 386.172918 -344.488101)
			(xy 386.21901 -344.456679) (xy 386.26927 -344.432478) (xy 386.322576 -344.416039) (xy 386.377736 -344.407729)
			(xy 386.405628 -344.407236) (xy 386.432959 -344.407731) (xy 386.487038 -344.415696) (xy 386.539372 -344.43148)
			(xy 386.588836 -344.454744) (xy 386.634369 -344.484988) (xy 386.674992 -344.521563) (xy 386.709832 -344.563683)
			(xy 386.724398 -344.586814) (xy 386.732342 -344.599023) (xy 386.753808 -344.618693) (xy 386.779956 -344.631498)
			(xy 386.808656 -344.636398) (xy 386.837571 -344.632992) (xy 386.851144 -344.627708) (xy 386.874352 -344.618213)
			(xy 386.922686 -344.604864) (xy 386.972376 -344.598138) (xy 386.997448 -344.597736) (xy 387.022517 -344.598156)
			(xy 387.072201 -344.604907) (xy 387.120535 -344.618241) (xy 387.143752 -344.627708) (xy 387.157334 -344.63294)
			(xy 387.186232 -344.636309) (xy 387.214909 -344.631401) (xy 387.241043 -344.618616) (xy 387.262517 -344.598987)
			(xy 387.270498 -344.586814) (xy 387.285067 -344.563683) (xy 387.31991 -344.521562) (xy 387.360533 -344.484983)
			(xy 387.406064 -344.454732) (xy 387.455526 -344.431456) (xy 387.507857 -344.415656) (xy 387.561936 -344.40767)
			(xy 387.6166 -344.40767) (xy 387.670679 -344.415656) (xy 387.72301 -344.431456) (xy 387.772472 -344.454732)
			(xy 387.818003 -344.484983) (xy 387.858626 -344.521562) (xy 387.893469 -344.563683) (xy 387.908038 -344.586814)
			(xy 387.915944 -344.59905) (xy 387.937421 -344.61872) (xy 387.963579 -344.631522) (xy 387.992288 -344.636414)
			(xy 388.021209 -344.632998) (xy 388.034784 -344.627708) (xy 388.057999 -344.618232) (xy 388.106329 -344.604875)
			(xy 388.156017 -344.598142) (xy 388.181088 -344.597736) (xy 388.207932 -344.598171) (xy 388.261065 -344.605875)
			(xy 388.312542 -344.621125) (xy 388.361297 -344.643606) (xy 388.406321 -344.672851) (xy 388.446681 -344.708256)
			(xy 388.481541 -344.749087) (xy 388.510181 -344.794499) (xy 388.532006 -344.843551) (xy 388.539736 -344.869262)
			(xy 388.544362 -344.883773) (xy 388.560887 -344.909341) (xy 388.584211 -344.928907) (xy 388.612263 -344.940734)
			(xy 388.642554 -344.943775) (xy 388.672397 -344.937757) (xy 388.68604 -344.930984) (xy 388.714189 -344.916356)
			(xy 388.774138 -344.895627) (xy 388.836696 -344.885126) (xy 388.868412 -344.884502) (xy 388.886431 -344.884725)
			(xy 388.922306 -344.888158) (xy 388.94004 -344.89136) (xy 388.955244 -344.893737) (xy 388.985802 -344.890199)
			(xy 389.013922 -344.877728) (xy 389.037058 -344.857454) (xy 389.053113 -344.831214) (xy 389.057388 -344.81643)
			(xy 389.064795 -344.789389) (xy 389.086426 -344.737665) (xy 389.11539 -344.689661) (xy 389.151065 -344.64641)
			(xy 389.192683 -344.608844) (xy 389.239348 -344.577769) (xy 389.290058 -344.553856) (xy 389.343719 -344.537617)
			(xy 389.39918 -344.529403) (xy 389.427212 -344.528902) (xy 389.454464 -344.529367) (xy 389.508413 -344.537125)
			(xy 389.560709 -344.552482) (xy 389.610287 -344.575125) (xy 389.656138 -344.604594) (xy 389.697328 -344.640288)
			(xy 389.733019 -344.68148) (xy 389.762485 -344.727333) (xy 389.785125 -344.776912) (xy 389.80048 -344.829209)
			(xy 389.808235 -344.883158) (xy 389.80872 -344.91041) (xy 389.808185 -344.937982) (xy 389.800246 -344.992551)
			(xy 389.784534 -345.04541) (xy 389.761377 -345.095456) (xy 389.731257 -345.141647) (xy 389.694801 -345.183022)
			(xy 389.6741 -345.20124) (xy 389.663193 -345.211129) (xy 389.647122 -345.235782) (xy 389.638739 -345.263992)
			(xy 389.638741 -345.293421) (xy 389.647127 -345.32163) (xy 389.663202 -345.346281) (xy 389.6741 -345.35618)
			(xy 389.694815 -345.374385) (xy 389.731279 -345.415758) (xy 389.761405 -345.461949) (xy 389.784567 -345.511998)
			(xy 389.800281 -345.564859) (xy 389.808221 -345.619433) (xy 389.80822 -345.67458) (xy 389.800279 -345.729153)
			(xy 389.784563 -345.782015) (xy 389.761399 -345.832062) (xy 389.731271 -345.878253) (xy 389.694806 -345.919624)
			(xy 389.6741 -345.93784) (xy 389.663193 -345.947729) (xy 389.647122 -345.972382) (xy 389.638739 -346.000592)
			(xy 389.638741 -346.030021) (xy 389.647127 -346.05823) (xy 389.663202 -346.082881) (xy 389.6741 -346.09278)
			(xy 389.694805 -346.110998) (xy 389.731275 -346.152365) (xy 389.761408 -346.198554) (xy 389.784575 -346.2486)
			(xy 389.800293 -346.301462) (xy 389.808234 -346.356036) (xy 389.80872 -346.38361) (xy 389.808232 -346.410861)
			(xy 389.800474 -346.464808) (xy 389.785118 -346.517102) (xy 389.762477 -346.566678) (xy 389.733011 -346.612528)
			(xy 389.697319 -346.653718) (xy 389.65613 -346.689409) (xy 389.61028 -346.718876) (xy 389.560704 -346.741517)
			(xy 389.50841 -346.756874) (xy 389.454463 -346.764631) (xy 389.427212 -346.765118) (xy 389.399358 -346.764571)
			(xy 389.344244 -346.756449) (xy 389.290895 -346.740406) (xy 389.240443 -346.716782) (xy 389.193959 -346.686078)
			(xy 389.152429 -346.648946) (xy 389.116736 -346.606174) (xy 389.087635 -346.55867) (xy 389.065746 -346.507442)
			(xy 389.05815 -346.480638) (xy 389.053874 -346.466522) (xy 389.038487 -346.441374) (xy 389.01657 -346.421656)
			(xy 388.98994 -346.409005) (xy 388.96081 -346.404471) (xy 388.946136 -346.405962) (xy 388.933182 -346.40762)
			(xy 388.907125 -346.409403) (xy 388.894066 -346.409518) (xy 388.893812 -346.409518) (xy 388.879663 -346.409423)
			(xy 388.85144 -346.40739) (xy 388.837424 -346.405454) (xy 388.82408 -346.403805) (xy 388.797379 -346.40691)
			(xy 388.772419 -346.416889) (xy 388.750936 -346.433048) (xy 388.734426 -346.454261) (xy 388.724036 -346.479053)
			(xy 388.721854 -346.492322) (xy 388.717712 -346.519466) (xy 388.702744 -346.572294) (xy 388.680358 -346.62243)
			(xy 388.651017 -346.668839) (xy 388.615326 -346.710563) (xy 388.574022 -346.74674) (xy 388.527959 -346.776623)
			(xy 388.478089 -346.799595) (xy 388.42544 -346.81518) (xy 388.371101 -346.823057) (xy 388.343648 -346.823538)
			(xy 388.316398 -346.823) (xy 388.262451 -346.81525) (xy 388.210156 -346.799902) (xy 388.160578 -346.777267)
			(xy 388.114726 -346.747807) (xy 388.073534 -346.712121) (xy 388.03784 -346.670936) (xy 388.00837 -346.62509)
			(xy 387.985725 -346.575517) (xy 387.970366 -346.523225) (xy 387.962605 -346.46928) (xy 387.96214 -346.44203)
			(xy 387.962612 -346.414456) (xy 387.970562 -346.359882) (xy 387.986284 -346.307022) (xy 388.009453 -346.256976)
			(xy 388.039585 -346.210786) (xy 388.076053 -346.169415) (xy 388.09676 -346.1512) (xy 388.10763 -346.141273)
			(xy 388.12371 -346.116632) (xy 388.1321 -346.088431) (xy 388.132106 -346.059008) (xy 388.123726 -346.030803)
			(xy 388.107656 -346.006157) (xy 388.09676 -345.99626) (xy 388.076067 -345.97803) (xy 388.039597 -345.936664)
			(xy 388.009463 -345.890478) (xy 387.986295 -345.840434) (xy 387.970574 -345.787575) (xy 387.962629 -345.733003)
			(xy 387.96214 -345.70543) (xy 387.962563 -345.678928) (xy 387.969914 -345.626435) (xy 387.984465 -345.575466)
			(xy 388.005935 -345.527005) (xy 388.033911 -345.481984) (xy 388.050532 -345.461336) (xy 388.059995 -345.449205)
			(xy 388.071785 -345.4208) (xy 388.074606 -345.390175) (xy 388.068206 -345.360093) (xy 388.05316 -345.33327)
			(xy 388.030828 -345.312125) (xy 388.017258 -345.304872) (xy 387.993566 -345.292774) (xy 387.949585 -345.262851)
			(xy 387.910304 -345.226979) (xy 387.876521 -345.185887) (xy 387.862318 -345.163394) (xy 387.854357 -345.151197)
			(xy 387.832896 -345.131527) (xy 387.806753 -345.118719) (xy 387.778056 -345.113816) (xy 387.749144 -345.117218)
			(xy 387.735572 -345.1225) (xy 387.712363 -345.13199) (xy 387.664029 -345.145341) (xy 387.61434 -345.152069)
			(xy 387.589268 -345.152472) (xy 387.564199 -345.152047) (xy 387.514516 -345.145298) (xy 387.466181 -345.131966)
			(xy 387.442964 -345.1225) (xy 387.429377 -345.117281) (xy 387.400481 -345.113909) (xy 387.371806 -345.118813)
			(xy 387.345673 -345.131595) (xy 387.324198 -345.151222) (xy 387.316218 -345.163394) (xy 387.301649 -345.186525)
			(xy 387.266806 -345.228646) (xy 387.226183 -345.265225) (xy 387.180652 -345.295476) (xy 387.13119 -345.318752)
			(xy 387.078859 -345.334552) (xy 387.02478 -345.342538) (xy 386.970116 -345.342538) (xy 386.916037 -345.334552)
			(xy 386.863706 -345.318752) (xy 386.814244 -345.295476) (xy 386.768713 -345.265225) (xy 386.72809 -345.228646)
			(xy 386.693247 -345.186525) (xy 386.678678 -345.163394) (xy 386.670755 -345.15117) (xy 386.649283 -345.131499)
			(xy 386.62313 -345.118695) (xy 386.594425 -345.1138) (xy 386.565506 -345.117212) (xy 386.551932 -345.1225)
			(xy 386.528715 -345.131972) (xy 386.480386 -345.14533) (xy 386.430699 -345.152065) (xy 386.405628 -345.152472)
			(xy 386.377736 -345.152071) (xy 386.322576 -345.143761) (xy 386.26927 -345.127322) (xy 386.21901 -345.103121)
			(xy 386.172918 -345.071699) (xy 386.132025 -345.033759) (xy 386.097243 -344.990147) (xy 386.069351 -344.941838)
			(xy 386.04897 -344.889911) (xy 386.036556 -344.835527) (xy 386.032387 -344.7799) (xy 368.247973 -344.7799)
			(xy 368.189783 -344.788266) (xy 368.105182 -344.792297) (xy 368.020581 -344.788266) (xy 367.936746 -344.776213)
			(xy 367.854437 -344.756245) (xy 367.774398 -344.728543) (xy 367.697355 -344.693359) (xy 367.624005 -344.65101)
			(xy 367.555013 -344.601881) (xy 367.491003 -344.546416) (xy 367.432555 -344.485118) (xy 367.380199 -344.418542)
			(xy 367.334409 -344.34729) (xy 367.295598 -344.272009) (xy 367.264119 -344.193379) (xy 367.240258 -344.112112)
			(xy 367.224229 -344.028946) (xy 367.216178 -343.944632) (xy 363.908287 -343.944632) (xy 363.90028 -344.027211)
			(xy 363.884229 -344.109199) (xy 363.86034 -344.189256) (xy 363.828835 -344.266633) (xy 363.79001 -344.340608)
			(xy 363.744227 -344.410491) (xy 363.691912 -344.475628) (xy 363.633555 -344.535413) (xy 363.569701 -344.589286)
			(xy 363.500945 -344.636745) (xy 363.427929 -344.677346) (xy 363.351336 -344.710711) (xy 363.27188 -344.736528)
			(xy 363.190304 -344.754556) (xy 363.107368 -344.764626) (xy 363.023848 -344.766645) (xy 362.940522 -344.760593)
			(xy 362.85817 -344.746528) (xy 362.77756 -344.72458) (xy 362.699444 -344.694954) (xy 362.624552 -344.657928)
			(xy 362.553584 -344.613847) (xy 362.487201 -344.563121) (xy 362.426024 -344.506226) (xy 362.370623 -344.443692)
			(xy 362.321517 -344.376103) (xy 362.279163 -344.30409) (xy 362.243957 -344.228325) (xy 362.216228 -344.149516)
			(xy 362.196235 -344.068399) (xy 362.184163 -343.985731) (xy 362.180127 -343.902284) (xy 361.434126 -343.902284)
			(xy 361.433622 -343.944632) (xy 361.425571 -344.028946) (xy 361.409542 -344.112112) (xy 361.385681 -344.193379)
			(xy 361.354202 -344.272009) (xy 361.315391 -344.34729) (xy 361.269601 -344.418542) (xy 361.217245 -344.485118)
			(xy 361.158797 -344.546416) (xy 361.094787 -344.601881) (xy 361.025795 -344.65101) (xy 360.952445 -344.693359)
			(xy 360.875402 -344.728543) (xy 360.795363 -344.756245) (xy 360.713054 -344.776213) (xy 360.629219 -344.788266)
			(xy 360.544618 -344.792297) (xy 360.460017 -344.788266) (xy 360.376182 -344.776213) (xy 360.293873 -344.756245)
			(xy 360.213834 -344.728543) (xy 360.136791 -344.693359) (xy 360.063441 -344.65101) (xy 359.994449 -344.601881)
			(xy 359.930439 -344.546416) (xy 359.871991 -344.485118) (xy 359.819635 -344.418542) (xy 359.773845 -344.34729)
			(xy 359.735034 -344.272009) (xy 359.703555 -344.193379) (xy 359.679694 -344.112112) (xy 359.663665 -344.028946)
			(xy 359.655614 -343.944632) (xy 356.202943 -343.944632) (xy 356.194936 -344.027211) (xy 356.178885 -344.109199)
			(xy 356.154996 -344.189256) (xy 356.123491 -344.266633) (xy 356.084666 -344.340608) (xy 356.038883 -344.410491)
			(xy 355.986568 -344.475628) (xy 355.928211 -344.535413) (xy 355.864357 -344.589286) (xy 355.795601 -344.636745)
			(xy 355.722585 -344.677346) (xy 355.645992 -344.710711) (xy 355.566536 -344.736528) (xy 355.48496 -344.754556)
			(xy 355.402024 -344.764626) (xy 355.318504 -344.766645) (xy 355.235178 -344.760593) (xy 355.152826 -344.746528)
			(xy 355.072216 -344.72458) (xy 354.9941 -344.694954) (xy 354.919208 -344.657928) (xy 354.84824 -344.613847)
			(xy 354.781857 -344.563121) (xy 354.72068 -344.506226) (xy 354.665279 -344.443692) (xy 354.616173 -344.376103)
			(xy 354.573819 -344.30409) (xy 354.538613 -344.228325) (xy 354.510884 -344.149516) (xy 354.490891 -344.068399)
			(xy 354.478819 -343.985731) (xy 354.474783 -343.902284) (xy 353.728782 -343.902284) (xy 353.728278 -343.944632)
			(xy 353.720227 -344.028946) (xy 353.704198 -344.112112) (xy 353.680337 -344.193379) (xy 353.648858 -344.272009)
			(xy 353.610047 -344.34729) (xy 353.564257 -344.418542) (xy 353.511901 -344.485118) (xy 353.453453 -344.546416)
			(xy 353.389443 -344.601881) (xy 353.320451 -344.65101) (xy 353.247101 -344.693359) (xy 353.170058 -344.728543)
			(xy 353.090019 -344.756245) (xy 353.00771 -344.776213) (xy 352.923875 -344.788266) (xy 352.839274 -344.792297)
			(xy 352.754673 -344.788266) (xy 352.670838 -344.776213) (xy 352.588529 -344.756245) (xy 352.50849 -344.728543)
			(xy 352.431447 -344.693359) (xy 352.358097 -344.65101) (xy 352.289105 -344.601881) (xy 352.225095 -344.546416)
			(xy 352.166647 -344.485118) (xy 352.114291 -344.418542) (xy 352.068501 -344.34729) (xy 352.02969 -344.272009)
			(xy 351.998211 -344.193379) (xy 351.97435 -344.112112) (xy 351.958321 -344.028946) (xy 351.95027 -343.944632)
			(xy 348.642379 -343.944632) (xy 348.634372 -344.027211) (xy 348.618321 -344.109199) (xy 348.594432 -344.189256)
			(xy 348.562927 -344.266633) (xy 348.524102 -344.340608) (xy 348.478319 -344.410491) (xy 348.426004 -344.475628)
			(xy 348.367647 -344.535413) (xy 348.303793 -344.589286) (xy 348.235037 -344.636745) (xy 348.162021 -344.677346)
			(xy 348.085428 -344.710711) (xy 348.005972 -344.736528) (xy 347.924396 -344.754556) (xy 347.84146 -344.764626)
			(xy 347.75794 -344.766645) (xy 347.674614 -344.760593) (xy 347.592262 -344.746528) (xy 347.511652 -344.72458)
			(xy 347.433536 -344.694954) (xy 347.358644 -344.657928) (xy 347.287676 -344.613847) (xy 347.221293 -344.563121)
			(xy 347.160116 -344.506226) (xy 347.104715 -344.443692) (xy 347.055609 -344.376103) (xy 347.013255 -344.30409)
			(xy 346.978049 -344.228325) (xy 346.95032 -344.149516) (xy 346.930327 -344.068399) (xy 346.918255 -343.985731)
			(xy 346.914219 -343.902284) (xy 346.168218 -343.902284) (xy 346.167714 -343.944632) (xy 346.159663 -344.028946)
			(xy 346.143634 -344.112112) (xy 346.119773 -344.193379) (xy 346.088294 -344.272009) (xy 346.049483 -344.34729)
			(xy 346.003693 -344.418542) (xy 345.951337 -344.485118) (xy 345.892889 -344.546416) (xy 345.828879 -344.601881)
			(xy 345.759887 -344.65101) (xy 345.686537 -344.693359) (xy 345.609494 -344.728543) (xy 345.529455 -344.756245)
			(xy 345.447146 -344.776213) (xy 345.363311 -344.788266) (xy 345.27871 -344.792297) (xy 345.194109 -344.788266)
			(xy 345.110274 -344.776213) (xy 345.027965 -344.756245) (xy 344.947926 -344.728543) (xy 344.870883 -344.693359)
			(xy 344.797533 -344.65101) (xy 344.728541 -344.601881) (xy 344.664531 -344.546416) (xy 344.606083 -344.485118)
			(xy 344.553727 -344.418542) (xy 344.507937 -344.34729) (xy 344.469126 -344.272009) (xy 344.437647 -344.193379)
			(xy 344.413786 -344.112112) (xy 344.397757 -344.028946) (xy 344.389706 -343.944632) (xy 325.426565 -343.944632)
			(xy 325.42583 -343.946919) (xy 325.399169 -343.999897) (xy 325.364633 -344.048112) (xy 325.323054 -344.090405)
			(xy 325.299578 -344.108532) (xy 325.287732 -344.118069) (xy 325.26975 -344.142571) (xy 325.259772 -344.171279)
			(xy 325.258678 -344.201652) (xy 325.266567 -344.231003) (xy 325.274178 -344.244168) (xy 325.287977 -344.267016)
			(xy 325.309721 -344.315762) (xy 325.324457 -344.367063) (xy 325.331898 -344.419918) (xy 325.332344 -344.446606)
			(xy 325.331858 -344.473857) (xy 325.324102 -344.527805) (xy 325.308747 -344.5801) (xy 325.286105 -344.629677)
			(xy 325.256639 -344.675527) (xy 325.220948 -344.716718) (xy 325.179757 -344.752409) (xy 325.133907 -344.781875)
			(xy 325.08433 -344.804517) (xy 325.032035 -344.819872) (xy 324.978087 -344.827628) (xy 324.923585 -344.827628)
			(xy 324.869637 -344.819872) (xy 324.817342 -344.804517) (xy 324.767765 -344.781875) (xy 324.721915 -344.752409)
			(xy 324.680724 -344.716718) (xy 324.645033 -344.675527) (xy 324.615567 -344.629677) (xy 324.592925 -344.5801)
			(xy 324.57757 -344.527805) (xy 324.569814 -344.473857) (xy 324.569328 -344.446606) (xy 319.947024 -344.446606)
			(xy 320.245908 -344.952066) (xy 322.703442 -344.952066) (xy 322.707513 -344.896444) (xy 322.719639 -344.842007)
			(xy 322.739562 -344.789916) (xy 322.766858 -344.741281) (xy 322.800944 -344.697138) (xy 322.841093 -344.658429)
			(xy 322.886451 -344.625978) (xy 322.936051 -344.600477) (xy 322.988835 -344.58247) (xy 323.043678 -344.57234)
			(xy 323.099412 -344.570303) (xy 323.154849 -344.576403) (xy 323.208806 -344.590509) (xy 323.260135 -344.612321)
			(xy 323.307741 -344.641375) (xy 323.350609 -344.67705) (xy 323.387826 -344.718587) (xy 323.418599 -344.7651)
			(xy 323.442271 -344.815597) (xy 323.458339 -344.869004) (xy 323.466459 -344.92418) (xy 323.466968 -344.952066)
			(xy 323.46688 -344.956892) (xy 323.685406 -344.956892) (xy 323.689477 -344.90127) (xy 323.701603 -344.846833)
			(xy 323.721526 -344.794742) (xy 323.748822 -344.746107) (xy 323.782908 -344.701964) (xy 323.823057 -344.663255)
			(xy 323.868415 -344.630804) (xy 323.918015 -344.605303) (xy 323.970799 -344.587296) (xy 324.025642 -344.577166)
			(xy 324.081376 -344.575129) (xy 324.136813 -344.581229) (xy 324.19077 -344.595335) (xy 324.242099 -344.617147)
			(xy 324.289705 -344.646201) (xy 324.332573 -344.681876) (xy 324.36979 -344.723413) (xy 324.400563 -344.769926)
			(xy 324.424235 -344.820423) (xy 324.430065 -344.8398) (xy 328.939331 -344.8398) (xy 328.9435 -344.78418)
			(xy 328.955912 -344.729802) (xy 328.97629 -344.677882) (xy 329.004179 -344.629579) (xy 329.038956 -344.585973)
			(xy 329.079844 -344.548037) (xy 329.12593 -344.516619) (xy 329.176183 -344.492421) (xy 329.229482 -344.475983)
			(xy 329.284636 -344.467673) (xy 329.312524 -344.46718) (xy 329.339854 -344.467705) (xy 329.39393 -344.475668)
			(xy 329.446262 -344.491448) (xy 329.495725 -344.514708) (xy 329.541258 -344.544947) (xy 329.581882 -344.581516)
			(xy 329.616726 -344.62363) (xy 329.631294 -344.646758) (xy 329.639256 -344.658956) (xy 329.660714 -344.678632)
			(xy 329.686857 -344.691442) (xy 329.715555 -344.696344) (xy 329.744468 -344.692937) (xy 329.75804 -344.687652)
			(xy 329.781247 -344.678155) (xy 329.829581 -344.664808) (xy 329.879272 -344.658082) (xy 329.904344 -344.65768)
			(xy 329.929413 -344.658105) (xy 329.979096 -344.664855) (xy 330.02743 -344.678187) (xy 330.050648 -344.687652)
			(xy 330.064237 -344.692861) (xy 330.09313 -344.696228) (xy 330.121802 -344.691324) (xy 330.147934 -344.678545)
			(xy 330.16941 -344.658926) (xy 330.177394 -344.646758) (xy 330.191963 -344.623627) (xy 330.226806 -344.581506)
			(xy 330.267429 -344.544927) (xy 330.31296 -344.514676) (xy 330.362422 -344.4914) (xy 330.414753 -344.4756)
			(xy 330.468832 -344.467614) (xy 330.523496 -344.467614) (xy 330.577575 -344.4756) (xy 330.629906 -344.4914)
			(xy 330.679368 -344.514676) (xy 330.724899 -344.544927) (xy 330.765522 -344.581506) (xy 330.800365 -344.623627)
			(xy 330.814934 -344.646758) (xy 330.822858 -344.658983) (xy 330.844326 -344.678659) (xy 330.87048 -344.691467)
			(xy 330.899187 -344.696361) (xy 330.928107 -344.692944) (xy 330.94168 -344.687652) (xy 330.964894 -344.678174)
			(xy 331.013225 -344.664819) (xy 331.062913 -344.658086) (xy 331.087984 -344.65768) (xy 331.114841 -344.658135)
			(xy 331.167998 -344.665853) (xy 331.219498 -344.681117) (xy 331.268276 -344.703613) (xy 331.313321 -344.732873)
			(xy 331.353703 -344.768293) (xy 331.388585 -344.80914) (xy 331.417247 -344.854569) (xy 331.428598 -344.878914)
			(xy 331.434622 -344.891386) (xy 331.452244 -344.912739) (xy 331.474963 -344.92856) (xy 331.501102 -344.937683)
			(xy 331.528733 -344.939433) (xy 331.555814 -344.933682) (xy 331.568298 -344.927682) (xy 331.595667 -344.914076)
			(xy 331.653678 -344.894838) (xy 331.714015 -344.885101) (xy 331.744574 -344.884502) (xy 331.744828 -344.884502)
			(xy 331.767947 -344.884832) (xy 331.813848 -344.890401) (xy 331.858736 -344.90149) (xy 331.880464 -344.909394)
			(xy 331.894243 -344.914198) (xy 331.923328 -344.916452) (xy 331.951865 -344.910395) (xy 331.977527 -344.896521)
			(xy 331.998222 -344.87596) (xy 332.012263 -344.850389) (xy 332.015846 -344.836242) (xy 332.022456 -344.808278)
			(xy 332.043051 -344.754635) (xy 332.071459 -344.704687) (xy 332.107036 -344.659565) (xy 332.148979 -344.620289)
			(xy 332.196338 -344.587748) (xy 332.248042 -344.562678) (xy 332.302921 -344.545646) (xy 332.359733 -344.537038)
			(xy 332.388464 -344.536522) (xy 332.415717 -344.536989) (xy 332.46967 -344.544742) (xy 332.521969 -344.560095)
			(xy 332.571551 -344.582735) (xy 332.617406 -344.612202) (xy 332.6586 -344.647896) (xy 332.694294 -344.689089)
			(xy 332.723762 -344.734943) (xy 332.746403 -344.784525) (xy 332.761757 -344.836824) (xy 332.769511 -344.890777)
			(xy 332.769972 -344.91803) (xy 332.76953 -344.945401) (xy 332.761708 -344.999582) (xy 332.746213 -345.052085)
			(xy 332.723366 -345.101832) (xy 332.693636 -345.147797) (xy 332.675992 -345.168728) (xy 332.666727 -345.180034)
			(xy 332.654554 -345.2066) (xy 332.650387 -345.235523) (xy 332.654567 -345.264444) (xy 332.666752 -345.291004)
			(xy 332.675992 -345.302332) (xy 332.693611 -345.32328) (xy 332.723326 -345.369248) (xy 332.746166 -345.418992)
			(xy 332.761662 -345.471489) (xy 332.769495 -345.525662) (xy 332.769972 -345.55303) (xy 332.769468 -345.580603)
			(xy 332.761525 -345.635175) (xy 332.745808 -345.688034) (xy 332.722645 -345.738081) (xy 332.692519 -345.784271)
			(xy 332.656057 -345.825644) (xy 332.635352 -345.84386) (xy 332.62442 -345.853726) (xy 332.608341 -345.878383)
			(xy 332.599957 -345.906601) (xy 332.599962 -345.936038) (xy 332.608358 -345.964252) (xy 332.624446 -345.988904)
			(xy 332.635352 -345.9988) (xy 332.656057 -346.017018) (xy 332.69253 -346.058384) (xy 332.722664 -346.104572)
			(xy 332.745831 -346.154619) (xy 332.761548 -346.207481) (xy 332.769487 -346.262055) (xy 332.769972 -346.28963)
			(xy 332.769573 -346.316885) (xy 332.761811 -346.37084) (xy 332.746449 -346.423142) (xy 332.723801 -346.472724)
			(xy 332.694326 -346.518579) (xy 332.678323 -346.537044) (xy 382.033826 -346.537044) (xy 382.033826 -346.482551)
			(xy 382.041582 -346.428612) (xy 382.056934 -346.376326) (xy 382.079571 -346.326756) (xy 382.109032 -346.280913)
			(xy 382.144717 -346.239729) (xy 382.185899 -346.204042) (xy 382.231741 -346.174579) (xy 382.281309 -346.15194)
			(xy 382.333595 -346.136585) (xy 382.387533 -346.128828) (xy 382.41478 -346.12834) (xy 382.43435 -346.128544)
			(xy 382.473291 -346.132488) (xy 382.492504 -346.136214) (xy 382.506172 -346.138647) (xy 382.533865 -346.136801)
			(xy 382.560034 -346.127559) (xy 382.582744 -346.111605) (xy 382.600312 -346.090118) (xy 382.611437 -346.064692)
			(xy 382.615296 -346.037208) (xy 382.611603 -346.009701) (xy 382.60655 -345.996768) (xy 382.596661 -345.972815)
			(xy 382.582754 -345.922894) (xy 382.57574 -345.871549) (xy 382.575308 -345.845638) (xy 382.575714 -345.818382)
			(xy 382.583467 -345.764424) (xy 382.59882 -345.712119) (xy 382.62146 -345.662531) (xy 382.650927 -345.61667)
			(xy 382.686621 -345.57547) (xy 382.727815 -345.539768) (xy 382.773671 -345.510293) (xy 382.823255 -345.487644)
			(xy 382.875557 -345.472281) (xy 382.929513 -345.464519) (xy 382.984025 -345.464515) (xy 383.037983 -345.472268)
			(xy 383.090288 -345.487622) (xy 383.139875 -345.510263) (xy 383.185736 -345.539731) (xy 383.226936 -345.575426)
			(xy 383.262636 -345.616621) (xy 383.292111 -345.662477) (xy 383.314759 -345.712061) (xy 383.33012 -345.764364)
			(xy 383.337881 -345.818321) (xy 383.337885 -345.872833) (xy 383.33013 -345.92679) (xy 383.314775 -345.979095)
			(xy 383.292133 -346.028682) (xy 383.262664 -346.074542) (xy 383.226969 -346.115741) (xy 383.185773 -346.151441)
			(xy 383.139916 -346.180914) (xy 383.090332 -346.203562) (xy 383.038029 -346.218922) (xy 382.984072 -346.226682)
			(xy 382.956816 -346.227146) (xy 382.937246 -346.226943) (xy 382.898305 -346.222999) (xy 382.879092 -346.219272)
			(xy 382.865405 -346.216953) (xy 382.837722 -346.218776) (xy 382.811557 -346.227999) (xy 382.78885 -346.243937)
			(xy 382.771282 -346.265408) (xy 382.760157 -346.290823) (xy 382.756298 -346.318296) (xy 382.759992 -346.345791)
			(xy 382.765046 -346.358718) (xy 382.774931 -346.382673) (xy 382.78884 -346.432593) (xy 382.795855 -346.483937)
			(xy 382.796288 -346.509848) (xy 382.79577 -346.537095) (xy 382.788009 -346.591033) (xy 382.77265 -346.643317)
			(xy 382.750007 -346.692884) (xy 382.720541 -346.738723) (xy 382.684851 -346.779903) (xy 382.643665 -346.815585)
			(xy 382.597819 -346.845042) (xy 382.548248 -346.867676) (xy 382.495961 -346.883024) (xy 382.442021 -346.890776)
			(xy 382.387528 -346.890772) (xy 382.33359 -346.883014) (xy 382.281304 -346.867658) (xy 382.231736 -346.845018)
			(xy 382.185895 -346.815555) (xy 382.144713 -346.779867) (xy 382.109029 -346.738683) (xy 382.079568 -346.692839)
			(xy 382.056932 -346.643269) (xy 382.04158 -346.590983) (xy 382.033826 -346.537044) (xy 332.678323 -346.537044)
			(xy 332.658626 -346.559772) (xy 332.617426 -346.595466) (xy 332.571566 -346.624932) (xy 332.52198 -346.647572)
			(xy 332.469676 -346.662925) (xy 332.415719 -346.670678) (xy 332.388464 -346.671138) (xy 332.360591 -346.670614)
			(xy 332.305439 -346.662496) (xy 332.252055 -346.646438) (xy 332.201576 -346.622782) (xy 332.155078 -346.592032)
			(xy 332.11355 -346.554842) (xy 332.077876 -346.512004) (xy 332.048817 -346.464431) (xy 332.037436 -346.438982)
			(xy 332.030807 -346.424806) (xy 332.01038 -346.401115) (xy 331.983751 -346.384701) (xy 331.953407 -346.377099)
			(xy 331.922185 -346.379018) (xy 331.907388 -346.384118) (xy 331.885475 -346.392177) (xy 331.840171 -346.403477)
			(xy 331.793828 -346.409168) (xy 331.770482 -346.409518) (xy 331.770228 -346.409518) (xy 331.756079 -346.409421)
			(xy 331.727856 -346.407389) (xy 331.71384 -346.405454) (xy 331.700495 -346.403821) (xy 331.673795 -346.406923)
			(xy 331.648836 -346.416899) (xy 331.627353 -346.433054) (xy 331.610843 -346.454264) (xy 331.600453 -346.479054)
			(xy 331.59827 -346.492322) (xy 331.594113 -346.519464) (xy 331.579146 -346.57229) (xy 331.556761 -346.622425)
			(xy 331.527421 -346.668834) (xy 331.491731 -346.710557) (xy 331.45043 -346.746735) (xy 331.404369 -346.776618)
			(xy 331.3545 -346.79959) (xy 331.301854 -346.815177) (xy 331.247517 -346.823056) (xy 331.220064 -346.823538)
			(xy 331.192813 -346.823056) (xy 331.138867 -346.815295) (xy 331.086574 -346.799937) (xy 331.036999 -346.777294)
			(xy 330.99115 -346.747827) (xy 330.949961 -346.712135) (xy 330.91427 -346.670945) (xy 330.884803 -346.625096)
			(xy 330.862161 -346.57552) (xy 330.846804 -346.523227) (xy 330.839044 -346.469281) (xy 330.838556 -346.44203)
			(xy 330.839023 -346.414455) (xy 330.846972 -346.359882) (xy 330.862696 -346.307021) (xy 330.885866 -346.256974)
			(xy 330.915999 -346.210785) (xy 330.952468 -346.169415) (xy 330.973176 -346.1512) (xy 330.984045 -346.141272)
			(xy 331.000122 -346.116631) (xy 331.008511 -346.08843) (xy 331.008517 -346.059008) (xy 331.000138 -346.030805)
			(xy 330.984071 -346.006157) (xy 330.973176 -345.99626) (xy 330.952486 -345.978026) (xy 330.916015 -345.936662)
			(xy 330.885881 -345.890476) (xy 330.862712 -345.840433) (xy 330.84699 -345.787575) (xy 330.839045 -345.733003)
			(xy 330.838556 -345.70543) (xy 330.838556 -345.704922) (xy 330.8391 -345.675514) (xy 330.848181 -345.617403)
			(xy 330.866068 -345.561372) (xy 330.89234 -345.508749) (xy 330.908914 -345.48445) (xy 330.91637 -345.473083)
			(xy 330.925686 -345.44756) (xy 330.927945 -345.420484) (xy 330.922989 -345.39377) (xy 330.911167 -345.369307)
			(xy 330.893316 -345.348824) (xy 330.882244 -345.34094) (xy 330.859621 -345.325432) (xy 330.818807 -345.288794)
			(xy 330.783827 -345.246549) (xy 330.769214 -345.223338) (xy 330.761245 -345.211145) (xy 330.739789 -345.19147)
			(xy 330.713648 -345.178659) (xy 330.684951 -345.173756) (xy 330.656039 -345.17716) (xy 330.642468 -345.182444)
			(xy 330.61926 -345.191938) (xy 330.570926 -345.205287) (xy 330.521236 -345.212013) (xy 330.496164 -345.212416)
			(xy 330.471095 -345.211988) (xy 330.421412 -345.20524) (xy 330.373078 -345.191909) (xy 330.34986 -345.182444)
			(xy 330.336267 -345.177245) (xy 330.307376 -345.173876) (xy 330.278705 -345.178779) (xy 330.252575 -345.191555)
			(xy 330.231098 -345.211171) (xy 330.223114 -345.223338) (xy 330.208545 -345.246469) (xy 330.173702 -345.28859)
			(xy 330.133079 -345.325169) (xy 330.087548 -345.35542) (xy 330.038086 -345.378696) (xy 329.985755 -345.394496)
			(xy 329.931676 -345.402482) (xy 329.877012 -345.402482) (xy 329.822933 -345.394496) (xy 329.770602 -345.378696)
			(xy 329.72114 -345.35542) (xy 329.675609 -345.325169) (xy 329.634986 -345.28859) (xy 329.600143 -345.246469)
			(xy 329.585574 -345.223338) (xy 329.577644 -345.211118) (xy 329.556177 -345.191442) (xy 329.530025 -345.178634)
			(xy 329.50132 -345.173738) (xy 329.472401 -345.177154) (xy 329.458828 -345.182444) (xy 329.435613 -345.191919)
			(xy 329.387282 -345.205275) (xy 329.337595 -345.212009) (xy 329.312524 -345.212416) (xy 329.284636 -345.211927)
			(xy 329.229482 -345.203617) (xy 329.176183 -345.187179) (xy 329.12593 -345.162981) (xy 329.079844 -345.131563)
			(xy 329.038956 -345.093627) (xy 329.004179 -345.050021) (xy 328.97629 -345.001718) (xy 328.955912 -344.949798)
			(xy 328.9435 -344.89542) (xy 328.939331 -344.8398) (xy 324.430065 -344.8398) (xy 324.440303 -344.87383)
			(xy 324.448423 -344.929006) (xy 324.448932 -344.956892) (xy 324.448423 -344.984778) (xy 324.440303 -345.039954)
			(xy 324.424235 -345.093361) (xy 324.400563 -345.143858) (xy 324.36979 -345.190371) (xy 324.332573 -345.231908)
			(xy 324.289705 -345.267583) (xy 324.242099 -345.296637) (xy 324.19077 -345.318449) (xy 324.136813 -345.332555)
			(xy 324.081376 -345.338655) (xy 324.025642 -345.336618) (xy 323.970799 -345.326488) (xy 323.918015 -345.308481)
			(xy 323.868415 -345.28298) (xy 323.823057 -345.250529) (xy 323.782908 -345.21182) (xy 323.748822 -345.167677)
			(xy 323.721526 -345.119042) (xy 323.701603 -345.066951) (xy 323.689477 -345.012514) (xy 323.685406 -344.956892)
			(xy 323.46688 -344.956892) (xy 323.466459 -344.979952) (xy 323.458339 -345.035128) (xy 323.442271 -345.088535)
			(xy 323.418599 -345.139032) (xy 323.387826 -345.185545) (xy 323.350609 -345.227082) (xy 323.307741 -345.262757)
			(xy 323.260135 -345.291811) (xy 323.208806 -345.313623) (xy 323.154849 -345.327729) (xy 323.099412 -345.333829)
			(xy 323.043678 -345.331792) (xy 322.988835 -345.321662) (xy 322.936051 -345.303655) (xy 322.886451 -345.278154)
			(xy 322.841093 -345.245703) (xy 322.800944 -345.206994) (xy 322.766858 -345.162851) (xy 322.739562 -345.114216)
			(xy 322.719639 -345.062125) (xy 322.707513 -345.007688) (xy 322.703442 -344.952066) (xy 320.245908 -344.952066)
			(xy 320.968637 -346.174314) (xy 323.948296 -346.174314) (xy 323.952367 -346.118692) (xy 323.964493 -346.064255)
			(xy 323.984416 -346.012164) (xy 324.011712 -345.963529) (xy 324.045798 -345.919386) (xy 324.085947 -345.880677)
			(xy 324.131305 -345.848226) (xy 324.180905 -345.822725) (xy 324.233689 -345.804718) (xy 324.288532 -345.794588)
			(xy 324.344266 -345.792551) (xy 324.399703 -345.798651) (xy 324.45366 -345.812757) (xy 324.504989 -345.834569)
			(xy 324.552595 -345.863623) (xy 324.595463 -345.899298) (xy 324.601093 -345.905582) (xy 325.481694 -345.905582)
			(xy 325.485765 -345.84996) (xy 325.497891 -345.795523) (xy 325.517814 -345.743432) (xy 325.54511 -345.694797)
			(xy 325.579196 -345.650654) (xy 325.619345 -345.611945) (xy 325.664703 -345.579494) (xy 325.714303 -345.553993)
			(xy 325.767087 -345.535986) (xy 325.82193 -345.525856) (xy 325.877664 -345.523819) (xy 325.933101 -345.529919)
			(xy 325.987058 -345.544025) (xy 326.038387 -345.565837) (xy 326.085993 -345.594891) (xy 326.128861 -345.630566)
			(xy 326.166078 -345.672103) (xy 326.196851 -345.718616) (xy 326.220523 -345.769113) (xy 326.236591 -345.82252)
			(xy 326.244711 -345.877696) (xy 326.24522 -345.905582) (xy 326.244711 -345.933468) (xy 326.236591 -345.988644)
			(xy 326.220523 -346.042051) (xy 326.196851 -346.092548) (xy 326.166078 -346.139061) (xy 326.128861 -346.180598)
			(xy 326.085993 -346.216273) (xy 326.038387 -346.245327) (xy 325.987058 -346.267139) (xy 325.933101 -346.281245)
			(xy 325.877664 -346.287345) (xy 325.82193 -346.285308) (xy 325.767087 -346.275178) (xy 325.714303 -346.257171)
			(xy 325.664703 -346.23167) (xy 325.619345 -346.199219) (xy 325.579196 -346.16051) (xy 325.54511 -346.116367)
			(xy 325.517814 -346.067732) (xy 325.497891 -346.015641) (xy 325.485765 -345.961204) (xy 325.481694 -345.905582)
			(xy 324.601093 -345.905582) (xy 324.63268 -345.940835) (xy 324.663453 -345.987348) (xy 324.687125 -346.037845)
			(xy 324.703193 -346.091252) (xy 324.711313 -346.146428) (xy 324.711822 -346.174314) (xy 324.711313 -346.2022)
			(xy 324.703193 -346.257376) (xy 324.687125 -346.310783) (xy 324.663453 -346.36128) (xy 324.63268 -346.407793)
			(xy 324.595463 -346.44933) (xy 324.552595 -346.485005) (xy 324.504989 -346.514059) (xy 324.45366 -346.535871)
			(xy 324.399703 -346.549977) (xy 324.344266 -346.556077) (xy 324.288532 -346.55404) (xy 324.233689 -346.54391)
			(xy 324.180905 -346.525903) (xy 324.131305 -346.500402) (xy 324.085947 -346.467951) (xy 324.045798 -346.429242)
			(xy 324.011712 -346.385099) (xy 323.984416 -346.336464) (xy 323.964493 -346.284373) (xy 323.952367 -346.229936)
			(xy 323.948296 -346.174314) (xy 320.968637 -346.174314) (xy 321.76466 -347.520514) (xy 321.772085 -347.532226)
			(xy 321.792039 -347.551465) (xy 321.816431 -347.564631) (xy 321.843464 -347.570754) (xy 321.871149 -347.569382)
			(xy 321.897445 -347.560618) (xy 321.920416 -347.545106) (xy 321.938371 -347.523988) (xy 321.949986 -347.498821)
			(xy 321.95262 -347.485208) (xy 321.957373 -347.458728) (xy 321.973349 -347.407357) (xy 321.99639 -347.358742)
			(xy 322.026037 -347.31385) (xy 322.061702 -347.273572) (xy 322.102676 -347.23871) (xy 322.148145 -347.209955)
			(xy 322.197205 -347.187879) (xy 322.248882 -347.17292) (xy 322.302149 -347.165377) (xy 322.329048 -347.164914)
			(xy 322.356296 -347.165404) (xy 322.410238 -347.173166) (xy 322.462525 -347.188525) (xy 322.512095 -347.211169)
			(xy 322.557938 -347.240637) (xy 322.59912 -347.276329) (xy 322.634805 -347.317518) (xy 322.664264 -347.363366)
			(xy 322.686899 -347.41294) (xy 322.702249 -347.465231) (xy 322.707127 -347.499178) (xy 326.2884 -347.499178)
			(xy 326.288939 -347.469489) (xy 326.298141 -347.410829) (xy 326.31632 -347.354303) (xy 326.343036 -347.301276)
			(xy 326.377645 -347.253028) (xy 326.41931 -347.210723) (xy 326.442832 -347.1926) (xy 326.453471 -347.184212)
			(xy 326.470174 -347.162889) (xy 326.480687 -347.137927) (xy 326.484272 -347.11108) (xy 326.480677 -347.084233)
			(xy 326.470153 -347.059275) (xy 326.453442 -347.03796) (xy 326.442832 -347.029532) (xy 326.419344 -347.011369)
			(xy 326.37768 -346.969072) (xy 326.343072 -346.920831) (xy 326.316356 -346.867811) (xy 326.298175 -346.811292)
			(xy 326.288969 -346.752639) (xy 326.2884 -346.722954) (xy 326.288886 -346.695703) (xy 326.296642 -346.641755)
			(xy 326.311997 -346.58946) (xy 326.334639 -346.539883) (xy 326.364105 -346.494033) (xy 326.399796 -346.452842)
			(xy 326.440987 -346.417151) (xy 326.486837 -346.387685) (xy 326.536414 -346.365043) (xy 326.588709 -346.349688)
			(xy 326.642657 -346.341932) (xy 326.697159 -346.341932) (xy 326.751107 -346.349688) (xy 326.803402 -346.365043)
			(xy 326.852979 -346.387685) (xy 326.898829 -346.417151) (xy 326.94002 -346.452842) (xy 326.975711 -346.494033)
			(xy 327.005177 -346.539883) (xy 327.027819 -346.58946) (xy 327.043174 -346.641755) (xy 327.05093 -346.695703)
			(xy 327.051416 -346.722954) (xy 327.050821 -346.75264) (xy 327.04163 -346.811297) (xy 327.023462 -346.867822)
			(xy 326.996756 -346.92085) (xy 326.984707 -346.937653) (xy 327.304861 -346.937653) (xy 327.304861 -346.883147)
			(xy 327.312618 -346.829196) (xy 327.327975 -346.776899) (xy 327.350617 -346.727319) (xy 327.380086 -346.681466)
			(xy 327.41578 -346.640274) (xy 327.456973 -346.604581) (xy 327.502826 -346.575113) (xy 327.552406 -346.552472)
			(xy 327.604704 -346.537117) (xy 327.658655 -346.529361) (xy 327.685908 -346.528898) (xy 327.686162 -346.528898)
			(xy 327.711365 -346.529306) (xy 327.761333 -346.535942) (xy 327.809988 -346.549116) (xy 327.856478 -346.568597)
			(xy 327.87844 -346.580968) (xy 327.891398 -346.58802) (xy 327.920037 -346.595048) (xy 327.94949 -346.593599)
			(xy 327.977302 -346.583795) (xy 328.001152 -346.566452) (xy 328.019051 -346.543016) (xy 328.024744 -346.529406)
			(xy 328.035473 -346.502644) (xy 328.063756 -346.452403) (xy 328.099281 -346.406993) (xy 328.141238 -346.367449)
			(xy 328.188671 -346.334674) (xy 328.240497 -346.309414) (xy 328.295536 -346.292244) (xy 328.352533 -346.283558)
			(xy 328.38136 -346.283026) (xy 328.408613 -346.283493) (xy 328.462566 -346.291245) (xy 328.514866 -346.306598)
			(xy 328.564448 -346.329238) (xy 328.610303 -346.358705) (xy 328.651497 -346.394399) (xy 328.687191 -346.435592)
			(xy 328.716659 -346.481447) (xy 328.7393 -346.531028) (xy 328.754654 -346.583328) (xy 328.762407 -346.637281)
			(xy 328.762868 -346.664534) (xy 328.762868 -346.664788) (xy 328.762281 -346.694626) (xy 328.752973 -346.753572)
			(xy 328.744326 -346.782136) (xy 328.740293 -346.796046) (xy 328.739378 -346.824979) (xy 328.74664 -346.853002)
			(xy 328.761492 -346.877849) (xy 328.782735 -346.897514) (xy 328.808653 -346.910408) (xy 328.822812 -346.913454)
			(xy 328.84889 -346.918601) (xy 328.899396 -346.935172) (xy 328.947111 -346.958596) (xy 328.991111 -346.98842)
			(xy 329.030542 -347.024066) (xy 329.064641 -347.064842) (xy 329.092747 -347.109958) (xy 329.114315 -347.158541)
			(xy 329.128927 -347.209648) (xy 329.1363 -347.262289) (xy 329.136756 -347.288866) (xy 329.13627 -347.316117)
			(xy 329.128514 -347.370065) (xy 329.113159 -347.42236) (xy 329.105453 -347.439234) (xy 383.381504 -347.439234)
			(xy 383.382082 -347.409547) (xy 383.391276 -347.350889) (xy 383.409446 -347.294363) (xy 383.436155 -347.241336)
			(xy 383.470757 -347.193086) (xy 383.512417 -347.15078) (xy 383.535936 -347.132656) (xy 383.546519 -347.124203)
			(xy 383.563221 -347.102895) (xy 383.573738 -347.077948) (xy 383.57733 -347.051113) (xy 383.573745 -347.024278)
			(xy 383.563235 -346.999328) (xy 383.546538 -346.978015) (xy 383.535936 -346.969588) (xy 383.512428 -346.95145)
			(xy 383.470765 -346.909147) (xy 383.436159 -346.860901) (xy 383.409446 -346.807877) (xy 383.39127 -346.751353)
			(xy 383.38207 -346.692697) (xy 383.381504 -346.66301) (xy 383.38199 -346.635759) (xy 383.389746 -346.581811)
			(xy 383.405101 -346.529516) (xy 383.427743 -346.479939) (xy 383.457209 -346.434089) (xy 383.4929 -346.392898)
			(xy 383.534091 -346.357207) (xy 383.579941 -346.327741) (xy 383.629518 -346.305099) (xy 383.681813 -346.289744)
			(xy 383.735761 -346.281988) (xy 383.790263 -346.281988) (xy 383.844211 -346.289744) (xy 383.896506 -346.305099)
			(xy 383.946083 -346.327741) (xy 383.991933 -346.357207) (xy 384.033124 -346.392898) (xy 384.068815 -346.434089)
			(xy 384.098281 -346.479939) (xy 384.120923 -346.529516) (xy 384.136278 -346.581811) (xy 384.144034 -346.635759)
			(xy 384.14452 -346.66301) (xy 384.143964 -346.692698) (xy 384.134764 -346.751357) (xy 384.116589 -346.807882)
			(xy 384.089876 -346.860909) (xy 384.077793 -346.877756) (xy 384.397917 -346.877756) (xy 384.397917 -346.823244)
			(xy 384.405675 -346.769286) (xy 384.421033 -346.716982) (xy 384.443679 -346.667396) (xy 384.473151 -346.621538)
			(xy 384.50885 -346.580341) (xy 384.550048 -346.544644) (xy 384.595907 -346.515173) (xy 384.645494 -346.492529)
			(xy 384.697798 -346.477172) (xy 384.751756 -346.469416) (xy 384.779012 -346.468954) (xy 384.779266 -346.468954)
			(xy 384.804469 -346.469366) (xy 384.854437 -346.476002) (xy 384.903091 -346.489175) (xy 384.949582 -346.508654)
			(xy 384.971544 -346.521024) (xy 384.984489 -346.528103) (xy 385.013135 -346.535136) (xy 385.042595 -346.533686)
			(xy 385.070411 -346.523876) (xy 385.094263 -346.506524) (xy 385.112159 -346.483078) (xy 385.117848 -346.469462)
			(xy 385.128551 -346.442689) (xy 385.156839 -346.392449) (xy 385.192369 -346.347041) (xy 385.23433 -346.307499)
			(xy 385.281766 -346.274725) (xy 385.333596 -346.249467) (xy 385.388637 -346.232299) (xy 385.445636 -346.223613)
			(xy 385.474464 -346.223082) (xy 385.501716 -346.223589) (xy 385.555664 -346.231341) (xy 385.607961 -346.246692)
			(xy 385.65754 -346.269329) (xy 385.703393 -346.298792) (xy 385.744586 -346.334482) (xy 385.78028 -346.37567)
			(xy 385.809749 -346.421519) (xy 385.832392 -346.471096) (xy 385.84775 -346.523391) (xy 385.855508 -346.577339)
			(xy 385.855972 -346.60459) (xy 385.855972 -346.604844) (xy 385.855401 -346.634683) (xy 385.846083 -346.693629)
			(xy 385.83743 -346.722192) (xy 385.833331 -346.736085) (xy 385.832428 -346.765028) (xy 385.839703 -346.793056)
			(xy 385.854568 -346.817907) (xy 385.875823 -346.837573) (xy 385.901752 -346.850466) (xy 385.915916 -346.85351)
			(xy 385.941986 -346.858696) (xy 385.992488 -346.875265) (xy 386.040201 -346.898686) (xy 386.084199 -346.928506)
			(xy 386.12363 -346.964147) (xy 386.157729 -347.004918) (xy 386.185837 -347.05003) (xy 386.207407 -347.098607)
			(xy 386.222023 -347.149709) (xy 386.229401 -347.202346) (xy 386.22986 -347.228922) (xy 386.229374 -347.256173)
			(xy 386.221618 -347.310121) (xy 386.206263 -347.362416) (xy 386.183621 -347.411993) (xy 386.154155 -347.457843)
			(xy 386.118464 -347.499034) (xy 386.077273 -347.534725) (xy 386.031423 -347.564191) (xy 385.981846 -347.586833)
			(xy 385.929551 -347.602188) (xy 385.875603 -347.609944) (xy 385.821101 -347.609944) (xy 385.767153 -347.602188)
			(xy 385.714858 -347.586833) (xy 385.665281 -347.564191) (xy 385.619431 -347.534725) (xy 385.57824 -347.499034)
			(xy 385.542549 -347.457843) (xy 385.513083 -347.411993) (xy 385.490441 -347.362416) (xy 385.475086 -347.310121)
			(xy 385.46733 -347.256173) (xy 385.466844 -347.228922) (xy 385.466844 -347.228668) (xy 385.467421 -347.198829)
			(xy 385.476735 -347.139883) (xy 385.485386 -347.11132) (xy 385.489459 -347.097421) (xy 385.490364 -347.068483)
			(xy 385.483092 -347.040458) (xy 385.468233 -347.015609) (xy 385.446984 -346.995944) (xy 385.421061 -346.983049)
			(xy 385.4069 -346.980002) (xy 385.37406 -346.973421) (xy 385.311208 -346.950297) (xy 385.281932 -346.934028)
			(xy 385.26899 -346.926946) (xy 385.240345 -346.919923) (xy 385.210887 -346.921377) (xy 385.183072 -346.931188)
			(xy 385.159221 -346.948537) (xy 385.141321 -346.971977) (xy 385.135628 -346.98559) (xy 385.12492 -347.012361)
			(xy 385.096635 -347.062604) (xy 385.061107 -347.108014) (xy 385.019147 -347.147557) (xy 384.971711 -347.180332)
			(xy 384.919882 -347.20559) (xy 384.86484 -347.222757) (xy 384.80784 -347.23144) (xy 384.779012 -347.23197)
			(xy 384.751756 -347.231584) (xy 384.697798 -347.223828) (xy 384.645494 -347.208471) (xy 384.595907 -347.185827)
			(xy 384.550048 -347.156356) (xy 384.50885 -347.120659) (xy 384.473151 -347.079462) (xy 384.443679 -347.033604)
			(xy 384.421033 -346.984018) (xy 384.405675 -346.931714) (xy 384.397917 -346.877756) (xy 384.077793 -346.877756)
			(xy 384.05527 -346.909158) (xy 384.013608 -346.951464) (xy 383.990088 -346.969588) (xy 383.979459 -346.977989)
			(xy 383.962753 -346.999307) (xy 383.952237 -347.024267) (xy 383.948649 -347.051113) (xy 383.952243 -347.077958)
			(xy 383.962766 -347.102915) (xy 383.979478 -347.12423) (xy 383.990088 -347.132656) (xy 384.013622 -347.150762)
			(xy 384.055282 -347.193072) (xy 384.089884 -347.241325) (xy 384.116593 -347.294356) (xy 384.134764 -347.350884)
			(xy 384.143958 -347.409545) (xy 384.14452 -347.439234) (xy 384.144034 -347.466485) (xy 384.136278 -347.520433)
			(xy 384.120923 -347.572728) (xy 384.098281 -347.622305) (xy 384.068815 -347.668155) (xy 384.033124 -347.709346)
			(xy 383.991933 -347.745037) (xy 383.946083 -347.774503) (xy 383.896506 -347.797145) (xy 383.844211 -347.8125)
			(xy 383.790263 -347.820256) (xy 383.735761 -347.820256) (xy 383.681813 -347.8125) (xy 383.629518 -347.797145)
			(xy 383.579941 -347.774503) (xy 383.534091 -347.745037) (xy 383.4929 -347.709346) (xy 383.457209 -347.668155)
			(xy 383.427743 -347.622305) (xy 383.405101 -347.572728) (xy 383.389746 -347.520433) (xy 383.38199 -347.466485)
			(xy 383.381504 -347.439234) (xy 329.105453 -347.439234) (xy 329.090517 -347.471937) (xy 329.061051 -347.517787)
			(xy 329.02536 -347.558978) (xy 328.984169 -347.594669) (xy 328.938319 -347.624135) (xy 328.888742 -347.646777)
			(xy 328.836447 -347.662132) (xy 328.782499 -347.669888) (xy 328.727997 -347.669888) (xy 328.674049 -347.662132)
			(xy 328.621754 -347.646777) (xy 328.572177 -347.624135) (xy 328.526327 -347.594669) (xy 328.485136 -347.558978)
			(xy 328.449445 -347.517787) (xy 328.419979 -347.471937) (xy 328.397337 -347.42236) (xy 328.381982 -347.370065)
			(xy 328.374226 -347.316117) (xy 328.37374 -347.288866) (xy 328.37374 -347.288612) (xy 328.374328 -347.258774)
			(xy 328.383635 -347.199828) (xy 328.392282 -347.171264) (xy 328.396308 -347.157353) (xy 328.397223 -347.128421)
			(xy 328.389962 -347.1004) (xy 328.375111 -347.075553) (xy 328.35387 -347.055888) (xy 328.327954 -347.042993)
			(xy 328.313796 -347.039946) (xy 328.280955 -347.033371) (xy 328.218103 -347.010243) (xy 328.188828 -346.993972)
			(xy 328.175839 -346.98698) (xy 328.147211 -346.979935) (xy 328.117765 -346.98137) (xy 328.089957 -346.991163)
			(xy 328.06611 -347.008498) (xy 328.048214 -347.031927) (xy 328.042524 -347.045534) (xy 328.031843 -347.072316)
			(xy 328.003552 -347.122557) (xy 327.968019 -347.167966) (xy 327.926055 -347.207508) (xy 327.878616 -347.24028)
			(xy 327.826783 -347.265537) (xy 327.771739 -347.282702) (xy 327.714737 -347.291385) (xy 327.685908 -347.291914)
			(xy 327.658655 -347.291439) (xy 327.604704 -347.283683) (xy 327.552406 -347.268328) (xy 327.502826 -347.245687)
			(xy 327.456973 -347.216219) (xy 327.41578 -347.180526) (xy 327.380086 -347.139334) (xy 327.350617 -347.093481)
			(xy 327.327975 -347.043901) (xy 327.312618 -346.991604) (xy 327.304861 -346.937653) (xy 326.984707 -346.937653)
			(xy 326.962158 -346.9691) (xy 326.920501 -347.011407) (xy 326.896984 -347.029532) (xy 326.886411 -347.037998)
			(xy 326.869706 -347.059302) (xy 326.859187 -347.084247) (xy 326.855592 -347.11108) (xy 326.859176 -347.137914)
			(xy 326.869685 -347.162863) (xy 326.886382 -347.184173) (xy 326.896984 -347.1926) (xy 326.920491 -347.21074)
			(xy 326.962153 -347.253043) (xy 326.996758 -347.301289) (xy 327.023471 -347.354313) (xy 327.041648 -347.410835)
			(xy 327.050849 -347.469491) (xy 327.051416 -347.499178) (xy 327.05093 -347.526429) (xy 327.043174 -347.580377)
			(xy 327.027819 -347.632672) (xy 327.005177 -347.682249) (xy 326.975711 -347.728099) (xy 326.94002 -347.76929)
			(xy 326.898829 -347.804981) (xy 326.852979 -347.834447) (xy 326.803402 -347.857089) (xy 326.751107 -347.872444)
			(xy 326.697159 -347.8802) (xy 326.642657 -347.8802) (xy 326.588709 -347.872444) (xy 326.536414 -347.857089)
			(xy 326.486837 -347.834447) (xy 326.440987 -347.804981) (xy 326.399796 -347.76929) (xy 326.364105 -347.728099)
			(xy 326.334639 -347.682249) (xy 326.311997 -347.632672) (xy 326.296642 -347.580377) (xy 326.288886 -347.526429)
			(xy 326.2884 -347.499178) (xy 322.707127 -347.499178) (xy 322.710001 -347.519174) (xy 322.710556 -347.546422)
			(xy 322.710109 -347.572801) (xy 322.702844 -347.625055) (xy 322.688453 -347.675812) (xy 322.667213 -347.724105)
			(xy 322.639527 -347.769014) (xy 322.605921 -347.809684) (xy 322.567038 -347.84534) (xy 322.523615 -347.875304)
			(xy 322.500244 -347.887544) (xy 322.487887 -347.894245) (xy 322.467162 -347.913218) (xy 322.452405 -347.937129)
			(xy 322.444736 -347.964161) (xy 322.444739 -347.992259) (xy 322.452413 -348.019289) (xy 322.467175 -348.043197)
			(xy 322.487904 -348.062167) (xy 322.500244 -348.0689) (xy 322.523614 -348.081145) (xy 322.567041 -348.111103)
			(xy 322.60593 -348.146756) (xy 322.639539 -348.187425) (xy 322.667227 -348.232334) (xy 322.688468 -348.280628)
			(xy 322.702856 -348.331386) (xy 322.710118 -348.383643) (xy 322.710556 -348.410022) (xy 322.710076 -348.437161)
			(xy 322.702379 -348.490892) (xy 322.687143 -348.542988) (xy 322.664676 -348.592399) (xy 322.635431 -348.638126)
			(xy 322.6 -348.679246) (xy 322.559098 -348.714928) (xy 322.536566 -348.730062) (xy 322.495672 -348.756732)
			(xy 323.760426 -350.895412) (xy 336.039206 -350.895412) (xy 336.039731 -350.866495) (xy 336.048458 -350.809324)
			(xy 336.065715 -350.754126) (xy 336.091105 -350.702164) (xy 336.124048 -350.65463) (xy 336.163787 -350.612612)
			(xy 336.186272 -350.594422) (xy 336.198067 -350.584512) (xy 336.215587 -350.559193) (xy 336.224765 -350.529802)
			(xy 336.224768 -350.499012) (xy 336.215593 -350.469621) (xy 336.198077 -350.444299) (xy 336.186272 -350.434402)
			(xy 336.163784 -350.416217) (xy 336.12405 -350.374195) (xy 336.091112 -350.326659) (xy 336.065725 -350.274696)
			(xy 336.04847 -350.219498) (xy 336.039741 -350.162328) (xy 336.039206 -350.133412) (xy 336.039743 -350.1044)
			(xy 336.048511 -350.047042) (xy 336.065861 -349.991673) (xy 336.091395 -349.939569) (xy 336.124522 -349.891931)
			(xy 336.144108 -349.870522) (xy 336.154365 -349.858964) (xy 336.167938 -349.831216) (xy 336.1726 -349.80068)
			(xy 336.167925 -349.770145) (xy 336.154342 -349.742403) (xy 336.144108 -349.730822) (xy 336.124536 -349.709401)
			(xy 336.091417 -349.661761) (xy 336.065886 -349.609659) (xy 336.04853 -349.554295) (xy 336.039748 -349.496942)
			(xy 336.039206 -349.467932) (xy 336.039729 -349.440676) (xy 336.04749 -349.386719) (xy 336.062846 -349.334415)
			(xy 336.085484 -349.284826) (xy 336.114944 -349.23896) (xy 336.150627 -349.19775) (xy 336.191808 -349.162033)
			(xy 336.214466 -349.146876) (xy 336.226362 -349.138554) (xy 336.245364 -349.116627) (xy 336.25742 -349.090236)
			(xy 336.261553 -349.061517) (xy 336.25743 -349.032797) (xy 336.245383 -349.006402) (xy 336.226389 -348.984469)
			(xy 336.214466 -348.976188) (xy 336.19178 -348.961065) (xy 336.150579 -348.925356) (xy 336.11488 -348.884147)
			(xy 336.085409 -348.838276) (xy 336.062767 -348.788677) (xy 336.047415 -348.736361) (xy 336.039664 -348.682393)
			(xy 336.039206 -348.655132) (xy 336.039685 -348.627879) (xy 336.047438 -348.573928) (xy 336.062791 -348.52163)
			(xy 336.085431 -348.472049) (xy 336.114897 -348.426195) (xy 336.150589 -348.385001) (xy 336.19178 -348.349307)
			(xy 336.237633 -348.319839) (xy 336.287213 -348.297197) (xy 336.339511 -348.281842) (xy 336.393461 -348.274086)
			(xy 336.420714 -348.273624) (xy 336.446635 -348.274074) (xy 336.497997 -348.281107) (xy 336.547935 -348.295027)
			(xy 336.595529 -348.315578) (xy 336.639903 -348.342383) (xy 336.680241 -348.374947) (xy 336.698336 -348.393512)
			(xy 336.707692 -348.402998) (xy 336.730329 -348.417038) (xy 336.755831 -348.424737) (xy 336.782456 -348.425569)
			(xy 336.808389 -348.419477) (xy 336.831858 -348.406876) (xy 336.851264 -348.388627) (xy 336.85861 -348.37751)
			(xy 336.873637 -348.354274) (xy 336.909342 -348.312) (xy 336.950778 -348.275326) (xy 336.997075 -348.245019)
			(xy 337.047264 -348.221716) (xy 337.100292 -348.205904) (xy 337.155047 -348.197915) (xy 337.182714 -348.197424)
			(xy 337.209967 -348.197847) (xy 337.263918 -348.205606) (xy 337.316215 -348.220963) (xy 337.365795 -348.243607)
			(xy 337.411647 -348.273076) (xy 337.452839 -348.308771) (xy 337.488532 -348.349964) (xy 337.518 -348.395818)
			(xy 337.540642 -348.445398) (xy 337.555997 -348.497696) (xy 337.563754 -348.551647) (xy 337.563754 -348.606153)
			(xy 337.560749 -348.627052) (xy 337.766138 -348.627052) (xy 337.766138 -348.572548) (xy 337.773894 -348.518599)
			(xy 337.789248 -348.466303) (xy 337.811888 -348.416723) (xy 337.841353 -348.37087) (xy 337.877043 -348.329677)
			(xy 337.918232 -348.293982) (xy 337.964081 -348.264511) (xy 338.013657 -348.241865) (xy 338.065952 -348.226504)
			(xy 338.1199 -348.218741) (xy 338.147152 -348.218252) (xy 338.176069 -348.218785) (xy 338.23324 -348.227508)
			(xy 338.288439 -348.244762) (xy 338.340402 -348.270151) (xy 338.387936 -348.303093) (xy 338.429952 -348.342833)
			(xy 338.448142 -348.365318) (xy 338.458039 -348.377123) (xy 338.483363 -348.394642) (xy 338.512756 -348.403818)
			(xy 338.543548 -348.403818) (xy 338.572941 -348.394642) (xy 338.598265 -348.377123) (xy 338.608162 -348.365318)
			(xy 338.624915 -348.344535) (xy 338.663269 -348.307405) (xy 338.706423 -348.275983) (xy 338.753537 -348.250884)
			(xy 338.803689 -348.232598) (xy 338.8559 -348.221481) (xy 338.909152 -348.217751) (xy 338.962404 -348.221481)
			(xy 339.014615 -348.232598) (xy 339.064767 -348.250884) (xy 339.111881 -348.275983) (xy 339.155035 -348.307405)
			(xy 339.193389 -348.344535) (xy 339.210142 -348.365318) (xy 339.220039 -348.377123) (xy 339.245363 -348.394642)
			(xy 339.274756 -348.403818) (xy 339.305548 -348.403818) (xy 339.334941 -348.394642) (xy 339.360265 -348.377123)
			(xy 339.370162 -348.365318) (xy 339.386915 -348.344535) (xy 339.425269 -348.307405) (xy 339.468423 -348.275983)
			(xy 339.515537 -348.250884) (xy 339.565689 -348.232598) (xy 339.6179 -348.221481) (xy 339.671152 -348.217751)
			(xy 339.724404 -348.221481) (xy 339.776615 -348.232598) (xy 339.826767 -348.250884) (xy 339.873881 -348.275983)
			(xy 339.917035 -348.307405) (xy 339.955389 -348.344535) (xy 339.972142 -348.365318) (xy 339.982039 -348.377123)
			(xy 340.007363 -348.394642) (xy 340.036756 -348.403818) (xy 340.067548 -348.403818) (xy 340.096941 -348.394642)
			(xy 340.122265 -348.377123) (xy 340.132162 -348.365318) (xy 340.150379 -348.342856) (xy 340.192393 -348.303119)
			(xy 340.239922 -348.270177) (xy 340.291878 -348.244785) (xy 340.347072 -348.227524) (xy 340.404237 -348.21879)
			(xy 340.433152 -348.218252) (xy 340.461719 -348.218782) (xy 340.518214 -348.227316) (xy 340.572807 -348.244169)
			(xy 340.624281 -348.268966) (xy 340.671487 -348.301155) (xy 340.713371 -348.340015) (xy 340.731602 -348.362016)
			(xy 340.741172 -348.373259) (xy 340.765411 -348.390096) (xy 340.793451 -348.399307) (xy 340.822953 -348.400124)
			(xy 340.851459 -348.392478) (xy 340.876593 -348.377006) (xy 340.886796 -348.366334) (xy 340.904952 -348.346705)
			(xy 340.945838 -348.312247) (xy 340.991134 -348.283834) (xy 341.039954 -348.262024) (xy 341.09134 -348.247243)
			(xy 341.144287 -348.239782) (xy 341.171022 -348.239334) (xy 341.199937 -348.239896) (xy 341.257107 -348.248614)
			(xy 341.312306 -348.265862) (xy 341.364268 -348.291246) (xy 341.411803 -348.324183) (xy 341.453821 -348.363917)
			(xy 341.472012 -348.3864) (xy 341.481909 -348.398205) (xy 341.507233 -348.415724) (xy 341.536626 -348.4249)
			(xy 341.567418 -348.4249) (xy 341.596811 -348.415724) (xy 341.622135 -348.398205) (xy 341.632032 -348.3864)
			(xy 341.650205 -348.363901) (xy 341.692228 -348.324167) (xy 341.739767 -348.29123) (xy 341.791732 -348.265844)
			(xy 341.846933 -348.248591) (xy 341.904105 -348.239867) (xy 341.933022 -348.239334) (xy 341.960275 -348.239737)
			(xy 342.014227 -348.247497) (xy 342.066524 -348.262856) (xy 342.116104 -348.285501) (xy 342.161957 -348.314971)
			(xy 342.203149 -348.350666) (xy 342.238842 -348.391861) (xy 342.26831 -348.437715) (xy 342.290952 -348.487296)
			(xy 342.306307 -348.539595) (xy 342.314064 -348.593547) (xy 342.314064 -348.648053) (xy 342.306307 -348.702005)
			(xy 342.290952 -348.754304) (xy 342.26831 -348.803885) (xy 342.238842 -348.849739) (xy 342.203149 -348.890934)
			(xy 342.161957 -348.926629) (xy 342.116104 -348.956099) (xy 342.066524 -348.978744) (xy 342.014227 -348.994103)
			(xy 341.960275 -349.001863) (xy 341.933022 -349.00235) (xy 341.904105 -349.001835) (xy 341.846933 -348.993108)
			(xy 341.791733 -348.975851) (xy 341.739771 -348.950458) (xy 341.692237 -348.917513) (xy 341.650221 -348.877771)
			(xy 341.632032 -348.855284) (xy 341.622135 -348.843479) (xy 341.596811 -348.82596) (xy 341.567418 -348.816784)
			(xy 341.536626 -348.816784) (xy 341.507233 -348.82596) (xy 341.481909 -348.843479) (xy 341.472012 -348.855284)
			(xy 341.45381 -348.877758) (xy 341.411793 -348.917495) (xy 341.364261 -348.950435) (xy 341.312301 -348.975826)
			(xy 341.257106 -348.993084) (xy 341.199937 -349.001814) (xy 341.171022 -349.00235) (xy 341.142456 -349.001766)
			(xy 341.085964 -348.993244) (xy 341.031372 -348.976401) (xy 340.979898 -348.951614) (xy 340.932691 -348.919435)
			(xy 340.890804 -348.880583) (xy 340.872572 -348.858586) (xy 340.86303 -348.847318) (xy 340.838783 -348.83048)
			(xy 340.810736 -348.821272) (xy 340.781228 -348.82046) (xy 340.752717 -348.828113) (xy 340.727582 -348.843592)
			(xy 340.717378 -348.854268) (xy 340.699186 -348.873862) (xy 340.658307 -348.908323) (xy 340.613018 -348.93674)
			(xy 340.564206 -348.958556) (xy 340.512826 -348.973344) (xy 340.459885 -348.980815) (xy 340.433152 -348.981268)
			(xy 340.404236 -348.980725) (xy 340.347065 -348.972002) (xy 340.291866 -348.95475) (xy 340.239904 -348.929363)
			(xy 340.19237 -348.896424) (xy 340.150352 -348.856686) (xy 340.132162 -348.834202) (xy 340.122265 -348.822397)
			(xy 340.096941 -348.804878) (xy 340.067548 -348.795702) (xy 340.036756 -348.795702) (xy 340.007363 -348.804878)
			(xy 339.982039 -348.822397) (xy 339.972142 -348.834202) (xy 339.955389 -348.854985) (xy 339.917035 -348.892115)
			(xy 339.873881 -348.923537) (xy 339.826767 -348.948636) (xy 339.776615 -348.966922) (xy 339.724404 -348.978039)
			(xy 339.671152 -348.981769) (xy 339.6179 -348.978039) (xy 339.565689 -348.966922) (xy 339.515537 -348.948636)
			(xy 339.468423 -348.923537) (xy 339.425269 -348.892115) (xy 339.386915 -348.854985) (xy 339.370162 -348.834202)
			(xy 339.360265 -348.822397) (xy 339.334941 -348.804878) (xy 339.305548 -348.795702) (xy 339.274756 -348.795702)
			(xy 339.245363 -348.804878) (xy 339.220039 -348.822397) (xy 339.210142 -348.834202) (xy 339.193389 -348.854985)
			(xy 339.155035 -348.892115) (xy 339.111881 -348.923537) (xy 339.064767 -348.948636) (xy 339.014615 -348.966922)
			(xy 338.962404 -348.978039) (xy 338.909152 -348.981769) (xy 338.8559 -348.978039) (xy 338.803689 -348.966922)
			(xy 338.753537 -348.948636) (xy 338.706423 -348.923537) (xy 338.663269 -348.892115) (xy 338.624915 -348.854985)
			(xy 338.608162 -348.834202) (xy 338.598265 -348.822397) (xy 338.572941 -348.804878) (xy 338.543548 -348.795702)
			(xy 338.512756 -348.795702) (xy 338.483363 -348.804878) (xy 338.458039 -348.822397) (xy 338.448142 -348.834202)
			(xy 338.429928 -348.856666) (xy 338.387913 -348.896402) (xy 338.340383 -348.929343) (xy 338.288426 -348.954735)
			(xy 338.233233 -348.971996) (xy 338.176067 -348.98073) (xy 338.147152 -348.981268) (xy 338.1199 -348.980859)
			(xy 338.065952 -348.973096) (xy 338.013657 -348.957735) (xy 337.964081 -348.935089) (xy 337.918232 -348.905618)
			(xy 337.877043 -348.869923) (xy 337.841353 -348.82873) (xy 337.811888 -348.782877) (xy 337.789248 -348.733297)
			(xy 337.773894 -348.681001) (xy 337.766138 -348.627052) (xy 337.560749 -348.627052) (xy 337.555997 -348.660104)
			(xy 337.540642 -348.712402) (xy 337.518 -348.761982) (xy 337.488532 -348.807836) (xy 337.452839 -348.849029)
			(xy 337.411647 -348.884724) (xy 337.365795 -348.914193) (xy 337.316215 -348.936837) (xy 337.263918 -348.952194)
			(xy 337.209967 -348.959953) (xy 337.182714 -348.96044) (xy 337.156793 -348.960017) (xy 337.10543 -348.952976)
			(xy 337.055492 -348.939049) (xy 337.007899 -348.918493) (xy 336.963525 -348.891684) (xy 336.923187 -348.859117)
			(xy 336.905092 -348.840552) (xy 336.895703 -348.831104) (xy 336.873072 -348.817068) (xy 336.84758 -348.809369)
			(xy 336.820963 -348.808534) (xy 336.795038 -348.814618) (xy 336.771572 -348.827208) (xy 336.752166 -348.845443)
			(xy 336.744818 -348.856554) (xy 336.729487 -348.880269) (xy 336.692936 -348.923312) (xy 336.650442 -348.960499)
			(xy 336.626962 -348.976188) (xy 336.614968 -348.984388) (xy 336.595949 -349.006342) (xy 336.583886 -349.032766)
			(xy 336.579756 -349.061517) (xy 336.583895 -349.090268) (xy 336.595967 -349.116687) (xy 336.614994 -349.138635)
			(xy 336.626962 -349.146876) (xy 336.653745 -349.164882) (xy 336.701371 -349.208427) (xy 336.721704 -349.23349)
			(xy 336.731601 -349.245295) (xy 336.756925 -349.262814) (xy 336.786318 -349.27199) (xy 336.81711 -349.27199)
			(xy 336.846503 -349.262814) (xy 336.871827 -349.245295) (xy 336.881724 -349.23349) (xy 336.899899 -349.210993)
			(xy 336.941922 -349.171259) (xy 336.989461 -349.138322) (xy 337.041425 -349.112936) (xy 337.096625 -349.095683)
			(xy 337.153797 -349.086957) (xy 337.182714 -349.086424) (xy 337.209969 -349.086842) (xy 337.263923 -349.094602)
			(xy 337.316224 -349.109961) (xy 337.365806 -349.132608) (xy 337.411661 -349.16208) (xy 337.452854 -349.197779)
			(xy 337.488548 -349.238976) (xy 337.518015 -349.284834) (xy 337.540655 -349.33442) (xy 337.556008 -349.386722)
			(xy 337.563761 -349.440677) (xy 337.564222 -349.467932) (xy 337.563704 -349.496945) (xy 337.554931 -349.554303)
			(xy 337.537575 -349.609672) (xy 337.512038 -349.661775) (xy 337.478908 -349.709413) (xy 337.45932 -349.730822)
			(xy 337.449116 -349.742424) (xy 337.435534 -349.770156) (xy 337.43086 -349.80068) (xy 337.435521 -349.831205)
			(xy 337.449093 -349.858943) (xy 337.45932 -349.870522) (xy 337.478917 -349.891921) (xy 337.512032 -349.939567)
			(xy 337.537558 -349.991675) (xy 337.554908 -350.047044) (xy 337.563683 -350.1044) (xy 337.564222 -350.133412)
			(xy 337.563824 -350.15424) (xy 337.765644 -350.15424) (xy 337.766188 -350.125228) (xy 337.774952 -350.06787)
			(xy 337.792301 -350.012501) (xy 337.817833 -349.960397) (xy 337.85096 -349.912759) (xy 337.870546 -349.89135)
			(xy 337.880781 -349.879772) (xy 337.894365 -349.852032) (xy 337.899035 -349.8215) (xy 337.894365 -349.790968)
			(xy 337.880781 -349.763228) (xy 337.870546 -349.75165) (xy 337.850977 -349.730227) (xy 337.81786 -349.682586)
			(xy 337.79233 -349.630485) (xy 337.774972 -349.575122) (xy 337.766188 -349.51777) (xy 337.765644 -349.48876)
			(xy 337.76614 -349.46151) (xy 337.773901 -349.407565) (xy 337.789259 -349.355274) (xy 337.811901 -349.305699)
			(xy 337.841367 -349.259851) (xy 337.877057 -349.218663) (xy 337.918245 -349.182972) (xy 337.964092 -349.153505)
			(xy 338.013666 -349.130862) (xy 338.065957 -349.115503) (xy 338.119902 -349.107741) (xy 338.147152 -349.107252)
			(xy 338.176069 -349.107785) (xy 338.23324 -349.116508) (xy 338.288439 -349.133762) (xy 338.340402 -349.159151)
			(xy 338.387936 -349.192093) (xy 338.429952 -349.231833) (xy 338.448142 -349.254318) (xy 338.458039 -349.266123)
			(xy 338.483363 -349.283642) (xy 338.512756 -349.292818) (xy 338.543548 -349.292818) (xy 338.572941 -349.283642)
			(xy 338.598265 -349.266123) (xy 338.608162 -349.254318) (xy 338.624915 -349.233535) (xy 338.663269 -349.196405)
			(xy 338.706423 -349.164983) (xy 338.753537 -349.139884) (xy 338.803689 -349.121598) (xy 338.8559 -349.110481)
			(xy 338.909152 -349.106751) (xy 338.962404 -349.110481) (xy 339.014615 -349.121598) (xy 339.064767 -349.139884)
			(xy 339.111881 -349.164983) (xy 339.155035 -349.196405) (xy 339.193389 -349.233535) (xy 339.210142 -349.254318)
			(xy 339.220039 -349.266123) (xy 339.245363 -349.283642) (xy 339.274756 -349.292818) (xy 339.305548 -349.292818)
			(xy 339.334941 -349.283642) (xy 339.360265 -349.266123) (xy 339.370162 -349.254318) (xy 339.386915 -349.233535)
			(xy 339.425269 -349.196405) (xy 339.468423 -349.164983) (xy 339.515537 -349.139884) (xy 339.565689 -349.121598)
			(xy 339.6179 -349.110481) (xy 339.671152 -349.106751) (xy 339.724404 -349.110481) (xy 339.776615 -349.121598)
			(xy 339.826767 -349.139884) (xy 339.873881 -349.164983) (xy 339.917035 -349.196405) (xy 339.955389 -349.233535)
			(xy 339.972142 -349.254318) (xy 339.982039 -349.266123) (xy 340.007363 -349.283642) (xy 340.036756 -349.292818)
			(xy 340.067548 -349.292818) (xy 340.096941 -349.283642) (xy 340.122265 -349.266123) (xy 340.132162 -349.254318)
			(xy 340.150379 -349.231856) (xy 340.192393 -349.192119) (xy 340.239922 -349.159177) (xy 340.291878 -349.133785)
			(xy 340.347072 -349.116524) (xy 340.404237 -349.10779) (xy 340.433152 -349.107252) (xy 340.461719 -349.107782)
			(xy 340.518214 -349.116316) (xy 340.572807 -349.133169) (xy 340.624281 -349.157966) (xy 340.671487 -349.190155)
			(xy 340.713371 -349.229015) (xy 340.731602 -349.251016) (xy 340.741172 -349.262259) (xy 340.765411 -349.279096)
			(xy 340.793451 -349.288307) (xy 340.822953 -349.289124) (xy 340.851459 -349.281478) (xy 340.876593 -349.266006)
			(xy 340.886796 -349.255334) (xy 340.904952 -349.235705) (xy 340.945838 -349.201247) (xy 340.991134 -349.172834)
			(xy 341.039954 -349.151024) (xy 341.09134 -349.136243) (xy 341.144287 -349.128782) (xy 341.171022 -349.128334)
			(xy 341.199937 -349.128896) (xy 341.257107 -349.137614) (xy 341.312306 -349.154862) (xy 341.364268 -349.180246)
			(xy 341.411803 -349.213183) (xy 341.453821 -349.252917) (xy 341.472012 -349.2754) (xy 341.481909 -349.287205)
			(xy 341.507233 -349.304724) (xy 341.536626 -349.3139) (xy 341.567418 -349.3139) (xy 341.596811 -349.304724)
			(xy 341.622135 -349.287205) (xy 341.632032 -349.2754) (xy 341.650205 -349.252901) (xy 341.692228 -349.213167)
			(xy 341.739767 -349.18023) (xy 341.791732 -349.154844) (xy 341.846933 -349.137591) (xy 341.904105 -349.128867)
			(xy 341.933022 -349.128334) (xy 341.960275 -349.128737) (xy 342.014227 -349.136497) (xy 342.066524 -349.151856)
			(xy 342.116104 -349.174501) (xy 342.161957 -349.203971) (xy 342.203149 -349.239666) (xy 342.238842 -349.280861)
			(xy 342.26831 -349.326715) (xy 342.290952 -349.376296) (xy 342.306307 -349.428595) (xy 342.314064 -349.482547)
			(xy 342.314064 -349.537053) (xy 342.306307 -349.591005) (xy 342.290952 -349.643304) (xy 342.26831 -349.692885)
			(xy 342.238842 -349.738739) (xy 342.203149 -349.779934) (xy 342.161957 -349.815629) (xy 342.116104 -349.845099)
			(xy 342.066524 -349.867744) (xy 342.014227 -349.883103) (xy 341.960275 -349.890863) (xy 341.933022 -349.89135)
			(xy 341.904105 -349.890835) (xy 341.846933 -349.882108) (xy 341.791733 -349.864851) (xy 341.739771 -349.839458)
			(xy 341.692237 -349.806513) (xy 341.650221 -349.766771) (xy 341.632032 -349.744284) (xy 341.622135 -349.732479)
			(xy 341.596811 -349.71496) (xy 341.567418 -349.705784) (xy 341.536626 -349.705784) (xy 341.507233 -349.71496)
			(xy 341.481909 -349.732479) (xy 341.472012 -349.744284) (xy 341.45381 -349.766758) (xy 341.411793 -349.806495)
			(xy 341.364261 -349.839435) (xy 341.312301 -349.864826) (xy 341.257106 -349.882084) (xy 341.199937 -349.890814)
			(xy 341.171022 -349.89135) (xy 341.142456 -349.890766) (xy 341.085964 -349.882244) (xy 341.031372 -349.865401)
			(xy 340.979898 -349.840614) (xy 340.932691 -349.808435) (xy 340.890804 -349.769583) (xy 340.872572 -349.747586)
			(xy 340.86303 -349.736318) (xy 340.838783 -349.71948) (xy 340.810736 -349.710272) (xy 340.781228 -349.70946)
			(xy 340.752717 -349.717113) (xy 340.727582 -349.732592) (xy 340.717378 -349.743268) (xy 340.699186 -349.762862)
			(xy 340.658307 -349.797323) (xy 340.613018 -349.82574) (xy 340.564206 -349.847556) (xy 340.512826 -349.862344)
			(xy 340.459885 -349.869815) (xy 340.433152 -349.870268) (xy 340.404236 -349.869725) (xy 340.347065 -349.861002)
			(xy 340.291866 -349.84375) (xy 340.239904 -349.818363) (xy 340.19237 -349.785424) (xy 340.150352 -349.745686)
			(xy 340.132162 -349.723202) (xy 340.122265 -349.711397) (xy 340.096941 -349.693878) (xy 340.067548 -349.684702)
			(xy 340.036756 -349.684702) (xy 340.007363 -349.693878) (xy 339.982039 -349.711397) (xy 339.972142 -349.723202)
			(xy 339.955389 -349.743985) (xy 339.917035 -349.781115) (xy 339.873881 -349.812537) (xy 339.826767 -349.837636)
			(xy 339.776615 -349.855922) (xy 339.724404 -349.867039) (xy 339.671152 -349.870769) (xy 339.6179 -349.867039)
			(xy 339.565689 -349.855922) (xy 339.515537 -349.837636) (xy 339.468423 -349.812537) (xy 339.425269 -349.781115)
			(xy 339.386915 -349.743985) (xy 339.370162 -349.723202) (xy 339.360265 -349.711397) (xy 339.334941 -349.693878)
			(xy 339.305548 -349.684702) (xy 339.274756 -349.684702) (xy 339.245363 -349.693878) (xy 339.220039 -349.711397)
			(xy 339.210142 -349.723202) (xy 339.193389 -349.743985) (xy 339.155035 -349.781115) (xy 339.111881 -349.812537)
			(xy 339.064767 -349.837636) (xy 339.014615 -349.855922) (xy 338.962404 -349.867039) (xy 338.909152 -349.870769)
			(xy 338.8559 -349.867039) (xy 338.803689 -349.855922) (xy 338.753537 -349.837636) (xy 338.706423 -349.812537)
			(xy 338.663269 -349.781115) (xy 338.624915 -349.743985) (xy 338.608162 -349.723202) (xy 338.598265 -349.711397)
			(xy 338.572941 -349.693878) (xy 338.543548 -349.684702) (xy 338.512756 -349.684702) (xy 338.483363 -349.693878)
			(xy 338.458039 -349.711397) (xy 338.448142 -349.723202) (xy 338.423758 -349.75165) (xy 338.413523 -349.763228)
			(xy 338.399939 -349.790968) (xy 338.395268 -349.8215) (xy 338.399939 -349.852032) (xy 338.413523 -349.879772)
			(xy 338.423758 -349.89135) (xy 338.443327 -349.912773) (xy 338.476444 -349.960414) (xy 338.501975 -350.012515)
			(xy 338.519332 -350.067878) (xy 338.528116 -350.12523) (xy 338.52866 -350.15424) (xy 338.528174 -350.181491)
			(xy 338.520418 -350.235439) (xy 338.505063 -350.287734) (xy 338.482421 -350.337311) (xy 338.452955 -350.383161)
			(xy 338.417264 -350.424352) (xy 338.376073 -350.460043) (xy 338.330223 -350.489509) (xy 338.280646 -350.512151)
			(xy 338.228351 -350.527506) (xy 338.174403 -350.535262) (xy 338.119901 -350.535262) (xy 338.065953 -350.527506)
			(xy 338.013658 -350.512151) (xy 337.964081 -350.489509) (xy 337.918231 -350.460043) (xy 337.87704 -350.424352)
			(xy 337.841349 -350.383161) (xy 337.811883 -350.337311) (xy 337.789241 -350.287734) (xy 337.773886 -350.235439)
			(xy 337.76613 -350.181491) (xy 337.765644 -350.15424) (xy 337.563824 -350.15424) (xy 337.56367 -350.162328)
			(xy 337.554952 -350.219499) (xy 337.537703 -350.274698) (xy 337.512318 -350.326661) (xy 337.479378 -350.374195)
			(xy 337.43964 -350.416212) (xy 337.417156 -350.434402) (xy 337.405335 -350.444284) (xy 337.38781 -350.46961)
			(xy 337.378631 -350.499008) (xy 337.378634 -350.529806) (xy 337.387816 -350.559204) (xy 337.405345 -350.584527)
			(xy 337.417156 -350.594422) (xy 337.439641 -350.612612) (xy 337.479378 -350.65463) (xy 337.512318 -350.702165)
			(xy 337.537707 -350.754127) (xy 337.554962 -350.809325) (xy 337.563689 -350.866496) (xy 337.564222 -350.895412)
			(xy 337.563848 -350.91624) (xy 342.433656 -350.91624) (xy 342.434182 -350.887323) (xy 342.442906 -350.830151)
			(xy 342.460161 -350.774952) (xy 342.485551 -350.722989) (xy 342.518495 -350.675455) (xy 342.558236 -350.633439)
			(xy 342.580722 -350.61525) (xy 342.592484 -350.605307) (xy 342.609996 -350.579994) (xy 342.619172 -350.550614)
			(xy 342.61918 -350.519835) (xy 342.610018 -350.49045) (xy 342.592518 -350.465129) (xy 342.580722 -350.45523)
			(xy 342.558257 -350.437016) (xy 342.51852 -350.395002) (xy 342.485578 -350.347472) (xy 342.460186 -350.295515)
			(xy 342.442926 -350.240321) (xy 342.434193 -350.183155) (xy 342.433656 -350.15424) (xy 342.434224 -350.125229)
			(xy 342.442986 -350.067874) (xy 342.46033 -350.012505) (xy 342.485856 -349.960401) (xy 342.518976 -349.912761)
			(xy 342.538558 -349.89135) (xy 342.548791 -349.879771) (xy 342.562374 -349.852032) (xy 342.567044 -349.8215)
			(xy 342.562374 -349.790968) (xy 342.548791 -349.763229) (xy 342.538558 -349.75165) (xy 342.518991 -349.730225)
			(xy 342.485874 -349.682585) (xy 342.460342 -349.630484) (xy 342.442985 -349.575121) (xy 342.4342 -349.51777)
			(xy 342.433656 -349.48876) (xy 342.43414 -349.461509) (xy 342.441902 -349.407564) (xy 342.45726 -349.355271)
			(xy 342.479903 -349.305696) (xy 342.50937 -349.259848) (xy 342.545062 -349.218659) (xy 342.586251 -349.182968)
			(xy 342.632099 -349.153501) (xy 342.681675 -349.130858) (xy 342.733967 -349.115501) (xy 342.787913 -349.10774)
			(xy 342.815164 -349.107252) (xy 342.844081 -349.107776) (xy 342.901253 -349.116501) (xy 342.956452 -349.133757)
			(xy 343.008415 -349.159147) (xy 343.055948 -349.192091) (xy 343.097965 -349.231832) (xy 343.116154 -349.254318)
			(xy 343.126051 -349.266123) (xy 343.151375 -349.283642) (xy 343.180768 -349.292818) (xy 343.21156 -349.292818)
			(xy 343.240953 -349.283642) (xy 343.266277 -349.266123) (xy 343.276174 -349.254318) (xy 343.294384 -349.231851)
			(xy 343.336399 -349.192114) (xy 343.38393 -349.159172) (xy 343.435888 -349.133781) (xy 343.491082 -349.116521)
			(xy 343.548249 -349.107789) (xy 343.577164 -349.107252) (xy 343.604413 -349.107812) (xy 343.658355 -349.115562)
			(xy 343.710646 -349.130911) (xy 343.760221 -349.153545) (xy 343.806069 -349.183003) (xy 343.847259 -349.218687)
			(xy 343.882951 -349.25987) (xy 343.912419 -349.305713) (xy 343.935063 -349.355282) (xy 343.950422 -349.40757)
			(xy 343.958183 -349.461512) (xy 343.958672 -349.48876) (xy 343.958124 -349.517772) (xy 343.94936 -349.575129)
			(xy 343.932012 -349.630498) (xy 343.906481 -349.682603) (xy 343.873356 -349.730241) (xy 343.85377 -349.75165)
			(xy 343.843534 -349.763227) (xy 343.829948 -349.790967) (xy 343.825277 -349.8215) (xy 343.829948 -349.852033)
			(xy 343.843534 -349.879773) (xy 343.85377 -349.89135) (xy 343.873341 -349.912771) (xy 343.906457 -349.960413)
			(xy 343.931987 -350.012514) (xy 343.949344 -350.067878) (xy 343.958128 -350.12523) (xy 343.958672 -350.15424)
			(xy 343.958121 -350.183156) (xy 343.949401 -350.240326) (xy 343.93215 -350.295525) (xy 343.906764 -350.347487)
			(xy 343.873826 -350.395021) (xy 343.834089 -350.437039) (xy 343.811606 -350.45523) (xy 343.799761 -350.465084)
			(xy 343.782246 -350.49042) (xy 343.773075 -350.519824) (xy 343.773082 -350.550625) (xy 343.782267 -350.580025)
			(xy 343.799795 -350.605352) (xy 343.811606 -350.61525) (xy 343.834067 -350.633468) (xy 343.866564 -350.667828)
			(xy 354.882702 -350.667828) (xy 354.886773 -350.612206) (xy 354.898899 -350.557769) (xy 354.918822 -350.505678)
			(xy 354.946118 -350.457043) (xy 354.980204 -350.4129) (xy 355.020353 -350.374191) (xy 355.065711 -350.34174)
			(xy 355.115311 -350.316239) (xy 355.168095 -350.298232) (xy 355.222938 -350.288102) (xy 355.278672 -350.286065)
			(xy 355.334109 -350.292165) (xy 355.388066 -350.306271) (xy 355.439395 -350.328083) (xy 355.487001 -350.357137)
			(xy 355.529869 -350.392812) (xy 355.536575 -350.400296) (xy 363.397796 -350.400296) (xy 363.397796 -350.3156)
			(xy 363.405847 -350.231286) (xy 363.421876 -350.14812) (xy 363.445737 -350.066853) (xy 363.477216 -349.988223)
			(xy 363.516027 -349.912942) (xy 363.561817 -349.84169) (xy 363.614173 -349.775114) (xy 363.672621 -349.713816)
			(xy 363.736631 -349.658351) (xy 363.805623 -349.609222) (xy 363.878973 -349.566873) (xy 363.956016 -349.531689)
			(xy 364.036055 -349.503987) (xy 364.118364 -349.484019) (xy 364.202199 -349.471966) (xy 364.2868 -349.467936)
			(xy 364.371401 -349.471966) (xy 364.455236 -349.484019) (xy 364.537545 -349.503987) (xy 364.617584 -349.531689)
			(xy 364.694627 -349.566873) (xy 364.767977 -349.609222) (xy 364.836969 -349.658351) (xy 364.900979 -349.713816)
			(xy 364.959427 -349.775114) (xy 365.011783 -349.84169) (xy 365.057573 -349.912942) (xy 365.096384 -349.988223)
			(xy 365.127863 -350.066853) (xy 365.151724 -350.14812) (xy 365.167753 -350.231286) (xy 365.175804 -350.3156)
			(xy 365.176308 -350.357948) (xy 365.922309 -350.357948) (xy 365.926345 -350.274501) (xy 365.938417 -350.191833)
			(xy 365.95841 -350.110716) (xy 365.986139 -350.031907) (xy 366.021345 -349.956142) (xy 366.063699 -349.884129)
			(xy 366.112805 -349.81654) (xy 366.168206 -349.754006) (xy 366.229383 -349.697111) (xy 366.295766 -349.646385)
			(xy 366.366734 -349.602304) (xy 366.441626 -349.565278) (xy 366.519742 -349.535652) (xy 366.600352 -349.513704)
			(xy 366.682704 -349.499639) (xy 366.76603 -349.493587) (xy 366.84955 -349.495606) (xy 366.932486 -349.505676)
			(xy 367.014062 -349.523704) (xy 367.093518 -349.549521) (xy 367.170111 -349.582886) (xy 367.243127 -349.623487)
			(xy 367.311883 -349.670946) (xy 367.375737 -349.724819) (xy 367.434094 -349.784604) (xy 367.486409 -349.849741)
			(xy 367.532192 -349.919624) (xy 367.571017 -349.993599) (xy 367.602522 -350.070976) (xy 367.626411 -350.151033)
			(xy 367.642462 -350.233021) (xy 367.650525 -350.316176) (xy 367.65103 -350.357948) (xy 367.650525 -350.39972)
			(xy 367.642462 -350.482875) (xy 367.626411 -350.564863) (xy 367.602522 -350.64492) (xy 367.571017 -350.722297)
			(xy 367.532192 -350.796272) (xy 367.486409 -350.866155) (xy 367.434094 -350.931292) (xy 367.375737 -350.991077)
			(xy 367.311883 -351.04495) (xy 367.243127 -351.092409) (xy 367.170111 -351.13301) (xy 367.093518 -351.166375)
			(xy 367.014062 -351.192192) (xy 366.932486 -351.21022) (xy 366.84955 -351.22029) (xy 366.76603 -351.222309)
			(xy 366.682704 -351.216257) (xy 366.600352 -351.202192) (xy 366.519742 -351.180244) (xy 366.441626 -351.150618)
			(xy 366.366734 -351.113592) (xy 366.295766 -351.069511) (xy 366.229383 -351.018785) (xy 366.168206 -350.96189)
			(xy 366.112805 -350.899356) (xy 366.063699 -350.831767) (xy 366.021345 -350.759754) (xy 365.986139 -350.683989)
			(xy 365.95841 -350.60518) (xy 365.938417 -350.524063) (xy 365.926345 -350.441395) (xy 365.922309 -350.357948)
			(xy 365.176308 -350.357948) (xy 365.175804 -350.400296) (xy 365.167753 -350.48461) (xy 365.151724 -350.567776)
			(xy 365.127863 -350.649043) (xy 365.096384 -350.727673) (xy 365.057573 -350.802954) (xy 365.011783 -350.874206)
			(xy 364.959427 -350.940782) (xy 364.900979 -351.00208) (xy 364.836969 -351.057545) (xy 364.767977 -351.106674)
			(xy 364.694627 -351.149023) (xy 364.617584 -351.184207) (xy 364.537545 -351.211909) (xy 364.455236 -351.231877)
			(xy 364.371401 -351.24393) (xy 364.2868 -351.247961) (xy 364.202199 -351.24393) (xy 364.118364 -351.231877)
			(xy 364.036055 -351.211909) (xy 363.956016 -351.184207) (xy 363.878973 -351.149023) (xy 363.805623 -351.106674)
			(xy 363.736631 -351.057545) (xy 363.672621 -351.00208) (xy 363.614173 -350.940782) (xy 363.561817 -350.874206)
			(xy 363.516027 -350.802954) (xy 363.477216 -350.727673) (xy 363.445737 -350.649043) (xy 363.421876 -350.567776)
			(xy 363.405847 -350.48461) (xy 363.397796 -350.400296) (xy 355.536575 -350.400296) (xy 355.567086 -350.434349)
			(xy 355.597859 -350.480862) (xy 355.621531 -350.531359) (xy 355.637599 -350.584766) (xy 355.645719 -350.639942)
			(xy 355.646228 -350.667828) (xy 355.645719 -350.695714) (xy 355.637599 -350.75089) (xy 355.621531 -350.804297)
			(xy 355.597859 -350.854794) (xy 355.567086 -350.901307) (xy 355.529869 -350.942844) (xy 355.487001 -350.978519)
			(xy 355.439395 -351.007573) (xy 355.388066 -351.029385) (xy 355.334109 -351.043491) (xy 355.278672 -351.049591)
			(xy 355.222938 -351.047554) (xy 355.168095 -351.037424) (xy 355.115311 -351.019417) (xy 355.065711 -350.993916)
			(xy 355.020353 -350.961465) (xy 354.980204 -350.922756) (xy 354.946118 -350.878613) (xy 354.918822 -350.829978)
			(xy 354.898899 -350.777887) (xy 354.886773 -350.72345) (xy 354.882702 -350.667828) (xy 343.866564 -350.667828)
			(xy 343.873803 -350.675482) (xy 343.906745 -350.723012) (xy 343.932137 -350.774968) (xy 343.949398 -350.83016)
			(xy 343.958133 -350.887326) (xy 343.958672 -350.91624) (xy 343.958259 -350.943494) (xy 343.950496 -350.997446)
			(xy 343.935134 -351.049744) (xy 343.912486 -351.099324) (xy 343.883012 -351.145176) (xy 343.847313 -351.186367)
			(xy 343.806115 -351.222058) (xy 343.760257 -351.251522) (xy 343.710673 -351.274161) (xy 343.658372 -351.289513)
			(xy 343.604418 -351.297265) (xy 343.577164 -351.297748) (xy 343.548248 -351.297203) (xy 343.491077 -351.288482)
			(xy 343.435878 -351.271231) (xy 343.383916 -351.245844) (xy 343.336381 -351.212904) (xy 343.294364 -351.173166)
			(xy 343.276174 -351.150682) (xy 343.266277 -351.138877) (xy 343.240953 -351.121358) (xy 343.21156 -351.112182)
			(xy 343.180768 -351.112182) (xy 343.151375 -351.121358) (xy 343.126051 -351.138877) (xy 343.116154 -351.150682)
			(xy 343.097928 -351.173136) (xy 343.055916 -351.212874) (xy 343.008389 -351.245817) (xy 342.956434 -351.27121)
			(xy 342.901243 -351.288473) (xy 342.844078 -351.297209) (xy 342.815164 -351.297748) (xy 342.787914 -351.297256)
			(xy 342.733968 -351.289495) (xy 342.681676 -351.274138) (xy 342.632101 -351.251495) (xy 342.586253 -351.222029)
			(xy 342.545064 -351.186338) (xy 342.509373 -351.14515) (xy 342.479907 -351.099302) (xy 342.457264 -351.049728)
			(xy 342.441905 -350.997436) (xy 342.434144 -350.94349) (xy 342.433656 -350.91624) (xy 337.563848 -350.91624)
			(xy 337.563733 -350.922663) (xy 337.555976 -350.97661) (xy 337.54062 -351.028904) (xy 337.517978 -351.07848)
			(xy 337.488512 -351.12433) (xy 337.452821 -351.165519) (xy 337.411631 -351.201211) (xy 337.365782 -351.230677)
			(xy 337.316206 -351.253319) (xy 337.263912 -351.268675) (xy 337.209965 -351.276433) (xy 337.182714 -351.27692)
			(xy 337.153796 -351.276422) (xy 337.096622 -351.267693) (xy 337.041422 -351.250433) (xy 336.98946 -351.225038)
			(xy 336.941926 -351.192089) (xy 336.899912 -351.152342) (xy 336.881724 -351.129854) (xy 336.871827 -351.118049)
			(xy 336.846503 -351.10053) (xy 336.81711 -351.091354) (xy 336.786318 -351.091354) (xy 336.756925 -351.10053)
			(xy 336.731601 -351.118049) (xy 336.721704 -351.129854) (xy 336.703524 -351.152347) (xy 336.661501 -351.192079)
			(xy 336.613963 -351.225015) (xy 336.562 -351.250402) (xy 336.506801 -351.267656) (xy 336.44963 -351.276385)
			(xy 336.420714 -351.27692) (xy 336.393462 -351.276432) (xy 336.339513 -351.268677) (xy 336.287216 -351.253323)
			(xy 336.237637 -351.230683) (xy 336.191784 -351.201218) (xy 336.150592 -351.165527) (xy 336.114898 -351.124337)
			(xy 336.085429 -351.078486) (xy 336.062786 -351.028908) (xy 336.047429 -350.976613) (xy 336.03967 -350.922664)
			(xy 336.039206 -350.895412) (xy 323.760426 -350.895412) (xy 324.180108 -351.605088) (xy 351.934778 -351.605088)
			(xy 351.938849 -351.549466) (xy 351.950975 -351.495029) (xy 351.970898 -351.442938) (xy 351.998194 -351.394303)
			(xy 352.03228 -351.35016) (xy 352.072429 -351.311451) (xy 352.117787 -351.279) (xy 352.167387 -351.253499)
			(xy 352.220171 -351.235492) (xy 352.275014 -351.225362) (xy 352.330748 -351.223325) (xy 352.386185 -351.229425)
			(xy 352.440142 -351.243531) (xy 352.491471 -351.265343) (xy 352.539077 -351.294397) (xy 352.581945 -351.330072)
			(xy 352.619162 -351.371609) (xy 352.649935 -351.418122) (xy 352.673607 -351.468619) (xy 352.689675 -351.522026)
			(xy 352.697795 -351.577202) (xy 352.698304 -351.605088) (xy 352.697795 -351.632974) (xy 352.689675 -351.68815)
			(xy 352.673607 -351.741557) (xy 352.649935 -351.792054) (xy 352.627431 -351.826068) (xy 352.798378 -351.826068)
			(xy 352.802449 -351.770446) (xy 352.814575 -351.716009) (xy 352.834498 -351.663918) (xy 352.861794 -351.615283)
			(xy 352.89588 -351.57114) (xy 352.936029 -351.532431) (xy 352.981387 -351.49998) (xy 353.030987 -351.474479)
			(xy 353.083771 -351.456472) (xy 353.138614 -351.446342) (xy 353.194348 -351.444305) (xy 353.249785 -351.450405)
			(xy 353.303742 -351.464511) (xy 353.355071 -351.486323) (xy 353.402677 -351.515377) (xy 353.445545 -351.551052)
			(xy 353.482762 -351.592589) (xy 353.513535 -351.639102) (xy 353.537207 -351.689599) (xy 353.553275 -351.743006)
			(xy 353.561395 -351.798182) (xy 353.561904 -351.826068) (xy 353.561395 -351.853954) (xy 353.553275 -351.90913)
			(xy 353.537207 -351.962537) (xy 353.533311 -351.970848) (xy 354.280976 -351.970848) (xy 354.285047 -351.915226)
			(xy 354.297173 -351.860789) (xy 354.317096 -351.808698) (xy 354.344392 -351.760063) (xy 354.378478 -351.71592)
			(xy 354.418627 -351.677211) (xy 354.463985 -351.64476) (xy 354.513585 -351.619259) (xy 354.566369 -351.601252)
			(xy 354.621212 -351.591122) (xy 354.676946 -351.589085) (xy 354.732383 -351.595185) (xy 354.78634 -351.609291)
			(xy 354.837669 -351.631103) (xy 354.885275 -351.660157) (xy 354.928143 -351.695832) (xy 354.93878 -351.707704)
			(xy 355.638352 -351.707704) (xy 355.642423 -351.652082) (xy 355.654549 -351.597645) (xy 355.674472 -351.545554)
			(xy 355.701768 -351.496919) (xy 355.735854 -351.452776) (xy 355.776003 -351.414067) (xy 355.821361 -351.381616)
			(xy 355.870961 -351.356115) (xy 355.923745 -351.338108) (xy 355.978588 -351.327978) (xy 356.034322 -351.325941)
			(xy 356.089759 -351.332041) (xy 356.143716 -351.346147) (xy 356.195045 -351.367959) (xy 356.242651 -351.397013)
			(xy 356.285519 -351.432688) (xy 356.322736 -351.474225) (xy 356.340416 -351.500948) (xy 356.859076 -351.500948)
			(xy 356.863147 -351.445326) (xy 356.875273 -351.390889) (xy 356.895196 -351.338798) (xy 356.922492 -351.290163)
			(xy 356.956578 -351.24602) (xy 356.996727 -351.207311) (xy 357.042085 -351.17486) (xy 357.091685 -351.149359)
			(xy 357.144469 -351.131352) (xy 357.199312 -351.121222) (xy 357.255046 -351.119185) (xy 357.310483 -351.125285)
			(xy 357.36444 -351.139391) (xy 357.415769 -351.161203) (xy 357.463375 -351.190257) (xy 357.506243 -351.225932)
			(xy 357.54346 -351.267469) (xy 357.574233 -351.313982) (xy 357.597905 -351.364479) (xy 357.613973 -351.417886)
			(xy 357.619842 -351.457768) (xy 359.071416 -351.457768) (xy 359.075487 -351.402146) (xy 359.087613 -351.347709)
			(xy 359.107536 -351.295618) (xy 359.134832 -351.246983) (xy 359.168918 -351.20284) (xy 359.209067 -351.164131)
			(xy 359.254425 -351.13168) (xy 359.304025 -351.106179) (xy 359.356809 -351.088172) (xy 359.411652 -351.078042)
			(xy 359.467386 -351.076005) (xy 359.522823 -351.082105) (xy 359.57678 -351.096211) (xy 359.628109 -351.118023)
			(xy 359.675715 -351.147077) (xy 359.718583 -351.182752) (xy 359.7558 -351.224289) (xy 359.786573 -351.270802)
			(xy 359.810245 -351.321299) (xy 359.821423 -351.358454) (xy 360.956858 -351.358454) (xy 360.960929 -351.302832)
			(xy 360.973055 -351.248395) (xy 360.992978 -351.196304) (xy 361.020274 -351.147669) (xy 361.05436 -351.103526)
			(xy 361.094509 -351.064817) (xy 361.139867 -351.032366) (xy 361.189467 -351.006865) (xy 361.242251 -350.988858)
			(xy 361.297094 -350.978728) (xy 361.352828 -350.976691) (xy 361.408265 -350.982791) (xy 361.462222 -350.996897)
			(xy 361.513551 -351.018709) (xy 361.561157 -351.047763) (xy 361.604025 -351.083438) (xy 361.641242 -351.124975)
			(xy 361.672015 -351.171488) (xy 361.695687 -351.221985) (xy 361.711755 -351.275392) (xy 361.719875 -351.330568)
			(xy 361.720384 -351.358454) (xy 361.719875 -351.38634) (xy 361.711755 -351.441516) (xy 361.695687 -351.494923)
			(xy 361.672015 -351.54542) (xy 361.641242 -351.591933) (xy 361.604025 -351.63347) (xy 361.561157 -351.669145)
			(xy 361.513551 -351.698199) (xy 361.462222 -351.720011) (xy 361.408265 -351.734117) (xy 361.352828 -351.740217)
			(xy 361.297094 -351.73818) (xy 361.242251 -351.72805) (xy 361.189467 -351.710043) (xy 361.139867 -351.684542)
			(xy 361.094509 -351.652091) (xy 361.05436 -351.613382) (xy 361.020274 -351.569239) (xy 360.992978 -351.520604)
			(xy 360.973055 -351.468513) (xy 360.960929 -351.414076) (xy 360.956858 -351.358454) (xy 359.821423 -351.358454)
			(xy 359.826313 -351.374706) (xy 359.834433 -351.429882) (xy 359.834942 -351.457768) (xy 359.834433 -351.485654)
			(xy 359.826313 -351.54083) (xy 359.810245 -351.594237) (xy 359.786573 -351.644734) (xy 359.7558 -351.691247)
			(xy 359.718583 -351.732784) (xy 359.675715 -351.768459) (xy 359.628109 -351.797513) (xy 359.57678 -351.819325)
			(xy 359.522823 -351.833431) (xy 359.467386 -351.839531) (xy 359.411652 -351.837494) (xy 359.356809 -351.827364)
			(xy 359.304025 -351.809357) (xy 359.254425 -351.783856) (xy 359.209067 -351.751405) (xy 359.168918 -351.712696)
			(xy 359.134832 -351.668553) (xy 359.107536 -351.619918) (xy 359.087613 -351.567827) (xy 359.075487 -351.51339)
			(xy 359.071416 -351.457768) (xy 357.619842 -351.457768) (xy 357.622093 -351.473062) (xy 357.622602 -351.500948)
			(xy 357.622093 -351.528834) (xy 357.613973 -351.58401) (xy 357.597905 -351.637417) (xy 357.574233 -351.687914)
			(xy 357.54346 -351.734427) (xy 357.506243 -351.775964) (xy 357.463375 -351.811639) (xy 357.415769 -351.840693)
			(xy 357.36444 -351.862505) (xy 357.310483 -351.876611) (xy 357.255046 -351.882711) (xy 357.199312 -351.880674)
			(xy 357.144469 -351.870544) (xy 357.091685 -351.852537) (xy 357.042085 -351.827036) (xy 356.996727 -351.794585)
			(xy 356.956578 -351.755876) (xy 356.922492 -351.711733) (xy 356.895196 -351.663098) (xy 356.875273 -351.611007)
			(xy 356.863147 -351.55657) (xy 356.859076 -351.500948) (xy 356.340416 -351.500948) (xy 356.353509 -351.520738)
			(xy 356.377181 -351.571235) (xy 356.393249 -351.624642) (xy 356.401369 -351.679818) (xy 356.401878 -351.707704)
			(xy 356.401369 -351.73559) (xy 356.393249 -351.790766) (xy 356.377181 -351.844173) (xy 356.353509 -351.89467)
			(xy 356.322736 -351.941183) (xy 356.285519 -351.98272) (xy 356.242651 -352.018395) (xy 356.195045 -352.047449)
			(xy 356.143716 -352.069261) (xy 356.089759 -352.083367) (xy 356.034322 -352.089467) (xy 355.978588 -352.08743)
			(xy 355.923745 -352.0773) (xy 355.870961 -352.059293) (xy 355.821361 -352.033792) (xy 355.776003 -352.001341)
			(xy 355.735854 -351.962632) (xy 355.701768 -351.918489) (xy 355.674472 -351.869854) (xy 355.654549 -351.817763)
			(xy 355.642423 -351.763326) (xy 355.638352 -351.707704) (xy 354.93878 -351.707704) (xy 354.96536 -351.737369)
			(xy 354.996133 -351.783882) (xy 355.019805 -351.834379) (xy 355.035873 -351.887786) (xy 355.043993 -351.942962)
			(xy 355.044502 -351.970848) (xy 355.043993 -351.998734) (xy 355.035873 -352.05391) (xy 355.019805 -352.107317)
			(xy 354.996133 -352.157814) (xy 354.96536 -352.204327) (xy 354.928143 -352.245864) (xy 354.885275 -352.281539)
			(xy 354.837669 -352.310593) (xy 354.78634 -352.332405) (xy 354.732383 -352.346511) (xy 354.676946 -352.352611)
			(xy 354.621212 -352.350574) (xy 354.566369 -352.340444) (xy 354.513585 -352.322437) (xy 354.463985 -352.296936)
			(xy 354.418627 -352.264485) (xy 354.378478 -352.225776) (xy 354.344392 -352.181633) (xy 354.317096 -352.132998)
			(xy 354.297173 -352.080907) (xy 354.285047 -352.02647) (xy 354.280976 -351.970848) (xy 353.533311 -351.970848)
			(xy 353.513535 -352.013034) (xy 353.482762 -352.059547) (xy 353.445545 -352.101084) (xy 353.402677 -352.136759)
			(xy 353.355071 -352.165813) (xy 353.303742 -352.187625) (xy 353.249785 -352.201731) (xy 353.194348 -352.207831)
			(xy 353.138614 -352.205794) (xy 353.083771 -352.195664) (xy 353.030987 -352.177657) (xy 352.981387 -352.152156)
			(xy 352.936029 -352.119705) (xy 352.89588 -352.080996) (xy 352.861794 -352.036853) (xy 352.834498 -351.988218)
			(xy 352.814575 -351.936127) (xy 352.802449 -351.88169) (xy 352.798378 -351.826068) (xy 352.627431 -351.826068)
			(xy 352.619162 -351.838567) (xy 352.581945 -351.880104) (xy 352.539077 -351.915779) (xy 352.491471 -351.944833)
			(xy 352.440142 -351.966645) (xy 352.386185 -351.980751) (xy 352.330748 -351.986851) (xy 352.275014 -351.984814)
			(xy 352.220171 -351.974684) (xy 352.167387 -351.956677) (xy 352.117787 -351.931176) (xy 352.072429 -351.898725)
			(xy 352.03228 -351.860016) (xy 351.998194 -351.815873) (xy 351.970898 -351.767238) (xy 351.950975 -351.715147)
			(xy 351.938849 -351.66071) (xy 351.934778 -351.605088) (xy 324.180108 -351.605088) (xy 324.648007 -352.396298)
			(xy 358.510076 -352.396298) (xy 358.514147 -352.340676) (xy 358.526273 -352.286239) (xy 358.546196 -352.234148)
			(xy 358.573492 -352.185513) (xy 358.607578 -352.14137) (xy 358.647727 -352.102661) (xy 358.693085 -352.07021)
			(xy 358.742685 -352.044709) (xy 358.795469 -352.026702) (xy 358.850312 -352.016572) (xy 358.906046 -352.014535)
			(xy 358.961483 -352.020635) (xy 359.01544 -352.034741) (xy 359.066769 -352.056553) (xy 359.114375 -352.085607)
			(xy 359.157243 -352.121282) (xy 359.19446 -352.162819) (xy 359.225233 -352.209332) (xy 359.248905 -352.259829)
			(xy 359.264973 -352.313236) (xy 359.273093 -352.368412) (xy 359.273602 -352.396298) (xy 359.273301 -352.412808)
			(xy 360.041442 -352.412808) (xy 360.045513 -352.357186) (xy 360.057639 -352.302749) (xy 360.077562 -352.250658)
			(xy 360.104858 -352.202023) (xy 360.138944 -352.15788) (xy 360.179093 -352.119171) (xy 360.224451 -352.08672)
			(xy 360.274051 -352.061219) (xy 360.326835 -352.043212) (xy 360.381678 -352.033082) (xy 360.437412 -352.031045)
			(xy 360.492849 -352.037145) (xy 360.546806 -352.051251) (xy 360.598135 -352.073063) (xy 360.645741 -352.102117)
			(xy 360.688609 -352.137792) (xy 360.725826 -352.179329) (xy 360.756599 -352.225842) (xy 360.780271 -352.276339)
			(xy 360.796339 -352.329746) (xy 360.804459 -352.384922) (xy 360.804968 -352.412808) (xy 360.804459 -352.440694)
			(xy 360.796339 -352.49587) (xy 360.780271 -352.549277) (xy 360.756599 -352.599774) (xy 360.725826 -352.646287)
			(xy 360.688609 -352.687824) (xy 360.645741 -352.723499) (xy 360.598135 -352.752553) (xy 360.546806 -352.774365)
			(xy 360.492849 -352.788471) (xy 360.437412 -352.794571) (xy 360.381678 -352.792534) (xy 360.326835 -352.782404)
			(xy 360.274051 -352.764397) (xy 360.224451 -352.738896) (xy 360.179093 -352.706445) (xy 360.138944 -352.667736)
			(xy 360.104858 -352.623593) (xy 360.077562 -352.574958) (xy 360.057639 -352.522867) (xy 360.045513 -352.46843)
			(xy 360.041442 -352.412808) (xy 359.273301 -352.412808) (xy 359.273093 -352.424184) (xy 359.264973 -352.47936)
			(xy 359.248905 -352.532767) (xy 359.225233 -352.583264) (xy 359.19446 -352.629777) (xy 359.157243 -352.671314)
			(xy 359.114375 -352.706989) (xy 359.066769 -352.736043) (xy 359.01544 -352.757855) (xy 358.961483 -352.771961)
			(xy 358.906046 -352.778061) (xy 358.850312 -352.776024) (xy 358.795469 -352.765894) (xy 358.742685 -352.747887)
			(xy 358.693085 -352.722386) (xy 358.647727 -352.689935) (xy 358.607578 -352.651226) (xy 358.573492 -352.607083)
			(xy 358.546196 -352.558448) (xy 358.526273 -352.506357) (xy 358.514147 -352.45192) (xy 358.510076 -352.396298)
			(xy 324.648007 -352.396298) (xy 324.85965 -352.754184) (xy 325.593964 -353.488498) (xy 358.420414 -353.488498)
			(xy 358.424485 -353.432876) (xy 358.436611 -353.378439) (xy 358.456534 -353.326348) (xy 358.48383 -353.277713)
			(xy 358.517916 -353.23357) (xy 358.558065 -353.194861) (xy 358.603423 -353.16241) (xy 358.653023 -353.136909)
			(xy 358.705807 -353.118902) (xy 358.76065 -353.108772) (xy 358.816384 -353.106735) (xy 358.871821 -353.112835)
			(xy 358.925778 -353.126941) (xy 358.977107 -353.148753) (xy 359.024713 -353.177807) (xy 359.067581 -353.213482)
			(xy 359.104798 -353.255019) (xy 359.135571 -353.301532) (xy 359.159243 -353.352029) (xy 359.175311 -353.405436)
			(xy 359.183431 -353.460612) (xy 359.18394 -353.488498) (xy 359.183431 -353.516384) (xy 359.175311 -353.57156)
			(xy 359.159243 -353.624967) (xy 359.135571 -353.675464) (xy 359.12315 -353.694238) (xy 360.057952 -353.694238)
			(xy 360.062023 -353.638616) (xy 360.074149 -353.584179) (xy 360.094072 -353.532088) (xy 360.121368 -353.483453)
			(xy 360.155454 -353.43931) (xy 360.195603 -353.400601) (xy 360.240961 -353.36815) (xy 360.290561 -353.342649)
			(xy 360.343345 -353.324642) (xy 360.398188 -353.314512) (xy 360.453922 -353.312475) (xy 360.509359 -353.318575)
			(xy 360.563316 -353.332681) (xy 360.614645 -353.354493) (xy 360.662251 -353.383547) (xy 360.705119 -353.419222)
			(xy 360.742336 -353.460759) (xy 360.773109 -353.507272) (xy 360.796781 -353.557769) (xy 360.812849 -353.611176)
			(xy 360.820969 -353.666352) (xy 360.821478 -353.694238) (xy 360.820969 -353.722124) (xy 360.812849 -353.7773)
			(xy 360.796781 -353.830707) (xy 360.773109 -353.881204) (xy 360.742336 -353.927717) (xy 360.705119 -353.969254)
			(xy 360.662251 -354.004929) (xy 360.614645 -354.033983) (xy 360.563316 -354.055795) (xy 360.509359 -354.069901)
			(xy 360.453922 -354.076001) (xy 360.398188 -354.073964) (xy 360.343345 -354.063834) (xy 360.290561 -354.045827)
			(xy 360.240961 -354.020326) (xy 360.195603 -353.987875) (xy 360.155454 -353.949166) (xy 360.121368 -353.905023)
			(xy 360.094072 -353.856388) (xy 360.074149 -353.804297) (xy 360.062023 -353.74986) (xy 360.057952 -353.694238)
			(xy 359.12315 -353.694238) (xy 359.104798 -353.721977) (xy 359.067581 -353.763514) (xy 359.024713 -353.799189)
			(xy 358.977107 -353.828243) (xy 358.925778 -353.850055) (xy 358.871821 -353.864161) (xy 358.816384 -353.870261)
			(xy 358.76065 -353.868224) (xy 358.705807 -353.858094) (xy 358.653023 -353.840087) (xy 358.603423 -353.814586)
			(xy 358.558065 -353.782135) (xy 358.517916 -353.743426) (xy 358.48383 -353.699283) (xy 358.456534 -353.650648)
			(xy 358.436611 -353.598557) (xy 358.424485 -353.54412) (xy 358.420414 -353.488498) (xy 325.593964 -353.488498)
			(xy 326.188578 -354.083112) (xy 349.389698 -354.083112) (xy 349.393769 -354.02749) (xy 349.405895 -353.973053)
			(xy 349.425818 -353.920962) (xy 349.453114 -353.872327) (xy 349.4872 -353.828184) (xy 349.527349 -353.789475)
			(xy 349.572707 -353.757024) (xy 349.622307 -353.731523) (xy 349.675091 -353.713516) (xy 349.729934 -353.703386)
			(xy 349.785668 -353.701349) (xy 349.841105 -353.707449) (xy 349.895062 -353.721555) (xy 349.946391 -353.743367)
			(xy 349.993997 -353.772421) (xy 350.036865 -353.808096) (xy 350.074082 -353.849633) (xy 350.104855 -353.896146)
			(xy 350.128527 -353.946643) (xy 350.144595 -354.00005) (xy 350.152715 -354.055226) (xy 350.153224 -354.083112)
			(xy 350.152715 -354.110998) (xy 350.144595 -354.166174) (xy 350.128527 -354.219581) (xy 350.104855 -354.270078)
			(xy 350.074082 -354.316591) (xy 350.036865 -354.358128) (xy 349.993997 -354.393803) (xy 349.946391 -354.422857)
			(xy 349.895062 -354.444669) (xy 349.89453 -354.444808) (xy 352.80803 -354.444808) (xy 352.812103 -354.389149)
			(xy 352.824238 -354.334676) (xy 352.844174 -354.28255) (xy 352.871488 -354.233882) (xy 352.905596 -354.18971)
			(xy 352.945773 -354.150975) (xy 352.991161 -354.118503) (xy 353.040793 -354.092985) (xy 353.093613 -354.074966)
			(xy 353.148492 -354.064829) (xy 353.204263 -354.062791) (xy 353.259737 -354.068894) (xy 353.31373 -354.08301)
			(xy 353.365093 -354.104837) (xy 353.412731 -354.13391) (xy 353.455627 -354.169609) (xy 353.492869 -354.211173)
			(xy 353.523663 -354.257717) (xy 353.547351 -354.308248) (xy 353.563429 -354.36169) (xy 353.571555 -354.416904)
			(xy 353.572064 -354.444808) (xy 353.571555 -354.472712) (xy 353.563429 -354.527926) (xy 353.547351 -354.581368)
			(xy 353.523663 -354.631899) (xy 353.492869 -354.678443) (xy 353.455627 -354.720007) (xy 353.420058 -354.749608)
			(xy 359.185462 -354.749608) (xy 359.189533 -354.693986) (xy 359.201659 -354.639549) (xy 359.221582 -354.587458)
			(xy 359.248878 -354.538823) (xy 359.282964 -354.49468) (xy 359.323113 -354.455971) (xy 359.368471 -354.42352)
			(xy 359.418071 -354.398019) (xy 359.470855 -354.380012) (xy 359.525698 -354.369882) (xy 359.581432 -354.367845)
			(xy 359.636869 -354.373945) (xy 359.690826 -354.388051) (xy 359.742155 -354.409863) (xy 359.789761 -354.438917)
			(xy 359.832629 -354.474592) (xy 359.869846 -354.516129) (xy 359.900619 -354.562642) (xy 359.924291 -354.613139)
			(xy 359.940359 -354.666546) (xy 359.948479 -354.721722) (xy 359.948988 -354.749608) (xy 359.948479 -354.777494)
			(xy 359.940359 -354.83267) (xy 359.924291 -354.886077) (xy 359.900619 -354.936574) (xy 359.883157 -354.962968)
			(xy 360.296712 -354.962968) (xy 360.300783 -354.907346) (xy 360.312909 -354.852909) (xy 360.332832 -354.800818)
			(xy 360.360128 -354.752183) (xy 360.394214 -354.70804) (xy 360.434363 -354.669331) (xy 360.479721 -354.63688)
			(xy 360.529321 -354.611379) (xy 360.582105 -354.593372) (xy 360.636948 -354.583242) (xy 360.692682 -354.581205)
			(xy 360.748119 -354.587305) (xy 360.802076 -354.601411) (xy 360.853405 -354.623223) (xy 360.901011 -354.652277)
			(xy 360.943879 -354.687952) (xy 360.981096 -354.729489) (xy 360.987685 -354.739448) (xy 361.378752 -354.739448)
			(xy 361.382823 -354.683826) (xy 361.394949 -354.629389) (xy 361.414872 -354.577298) (xy 361.442168 -354.528663)
			(xy 361.476254 -354.48452) (xy 361.516403 -354.445811) (xy 361.561761 -354.41336) (xy 361.611361 -354.387859)
			(xy 361.664145 -354.369852) (xy 361.718988 -354.359722) (xy 361.774722 -354.357685) (xy 361.830159 -354.363785)
			(xy 361.884116 -354.377891) (xy 361.935445 -354.399703) (xy 361.983051 -354.428757) (xy 362.025919 -354.464432)
			(xy 362.063136 -354.505969) (xy 362.093909 -354.552482) (xy 362.117581 -354.602979) (xy 362.133649 -354.656386)
			(xy 362.138285 -354.687886) (xy 364.22584 -354.687886) (xy 364.226278 -354.661506) (xy 364.233533 -354.609247)
			(xy 364.247918 -354.558486) (xy 364.269157 -354.51019) (xy 364.296845 -354.46528) (xy 364.330456 -354.424611)
			(xy 364.369348 -354.38896) (xy 364.41278 -354.359006) (xy 364.436152 -354.346764) (xy 364.448524 -354.340084)
			(xy 364.469257 -354.321106) (xy 364.484021 -354.297188) (xy 364.491693 -354.270148) (xy 364.491692 -354.24204)
			(xy 364.484016 -354.215001) (xy 364.469249 -354.191084) (xy 364.448514 -354.172109) (xy 364.436152 -354.165408)
			(xy 364.412765 -354.153197) (xy 364.369342 -354.123229) (xy 364.330458 -354.087569) (xy 364.296855 -354.046894)
			(xy 364.26917 -354.001981) (xy 364.247932 -353.953685) (xy 364.233546 -353.902924) (xy 364.226284 -353.850666)
			(xy 364.22584 -353.824286) (xy 364.226326 -353.797035) (xy 364.234082 -353.743087) (xy 364.249437 -353.690792)
			(xy 364.272079 -353.641215) (xy 364.301545 -353.595365) (xy 364.337236 -353.554174) (xy 364.378427 -353.518483)
			(xy 364.424277 -353.489017) (xy 364.473854 -353.466375) (xy 364.526149 -353.45102) (xy 364.580097 -353.443264)
			(xy 364.634599 -353.443264) (xy 364.688547 -353.45102) (xy 364.740842 -353.466375) (xy 364.790419 -353.489017)
			(xy 364.836269 -353.518483) (xy 364.87746 -353.554174) (xy 364.913151 -353.595365) (xy 364.942617 -353.641215)
			(xy 364.965259 -353.690792) (xy 364.980614 -353.743087) (xy 364.98776 -353.79279) (xy 366.64722 -353.79279)
			(xy 366.651291 -353.737168) (xy 366.663417 -353.682731) (xy 366.68334 -353.63064) (xy 366.710636 -353.582005)
			(xy 366.744722 -353.537862) (xy 366.784871 -353.499153) (xy 366.830229 -353.466702) (xy 366.879829 -353.441201)
			(xy 366.932613 -353.423194) (xy 366.987456 -353.413064) (xy 367.04319 -353.411027) (xy 367.098627 -353.417127)
			(xy 367.152584 -353.431233) (xy 367.203913 -353.453045) (xy 367.251519 -353.482099) (xy 367.294387 -353.517774)
			(xy 367.331604 -353.559311) (xy 367.362377 -353.605824) (xy 367.386049 -353.656321) (xy 367.402117 -353.709728)
			(xy 367.410237 -353.764904) (xy 367.410746 -353.79279) (xy 367.410237 -353.820676) (xy 367.402117 -353.875852)
			(xy 367.386049 -353.929259) (xy 367.362377 -353.979756) (xy 367.331604 -354.026269) (xy 367.294387 -354.067806)
			(xy 367.251519 -354.103481) (xy 367.203913 -354.132535) (xy 367.152584 -354.154347) (xy 367.098627 -354.168453)
			(xy 367.04319 -354.174553) (xy 366.987456 -354.172516) (xy 366.932613 -354.162386) (xy 366.879829 -354.144379)
			(xy 366.830229 -354.118878) (xy 366.784871 -354.086427) (xy 366.744722 -354.047718) (xy 366.710636 -354.003575)
			(xy 366.68334 -353.95494) (xy 366.663417 -353.902849) (xy 366.651291 -353.848412) (xy 366.64722 -353.79279)
			(xy 364.98776 -353.79279) (xy 364.98837 -353.797035) (xy 364.988856 -353.824286) (xy 364.988425 -353.850666)
			(xy 364.981162 -353.902922) (xy 364.966772 -353.953681) (xy 364.945531 -354.001975) (xy 364.917841 -354.046884)
			(xy 364.884232 -354.087552) (xy 364.845342 -354.123205) (xy 364.801914 -354.153164) (xy 364.778544 -354.165408)
			(xy 364.766197 -354.17213) (xy 364.745467 -354.191101) (xy 364.730705 -354.215011) (xy 364.723031 -354.242044)
			(xy 364.72303 -354.270144) (xy 364.7307 -354.297177) (xy 364.745459 -354.321089) (xy 364.766186 -354.340063)
			(xy 364.778544 -354.346764) (xy 364.801919 -354.358998) (xy 364.845341 -354.388962) (xy 364.884225 -354.42462)
			(xy 364.91783 -354.465291) (xy 364.945516 -354.5102) (xy 364.966756 -354.558494) (xy 364.981145 -354.609252)
			(xy 364.98841 -354.661507) (xy 364.988856 -354.687886) (xy 364.98837 -354.715137) (xy 364.980614 -354.769085)
			(xy 364.965259 -354.82138) (xy 364.942617 -354.870957) (xy 364.913151 -354.916807) (xy 364.87746 -354.957998)
			(xy 364.836269 -354.993689) (xy 364.790419 -355.023155) (xy 364.740842 -355.045797) (xy 364.688547 -355.061152)
			(xy 364.634599 -355.068908) (xy 364.580097 -355.068908) (xy 364.526149 -355.061152) (xy 364.473854 -355.045797)
			(xy 364.424277 -355.023155) (xy 364.378427 -354.993689) (xy 364.337236 -354.957998) (xy 364.301545 -354.916807)
			(xy 364.272079 -354.870957) (xy 364.249437 -354.82138) (xy 364.234082 -354.769085) (xy 364.226326 -354.715137)
			(xy 364.22584 -354.687886) (xy 362.138285 -354.687886) (xy 362.141769 -354.711562) (xy 362.142278 -354.739448)
			(xy 362.141769 -354.767334) (xy 362.133649 -354.82251) (xy 362.117581 -354.875917) (xy 362.093909 -354.926414)
			(xy 362.063136 -354.972927) (xy 362.025919 -355.014464) (xy 361.983051 -355.050139) (xy 361.935445 -355.079193)
			(xy 361.884116 -355.101005) (xy 361.830159 -355.115111) (xy 361.774722 -355.121211) (xy 361.718988 -355.119174)
			(xy 361.664145 -355.109044) (xy 361.611361 -355.091037) (xy 361.561761 -355.065536) (xy 361.516403 -355.033085)
			(xy 361.476254 -354.994376) (xy 361.442168 -354.950233) (xy 361.414872 -354.901598) (xy 361.394949 -354.849507)
			(xy 361.382823 -354.79507) (xy 361.378752 -354.739448) (xy 360.987685 -354.739448) (xy 361.011869 -354.776002)
			(xy 361.035541 -354.826499) (xy 361.051609 -354.879906) (xy 361.059729 -354.935082) (xy 361.060238 -354.962968)
			(xy 361.059729 -354.990854) (xy 361.051609 -355.04603) (xy 361.035541 -355.099437) (xy 361.011869 -355.149934)
			(xy 360.981096 -355.196447) (xy 360.943879 -355.237984) (xy 360.901011 -355.273659) (xy 360.853405 -355.302713)
			(xy 360.802076 -355.324525) (xy 360.748119 -355.338631) (xy 360.692682 -355.344731) (xy 360.636948 -355.342694)
			(xy 360.582105 -355.332564) (xy 360.529321 -355.314557) (xy 360.479721 -355.289056) (xy 360.434363 -355.256605)
			(xy 360.394214 -355.217896) (xy 360.360128 -355.173753) (xy 360.332832 -355.125118) (xy 360.312909 -355.073027)
			(xy 360.300783 -355.01859) (xy 360.296712 -354.962968) (xy 359.883157 -354.962968) (xy 359.869846 -354.983087)
			(xy 359.832629 -355.024624) (xy 359.789761 -355.060299) (xy 359.742155 -355.089353) (xy 359.690826 -355.111165)
			(xy 359.636869 -355.125271) (xy 359.581432 -355.131371) (xy 359.525698 -355.129334) (xy 359.470855 -355.119204)
			(xy 359.418071 -355.101197) (xy 359.368471 -355.075696) (xy 359.323113 -355.043245) (xy 359.282964 -355.004536)
			(xy 359.248878 -354.960393) (xy 359.221582 -354.911758) (xy 359.201659 -354.859667) (xy 359.189533 -354.80523)
			(xy 359.185462 -354.749608) (xy 353.420058 -354.749608) (xy 353.412731 -354.755706) (xy 353.365093 -354.784779)
			(xy 353.31373 -354.806606) (xy 353.259737 -354.820722) (xy 353.204263 -354.826825) (xy 353.148492 -354.824787)
			(xy 353.093613 -354.81465) (xy 353.040793 -354.796631) (xy 352.991161 -354.771113) (xy 352.945773 -354.738641)
			(xy 352.905596 -354.699906) (xy 352.871488 -354.655734) (xy 352.844174 -354.607066) (xy 352.824238 -354.55494)
			(xy 352.812103 -354.500467) (xy 352.80803 -354.444808) (xy 349.89453 -354.444808) (xy 349.841105 -354.458775)
			(xy 349.785668 -354.464875) (xy 349.729934 -354.462838) (xy 349.675091 -354.452708) (xy 349.622307 -354.434701)
			(xy 349.572707 -354.4092) (xy 349.527349 -354.376749) (xy 349.4872 -354.33804) (xy 349.453114 -354.293897)
			(xy 349.425818 -354.245262) (xy 349.405895 -354.193171) (xy 349.393769 -354.138734) (xy 349.389698 -354.083112)
			(xy 326.188578 -354.083112) (xy 326.424036 -354.31857) (xy 326.424036 -355.359462) (xy 346.916246 -355.359462)
			(xy 346.920317 -355.30384) (xy 346.932443 -355.249403) (xy 346.952366 -355.197312) (xy 346.979662 -355.148677)
			(xy 347.013748 -355.104534) (xy 347.053897 -355.065825) (xy 347.099255 -355.033374) (xy 347.148855 -355.007873)
			(xy 347.201639 -354.989866) (xy 347.256482 -354.979736) (xy 347.312216 -354.977699) (xy 347.367653 -354.983799)
			(xy 347.42161 -354.997905) (xy 347.472939 -355.019717) (xy 347.520545 -355.048771) (xy 347.563413 -355.084446)
			(xy 347.60063 -355.125983) (xy 347.631403 -355.172496) (xy 347.655075 -355.222993) (xy 347.671143 -355.2764)
			(xy 347.679263 -355.331576) (xy 347.679647 -355.352604) (xy 368.216686 -355.352604) (xy 368.220757 -355.296982)
			(xy 368.232883 -355.242545) (xy 368.252806 -355.190454) (xy 368.280102 -355.141819) (xy 368.314188 -355.097676)
			(xy 368.354337 -355.058967) (xy 368.399695 -355.026516) (xy 368.449295 -355.001015) (xy 368.502079 -354.983008)
			(xy 368.556922 -354.972878) (xy 368.612656 -354.970841) (xy 368.668093 -354.976941) (xy 368.72205 -354.991047)
			(xy 368.773379 -355.012859) (xy 368.820985 -355.041913) (xy 368.863853 -355.077588) (xy 368.90107 -355.119125)
			(xy 368.931843 -355.165638) (xy 368.955515 -355.216135) (xy 368.971583 -355.269542) (xy 368.979703 -355.324718)
			(xy 368.980212 -355.352604) (xy 368.979703 -355.38049) (xy 368.971583 -355.435666) (xy 368.955515 -355.489073)
			(xy 368.931843 -355.53957) (xy 368.90107 -355.586083) (xy 368.863853 -355.62762) (xy 368.820985 -355.663295)
			(xy 368.773379 -355.692349) (xy 368.72205 -355.714161) (xy 368.668093 -355.728267) (xy 368.612656 -355.734367)
			(xy 368.556922 -355.73233) (xy 368.502079 -355.7222) (xy 368.449295 -355.704193) (xy 368.399695 -355.678692)
			(xy 368.354337 -355.646241) (xy 368.314188 -355.607532) (xy 368.280102 -355.563389) (xy 368.252806 -355.514754)
			(xy 368.232883 -355.462663) (xy 368.220757 -355.408226) (xy 368.216686 -355.352604) (xy 347.679647 -355.352604)
			(xy 347.679772 -355.359462) (xy 347.679263 -355.387348) (xy 347.671143 -355.442524) (xy 347.655075 -355.495931)
			(xy 347.631403 -355.546428) (xy 347.60063 -355.592941) (xy 347.563413 -355.634478) (xy 347.520545 -355.670153)
			(xy 347.472939 -355.699207) (xy 347.42161 -355.721019) (xy 347.367653 -355.735125) (xy 347.312216 -355.741225)
			(xy 347.256482 -355.739188) (xy 347.201639 -355.729058) (xy 347.148855 -355.711051) (xy 347.099255 -355.68555)
			(xy 347.053897 -355.653099) (xy 347.013748 -355.61439) (xy 346.979662 -355.570247) (xy 346.952366 -355.521612)
			(xy 346.932443 -355.469521) (xy 346.920317 -355.415084) (xy 346.916246 -355.359462) (xy 326.424036 -355.359462)
			(xy 326.424036 -355.399594) (xy 327.307526 -356.89365) (xy 336.912199 -356.89365) (xy 336.912199 -356.83915)
			(xy 336.919955 -356.785205) (xy 336.93531 -356.732913) (xy 336.95795 -356.683338) (xy 336.987415 -356.63749)
			(xy 337.023105 -356.596302) (xy 337.064293 -356.560613) (xy 337.110142 -356.531148) (xy 337.159717 -356.508508)
			(xy 337.212009 -356.493155) (xy 337.265954 -356.485399) (xy 337.293204 -356.484936) (xy 337.319273 -356.485399)
			(xy 337.370924 -356.492507) (xy 337.421127 -356.506577) (xy 337.468949 -356.527347) (xy 337.5135 -356.55443)
			(xy 337.553953 -356.587323) (xy 337.589553 -356.625414) (xy 337.619639 -356.667995) (xy 337.63204 -356.69093)
			(xy 337.638853 -356.703047) (xy 337.65782 -356.723352) (xy 337.681561 -356.737788) (xy 337.708317 -356.745284)
			(xy 337.736103 -356.745284) (xy 337.762859 -356.737788) (xy 337.7866 -356.723352) (xy 337.805567 -356.703047)
			(xy 337.81238 -356.69093) (xy 337.825437 -356.666805) (xy 337.857419 -356.622237) (xy 337.895431 -356.582687)
			(xy 337.916774 -356.565454) (xy 337.928536 -356.555509) (xy 337.946057 -356.530199) (xy 337.955239 -356.500818)
			(xy 337.955247 -356.470036) (xy 337.946081 -356.44065) (xy 337.928574 -356.41533) (xy 337.916774 -356.405434)
			(xy 337.894301 -356.38723) (xy 337.854567 -356.345212) (xy 337.821627 -356.29768) (xy 337.796237 -356.245721)
			(xy 337.778978 -356.190526) (xy 337.770245 -356.133359) (xy 337.769708 -356.104444) (xy 337.770196 -356.077192)
			(xy 337.777948 -356.023241) (xy 337.793299 -355.970942) (xy 337.815937 -355.921361) (xy 337.845402 -355.875507)
			(xy 337.881094 -355.834314) (xy 337.922285 -355.798619) (xy 337.968137 -355.769151) (xy 338.017716 -355.746509)
			(xy 338.070013 -355.731154) (xy 338.123964 -355.723398) (xy 338.151216 -355.722936) (xy 338.180131 -355.723501)
			(xy 338.237301 -355.732219) (xy 338.292499 -355.749466) (xy 338.344462 -355.774849) (xy 338.391997 -355.807785)
			(xy 338.434015 -355.84752) (xy 338.452206 -355.870002) (xy 338.462103 -355.881807) (xy 338.487427 -355.899326)
			(xy 338.51682 -355.908502) (xy 338.547612 -355.908502) (xy 338.577005 -355.899326) (xy 338.602329 -355.881807)
			(xy 338.612226 -355.870002) (xy 338.628979 -355.849219) (xy 338.667333 -355.812089) (xy 338.710487 -355.780667)
			(xy 338.757601 -355.755568) (xy 338.807753 -355.737282) (xy 338.859964 -355.726165) (xy 338.913216 -355.722435)
			(xy 338.966468 -355.726165) (xy 339.018679 -355.737282) (xy 339.068831 -355.755568) (xy 339.115945 -355.780667)
			(xy 339.159099 -355.812089) (xy 339.197453 -355.849219) (xy 339.214206 -355.870002) (xy 339.224103 -355.881807)
			(xy 339.249427 -355.899326) (xy 339.27882 -355.908502) (xy 339.309612 -355.908502) (xy 339.339005 -355.899326)
			(xy 339.364329 -355.881807) (xy 339.374226 -355.870002) (xy 339.390979 -355.849219) (xy 339.429333 -355.812089)
			(xy 339.472487 -355.780667) (xy 339.519601 -355.755568) (xy 339.569753 -355.737282) (xy 339.621964 -355.726165)
			(xy 339.675216 -355.722435) (xy 339.728468 -355.726165) (xy 339.780679 -355.737282) (xy 339.830831 -355.755568)
			(xy 339.877945 -355.780667) (xy 339.921099 -355.812089) (xy 339.959453 -355.849219) (xy 339.976206 -355.870002)
			(xy 339.986103 -355.881807) (xy 340.011427 -355.899326) (xy 340.04082 -355.908502) (xy 340.071612 -355.908502)
			(xy 340.101005 -355.899326) (xy 340.126329 -355.881807) (xy 340.136226 -355.870002) (xy 340.152979 -355.849219)
			(xy 340.191333 -355.812089) (xy 340.234487 -355.780667) (xy 340.281601 -355.755568) (xy 340.331753 -355.737282)
			(xy 340.383964 -355.726165) (xy 340.437216 -355.722435) (xy 340.490468 -355.726165) (xy 340.542679 -355.737282)
			(xy 340.592831 -355.755568) (xy 340.639945 -355.780667) (xy 340.683099 -355.812089) (xy 340.721453 -355.849219)
			(xy 340.738206 -355.870002) (xy 340.748103 -355.881807) (xy 340.773427 -355.899326) (xy 340.80282 -355.908502)
			(xy 340.833612 -355.908502) (xy 340.863005 -355.899326) (xy 340.888329 -355.881807) (xy 340.898226 -355.870002)
			(xy 340.914979 -355.849219) (xy 340.953333 -355.812089) (xy 340.996487 -355.780667) (xy 341.043601 -355.755568)
			(xy 341.093753 -355.737282) (xy 341.145964 -355.726165) (xy 341.199216 -355.722435) (xy 341.252468 -355.726165)
			(xy 341.304679 -355.737282) (xy 341.354831 -355.755568) (xy 341.401945 -355.780667) (xy 341.445099 -355.812089)
			(xy 341.483453 -355.849219) (xy 341.500206 -355.870002) (xy 341.510103 -355.881807) (xy 341.535427 -355.899326)
			(xy 341.56482 -355.908502) (xy 341.595612 -355.908502) (xy 341.625005 -355.899326) (xy 341.650329 -355.881807)
			(xy 341.660226 -355.870002) (xy 341.678403 -355.847506) (xy 341.720425 -355.807772) (xy 341.767963 -355.774834)
			(xy 341.819927 -355.749448) (xy 341.875127 -355.732194) (xy 341.932299 -355.723469) (xy 341.961216 -355.722936)
			(xy 341.987469 -355.723337) (xy 342.03948 -355.730528) (xy 342.090012 -355.744786) (xy 342.138112 -355.76584)
			(xy 342.182868 -355.793294) (xy 342.223436 -355.826627) (xy 342.259047 -355.86521) (xy 342.274398 -355.886512)
			(xy 342.282762 -355.897725) (xy 342.304387 -355.915451) (xy 342.330011 -355.926648) (xy 342.35771 -355.930476)
			(xy 342.385409 -355.926648) (xy 342.411033 -355.915451) (xy 342.432658 -355.897725) (xy 342.441022 -355.886512)
			(xy 342.456356 -355.865201) (xy 342.491981 -355.826635) (xy 342.532557 -355.793316) (xy 342.577317 -355.765873)
			(xy 342.625416 -355.744825) (xy 342.675946 -355.730568) (xy 342.727953 -355.723372) (xy 342.754204 -355.722936)
			(xy 342.784327 -355.723508) (xy 342.843823 -355.73299) (xy 342.901091 -355.7517) (xy 342.954708 -355.779176)
			(xy 343.003343 -355.814733) (xy 343.024968 -355.835712) (xy 343.03469 -355.84493) (xy 343.057852 -355.858375)
			(xy 343.083713 -355.865337) (xy 343.110495 -355.865337) (xy 343.136356 -355.858375) (xy 343.159518 -355.84493)
			(xy 343.16924 -355.835712) (xy 343.19087 -355.814737) (xy 343.239497 -355.779168) (xy 343.293112 -355.751687)
			(xy 343.350382 -355.732977) (xy 343.40988 -355.723505) (xy 343.440004 -355.722936) (xy 343.467259 -355.723352)
			(xy 343.521214 -355.73111) (xy 343.573515 -355.746469) (xy 343.623098 -355.769115) (xy 343.668954 -355.798588)
			(xy 343.710147 -355.834287) (xy 343.745841 -355.875485) (xy 343.775308 -355.921344) (xy 343.797948 -355.97093)
			(xy 343.8133 -356.023233) (xy 343.815772 -356.040436) (xy 351.932492 -356.040436) (xy 351.936565 -355.984777)
			(xy 351.9487 -355.930304) (xy 351.968636 -355.878178) (xy 351.99595 -355.82951) (xy 352.030058 -355.785338)
			(xy 352.070235 -355.746603) (xy 352.115623 -355.714131) (xy 352.165255 -355.688613) (xy 352.218075 -355.670594)
			(xy 352.272954 -355.660457) (xy 352.328725 -355.658419) (xy 352.384199 -355.664522) (xy 352.438192 -355.678638)
			(xy 352.489555 -355.700465) (xy 352.537193 -355.729538) (xy 352.580089 -355.765237) (xy 352.617331 -355.806801)
			(xy 352.648125 -355.853345) (xy 352.671813 -355.903876) (xy 352.687891 -355.957318) (xy 352.696017 -356.012532)
			(xy 352.696526 -356.040436) (xy 352.696017 -356.06834) (xy 352.687891 -356.123554) (xy 352.677975 -356.156514)
			(xy 358.86593 -356.156514) (xy 358.870001 -356.100892) (xy 358.882127 -356.046455) (xy 358.90205 -355.994364)
			(xy 358.929346 -355.945729) (xy 358.963432 -355.901586) (xy 359.003581 -355.862877) (xy 359.048939 -355.830426)
			(xy 359.098539 -355.804925) (xy 359.151323 -355.786918) (xy 359.206166 -355.776788) (xy 359.2619 -355.774751)
			(xy 359.317337 -355.780851) (xy 359.371294 -355.794957) (xy 359.422623 -355.816769) (xy 359.470229 -355.845823)
			(xy 359.513097 -355.881498) (xy 359.550314 -355.923035) (xy 359.581087 -355.969548) (xy 359.604759 -356.020045)
			(xy 359.620827 -356.073452) (xy 359.628947 -356.128628) (xy 359.629456 -356.156514) (xy 359.628947 -356.1844)
			(xy 359.620827 -356.239576) (xy 359.604759 -356.292983) (xy 359.581087 -356.34348) (xy 359.550314 -356.389993)
			(xy 359.513097 -356.43153) (xy 359.470229 -356.467205) (xy 359.422623 -356.496259) (xy 359.371294 -356.518071)
			(xy 359.317337 -356.532177) (xy 359.2619 -356.538277) (xy 359.206166 -356.53624) (xy 359.151323 -356.52611)
			(xy 359.098539 -356.508103) (xy 359.048939 -356.482602) (xy 359.003581 -356.450151) (xy 358.963432 -356.411442)
			(xy 358.929346 -356.367299) (xy 358.90205 -356.318664) (xy 358.882127 -356.266573) (xy 358.870001 -356.212136)
			(xy 358.86593 -356.156514) (xy 352.677975 -356.156514) (xy 352.671813 -356.176996) (xy 352.648125 -356.227527)
			(xy 352.617331 -356.274071) (xy 352.580089 -356.315635) (xy 352.537193 -356.351334) (xy 352.489555 -356.380407)
			(xy 352.438192 -356.402234) (xy 352.384199 -356.41635) (xy 352.328725 -356.422453) (xy 352.272954 -356.420415)
			(xy 352.218075 -356.410278) (xy 352.165255 -356.392259) (xy 352.115623 -356.366741) (xy 352.070235 -356.334269)
			(xy 352.030058 -356.295534) (xy 351.99595 -356.251362) (xy 351.968636 -356.202694) (xy 351.9487 -356.150568)
			(xy 351.936565 -356.096095) (xy 351.932492 -356.040436) (xy 343.815772 -356.040436) (xy 343.821052 -356.077189)
			(xy 343.821512 -356.104444) (xy 343.820987 -356.133361) (xy 343.812264 -356.190533) (xy 343.795009 -356.245734)
			(xy 343.769619 -356.297696) (xy 343.736675 -356.34523) (xy 343.696932 -356.387245) (xy 343.674446 -356.405434)
			(xy 343.662593 -356.415281) (xy 343.645071 -356.440617) (xy 343.635897 -356.470024) (xy 343.635899 -356.478332)
			(xy 346.916246 -356.478332) (xy 346.920317 -356.42271) (xy 346.932443 -356.368273) (xy 346.952366 -356.316182)
			(xy 346.979662 -356.267547) (xy 347.013748 -356.223404) (xy 347.053897 -356.184695) (xy 347.099255 -356.152244)
			(xy 347.148855 -356.126743) (xy 347.201639 -356.108736) (xy 347.256482 -356.098606) (xy 347.312216 -356.096569)
			(xy 347.367653 -356.102669) (xy 347.42161 -356.116775) (xy 347.472939 -356.138587) (xy 347.520545 -356.167641)
			(xy 347.563413 -356.203316) (xy 347.60063 -356.244853) (xy 347.631403 -356.291366) (xy 347.655075 -356.341863)
			(xy 347.671143 -356.39527) (xy 347.679263 -356.450446) (xy 347.679772 -356.478332) (xy 347.679263 -356.506218)
			(xy 347.673274 -356.546912) (xy 361.125006 -356.546912) (xy 361.129077 -356.49129) (xy 361.141203 -356.436853)
			(xy 361.161126 -356.384762) (xy 361.188422 -356.336127) (xy 361.222508 -356.291984) (xy 361.262657 -356.253275)
			(xy 361.308015 -356.220824) (xy 361.357615 -356.195323) (xy 361.410399 -356.177316) (xy 361.465242 -356.167186)
			(xy 361.520976 -356.165149) (xy 361.576413 -356.171249) (xy 361.63037 -356.185355) (xy 361.681699 -356.207167)
			(xy 361.729305 -356.236221) (xy 361.772173 -356.271896) (xy 361.80939 -356.313433) (xy 361.840163 -356.359946)
			(xy 361.846722 -356.373938) (xy 368.222274 -356.373938) (xy 368.226345 -356.318316) (xy 368.238471 -356.263879)
			(xy 368.258394 -356.211788) (xy 368.28569 -356.163153) (xy 368.319776 -356.11901) (xy 368.359925 -356.080301)
			(xy 368.405283 -356.04785) (xy 368.454883 -356.022349) (xy 368.507667 -356.004342) (xy 368.56251 -355.994212)
			(xy 368.618244 -355.992175) (xy 368.673681 -355.998275) (xy 368.727638 -356.012381) (xy 368.778967 -356.034193)
			(xy 368.826573 -356.063247) (xy 368.869441 -356.098922) (xy 368.906658 -356.140459) (xy 368.937431 -356.186972)
			(xy 368.961103 -356.237469) (xy 368.977171 -356.290876) (xy 368.978854 -356.30231) (xy 370.449854 -356.30231)
			(xy 370.453925 -356.246688) (xy 370.466051 -356.192251) (xy 370.485974 -356.14016) (xy 370.51327 -356.091525)
			(xy 370.547356 -356.047382) (xy 370.587505 -356.008673) (xy 370.632863 -355.976222) (xy 370.682463 -355.950721)
			(xy 370.735247 -355.932714) (xy 370.79009 -355.922584) (xy 370.845824 -355.920547) (xy 370.901261 -355.926647)
			(xy 370.955218 -355.940753) (xy 371.006547 -355.962565) (xy 371.054153 -355.991619) (xy 371.097021 -356.027294)
			(xy 371.134238 -356.068831) (xy 371.165011 -356.115344) (xy 371.188683 -356.165841) (xy 371.204751 -356.219248)
			(xy 371.212871 -356.274424) (xy 371.21338 -356.30231) (xy 371.212871 -356.330196) (xy 371.204751 -356.385372)
			(xy 371.188683 -356.438779) (xy 371.165011 -356.489276) (xy 371.134238 -356.535789) (xy 371.097021 -356.577326)
			(xy 371.054153 -356.613001) (xy 371.006547 -356.642055) (xy 370.955218 -356.663867) (xy 370.901261 -356.677973)
			(xy 370.845824 -356.684073) (xy 370.79009 -356.682036) (xy 370.735247 -356.671906) (xy 370.682463 -356.653899)
			(xy 370.632863 -356.628398) (xy 370.587505 -356.595947) (xy 370.547356 -356.557238) (xy 370.51327 -356.513095)
			(xy 370.485974 -356.46446) (xy 370.466051 -356.412369) (xy 370.453925 -356.357932) (xy 370.449854 -356.30231)
			(xy 368.978854 -356.30231) (xy 368.985291 -356.346052) (xy 368.9858 -356.373938) (xy 368.985291 -356.401824)
			(xy 368.977171 -356.457) (xy 368.961103 -356.510407) (xy 368.937431 -356.560904) (xy 368.906658 -356.607417)
			(xy 368.869441 -356.648954) (xy 368.826573 -356.684629) (xy 368.778967 -356.713683) (xy 368.727638 -356.735495)
			(xy 368.673681 -356.749601) (xy 368.618244 -356.755701) (xy 368.56251 -356.753664) (xy 368.507667 -356.743534)
			(xy 368.454883 -356.725527) (xy 368.405283 -356.700026) (xy 368.359925 -356.667575) (xy 368.319776 -356.628866)
			(xy 368.28569 -356.584723) (xy 368.258394 -356.536088) (xy 368.238471 -356.483997) (xy 368.226345 -356.42956)
			(xy 368.222274 -356.373938) (xy 361.846722 -356.373938) (xy 361.863835 -356.410443) (xy 361.879903 -356.46385)
			(xy 361.888023 -356.519026) (xy 361.888532 -356.546912) (xy 361.888023 -356.574798) (xy 361.879903 -356.629974)
			(xy 361.863835 -356.683381) (xy 361.840163 -356.733878) (xy 361.80939 -356.780391) (xy 361.772173 -356.821928)
			(xy 361.729305 -356.857603) (xy 361.681699 -356.886657) (xy 361.63037 -356.908469) (xy 361.576413 -356.922575)
			(xy 361.520976 -356.928675) (xy 361.465242 -356.926638) (xy 361.410399 -356.916508) (xy 361.357615 -356.898501)
			(xy 361.308015 -356.873) (xy 361.262657 -356.840549) (xy 361.222508 -356.80184) (xy 361.188422 -356.757697)
			(xy 361.161126 -356.709062) (xy 361.141203 -356.656971) (xy 361.129077 -356.602534) (xy 361.125006 -356.546912)
			(xy 347.673274 -356.546912) (xy 347.671143 -356.561394) (xy 347.655075 -356.614801) (xy 347.631403 -356.665298)
			(xy 347.60063 -356.711811) (xy 347.563413 -356.753348) (xy 347.520545 -356.789023) (xy 347.472939 -356.818077)
			(xy 347.42161 -356.839889) (xy 347.367653 -356.853995) (xy 347.312216 -356.860095) (xy 347.256482 -356.858058)
			(xy 347.201639 -356.847928) (xy 347.148855 -356.829921) (xy 347.099255 -356.80442) (xy 347.053897 -356.771969)
			(xy 347.013748 -356.73326) (xy 346.979662 -356.689117) (xy 346.952366 -356.640482) (xy 346.932443 -356.588391)
			(xy 346.920317 -356.533954) (xy 346.916246 -356.478332) (xy 343.635899 -356.478332) (xy 343.635905 -356.500829)
			(xy 343.645095 -356.530232) (xy 343.662631 -356.555558) (xy 343.674446 -356.565454) (xy 343.696917 -356.583659)
			(xy 343.736651 -356.625678) (xy 343.76959 -356.67321) (xy 343.79498 -356.725168) (xy 343.81224 -356.780362)
			(xy 343.820974 -356.837529) (xy 343.821512 -356.866444) (xy 343.821063 -356.893696) (xy 343.813301 -356.947645)
			(xy 343.79794 -356.99994) (xy 343.775294 -357.049517) (xy 343.758276 -357.075994) (xy 362.04347 -357.075994)
			(xy 362.047541 -357.020372) (xy 362.059667 -356.965935) (xy 362.07959 -356.913844) (xy 362.106886 -356.865209)
			(xy 362.140972 -356.821066) (xy 362.181121 -356.782357) (xy 362.226479 -356.749906) (xy 362.276079 -356.724405)
			(xy 362.328863 -356.706398) (xy 362.383706 -356.696268) (xy 362.43944 -356.694231) (xy 362.494877 -356.700331)
			(xy 362.548834 -356.714437) (xy 362.600163 -356.736249) (xy 362.647769 -356.765303) (xy 362.690637 -356.800978)
			(xy 362.727854 -356.842515) (xy 362.758627 -356.889028) (xy 362.782299 -356.939525) (xy 362.798367 -356.992932)
			(xy 362.806487 -357.048108) (xy 362.806996 -357.075994) (xy 362.806487 -357.10388) (xy 362.798367 -357.159056)
			(xy 362.786829 -357.197406) (xy 364.728504 -357.197406) (xy 364.732575 -357.141784) (xy 364.744701 -357.087347)
			(xy 364.764624 -357.035256) (xy 364.79192 -356.986621) (xy 364.826006 -356.942478) (xy 364.866155 -356.903769)
			(xy 364.911513 -356.871318) (xy 364.961113 -356.845817) (xy 365.013897 -356.82781) (xy 365.06874 -356.81768)
			(xy 365.124474 -356.815643) (xy 365.179911 -356.821743) (xy 365.233868 -356.835849) (xy 365.285197 -356.857661)
			(xy 365.332803 -356.886715) (xy 365.375671 -356.92239) (xy 365.412888 -356.963927) (xy 365.443661 -357.01044)
			(xy 365.467333 -357.060937) (xy 365.483401 -357.114344) (xy 365.491521 -357.16952) (xy 365.49203 -357.197406)
			(xy 365.491521 -357.225292) (xy 365.483401 -357.280468) (xy 365.467333 -357.333875) (xy 365.443661 -357.384372)
			(xy 365.412888 -357.430885) (xy 365.375671 -357.472422) (xy 365.332803 -357.508097) (xy 365.285197 -357.537151)
			(xy 365.233868 -357.558963) (xy 365.179911 -357.573069) (xy 365.124474 -357.579169) (xy 365.06874 -357.577132)
			(xy 365.013897 -357.567002) (xy 364.961113 -357.548995) (xy 364.911513 -357.523494) (xy 364.866155 -357.491043)
			(xy 364.826006 -357.452334) (xy 364.79192 -357.408191) (xy 364.764624 -357.359556) (xy 364.744701 -357.307465)
			(xy 364.732575 -357.253028) (xy 364.728504 -357.197406) (xy 362.786829 -357.197406) (xy 362.782299 -357.212463)
			(xy 362.758627 -357.26296) (xy 362.727854 -357.309473) (xy 362.690637 -357.35101) (xy 362.647769 -357.386685)
			(xy 362.600163 -357.415739) (xy 362.548834 -357.437551) (xy 362.494877 -357.451657) (xy 362.43944 -357.457757)
			(xy 362.383706 -357.45572) (xy 362.328863 -357.44559) (xy 362.276079 -357.427583) (xy 362.226479 -357.402082)
			(xy 362.181121 -357.369631) (xy 362.140972 -357.330922) (xy 362.106886 -357.286779) (xy 362.07959 -357.238144)
			(xy 362.059667 -357.186053) (xy 362.047541 -357.131616) (xy 362.04347 -357.075994) (xy 343.758276 -357.075994)
			(xy 343.745824 -357.095367) (xy 343.710129 -357.136557) (xy 343.668935 -357.172248) (xy 343.623082 -357.201713)
			(xy 343.573503 -357.224354) (xy 343.521206 -357.239709) (xy 343.467256 -357.247466) (xy 343.440004 -357.247952)
			(xy 343.409881 -357.247378) (xy 343.350384 -357.237898) (xy 343.293117 -357.219188) (xy 343.2395 -357.191712)
			(xy 343.190865 -357.156155) (xy 343.16924 -357.135176) (xy 343.159518 -357.125958) (xy 343.136356 -357.112513)
			(xy 343.110495 -357.105551) (xy 343.083713 -357.105551) (xy 343.057852 -357.112513) (xy 343.03469 -357.125958)
			(xy 343.024968 -357.135176) (xy 343.003332 -357.156145) (xy 342.954707 -357.191715) (xy 342.901093 -357.219198)
			(xy 342.843825 -357.237909) (xy 342.784328 -357.247383) (xy 342.754204 -357.247952) (xy 342.727951 -357.247541)
			(xy 342.675941 -357.240352) (xy 342.625408 -357.226097) (xy 342.577309 -357.205044) (xy 342.532552 -357.177592)
			(xy 342.491984 -357.14426) (xy 342.456373 -357.105677) (xy 342.441022 -357.084376) (xy 342.432658 -357.073163)
			(xy 342.411033 -357.055437) (xy 342.385409 -357.04424) (xy 342.35771 -357.040412) (xy 342.330011 -357.04424)
			(xy 342.304387 -357.055437) (xy 342.282762 -357.073163) (xy 342.274398 -357.084376) (xy 342.259048 -357.105675)
			(xy 342.223426 -357.144242) (xy 342.182853 -357.177562) (xy 342.138096 -357.205006) (xy 342.09 -357.226057)
			(xy 342.039472 -357.240316) (xy 341.987467 -357.247514) (xy 341.961216 -357.247952) (xy 341.932299 -357.24744)
			(xy 341.875126 -357.238713) (xy 341.819927 -357.221454) (xy 341.767964 -357.196062) (xy 341.720431 -357.163116)
			(xy 341.678415 -357.123373) (xy 341.660226 -357.100886) (xy 341.650329 -357.089081) (xy 341.625005 -357.071562)
			(xy 341.595612 -357.062386) (xy 341.56482 -357.062386) (xy 341.535427 -357.071562) (xy 341.510103 -357.089081)
			(xy 341.500206 -357.100886) (xy 341.483453 -357.121669) (xy 341.445099 -357.158799) (xy 341.401945 -357.190221)
			(xy 341.354831 -357.21532) (xy 341.304679 -357.233606) (xy 341.252468 -357.244723) (xy 341.199216 -357.248453)
			(xy 341.145964 -357.244723) (xy 341.093753 -357.233606) (xy 341.043601 -357.21532) (xy 340.996487 -357.190221)
			(xy 340.953333 -357.158799) (xy 340.914979 -357.121669) (xy 340.898226 -357.100886) (xy 340.888329 -357.089081)
			(xy 340.863005 -357.071562) (xy 340.833612 -357.062386) (xy 340.80282 -357.062386) (xy 340.773427 -357.071562)
			(xy 340.748103 -357.089081) (xy 340.738206 -357.100886) (xy 340.721453 -357.121669) (xy 340.683099 -357.158799)
			(xy 340.639945 -357.190221) (xy 340.592831 -357.21532) (xy 340.542679 -357.233606) (xy 340.490468 -357.244723)
			(xy 340.437216 -357.248453) (xy 340.383964 -357.244723) (xy 340.331753 -357.233606) (xy 340.281601 -357.21532)
			(xy 340.234487 -357.190221) (xy 340.191333 -357.158799) (xy 340.152979 -357.121669) (xy 340.136226 -357.100886)
			(xy 340.126329 -357.089081) (xy 340.101005 -357.071562) (xy 340.071612 -357.062386) (xy 340.04082 -357.062386)
			(xy 340.011427 -357.071562) (xy 339.986103 -357.089081) (xy 339.976206 -357.100886) (xy 339.959453 -357.121669)
			(xy 339.921099 -357.158799) (xy 339.877945 -357.190221) (xy 339.830831 -357.21532) (xy 339.780679 -357.233606)
			(xy 339.728468 -357.244723) (xy 339.675216 -357.248453) (xy 339.621964 -357.244723) (xy 339.569753 -357.233606)
			(xy 339.519601 -357.21532) (xy 339.472487 -357.190221) (xy 339.429333 -357.158799) (xy 339.390979 -357.121669)
			(xy 339.374226 -357.100886) (xy 339.364329 -357.089081) (xy 339.339005 -357.071562) (xy 339.309612 -357.062386)
			(xy 339.27882 -357.062386) (xy 339.249427 -357.071562) (xy 339.224103 -357.089081) (xy 339.214206 -357.100886)
			(xy 339.197453 -357.121669) (xy 339.159099 -357.158799) (xy 339.115945 -357.190221) (xy 339.068831 -357.21532)
			(xy 339.018679 -357.233606) (xy 338.966468 -357.244723) (xy 338.913216 -357.248453) (xy 338.859964 -357.244723)
			(xy 338.807753 -357.233606) (xy 338.757601 -357.21532) (xy 338.710487 -357.190221) (xy 338.667333 -357.158799)
			(xy 338.628979 -357.121669) (xy 338.612226 -357.100886) (xy 338.602329 -357.089081) (xy 338.577005 -357.071562)
			(xy 338.547612 -357.062386) (xy 338.51682 -357.062386) (xy 338.487427 -357.071562) (xy 338.462103 -357.089081)
			(xy 338.452206 -357.100886) (xy 338.434008 -357.123364) (xy 338.39199 -357.1631) (xy 338.344457 -357.19604)
			(xy 338.292497 -357.221429) (xy 338.2373 -357.238687) (xy 338.180132 -357.247417) (xy 338.151216 -357.247952)
			(xy 338.125148 -357.247479) (xy 338.073497 -357.240373) (xy 338.023293 -357.226305) (xy 337.975471 -357.205538)
			(xy 337.93092 -357.178456) (xy 337.890467 -357.145564) (xy 337.854867 -357.107473) (xy 337.82478 -357.064893)
			(xy 337.81238 -357.041958) (xy 337.805567 -357.029841) (xy 337.7866 -357.009536) (xy 337.762859 -356.9951)
			(xy 337.736103 -356.987604) (xy 337.708317 -356.987604) (xy 337.681561 -356.9951) (xy 337.65782 -357.009536)
			(xy 337.638853 -357.029841) (xy 337.63204 -357.041958) (xy 337.619684 -357.064922) (xy 337.589607 -357.107522)
			(xy 337.554009 -357.145628) (xy 337.513553 -357.178532) (xy 337.468992 -357.20562) (xy 337.421158 -357.226386)
			(xy 337.370941 -357.240445) (xy 337.319278 -357.247534) (xy 337.293204 -357.247952) (xy 337.265954 -357.247401)
			(xy 337.212009 -357.239645) (xy 337.159717 -357.224292) (xy 337.110142 -357.201652) (xy 337.064293 -357.172187)
			(xy 337.023105 -357.136498) (xy 336.987415 -357.09531) (xy 336.95795 -357.049462) (xy 336.93531 -356.999887)
			(xy 336.919955 -356.947595) (xy 336.912199 -356.89365) (xy 327.307526 -356.89365) (xy 328.694299 -359.238802)
			(xy 335.453223 -359.238802) (xy 335.456952 -359.18555) (xy 335.46807 -359.133337) (xy 335.486358 -359.083185)
			(xy 335.511459 -359.036072) (xy 335.542884 -358.992918) (xy 335.580018 -358.954566) (xy 335.600802 -358.937814)
			(xy 335.612602 -358.927911) (xy 335.630117 -358.902589) (xy 335.639292 -358.873197) (xy 335.639292 -358.842407)
			(xy 335.630119 -358.813016) (xy 335.612605 -358.787692) (xy 335.600802 -358.777794) (xy 335.578316 -358.759606)
			(xy 335.538581 -358.717586) (xy 335.505642 -358.67005) (xy 335.480254 -358.618088) (xy 335.462999 -358.56289)
			(xy 335.45427 -358.50572) (xy 335.453736 -358.476804) (xy 335.454159 -358.449549) (xy 335.461917 -358.395595)
			(xy 335.477275 -358.343293) (xy 335.49992 -358.29371) (xy 335.529391 -358.247855) (xy 335.565089 -358.206661)
			(xy 335.606287 -358.170967) (xy 335.652145 -358.141501) (xy 335.701731 -358.118861) (xy 335.754034 -358.103508)
			(xy 335.807989 -358.095756) (xy 335.835244 -358.095296) (xy 335.864296 -358.095875) (xy 335.92173 -358.104666)
			(xy 335.977166 -358.122067) (xy 336.029321 -358.147676) (xy 336.076988 -358.1809) (xy 336.119063 -358.220971)
			(xy 336.13725 -358.243632) (xy 336.146504 -358.254707) (xy 336.169828 -358.271677) (xy 336.196969 -358.281442)
			(xy 336.225758 -358.283222) (xy 336.253895 -358.276877) (xy 336.279133 -358.262911) (xy 336.28965 -358.25303)
			(xy 336.298332 -358.244396) (xy 336.316634 -358.228128) (xy 336.326226 -358.220518) (xy 336.33802 -358.21061)
			(xy 336.355531 -358.185287) (xy 336.364703 -358.155898) (xy 336.364705 -358.125111) (xy 336.355535 -358.095721)
			(xy 336.338026 -358.070397) (xy 336.326226 -358.060498) (xy 336.303747 -358.042302) (xy 336.26401 -358.000284)
			(xy 336.23107 -357.95275) (xy 336.205681 -357.90079) (xy 336.188424 -357.845593) (xy 336.179695 -357.788424)
			(xy 336.17916 -357.759508) (xy 336.179685 -357.732258) (xy 336.18744 -357.678314) (xy 336.202792 -357.626022)
			(xy 336.22543 -357.576447) (xy 336.254893 -357.530598) (xy 336.29058 -357.489408) (xy 336.331766 -357.453717)
			(xy 336.377611 -357.424249) (xy 336.427184 -357.401606) (xy 336.479475 -357.386248) (xy 336.533418 -357.378488)
			(xy 336.560668 -357.378) (xy 336.588047 -357.378477) (xy 336.64224 -357.386314) (xy 336.694757 -357.401816)
			(xy 336.744519 -357.424665) (xy 336.790505 -357.454393) (xy 336.831769 -357.490388) (xy 336.849974 -357.510842)
			(xy 336.860022 -357.521832) (xy 336.885087 -357.537887) (xy 336.913716 -357.54604) (xy 336.943479 -357.545599)
			(xy 336.971854 -357.536602) (xy 336.996433 -357.519812) (xy 337.006184 -357.508556) (xy 337.024421 -357.486776)
			(xy 337.066213 -357.448305) (xy 337.113247 -357.416454) (xy 337.164482 -357.391927) (xy 337.218787 -357.375267)
			(xy 337.274962 -357.366841) (xy 337.303364 -357.366316) (xy 337.331062 -357.366795) (xy 337.385876 -357.374797)
			(xy 337.438957 -357.390639) (xy 337.489191 -357.413988) (xy 337.535522 -357.444352) (xy 337.576978 -357.481096)
			(xy 337.59521 -357.501952) (xy 337.604729 -357.512643) (xy 337.628495 -357.528585) (xy 337.655753 -357.537301)
			(xy 337.684359 -357.538106) (xy 337.712064 -357.530938) (xy 337.736689 -357.516359) (xy 337.746848 -357.50627)
			(xy 337.764952 -357.487755) (xy 337.805259 -357.455249) (xy 337.849593 -357.428494) (xy 337.897138 -357.407982)
			(xy 337.947021 -357.394091) (xy 337.998325 -357.387075) (xy 338.024216 -357.386636) (xy 338.051471 -357.38704)
			(xy 338.105427 -357.3948) (xy 338.157728 -357.410161) (xy 338.207312 -357.432808) (xy 338.253167 -357.462282)
			(xy 338.29436 -357.497982) (xy 338.330054 -357.539181) (xy 338.35952 -357.585041) (xy 338.38216 -357.634628)
			(xy 338.397512 -357.686932) (xy 338.405264 -357.740889) (xy 338.405724 -357.768144) (xy 338.405194 -357.797061)
			(xy 338.396471 -357.854233) (xy 338.379218 -357.909433) (xy 338.353828 -357.961395) (xy 338.320885 -358.008929)
			(xy 338.281144 -358.050945) (xy 338.258658 -358.069134) (xy 338.246804 -358.078981) (xy 338.22928 -358.104316)
			(xy 338.220104 -358.133724) (xy 338.220112 -358.16453) (xy 338.229303 -358.193933) (xy 338.246842 -358.219259)
			(xy 338.258658 -358.229154) (xy 338.281111 -358.247382) (xy 338.32085 -358.289392) (xy 338.353794 -358.336919)
			(xy 338.379188 -358.388874) (xy 338.39645 -358.444065) (xy 338.405186 -358.50123) (xy 338.405724 -358.530144)
			(xy 338.405225 -358.557347) (xy 338.397493 -358.611202) (xy 338.382179 -358.663409) (xy 338.359595 -358.712906)
			(xy 338.330198 -358.758688) (xy 338.31276 -358.779572) (xy 338.303282 -358.791464) (xy 338.291054 -358.819286)
			(xy 338.287557 -358.849474) (xy 338.293099 -358.879354) (xy 338.307191 -358.906279) (xy 338.328583 -358.927865)
			(xy 338.341716 -358.935528) (xy 338.364879 -358.948451) (xy 338.407693 -358.979759) (xy 338.445736 -359.016719)
			(xy 338.462366 -359.037382) (xy 338.472263 -359.049187) (xy 338.497587 -359.066706) (xy 338.52698 -359.075882)
			(xy 338.557772 -359.075882) (xy 338.587165 -359.066706) (xy 338.612489 -359.049187) (xy 338.622386 -359.037382)
			(xy 338.639139 -359.016599) (xy 338.677493 -358.979469) (xy 338.720647 -358.948047) (xy 338.767761 -358.922948)
			(xy 338.817913 -358.904662) (xy 338.870124 -358.893545) (xy 338.923376 -358.889815) (xy 338.976628 -358.893545)
			(xy 339.028839 -358.904662) (xy 339.078991 -358.922948) (xy 339.126105 -358.948047) (xy 339.169259 -358.979469)
			(xy 339.207613 -359.016599) (xy 339.224366 -359.037382) (xy 339.234263 -359.049187) (xy 339.259587 -359.066706)
			(xy 339.28898 -359.075882) (xy 339.319772 -359.075882) (xy 339.349165 -359.066706) (xy 339.374489 -359.049187)
			(xy 339.384386 -359.037382) (xy 339.401139 -359.016599) (xy 339.439493 -358.979469) (xy 339.482647 -358.948047)
			(xy 339.529761 -358.922948) (xy 339.579913 -358.904662) (xy 339.632124 -358.893545) (xy 339.685376 -358.889815)
			(xy 339.738628 -358.893545) (xy 339.790839 -358.904662) (xy 339.840991 -358.922948) (xy 339.888105 -358.948047)
			(xy 339.931259 -358.979469) (xy 339.969613 -359.016599) (xy 339.986366 -359.037382) (xy 339.996263 -359.049187)
			(xy 340.021587 -359.066706) (xy 340.05098 -359.075882) (xy 340.081772 -359.075882) (xy 340.111165 -359.066706)
			(xy 340.136489 -359.049187) (xy 340.146386 -359.037382) (xy 340.163139 -359.016599) (xy 340.201493 -358.979469)
			(xy 340.244647 -358.948047) (xy 340.291761 -358.922948) (xy 340.341913 -358.904662) (xy 340.394124 -358.893545)
			(xy 340.447376 -358.889815) (xy 340.500628 -358.893545) (xy 340.552839 -358.904662) (xy 340.602991 -358.922948)
			(xy 340.650105 -358.948047) (xy 340.693259 -358.979469) (xy 340.731613 -359.016599) (xy 340.748366 -359.037382)
			(xy 340.758263 -359.049187) (xy 340.783587 -359.066706) (xy 340.81298 -359.075882) (xy 340.843772 -359.075882)
			(xy 340.873165 -359.066706) (xy 340.898489 -359.049187) (xy 340.908386 -359.037382) (xy 340.925139 -359.016599)
			(xy 340.963493 -358.979469) (xy 341.006647 -358.948047) (xy 341.053761 -358.922948) (xy 341.103913 -358.904662)
			(xy 341.156124 -358.893545) (xy 341.209376 -358.889815) (xy 341.262628 -358.893545) (xy 341.314839 -358.904662)
			(xy 341.364991 -358.922948) (xy 341.412105 -358.948047) (xy 341.455259 -358.979469) (xy 341.493613 -359.016599)
			(xy 341.510366 -359.037382) (xy 341.520263 -359.049187) (xy 341.545587 -359.066706) (xy 341.57498 -359.075882)
			(xy 341.605772 -359.075882) (xy 341.635165 -359.066706) (xy 341.660489 -359.049187) (xy 341.670386 -359.037382)
			(xy 341.688207 -359.015359) (xy 341.729273 -358.976336) (xy 341.752174 -358.959658) (xy 341.764272 -358.950505)
			(xy 341.782866 -358.926555) (xy 341.793608 -358.8982) (xy 341.795551 -358.867941) (xy 341.788523 -358.838446)
			(xy 341.773144 -358.812314) (xy 341.762334 -358.80167) (xy 341.743114 -358.783539) (xy 341.709397 -358.742857)
			(xy 341.681616 -358.697912) (xy 341.660303 -358.649563) (xy 341.645864 -358.598736) (xy 341.638575 -358.546403)
			(xy 341.638128 -358.519984) (xy 341.638696 -358.491069) (xy 341.647413 -358.4339) (xy 341.664661 -358.378701)
			(xy 341.690043 -358.326739) (xy 341.722978 -358.279204) (xy 341.762712 -358.237186) (xy 341.785194 -358.218994)
			(xy 341.797015 -358.209114) (xy 341.814531 -358.183785) (xy 341.823704 -358.154388) (xy 341.823701 -358.123593)
			(xy 341.814522 -358.094197) (xy 341.797001 -358.068872) (xy 341.785194 -358.058974) (xy 341.762697 -358.040799)
			(xy 341.722963 -357.998776) (xy 341.690026 -357.951238) (xy 341.66464 -357.899273) (xy 341.647386 -357.844073)
			(xy 341.638661 -357.786901) (xy 341.638128 -357.757984) (xy 341.63854 -357.730729) (xy 341.6463 -357.676774)
			(xy 341.66166 -357.624473) (xy 341.684307 -357.574891) (xy 341.71378 -357.529036) (xy 341.749479 -357.487842)
			(xy 341.790678 -357.452149) (xy 341.836536 -357.422682) (xy 341.886122 -357.400042) (xy 341.938425 -357.384689)
			(xy 341.992381 -357.376936) (xy 342.019636 -357.376476) (xy 342.01989 -357.376476) (xy 342.047433 -357.37695)
			(xy 342.101943 -357.384895) (xy 342.154745 -357.400592) (xy 342.204743 -357.423715) (xy 342.250898 -357.453785)
			(xy 342.292251 -357.490176) (xy 342.310466 -357.510842) (xy 342.320577 -357.521809) (xy 342.345631 -357.537962)
			(xy 342.374281 -357.5462) (xy 342.404088 -357.545822) (xy 342.432519 -357.536859) (xy 342.457154 -357.520074)
			(xy 342.46693 -357.50881) (xy 342.485142 -357.486967) (xy 342.526959 -357.448426) (xy 342.574034 -357.416519)
			(xy 342.625322 -357.39195) (xy 342.679689 -357.375266) (xy 342.735929 -357.366836) (xy 342.764364 -357.366316)
			(xy 342.794486 -357.366919) (xy 342.85398 -357.376394) (xy 342.911248 -357.395098) (xy 342.964865 -357.422566)
			(xy 343.013502 -357.458117) (xy 343.035128 -357.479092) (xy 343.04485 -357.48831) (xy 343.068012 -357.501755)
			(xy 343.093873 -357.508717) (xy 343.120655 -357.508717) (xy 343.146516 -357.501755) (xy 343.169678 -357.48831)
			(xy 343.1794 -357.479092) (xy 343.201 -357.458085) (xy 343.249636 -357.422521) (xy 343.303259 -357.395046)
			(xy 343.360534 -357.376344) (xy 343.420038 -357.36688) (xy 343.450164 -357.366316) (xy 343.477417 -357.366789)
			(xy 343.531369 -357.374542) (xy 343.583668 -357.389894) (xy 343.63325 -357.412534) (xy 343.679104 -357.442001)
			(xy 343.720298 -357.477694) (xy 343.734715 -357.494332) (xy 346.916246 -357.494332) (xy 346.920317 -357.43871)
			(xy 346.932443 -357.384273) (xy 346.952366 -357.332182) (xy 346.979662 -357.283547) (xy 347.013748 -357.239404)
			(xy 347.053897 -357.200695) (xy 347.099255 -357.168244) (xy 347.148855 -357.142743) (xy 347.201639 -357.124736)
			(xy 347.256482 -357.114606) (xy 347.312216 -357.112569) (xy 347.367653 -357.118669) (xy 347.42161 -357.132775)
			(xy 347.472939 -357.154587) (xy 347.520545 -357.183641) (xy 347.563413 -357.219316) (xy 347.60063 -357.260853)
			(xy 347.631403 -357.307366) (xy 347.655075 -357.357863) (xy 347.671143 -357.41127) (xy 347.679263 -357.466446)
			(xy 347.679772 -357.494332) (xy 347.679263 -357.522218) (xy 347.671143 -357.577394) (xy 347.655075 -357.630801)
			(xy 347.631403 -357.681298) (xy 347.60063 -357.727811) (xy 347.563413 -357.769348) (xy 347.520545 -357.805023)
			(xy 347.472939 -357.834077) (xy 347.42161 -357.855889) (xy 347.367653 -357.869995) (xy 347.312216 -357.876095)
			(xy 347.256482 -357.874058) (xy 347.201639 -357.863928) (xy 347.148855 -357.845921) (xy 347.099255 -357.82042)
			(xy 347.053897 -357.787969) (xy 347.013748 -357.74926) (xy 346.979662 -357.705117) (xy 346.952366 -357.656482)
			(xy 346.932443 -357.604391) (xy 346.920317 -357.549954) (xy 346.916246 -357.494332) (xy 343.734715 -357.494332)
			(xy 343.755992 -357.518886) (xy 343.78546 -357.56474) (xy 343.808102 -357.614321) (xy 343.823456 -357.666619)
			(xy 343.83121 -357.720571) (xy 343.831672 -357.747824) (xy 343.83111 -357.776739) (xy 343.822392 -357.833909)
			(xy 343.805143 -357.889108) (xy 343.77976 -357.94107) (xy 343.746823 -357.988605) (xy 343.707089 -358.030623)
			(xy 343.684606 -358.048814) (xy 343.672777 -358.058686) (xy 343.655261 -358.084017) (xy 343.646089 -358.113416)
			(xy 343.646093 -358.144213) (xy 343.655274 -358.17361) (xy 343.672798 -358.198936) (xy 343.684606 -358.208834)
			(xy 343.695667 -358.217724) (xy 347.824296 -358.217724) (xy 347.828367 -358.162102) (xy 347.840493 -358.107665)
			(xy 347.860416 -358.055574) (xy 347.887712 -358.006939) (xy 347.921798 -357.962796) (xy 347.961947 -357.924087)
			(xy 348.007305 -357.891636) (xy 348.056905 -357.866135) (xy 348.109689 -357.848128) (xy 348.164532 -357.837998)
			(xy 348.220266 -357.835961) (xy 348.275703 -357.842061) (xy 348.32966 -357.856167) (xy 348.380989 -357.877979)
			(xy 348.428595 -357.907033) (xy 348.471463 -357.942708) (xy 348.50868 -357.984245) (xy 348.539453 -358.030758)
			(xy 348.563125 -358.081255) (xy 348.579193 -358.134662) (xy 348.587313 -358.189838) (xy 348.587822 -358.217724)
			(xy 348.587313 -358.24561) (xy 348.582877 -358.275754) (xy 351.436636 -358.275754) (xy 351.436636 -358.221246)
			(xy 351.444393 -358.167294) (xy 351.459749 -358.114995) (xy 351.482392 -358.065413) (xy 351.51186 -358.019558)
			(xy 351.547554 -357.978364) (xy 351.588747 -357.942668) (xy 351.634601 -357.913198) (xy 351.684181 -357.890554)
			(xy 351.73648 -357.875196) (xy 351.790432 -357.867437) (xy 351.817686 -357.86695) (xy 351.833829 -357.867091)
			(xy 351.866003 -357.869764) (xy 351.881948 -357.872284) (xy 351.89597 -357.874265) (xy 351.924113 -357.871202)
			(xy 351.950334 -357.86053) (xy 351.972617 -357.843069) (xy 351.989249 -357.82016) (xy 351.998953 -357.793566)
			(xy 352.000981 -357.765329) (xy 351.998534 -357.75138) (xy 351.994727 -357.732111) (xy 351.990659 -357.693042)
			(xy 351.990406 -357.673402) (xy 351.990857 -357.646149) (xy 351.998614 -357.592196) (xy 352.013971 -357.539898)
			(xy 352.036614 -357.490317) (xy 352.066083 -357.444463) (xy 352.101778 -357.40327) (xy 352.142972 -357.367576)
			(xy 352.188827 -357.338108) (xy 352.238409 -357.315467) (xy 352.290708 -357.300112) (xy 352.344661 -357.292356)
			(xy 352.371914 -357.291894) (xy 352.399165 -357.292377) (xy 352.453111 -357.300135) (xy 352.505405 -357.315491)
			(xy 352.55498 -357.338133) (xy 352.600829 -357.3676) (xy 352.642018 -357.403292) (xy 352.677708 -357.444482)
			(xy 352.707173 -357.490332) (xy 352.729814 -357.539909) (xy 352.736121 -357.561388) (xy 360.900216 -357.561388)
			(xy 360.904287 -357.505766) (xy 360.916413 -357.451329) (xy 360.936336 -357.399238) (xy 360.963632 -357.350603)
			(xy 360.997718 -357.30646) (xy 361.037867 -357.267751) (xy 361.083225 -357.2353) (xy 361.132825 -357.209799)
			(xy 361.185609 -357.191792) (xy 361.240452 -357.181662) (xy 361.296186 -357.179625) (xy 361.351623 -357.185725)
			(xy 361.40558 -357.199831) (xy 361.456909 -357.221643) (xy 361.504515 -357.250697) (xy 361.547383 -357.286372)
			(xy 361.5846 -357.327909) (xy 361.615373 -357.374422) (xy 361.639045 -357.424919) (xy 361.655113 -357.478326)
			(xy 361.663233 -357.533502) (xy 361.663742 -357.561388) (xy 361.663233 -357.589274) (xy 361.655113 -357.64445)
			(xy 361.639045 -357.697857) (xy 361.615373 -357.748354) (xy 361.5846 -357.794867) (xy 361.547383 -357.836404)
			(xy 361.504515 -357.872079) (xy 361.456909 -357.901133) (xy 361.40558 -357.922945) (xy 361.351623 -357.937051)
			(xy 361.296186 -357.943151) (xy 361.240452 -357.941114) (xy 361.185609 -357.930984) (xy 361.132825 -357.912977)
			(xy 361.083225 -357.887476) (xy 361.037867 -357.855025) (xy 360.997718 -357.816316) (xy 360.963632 -357.772173)
			(xy 360.936336 -357.723538) (xy 360.916413 -357.671447) (xy 360.904287 -357.61701) (xy 360.900216 -357.561388)
			(xy 352.736121 -357.561388) (xy 352.745168 -357.592202) (xy 352.752924 -357.646149) (xy 352.752924 -357.700651)
			(xy 352.745168 -357.754598) (xy 352.729814 -357.806891) (xy 352.707173 -357.856468) (xy 352.677708 -357.902318)
			(xy 352.642018 -357.943508) (xy 352.600829 -357.9792) (xy 352.55498 -358.008667) (xy 352.505405 -358.031309)
			(xy 352.453111 -358.046665) (xy 352.399165 -358.054423) (xy 352.371914 -358.05491) (xy 352.355771 -358.05477)
			(xy 352.323597 -358.052097) (xy 352.307652 -358.049576) (xy 352.293627 -358.047643) (xy 352.265492 -358.050705)
			(xy 352.239279 -358.061372) (xy 352.217001 -358.078825) (xy 352.200612 -358.101389) (xy 369.986045 -358.101389)
			(xy 369.993796 -358.047437) (xy 370.009146 -357.995136) (xy 370.031783 -357.945553) (xy 370.061246 -357.899696)
			(xy 370.096935 -357.858499) (xy 370.138124 -357.8228) (xy 370.183974 -357.793326) (xy 370.233552 -357.770678)
			(xy 370.285848 -357.755315) (xy 370.339799 -357.747551) (xy 370.367052 -357.747062) (xy 370.380048 -357.747169)
			(xy 370.405979 -357.748949) (xy 370.418868 -357.750618) (xy 370.433246 -357.752024) (xy 370.461801 -357.747758)
			(xy 370.488017 -357.735664) (xy 370.509796 -357.71671) (xy 370.525393 -357.692414) (xy 370.533559 -357.664721)
			(xy 370.53364 -357.635849) (xy 370.53012 -357.62184) (xy 370.523261 -357.596222) (xy 370.515862 -357.543708)
			(xy 370.515388 -357.517192) (xy 370.515388 -357.51643) (xy 370.515823 -357.489174) (xy 370.523576 -357.435218)
			(xy 370.53893 -357.382913) (xy 370.561571 -357.333327) (xy 370.591039 -357.287467) (xy 370.626734 -357.246268)
			(xy 370.667928 -357.210568) (xy 370.713784 -357.181095) (xy 370.763368 -357.158447) (xy 370.81567 -357.143087)
			(xy 370.869626 -357.135326) (xy 370.924137 -357.135324) (xy 370.978093 -357.143079) (xy 371.030397 -357.158434)
			(xy 371.079983 -357.181077) (xy 371.125842 -357.210546) (xy 371.16704 -357.246242) (xy 371.202738 -357.287437)
			(xy 371.232211 -357.333294) (xy 371.254857 -357.382878) (xy 371.270216 -357.435181) (xy 371.277975 -357.489137)
			(xy 371.277976 -357.543648) (xy 371.270219 -357.597605) (xy 371.254862 -357.649908) (xy 371.232218 -357.699493)
			(xy 371.202747 -357.745351) (xy 371.16705 -357.786548) (xy 371.125854 -357.822245) (xy 371.079996 -357.851716)
			(xy 371.030411 -357.874361) (xy 370.978108 -357.889718) (xy 370.924152 -357.897475) (xy 370.896896 -357.897938)
			(xy 370.8839 -357.897826) (xy 370.857969 -357.896049) (xy 370.84508 -357.894382) (xy 370.830698 -357.893022)
			(xy 370.802146 -357.897276) (xy 370.77593 -357.909361) (xy 370.754151 -357.928308) (xy 370.738553 -357.952598)
			(xy 370.730387 -357.980286) (xy 370.730307 -358.009153) (xy 370.733828 -358.02316) (xy 370.740688 -358.048778)
			(xy 370.748086 -358.101292) (xy 370.74856 -358.127808) (xy 370.74856 -358.12857) (xy 370.748154 -358.155823)
			(xy 370.740402 -358.209775) (xy 370.72505 -358.262075) (xy 370.702411 -358.311657) (xy 370.672947 -358.357513)
			(xy 370.637256 -358.398709) (xy 370.596066 -358.434407) (xy 370.550215 -358.463879) (xy 370.500637 -358.486527)
			(xy 370.44834 -358.501888) (xy 370.394389 -358.50965) (xy 370.339883 -358.509655) (xy 370.285931 -358.501903)
			(xy 370.233631 -358.486552) (xy 370.184048 -358.463914) (xy 370.138191 -358.43445) (xy 370.096995 -358.39876)
			(xy 370.061297 -358.357571) (xy 370.031823 -358.311721) (xy 370.009176 -358.262142) (xy 369.993814 -358.209846)
			(xy 369.986051 -358.155895) (xy 369.986045 -358.101389) (xy 352.200612 -358.101389) (xy 352.200369 -358.101723)
			(xy 352.190662 -358.128307) (xy 352.188624 -358.156534) (xy 352.191066 -358.17048) (xy 352.194867 -358.18975)
			(xy 352.198939 -358.228818) (xy 352.199194 -358.248458) (xy 352.198706 -358.27571) (xy 352.190954 -358.329661)
			(xy 352.175603 -358.381959) (xy 352.152964 -358.43154) (xy 352.123499 -358.477394) (xy 352.087808 -358.518588)
			(xy 352.046617 -358.554282) (xy 352.01185 -358.576626) (xy 360.646216 -358.576626) (xy 360.650287 -358.521004)
			(xy 360.662413 -358.466567) (xy 360.682336 -358.414476) (xy 360.709632 -358.365841) (xy 360.743718 -358.321698)
			(xy 360.783867 -358.282989) (xy 360.829225 -358.250538) (xy 360.878825 -358.225037) (xy 360.931609 -358.20703)
			(xy 360.986452 -358.1969) (xy 361.042186 -358.194863) (xy 361.097623 -358.200963) (xy 361.15158 -358.215069)
			(xy 361.202909 -358.236881) (xy 361.250515 -358.265935) (xy 361.293383 -358.30161) (xy 361.3306 -358.343147)
			(xy 361.361373 -358.38966) (xy 361.385045 -358.440157) (xy 361.401113 -358.493564) (xy 361.409233 -358.54874)
			(xy 361.409742 -358.576626) (xy 361.409233 -358.604512) (xy 361.401113 -358.659688) (xy 361.385045 -358.713095)
			(xy 361.361373 -358.763592) (xy 361.3306 -358.810105) (xy 361.32291 -358.818688) (xy 366.653062 -358.818688)
			(xy 366.657133 -358.763066) (xy 366.669259 -358.708629) (xy 366.689182 -358.656538) (xy 366.716478 -358.607903)
			(xy 366.750564 -358.56376) (xy 366.790713 -358.525051) (xy 366.836071 -358.4926) (xy 366.885671 -358.467099)
			(xy 366.938455 -358.449092) (xy 366.993298 -358.438962) (xy 367.049032 -358.436925) (xy 367.104469 -358.443025)
			(xy 367.158426 -358.457131) (xy 367.209755 -358.478943) (xy 367.257361 -358.507997) (xy 367.300229 -358.543672)
			(xy 367.337446 -358.585209) (xy 367.368219 -358.631722) (xy 367.391891 -358.682219) (xy 367.407959 -358.735626)
			(xy 367.416079 -358.790802) (xy 367.416588 -358.818688) (xy 367.416079 -358.846574) (xy 367.407959 -358.90175)
			(xy 367.391891 -358.955157) (xy 367.387519 -358.964484) (xy 370.72773 -358.964484) (xy 370.731801 -358.908862)
			(xy 370.743927 -358.854425) (xy 370.76385 -358.802334) (xy 370.791146 -358.753699) (xy 370.825232 -358.709556)
			(xy 370.865381 -358.670847) (xy 370.910739 -358.638396) (xy 370.960339 -358.612895) (xy 371.013123 -358.594888)
			(xy 371.067966 -358.584758) (xy 371.1237 -358.582721) (xy 371.179137 -358.588821) (xy 371.233094 -358.602927)
			(xy 371.284423 -358.624739) (xy 371.332029 -358.653793) (xy 371.374897 -358.689468) (xy 371.412114 -358.731005)
			(xy 371.442887 -358.777518) (xy 371.466559 -358.828015) (xy 371.482627 -358.881422) (xy 371.490747 -358.936598)
			(xy 371.491256 -358.964484) (xy 371.490747 -358.99237) (xy 371.482627 -359.047546) (xy 371.466559 -359.100953)
			(xy 371.442887 -359.15145) (xy 371.412114 -359.197963) (xy 371.374897 -359.2395) (xy 371.332029 -359.275175)
			(xy 371.284423 -359.304229) (xy 371.233094 -359.326041) (xy 371.179137 -359.340147) (xy 371.1237 -359.346247)
			(xy 371.067966 -359.34421) (xy 371.013123 -359.33408) (xy 370.960339 -359.316073) (xy 370.910739 -359.290572)
			(xy 370.865381 -359.258121) (xy 370.825232 -359.219412) (xy 370.791146 -359.175269) (xy 370.76385 -359.126634)
			(xy 370.743927 -359.074543) (xy 370.731801 -359.020106) (xy 370.72773 -358.964484) (xy 367.387519 -358.964484)
			(xy 367.368219 -359.005654) (xy 367.337446 -359.052167) (xy 367.300229 -359.093704) (xy 367.257361 -359.129379)
			(xy 367.209755 -359.158433) (xy 367.158426 -359.180245) (xy 367.104469 -359.194351) (xy 367.049032 -359.200451)
			(xy 366.993298 -359.198414) (xy 366.938455 -359.188284) (xy 366.885671 -359.170277) (xy 366.836071 -359.144776)
			(xy 366.790713 -359.112325) (xy 366.750564 -359.073616) (xy 366.716478 -359.029473) (xy 366.689182 -358.980838)
			(xy 366.669259 -358.928747) (xy 366.657133 -358.87431) (xy 366.653062 -358.818688) (xy 361.32291 -358.818688)
			(xy 361.293383 -358.851642) (xy 361.250515 -358.887317) (xy 361.202909 -358.916371) (xy 361.15158 -358.938183)
			(xy 361.097623 -358.952289) (xy 361.042186 -358.958389) (xy 360.986452 -358.956352) (xy 360.931609 -358.946222)
			(xy 360.878825 -358.928215) (xy 360.829225 -358.902714) (xy 360.783867 -358.870263) (xy 360.743718 -358.831554)
			(xy 360.709632 -358.787411) (xy 360.682336 -358.738776) (xy 360.662413 -358.686685) (xy 360.650287 -358.632248)
			(xy 360.646216 -358.576626) (xy 352.01185 -358.576626) (xy 352.000765 -358.58375) (xy 351.951186 -358.606393)
			(xy 351.898889 -358.621748) (xy 351.844938 -358.629504) (xy 351.817686 -358.629966) (xy 351.790432 -358.629563)
			(xy 351.73648 -358.621804) (xy 351.684181 -358.606446) (xy 351.634601 -358.583802) (xy 351.588747 -358.554332)
			(xy 351.547554 -358.518636) (xy 351.51186 -358.477442) (xy 351.482392 -358.431587) (xy 351.459749 -358.382005)
			(xy 351.444393 -358.329706) (xy 351.436636 -358.275754) (xy 348.582877 -358.275754) (xy 348.579193 -358.300786)
			(xy 348.563125 -358.354193) (xy 348.539453 -358.40469) (xy 348.50868 -358.451203) (xy 348.471463 -358.49274)
			(xy 348.428595 -358.528415) (xy 348.380989 -358.557469) (xy 348.32966 -358.579281) (xy 348.275703 -358.593387)
			(xy 348.220266 -358.599487) (xy 348.164532 -358.59745) (xy 348.109689 -358.58732) (xy 348.056905 -358.569313)
			(xy 348.007305 -358.543812) (xy 347.961947 -358.511361) (xy 347.921798 -358.472652) (xy 347.887712 -358.428509)
			(xy 347.860416 -358.379874) (xy 347.840493 -358.327783) (xy 347.828367 -358.273346) (xy 347.824296 -358.217724)
			(xy 343.695667 -358.217724) (xy 343.705414 -358.225558) (xy 343.742548 -358.263913) (xy 343.773972 -358.307071)
			(xy 343.799073 -358.354188) (xy 343.81736 -358.404344) (xy 343.828477 -358.456559) (xy 343.832205 -358.509815)
			(xy 343.828473 -358.56307) (xy 343.817352 -358.615285) (xy 343.799061 -358.665439) (xy 343.773957 -358.712554)
			(xy 343.742529 -358.755709) (xy 343.705392 -358.794062) (xy 343.684606 -358.810814) (xy 343.672777 -358.820686)
			(xy 343.655261 -358.846017) (xy 343.646089 -358.875416) (xy 343.646093 -358.906213) (xy 343.655274 -358.93561)
			(xy 343.672798 -358.960936) (xy 343.684606 -358.970834) (xy 343.705414 -358.987558) (xy 343.742548 -359.025913)
			(xy 343.773972 -359.069071) (xy 343.799073 -359.116188) (xy 343.81736 -359.166344) (xy 343.828477 -359.218559)
			(xy 343.832205 -359.271815) (xy 343.828473 -359.32507) (xy 343.822394 -359.353612) (xy 346.946726 -359.353612)
			(xy 346.950797 -359.29799) (xy 346.962923 -359.243553) (xy 346.982846 -359.191462) (xy 347.010142 -359.142827)
			(xy 347.044228 -359.098684) (xy 347.084377 -359.059975) (xy 347.129735 -359.027524) (xy 347.179335 -359.002023)
			(xy 347.232119 -358.984016) (xy 347.286962 -358.973886) (xy 347.342696 -358.971849) (xy 347.398133 -358.977949)
			(xy 347.45209 -358.992055) (xy 347.503419 -359.013867) (xy 347.551025 -359.042921) (xy 347.593893 -359.078596)
			(xy 347.63111 -359.120133) (xy 347.661883 -359.166646) (xy 347.685555 -359.217143) (xy 347.701623 -359.27055)
			(xy 347.709743 -359.325726) (xy 347.710252 -359.353612) (xy 347.709743 -359.381498) (xy 347.701623 -359.436674)
			(xy 347.687334 -359.484168) (xy 349.7359 -359.484168) (xy 349.739971 -359.428546) (xy 349.752097 -359.374109)
			(xy 349.77202 -359.322018) (xy 349.799316 -359.273383) (xy 349.833402 -359.22924) (xy 349.873551 -359.190531)
			(xy 349.918909 -359.15808) (xy 349.968509 -359.132579) (xy 350.021293 -359.114572) (xy 350.076136 -359.104442)
			(xy 350.13187 -359.102405) (xy 350.187307 -359.108505) (xy 350.241264 -359.122611) (xy 350.292593 -359.144423)
			(xy 350.307817 -359.153714) (xy 351.933254 -359.153714) (xy 351.937325 -359.098092) (xy 351.949451 -359.043655)
			(xy 351.969374 -358.991564) (xy 351.99667 -358.942929) (xy 352.030756 -358.898786) (xy 352.070905 -358.860077)
			(xy 352.116263 -358.827626) (xy 352.165863 -358.802125) (xy 352.218647 -358.784118) (xy 352.27349 -358.773988)
			(xy 352.329224 -358.771951) (xy 352.384661 -358.778051) (xy 352.438618 -358.792157) (xy 352.489947 -358.813969)
			(xy 352.537553 -358.843023) (xy 352.580421 -358.878698) (xy 352.617638 -358.920235) (xy 352.648411 -358.966748)
			(xy 352.672083 -359.017245) (xy 352.688151 -359.070652) (xy 352.696271 -359.125828) (xy 352.69678 -359.153714)
			(xy 352.696271 -359.1816) (xy 352.688151 -359.236776) (xy 352.672083 -359.290183) (xy 352.648411 -359.34068)
			(xy 352.617638 -359.387193) (xy 352.580421 -359.42873) (xy 352.537553 -359.464405) (xy 352.489947 -359.493459)
			(xy 352.438618 -359.515271) (xy 352.384661 -359.529377) (xy 352.329224 -359.535477) (xy 352.27349 -359.53344)
			(xy 352.218647 -359.52331) (xy 352.165863 -359.505303) (xy 352.116263 -359.479802) (xy 352.070905 -359.447351)
			(xy 352.030756 -359.408642) (xy 351.99667 -359.364499) (xy 351.969374 -359.315864) (xy 351.949451 -359.263773)
			(xy 351.937325 -359.209336) (xy 351.933254 -359.153714) (xy 350.307817 -359.153714) (xy 350.340199 -359.173477)
			(xy 350.383067 -359.209152) (xy 350.420284 -359.250689) (xy 350.451057 -359.297202) (xy 350.474729 -359.347699)
			(xy 350.490797 -359.401106) (xy 350.498917 -359.456282) (xy 350.499426 -359.484168) (xy 350.498917 -359.512054)
			(xy 350.490797 -359.56723) (xy 350.482239 -359.595674) (xy 360.673902 -359.595674) (xy 360.677973 -359.540052)
			(xy 360.690099 -359.485615) (xy 360.710022 -359.433524) (xy 360.737318 -359.384889) (xy 360.771404 -359.340746)
			(xy 360.811553 -359.302037) (xy 360.856911 -359.269586) (xy 360.906511 -359.244085) (xy 360.959295 -359.226078)
			(xy 361.014138 -359.215948) (xy 361.069872 -359.213911) (xy 361.125309 -359.220011) (xy 361.179266 -359.234117)
			(xy 361.230595 -359.255929) (xy 361.278201 -359.284983) (xy 361.321069 -359.320658) (xy 361.358286 -359.362195)
			(xy 361.389059 -359.408708) (xy 361.412731 -359.459205) (xy 361.412982 -359.460038) (xy 363.93323 -359.460038)
			(xy 363.937301 -359.404416) (xy 363.949427 -359.349979) (xy 363.96935 -359.297888) (xy 363.996646 -359.249253)
			(xy 364.030732 -359.20511) (xy 364.070881 -359.166401) (xy 364.116239 -359.13395) (xy 364.165839 -359.108449)
			(xy 364.218623 -359.090442) (xy 364.273466 -359.080312) (xy 364.3292 -359.078275) (xy 364.384637 -359.084375)
			(xy 364.438594 -359.098481) (xy 364.489923 -359.120293) (xy 364.537529 -359.149347) (xy 364.580397 -359.185022)
			(xy 364.617614 -359.226559) (xy 364.648387 -359.273072) (xy 364.672059 -359.323569) (xy 364.688127 -359.376976)
			(xy 364.696247 -359.432152) (xy 364.696756 -359.460038) (xy 364.696247 -359.487924) (xy 364.688127 -359.5431)
			(xy 364.672059 -359.596507) (xy 364.648387 -359.647004) (xy 364.617614 -359.693517) (xy 364.580397 -359.735054)
			(xy 364.537529 -359.770729) (xy 364.489923 -359.799783) (xy 364.438594 -359.821595) (xy 364.384637 -359.835701)
			(xy 364.3292 -359.841801) (xy 364.273466 -359.839764) (xy 364.218623 -359.829634) (xy 364.165839 -359.811627)
			(xy 364.116239 -359.786126) (xy 364.070881 -359.753675) (xy 364.030732 -359.714966) (xy 363.996646 -359.670823)
			(xy 363.96935 -359.622188) (xy 363.949427 -359.570097) (xy 363.937301 -359.51566) (xy 363.93323 -359.460038)
			(xy 361.412982 -359.460038) (xy 361.428799 -359.512612) (xy 361.436919 -359.567788) (xy 361.437428 -359.595674)
			(xy 361.436919 -359.62356) (xy 361.428799 -359.678736) (xy 361.412731 -359.732143) (xy 361.389059 -359.78264)
			(xy 361.358286 -359.829153) (xy 361.321069 -359.87069) (xy 361.278201 -359.906365) (xy 361.230595 -359.935419)
			(xy 361.179266 -359.957231) (xy 361.125309 -359.971337) (xy 361.069872 -359.977437) (xy 361.014138 -359.9754)
			(xy 360.959295 -359.96527) (xy 360.906511 -359.947263) (xy 360.856911 -359.921762) (xy 360.811553 -359.889311)
			(xy 360.771404 -359.850602) (xy 360.737318 -359.806459) (xy 360.710022 -359.757824) (xy 360.690099 -359.705733)
			(xy 360.677973 -359.651296) (xy 360.673902 -359.595674) (xy 350.482239 -359.595674) (xy 350.474729 -359.620637)
			(xy 350.451057 -359.671134) (xy 350.420284 -359.717647) (xy 350.383067 -359.759184) (xy 350.340199 -359.794859)
			(xy 350.292593 -359.823913) (xy 350.241264 -359.845725) (xy 350.187307 -359.859831) (xy 350.13187 -359.865931)
			(xy 350.076136 -359.863894) (xy 350.021293 -359.853764) (xy 349.968509 -359.835757) (xy 349.918909 -359.810256)
			(xy 349.873551 -359.777805) (xy 349.833402 -359.739096) (xy 349.799316 -359.694953) (xy 349.77202 -359.646318)
			(xy 349.752097 -359.594227) (xy 349.739971 -359.53979) (xy 349.7359 -359.484168) (xy 347.687334 -359.484168)
			(xy 347.685555 -359.490081) (xy 347.661883 -359.540578) (xy 347.63111 -359.587091) (xy 347.593893 -359.628628)
			(xy 347.551025 -359.664303) (xy 347.503419 -359.693357) (xy 347.45209 -359.715169) (xy 347.398133 -359.729275)
			(xy 347.342696 -359.735375) (xy 347.286962 -359.733338) (xy 347.232119 -359.723208) (xy 347.179335 -359.705201)
			(xy 347.129735 -359.6797) (xy 347.084377 -359.647249) (xy 347.044228 -359.60854) (xy 347.010142 -359.564397)
			(xy 346.982846 -359.515762) (xy 346.962923 -359.463671) (xy 346.950797 -359.409234) (xy 346.946726 -359.353612)
			(xy 343.822394 -359.353612) (xy 343.817352 -359.377285) (xy 343.799061 -359.427439) (xy 343.773957 -359.474554)
			(xy 343.742529 -359.517709) (xy 343.705392 -359.556062) (xy 343.684606 -359.572814) (xy 343.672777 -359.582686)
			(xy 343.655261 -359.608017) (xy 343.646089 -359.637416) (xy 343.646093 -359.668213) (xy 343.655274 -359.69761)
			(xy 343.672798 -359.722936) (xy 343.684606 -359.732834) (xy 343.705414 -359.749558) (xy 343.742548 -359.787913)
			(xy 343.773972 -359.831071) (xy 343.799073 -359.878188) (xy 343.81736 -359.928344) (xy 343.828477 -359.980559)
			(xy 343.832205 -360.033815) (xy 343.828473 -360.08707) (xy 343.817352 -360.139285) (xy 343.799061 -360.189439)
			(xy 343.773957 -360.236554) (xy 343.742529 -360.279709) (xy 343.705392 -360.318062) (xy 343.684606 -360.334814)
			(xy 343.672777 -360.344686) (xy 343.655261 -360.370017) (xy 343.646089 -360.399416) (xy 343.646093 -360.430213)
			(xy 343.655274 -360.45961) (xy 343.672798 -360.484936) (xy 343.673697 -360.48569) (xy 347.061788 -360.48569)
			(xy 347.065859 -360.430068) (xy 347.077985 -360.375631) (xy 347.097908 -360.32354) (xy 347.125204 -360.274905)
			(xy 347.15929 -360.230762) (xy 347.199439 -360.192053) (xy 347.244797 -360.159602) (xy 347.294397 -360.134101)
			(xy 347.347181 -360.116094) (xy 347.402024 -360.105964) (xy 347.457758 -360.103927) (xy 347.513195 -360.110027)
			(xy 347.567152 -360.124133) (xy 347.618481 -360.145945) (xy 347.666087 -360.174999) (xy 347.708955 -360.210674)
			(xy 347.743033 -360.248708) (xy 352.035362 -360.248708) (xy 352.039433 -360.193086) (xy 352.051559 -360.138649)
			(xy 352.071482 -360.086558) (xy 352.098778 -360.037923) (xy 352.132864 -359.99378) (xy 352.173013 -359.955071)
			(xy 352.218371 -359.92262) (xy 352.267971 -359.897119) (xy 352.320755 -359.879112) (xy 352.375598 -359.868982)
			(xy 352.431332 -359.866945) (xy 352.486769 -359.873045) (xy 352.540726 -359.887151) (xy 352.592055 -359.908963)
			(xy 352.639661 -359.938017) (xy 352.682529 -359.973692) (xy 352.719746 -360.015229) (xy 352.750519 -360.061742)
			(xy 352.774191 -360.112239) (xy 352.786745 -360.153966) (xy 366.16843 -360.153966) (xy 366.172501 -360.098344)
			(xy 366.184627 -360.043907) (xy 366.20455 -359.991816) (xy 366.231846 -359.943181) (xy 366.265932 -359.899038)
			(xy 366.306081 -359.860329) (xy 366.351439 -359.827878) (xy 366.401039 -359.802377) (xy 366.453823 -359.78437)
			(xy 366.508666 -359.77424) (xy 366.5644 -359.772203) (xy 366.619837 -359.778303) (xy 366.673794 -359.792409)
			(xy 366.725123 -359.814221) (xy 366.772729 -359.843275) (xy 366.815597 -359.87895) (xy 366.852814 -359.920487)
			(xy 366.883587 -359.967) (xy 366.907259 -360.017497) (xy 366.923327 -360.070904) (xy 366.931447 -360.12608)
			(xy 366.931956 -360.153966) (xy 366.931447 -360.181852) (xy 366.923327 -360.237028) (xy 366.907259 -360.290435)
			(xy 366.883587 -360.340932) (xy 366.852814 -360.387445) (xy 366.815597 -360.428982) (xy 366.772729 -360.464657)
			(xy 366.725123 -360.493711) (xy 366.673794 -360.515523) (xy 366.619837 -360.529629) (xy 366.5644 -360.535729)
			(xy 366.508666 -360.533692) (xy 366.453823 -360.523562) (xy 366.401039 -360.505555) (xy 366.351439 -360.480054)
			(xy 366.306081 -360.447603) (xy 366.265932 -360.408894) (xy 366.231846 -360.364751) (xy 366.20455 -360.316116)
			(xy 366.184627 -360.264025) (xy 366.172501 -360.209588) (xy 366.16843 -360.153966) (xy 352.786745 -360.153966)
			(xy 352.790259 -360.165646) (xy 352.798379 -360.220822) (xy 352.798888 -360.248708) (xy 352.798379 -360.276594)
			(xy 352.790259 -360.33177) (xy 352.774191 -360.385177) (xy 352.750519 -360.435674) (xy 352.719746 -360.482187)
			(xy 352.682529 -360.523724) (xy 352.639661 -360.559399) (xy 352.592055 -360.588453) (xy 352.540726 -360.610265)
			(xy 352.536308 -360.61142) (xy 360.771438 -360.61142) (xy 360.775509 -360.555798) (xy 360.787635 -360.501361)
			(xy 360.807558 -360.44927) (xy 360.834854 -360.400635) (xy 360.86894 -360.356492) (xy 360.909089 -360.317783)
			(xy 360.954447 -360.285332) (xy 361.004047 -360.259831) (xy 361.056831 -360.241824) (xy 361.111674 -360.231694)
			(xy 361.167408 -360.229657) (xy 361.222845 -360.235757) (xy 361.276802 -360.249863) (xy 361.328131 -360.271675)
			(xy 361.375737 -360.300729) (xy 361.418605 -360.336404) (xy 361.455822 -360.377941) (xy 361.486595 -360.424454)
			(xy 361.510267 -360.474951) (xy 361.526335 -360.528358) (xy 361.534455 -360.583534) (xy 361.534964 -360.61142)
			(xy 361.534455 -360.639306) (xy 361.528391 -360.680508) (xy 376.90628 -360.680508) (xy 376.910351 -360.624886)
			(xy 376.922477 -360.570449) (xy 376.9424 -360.518358) (xy 376.969696 -360.469723) (xy 377.003782 -360.42558)
			(xy 377.043931 -360.386871) (xy 377.089289 -360.35442) (xy 377.138889 -360.328919) (xy 377.191673 -360.310912)
			(xy 377.246516 -360.300782) (xy 377.30225 -360.298745) (xy 377.357687 -360.304845) (xy 377.411644 -360.318951)
			(xy 377.462973 -360.340763) (xy 377.510579 -360.369817) (xy 377.553447 -360.405492) (xy 377.590664 -360.447029)
			(xy 377.621437 -360.493542) (xy 377.645109 -360.544039) (xy 377.661177 -360.597446) (xy 377.669297 -360.652622)
			(xy 377.669806 -360.680508) (xy 377.669297 -360.708394) (xy 377.661177 -360.76357) (xy 377.645109 -360.816977)
			(xy 377.621437 -360.867474) (xy 377.590664 -360.913987) (xy 377.553447 -360.955524) (xy 377.510579 -360.991199)
			(xy 377.462973 -361.020253) (xy 377.411644 -361.042065) (xy 377.357687 -361.056171) (xy 377.30225 -361.062271)
			(xy 377.246516 -361.060234) (xy 377.191673 -361.050104) (xy 377.138889 -361.032097) (xy 377.089289 -361.006596)
			(xy 377.043931 -360.974145) (xy 377.003782 -360.935436) (xy 376.969696 -360.891293) (xy 376.9424 -360.842658)
			(xy 376.922477 -360.790567) (xy 376.910351 -360.73613) (xy 376.90628 -360.680508) (xy 361.528391 -360.680508)
			(xy 361.526335 -360.694482) (xy 361.510267 -360.747889) (xy 361.486595 -360.798386) (xy 361.455822 -360.844899)
			(xy 361.418605 -360.886436) (xy 361.375737 -360.922111) (xy 361.328131 -360.951165) (xy 361.276802 -360.972977)
			(xy 361.222845 -360.987083) (xy 361.167408 -360.993183) (xy 361.111674 -360.991146) (xy 361.056831 -360.981016)
			(xy 361.004047 -360.963009) (xy 360.954447 -360.937508) (xy 360.909089 -360.905057) (xy 360.86894 -360.866348)
			(xy 360.834854 -360.822205) (xy 360.807558 -360.77357) (xy 360.787635 -360.721479) (xy 360.775509 -360.667042)
			(xy 360.771438 -360.61142) (xy 352.536308 -360.61142) (xy 352.486769 -360.624371) (xy 352.431332 -360.630471)
			(xy 352.375598 -360.628434) (xy 352.320755 -360.618304) (xy 352.267971 -360.600297) (xy 352.218371 -360.574796)
			(xy 352.173013 -360.542345) (xy 352.132864 -360.503636) (xy 352.098778 -360.459493) (xy 352.071482 -360.410858)
			(xy 352.051559 -360.358767) (xy 352.039433 -360.30433) (xy 352.035362 -360.248708) (xy 347.743033 -360.248708)
			(xy 347.746172 -360.252211) (xy 347.776945 -360.298724) (xy 347.800617 -360.349221) (xy 347.816685 -360.402628)
			(xy 347.824805 -360.457804) (xy 347.825314 -360.48569) (xy 347.824805 -360.513576) (xy 347.816685 -360.568752)
			(xy 347.800617 -360.622159) (xy 347.776945 -360.672656) (xy 347.746172 -360.719169) (xy 347.708955 -360.760706)
			(xy 347.666087 -360.796381) (xy 347.618481 -360.825435) (xy 347.567152 -360.847247) (xy 347.513195 -360.861353)
			(xy 347.457758 -360.867453) (xy 347.402024 -360.865416) (xy 347.347181 -360.855286) (xy 347.294397 -360.837279)
			(xy 347.244797 -360.811778) (xy 347.199439 -360.779327) (xy 347.15929 -360.740618) (xy 347.125204 -360.696475)
			(xy 347.097908 -360.64784) (xy 347.077985 -360.595749) (xy 347.065859 -360.541312) (xy 347.061788 -360.48569)
			(xy 343.673697 -360.48569) (xy 343.684606 -360.494834) (xy 343.707107 -360.513004) (xy 343.746841 -360.555029)
			(xy 343.779778 -360.602568) (xy 343.805163 -360.654533) (xy 343.822415 -360.709734) (xy 343.83114 -360.766907)
			(xy 343.831672 -360.795824) (xy 343.831267 -360.823079) (xy 343.823506 -360.877034) (xy 343.808145 -360.929335)
			(xy 343.785497 -360.978918) (xy 343.756023 -361.024773) (xy 343.720324 -361.065966) (xy 343.679125 -361.101659)
			(xy 343.633265 -361.131126) (xy 343.583679 -361.153766) (xy 343.554449 -361.162346) (xy 347.74454 -361.162346)
			(xy 347.748611 -361.106724) (xy 347.760737 -361.052287) (xy 347.78066 -361.000196) (xy 347.807956 -360.951561)
			(xy 347.842042 -360.907418) (xy 347.882191 -360.868709) (xy 347.927549 -360.836258) (xy 347.977149 -360.810757)
			(xy 348.029933 -360.79275) (xy 348.084776 -360.78262) (xy 348.14051 -360.780583) (xy 348.195947 -360.786683)
			(xy 348.249904 -360.800789) (xy 348.301233 -360.822601) (xy 348.348839 -360.851655) (xy 348.391707 -360.88733)
			(xy 348.428924 -360.928867) (xy 348.459697 -360.97538) (xy 348.483369 -361.025877) (xy 348.499437 -361.079284)
			(xy 348.507362 -361.133136) (xy 369.3861 -361.133136) (xy 369.390189 -361.077254) (xy 369.402372 -361.022564)
			(xy 369.422388 -360.97023) (xy 369.449811 -360.921368) (xy 369.484056 -360.87702) (xy 369.524392 -360.83813)
			(xy 369.569962 -360.805528) (xy 369.619793 -360.779909) (xy 369.672823 -360.761817) (xy 369.727921 -360.75164)
			(xy 369.783915 -360.749594) (xy 369.83961 -360.755722) (xy 369.893819 -360.769894) (xy 369.945387 -360.791808)
			(xy 369.993215 -360.820997) (xy 370.036283 -360.856838) (xy 370.073673 -360.898568) (xy 370.104589 -360.945298)
			(xy 370.128372 -360.996031) (xy 370.144514 -361.049687) (xy 370.152673 -361.105121) (xy 370.153184 -361.133136)
			(xy 370.152673 -361.161151) (xy 370.144514 -361.216585) (xy 370.128372 -361.270241) (xy 370.104589 -361.320974)
			(xy 370.073673 -361.367704) (xy 370.036283 -361.409434) (xy 369.993215 -361.445275) (xy 369.945387 -361.474464)
			(xy 369.893819 -361.496378) (xy 369.83961 -361.51055) (xy 369.783915 -361.516678) (xy 369.727921 -361.514632)
			(xy 369.672823 -361.504455) (xy 369.619793 -361.486363) (xy 369.569962 -361.460744) (xy 369.524392 -361.428142)
			(xy 369.484056 -361.389252) (xy 369.449811 -361.344904) (xy 369.422388 -361.296042) (xy 369.402372 -361.243708)
			(xy 369.390189 -361.189018) (xy 369.3861 -361.133136) (xy 348.507362 -361.133136) (xy 348.507557 -361.13446)
			(xy 348.508066 -361.162346) (xy 348.507557 -361.190232) (xy 348.499437 -361.245408) (xy 348.483369 -361.298815)
			(xy 348.459697 -361.349312) (xy 348.428924 -361.395825) (xy 348.391707 -361.437362) (xy 348.348839 -361.473037)
			(xy 348.301233 -361.502091) (xy 348.249904 -361.523903) (xy 348.195947 -361.538009) (xy 348.14051 -361.544109)
			(xy 348.084776 -361.542072) (xy 348.029933 -361.531942) (xy 347.977149 -361.513935) (xy 347.927549 -361.488434)
			(xy 347.882191 -361.455983) (xy 347.842042 -361.417274) (xy 347.807956 -361.373131) (xy 347.78066 -361.324496)
			(xy 347.760737 -361.272405) (xy 347.748611 -361.217968) (xy 347.74454 -361.162346) (xy 343.554449 -361.162346)
			(xy 343.531375 -361.169119) (xy 343.477419 -361.176872) (xy 343.450164 -361.177332) (xy 343.420835 -361.17678)
			(xy 343.362867 -361.167803) (xy 343.306955 -361.150067) (xy 343.254413 -361.123987) (xy 343.206477 -361.090179)
			(xy 343.164276 -361.049438) (xy 343.128803 -361.002721) (xy 343.114376 -360.97718) (xy 343.035128 -360.964226)
			(xy 343.02319 -360.974894) (xy 343.013502 -360.983802) (xy 342.998565 -361.005455) (xy 342.98967 -361.030211)
			(xy 342.987408 -361.056418) (xy 342.991932 -361.082332) (xy 343.002939 -361.106223) (xy 343.010998 -361.116626)
			(xy 343.027386 -361.137204) (xy 343.054961 -361.182004) (xy 343.076115 -361.23017) (xy 343.090444 -361.280787)
			(xy 343.097678 -361.332893) (xy 343.09812 -361.359196) (xy 343.097619 -361.386447) (xy 343.089863 -361.440393)
			(xy 343.074509 -361.492687) (xy 343.051869 -361.542263) (xy 343.022404 -361.588113) (xy 342.986714 -361.629303)
			(xy 342.945526 -361.664995) (xy 342.899677 -361.694461) (xy 342.850102 -361.717103) (xy 342.797809 -361.732459)
			(xy 342.743863 -361.740217) (xy 342.716612 -361.740704) (xy 342.687694 -361.740214) (xy 342.630519 -361.731484)
			(xy 342.575318 -361.714223) (xy 342.523356 -361.688826) (xy 342.475823 -361.655876) (xy 342.43381 -361.616127)
			(xy 342.415622 -361.593638) (xy 342.405725 -361.581833) (xy 342.380401 -361.564314) (xy 342.351008 -361.555138)
			(xy 342.320216 -361.555138) (xy 342.290823 -361.564314) (xy 342.265499 -361.581833) (xy 342.255602 -361.593638)
			(xy 342.248333 -361.602813) (xy 342.232828 -361.620351) (xy 342.224614 -361.62869) (xy 342.214238 -361.639813)
			(xy 342.200039 -361.666701) (xy 342.19437 -361.696575) (xy 342.197731 -361.726795) (xy 342.209827 -361.754692)
			(xy 342.21928 -361.766612) (xy 342.236469 -361.78743) (xy 342.265387 -361.833019) (xy 342.287596 -361.882227)
			(xy 342.302652 -361.934073) (xy 342.305423 -361.953556) (xy 349.395032 -361.953556) (xy 349.399103 -361.897934)
			(xy 349.411229 -361.843497) (xy 349.431152 -361.791406) (xy 349.458448 -361.742771) (xy 349.492534 -361.698628)
			(xy 349.532683 -361.659919) (xy 349.578041 -361.627468) (xy 349.627641 -361.601967) (xy 349.680425 -361.58396)
			(xy 349.735268 -361.57383) (xy 349.791002 -361.571793) (xy 349.846439 -361.577893) (xy 349.900396 -361.591999)
			(xy 349.951725 -361.613811) (xy 349.999331 -361.642865) (xy 350.042199 -361.67854) (xy 350.079416 -361.720077)
			(xy 350.110189 -361.76659) (xy 350.133861 -361.817087) (xy 350.149929 -361.870494) (xy 350.158049 -361.92567)
			(xy 350.15853 -361.952032) (xy 350.408746 -361.952032) (xy 350.412817 -361.89641) (xy 350.424943 -361.841973)
			(xy 350.444866 -361.789882) (xy 350.472162 -361.741247) (xy 350.506248 -361.697104) (xy 350.546397 -361.658395)
			(xy 350.591755 -361.625944) (xy 350.641355 -361.600443) (xy 350.694139 -361.582436) (xy 350.748982 -361.572306)
			(xy 350.804716 -361.570269) (xy 350.860153 -361.576369) (xy 350.91411 -361.590475) (xy 350.965439 -361.612287)
			(xy 351.013045 -361.641341) (xy 351.055913 -361.677016) (xy 351.059723 -361.681268) (xy 352.721162 -361.681268)
			(xy 352.725233 -361.625646) (xy 352.737359 -361.571209) (xy 352.757282 -361.519118) (xy 352.784578 -361.470483)
			(xy 352.818664 -361.42634) (xy 352.858813 -361.387631) (xy 352.904171 -361.35518) (xy 352.953771 -361.329679)
			(xy 353.006555 -361.311672) (xy 353.061398 -361.301542) (xy 353.117132 -361.299505) (xy 353.172569 -361.305605)
			(xy 353.226526 -361.319711) (xy 353.277855 -361.341523) (xy 353.325461 -361.370577) (xy 353.368329 -361.406252)
			(xy 353.405546 -361.447789) (xy 353.436319 -361.494302) (xy 353.459905 -361.544616) (xy 360.295696 -361.544616)
			(xy 360.299767 -361.488994) (xy 360.311893 -361.434557) (xy 360.331816 -361.382466) (xy 360.359112 -361.333831)
			(xy 360.393198 -361.289688) (xy 360.433347 -361.250979) (xy 360.478705 -361.218528) (xy 360.528305 -361.193027)
			(xy 360.581089 -361.17502) (xy 360.635932 -361.16489) (xy 360.691666 -361.162853) (xy 360.747103 -361.168953)
			(xy 360.80106 -361.183059) (xy 360.852389 -361.204871) (xy 360.899995 -361.233925) (xy 360.942863 -361.2696)
			(xy 360.98008 -361.311137) (xy 361.010853 -361.35765) (xy 361.034525 -361.408147) (xy 361.050593 -361.461554)
			(xy 361.058713 -361.51673) (xy 361.059222 -361.544616) (xy 361.058713 -361.572502) (xy 361.050593 -361.627678)
			(xy 361.034525 -361.681085) (xy 361.010853 -361.731582) (xy 360.98008 -361.778095) (xy 360.942863 -361.819632)
			(xy 360.899995 -361.855307) (xy 360.852389 -361.884361) (xy 360.80106 -361.906173) (xy 360.747103 -361.920279)
			(xy 360.691666 -361.926379) (xy 360.635932 -361.924342) (xy 360.581089 -361.914212) (xy 360.528305 -361.896205)
			(xy 360.478705 -361.870704) (xy 360.433347 -361.838253) (xy 360.393198 -361.799544) (xy 360.359112 -361.755401)
			(xy 360.331816 -361.706766) (xy 360.311893 -361.654675) (xy 360.299767 -361.600238) (xy 360.295696 -361.544616)
			(xy 353.459905 -361.544616) (xy 353.459991 -361.544799) (xy 353.476059 -361.598206) (xy 353.484179 -361.653382)
			(xy 353.484688 -361.681268) (xy 353.484179 -361.709154) (xy 353.476059 -361.76433) (xy 353.459991 -361.817737)
			(xy 353.436319 -361.868234) (xy 353.405546 -361.914747) (xy 353.368329 -361.956284) (xy 353.325461 -361.991959)
			(xy 353.277855 -362.021013) (xy 353.226526 -362.042825) (xy 353.172569 -362.056931) (xy 353.117132 -362.063031)
			(xy 353.061398 -362.060994) (xy 353.006555 -362.050864) (xy 352.953771 -362.032857) (xy 352.904171 -362.007356)
			(xy 352.858813 -361.974905) (xy 352.818664 -361.936196) (xy 352.784578 -361.892053) (xy 352.757282 -361.843418)
			(xy 352.737359 -361.791327) (xy 352.725233 -361.73689) (xy 352.721162 -361.681268) (xy 351.059723 -361.681268)
			(xy 351.09313 -361.718553) (xy 351.123903 -361.765066) (xy 351.147575 -361.815563) (xy 351.163643 -361.86897)
			(xy 351.171763 -361.924146) (xy 351.172272 -361.952032) (xy 351.171763 -361.979918) (xy 351.163643 -362.035094)
			(xy 351.147575 -362.088501) (xy 351.123903 -362.138998) (xy 351.09313 -362.185511) (xy 351.055913 -362.227048)
			(xy 351.013045 -362.262723) (xy 350.965439 -362.291777) (xy 350.91411 -362.313589) (xy 350.860153 -362.327695)
			(xy 350.804716 -362.333795) (xy 350.748982 -362.331758) (xy 350.694139 -362.321628) (xy 350.641355 -362.303621)
			(xy 350.591755 -362.27812) (xy 350.546397 -362.245669) (xy 350.506248 -362.20696) (xy 350.472162 -362.162817)
			(xy 350.444866 -362.114182) (xy 350.424943 -362.062091) (xy 350.412817 -362.007654) (xy 350.408746 -361.952032)
			(xy 350.15853 -361.952032) (xy 350.158558 -361.953556) (xy 350.158049 -361.981442) (xy 350.149929 -362.036618)
			(xy 350.133861 -362.090025) (xy 350.110189 -362.140522) (xy 350.079416 -362.187035) (xy 350.042199 -362.228572)
			(xy 349.999331 -362.264247) (xy 349.951725 -362.293301) (xy 349.900396 -362.315113) (xy 349.846439 -362.329219)
			(xy 349.791002 -362.335319) (xy 349.735268 -362.333282) (xy 349.680425 -362.323152) (xy 349.627641 -362.305145)
			(xy 349.578041 -362.279644) (xy 349.532683 -362.247193) (xy 349.492534 -362.208484) (xy 349.458448 -362.164341)
			(xy 349.431152 -362.115706) (xy 349.411229 -362.063615) (xy 349.399103 -362.009178) (xy 349.395032 -361.953556)
			(xy 342.305423 -361.953556) (xy 342.310254 -361.987522) (xy 342.31072 -362.014516) (xy 342.310237 -362.041767)
			(xy 342.302479 -362.095714) (xy 342.287122 -362.148008) (xy 342.26448 -362.197585) (xy 342.235013 -362.243435)
			(xy 342.199322 -362.284624) (xy 342.158131 -362.320316) (xy 342.112281 -362.349782) (xy 342.062705 -362.372424)
			(xy 342.01041 -362.38778) (xy 341.956463 -362.395537) (xy 341.929212 -362.396024) (xy 341.901243 -362.395556)
			(xy 341.845902 -362.3874) (xy 341.792347 -362.371247) (xy 341.741726 -362.347444) (xy 341.695126 -362.3165)
			(xy 341.653546 -362.279081) (xy 341.635334 -362.257848) (xy 341.625758 -362.247132) (xy 341.601994 -362.231)
			(xy 341.574677 -362.222124) (xy 341.545969 -362.221208) (xy 341.518142 -362.228325) (xy 341.493398 -362.24291)
			(xy 341.483188 -362.253022) (xy 341.465075 -362.271613) (xy 341.424725 -362.30426) (xy 341.38032 -362.331132)
			(xy 341.33268 -362.351734) (xy 341.282687 -362.365685) (xy 341.231264 -362.372726) (xy 341.205312 -362.373164)
			(xy 341.176395 -362.372651) (xy 341.119223 -362.363923) (xy 341.064023 -362.346664) (xy 341.012061 -362.321272)
			(xy 340.964528 -362.288327) (xy 340.922511 -362.248584) (xy 340.904322 -362.226098) (xy 340.894425 -362.214293)
			(xy 340.869101 -362.196774) (xy 340.839708 -362.187598) (xy 340.808916 -362.187598) (xy 340.779523 -362.196774)
			(xy 340.754199 -362.214293) (xy 340.744302 -362.226098) (xy 340.727549 -362.246881) (xy 340.689195 -362.284011)
			(xy 340.646041 -362.315433) (xy 340.598927 -362.340532) (xy 340.548775 -362.358818) (xy 340.496564 -362.369935)
			(xy 340.443312 -362.373665) (xy 340.39006 -362.369935) (xy 340.337849 -362.358818) (xy 340.287697 -362.340532)
			(xy 340.240583 -362.315433) (xy 340.197429 -362.284011) (xy 340.159075 -362.246881) (xy 340.142322 -362.226098)
			(xy 340.132425 -362.214293) (xy 340.107101 -362.196774) (xy 340.077708 -362.187598) (xy 340.046916 -362.187598)
			(xy 340.017523 -362.196774) (xy 339.992199 -362.214293) (xy 339.982302 -362.226098) (xy 339.964109 -362.24858)
			(xy 339.92209 -362.288315) (xy 339.874555 -362.321255) (xy 339.822594 -362.346643) (xy 339.767397 -362.3639)
			(xy 339.710228 -362.372629) (xy 339.681312 -362.373164) (xy 339.654097 -362.372702) (xy 339.600221 -362.364968)
			(xy 339.54799 -362.349654) (xy 339.498466 -362.327072) (xy 339.452655 -362.297681) (xy 339.411486 -362.262076)
			(xy 339.393276 -362.241846) (xy 339.383459 -362.231266) (xy 339.359238 -362.215595) (xy 339.331598 -362.207332)
			(xy 339.302751 -362.207139) (xy 339.275003 -362.215032) (xy 339.250575 -362.230378) (xy 339.240622 -362.24083)
			(xy 339.222462 -362.260636) (xy 339.18151 -362.295429) (xy 339.13608 -362.324127) (xy 339.08707 -362.346163)
			(xy 339.035452 -362.3611) (xy 338.982248 -362.368642) (xy 338.95538 -362.3691) (xy 338.926465 -362.368524)
			(xy 338.869297 -362.359807) (xy 338.814099 -362.342561) (xy 338.762137 -362.31718) (xy 338.714602 -362.284246)
			(xy 338.672582 -362.244515) (xy 338.65439 -362.222034) (xy 338.644493 -362.210229) (xy 338.619169 -362.19271)
			(xy 338.589776 -362.183534) (xy 338.558984 -362.183534) (xy 338.529591 -362.19271) (xy 338.504267 -362.210229)
			(xy 338.49437 -362.222034) (xy 338.476205 -362.244539) (xy 338.434178 -362.284271) (xy 338.386638 -362.317207)
			(xy 338.334672 -362.342591) (xy 338.27947 -362.359843) (xy 338.222297 -362.368567) (xy 338.19338 -362.3691)
			(xy 338.167312 -362.36863) (xy 338.115662 -362.361521) (xy 338.06546 -362.347451) (xy 338.017638 -362.326681)
			(xy 337.973087 -362.299599) (xy 337.932635 -362.266708) (xy 337.897034 -362.228618) (xy 337.866946 -362.18604)
			(xy 337.854544 -362.163106) (xy 337.847731 -362.150989) (xy 337.828764 -362.130684) (xy 337.805023 -362.116248)
			(xy 337.778267 -362.108752) (xy 337.750481 -362.108752) (xy 337.723725 -362.116248) (xy 337.699984 -362.130684)
			(xy 337.681017 -362.150989) (xy 337.674204 -362.163106) (xy 337.661804 -362.186044) (xy 337.63173 -362.228638)
			(xy 337.596136 -362.266741) (xy 337.555686 -362.299643) (xy 337.511132 -362.326731) (xy 337.463305 -362.347499)
			(xy 337.413096 -362.361562) (xy 337.361439 -362.368658) (xy 337.335368 -362.3691) (xy 337.30799 -362.368598)
			(xy 337.253798 -362.360767) (xy 337.201281 -362.345269) (xy 337.151519 -362.322425) (xy 337.105533 -362.292702)
			(xy 337.064268 -362.256711) (xy 337.046062 -362.236258) (xy 337.035978 -362.225304) (xy 337.010922 -362.209248)
			(xy 336.982304 -362.201091) (xy 336.952548 -362.201525) (xy 336.924179 -362.210513) (xy 336.899603 -362.227293)
			(xy 336.889852 -362.238544) (xy 336.871595 -362.260307) (xy 336.829807 -362.298779) (xy 336.782778 -362.330632)
			(xy 336.731546 -362.355162) (xy 336.677245 -362.371826) (xy 336.621073 -362.380257) (xy 336.592672 -362.380784)
			(xy 336.563618 -362.380272) (xy 336.50618 -362.371469) (xy 336.450742 -362.354055) (xy 336.398587 -362.328433)
			(xy 336.350922 -362.295197) (xy 336.30885 -362.255115) (xy 336.290666 -362.232448) (xy 336.281394 -362.221386)
			(xy 336.258079 -362.204404) (xy 336.230941 -362.19463) (xy 336.202152 -362.192845) (xy 336.174014 -362.199193)
			(xy 336.14878 -362.213165) (xy 336.138266 -362.22305) (xy 336.116651 -362.244093) (xy 336.067986 -362.279738)
			(xy 336.014317 -362.307277) (xy 335.956981 -362.326024) (xy 335.897409 -362.335512) (xy 335.867248 -362.33608)
			(xy 335.839995 -362.3356) (xy 335.786043 -362.327849) (xy 335.733744 -362.312497) (xy 335.684162 -362.289858)
			(xy 335.638307 -362.260393) (xy 335.597114 -362.224701) (xy 335.561419 -362.183509) (xy 335.531951 -362.137655)
			(xy 335.50931 -362.088075) (xy 335.493955 -362.035776) (xy 335.486201 -361.981825) (xy 335.48574 -361.954572)
			(xy 335.486232 -361.926969) (xy 335.494193 -361.872338) (xy 335.509943 -361.819426) (xy 335.533154 -361.769336)
			(xy 335.563343 -361.723113) (xy 335.581244 -361.702096) (xy 335.590775 -361.690438) (xy 335.603212 -361.663031)
			(xy 335.607139 -361.633191) (xy 335.602218 -361.6035) (xy 335.588874 -361.576523) (xy 335.578958 -361.56519)
			(xy 335.559564 -361.54383) (xy 335.526755 -361.496377) (xy 335.501471 -361.444522) (xy 335.484288 -361.389449)
			(xy 335.4756 -361.332416) (xy 335.475072 -361.30357) (xy 335.475072 -361.303316) (xy 335.475523 -361.275711)
			(xy 335.483492 -361.221079) (xy 335.499252 -361.168165) (xy 335.522473 -361.118076) (xy 335.55267 -361.071856)
			(xy 335.570576 -361.05084) (xy 335.580061 -361.039148) (xy 335.592499 -361.011753) (xy 335.596433 -360.981925)
			(xy 335.591524 -360.952241) (xy 335.578196 -360.925268) (xy 335.56829 -360.913934) (xy 335.548875 -360.892593)
			(xy 335.516067 -360.845135) (xy 335.490786 -360.793275) (xy 335.473609 -360.738198) (xy 335.464928 -360.681161)
			(xy 335.464404 -360.652314) (xy 335.464404 -360.65206) (xy 335.464898 -360.624457) (xy 335.472859 -360.569827)
			(xy 335.48861 -360.516915) (xy 335.511821 -360.466825) (xy 335.542007 -360.420602) (xy 335.559908 -360.399584)
			(xy 335.569445 -360.387932) (xy 335.581872 -360.360522) (xy 335.585794 -360.330682) (xy 335.580873 -360.300991)
			(xy 335.567534 -360.274013) (xy 335.557622 -360.262678) (xy 335.538216 -360.241329) (xy 335.50541 -360.193872)
			(xy 335.480129 -360.142014) (xy 335.462949 -360.086939) (xy 335.454263 -360.029904) (xy 335.453736 -360.001058)
			(xy 335.453736 -360.000804) (xy 335.454244 -359.971887) (xy 335.462973 -359.914714) (xy 335.480232 -359.859515)
			(xy 335.505626 -359.807553) (xy 335.538572 -359.760019) (xy 335.578315 -359.718003) (xy 335.600802 -359.699814)
			(xy 335.612602 -359.689911) (xy 335.630117 -359.664589) (xy 335.639292 -359.635197) (xy 335.639292 -359.604407)
			(xy 335.630119 -359.575016) (xy 335.612605 -359.549692) (xy 335.600802 -359.539794) (xy 335.580021 -359.523037)
			(xy 335.542887 -359.484686) (xy 335.511462 -359.441533) (xy 335.48636 -359.39442) (xy 335.468071 -359.344267)
			(xy 335.456953 -359.292055) (xy 335.453223 -359.238802) (xy 328.694299 -359.238802) (xy 330.843804 -362.873798)
			(xy 346.387672 -362.873798) (xy 346.391743 -362.818176) (xy 346.403869 -362.763739) (xy 346.423792 -362.711648)
			(xy 346.451088 -362.663013) (xy 346.485174 -362.61887) (xy 346.525323 -362.580161) (xy 346.570681 -362.54771)
			(xy 346.620281 -362.522209) (xy 346.673065 -362.504202) (xy 346.727908 -362.494072) (xy 346.783642 -362.492035)
			(xy 346.839079 -362.498135) (xy 346.893036 -362.512241) (xy 346.944365 -362.534053) (xy 346.991971 -362.563107)
			(xy 347.034839 -362.598782) (xy 347.057083 -362.623608) (xy 351.008948 -362.623608) (xy 351.013019 -362.567986)
			(xy 351.025145 -362.513549) (xy 351.045068 -362.461458) (xy 351.072364 -362.412823) (xy 351.10645 -362.36868)
			(xy 351.146599 -362.329971) (xy 351.191957 -362.29752) (xy 351.241557 -362.272019) (xy 351.294341 -362.254012)
			(xy 351.349184 -362.243882) (xy 351.404918 -362.241845) (xy 351.460355 -362.247945) (xy 351.514312 -362.262051)
			(xy 351.565641 -362.283863) (xy 351.613247 -362.312917) (xy 351.653899 -362.346748) (xy 353.600002 -362.346748)
			(xy 353.604073 -362.291126) (xy 353.616199 -362.236689) (xy 353.636122 -362.184598) (xy 353.663418 -362.135963)
			(xy 353.697504 -362.09182) (xy 353.737653 -362.053111) (xy 353.783011 -362.02066) (xy 353.832611 -361.995159)
			(xy 353.885395 -361.977152) (xy 353.940238 -361.967022) (xy 353.995972 -361.964985) (xy 354.051409 -361.971085)
			(xy 354.105366 -361.985191) (xy 354.156695 -362.007003) (xy 354.204301 -362.036057) (xy 354.247169 -362.071732)
			(xy 354.284386 -362.113269) (xy 354.315159 -362.159782) (xy 354.338831 -362.210279) (xy 354.354899 -362.263686)
			(xy 354.363019 -362.318862) (xy 354.363528 -362.346748) (xy 354.363019 -362.374634) (xy 354.354899 -362.42981)
			(xy 354.354824 -362.43006) (xy 358.973626 -362.43006) (xy 358.977697 -362.374438) (xy 358.989823 -362.320001)
			(xy 359.009746 -362.26791) (xy 359.037042 -362.219275) (xy 359.071128 -362.175132) (xy 359.111277 -362.136423)
			(xy 359.156635 -362.103972) (xy 359.206235 -362.078471) (xy 359.259019 -362.060464) (xy 359.313862 -362.050334)
			(xy 359.369596 -362.048297) (xy 359.425033 -362.054397) (xy 359.47899 -362.068503) (xy 359.530319 -362.090315)
			(xy 359.541381 -362.097066) (xy 376.025154 -362.097066) (xy 376.029225 -362.041444) (xy 376.041351 -361.987007)
			(xy 376.061274 -361.934916) (xy 376.08857 -361.886281) (xy 376.122656 -361.842138) (xy 376.162805 -361.803429)
			(xy 376.208163 -361.770978) (xy 376.257763 -361.745477) (xy 376.310547 -361.72747) (xy 376.36539 -361.71734)
			(xy 376.421124 -361.715303) (xy 376.476561 -361.721403) (xy 376.52724 -361.734652) (xy 382.553685 -361.734652)
			(xy 382.553685 -361.680148) (xy 382.561442 -361.6262) (xy 382.576798 -361.573905) (xy 382.59944 -361.524328)
			(xy 382.628907 -361.478477) (xy 382.6646 -361.437287) (xy 382.705792 -361.401596) (xy 382.751643 -361.372131)
			(xy 382.801222 -361.349492) (xy 382.853518 -361.334138) (xy 382.907466 -361.326384) (xy 382.934718 -361.325922)
			(xy 382.96148 -361.326343) (xy 383.014474 -361.333852) (xy 383.0659 -361.348693) (xy 383.114747 -361.370573)
			(xy 383.160058 -361.399065) (xy 383.200943 -361.433608) (xy 383.2366 -361.473525) (xy 383.26633 -361.518033)
			(xy 383.289549 -361.566259) (xy 383.305801 -361.617256) (xy 383.314768 -361.670023) (xy 383.315972 -361.696762)
			(xy 383.316841 -361.712162) (xy 383.3268 -361.741345) (xy 383.345005 -361.766232) (xy 383.369801 -361.784562)
			(xy 383.398933 -361.794667) (xy 383.429753 -361.79563) (xy 383.44475 -361.792012) (xy 383.469775 -361.785504)
			(xy 383.521005 -361.778492) (xy 383.546858 -361.778042) (xy 383.574112 -361.778495) (xy 383.628066 -361.786247)
			(xy 383.680367 -361.8016) (xy 383.72995 -361.824242) (xy 383.775806 -361.85371) (xy 383.817001 -361.889405)
			(xy 383.852695 -361.9306) (xy 383.882162 -361.976457) (xy 383.904802 -362.02604) (xy 383.920155 -362.078342)
			(xy 383.927906 -362.132296) (xy 383.928366 -362.15955) (xy 383.928112 -362.176568) (xy 383.927909 -362.191398)
			(xy 383.935129 -362.220154) (xy 383.950314 -362.245619) (xy 383.97218 -362.265641) (xy 383.998881 -362.278529)
			(xy 384.02816 -362.283195) (xy 384.04292 -362.281724) (xy 384.055371 -362.280175) (xy 384.080411 -362.278523)
			(xy 384.092958 -362.278422) (xy 384.120211 -362.278894) (xy 384.174163 -362.286646) (xy 384.226463 -362.301999)
			(xy 384.276045 -362.324639) (xy 384.3219 -362.354105) (xy 384.363094 -362.389798) (xy 384.398788 -362.430991)
			(xy 384.428256 -362.476845) (xy 384.450897 -362.526426) (xy 384.466251 -362.578725) (xy 384.474005 -362.632677)
			(xy 384.474466 -362.65993) (xy 384.474274 -362.676528) (xy 384.471345 -362.709595) (xy 384.468624 -362.72597)
			(xy 384.466495 -362.741477) (xy 384.470727 -362.772475) (xy 384.484126 -362.800745) (xy 384.505442 -362.823645)
			(xy 384.532681 -362.839034) (xy 384.547872 -362.84281) (xy 384.576032 -362.849306) (xy 384.630114 -362.869669)
			(xy 384.680507 -362.897954) (xy 384.726059 -362.933515) (xy 384.765729 -362.975538) (xy 384.798607 -363.023062)
			(xy 384.823944 -363.075) (xy 384.84116 -363.130165) (xy 384.84986 -363.187295) (xy 384.850386 -363.21619)
			(xy 384.850207 -363.233753) (xy 384.84703 -363.268734) (xy 384.844036 -363.28604) (xy 384.841779 -363.301008)
			(xy 384.845177 -363.331074) (xy 384.857239 -363.358822) (xy 384.876904 -363.381817) (xy 384.902446 -363.398037)
			(xy 384.93162 -363.406059) (xy 384.961864 -363.405177) (xy 384.97637 -363.400848) (xy 385.005916 -363.391507)
			(xy 385.067055 -363.381427) (xy 385.098036 -363.380782) (xy 385.098798 -363.380782) (xy 385.126051 -363.381253)
			(xy 385.180003 -363.38901) (xy 385.232301 -363.404366) (xy 385.281882 -363.427009) (xy 385.327736 -363.456477)
			(xy 385.368929 -363.492171) (xy 385.404623 -363.533364) (xy 385.434091 -363.579218) (xy 385.456734 -363.628799)
			(xy 385.47209 -363.681097) (xy 385.479847 -363.735049) (xy 385.479847 -363.789555) (xy 385.472089 -363.843507)
			(xy 385.456733 -363.895805) (xy 385.434089 -363.945386) (xy 385.404621 -363.991239) (xy 385.368926 -364.032432)
			(xy 385.327733 -364.068125) (xy 385.281879 -364.097593) (xy 385.232298 -364.120235) (xy 385.179999 -364.135591)
			(xy 385.126047 -364.143347) (xy 385.071541 -364.143346) (xy 385.017589 -364.135588) (xy 384.965291 -364.120231)
			(xy 384.915711 -364.097587) (xy 384.869858 -364.068118) (xy 384.828665 -364.032423) (xy 384.792972 -363.991229)
			(xy 384.763505 -363.945375) (xy 384.740863 -363.895794) (xy 384.725508 -363.843495) (xy 384.717753 -363.789543)
			(xy 384.71729 -363.76229) (xy 384.717465 -363.744727) (xy 384.720645 -363.709746) (xy 384.72364 -363.69244)
			(xy 384.725817 -363.677466) (xy 384.722415 -363.647418) (xy 384.71036 -363.619686) (xy 384.690709 -363.596702)
			(xy 384.665187 -363.580483) (xy 384.636034 -363.572453) (xy 384.605807 -363.573315) (xy 384.591306 -363.577632)
			(xy 384.561761 -363.586978) (xy 384.500621 -363.597055) (xy 384.46964 -363.597698) (xy 384.468878 -363.597698)
			(xy 384.441626 -363.597243) (xy 384.387676 -363.589483) (xy 384.33538 -363.574124) (xy 384.285803 -363.55148)
			(xy 384.239952 -363.522011) (xy 384.198762 -363.486316) (xy 384.16307 -363.445123) (xy 384.133605 -363.399269)
			(xy 384.110964 -363.349689) (xy 384.09561 -363.297392) (xy 384.087855 -363.243442) (xy 384.08737 -363.21619)
			(xy 384.087564 -363.199592) (xy 384.090491 -363.166525) (xy 384.093212 -363.15015) (xy 384.095292 -363.134639)
			(xy 384.091067 -363.103649) (xy 384.077678 -363.075384) (xy 384.056375 -363.052484) (xy 384.029149 -363.037091)
			(xy 384.013964 -363.03331) (xy 383.985798 -363.026841) (xy 383.931718 -363.00647) (xy 383.881327 -362.978179)
			(xy 383.835777 -362.942614) (xy 383.79611 -362.900588) (xy 383.763232 -362.853061) (xy 383.737895 -362.801122)
			(xy 383.720679 -362.745956) (xy 383.711977 -362.688825) (xy 383.71145 -362.65993) (xy 383.711704 -362.642912)
			(xy 383.711907 -362.628082) (xy 383.704683 -362.599329) (xy 383.689497 -362.573866) (xy 383.667631 -362.553845)
			(xy 383.640933 -362.540956) (xy 383.611655 -362.536288) (xy 383.596896 -362.537756) (xy 383.584444 -362.539304)
			(xy 383.559405 -362.540956) (xy 383.546858 -362.541058) (xy 383.520097 -362.540586) (xy 383.467103 -362.533086)
			(xy 383.415678 -362.518254) (xy 383.36683 -362.496381) (xy 383.321518 -362.467896) (xy 383.280631 -362.433357)
			(xy 383.244973 -362.393444) (xy 383.215243 -362.348939) (xy 383.192024 -362.300716) (xy 383.175772 -362.249721)
			(xy 383.166806 -362.196956) (xy 383.165604 -362.170218) (xy 383.164656 -362.154828) (xy 383.154702 -362.125661)
			(xy 383.13651 -362.100785) (xy 383.111733 -362.082457) (xy 383.08262 -362.072344) (xy 383.051817 -362.071363)
			(xy 383.036826 -362.074968) (xy 383.011802 -362.08148) (xy 382.960572 -362.08849) (xy 382.934718 -362.088938)
			(xy 382.907466 -362.088416) (xy 382.853518 -362.080662) (xy 382.801222 -362.065308) (xy 382.751643 -362.042669)
			(xy 382.705792 -362.013204) (xy 382.6646 -361.977513) (xy 382.628907 -361.936323) (xy 382.59944 -361.890472)
			(xy 382.576798 -361.840895) (xy 382.561442 -361.7886) (xy 382.553685 -361.734652) (xy 376.52724 -361.734652)
			(xy 376.530518 -361.735509) (xy 376.581847 -361.757321) (xy 376.629453 -361.786375) (xy 376.672321 -361.82205)
			(xy 376.709538 -361.863587) (xy 376.740311 -361.9101) (xy 376.763983 -361.960597) (xy 376.780051 -362.014004)
			(xy 376.788171 -362.06918) (xy 376.78868 -362.097066) (xy 376.788171 -362.124952) (xy 376.780051 -362.180128)
			(xy 376.763983 -362.233535) (xy 376.740311 -362.284032) (xy 376.709538 -362.330545) (xy 376.672321 -362.372082)
			(xy 376.629453 -362.407757) (xy 376.581847 -362.436811) (xy 376.530518 -362.458623) (xy 376.476561 -362.472729)
			(xy 376.421124 -362.478829) (xy 376.36539 -362.476792) (xy 376.310547 -362.466662) (xy 376.257763 -362.448655)
			(xy 376.208163 -362.423154) (xy 376.162805 -362.390703) (xy 376.122656 -362.351994) (xy 376.08857 -362.307851)
			(xy 376.061274 -362.259216) (xy 376.041351 -362.207125) (xy 376.029225 -362.152688) (xy 376.025154 -362.097066)
			(xy 359.541381 -362.097066) (xy 359.577925 -362.119369) (xy 359.620793 -362.155044) (xy 359.65801 -362.196581)
			(xy 359.688783 -362.243094) (xy 359.712455 -362.293591) (xy 359.728523 -362.346998) (xy 359.736643 -362.402174)
			(xy 359.737152 -362.43006) (xy 359.736643 -362.457946) (xy 359.728523 -362.513122) (xy 359.712455 -362.566529)
			(xy 359.688783 -362.617026) (xy 359.65801 -362.663539) (xy 359.620793 -362.705076) (xy 359.577925 -362.740751)
			(xy 359.530319 -362.769805) (xy 359.47899 -362.791617) (xy 359.425033 -362.805723) (xy 359.369596 -362.811823)
			(xy 359.313862 -362.809786) (xy 359.259019 -362.799656) (xy 359.206235 -362.781649) (xy 359.156635 -362.756148)
			(xy 359.111277 -362.723697) (xy 359.071128 -362.684988) (xy 359.037042 -362.640845) (xy 359.009746 -362.59221)
			(xy 358.989823 -362.540119) (xy 358.977697 -362.485682) (xy 358.973626 -362.43006) (xy 354.354824 -362.43006)
			(xy 354.338831 -362.483217) (xy 354.315159 -362.533714) (xy 354.284386 -362.580227) (xy 354.247169 -362.621764)
			(xy 354.204301 -362.657439) (xy 354.156695 -362.686493) (xy 354.105366 -362.708305) (xy 354.051409 -362.722411)
			(xy 353.995972 -362.728511) (xy 353.940238 -362.726474) (xy 353.885395 -362.716344) (xy 353.832611 -362.698337)
			(xy 353.783011 -362.672836) (xy 353.737653 -362.640385) (xy 353.697504 -362.601676) (xy 353.663418 -362.557533)
			(xy 353.636122 -362.508898) (xy 353.616199 -362.456807) (xy 353.604073 -362.40237) (xy 353.600002 -362.346748)
			(xy 351.653899 -362.346748) (xy 351.656115 -362.348592) (xy 351.693332 -362.390129) (xy 351.724105 -362.436642)
			(xy 351.747777 -362.487139) (xy 351.763845 -362.540546) (xy 351.771965 -362.595722) (xy 351.772474 -362.623608)
			(xy 351.771965 -362.651494) (xy 351.763845 -362.70667) (xy 351.747777 -362.760077) (xy 351.724105 -362.810574)
			(xy 351.693332 -362.857087) (xy 351.656115 -362.898624) (xy 351.613247 -362.934299) (xy 351.565641 -362.963353)
			(xy 351.514312 -362.985165) (xy 351.460355 -362.999271) (xy 351.404918 -363.005371) (xy 351.349184 -363.003334)
			(xy 351.294341 -362.993204) (xy 351.241557 -362.975197) (xy 351.191957 -362.949696) (xy 351.146599 -362.917245)
			(xy 351.10645 -362.878536) (xy 351.072364 -362.834393) (xy 351.045068 -362.785758) (xy 351.025145 -362.733667)
			(xy 351.013019 -362.67923) (xy 351.008948 -362.623608) (xy 347.057083 -362.623608) (xy 347.072056 -362.640319)
			(xy 347.102829 -362.686832) (xy 347.126501 -362.737329) (xy 347.142569 -362.790736) (xy 347.150689 -362.845912)
			(xy 347.151198 -362.873798) (xy 347.150689 -362.901684) (xy 347.142569 -362.95686) (xy 347.126501 -363.010267)
			(xy 347.102829 -363.060764) (xy 347.072056 -363.107277) (xy 347.034839 -363.148814) (xy 346.991971 -363.184489)
			(xy 346.944365 -363.213543) (xy 346.893036 -363.235355) (xy 346.839079 -363.249461) (xy 346.783642 -363.255561)
			(xy 346.727908 -363.253524) (xy 346.673065 -363.243394) (xy 346.620281 -363.225387) (xy 346.570681 -363.199886)
			(xy 346.525323 -363.167435) (xy 346.485174 -363.128726) (xy 346.451088 -363.084583) (xy 346.423792 -363.035948)
			(xy 346.403869 -362.983857) (xy 346.391743 -362.92942) (xy 346.387672 -362.873798) (xy 330.843804 -362.873798)
			(xy 331.269619 -363.593888) (xy 346.993462 -363.593888) (xy 346.997533 -363.538266) (xy 347.009659 -363.483829)
			(xy 347.029582 -363.431738) (xy 347.056878 -363.383103) (xy 347.090964 -363.33896) (xy 347.131113 -363.300251)
			(xy 347.176471 -363.2678) (xy 347.226071 -363.242299) (xy 347.278855 -363.224292) (xy 347.333698 -363.214162)
			(xy 347.389432 -363.212125) (xy 347.444869 -363.218225) (xy 347.498826 -363.232331) (xy 347.550155 -363.254143)
			(xy 347.597761 -363.283197) (xy 347.640629 -363.318872) (xy 347.677846 -363.360409) (xy 347.708619 -363.406922)
			(xy 347.732291 -363.457419) (xy 347.748359 -363.510826) (xy 347.756479 -363.566002) (xy 347.756988 -363.593888)
			(xy 347.756479 -363.621774) (xy 347.754116 -363.63783) (xy 352.31146 -363.63783) (xy 352.315531 -363.582208)
			(xy 352.327657 -363.527771) (xy 352.34758 -363.47568) (xy 352.374876 -363.427045) (xy 352.408962 -363.382902)
			(xy 352.449111 -363.344193) (xy 352.494469 -363.311742) (xy 352.544069 -363.286241) (xy 352.596853 -363.268234)
			(xy 352.651696 -363.258104) (xy 352.70743 -363.256067) (xy 352.762867 -363.262167) (xy 352.816824 -363.276273)
			(xy 352.820083 -363.277658) (xy 354.17836 -363.277658) (xy 354.182431 -363.222036) (xy 354.194557 -363.167599)
			(xy 354.21448 -363.115508) (xy 354.241776 -363.066873) (xy 354.275862 -363.02273) (xy 354.316011 -362.984021)
			(xy 354.361369 -362.95157) (xy 354.410969 -362.926069) (xy 354.463753 -362.908062) (xy 354.518596 -362.897932)
			(xy 354.57433 -362.895895) (xy 354.629767 -362.901995) (xy 354.683724 -362.916101) (xy 354.735053 -362.937913)
			(xy 354.782659 -362.966967) (xy 354.825527 -363.002642) (xy 354.862744 -363.044179) (xy 354.893517 -363.090692)
			(xy 354.917189 -363.141189) (xy 354.933257 -363.194596) (xy 354.941377 -363.249772) (xy 354.941886 -363.277658)
			(xy 354.941377 -363.305544) (xy 354.933257 -363.36072) (xy 354.92875 -363.375702) (xy 357.676702 -363.375702)
			(xy 357.680773 -363.32008) (xy 357.692899 -363.265643) (xy 357.712822 -363.213552) (xy 357.740118 -363.164917)
			(xy 357.774204 -363.120774) (xy 357.814353 -363.082065) (xy 357.859711 -363.049614) (xy 357.909311 -363.024113)
			(xy 357.962095 -363.006106) (xy 358.016938 -362.995976) (xy 358.072672 -362.993939) (xy 358.128109 -363.000039)
			(xy 358.182066 -363.014145) (xy 358.233395 -363.035957) (xy 358.281001 -363.065011) (xy 358.323869 -363.100686)
			(xy 358.361086 -363.142223) (xy 358.391859 -363.188736) (xy 358.415531 -363.239233) (xy 358.431599 -363.29264)
			(xy 358.436422 -363.32541) (xy 360.662472 -363.32541) (xy 360.666543 -363.269788) (xy 360.678669 -363.215351)
			(xy 360.698592 -363.16326) (xy 360.725888 -363.114625) (xy 360.759974 -363.070482) (xy 360.800123 -363.031773)
			(xy 360.845481 -362.999322) (xy 360.895081 -362.973821) (xy 360.947865 -362.955814) (xy 361.002708 -362.945684)
			(xy 361.058442 -362.943647) (xy 361.113879 -362.949747) (xy 361.167836 -362.963853) (xy 361.219165 -362.985665)
			(xy 361.266771 -363.014719) (xy 361.271713 -363.018832) (xy 363.790482 -363.018832) (xy 363.794553 -362.96321)
			(xy 363.806679 -362.908773) (xy 363.826602 -362.856682) (xy 363.853898 -362.808047) (xy 363.887984 -362.763904)
			(xy 363.928133 -362.725195) (xy 363.973491 -362.692744) (xy 364.023091 -362.667243) (xy 364.075875 -362.649236)
			(xy 364.130718 -362.639106) (xy 364.186452 -362.637069) (xy 364.241889 -362.643169) (xy 364.295846 -362.657275)
			(xy 364.347175 -362.679087) (xy 364.394781 -362.708141) (xy 364.437649 -362.743816) (xy 364.474866 -362.785353)
			(xy 364.505639 -362.831866) (xy 364.529311 -362.882363) (xy 364.545379 -362.93577) (xy 364.553499 -362.990946)
			(xy 364.554008 -363.018832) (xy 364.553499 -363.046718) (xy 364.545379 -363.101894) (xy 364.529311 -363.155301)
			(xy 364.505639 -363.205798) (xy 364.474866 -363.252311) (xy 364.437649 -363.293848) (xy 364.394781 -363.329523)
			(xy 364.347175 -363.358577) (xy 364.295846 -363.380389) (xy 364.241889 -363.394495) (xy 364.186452 -363.400595)
			(xy 364.130718 -363.398558) (xy 364.075875 -363.388428) (xy 364.023091 -363.370421) (xy 363.973491 -363.34492)
			(xy 363.928133 -363.312469) (xy 363.887984 -363.27376) (xy 363.853898 -363.229617) (xy 363.826602 -363.180982)
			(xy 363.806679 -363.128891) (xy 363.794553 -363.074454) (xy 363.790482 -363.018832) (xy 361.271713 -363.018832)
			(xy 361.309639 -363.050394) (xy 361.346856 -363.091931) (xy 361.377629 -363.138444) (xy 361.401301 -363.188941)
			(xy 361.417369 -363.242348) (xy 361.425489 -363.297524) (xy 361.425998 -363.32541) (xy 361.425489 -363.353296)
			(xy 361.417369 -363.408472) (xy 361.401301 -363.461879) (xy 361.377629 -363.512376) (xy 361.346856 -363.558889)
			(xy 361.309639 -363.600426) (xy 361.266771 -363.636101) (xy 361.219165 -363.665155) (xy 361.167836 -363.686967)
			(xy 361.113879 -363.701073) (xy 361.058442 -363.707173) (xy 361.002708 -363.705136) (xy 360.947865 -363.695006)
			(xy 360.895081 -363.676999) (xy 360.845481 -363.651498) (xy 360.800123 -363.619047) (xy 360.759974 -363.580338)
			(xy 360.725888 -363.536195) (xy 360.698592 -363.48756) (xy 360.678669 -363.435469) (xy 360.666543 -363.381032)
			(xy 360.662472 -363.32541) (xy 358.436422 -363.32541) (xy 358.439719 -363.347816) (xy 358.440228 -363.375702)
			(xy 358.439719 -363.403588) (xy 358.431599 -363.458764) (xy 358.415531 -363.512171) (xy 358.391859 -363.562668)
			(xy 358.361086 -363.609181) (xy 358.323869 -363.650718) (xy 358.281001 -363.686393) (xy 358.233395 -363.715447)
			(xy 358.182066 -363.737259) (xy 358.128109 -363.751365) (xy 358.072672 -363.757465) (xy 358.016938 -363.755428)
			(xy 357.962095 -363.745298) (xy 357.909311 -363.727291) (xy 357.859711 -363.70179) (xy 357.814353 -363.669339)
			(xy 357.774204 -363.63063) (xy 357.740118 -363.586487) (xy 357.712822 -363.537852) (xy 357.692899 -363.485761)
			(xy 357.680773 -363.431324) (xy 357.676702 -363.375702) (xy 354.92875 -363.375702) (xy 354.917189 -363.414127)
			(xy 354.893517 -363.464624) (xy 354.862744 -363.511137) (xy 354.825527 -363.552674) (xy 354.782659 -363.588349)
			(xy 354.735053 -363.617403) (xy 354.683724 -363.639215) (xy 354.629767 -363.653321) (xy 354.57433 -363.659421)
			(xy 354.518596 -363.657384) (xy 354.463753 -363.647254) (xy 354.410969 -363.629247) (xy 354.361369 -363.603746)
			(xy 354.316011 -363.571295) (xy 354.275862 -363.532586) (xy 354.241776 -363.488443) (xy 354.21448 -363.439808)
			(xy 354.194557 -363.387717) (xy 354.182431 -363.33328) (xy 354.17836 -363.277658) (xy 352.820083 -363.277658)
			(xy 352.868153 -363.298085) (xy 352.915759 -363.327139) (xy 352.958627 -363.362814) (xy 352.995844 -363.404351)
			(xy 353.026617 -363.450864) (xy 353.050289 -363.501361) (xy 353.066357 -363.554768) (xy 353.074477 -363.609944)
			(xy 353.074986 -363.63783) (xy 353.074477 -363.665716) (xy 353.066357 -363.720892) (xy 353.050289 -363.774299)
			(xy 353.026617 -363.824796) (xy 352.995844 -363.871309) (xy 352.958627 -363.912846) (xy 352.915759 -363.948521)
			(xy 352.868153 -363.977575) (xy 352.816824 -363.999387) (xy 352.762867 -364.013493) (xy 352.70743 -364.019593)
			(xy 352.651696 -364.017556) (xy 352.596853 -364.007426) (xy 352.544069 -363.989419) (xy 352.494469 -363.963918)
			(xy 352.449111 -363.931467) (xy 352.408962 -363.892758) (xy 352.374876 -363.848615) (xy 352.34758 -363.79998)
			(xy 352.327657 -363.747889) (xy 352.315531 -363.693452) (xy 352.31146 -363.63783) (xy 347.754116 -363.63783)
			(xy 347.748359 -363.67695) (xy 347.732291 -363.730357) (xy 347.708619 -363.780854) (xy 347.677846 -363.827367)
			(xy 347.640629 -363.868904) (xy 347.597761 -363.904579) (xy 347.550155 -363.933633) (xy 347.498826 -363.955445)
			(xy 347.444869 -363.969551) (xy 347.389432 -363.975651) (xy 347.333698 -363.973614) (xy 347.278855 -363.963484)
			(xy 347.226071 -363.945477) (xy 347.176471 -363.919976) (xy 347.131113 -363.887525) (xy 347.090964 -363.848816)
			(xy 347.056878 -363.804673) (xy 347.029582 -363.756038) (xy 347.009659 -363.703947) (xy 346.997533 -363.64951)
			(xy 346.993462 -363.593888) (xy 331.269619 -363.593888) (xy 331.606516 -364.16361) (xy 347.661482 -364.16361)
			(xy 347.665553 -364.107988) (xy 347.677679 -364.053551) (xy 347.697602 -364.00146) (xy 347.724898 -363.952825)
			(xy 347.758984 -363.908682) (xy 347.799133 -363.869973) (xy 347.844491 -363.837522) (xy 347.894091 -363.812021)
			(xy 347.946875 -363.794014) (xy 348.001718 -363.783884) (xy 348.057452 -363.781847) (xy 348.112889 -363.787947)
			(xy 348.166846 -363.802053) (xy 348.218175 -363.823865) (xy 348.265781 -363.852919) (xy 348.308649 -363.888594)
			(xy 348.345866 -363.930131) (xy 348.376639 -363.976644) (xy 348.400311 -364.027141) (xy 348.416379 -364.080548)
			(xy 348.424499 -364.135724) (xy 348.425008 -364.16361) (xy 348.424499 -364.191496) (xy 348.416379 -364.246672)
			(xy 348.400311 -364.300079) (xy 348.376639 -364.350576) (xy 348.345866 -364.397089) (xy 348.330893 -364.4138)
			(xy 354.060504 -364.4138) (xy 354.064575 -364.358178) (xy 354.076701 -364.303741) (xy 354.096624 -364.25165)
			(xy 354.12392 -364.203015) (xy 354.158006 -364.158872) (xy 354.198155 -364.120163) (xy 354.243513 -364.087712)
			(xy 354.293113 -364.062211) (xy 354.345897 -364.044204) (xy 354.40074 -364.034074) (xy 354.456474 -364.032037)
			(xy 354.511911 -364.038137) (xy 354.565868 -364.052243) (xy 354.617197 -364.074055) (xy 354.664803 -364.103109)
			(xy 354.707671 -364.138784) (xy 354.744888 -364.180321) (xy 354.775661 -364.226834) (xy 354.799333 -364.277331)
			(xy 354.815401 -364.330738) (xy 354.823521 -364.385914) (xy 354.823529 -364.386368) (xy 355.566216 -364.386368)
			(xy 355.570287 -364.330746) (xy 355.582413 -364.276309) (xy 355.602336 -364.224218) (xy 355.629632 -364.175583)
			(xy 355.663718 -364.13144) (xy 355.703867 -364.092731) (xy 355.749225 -364.06028) (xy 355.798825 -364.034779)
			(xy 355.851609 -364.016772) (xy 355.906452 -364.006642) (xy 355.962186 -364.004605) (xy 356.017623 -364.010705)
			(xy 356.07158 -364.024811) (xy 356.122909 -364.046623) (xy 356.170515 -364.075677) (xy 356.213383 -364.111352)
			(xy 356.2506 -364.152889) (xy 356.281373 -364.199402) (xy 356.305045 -364.249899) (xy 356.321113 -364.303306)
			(xy 356.329233 -364.358482) (xy 356.329742 -364.386368) (xy 356.32938 -364.40618) (xy 357.767634 -364.40618)
			(xy 357.771705 -364.350558) (xy 357.783831 -364.296121) (xy 357.803754 -364.24403) (xy 357.83105 -364.195395)
			(xy 357.865136 -364.151252) (xy 357.905285 -364.112543) (xy 357.950643 -364.080092) (xy 358.000243 -364.054591)
			(xy 358.053027 -364.036584) (xy 358.10787 -364.026454) (xy 358.163604 -364.024417) (xy 358.219041 -364.030517)
			(xy 358.272998 -364.044623) (xy 358.324327 -364.066435) (xy 358.371933 -364.095489) (xy 358.414801 -364.131164)
			(xy 358.452018 -364.172701) (xy 358.482791 -364.219214) (xy 358.484587 -364.223046) (xy 359.35107 -364.223046)
			(xy 359.355141 -364.167424) (xy 359.367267 -364.112987) (xy 359.38719 -364.060896) (xy 359.414486 -364.012261)
			(xy 359.448572 -363.968118) (xy 359.488721 -363.929409) (xy 359.534079 -363.896958) (xy 359.583679 -363.871457)
			(xy 359.636463 -363.85345) (xy 359.691306 -363.84332) (xy 359.74704 -363.841283) (xy 359.802477 -363.847383)
			(xy 359.856434 -363.861489) (xy 359.907763 -363.883301) (xy 359.955369 -363.912355) (xy 359.998237 -363.94803)
			(xy 360.035454 -363.989567) (xy 360.066227 -364.03608) (xy 360.089899 -364.086577) (xy 360.105967 -364.139984)
			(xy 360.114087 -364.19516) (xy 360.114137 -364.1979) (xy 361.549948 -364.1979) (xy 361.554021 -364.142241)
			(xy 361.566156 -364.087768) (xy 361.586092 -364.035642) (xy 361.613406 -363.986974) (xy 361.647514 -363.942802)
			(xy 361.687691 -363.904067) (xy 361.733079 -363.871595) (xy 361.782711 -363.846077) (xy 361.835531 -363.828058)
			(xy 361.89041 -363.817921) (xy 361.946181 -363.815883) (xy 362.001655 -363.821986) (xy 362.055648 -363.836102)
			(xy 362.107011 -363.857929) (xy 362.15382 -363.886496) (xy 366.311686 -363.886496) (xy 366.315757 -363.830874)
			(xy 366.327883 -363.776437) (xy 366.347806 -363.724346) (xy 366.375102 -363.675711) (xy 366.409188 -363.631568)
			(xy 366.449337 -363.592859) (xy 366.494695 -363.560408) (xy 366.544295 -363.534907) (xy 366.597079 -363.5169)
			(xy 366.651922 -363.50677) (xy 366.707656 -363.504733) (xy 366.763093 -363.510833) (xy 366.81705 -363.524939)
			(xy 366.868379 -363.546751) (xy 366.915985 -363.575805) (xy 366.958853 -363.61148) (xy 366.99607 -363.653017)
			(xy 367.026843 -363.69953) (xy 367.050515 -363.750027) (xy 367.066583 -363.803434) (xy 367.074703 -363.85861)
			(xy 367.075212 -363.886496) (xy 367.074703 -363.914382) (xy 367.066583 -363.969558) (xy 367.050515 -364.022965)
			(xy 367.026843 -364.073462) (xy 366.99607 -364.119975) (xy 366.958853 -364.161512) (xy 366.915985 -364.197187)
			(xy 366.868379 -364.226241) (xy 366.81705 -364.248053) (xy 366.763093 -364.262159) (xy 366.707656 -364.268259)
			(xy 366.651922 -364.266222) (xy 366.597079 -364.256092) (xy 366.544295 -364.238085) (xy 366.494695 -364.212584)
			(xy 366.449337 -364.180133) (xy 366.409188 -364.141424) (xy 366.375102 -364.097281) (xy 366.347806 -364.048646)
			(xy 366.327883 -363.996555) (xy 366.315757 -363.942118) (xy 366.311686 -363.886496) (xy 362.15382 -363.886496)
			(xy 362.154649 -363.887002) (xy 362.197545 -363.922701) (xy 362.234787 -363.964265) (xy 362.265581 -364.010809)
			(xy 362.289269 -364.06134) (xy 362.305347 -364.114782) (xy 362.313473 -364.169996) (xy 362.313982 -364.1979)
			(xy 362.313473 -364.225804) (xy 362.305347 -364.281018) (xy 362.289269 -364.33446) (xy 362.265581 -364.384991)
			(xy 362.234787 -364.431535) (xy 362.197545 -364.473099) (xy 362.154649 -364.508798) (xy 362.107011 -364.537871)
			(xy 362.055648 -364.559698) (xy 362.001655 -364.573814) (xy 361.946181 -364.579917) (xy 361.89041 -364.577879)
			(xy 361.835531 -364.567742) (xy 361.782711 -364.549723) (xy 361.733079 -364.524205) (xy 361.687691 -364.491733)
			(xy 361.647514 -364.452998) (xy 361.613406 -364.408826) (xy 361.586092 -364.360158) (xy 361.566156 -364.308032)
			(xy 361.554021 -364.253559) (xy 361.549948 -364.1979) (xy 360.114137 -364.1979) (xy 360.114596 -364.223046)
			(xy 360.114087 -364.250932) (xy 360.105967 -364.306108) (xy 360.089899 -364.359515) (xy 360.066227 -364.410012)
			(xy 360.035454 -364.456525) (xy 359.998237 -364.498062) (xy 359.955369 -364.533737) (xy 359.907763 -364.562791)
			(xy 359.856434 -364.584603) (xy 359.802477 -364.598709) (xy 359.74704 -364.604809) (xy 359.691306 -364.602772)
			(xy 359.636463 -364.592642) (xy 359.583679 -364.574635) (xy 359.534079 -364.549134) (xy 359.488721 -364.516683)
			(xy 359.448572 -364.477974) (xy 359.414486 -364.433831) (xy 359.38719 -364.385196) (xy 359.367267 -364.333105)
			(xy 359.355141 -364.278668) (xy 359.35107 -364.223046) (xy 358.484587 -364.223046) (xy 358.506463 -364.269711)
			(xy 358.522531 -364.323118) (xy 358.530651 -364.378294) (xy 358.53116 -364.40618) (xy 358.530651 -364.434066)
			(xy 358.522531 -364.489242) (xy 358.506463 -364.542649) (xy 358.482791 -364.593146) (xy 358.452018 -364.639659)
			(xy 358.414801 -364.681196) (xy 358.371933 -364.716871) (xy 358.324327 -364.745925) (xy 358.272998 -364.767737)
			(xy 358.219041 -364.781843) (xy 358.163604 -364.787943) (xy 358.10787 -364.785906) (xy 358.053027 -364.775776)
			(xy 358.000243 -364.757769) (xy 357.950643 -364.732268) (xy 357.905285 -364.699817) (xy 357.865136 -364.661108)
			(xy 357.83105 -364.616965) (xy 357.803754 -364.56833) (xy 357.783831 -364.516239) (xy 357.771705 -364.461802)
			(xy 357.767634 -364.40618) (xy 356.32938 -364.40618) (xy 356.329233 -364.414254) (xy 356.321113 -364.46943)
			(xy 356.305045 -364.522837) (xy 356.281373 -364.573334) (xy 356.2506 -364.619847) (xy 356.213383 -364.661384)
			(xy 356.170515 -364.697059) (xy 356.122909 -364.726113) (xy 356.07158 -364.747925) (xy 356.017623 -364.762031)
			(xy 355.962186 -364.768131) (xy 355.906452 -364.766094) (xy 355.851609 -364.755964) (xy 355.798825 -364.737957)
			(xy 355.749225 -364.712456) (xy 355.703867 -364.680005) (xy 355.663718 -364.641296) (xy 355.629632 -364.597153)
			(xy 355.602336 -364.548518) (xy 355.582413 -364.496427) (xy 355.570287 -364.44199) (xy 355.566216 -364.386368)
			(xy 354.823529 -364.386368) (xy 354.82403 -364.4138) (xy 354.823521 -364.441686) (xy 354.815401 -364.496862)
			(xy 354.799333 -364.550269) (xy 354.775661 -364.600766) (xy 354.744888 -364.647279) (xy 354.707671 -364.688816)
			(xy 354.664803 -364.724491) (xy 354.617197 -364.753545) (xy 354.565868 -364.775357) (xy 354.511911 -364.789463)
			(xy 354.456474 -364.795563) (xy 354.40074 -364.793526) (xy 354.345897 -364.783396) (xy 354.293113 -364.765389)
			(xy 354.243513 -364.739888) (xy 354.198155 -364.707437) (xy 354.158006 -364.668728) (xy 354.12392 -364.624585)
			(xy 354.096624 -364.57595) (xy 354.076701 -364.523859) (xy 354.064575 -364.469422) (xy 354.060504 -364.4138)
			(xy 348.330893 -364.4138) (xy 348.308649 -364.438626) (xy 348.265781 -364.474301) (xy 348.218175 -364.503355)
			(xy 348.166846 -364.525167) (xy 348.112889 -364.539273) (xy 348.057452 -364.545373) (xy 348.001718 -364.543336)
			(xy 347.946875 -364.533206) (xy 347.894091 -364.515199) (xy 347.844491 -364.489698) (xy 347.799133 -364.457247)
			(xy 347.758984 -364.418538) (xy 347.724898 -364.374395) (xy 347.697602 -364.32576) (xy 347.677679 -364.273669)
			(xy 347.665553 -364.219232) (xy 347.661482 -364.16361) (xy 331.606516 -364.16361) (xy 332.229093 -365.21644)
			(xy 354.854508 -365.21644) (xy 354.858579 -365.160818) (xy 354.870705 -365.106381) (xy 354.890628 -365.05429)
			(xy 354.917924 -365.005655) (xy 354.95201 -364.961512) (xy 354.992159 -364.922803) (xy 355.037517 -364.890352)
			(xy 355.087117 -364.864851) (xy 355.139901 -364.846844) (xy 355.194744 -364.836714) (xy 355.250478 -364.834677)
			(xy 355.305915 -364.840777) (xy 355.359872 -364.854883) (xy 355.411201 -364.876695) (xy 355.458807 -364.905749)
			(xy 355.50068 -364.940596) (xy 358.631742 -364.940596) (xy 358.635813 -364.884974) (xy 358.647939 -364.830537)
			(xy 358.667862 -364.778446) (xy 358.695158 -364.729811) (xy 358.729244 -364.685668) (xy 358.769393 -364.646959)
			(xy 358.814751 -364.614508) (xy 358.864351 -364.589007) (xy 358.917135 -364.571) (xy 358.971978 -364.56087)
			(xy 359.027712 -364.558833) (xy 359.083149 -364.564933) (xy 359.137106 -364.579039) (xy 359.188435 -364.600851)
			(xy 359.236041 -364.629905) (xy 359.278909 -364.66558) (xy 359.316126 -364.707117) (xy 359.329101 -364.726728)
			(xy 360.233466 -364.726728) (xy 360.237537 -364.671106) (xy 360.249663 -364.616669) (xy 360.269586 -364.564578)
			(xy 360.296882 -364.515943) (xy 360.330968 -364.4718) (xy 360.371117 -364.433091) (xy 360.416475 -364.40064)
			(xy 360.466075 -364.375139) (xy 360.518859 -364.357132) (xy 360.573702 -364.347002) (xy 360.629436 -364.344965)
			(xy 360.684873 -364.351065) (xy 360.73883 -364.365171) (xy 360.790159 -364.386983) (xy 360.837765 -364.416037)
			(xy 360.880633 -364.451712) (xy 360.91785 -364.493249) (xy 360.948623 -364.539762) (xy 360.972295 -364.590259)
			(xy 360.988363 -364.643666) (xy 360.996483 -364.698842) (xy 360.996992 -364.726728) (xy 360.996483 -364.754614)
			(xy 360.988363 -364.80979) (xy 360.972295 -364.863197) (xy 360.948623 -364.913694) (xy 360.91785 -364.960207)
			(xy 360.901284 -364.978696) (xy 365.31245 -364.978696) (xy 365.316521 -364.923074) (xy 365.328647 -364.868637)
			(xy 365.34857 -364.816546) (xy 365.375866 -364.767911) (xy 365.409952 -364.723768) (xy 365.450101 -364.685059)
			(xy 365.495459 -364.652608) (xy 365.545059 -364.627107) (xy 365.597843 -364.6091) (xy 365.652686 -364.59897)
			(xy 365.70842 -364.596933) (xy 365.763857 -364.603033) (xy 365.817814 -364.617139) (xy 365.869143 -364.638951)
			(xy 365.916749 -364.668005) (xy 365.959617 -364.70368) (xy 365.996834 -364.745217) (xy 366.027607 -364.79173)
			(xy 366.051279 -364.842227) (xy 366.067347 -364.895634) (xy 366.075467 -364.95081) (xy 366.075976 -364.978696)
			(xy 366.075467 -365.006582) (xy 366.067347 -365.061758) (xy 366.051279 -365.115165) (xy 366.027607 -365.165662)
			(xy 365.996834 -365.212175) (xy 365.959617 -365.253712) (xy 365.916749 -365.289387) (xy 365.869143 -365.318441)
			(xy 365.817814 -365.340253) (xy 365.763857 -365.354359) (xy 365.70842 -365.360459) (xy 365.652686 -365.358422)
			(xy 365.597843 -365.348292) (xy 365.545059 -365.330285) (xy 365.495459 -365.304784) (xy 365.450101 -365.272333)
			(xy 365.409952 -365.233624) (xy 365.375866 -365.189481) (xy 365.34857 -365.140846) (xy 365.328647 -365.088755)
			(xy 365.316521 -365.034318) (xy 365.31245 -364.978696) (xy 360.901284 -364.978696) (xy 360.880633 -365.001744)
			(xy 360.837765 -365.037419) (xy 360.790159 -365.066473) (xy 360.73883 -365.088285) (xy 360.684873 -365.102391)
			(xy 360.629436 -365.108491) (xy 360.573702 -365.106454) (xy 360.518859 -365.096324) (xy 360.466075 -365.078317)
			(xy 360.416475 -365.052816) (xy 360.371117 -365.020365) (xy 360.330968 -364.981656) (xy 360.296882 -364.937513)
			(xy 360.269586 -364.888878) (xy 360.249663 -364.836787) (xy 360.237537 -364.78235) (xy 360.233466 -364.726728)
			(xy 359.329101 -364.726728) (xy 359.346899 -364.75363) (xy 359.370571 -364.804127) (xy 359.386639 -364.857534)
			(xy 359.394759 -364.91271) (xy 359.395268 -364.940596) (xy 359.394759 -364.968482) (xy 359.386639 -365.023658)
			(xy 359.370571 -365.077065) (xy 359.346899 -365.127562) (xy 359.316126 -365.174075) (xy 359.278909 -365.215612)
			(xy 359.236041 -365.251287) (xy 359.188435 -365.280341) (xy 359.137106 -365.302153) (xy 359.083149 -365.316259)
			(xy 359.027712 -365.322359) (xy 358.971978 -365.320322) (xy 358.917135 -365.310192) (xy 358.864351 -365.292185)
			(xy 358.814751 -365.266684) (xy 358.769393 -365.234233) (xy 358.729244 -365.195524) (xy 358.695158 -365.151381)
			(xy 358.667862 -365.102746) (xy 358.647939 -365.050655) (xy 358.635813 -364.996218) (xy 358.631742 -364.940596)
			(xy 355.50068 -364.940596) (xy 355.501675 -364.941424) (xy 355.538892 -364.982961) (xy 355.569665 -365.029474)
			(xy 355.593337 -365.079971) (xy 355.609405 -365.133378) (xy 355.617525 -365.188554) (xy 355.618034 -365.21644)
			(xy 355.617525 -365.244326) (xy 355.609405 -365.299502) (xy 355.593337 -365.352909) (xy 355.569665 -365.403406)
			(xy 355.538892 -365.449919) (xy 355.501675 -365.491456) (xy 355.458807 -365.527131) (xy 355.411201 -365.556185)
			(xy 355.359872 -365.577997) (xy 355.305915 -365.592103) (xy 355.250478 -365.598203) (xy 355.194744 -365.596166)
			(xy 355.139901 -365.586036) (xy 355.087117 -365.568029) (xy 355.037517 -365.542528) (xy 354.992159 -365.510077)
			(xy 354.95201 -365.471368) (xy 354.917924 -365.427225) (xy 354.890628 -365.37859) (xy 354.870705 -365.326499)
			(xy 354.858579 -365.272062) (xy 354.854508 -365.21644) (xy 332.229093 -365.21644) (xy 332.568093 -365.789718)
			(xy 357.87914 -365.789718) (xy 357.883211 -365.734096) (xy 357.895337 -365.679659) (xy 357.91526 -365.627568)
			(xy 357.942556 -365.578933) (xy 357.976642 -365.53479) (xy 358.016791 -365.496081) (xy 358.062149 -365.46363)
			(xy 358.111749 -365.438129) (xy 358.164533 -365.420122) (xy 358.219376 -365.409992) (xy 358.27511 -365.407955)
			(xy 358.330547 -365.414055) (xy 358.384504 -365.428161) (xy 358.435833 -365.449973) (xy 358.483439 -365.479027)
			(xy 358.526307 -365.514702) (xy 358.563524 -365.556239) (xy 358.594297 -365.602752) (xy 358.612049 -365.64062)
			(xy 380.886211 -365.64062) (xy 380.890247 -365.557173) (xy 380.902319 -365.474505) (xy 380.922312 -365.393388)
			(xy 380.950041 -365.314579) (xy 380.985247 -365.238814) (xy 381.027601 -365.166801) (xy 381.076707 -365.099212)
			(xy 381.132108 -365.036678) (xy 381.193285 -364.979783) (xy 381.259668 -364.929057) (xy 381.330636 -364.884976)
			(xy 381.405528 -364.84795) (xy 381.483644 -364.818324) (xy 381.564254 -364.796376) (xy 381.646606 -364.782311)
			(xy 381.729932 -364.776259) (xy 381.813452 -364.778278) (xy 381.896388 -364.788348) (xy 381.977964 -364.806376)
			(xy 382.05742 -364.832193) (xy 382.134013 -364.865558) (xy 382.207029 -364.906159) (xy 382.275785 -364.953618)
			(xy 382.339639 -365.007491) (xy 382.397996 -365.067276) (xy 382.450311 -365.132413) (xy 382.496094 -365.202296)
			(xy 382.534919 -365.276271) (xy 382.566424 -365.353648) (xy 382.590313 -365.433705) (xy 382.606364 -365.515693)
			(xy 382.614427 -365.598848) (xy 382.614932 -365.64062) (xy 382.614427 -365.682392) (xy 382.606364 -365.765547)
			(xy 382.590313 -365.847535) (xy 382.566424 -365.927592) (xy 382.534919 -366.004969) (xy 382.496094 -366.078944)
			(xy 382.450311 -366.148827) (xy 382.397996 -366.213964) (xy 382.339639 -366.273749) (xy 382.275785 -366.327622)
			(xy 382.207029 -366.375081) (xy 382.134013 -366.415682) (xy 382.05742 -366.449047) (xy 381.977964 -366.474864)
			(xy 381.896388 -366.492892) (xy 381.813452 -366.502962) (xy 381.729932 -366.504981) (xy 381.646606 -366.498929)
			(xy 381.564254 -366.484864) (xy 381.483644 -366.462916) (xy 381.405528 -366.43329) (xy 381.330636 -366.396264)
			(xy 381.259668 -366.352183) (xy 381.193285 -366.301457) (xy 381.132108 -366.244562) (xy 381.076707 -366.182028)
			(xy 381.027601 -366.114439) (xy 380.985247 -366.042426) (xy 380.950041 -365.966661) (xy 380.922312 -365.887852)
			(xy 380.902319 -365.806735) (xy 380.890247 -365.724067) (xy 380.886211 -365.64062) (xy 358.612049 -365.64062)
			(xy 358.617969 -365.653249) (xy 358.634037 -365.706656) (xy 358.642157 -365.761832) (xy 358.642666 -365.789718)
			(xy 358.642157 -365.817604) (xy 358.634037 -365.87278) (xy 358.617969 -365.926187) (xy 358.594297 -365.976684)
			(xy 358.563524 -366.023197) (xy 358.526307 -366.064734) (xy 358.483439 -366.100409) (xy 358.435833 -366.129463)
			(xy 358.384504 -366.151275) (xy 358.330547 -366.165381) (xy 358.27511 -366.171481) (xy 358.219376 -366.169444)
			(xy 358.164533 -366.159314) (xy 358.111749 -366.141307) (xy 358.062149 -366.115806) (xy 358.016791 -366.083355)
			(xy 357.976642 -366.044646) (xy 357.942556 -366.000503) (xy 357.91526 -365.951868) (xy 357.895337 -365.899777)
			(xy 357.883211 -365.84534) (xy 357.87914 -365.789718) (xy 332.568093 -365.789718) (xy 332.977236 -366.481614)
			(xy 333.59471 -367.099088) (xy 345.670122 -367.099088) (xy 345.674193 -367.043466) (xy 345.686319 -366.989029)
			(xy 345.706242 -366.936938) (xy 345.733538 -366.888303) (xy 345.767624 -366.84416) (xy 345.807773 -366.805451)
			(xy 345.853131 -366.773) (xy 345.902731 -366.747499) (xy 345.955515 -366.729492) (xy 346.010358 -366.719362)
			(xy 346.066092 -366.717325) (xy 346.121529 -366.723425) (xy 346.175486 -366.737531) (xy 346.226815 -366.759343)
			(xy 346.274421 -366.788397) (xy 346.317289 -366.824072) (xy 346.354506 -366.865609) (xy 346.385279 -366.912122)
			(xy 346.408951 -366.962619) (xy 346.415339 -366.983852) (xy 355.291872 -366.983852) (xy 355.291872 -366.929348)
			(xy 355.299628 -366.8754) (xy 355.314984 -366.823105) (xy 355.337625 -366.773527) (xy 355.367092 -366.727676)
			(xy 355.402783 -366.686485) (xy 355.443974 -366.650793) (xy 355.489825 -366.621326) (xy 355.539403 -366.598684)
			(xy 355.591698 -366.583329) (xy 355.645646 -366.575572) (xy 355.672898 -366.575086) (xy 355.699276 -366.575567)
			(xy 355.751532 -366.582819) (xy 355.802291 -366.597199) (xy 355.850585 -366.618432) (xy 355.895495 -366.646115)
			(xy 355.936164 -366.679719) (xy 355.971818 -366.718604) (xy 356.001776 -366.762029) (xy 356.01402 -366.785398)
			(xy 356.020722 -366.797757) (xy 356.039697 -366.818485) (xy 356.063611 -366.833247) (xy 356.090647 -366.840919)
			(xy 356.118749 -366.840919) (xy 356.145785 -366.833247) (xy 356.169699 -366.818485) (xy 356.188674 -366.797757)
			(xy 356.195376 -366.785398) (xy 356.207619 -366.762028) (xy 356.23758 -366.718604) (xy 356.273235 -366.679718)
			(xy 356.313905 -366.646112) (xy 356.358813 -366.618425) (xy 356.407106 -366.597184) (xy 356.457864 -366.582795)
			(xy 356.510119 -366.575531) (xy 356.536498 -366.575086) (xy 356.563751 -366.575561) (xy 356.617701 -366.583318)
			(xy 356.669998 -366.598673) (xy 356.719578 -366.621315) (xy 356.76543 -366.650783) (xy 356.806623 -366.686476)
			(xy 356.842316 -366.727668) (xy 356.871784 -366.773521) (xy 356.894426 -366.8231) (xy 356.909782 -366.875397)
			(xy 356.917539 -366.929347) (xy 356.917539 -366.983853) (xy 356.909782 -367.037803) (xy 356.894426 -367.0901)
			(xy 356.871784 -367.139679) (xy 356.842316 -367.185532) (xy 356.806623 -367.226724) (xy 356.76543 -367.262417)
			(xy 356.719578 -367.291885) (xy 356.669998 -367.314527) (xy 356.617701 -367.329882) (xy 356.563751 -367.337639)
			(xy 356.536498 -367.338102) (xy 356.510119 -367.337631) (xy 356.457863 -367.330378) (xy 356.407104 -367.315997)
			(xy 356.358809 -367.294763) (xy 356.313899 -367.267078) (xy 356.27323 -367.233473) (xy 356.237577 -367.194586)
			(xy 356.207619 -367.151159) (xy 356.195376 -367.12779) (xy 356.188674 -367.115431) (xy 356.169699 -367.094703)
			(xy 356.145785 -367.079941) (xy 356.118749 -367.072269) (xy 356.090647 -367.072269) (xy 356.063611 -367.079941)
			(xy 356.039697 -367.094703) (xy 356.020722 -367.115431) (xy 356.01402 -367.12779) (xy 356.001775 -367.151159)
			(xy 355.971814 -367.194584) (xy 355.93616 -367.23347) (xy 355.895491 -367.267077) (xy 355.850582 -367.294764)
			(xy 355.80229 -367.316004) (xy 355.751532 -367.330393) (xy 355.699277 -367.337657) (xy 355.672898 -367.338102)
			(xy 355.645646 -367.337628) (xy 355.591698 -367.329871) (xy 355.539403 -367.314516) (xy 355.489825 -367.291874)
			(xy 355.443974 -367.262407) (xy 355.402783 -367.226715) (xy 355.367092 -367.185524) (xy 355.337625 -367.139673)
			(xy 355.314984 -367.090095) (xy 355.299628 -367.0378) (xy 355.291872 -366.983852) (xy 346.415339 -366.983852)
			(xy 346.425019 -367.016026) (xy 346.433139 -367.071202) (xy 346.433648 -367.099088) (xy 346.433139 -367.126974)
			(xy 346.425019 -367.18215) (xy 346.408951 -367.235557) (xy 346.385279 -367.286054) (xy 346.354506 -367.332567)
			(xy 346.317289 -367.374104) (xy 346.274421 -367.409779) (xy 346.226815 -367.438833) (xy 346.175486 -367.460645)
			(xy 346.121529 -367.474751) (xy 346.066092 -367.480851) (xy 346.010358 -367.478814) (xy 345.955515 -367.468684)
			(xy 345.902731 -367.450677) (xy 345.853131 -367.425176) (xy 345.807773 -367.392725) (xy 345.767624 -367.354016)
			(xy 345.733538 -367.309873) (xy 345.706242 -367.261238) (xy 345.686319 -367.209147) (xy 345.674193 -367.15471)
			(xy 345.670122 -367.099088) (xy 333.59471 -367.099088) (xy 333.98667 -367.491048) (xy 352.48091 -367.491048)
			(xy 352.48091 -367.436552) (xy 352.488665 -367.382611) (xy 352.504018 -367.330322) (xy 352.526656 -367.28075)
			(xy 352.556118 -367.234905) (xy 352.591804 -367.193718) (xy 352.632989 -367.15803) (xy 352.678833 -367.128566)
			(xy 352.728403 -367.105925) (xy 352.780691 -367.09057) (xy 352.834632 -367.082812) (xy 352.86188 -367.082324)
			(xy 352.888261 -367.082716) (xy 352.940522 -367.08998) (xy 352.991284 -367.104372) (xy 353.03958 -367.125618)
			(xy 353.084489 -367.153313) (xy 353.125157 -367.18693) (xy 353.160807 -367.225826) (xy 353.190761 -367.269262)
			(xy 353.203002 -367.292636) (xy 353.209704 -367.304995) (xy 353.228679 -367.325723) (xy 353.252593 -367.340485)
			(xy 353.279629 -367.348157) (xy 353.307731 -367.348157) (xy 353.334767 -367.340485) (xy 353.358681 -367.325723)
			(xy 353.377656 -367.304995) (xy 353.384358 -367.292636) (xy 353.396587 -367.269259) (xy 353.426553 -367.225837)
			(xy 353.462212 -367.186954) (xy 353.502883 -367.15335) (xy 353.547794 -367.125665) (xy 353.596088 -367.104425)
			(xy 353.646845 -367.090035) (xy 353.699101 -367.08277) (xy 353.72548 -367.082324) (xy 353.752736 -367.082722)
			(xy 353.806694 -367.090477) (xy 353.858998 -367.105832) (xy 353.908585 -367.128476) (xy 353.954445 -367.157946)
			(xy 353.995643 -367.193642) (xy 354.031342 -367.234839) (xy 354.060815 -367.280697) (xy 354.083461 -367.330283)
			(xy 354.098819 -367.382587) (xy 354.106577 -367.436544) (xy 354.106577 -367.491056) (xy 354.098819 -367.545013)
			(xy 354.083461 -367.597317) (xy 354.060815 -367.646903) (xy 354.031342 -367.692761) (xy 353.995643 -367.733958)
			(xy 353.954445 -367.769654) (xy 353.944177 -367.776252) (xy 369.189506 -367.776252) (xy 369.193577 -367.72063)
			(xy 369.205703 -367.666193) (xy 369.225626 -367.614102) (xy 369.252922 -367.565467) (xy 369.287008 -367.521324)
			(xy 369.327157 -367.482615) (xy 369.372515 -367.450164) (xy 369.422115 -367.424663) (xy 369.474899 -367.406656)
			(xy 369.529742 -367.396526) (xy 369.585476 -367.394489) (xy 369.640913 -367.400589) (xy 369.69487 -367.414695)
			(xy 369.746199 -367.436507) (xy 369.793805 -367.465561) (xy 369.836673 -367.501236) (xy 369.87389 -367.542773)
			(xy 369.904663 -367.589286) (xy 369.928335 -367.639783) (xy 369.944403 -367.69319) (xy 369.952523 -367.748366)
			(xy 369.953032 -367.776252) (xy 369.952523 -367.804138) (xy 369.944403 -367.859314) (xy 369.928335 -367.912721)
			(xy 369.905269 -367.961926) (xy 370.232686 -367.961926) (xy 370.23319 -367.933008) (xy 370.241918 -367.875835)
			(xy 370.259176 -367.820634) (xy 370.28457 -367.768672) (xy 370.317518 -367.721139) (xy 370.357264 -367.679124)
			(xy 370.379752 -367.660936) (xy 370.391535 -367.651012) (xy 370.409059 -367.625697) (xy 370.418241 -367.59631)
			(xy 370.418245 -367.565522) (xy 370.409073 -367.536131) (xy 370.391557 -367.510811) (xy 370.379752 -367.500916)
			(xy 370.357266 -367.482728) (xy 370.317533 -367.440706) (xy 370.284596 -367.39317) (xy 370.259208 -367.341209)
			(xy 370.241952 -367.286011) (xy 370.233222 -367.228842) (xy 370.232686 -367.199926) (xy 370.233172 -367.172675)
			(xy 370.240928 -367.118727) (xy 370.256283 -367.066432) (xy 370.278925 -367.016855) (xy 370.308391 -366.971005)
			(xy 370.344082 -366.929814) (xy 370.385273 -366.894123) (xy 370.431123 -366.864657) (xy 370.4807 -366.842015)
			(xy 370.532995 -366.82666) (xy 370.586943 -366.818904) (xy 370.641445 -366.818904) (xy 370.695393 -366.82666)
			(xy 370.747688 -366.842015) (xy 370.797265 -366.864657) (xy 370.843115 -366.894123) (xy 370.884306 -366.929814)
			(xy 370.919997 -366.971005) (xy 370.949463 -367.016855) (xy 370.972105 -367.066432) (xy 370.98746 -367.118727)
			(xy 370.995216 -367.172675) (xy 370.995702 -367.199926) (xy 370.99513 -367.228841) (xy 370.986412 -367.28601)
			(xy 370.969165 -367.341207) (xy 370.943783 -367.393169) (xy 370.910849 -367.440705) (xy 370.871117 -367.482724)
			(xy 370.848636 -367.500916) (xy 370.836802 -367.510784) (xy 370.819281 -367.536114) (xy 370.810106 -367.565516)
			(xy 370.810111 -367.596316) (xy 370.819295 -367.625715) (xy 370.836825 -367.65104) (xy 370.848636 -367.660936)
			(xy 370.871144 -367.679098) (xy 370.910876 -367.721125) (xy 370.943811 -367.768666) (xy 370.969195 -367.820633)
			(xy 370.986446 -367.875835) (xy 370.99517 -367.933008) (xy 370.995702 -367.961926) (xy 372.38051 -367.961926)
			(xy 372.381043 -367.93301) (xy 372.389769 -367.875839) (xy 372.407023 -367.82064) (xy 372.432412 -367.768678)
			(xy 372.465353 -367.721144) (xy 372.505092 -367.679127) (xy 372.527576 -367.660936) (xy 372.539356 -367.651011)
			(xy 372.556876 -367.625695) (xy 372.566056 -367.596309) (xy 372.56606 -367.565523) (xy 372.55689 -367.536134)
			(xy 372.539378 -367.510813) (xy 372.527576 -367.500916) (xy 372.505095 -367.482722) (xy 372.465361 -367.440702)
			(xy 372.432422 -367.393168) (xy 372.407034 -367.341207) (xy 372.389777 -367.28601) (xy 372.381046 -367.228842)
			(xy 372.38051 -367.199926) (xy 372.380996 -367.172675) (xy 372.388752 -367.118727) (xy 372.404107 -367.066432)
			(xy 372.426749 -367.016855) (xy 372.456215 -366.971005) (xy 372.491906 -366.929814) (xy 372.533097 -366.894123)
			(xy 372.578947 -366.864657) (xy 372.628524 -366.842015) (xy 372.680819 -366.82666) (xy 372.734767 -366.818904)
			(xy 372.789269 -366.818904) (xy 372.843217 -366.82666) (xy 372.895512 -366.842015) (xy 372.945089 -366.864657)
			(xy 372.990939 -366.894123) (xy 373.03213 -366.929814) (xy 373.067821 -366.971005) (xy 373.097287 -367.016855)
			(xy 373.119929 -367.066432) (xy 373.135284 -367.118727) (xy 373.14304 -367.172675) (xy 373.143526 -367.199926)
			(xy 373.142982 -367.228842) (xy 373.134263 -367.286014) (xy 373.117011 -367.341213) (xy 373.091625 -367.393176)
			(xy 373.058684 -367.44071) (xy 373.018945 -367.482726) (xy 372.99646 -367.500916) (xy 372.984624 -367.510783)
			(xy 372.967099 -367.536112) (xy 372.957922 -367.565515) (xy 372.957926 -367.596317) (xy 372.967113 -367.625716)
			(xy 372.984647 -367.651041) (xy 372.99646 -367.660936) (xy 373.018952 -367.679117) (xy 373.058689 -367.721137)
			(xy 373.091628 -367.768674) (xy 373.117015 -367.820638) (xy 373.134269 -367.875838) (xy 373.142994 -367.933009)
			(xy 373.143526 -367.961926) (xy 374.51411 -367.961926) (xy 374.514643 -367.93301) (xy 374.523369 -367.875839)
			(xy 374.540623 -367.82064) (xy 374.566012 -367.768678) (xy 374.598953 -367.721144) (xy 374.638692 -367.679127)
			(xy 374.661176 -367.660936) (xy 374.672956 -367.651011) (xy 374.690476 -367.625695) (xy 374.699656 -367.596309)
			(xy 374.69966 -367.565523) (xy 374.69049 -367.536134) (xy 374.672978 -367.510813) (xy 374.661176 -367.500916)
			(xy 374.638695 -367.482722) (xy 374.598961 -367.440702) (xy 374.566022 -367.393168) (xy 374.540634 -367.341207)
			(xy 374.523377 -367.28601) (xy 374.514646 -367.228842) (xy 374.51411 -367.199926) (xy 374.514596 -367.172675)
			(xy 374.522352 -367.118727) (xy 374.537707 -367.066432) (xy 374.560349 -367.016855) (xy 374.589815 -366.971005)
			(xy 374.625506 -366.929814) (xy 374.666697 -366.894123) (xy 374.712547 -366.864657) (xy 374.762124 -366.842015)
			(xy 374.814419 -366.82666) (xy 374.868367 -366.818904) (xy 374.922869 -366.818904) (xy 374.976817 -366.82666)
			(xy 375.029112 -366.842015) (xy 375.078689 -366.864657) (xy 375.124539 -366.894123) (xy 375.16573 -366.929814)
			(xy 375.201421 -366.971005) (xy 375.230887 -367.016855) (xy 375.253529 -367.066432) (xy 375.268884 -367.118727)
			(xy 375.27664 -367.172675) (xy 375.277126 -367.199926) (xy 375.276582 -367.228842) (xy 375.267863 -367.286014)
			(xy 375.250611 -367.341213) (xy 375.225225 -367.393176) (xy 375.192284 -367.44071) (xy 375.152545 -367.482726)
			(xy 375.13006 -367.500916) (xy 375.118224 -367.510783) (xy 375.100699 -367.536112) (xy 375.091522 -367.565515)
			(xy 375.091526 -367.596317) (xy 375.100713 -367.625716) (xy 375.118247 -367.651041) (xy 375.13006 -367.660936)
			(xy 375.152552 -367.679117) (xy 375.192289 -367.721137) (xy 375.225228 -367.768674) (xy 375.250615 -367.820638)
			(xy 375.267869 -367.875838) (xy 375.276594 -367.933009) (xy 375.276603 -367.933478) (xy 376.66676 -367.933478)
			(xy 376.667312 -367.904562) (xy 376.676031 -367.847391) (xy 376.693281 -367.792192) (xy 376.718666 -367.74023)
			(xy 376.751605 -367.692695) (xy 376.791342 -367.650678) (xy 376.813826 -367.632488) (xy 376.825649 -367.622612)
			(xy 376.84316 -367.597281) (xy 376.852329 -367.567884) (xy 376.852325 -367.537089) (xy 376.843148 -367.507694)
			(xy 376.825631 -367.482368) (xy 376.813826 -367.472468) (xy 376.791333 -367.454288) (xy 376.751597 -367.412267)
			(xy 376.718658 -367.36473) (xy 376.693271 -367.312766) (xy 376.676018 -367.257566) (xy 376.667293 -367.200395)
			(xy 376.66676 -367.171478) (xy 376.667246 -367.144227) (xy 376.675002 -367.090279) (xy 376.690357 -367.037984)
			(xy 376.712999 -366.988407) (xy 376.742465 -366.942557) (xy 376.778156 -366.901366) (xy 376.819347 -366.865675)
			(xy 376.865197 -366.836209) (xy 376.914774 -366.813567) (xy 376.967069 -366.798212) (xy 377.021017 -366.790456)
			(xy 377.075519 -366.790456) (xy 377.129467 -366.798212) (xy 377.181762 -366.813567) (xy 377.231339 -366.836209)
			(xy 377.277189 -366.865675) (xy 377.31838 -366.901366) (xy 377.354071 -366.942557) (xy 377.383537 -366.988407)
			(xy 377.406179 -367.037984) (xy 377.421534 -367.090279) (xy 377.42929 -367.144227) (xy 377.429776 -367.171478)
			(xy 377.429251 -367.200395) (xy 377.420525 -367.257566) (xy 377.403269 -367.312765) (xy 377.377878 -367.364727)
			(xy 377.344935 -367.412261) (xy 377.305195 -367.454278) (xy 377.28271 -367.472468) (xy 377.270927 -367.48239)
			(xy 377.25341 -367.507707) (xy 377.244232 -367.537093) (xy 377.244228 -367.56788) (xy 377.253398 -367.597269)
			(xy 377.270909 -367.62259) (xy 377.28271 -367.632488) (xy 377.30519 -367.650683) (xy 377.344925 -367.692702)
			(xy 377.377864 -367.740237) (xy 377.403253 -367.792197) (xy 377.42051 -367.847394) (xy 377.42924 -367.904562)
			(xy 377.429776 -367.933478) (xy 377.42929 -367.960729) (xy 377.421534 -368.014677) (xy 377.406179 -368.066972)
			(xy 377.383537 -368.116549) (xy 377.354071 -368.162399) (xy 377.336143 -368.18309) (xy 380.86182 -368.18309)
			(xy 380.86182 -368.098394) (xy 380.869871 -368.01408) (xy 380.8859 -367.930914) (xy 380.909761 -367.849647)
			(xy 380.94124 -367.771017) (xy 380.980051 -367.695736) (xy 381.025841 -367.624484) (xy 381.078197 -367.557908)
			(xy 381.136645 -367.49661) (xy 381.200655 -367.441145) (xy 381.269647 -367.392016) (xy 381.342997 -367.349667)
			(xy 381.42004 -367.314483) (xy 381.500079 -367.286781) (xy 381.582388 -367.266813) (xy 381.666223 -367.25476)
			(xy 381.750824 -367.25073) (xy 381.835425 -367.25476) (xy 381.91926 -367.266813) (xy 382.001569 -367.286781)
			(xy 382.081608 -367.314483) (xy 382.158651 -367.349667) (xy 382.232001 -367.392016) (xy 382.300993 -367.441145)
			(xy 382.365003 -367.49661) (xy 382.423451 -367.557908) (xy 382.475807 -367.624484) (xy 382.521597 -367.695736)
			(xy 382.560408 -367.771017) (xy 382.591887 -367.849647) (xy 382.615748 -367.930914) (xy 382.631777 -368.01408)
			(xy 382.639828 -368.098394) (xy 382.640332 -368.140742) (xy 382.639828 -368.18309) (xy 382.631777 -368.267404)
			(xy 382.615748 -368.35057) (xy 382.591887 -368.431837) (xy 382.560408 -368.510467) (xy 382.521597 -368.585748)
			(xy 382.475807 -368.657) (xy 382.423451 -368.723576) (xy 382.365003 -368.784874) (xy 382.300993 -368.840339)
			(xy 382.232001 -368.889468) (xy 382.158651 -368.931817) (xy 382.081608 -368.967001) (xy 382.001569 -368.994703)
			(xy 381.91926 -369.014671) (xy 381.835425 -369.026724) (xy 381.750824 -369.030755) (xy 381.666223 -369.026724)
			(xy 381.582388 -369.014671) (xy 381.500079 -368.994703) (xy 381.42004 -368.967001) (xy 381.342997 -368.931817)
			(xy 381.269647 -368.889468) (xy 381.200655 -368.840339) (xy 381.136645 -368.784874) (xy 381.078197 -368.723576)
			(xy 381.025841 -368.657) (xy 380.980051 -368.585748) (xy 380.94124 -368.510467) (xy 380.909761 -368.431837)
			(xy 380.8859 -368.35057) (xy 380.869871 -368.267404) (xy 380.86182 -368.18309) (xy 377.336143 -368.18309)
			(xy 377.31838 -368.20359) (xy 377.277189 -368.239281) (xy 377.231339 -368.268747) (xy 377.181762 -368.291389)
			(xy 377.129467 -368.306744) (xy 377.075519 -368.3145) (xy 377.021017 -368.3145) (xy 376.967069 -368.306744)
			(xy 376.914774 -368.291389) (xy 376.865197 -368.268747) (xy 376.819347 -368.239281) (xy 376.778156 -368.20359)
			(xy 376.742465 -368.162399) (xy 376.712999 -368.116549) (xy 376.690357 -368.066972) (xy 376.675002 -368.014677)
			(xy 376.667246 -367.960729) (xy 376.66676 -367.933478) (xy 375.276603 -367.933478) (xy 375.277126 -367.961926)
			(xy 375.27664 -367.989177) (xy 375.268884 -368.043125) (xy 375.253529 -368.09542) (xy 375.230887 -368.144997)
			(xy 375.201421 -368.190847) (xy 375.16573 -368.232038) (xy 375.124539 -368.267729) (xy 375.078689 -368.297195)
			(xy 375.029112 -368.319837) (xy 374.976817 -368.335192) (xy 374.922869 -368.342948) (xy 374.868367 -368.342948)
			(xy 374.814419 -368.335192) (xy 374.762124 -368.319837) (xy 374.712547 -368.297195) (xy 374.666697 -368.267729)
			(xy 374.625506 -368.232038) (xy 374.589815 -368.190847) (xy 374.560349 -368.144997) (xy 374.537707 -368.09542)
			(xy 374.522352 -368.043125) (xy 374.514596 -367.989177) (xy 374.51411 -367.961926) (xy 373.143526 -367.961926)
			(xy 373.14304 -367.989177) (xy 373.135284 -368.043125) (xy 373.119929 -368.09542) (xy 373.097287 -368.144997)
			(xy 373.067821 -368.190847) (xy 373.03213 -368.232038) (xy 372.990939 -368.267729) (xy 372.945089 -368.297195)
			(xy 372.895512 -368.319837) (xy 372.843217 -368.335192) (xy 372.789269 -368.342948) (xy 372.734767 -368.342948)
			(xy 372.680819 -368.335192) (xy 372.628524 -368.319837) (xy 372.578947 -368.297195) (xy 372.533097 -368.267729)
			(xy 372.491906 -368.232038) (xy 372.456215 -368.190847) (xy 372.426749 -368.144997) (xy 372.404107 -368.09542)
			(xy 372.388752 -368.043125) (xy 372.380996 -367.989177) (xy 372.38051 -367.961926) (xy 370.995702 -367.961926)
			(xy 370.995216 -367.989177) (xy 370.98746 -368.043125) (xy 370.972105 -368.09542) (xy 370.949463 -368.144997)
			(xy 370.919997 -368.190847) (xy 370.884306 -368.232038) (xy 370.843115 -368.267729) (xy 370.797265 -368.297195)
			(xy 370.747688 -368.319837) (xy 370.695393 -368.335192) (xy 370.641445 -368.342948) (xy 370.586943 -368.342948)
			(xy 370.532995 -368.335192) (xy 370.4807 -368.319837) (xy 370.431123 -368.297195) (xy 370.385273 -368.267729)
			(xy 370.344082 -368.232038) (xy 370.308391 -368.190847) (xy 370.278925 -368.144997) (xy 370.256283 -368.09542)
			(xy 370.240928 -368.043125) (xy 370.233172 -367.989177) (xy 370.232686 -367.961926) (xy 369.905269 -367.961926)
			(xy 369.904663 -367.963218) (xy 369.87389 -368.009731) (xy 369.836673 -368.051268) (xy 369.793805 -368.086943)
			(xy 369.746199 -368.115997) (xy 369.69487 -368.137809) (xy 369.640913 -368.151915) (xy 369.585476 -368.158015)
			(xy 369.529742 -368.155978) (xy 369.474899 -368.145848) (xy 369.422115 -368.127841) (xy 369.372515 -368.10234)
			(xy 369.327157 -368.069889) (xy 369.287008 -368.03118) (xy 369.252922 -367.987037) (xy 369.225626 -367.938402)
			(xy 369.205703 -367.886311) (xy 369.193577 -367.831874) (xy 369.189506 -367.776252) (xy 353.944177 -367.776252)
			(xy 353.908585 -367.799124) (xy 353.858998 -367.821768) (xy 353.806694 -367.837123) (xy 353.752736 -367.844878)
			(xy 353.72548 -367.84534) (xy 353.699102 -367.844863) (xy 353.646847 -367.837609) (xy 353.596089 -367.823227)
			(xy 353.547795 -367.801992) (xy 353.502885 -367.774309) (xy 353.462216 -367.740705) (xy 353.426562 -367.70182)
			(xy 353.396603 -367.658396) (xy 353.384358 -367.635028) (xy 353.377656 -367.622669) (xy 353.358681 -367.601941)
			(xy 353.334767 -367.587179) (xy 353.307731 -367.579507) (xy 353.279629 -367.579507) (xy 353.252593 -367.587179)
			(xy 353.228679 -367.601941) (xy 353.209704 -367.622669) (xy 353.203002 -367.635028) (xy 353.190787 -367.658413)
			(xy 353.160821 -367.701837) (xy 353.125161 -367.740721) (xy 353.084488 -367.774326) (xy 353.039575 -367.802011)
			(xy 352.991278 -367.823249) (xy 352.940518 -367.837635) (xy 352.88826 -367.844896) (xy 352.86188 -367.84534)
			(xy 352.834632 -367.844788) (xy 352.780691 -367.83703) (xy 352.728403 -367.821675) (xy 352.678833 -367.799034)
			(xy 352.632989 -367.76957) (xy 352.591804 -367.733882) (xy 352.556118 -367.692695) (xy 352.526656 -367.64685)
			(xy 352.504018 -367.597278) (xy 352.488665 -367.544989) (xy 352.48091 -367.491048) (xy 333.98667 -367.491048)
			(xy 334.600296 -368.104674) (xy 346.277182 -368.104674) (xy 346.281253 -368.049052) (xy 346.293379 -367.994615)
			(xy 346.313302 -367.942524) (xy 346.340598 -367.893889) (xy 346.374684 -367.849746) (xy 346.414833 -367.811037)
			(xy 346.460191 -367.778586) (xy 346.509791 -367.753085) (xy 346.562575 -367.735078) (xy 346.617418 -367.724948)
			(xy 346.673152 -367.722911) (xy 346.728589 -367.729011) (xy 346.782546 -367.743117) (xy 346.833875 -367.764929)
			(xy 346.881481 -367.793983) (xy 346.924349 -367.829658) (xy 346.961566 -367.871195) (xy 346.992339 -367.917708)
			(xy 347.016011 -367.968205) (xy 347.032079 -368.021612) (xy 347.040199 -368.076788) (xy 347.040708 -368.104674)
			(xy 347.040569 -368.112294) (xy 347.30385 -368.112294) (xy 347.307921 -368.056672) (xy 347.320047 -368.002235)
			(xy 347.33997 -367.950144) (xy 347.367266 -367.901509) (xy 347.401352 -367.857366) (xy 347.441501 -367.818657)
			(xy 347.486859 -367.786206) (xy 347.536459 -367.760705) (xy 347.589243 -367.742698) (xy 347.644086 -367.732568)
			(xy 347.69982 -367.730531) (xy 347.755257 -367.736631) (xy 347.809214 -367.750737) (xy 347.860543 -367.772549)
			(xy 347.908149 -367.801603) (xy 347.951017 -367.837278) (xy 347.988234 -367.878815) (xy 348.019007 -367.925328)
			(xy 348.042679 -367.975825) (xy 348.058747 -368.029232) (xy 348.066867 -368.084408) (xy 348.067376 -368.112294)
			(xy 348.066867 -368.14018) (xy 348.058747 -368.195356) (xy 348.042679 -368.248763) (xy 348.019007 -368.29926)
			(xy 347.988234 -368.345773) (xy 347.951017 -368.38731) (xy 347.908149 -368.422985) (xy 347.860543 -368.452039)
			(xy 347.809214 -368.473851) (xy 347.755257 -368.487957) (xy 347.69982 -368.494057) (xy 347.644086 -368.49202)
			(xy 347.589243 -368.48189) (xy 347.536459 -368.463883) (xy 347.486859 -368.438382) (xy 347.441501 -368.405931)
			(xy 347.401352 -368.367222) (xy 347.367266 -368.323079) (xy 347.33997 -368.274444) (xy 347.320047 -368.222353)
			(xy 347.307921 -368.167916) (xy 347.30385 -368.112294) (xy 347.040569 -368.112294) (xy 347.040199 -368.13256)
			(xy 347.032079 -368.187736) (xy 347.016011 -368.241143) (xy 346.992339 -368.29164) (xy 346.961566 -368.338153)
			(xy 346.924349 -368.37969) (xy 346.881481 -368.415365) (xy 346.833875 -368.444419) (xy 346.782546 -368.466231)
			(xy 346.728589 -368.480337) (xy 346.673152 -368.486437) (xy 346.617418 -368.4844) (xy 346.562575 -368.47427)
			(xy 346.509791 -368.456263) (xy 346.460191 -368.430762) (xy 346.414833 -368.398311) (xy 346.374684 -368.359602)
			(xy 346.340598 -368.315459) (xy 346.313302 -368.266824) (xy 346.293379 -368.214733) (xy 346.281253 -368.160296)
			(xy 346.277182 -368.104674) (xy 334.600296 -368.104674) (xy 336.136554 -369.640932) (xy 346.293341 -369.640932)
			(xy 346.293345 -369.586423) (xy 346.301105 -369.532469) (xy 346.316466 -369.480169) (xy 346.339113 -369.430588)
			(xy 346.368587 -369.384734) (xy 346.404286 -369.343541) (xy 346.445484 -369.307849) (xy 346.491343 -369.278383)
			(xy 346.540928 -369.255744) (xy 346.59323 -369.240392) (xy 346.647185 -369.23264) (xy 346.67444 -369.23218)
			(xy 346.695505 -369.232424) (xy 346.737385 -369.237011) (xy 346.758006 -369.241324) (xy 346.77144 -369.243944)
			(xy 346.79877 -369.24259) (xy 346.824757 -369.234019) (xy 346.847531 -369.218848) (xy 346.865453 -369.19817)
			(xy 346.877234 -369.173471) (xy 346.882025 -369.14653) (xy 346.881196 -369.132866) (xy 346.879672 -369.098068)
			(xy 346.880212 -369.070819) (xy 346.887973 -369.016877) (xy 346.903331 -368.964588) (xy 346.925974 -368.915018)
			(xy 346.955441 -368.869174) (xy 346.991133 -368.82799) (xy 347.032322 -368.792305) (xy 347.07817 -368.762845)
			(xy 347.127745 -368.74021) (xy 347.180036 -368.72486) (xy 347.233979 -368.717108) (xy 347.288477 -368.717112)
			(xy 347.342419 -368.724872) (xy 347.394708 -368.740229) (xy 347.444279 -368.762872) (xy 347.490123 -368.792339)
			(xy 347.531307 -368.82803) (xy 347.566993 -368.869219) (xy 347.596453 -368.915067) (xy 347.619089 -368.964641)
			(xy 347.634439 -369.016932) (xy 347.642192 -369.070875) (xy 347.642188 -369.125373) (xy 347.634429 -369.179315)
			(xy 347.619072 -369.231604) (xy 347.59643 -369.281175) (xy 347.566964 -369.32702) (xy 347.531273 -369.368204)
			(xy 347.490085 -369.40389) (xy 347.444237 -369.433351) (xy 347.394663 -369.455987) (xy 347.342372 -369.471338)
			(xy 347.288429 -369.479091) (xy 347.26118 -369.479576) (xy 347.240115 -369.479329) (xy 347.198235 -369.474745)
			(xy 347.177614 -369.470432) (xy 347.16417 -369.467881) (xy 347.136851 -369.469231) (xy 347.110873 -369.477794)
			(xy 347.088105 -369.492953) (xy 347.070184 -369.513618) (xy 347.060002 -369.534948) (xy 364.036862 -369.534948)
			(xy 364.040933 -369.479326) (xy 364.053059 -369.424889) (xy 364.072982 -369.372798) (xy 364.100278 -369.324163)
			(xy 364.134364 -369.28002) (xy 364.174513 -369.241311) (xy 364.219871 -369.20886) (xy 364.269471 -369.183359)
			(xy 364.322255 -369.165352) (xy 364.377098 -369.155222) (xy 364.432832 -369.153185) (xy 364.488269 -369.159285)
			(xy 364.542226 -369.173391) (xy 364.593555 -369.195203) (xy 364.641161 -369.224257) (xy 364.684029 -369.259932)
			(xy 364.721246 -369.301469) (xy 364.752019 -369.347982) (xy 364.775691 -369.398479) (xy 364.791759 -369.451886)
			(xy 364.799879 -369.507062) (xy 364.800388 -369.534948) (xy 364.800249 -369.542568) (xy 365.489742 -369.542568)
			(xy 365.493813 -369.486946) (xy 365.505939 -369.432509) (xy 365.525862 -369.380418) (xy 365.553158 -369.331783)
			(xy 365.587244 -369.28764) (xy 365.627393 -369.248931) (xy 365.672751 -369.21648) (xy 365.722351 -369.190979)
			(xy 365.775135 -369.172972) (xy 365.829978 -369.162842) (xy 365.885712 -369.160805) (xy 365.941149 -369.166905)
			(xy 365.995106 -369.181011) (xy 366.046435 -369.202823) (xy 366.094041 -369.231877) (xy 366.136909 -369.267552)
			(xy 366.174126 -369.309089) (xy 366.204899 -369.355602) (xy 366.228571 -369.406099) (xy 366.244639 -369.459506)
			(xy 366.252759 -369.514682) (xy 366.253268 -369.542568) (xy 366.252759 -369.570454) (xy 366.244639 -369.62563)
			(xy 366.228571 -369.679037) (xy 366.204899 -369.729534) (xy 366.174126 -369.776047) (xy 366.136909 -369.817584)
			(xy 366.094041 -369.853259) (xy 366.046435 -369.882313) (xy 365.995106 -369.904125) (xy 365.941149 -369.918231)
			(xy 365.885712 -369.924331) (xy 365.829978 -369.922294) (xy 365.775135 -369.912164) (xy 365.722351 -369.894157)
			(xy 365.672751 -369.868656) (xy 365.627393 -369.836205) (xy 365.587244 -369.797496) (xy 365.553158 -369.753353)
			(xy 365.525862 -369.704718) (xy 365.505939 -369.652627) (xy 365.493813 -369.59819) (xy 365.489742 -369.542568)
			(xy 364.800249 -369.542568) (xy 364.799879 -369.562834) (xy 364.791759 -369.61801) (xy 364.775691 -369.671417)
			(xy 364.752019 -369.721914) (xy 364.721246 -369.768427) (xy 364.684029 -369.809964) (xy 364.641161 -369.845639)
			(xy 364.593555 -369.874693) (xy 364.542226 -369.896505) (xy 364.488269 -369.910611) (xy 364.432832 -369.916711)
			(xy 364.377098 -369.914674) (xy 364.322255 -369.904544) (xy 364.269471 -369.886537) (xy 364.219871 -369.861036)
			(xy 364.174513 -369.828585) (xy 364.134364 -369.789876) (xy 364.100278 -369.745733) (xy 364.072982 -369.697098)
			(xy 364.053059 -369.645007) (xy 364.040933 -369.59057) (xy 364.036862 -369.534948) (xy 347.060002 -369.534948)
			(xy 347.0584 -369.538303) (xy 347.053601 -369.565231) (xy 347.054424 -369.57889) (xy 347.055948 -369.613688)
			(xy 347.055458 -369.640943) (xy 347.047702 -369.694897) (xy 347.032346 -369.747198) (xy 347.009703 -369.796782)
			(xy 346.980234 -369.842638) (xy 346.944539 -369.883834) (xy 346.903344 -369.91953) (xy 346.857488 -369.949)
			(xy 346.807905 -369.971644) (xy 346.755604 -369.987001) (xy 346.701649 -369.994757) (xy 346.64714 -369.994757)
			(xy 346.593186 -369.986998) (xy 346.540885 -369.97164) (xy 346.491303 -369.948995) (xy 346.445448 -369.919524)
			(xy 346.404254 -369.883826) (xy 346.368559 -369.84263) (xy 346.339092 -369.796773) (xy 346.31645 -369.747188)
			(xy 346.301096 -369.694887) (xy 346.293341 -369.640932) (xy 336.136554 -369.640932) (xy 336.60461 -370.108988)
			(xy 347.338902 -370.108988) (xy 347.342973 -370.053366) (xy 347.355099 -369.998929) (xy 347.375022 -369.946838)
			(xy 347.402318 -369.898203) (xy 347.436404 -369.85406) (xy 347.476553 -369.815351) (xy 347.521911 -369.7829)
			(xy 347.571511 -369.757399) (xy 347.624295 -369.739392) (xy 347.679138 -369.729262) (xy 347.734872 -369.727225)
			(xy 347.790309 -369.733325) (xy 347.844266 -369.747431) (xy 347.895595 -369.769243) (xy 347.943201 -369.798297)
			(xy 347.986069 -369.833972) (xy 348.023286 -369.875509) (xy 348.054059 -369.922022) (xy 348.077731 -369.972519)
			(xy 348.093799 -370.025926) (xy 348.101919 -370.081102) (xy 348.102428 -370.108988) (xy 348.101919 -370.136874)
			(xy 348.093799 -370.19205) (xy 348.077731 -370.245457) (xy 348.054059 -370.295954) (xy 348.023286 -370.342467)
			(xy 347.986069 -370.384004) (xy 347.943201 -370.419679) (xy 347.895595 -370.448733) (xy 347.844266 -370.470545)
			(xy 347.790309 -370.484651) (xy 347.734872 -370.490751) (xy 347.679138 -370.488714) (xy 347.624295 -370.478584)
			(xy 347.571511 -370.460577) (xy 347.521911 -370.435076) (xy 347.476553 -370.402625) (xy 347.436404 -370.363916)
			(xy 347.402318 -370.319773) (xy 347.375022 -370.271138) (xy 347.355099 -370.219047) (xy 347.342973 -370.16461)
			(xy 347.338902 -370.108988) (xy 336.60461 -370.108988) (xy 337.430618 -370.934996) (xy 347.608396 -370.934996)
			(xy 347.612467 -370.879374) (xy 347.624593 -370.824937) (xy 347.644516 -370.772846) (xy 347.671812 -370.724211)
			(xy 347.705898 -370.680068) (xy 347.746047 -370.641359) (xy 347.791405 -370.608908) (xy 347.841005 -370.583407)
			(xy 347.893789 -370.5654) (xy 347.948632 -370.55527) (xy 348.004366 -370.553233) (xy 348.059803 -370.559333)
			(xy 348.11376 -370.573439) (xy 348.165089 -370.595251) (xy 348.212695 -370.624305) (xy 348.255563 -370.65998)
			(xy 348.29278 -370.701517) (xy 348.323553 -370.74803) (xy 348.347225 -370.798527) (xy 348.363293 -370.851934)
			(xy 348.371413 -370.90711) (xy 348.371922 -370.934996) (xy 348.371413 -370.962882) (xy 348.363293 -371.018058)
			(xy 348.347225 -371.071465) (xy 348.323553 -371.121962) (xy 348.29278 -371.168475) (xy 348.255563 -371.210012)
			(xy 348.212695 -371.245687) (xy 348.165089 -371.274741) (xy 348.11376 -371.296553) (xy 348.059803 -371.310659)
			(xy 348.004366 -371.316759) (xy 347.948632 -371.314722) (xy 347.893789 -371.304592) (xy 347.841005 -371.286585)
			(xy 347.791405 -371.261084) (xy 347.746047 -371.228633) (xy 347.705898 -371.189924) (xy 347.671812 -371.145781)
			(xy 347.644516 -371.097146) (xy 347.624593 -371.045055) (xy 347.612467 -370.990618) (xy 347.608396 -370.934996)
			(xy 337.430618 -370.934996) (xy 339.411056 -372.915434) (xy 380.896876 -372.915434)
		)
		(stroke
			(width 0)
			(type solid)
		)
		(fill yes)
		(layer "In13.Cu")
		(net "GND")
	)
)
